(kicad_pcb
	(version 20260206)
	(generator "pcbnew")
	(generator_version "10.0")
	(general
		(thickness 1.6)
		(legacy_teardrops no)
	)
	(paper "A4")
	(layers
		(0 "F.Cu" signal "TOP")
		(4 "In1.Cu" signal "GND")
		(6 "In2.Cu" signal "VCC")
		(8 "In3.Cu" signal "VCC1")
		(10 "In4.Cu" signal "GND1")
		(12 "In5.Cu" signal "IN1")
		(14 "In6.Cu" signal "GND2")
		(16 "In7.Cu" signal "IN2")
		(18 "In8.Cu" signal "GND3")
		(20 "In9.Cu" signal "IN3")
		(22 "In10.Cu" signal "GND4")
		(24 "In11.Cu" signal "IN4")
		(26 "In12.Cu" signal "GND5")
		(28 "In13.Cu" signal "IN5")
		(30 "In14.Cu" signal "GND6")
		(32 "In15.Cu" signal "IN6")
		(34 "In16.Cu" signal "GND7")
		(2 "B.Cu" signal "BOTTOM")
		(9 "F.Adhes" user "F.Adhesive")
		(11 "B.Adhes" user "B.Adhesive")
		(13 "F.Paste" user "Package Geometry/Pastemask Top")
		(15 "B.Paste" user "Package Geometry/Pastemask Bottom")
		(5 "F.SilkS" user "Ref Des/Silkscreen Top")
		(7 "B.SilkS" user "Ref Des/Silkscreen Bottom")
		(1 "F.Mask" user "Board Geometry/Soldermask Top")
		(3 "B.Mask" user "Board Geometry/Soldermask Bottom")
		(17 "Dwgs.User" user "User.Drawings")
		(19 "Cmts.User" user "User.Comments")
		(21 "Eco1.User" user "User.Eco1")
		(23 "Eco2.User" user "User.Eco2")
		(25 "Edge.Cuts" user "Board Geometry/Outline")
		(27 "Margin" user)
		(31 "F.CrtYd" user "Package Geometry/Place Bound Top")
		(29 "B.CrtYd" user "Package Geometry/Place Bound Bottom")
		(35 "F.Fab" user "Ref Des/Assembly Top")
		(33 "B.Fab" user "Ref Des/Assembly Bottom")
	)
	(setup
		(pad_to_mask_clearance 0)
		(allow_soldermask_bridges_in_footprints no)
		(tenting
			(front yes)
			(back yes)
		)
		(covering
			(front no)
			(back no)
		)
		(plugging
			(front no)
			(back no)
		)
		(capping no)
		(filling no)
		(pcbplotparams
			(layerselection 0x00000000_00000000_55555555_5755f5ff)
			(plot_on_all_layers_selection 0x00000000_00000000_00000000_00000000)
			(disableapertmacros no)
			(usegerberextensions no)
			(usegerberattributes yes)
			(usegerberadvancedattributes yes)
			(creategerberjobfile yes)
			(dashed_line_dash_ratio 12)
			(dashed_line_gap_ratio 3)
			(svgprecision 4)
			(plotframeref no)
			(mode 1)
			(useauxorigin no)
			(pdf_front_fp_property_popups yes)
			(pdf_back_fp_property_popups yes)
			(pdf_metadata yes)
			(pdf_single_document no)
			(dxfpolygonmode yes)
			(dxfimperialunits yes)
			(dxfusepcbnewfont yes)
			(psnegative no)
			(psa4output no)
			(plot_black_and_white yes)
			(sketchpadsonfab no)
			(plotpadnumbers no)
			(hidednponfab no)
			(sketchdnponfab yes)
			(crossoutdnponfab yes)
			(subtractmaskfromsilk no)
			(outputformat 1)
			(mirror no)
			(drillshape 1)
			(scaleselection 1)
			(outputdirectory "")
		)
	)
	(gr_poly
		(pts
			(xy 166.793926 -318.779144) (xy 166.803559 -318.778677) (xy 166.821443 -318.771498) (xy 166.828724 -318.765174)
			(xy 166.879524 -318.717168) (xy 166.882938 -318.713781) (xy 166.888557 -318.705979) (xy 166.8907 -318.701674)
			(xy 166.894764 -318.693038) (xy 166.895272 -318.683132) (xy 166.897215 -318.657473) (xy 166.908611 -318.607296)
			(xy 166.928254 -318.559739) (xy 166.955589 -318.516147) (xy 166.989844 -318.477752) (xy 167.030048 -318.44564)
			(xy 167.075065 -318.420721) (xy 167.123622 -318.403698) (xy 167.174345 -318.395054) (xy 167.200072 -318.394588)
			(xy 167.231822 -318.396112) (xy 167.24249 -318.397382) (xy 167.25265 -318.39408) (xy 167.261032 -318.390524)
			(xy 167.271192 -318.383412) (xy 167.327072 -318.332866) (xy 167.334574 -318.325319) (xy 167.343219 -318.305899)
			(xy 167.343836 -318.295274) (xy 167.343836 -318.224916) (xy 167.343999 -318.211262) (xy 167.34629 -318.18405)
			(xy 167.348408 -318.17056) (xy 167.350186 -318.158622) (xy 167.346884 -318.1477) (xy 167.345001 -318.142047)
			(xy 167.338968 -318.131776) (xy 167.334946 -318.12738) (xy 167.278812 -318.068452) (xy 167.274582 -318.064222)
			(xy 167.264571 -318.057678) (xy 167.259 -318.055498) (xy 167.248078 -318.051688) (xy 167.23614 -318.053212)
			(xy 167.227156 -318.054195) (xy 167.20911 -318.055213) (xy 167.200072 -318.055244) (xy 167.175248 -318.054756)
			(xy 167.126255 -318.046719) (xy 167.079208 -318.030862) (xy 167.035345 -318.007602) (xy 166.995824 -317.977553)
			(xy 166.961685 -317.941506) (xy 166.933827 -317.90041) (xy 166.912985 -317.855349) (xy 166.899707 -317.807509)
			(xy 166.894344 -317.758152) (xy 166.897037 -317.708577) (xy 166.907715 -317.660091) (xy 166.926096 -317.613971)
			(xy 166.951697 -317.571433) (xy 166.983842 -317.533597) (xy 167.021685 -317.501459) (xy 167.064229 -317.475868)
			(xy 167.110353 -317.457496) (xy 167.158841 -317.446829) (xy 167.208416 -317.444146) (xy 167.257772 -317.449519)
			(xy 167.305609 -317.462807) (xy 167.350666 -317.483658) (xy 167.391756 -317.511525) (xy 167.427796 -317.545672)
			(xy 167.457837 -317.585199) (xy 167.481087 -317.629067) (xy 167.496935 -317.676117) (xy 167.504961 -317.725112)
			(xy 167.50538 -317.749936) (xy 167.50534 -317.759037) (xy 167.504321 -317.777209) (xy 167.503348 -317.786258)
			(xy 167.501824 -317.798196) (xy 167.505634 -317.809118) (xy 167.507797 -317.814698) (xy 167.514343 -317.824712)
			(xy 167.518588 -317.82893) (xy 167.577516 -317.885064) (xy 167.581938 -317.889051) (xy 167.592202 -317.895078)
			(xy 167.597836 -317.897002) (xy 167.608758 -317.900304) (xy 167.620696 -317.898526) (xy 167.634122 -317.896407)
			(xy 167.661207 -317.894114) (xy 167.674798 -317.893954) (xy 167.684216 -317.893989) (xy 167.703024 -317.895003)
			(xy 167.71239 -317.895986) (xy 167.72382 -317.89751) (xy 167.734742 -317.8937) (xy 167.739967 -317.891636)
			(xy 167.749448 -317.885614) (xy 167.753538 -317.881762) (xy 167.810434 -317.825374) (xy 167.814236 -317.821354)
			(xy 167.820136 -317.811997) (xy 167.822118 -317.806832) (xy 167.826182 -317.796164) (xy 167.824912 -317.78448)
			(xy 167.82288 -317.75019) (xy 167.82288 -317.749682) (xy 167.8234 -317.723986) (xy 167.831471 -317.673232)
			(xy 167.847379 -317.624364) (xy 167.870733 -317.578585) (xy 167.900959 -317.537022) (xy 167.937312 -317.500696)
			(xy 167.978899 -317.470502) (xy 168.024696 -317.447183) (xy 168.073576 -317.431312) (xy 168.124336 -317.423281)
			(xy 168.150032 -317.422784) (xy 168.175739 -317.423265) (xy 168.22652 -317.431313) (xy 168.275416 -317.447205)
			(xy 168.321224 -317.470552) (xy 168.362816 -317.500776) (xy 168.399168 -317.537136) (xy 168.429384 -317.578734)
			(xy 168.452721 -317.624547) (xy 168.468603 -317.673447) (xy 168.476641 -317.724229) (xy 168.477184 -317.749936)
			(xy 168.476678 -317.77563) (xy 168.468639 -317.826386) (xy 168.452763 -317.87526) (xy 168.429442 -317.921052)
			(xy 168.399248 -317.962635) (xy 168.362925 -317.998986) (xy 168.321366 -318.029211) (xy 168.275592 -318.052567)
			(xy 168.226729 -318.06848) (xy 168.17598 -318.076559) (xy 168.150286 -318.077088) (xy 168.149778 -318.077088)
			(xy 168.115488 -318.075056) (xy 168.103804 -318.073786) (xy 168.092882 -318.07785) (xy 168.087738 -318.079875)
			(xy 168.078388 -318.085769) (xy 168.07434 -318.089534) (xy 168.018206 -318.145922) (xy 168.014171 -318.150125)
			(xy 168.008002 -318.160004) (xy 168.006014 -318.16548) (xy 168.002458 -318.175894) (xy 168.003728 -318.187578)
			(xy 168.004696 -318.196882) (xy 168.005713 -318.215562) (xy 168.00576 -318.224916) (xy 168.00576 -318.27343)
			(xy 168.006227 -318.284085) (xy 168.014925 -318.303537) (xy 168.022524 -318.311022) (xy 168.07815 -318.361568)
			(xy 168.08224 -318.36509) (xy 168.09159 -318.370475) (xy 168.096692 -318.372236) (xy 168.106598 -318.375538)
			(xy 168.11752 -318.374522) (xy 168.149778 -318.372744) (xy 168.150286 -318.372744) (xy 168.175129 -318.373221)
			(xy 168.224241 -318.380764) (xy 168.271646 -318.39565) (xy 168.316254 -318.417535) (xy 168.357038 -318.445916)
			(xy 168.39306 -318.480139) (xy 168.423491 -318.519418) (xy 168.447631 -318.562847) (xy 168.464923 -318.609428)
			(xy 168.47497 -318.658089) (xy 168.476676 -318.682878) (xy 168.477184 -318.692784) (xy 168.481248 -318.70142)
			(xy 168.483366 -318.70574) (xy 168.48899 -318.713545) (xy 168.492424 -318.716914) (xy 168.54297 -318.765174)
			(xy 168.544494 -318.766444) (xy 168.545002 -318.766952) (xy 168.551591 -318.772127) (xy 168.567142 -318.778335)
			(xy 168.575482 -318.779144) (xy 168.693846 -318.779144) (xy 168.703477 -318.778673) (xy 168.721357 -318.77149)
			(xy 168.728644 -318.765174) (xy 168.779444 -318.717168) (xy 168.782857 -318.713781) (xy 168.788474 -318.705978)
			(xy 168.79062 -318.701674) (xy 168.794684 -318.693038) (xy 168.795192 -318.683132) (xy 168.797136 -318.657474)
			(xy 168.808531 -318.607298) (xy 168.828175 -318.559743) (xy 168.85551 -318.516152) (xy 168.889765 -318.477759)
			(xy 168.92997 -318.44565) (xy 168.974987 -318.420733) (xy 169.023544 -318.403713) (xy 169.074266 -318.395072)
			(xy 169.099992 -318.394588) (xy 169.131742 -318.396112) (xy 169.14241 -318.397382) (xy 169.15257 -318.39408)
			(xy 169.160952 -318.390524) (xy 169.171112 -318.383412) (xy 169.226992 -318.332866) (xy 169.234492 -318.325318)
			(xy 169.243133 -318.305898) (xy 169.243756 -318.295274) (xy 169.243756 -318.224916) (xy 169.243919 -318.211262)
			(xy 169.24621 -318.18405) (xy 169.248328 -318.17056) (xy 169.250106 -318.158622) (xy 169.246804 -318.1477)
			(xy 169.244922 -318.142047) (xy 169.238891 -318.131774) (xy 169.234866 -318.12738) (xy 169.178732 -318.068452)
			(xy 169.174503 -318.06422) (xy 169.164493 -318.057673) (xy 169.15892 -318.055498) (xy 169.147998 -318.051688)
			(xy 169.13606 -318.053212) (xy 169.127076 -318.054196) (xy 169.10903 -318.055215) (xy 169.099992 -318.055244)
			(xy 169.075168 -318.054757) (xy 169.026174 -318.046724) (xy 168.979124 -318.030869) (xy 168.93526 -318.007612)
			(xy 168.895737 -317.977564) (xy 168.861595 -317.941518) (xy 168.833735 -317.900424) (xy 168.81289 -317.855363)
			(xy 168.79961 -317.807523) (xy 168.794245 -317.758165) (xy 168.796935 -317.70859) (xy 168.807611 -317.660103)
			(xy 168.825991 -317.613982) (xy 168.851591 -317.571442) (xy 168.883735 -317.533604) (xy 168.921578 -317.501465)
			(xy 168.964121 -317.475872) (xy 169.010245 -317.457498) (xy 169.058734 -317.44683) (xy 169.10831 -317.444146)
			(xy 169.157667 -317.449518) (xy 169.205504 -317.462805) (xy 169.250562 -317.483656) (xy 169.291653 -317.511522)
			(xy 169.327694 -317.545669) (xy 169.357736 -317.585197) (xy 169.380987 -317.629065) (xy 169.396834 -317.676116)
			(xy 169.404861 -317.725112) (xy 169.4053 -317.749936) (xy 169.40526 -317.759037) (xy 169.404241 -317.777209)
			(xy 169.403268 -317.786258) (xy 169.401744 -317.798196) (xy 169.405554 -317.809118) (xy 169.407718 -317.814697)
			(xy 169.414265 -317.82471) (xy 169.418508 -317.82893) (xy 169.477436 -317.885064) (xy 169.481854 -317.889057)
			(xy 169.492113 -317.895099) (xy 169.497756 -317.897002) (xy 169.508678 -317.900304) (xy 169.520616 -317.898526)
			(xy 169.534042 -317.896408) (xy 169.561127 -317.894116) (xy 169.574718 -317.893954) (xy 169.584136 -317.893989)
			(xy 169.602943 -317.895005) (xy 169.61231 -317.895986) (xy 169.62374 -317.89751) (xy 169.634662 -317.8937)
			(xy 169.639886 -317.891634) (xy 169.649364 -317.885609) (xy 169.653458 -317.881762) (xy 169.710354 -317.825374)
			(xy 169.714154 -317.821353) (xy 169.720052 -317.811996) (xy 169.722038 -317.806832) (xy 169.726102 -317.796164)
			(xy 169.724832 -317.78448) (xy 169.7228 -317.75019) (xy 169.7228 -317.749682) (xy 169.72332 -317.723984)
			(xy 169.73139 -317.673225) (xy 169.747297 -317.624352) (xy 169.77065 -317.578567) (xy 169.800874 -317.536997)
			(xy 169.837227 -317.500664) (xy 169.878813 -317.470461) (xy 169.924609 -317.447132) (xy 169.973491 -317.43125)
			(xy 170.024254 -317.423207) (xy 170.049952 -317.422784) (xy 170.075663 -317.423259) (xy 170.126453 -317.431297)
			(xy 170.17536 -317.447182) (xy 170.22118 -317.470524) (xy 170.262783 -317.500748) (xy 170.299144 -317.537108)
			(xy 170.329369 -317.57871) (xy 170.352713 -317.624528) (xy 170.368601 -317.673435) (xy 170.37664 -317.724225)
			(xy 170.377104 -317.749936) (xy 170.376598 -317.775628) (xy 170.368558 -317.826379) (xy 170.352681 -317.875248)
			(xy 170.329358 -317.921034) (xy 170.299164 -317.96261) (xy 170.262839 -317.998953) (xy 170.221279 -318.02917)
			(xy 170.175505 -318.052516) (xy 170.126644 -318.068418) (xy 170.075897 -318.076484) (xy 170.050206 -318.077088)
			(xy 170.049698 -318.077088) (xy 170.015408 -318.075056) (xy 170.003724 -318.073786) (xy 169.992802 -318.07785)
			(xy 169.987657 -318.079873) (xy 169.978305 -318.085765) (xy 169.97426 -318.089534) (xy 169.918126 -318.145922)
			(xy 169.91409 -318.150124) (xy 169.907918 -318.160003) (xy 169.905934 -318.16548) (xy 169.902378 -318.175894)
			(xy 169.903648 -318.187578) (xy 169.904616 -318.196882) (xy 169.905633 -318.215562) (xy 169.90568 -318.224916)
			(xy 169.90568 -318.27343) (xy 169.906145 -318.284087) (xy 169.914832 -318.303548) (xy 169.922444 -318.311022)
			(xy 169.97807 -318.361568) (xy 169.98216 -318.365088) (xy 169.991512 -318.37047) (xy 169.996612 -318.372236)
			(xy 170.006518 -318.375538) (xy 170.01744 -318.374522) (xy 170.049698 -318.372744) (xy 170.050206 -318.372744)
			(xy 170.075048 -318.373222) (xy 170.124157 -318.380768) (xy 170.17156 -318.395656) (xy 170.216165 -318.417542)
			(xy 170.256947 -318.445923) (xy 170.292967 -318.480146) (xy 170.323396 -318.519424) (xy 170.347533 -318.562853)
			(xy 170.364824 -318.609432) (xy 170.374871 -318.658091) (xy 170.376596 -318.682878) (xy 170.377104 -318.692784)
			(xy 170.381168 -318.70142) (xy 170.383287 -318.705739) (xy 170.388912 -318.713543) (xy 170.392344 -318.716914)
			(xy 170.44289 -318.765174) (xy 170.444414 -318.766444) (xy 170.444922 -318.766952) (xy 170.451512 -318.772124)
			(xy 170.467063 -318.778326) (xy 170.475402 -318.779144) (xy 170.593766 -318.779144) (xy 170.603403 -318.778687)
			(xy 170.621302 -318.771524) (xy 170.628564 -318.765174) (xy 170.679364 -318.717168) (xy 170.682776 -318.71378)
			(xy 170.688391 -318.705976) (xy 170.69054 -318.701674) (xy 170.694604 -318.693038) (xy 170.695112 -318.683132)
			(xy 170.697056 -318.657474) (xy 170.708451 -318.6073) (xy 170.728095 -318.559746) (xy 170.755431 -318.516157)
			(xy 170.789686 -318.477766) (xy 170.829891 -318.445659) (xy 170.874909 -318.420745) (xy 170.923465 -318.403728)
			(xy 170.974186 -318.39509) (xy 170.999912 -318.394588) (xy 171.031916 -318.396366) (xy 171.042838 -318.397382)
			(xy 171.052998 -318.39408) (xy 171.057955 -318.392341) (xy 171.067055 -318.387097) (xy 171.071032 -318.383666)
			(xy 171.12742 -318.33312) (xy 171.131484 -318.329056) (xy 171.136637 -318.322728) (xy 171.142967 -318.307697)
			(xy 171.14393 -318.299592) (xy 171.14393 -318.299084) (xy 171.144184 -318.295274) (xy 171.144184 -318.224916)
			(xy 171.144347 -318.211262) (xy 171.146637 -318.18405) (xy 171.148756 -318.17056) (xy 171.150788 -318.158622)
			(xy 171.147232 -318.147192) (xy 171.145717 -318.142662) (xy 171.141241 -318.134225) (xy 171.138342 -318.130428)
			(xy 171.135548 -318.12738) (xy 171.07916 -318.068452) (xy 171.074933 -318.064218) (xy 171.064925 -318.057665)
			(xy 171.059348 -318.055498) (xy 171.048426 -318.051688) (xy 171.036234 -318.052958) (xy 171.02719 -318.054007)
			(xy 171.009016 -318.055151) (xy 170.999912 -318.055244) (xy 170.975087 -318.054759) (xy 170.926092 -318.046728)
			(xy 170.879041 -318.030876) (xy 170.835175 -318.007621) (xy 170.795649 -317.977576) (xy 170.761505 -317.941531)
			(xy 170.733642 -317.900437) (xy 170.712795 -317.855377) (xy 170.699513 -317.807537) (xy 170.694145 -317.758179)
			(xy 170.696834 -317.708603) (xy 170.707508 -317.660114) (xy 170.725886 -317.613992) (xy 170.751484 -317.57145)
			(xy 170.783628 -317.533611) (xy 170.82147 -317.50147) (xy 170.864013 -317.475875) (xy 170.910137 -317.457501)
			(xy 170.958626 -317.446831) (xy 171.008203 -317.444146) (xy 171.057561 -317.449517) (xy 171.105399 -317.462803)
			(xy 171.150458 -317.483654) (xy 171.19155 -317.51152) (xy 171.227592 -317.545667) (xy 171.257634 -317.585195)
			(xy 171.280886 -317.629063) (xy 171.296734 -317.676115) (xy 171.304761 -317.725111) (xy 171.30522 -317.749936)
			(xy 171.305122 -317.75904) (xy 171.303979 -317.777213) (xy 171.302934 -317.786258) (xy 171.301664 -317.79845)
			(xy 171.305474 -317.809372) (xy 171.307644 -317.814947) (xy 171.3142 -317.82495) (xy 171.318428 -317.829184)
			(xy 171.377356 -317.885572) (xy 171.380404 -317.888366) (xy 171.384199 -317.891268) (xy 171.392636 -317.895746)
			(xy 171.397168 -317.897256) (xy 171.408598 -317.900812) (xy 171.420536 -317.89878) (xy 171.434024 -317.896649)
			(xy 171.461237 -317.89436) (xy 171.474892 -317.894208) (xy 171.484246 -317.894251) (xy 171.502927 -317.895266)
			(xy 171.51223 -317.89624) (xy 171.523914 -317.897764) (xy 171.534582 -317.893954) (xy 171.539894 -317.891949)
			(xy 171.549514 -317.885924) (xy 171.553632 -317.882016) (xy 171.610274 -317.825628) (xy 171.61407 -317.821605)
			(xy 171.619957 -317.812243) (xy 171.621958 -317.807086) (xy 171.626022 -317.796164) (xy 171.624752 -317.78448)
			(xy 171.62272 -317.75019) (xy 171.62272 -317.749682) (xy 171.62324 -317.723985) (xy 171.63131 -317.673227)
			(xy 171.647218 -317.624355) (xy 171.670571 -317.578572) (xy 171.700795 -317.537003) (xy 171.737148 -317.500672)
			(xy 171.778734 -317.470471) (xy 171.824531 -317.447145) (xy 171.873412 -317.431266) (xy 171.924174 -317.423225)
			(xy 171.949872 -317.422784) (xy 171.975582 -317.42326) (xy 172.02637 -317.431301) (xy 172.075274 -317.447188)
			(xy 172.121091 -317.470531) (xy 172.162691 -317.500755) (xy 172.19905 -317.537115) (xy 172.229273 -317.578716)
			(xy 172.252615 -317.624533) (xy 172.268501 -317.673438) (xy 172.276541 -317.724226) (xy 172.277024 -317.749936)
			(xy 172.276518 -317.775628) (xy 172.268478 -317.82638) (xy 172.252602 -317.875251) (xy 172.22928 -317.921039)
			(xy 172.199085 -317.962616) (xy 172.162761 -317.998961) (xy 172.121201 -318.02918) (xy 172.075427 -318.052529)
			(xy 172.026565 -318.068434) (xy 171.975818 -318.076503) (xy 171.950126 -318.077088) (xy 171.949618 -318.077088)
			(xy 171.915328 -318.075056) (xy 171.903644 -318.073786) (xy 171.892722 -318.07785) (xy 171.887581 -318.07988)
			(xy 171.878239 -318.085782) (xy 171.87418 -318.089534) (xy 171.817792 -318.146176) (xy 171.813911 -318.150315)
			(xy 171.807896 -318.159932) (xy 171.805854 -318.165226) (xy 171.802044 -318.175894) (xy 171.803568 -318.187578)
			(xy 171.804538 -318.196882) (xy 171.805557 -318.215562) (xy 171.8056 -318.224916) (xy 171.8056 -318.27343)
			(xy 171.806065 -318.284086) (xy 171.814755 -318.303545) (xy 171.822364 -318.311022) (xy 171.87799 -318.361568)
			(xy 171.882081 -318.365087) (xy 171.891434 -318.370465) (xy 171.896532 -318.372236) (xy 171.906438 -318.375538)
			(xy 171.91736 -318.374522) (xy 171.949618 -318.372744) (xy 171.950126 -318.372744) (xy 171.974967 -318.373224)
			(xy 172.024074 -318.380772) (xy 172.071474 -318.395661) (xy 172.116077 -318.417549) (xy 172.156856 -318.445931)
			(xy 172.192873 -318.480154) (xy 172.2233 -318.519431) (xy 172.247435 -318.562858) (xy 172.264725 -318.609436)
			(xy 172.274771 -318.658093) (xy 172.276516 -318.682878) (xy 172.277024 -318.692784) (xy 172.281088 -318.70142)
			(xy 172.283207 -318.705739) (xy 172.288834 -318.71354) (xy 172.292264 -318.716914) (xy 172.34281 -318.765174)
			(xy 172.344334 -318.766444) (xy 172.344842 -318.766952) (xy 172.351428 -318.772135) (xy 172.366978 -318.778361)
			(xy 172.375322 -318.779144) (xy 172.49394 -318.779144) (xy 172.503572 -318.778674) (xy 172.521452 -318.771492)
			(xy 172.528738 -318.765174) (xy 172.579538 -318.717168) (xy 172.582951 -318.713781) (xy 172.588569 -318.705978)
			(xy 172.590714 -318.701674) (xy 172.594778 -318.693038) (xy 172.595286 -318.683132) (xy 172.597229 -318.657473)
			(xy 172.608625 -318.607298) (xy 172.628268 -318.559742) (xy 172.655604 -318.51615) (xy 172.689859 -318.477757)
			(xy 172.730063 -318.445647) (xy 172.775081 -318.420729) (xy 172.823637 -318.403709) (xy 172.87436 -318.395067)
			(xy 172.900086 -318.394588) (xy 172.931836 -318.396366) (xy 172.942758 -318.397382) (xy 172.952918 -318.39408)
			(xy 172.9613 -318.390524) (xy 172.97146 -318.383412) (xy 173.02734 -318.332866) (xy 173.034846 -318.325321)
			(xy 173.043497 -318.305901) (xy 173.044104 -318.295274) (xy 173.044104 -318.224916) (xy 173.044267 -318.211262)
			(xy 173.046557 -318.18405) (xy 173.048676 -318.17056) (xy 173.050708 -318.158622) (xy 173.047152 -318.147192)
			(xy 173.045638 -318.142662) (xy 173.041163 -318.134223) (xy 173.038262 -318.130428) (xy 173.035468 -318.12738)
			(xy 172.97908 -318.068452) (xy 172.974849 -318.064224) (xy 172.964835 -318.057686) (xy 172.959268 -318.055498)
			(xy 172.948346 -318.051688) (xy 172.936408 -318.053212) (xy 172.927361 -318.0542) (xy 172.909187 -318.055214)
			(xy 172.900086 -318.055244) (xy 172.875262 -318.054757) (xy 172.826268 -318.046722) (xy 172.779219 -318.030867)
			(xy 172.735356 -318.007609) (xy 172.695833 -317.977561) (xy 172.661692 -317.941515) (xy 172.633832 -317.900419)
			(xy 172.612988 -317.855359) (xy 172.599709 -317.807519) (xy 172.594345 -317.758161) (xy 172.597036 -317.708586)
			(xy 172.607712 -317.660099) (xy 172.626093 -317.613979) (xy 172.651692 -317.571439) (xy 172.683837 -317.533602)
			(xy 172.72168 -317.501463) (xy 172.764224 -317.47587) (xy 172.810347 -317.457498) (xy 172.858836 -317.446829)
			(xy 172.908412 -317.444146) (xy 172.957768 -317.449519) (xy 173.005606 -317.462806) (xy 173.050663 -317.483657)
			(xy 173.091754 -317.511523) (xy 173.127794 -317.54567) (xy 173.157836 -317.585198) (xy 173.181087 -317.629065)
			(xy 173.196934 -317.676117) (xy 173.204961 -317.725112) (xy 173.205394 -317.749936) (xy 173.205354 -317.759037)
			(xy 173.204335 -317.777209) (xy 173.203362 -317.786258) (xy 173.201838 -317.798196) (xy 173.205648 -317.809118)
			(xy 173.207812 -317.814697) (xy 173.214358 -317.824711) (xy 173.218602 -317.82893) (xy 173.27753 -317.885318)
			(xy 173.280578 -317.888112) (xy 173.284374 -317.891012) (xy 173.292813 -317.895483) (xy 173.297342 -317.897002)
			(xy 173.308772 -317.900558) (xy 173.32071 -317.898526) (xy 173.334198 -317.896395) (xy 173.361411 -317.894102)
			(xy 173.375066 -317.893954) (xy 173.38442 -317.893996) (xy 173.403101 -317.895012) (xy 173.412404 -317.895986)
			(xy 173.424088 -317.897256) (xy 173.434502 -317.8937) (xy 173.439946 -317.891644) (xy 173.449821 -317.885494)
			(xy 173.45406 -317.881508) (xy 173.510448 -317.825374) (xy 173.514249 -317.821353) (xy 173.520147 -317.811996)
			(xy 173.522132 -317.806832) (xy 173.526196 -317.79591) (xy 173.524926 -317.78448) (xy 173.523148 -317.749936)
			(xy 173.523649 -317.724232) (xy 173.531684 -317.673455) (xy 173.547563 -317.624561) (xy 173.570893 -317.578752)
			(xy 173.601102 -317.537155) (xy 173.637445 -317.500796) (xy 173.679028 -317.470569) (xy 173.724827 -317.447218)
			(xy 173.773715 -317.431318) (xy 173.824487 -317.42326) (xy 173.875896 -317.423243) (xy 173.926674 -317.431267)
			(xy 173.975572 -317.447135) (xy 174.021386 -317.470455) (xy 174.062989 -317.500655) (xy 174.099356 -317.53699)
			(xy 174.129593 -317.578566) (xy 174.152954 -317.62436) (xy 174.168865 -317.673244) (xy 174.176934 -317.724015)
			(xy 174.176948 -317.749936) (xy 174.494202 -317.749936) (xy 174.498162 -317.700882) (xy 174.509939 -317.653098)
			(xy 174.52923 -317.607822) (xy 174.555533 -317.566226) (xy 174.588168 -317.529389) (xy 174.626289 -317.498264)
			(xy 174.66891 -317.473657) (xy 174.714926 -317.456205) (xy 174.763145 -317.446361) (xy 174.81232 -317.44438)
			(xy 174.861175 -317.450312) (xy 174.908446 -317.464004) (xy 174.952908 -317.485102) (xy 174.993411 -317.513058)
			(xy 175.028904 -317.54715) (xy 175.058469 -317.586494) (xy 175.08134 -317.630071) (xy 175.096924 -317.676752)
			(xy 175.104819 -317.725329) (xy 175.105314 -317.749936) (xy 175.104819 -317.774543) (xy 175.096924 -317.82312)
			(xy 175.08134 -317.869801) (xy 175.058469 -317.913378) (xy 175.028904 -317.952722) (xy 174.993411 -317.986814)
			(xy 174.952908 -318.01477) (xy 174.908446 -318.035868) (xy 174.861175 -318.04956) (xy 174.81232 -318.055492)
			(xy 174.763145 -318.053511) (xy 174.714926 -318.043667) (xy 174.66891 -318.026215) (xy 174.626289 -318.001608)
			(xy 174.588168 -317.970483) (xy 174.555533 -317.933646) (xy 174.52923 -317.89205) (xy 174.509939 -317.846774)
			(xy 174.498162 -317.79899) (xy 174.494202 -317.749936) (xy 174.176948 -317.749936) (xy 174.176962 -317.775423)
			(xy 174.16895 -317.826203) (xy 174.153093 -317.875105) (xy 174.129783 -317.920924) (xy 174.099592 -317.962534)
			(xy 174.063265 -317.998909) (xy 174.021696 -318.029155) (xy 173.975907 -318.052526) (xy 173.927027 -318.068448)
			(xy 173.876258 -318.076528) (xy 173.850554 -318.077088) (xy 173.850046 -318.077088) (xy 173.815502 -318.075056)
			(xy 173.804072 -318.073786) (xy 173.79315 -318.07785) (xy 173.788008 -318.079878) (xy 173.778662 -318.085776)
			(xy 173.774608 -318.089534) (xy 173.718474 -318.145922) (xy 173.714441 -318.150126) (xy 173.708276 -318.160007)
			(xy 173.706282 -318.16548) (xy 173.702726 -318.175894) (xy 173.703996 -318.187578) (xy 173.704964 -318.196882)
			(xy 173.705981 -318.215562) (xy 173.706028 -318.224916) (xy 173.706028 -318.27343) (xy 173.706494 -318.284085)
			(xy 173.715188 -318.303541) (xy 173.722792 -318.311022) (xy 173.778418 -318.361568) (xy 173.78251 -318.365085)
			(xy 173.791865 -318.370458) (xy 173.79696 -318.372236) (xy 173.806866 -318.375538) (xy 173.817788 -318.374522)
			(xy 173.849792 -318.372744) (xy 173.8503 -318.372744) (xy 173.875143 -318.373222) (xy 173.924252 -318.380767)
			(xy 173.971656 -318.395654) (xy 174.016262 -318.41754) (xy 174.057044 -318.445921) (xy 174.093065 -318.480144)
			(xy 174.123494 -318.519422) (xy 174.147632 -318.562851) (xy 174.164924 -318.609431) (xy 174.174971 -318.658091)
			(xy 174.17669 -318.682878) (xy 174.177198 -318.692784) (xy 174.181262 -318.70142) (xy 174.18338 -318.70574)
			(xy 174.189005 -318.713543) (xy 174.192438 -318.716914) (xy 174.242984 -318.765174) (xy 174.244508 -318.766444)
			(xy 174.245016 -318.766952) (xy 174.251605 -318.772126) (xy 174.267157 -318.778329) (xy 174.275496 -318.779144)
			(xy 174.39386 -318.779144) (xy 174.40349 -318.778671) (xy 174.421366 -318.771484) (xy 174.428658 -318.765174)
			(xy 174.479458 -318.717168) (xy 174.48287 -318.71378) (xy 174.488486 -318.705976) (xy 174.490634 -318.701674)
			(xy 174.494698 -318.693038) (xy 174.495206 -318.683132) (xy 174.49702 -318.658827) (xy 174.507394 -318.611208)
			(xy 174.525202 -318.565842) (xy 174.549993 -318.523883) (xy 174.581135 -318.486395) (xy 174.617838 -318.454331)
			(xy 174.659169 -318.428506) (xy 174.704079 -318.409577) (xy 174.751425 -318.398023) (xy 174.800006 -318.394139)
			(xy 174.848587 -318.398023) (xy 174.895933 -318.409577) (xy 174.940843 -318.428506) (xy 174.982174 -318.454331)
			(xy 175.018877 -318.486395) (xy 175.050019 -318.523883) (xy 175.07481 -318.565842) (xy 175.092618 -318.611208)
			(xy 175.102992 -318.658827) (xy 175.104806 -318.683132) (xy 175.105314 -318.693038) (xy 175.109378 -318.701674)
			(xy 175.111501 -318.70599) (xy 175.117133 -318.713787) (xy 175.120554 -318.717168) (xy 175.171354 -318.765174)
			(xy 175.178624 -318.771515) (xy 175.196515 -318.778684) (xy 175.206152 -318.779144) (xy 175.324516 -318.779144)
			(xy 175.332877 -318.778431) (xy 175.34845 -318.772203) (xy 175.354996 -318.766952) (xy 175.355504 -318.766444)
			(xy 175.357028 -318.765174) (xy 175.407574 -318.716914) (xy 175.410993 -318.713531) (xy 175.416624 -318.705734)
			(xy 175.41875 -318.70142) (xy 175.422814 -318.692784) (xy 175.423322 -318.682878) (xy 175.425082 -318.658099)
			(xy 175.435149 -318.609456) (xy 175.452453 -318.562893) (xy 175.476595 -318.51948) (xy 175.507022 -318.480215)
			(xy 175.543034 -318.446) (xy 175.583803 -318.417621) (xy 175.628394 -318.39573) (xy 175.675781 -318.380831)
			(xy 175.724876 -318.373264) (xy 175.749712 -318.372744) (xy 175.75022 -318.372744) (xy 175.782224 -318.374522)
			(xy 175.793146 -318.375538) (xy 175.803052 -318.372236) (xy 175.808142 -318.370451) (xy 175.817486 -318.365065)
			(xy 175.821594 -318.361568) (xy 175.87722 -318.311022) (xy 175.884726 -318.303475) (xy 175.893383 -318.284057)
			(xy 175.893984 -318.27343) (xy 175.893984 -318.224916) (xy 175.894027 -318.215562) (xy 175.895044 -318.196882)
			(xy 175.896016 -318.187578) (xy 175.897286 -318.175894) (xy 175.89373 -318.16548) (xy 175.891674 -318.160036)
			(xy 175.885524 -318.150161) (xy 175.881538 -318.145922) (xy 175.825404 -318.089534) (xy 175.821384 -318.085732)
			(xy 175.812028 -318.07983) (xy 175.806862 -318.07785) (xy 175.79594 -318.073786) (xy 175.78451 -318.075056)
			(xy 175.75022 -318.077088) (xy 175.749712 -318.077088) (xy 175.724035 -318.076562) (xy 175.673318 -318.068487)
			(xy 175.624488 -318.052579) (xy 175.578746 -318.029232) (xy 175.537219 -317.999019) (xy 175.500926 -317.962683)
			(xy 175.470763 -317.921119) (xy 175.44747 -317.875349) (xy 175.431622 -317.8265) (xy 175.423607 -317.775774)
			(xy 175.423623 -317.724418) (xy 175.43167 -317.673697) (xy 175.44755 -317.624858) (xy 175.470872 -317.579103)
			(xy 175.501062 -317.537559) (xy 175.537377 -317.501246) (xy 175.578924 -317.471059) (xy 175.62468 -317.447741)
			(xy 175.67352 -317.431865) (xy 175.724242 -317.423821) (xy 175.775598 -317.423809) (xy 175.826324 -317.431827)
			(xy 175.875172 -317.447679) (xy 175.920939 -317.470975) (xy 175.962501 -317.501142) (xy 175.998834 -317.537437)
			(xy 176.029044 -317.578967) (xy 176.052389 -317.62471) (xy 176.068292 -317.673541) (xy 176.076364 -317.724259)
			(xy 176.076864 -317.749936) (xy 176.075086 -317.78448) (xy 176.073816 -317.79591) (xy 176.07788 -317.806832)
			(xy 176.079903 -317.811977) (xy 176.085794 -317.82133) (xy 176.089564 -317.825374) (xy 176.145952 -317.881508)
			(xy 176.150156 -317.88554) (xy 176.160038 -317.891702) (xy 176.16551 -317.8937) (xy 176.175924 -317.897256)
			(xy 176.187608 -317.895986) (xy 176.196912 -317.895019) (xy 176.215592 -317.894004) (xy 176.224946 -317.893954)
			(xy 176.2386 -317.894115) (xy 176.265813 -317.896403) (xy 176.279302 -317.898526) (xy 176.29124 -317.900558)
			(xy 176.30267 -317.897002) (xy 176.307201 -317.895489) (xy 176.315641 -317.891016) (xy 176.319434 -317.888112)
			(xy 176.322482 -317.885318) (xy 176.38141 -317.82893) (xy 176.385644 -317.824703) (xy 176.392196 -317.814694)
			(xy 176.394364 -317.809118) (xy 176.398174 -317.798196) (xy 176.39665 -317.786258) (xy 176.395661 -317.777211)
			(xy 176.394644 -317.759037) (xy 176.394618 -317.749936) (xy 176.395101 -317.725117) (xy 176.403126 -317.676132)
			(xy 176.41897 -317.629091) (xy 176.442215 -317.585233) (xy 176.47225 -317.545713) (xy 176.508283 -317.511573)
			(xy 176.549365 -317.483712) (xy 176.594413 -317.462865) (xy 176.64224 -317.44958) (xy 176.691586 -317.444208)
			(xy 176.741152 -317.44689) (xy 176.78963 -317.457556) (xy 176.835744 -317.475924) (xy 176.878279 -317.50151)
			(xy 176.916115 -317.533641) (xy 176.948254 -317.57147) (xy 176.973849 -317.614) (xy 176.992226 -317.660111)
			(xy 177.002902 -317.708587) (xy 177.005594 -317.758152) (xy 177.000232 -317.807499) (xy 176.986957 -317.855329)
			(xy 176.966118 -317.900381) (xy 176.938266 -317.941468) (xy 176.904133 -317.977508) (xy 176.86462 -318.007551)
			(xy 176.820766 -318.030806) (xy 176.773728 -318.046659) (xy 176.724745 -318.054694) (xy 176.699926 -318.055244)
			(xy 176.690825 -318.055205) (xy 176.672652 -318.05419) (xy 176.663604 -318.053212) (xy 176.651666 -318.051688)
			(xy 176.640744 -318.055498) (xy 176.635165 -318.057663) (xy 176.625153 -318.06421) (xy 176.620932 -318.068452)
			(xy 176.564544 -318.12738) (xy 176.56175 -318.130428) (xy 176.558849 -318.134223) (xy 176.554373 -318.142661)
			(xy 176.55286 -318.147192) (xy 176.549304 -318.158622) (xy 176.551336 -318.17056) (xy 176.553465 -318.184048)
			(xy 176.555754 -318.211262) (xy 176.555908 -318.224916) (xy 176.555908 -318.295274) (xy 176.556363 -318.305935)
			(xy 176.56504 -318.325409) (xy 176.572672 -318.332866) (xy 176.628552 -318.383412) (xy 176.638712 -318.390524)
			(xy 176.647094 -318.39408) (xy 176.657254 -318.397382) (xy 176.668176 -318.396366) (xy 176.699926 -318.394588)
			(xy 176.725655 -318.395114) (xy 176.776385 -318.403731) (xy 176.824952 -318.420732) (xy 176.86998 -318.445638)
			(xy 176.910194 -318.477741) (xy 176.944455 -318.516133) (xy 176.971793 -318.559727) (xy 176.991433 -318.607288)
			(xy 177.00282 -318.657469) (xy 177.004726 -318.683132) (xy 177.005234 -318.693038) (xy 177.009298 -318.701674)
			(xy 177.011421 -318.70599) (xy 177.017055 -318.713784) (xy 177.020474 -318.717168) (xy 177.071274 -318.765174)
			(xy 177.07854 -318.771527) (xy 177.096431 -318.778724) (xy 177.106072 -318.779144) (xy 177.224436 -318.779144)
			(xy 177.232796 -318.778428) (xy 177.248365 -318.772195) (xy 177.254916 -318.766952) (xy 177.255424 -318.766444)
			(xy 177.256948 -318.765174) (xy 177.307494 -318.716914) (xy 177.310912 -318.71353) (xy 177.316541 -318.705733)
			(xy 177.31867 -318.70142) (xy 177.322734 -318.692784) (xy 177.323242 -318.682878) (xy 177.325002 -318.6581)
			(xy 177.335069 -318.609457) (xy 177.352373 -318.562896) (xy 177.376516 -318.519485) (xy 177.406943 -318.480221)
			(xy 177.442955 -318.446008) (xy 177.483725 -318.417632) (xy 177.528316 -318.395743) (xy 177.575702 -318.380846)
			(xy 177.624796 -318.373283) (xy 177.649632 -318.372744) (xy 177.65014 -318.372744) (xy 177.682144 -318.374522)
			(xy 177.693066 -318.375538) (xy 177.702972 -318.372236) (xy 177.708066 -318.370458) (xy 177.71742 -318.365082)
			(xy 177.721514 -318.361568) (xy 177.77714 -318.311022) (xy 177.784655 -318.30348) (xy 177.793326 -318.28406)
			(xy 177.793904 -318.27343) (xy 177.793904 -318.224916) (xy 177.793947 -318.215562) (xy 177.794964 -318.196882)
			(xy 177.795936 -318.187578) (xy 177.797206 -318.175894) (xy 177.79365 -318.16548) (xy 177.791595 -318.160036)
			(xy 177.785446 -318.150159) (xy 177.781458 -318.145922) (xy 177.725324 -318.089534) (xy 177.721305 -318.085731)
			(xy 177.71195 -318.079825) (xy 177.706782 -318.07785) (xy 177.69586 -318.073786) (xy 177.68443 -318.075056)
			(xy 177.65014 -318.077088) (xy 177.649632 -318.077088) (xy 177.623954 -318.076564) (xy 177.573236 -318.068491)
			(xy 177.524405 -318.052586) (xy 177.478661 -318.029241) (xy 177.437132 -317.99903) (xy 177.400837 -317.962695)
			(xy 177.370671 -317.921132) (xy 177.347376 -317.875363) (xy 177.331525 -317.826514) (xy 177.323508 -317.775788)
			(xy 177.323522 -317.724431) (xy 177.331567 -317.673709) (xy 177.347446 -317.624869) (xy 177.370766 -317.579113)
			(xy 177.400955 -317.537567) (xy 177.43727 -317.501252) (xy 177.478816 -317.471064) (xy 177.524573 -317.447744)
			(xy 177.573413 -317.431866) (xy 177.624135 -317.423822) (xy 177.675492 -317.423808) (xy 177.726218 -317.431826)
			(xy 177.775067 -317.447678) (xy 177.820836 -317.470973) (xy 177.862398 -317.50114) (xy 177.898732 -317.537435)
			(xy 177.928943 -317.578965) (xy 177.952288 -317.624709) (xy 177.968192 -317.67354) (xy 177.976264 -317.724258)
			(xy 177.976784 -317.749936) (xy 177.975006 -317.78448) (xy 177.973736 -317.79591) (xy 177.9778 -317.806832)
			(xy 177.979824 -317.811977) (xy 177.985716 -317.821328) (xy 177.989484 -317.825374) (xy 178.045872 -317.881508)
			(xy 178.050077 -317.885538) (xy 178.059961 -317.891696) (xy 178.06543 -317.8937) (xy 178.075844 -317.897256)
			(xy 178.087528 -317.895986) (xy 178.096832 -317.895019) (xy 178.115512 -317.894005) (xy 178.124866 -317.893954)
			(xy 178.13852 -317.894116) (xy 178.165733 -317.896406) (xy 178.179222 -317.898526) (xy 178.19116 -317.900558)
			(xy 178.20259 -317.897002) (xy 178.20712 -317.895488) (xy 178.215558 -317.891012) (xy 178.219354 -317.888112)
			(xy 178.222402 -317.885318) (xy 178.28133 -317.82893) (xy 178.285563 -317.824702) (xy 178.292112 -317.814692)
			(xy 178.294284 -317.809118) (xy 178.298094 -317.798196) (xy 178.29657 -317.786258) (xy 178.295581 -317.777211)
			(xy 178.294564 -317.759037) (xy 178.294538 -317.749936) (xy 178.295021 -317.725119) (xy 178.303045 -317.676138)
			(xy 178.318887 -317.6291) (xy 178.342131 -317.585245) (xy 178.372163 -317.545729) (xy 178.408193 -317.511591)
			(xy 178.449271 -317.483732) (xy 178.494315 -317.462885) (xy 178.542138 -317.449601) (xy 178.59148 -317.444228)
			(xy 178.641042 -317.446909) (xy 178.689517 -317.457572) (xy 178.735628 -317.475938) (xy 178.77816 -317.501521)
			(xy 178.815994 -317.533648) (xy 178.848131 -317.571473) (xy 178.873726 -317.613999) (xy 178.892103 -317.660105)
			(xy 178.90278 -317.708577) (xy 178.905474 -317.758138) (xy 178.900115 -317.807481) (xy 178.886843 -317.855308)
			(xy 178.866009 -317.900357) (xy 178.838161 -317.941443) (xy 178.804033 -317.977482) (xy 178.764524 -318.007525)
			(xy 178.720675 -318.03078) (xy 178.673642 -318.046635) (xy 178.624663 -318.054673) (xy 178.599846 -318.055244)
			(xy 178.590745 -318.055206) (xy 178.572572 -318.054192) (xy 178.563524 -318.053212) (xy 178.551586 -318.051688)
			(xy 178.540664 -318.055498) (xy 178.535084 -318.057661) (xy 178.525069 -318.064206) (xy 178.520852 -318.068452)
			(xy 178.464464 -318.12738) (xy 178.46167 -318.130428) (xy 178.458768 -318.134222) (xy 178.45429 -318.14266)
			(xy 178.45278 -318.147192) (xy 178.449224 -318.158622) (xy 178.451256 -318.17056) (xy 178.453385 -318.184048)
			(xy 178.455674 -318.211262) (xy 178.455828 -318.224916) (xy 178.455828 -318.295274) (xy 178.456283 -318.305935)
			(xy 178.464962 -318.325407) (xy 178.472592 -318.332866) (xy 178.528472 -318.383412) (xy 178.538632 -318.390524)
			(xy 178.547014 -318.39408) (xy 178.557174 -318.397382) (xy 178.568096 -318.396366) (xy 178.599846 -318.394588)
			(xy 178.625573 -318.395116) (xy 178.676301 -318.403735) (xy 178.724865 -318.420738) (xy 178.76989 -318.445645)
			(xy 178.810101 -318.477748) (xy 178.84436 -318.51614) (xy 178.871696 -318.559733) (xy 178.891334 -318.607292)
			(xy 178.90272 -318.657472) (xy 178.904646 -318.683132) (xy 178.905154 -318.693038) (xy 178.909218 -318.701674)
			(xy 178.911338 -318.705992) (xy 178.916965 -318.713793) (xy 178.920394 -318.717168) (xy 178.971194 -318.765174)
			(xy 178.978461 -318.771524) (xy 178.996352 -318.778713) (xy 179.005992 -318.779144) (xy 179.12461 -318.779144)
			(xy 179.132972 -318.778432) (xy 179.148546 -318.772205) (xy 179.15509 -318.766952) (xy 179.155598 -318.766444)
			(xy 179.157122 -318.765174) (xy 179.207668 -318.716914) (xy 179.211087 -318.713531) (xy 179.216719 -318.705735)
			(xy 179.218844 -318.70142) (xy 179.222908 -318.692784) (xy 179.223416 -318.682878) (xy 179.225176 -318.658099)
			(xy 179.235243 -318.609455) (xy 179.252546 -318.562892) (xy 179.276689 -318.519479) (xy 179.307116 -318.480213)
			(xy 179.343127 -318.445998) (xy 179.383897 -318.417618) (xy 179.428488 -318.395726) (xy 179.475875 -318.380826)
			(xy 179.524969 -318.373259) (xy 179.549806 -318.372744) (xy 179.550314 -318.372744) (xy 179.582572 -318.374522)
			(xy 179.593494 -318.375538) (xy 179.6034 -318.372236) (xy 179.608493 -318.370456) (xy 179.617843 -318.365076)
			(xy 179.621942 -318.361568) (xy 179.677568 -318.311022) (xy 179.68508 -318.303478) (xy 179.693746 -318.284059)
			(xy 179.694332 -318.27343) (xy 179.694332 -318.224916) (xy 179.694375 -318.215562) (xy 179.69539 -318.196881)
			(xy 179.696364 -318.187578) (xy 179.697888 -318.175894) (xy 179.694078 -318.165226) (xy 179.692075 -318.159913)
			(xy 179.686053 -318.15029) (xy 179.68214 -318.146176) (xy 179.625752 -318.089534) (xy 179.62173 -318.085736)
			(xy 179.612371 -318.079843) (xy 179.60721 -318.07785) (xy 179.596288 -318.073786) (xy 179.584604 -318.075056)
			(xy 179.550314 -318.077088) (xy 179.549806 -318.077088) (xy 179.524112 -318.076562) (xy 179.473363 -318.068483)
			(xy 179.424501 -318.052569) (xy 179.378728 -318.029212) (xy 179.337169 -317.998986) (xy 179.300846 -317.962635)
			(xy 179.270653 -317.921052) (xy 179.247332 -317.87526) (xy 179.231457 -317.826386) (xy 179.223418 -317.77563)
			(xy 179.222908 -317.749936) (xy 179.223409 -317.724225) (xy 179.231448 -317.673436) (xy 179.247332 -317.62453)
			(xy 179.270672 -317.57871) (xy 179.300892 -317.537106) (xy 179.337248 -317.500741) (xy 179.378845 -317.470512)
			(xy 179.424659 -317.447161) (xy 179.473562 -317.431266) (xy 179.524349 -317.423215) (xy 179.55006 -317.422784)
			(xy 179.575756 -317.423284) (xy 179.626517 -317.431315) (xy 179.675397 -317.447184) (xy 179.721195 -317.470503)
			(xy 179.762782 -317.500696) (xy 179.799136 -317.537022) (xy 179.829362 -317.578585) (xy 179.852717 -317.624364)
			(xy 179.868625 -317.673232) (xy 179.876696 -317.723986) (xy 179.877212 -317.749682) (xy 179.877212 -317.75019)
			(xy 179.87518 -317.78448) (xy 179.87391 -317.796164) (xy 179.877974 -317.807086) (xy 179.879993 -317.812234)
			(xy 179.885877 -317.821593) (xy 179.889658 -317.825628) (xy 179.9463 -317.882016) (xy 179.950436 -317.885902)
			(xy 179.960049 -317.891929) (xy 179.96535 -317.893954) (xy 179.976018 -317.897764) (xy 179.987702 -317.89624)
			(xy 179.997006 -317.895271) (xy 180.015686 -317.894254) (xy 180.02504 -317.894208) (xy 180.038694 -317.894369)
			(xy 180.065907 -317.896656) (xy 180.079396 -317.89878) (xy 180.091334 -317.900812) (xy 180.102764 -317.897256)
			(xy 180.107296 -317.895745) (xy 180.115739 -317.891276) (xy 180.119528 -317.888366) (xy 180.122576 -317.885572)
			(xy 180.181504 -317.829184) (xy 180.185735 -317.824955) (xy 180.192279 -317.814943) (xy 180.194458 -317.809372)
			(xy 180.198268 -317.79845) (xy 180.196998 -317.786258) (xy 180.195948 -317.777214) (xy 180.194802 -317.75904)
			(xy 180.194712 -317.749936) (xy 180.195195 -317.725116) (xy 180.20322 -317.67613) (xy 180.219064 -317.629088)
			(xy 180.242311 -317.585229) (xy 180.272347 -317.545708) (xy 180.308381 -317.511568) (xy 180.349463 -317.483706)
			(xy 180.394512 -317.462859) (xy 180.442341 -317.449574) (xy 180.491688 -317.444202) (xy 180.541255 -317.446884)
			(xy 180.589734 -317.457551) (xy 180.635849 -317.475919) (xy 180.678385 -317.501507) (xy 180.716221 -317.533639)
			(xy 180.74836 -317.571469) (xy 180.773956 -317.614) (xy 180.792333 -317.660112) (xy 180.803008 -317.70859)
			(xy 180.8057 -317.758156) (xy 180.800337 -317.807504) (xy 180.787061 -317.855335) (xy 180.766221 -317.900388)
			(xy 180.738368 -317.941476) (xy 180.704234 -317.977516) (xy 180.664719 -318.007559) (xy 180.620863 -318.030813)
			(xy 180.573824 -318.046667) (xy 180.524839 -318.054701) (xy 180.50002 -318.055244) (xy 180.490916 -318.055145)
			(xy 180.472743 -318.053999) (xy 180.463698 -318.052958) (xy 180.451506 -318.051688) (xy 180.440584 -318.055498)
			(xy 180.435003 -318.05766) (xy 180.424985 -318.064201) (xy 180.420772 -318.068452) (xy 180.364384 -318.12738)
			(xy 180.36159 -318.130428) (xy 180.358687 -318.134222) (xy 180.354207 -318.142659) (xy 180.3527 -318.147192)
			(xy 180.349144 -318.158622) (xy 180.351176 -318.17056) (xy 180.353306 -318.184048) (xy 180.355592 -318.211262)
			(xy 180.355748 -318.224916) (xy 180.355748 -318.295274) (xy 180.356002 -318.299084) (xy 180.356002 -318.299592)
			(xy 180.356964 -318.307694) (xy 180.363313 -318.322715) (xy 180.368448 -318.329056) (xy 180.372512 -318.33312)
			(xy 180.4289 -318.383666) (xy 180.432904 -318.38706) (xy 180.441992 -318.39231) (xy 180.446934 -318.39408)
			(xy 180.457094 -318.397382) (xy 180.468016 -318.396366) (xy 180.50002 -318.394588) (xy 180.525749 -318.395114)
			(xy 180.57648 -318.403729) (xy 180.625048 -318.420731) (xy 180.670076 -318.445635) (xy 180.710291 -318.477739)
			(xy 180.744553 -318.516131) (xy 180.771892 -318.559726) (xy 180.791533 -318.607287) (xy 180.80292 -318.657469)
			(xy 180.80482 -318.683132) (xy 180.805328 -318.693038) (xy 180.809392 -318.701674) (xy 180.811515 -318.70599)
			(xy 180.817148 -318.713785) (xy 180.820568 -318.717168) (xy 180.871368 -318.765174) (xy 180.878633 -318.771528)
			(xy 180.896524 -318.778727) (xy 180.906166 -318.779144) (xy 181.02453 -318.779144) (xy 181.03289 -318.778429)
			(xy 181.04846 -318.772198) (xy 181.05501 -318.766952) (xy 181.055518 -318.766444) (xy 181.057042 -318.765174)
			(xy 181.107588 -318.716914) (xy 181.111006 -318.71353) (xy 181.116636 -318.705733) (xy 181.118764 -318.70142)
			(xy 181.122828 -318.692784) (xy 181.123336 -318.682878) (xy 181.125096 -318.658099) (xy 181.135163 -318.609457)
			(xy 181.152467 -318.562895) (xy 181.17661 -318.519483) (xy 181.207037 -318.480219) (xy 181.243049 -318.446006)
			(xy 181.283819 -318.417628) (xy 181.328409 -318.395739) (xy 181.375796 -318.380842) (xy 181.42489 -318.373277)
			(xy 181.449726 -318.372744) (xy 181.450234 -318.372744) (xy 181.482492 -318.374522) (xy 181.493414 -318.375538)
			(xy 181.50332 -318.372236) (xy 181.508412 -318.370454) (xy 181.51776 -318.365072) (xy 181.521862 -318.361568)
			(xy 181.577488 -318.311022) (xy 181.584997 -318.303477) (xy 181.59366 -318.284058) (xy 181.594252 -318.27343)
			(xy 181.594252 -318.224916) (xy 181.594295 -318.215562) (xy 181.59531 -318.196881) (xy 181.596284 -318.187578)
			(xy 181.597808 -318.175894) (xy 181.593998 -318.165226) (xy 181.591992 -318.159915) (xy 181.585963 -318.150299)
			(xy 181.58206 -318.146176) (xy 181.525672 -318.089534) (xy 181.521651 -318.085735) (xy 181.512293 -318.079838)
			(xy 181.50713 -318.07785) (xy 181.496208 -318.073786) (xy 181.484524 -318.075056) (xy 181.450234 -318.077088)
			(xy 181.449726 -318.077088) (xy 181.424031 -318.076564) (xy 181.37328 -318.068487) (xy 181.324415 -318.052575)
			(xy 181.278639 -318.029219) (xy 181.237077 -317.998993) (xy 181.200752 -317.962641) (xy 181.170557 -317.921058)
			(xy 181.147234 -317.875265) (xy 181.131358 -317.826388) (xy 181.123318 -317.775631) (xy 181.122828 -317.749936)
			(xy 181.123303 -317.724224) (xy 181.131343 -317.673432) (xy 181.147229 -317.624523) (xy 181.17057 -317.578701)
			(xy 181.200793 -317.537095) (xy 181.237153 -317.50073) (xy 181.278753 -317.4705) (xy 181.324571 -317.44715)
			(xy 181.373477 -317.431256) (xy 181.424268 -317.423208) (xy 181.44998 -317.422784) (xy 181.475675 -317.423286)
			(xy 181.526433 -317.431319) (xy 181.575311 -317.44719) (xy 181.621106 -317.47051) (xy 181.66269 -317.500703)
			(xy 181.699042 -317.537028) (xy 181.729266 -317.578591) (xy 181.752619 -317.624369) (xy 181.768526 -317.673235)
			(xy 181.776596 -317.723987) (xy 181.777132 -317.749682) (xy 181.777132 -317.75019) (xy 181.7751 -317.78448)
			(xy 181.77383 -317.796164) (xy 181.777894 -317.807086) (xy 181.779914 -317.812233) (xy 181.7858 -317.821591)
			(xy 181.789578 -317.825628) (xy 181.84622 -317.882016) (xy 181.850357 -317.885901) (xy 181.859971 -317.891924)
			(xy 181.86527 -317.893954) (xy 181.875938 -317.897764) (xy 181.887622 -317.89624) (xy 181.896926 -317.895272)
			(xy 181.915606 -317.894256) (xy 181.92496 -317.894208) (xy 181.938614 -317.89437) (xy 181.965827 -317.896658)
			(xy 181.979316 -317.89878) (xy 181.991254 -317.900812) (xy 182.002684 -317.897256) (xy 182.007216 -317.895744)
			(xy 182.015657 -317.891272) (xy 182.019448 -317.888366) (xy 182.022496 -317.885572) (xy 182.081424 -317.829184)
			(xy 182.085654 -317.824954) (xy 182.092195 -317.814942) (xy 182.094378 -317.809372) (xy 182.098188 -317.79845)
			(xy 182.096918 -317.786258) (xy 182.095869 -317.777214) (xy 182.094723 -317.75904) (xy 182.094632 -317.749936)
			(xy 182.095115 -317.725118) (xy 182.103139 -317.676136) (xy 182.118982 -317.629098) (xy 182.142226 -317.585242)
			(xy 182.172259 -317.545724) (xy 182.20829 -317.511585) (xy 182.249369 -317.483726) (xy 182.294414 -317.462879)
			(xy 182.342239 -317.449595) (xy 182.391582 -317.444222) (xy 182.441145 -317.446903) (xy 182.489621 -317.457567)
			(xy 182.535733 -317.475934) (xy 182.578266 -317.501518) (xy 182.6161 -317.533646) (xy 182.648238 -317.571472)
			(xy 182.673833 -317.613999) (xy 182.69221 -317.660107) (xy 182.702886 -317.70858) (xy 182.70558 -317.758142)
			(xy 182.70022 -317.807487) (xy 182.686947 -317.855314) (xy 182.666112 -317.900365) (xy 182.638262 -317.94145)
			(xy 182.604133 -317.97749) (xy 182.564623 -318.007533) (xy 182.520772 -318.030788) (xy 182.473738 -318.046643)
			(xy 182.424757 -318.054679) (xy 182.39994 -318.055244) (xy 182.390836 -318.055146) (xy 182.372663 -318.054001)
			(xy 182.363618 -318.052958) (xy 182.351426 -318.051688) (xy 182.340504 -318.055498) (xy 182.334922 -318.057658)
			(xy 182.324901 -318.064197) (xy 182.320692 -318.068452) (xy 182.264304 -318.12738) (xy 182.26151 -318.130428)
			(xy 182.258606 -318.134221) (xy 182.254125 -318.142658) (xy 182.25262 -318.147192) (xy 182.249064 -318.158622)
			(xy 182.251096 -318.17056) (xy 182.253226 -318.184048) (xy 182.255512 -318.211262) (xy 182.255668 -318.224916)
			(xy 182.255668 -318.295274) (xy 182.255922 -318.299084) (xy 182.255922 -318.299592) (xy 182.256885 -318.307694)
			(xy 182.263235 -318.322713) (xy 182.268368 -318.329056) (xy 182.272432 -318.33312) (xy 182.32882 -318.383666)
			(xy 182.332825 -318.387059) (xy 182.341914 -318.392305) (xy 182.346854 -318.39408) (xy 182.357014 -318.397382)
			(xy 182.367936 -318.396366) (xy 182.39994 -318.394588) (xy 182.425668 -318.395115) (xy 182.476396 -318.403734)
			(xy 182.524961 -318.420737) (xy 182.569987 -318.445642) (xy 182.610199 -318.477746) (xy 182.644458 -318.516138)
			(xy 182.671795 -318.559731) (xy 182.691434 -318.607291) (xy 182.70282 -318.657471) (xy 182.70474 -318.683132)
			(xy 182.705248 -318.693038) (xy 182.709312 -318.701674) (xy 182.711432 -318.705992) (xy 182.717059 -318.713794)
			(xy 182.720488 -318.717168) (xy 182.771288 -318.765174) (xy 182.778554 -318.771525) (xy 182.796446 -318.778717)
			(xy 182.806086 -318.779144) (xy 182.943754 -318.779144) (xy 182.953385 -318.778672) (xy 182.971262 -318.771486)
			(xy 182.978552 -318.765174) (xy 183.029352 -318.717168) (xy 183.032764 -318.71378) (xy 183.038381 -318.705977)
			(xy 183.040528 -318.701674) (xy 183.044592 -318.693038) (xy 183.0451 -318.683132) (xy 183.047044 -318.657474)
			(xy 183.058439 -318.607299) (xy 183.078083 -318.559744) (xy 183.105419 -318.516154) (xy 183.139674 -318.477762)
			(xy 183.179878 -318.445654) (xy 183.224896 -318.420738) (xy 183.273452 -318.403719) (xy 183.324174 -318.395079)
			(xy 183.3499 -318.394588) (xy 183.381904 -318.396366) (xy 183.392826 -318.397382) (xy 183.402986 -318.39408)
			(xy 183.407943 -318.392342) (xy 183.417045 -318.3871) (xy 183.42102 -318.383666) (xy 183.477408 -318.33312)
			(xy 183.481472 -318.329056) (xy 183.486626 -318.322729) (xy 183.492957 -318.307698) (xy 183.493918 -318.299592)
			(xy 183.493918 -318.299084) (xy 183.494172 -318.295274) (xy 183.494172 -318.224916) (xy 183.494335 -318.211262)
			(xy 183.496626 -318.18405) (xy 183.498744 -318.17056) (xy 183.500776 -318.158622) (xy 183.49722 -318.147192)
			(xy 183.495705 -318.142662) (xy 183.491228 -318.134226) (xy 183.48833 -318.130428) (xy 183.485536 -318.12738)
			(xy 183.429148 -318.068452) (xy 183.42492 -318.064219) (xy 183.414911 -318.057669) (xy 183.409336 -318.055498)
			(xy 183.398414 -318.051688) (xy 183.386222 -318.052958) (xy 183.377178 -318.054006) (xy 183.359004 -318.05515)
			(xy 183.3499 -318.055244) (xy 183.325076 -318.054758) (xy 183.276081 -318.046725) (xy 183.229031 -318.030872)
			(xy 183.185166 -318.007616) (xy 183.145642 -317.977569) (xy 183.111499 -317.941523) (xy 183.083638 -317.900429)
			(xy 183.062792 -317.855368) (xy 183.049511 -317.807529) (xy 183.044145 -317.758171) (xy 183.046835 -317.708595)
			(xy 183.05751 -317.660107) (xy 183.075889 -317.613986) (xy 183.101488 -317.571445) (xy 183.133632 -317.533607)
			(xy 183.171475 -317.501467) (xy 183.214018 -317.475873) (xy 183.260142 -317.457499) (xy 183.308631 -317.44683)
			(xy 183.358207 -317.444146) (xy 183.407564 -317.449518) (xy 183.455402 -317.462804) (xy 183.50046 -317.483655)
			(xy 183.541552 -317.511521) (xy 183.577593 -317.545668) (xy 183.607635 -317.585197) (xy 183.630886 -317.629064)
			(xy 183.646734 -317.676116) (xy 183.654761 -317.725112) (xy 183.655208 -317.749936) (xy 183.65511 -317.75904)
			(xy 183.653967 -317.777213) (xy 183.652922 -317.786258) (xy 183.651652 -317.79845) (xy 183.655462 -317.809372)
			(xy 183.657631 -317.814948) (xy 183.664186 -317.824952) (xy 183.668416 -317.829184) (xy 183.727344 -317.885572)
			(xy 183.730392 -317.888366) (xy 183.73419 -317.891262) (xy 183.742631 -317.895727) (xy 183.747156 -317.897256)
			(xy 183.758586 -317.900812) (xy 183.770524 -317.89878) (xy 183.784012 -317.896648) (xy 183.811225 -317.894358)
			(xy 183.82488 -317.894208) (xy 183.838534 -317.894371) (xy 183.865746 -317.896661) (xy 183.879236 -317.89878)
			(xy 183.891174 -317.900812) (xy 183.902604 -317.897256) (xy 183.907135 -317.895742) (xy 183.915574 -317.891268)
			(xy 183.919368 -317.888366) (xy 183.922416 -317.885572) (xy 183.981344 -317.829184) (xy 183.985572 -317.824953)
			(xy 183.992111 -317.81494) (xy 183.994298 -317.809372) (xy 183.998108 -317.79845) (xy 183.996838 -317.786258)
			(xy 183.995789 -317.777214) (xy 183.994643 -317.75904) (xy 183.994552 -317.749936) (xy 183.995035 -317.725111)
			(xy 184.003062 -317.676113) (xy 184.018911 -317.62906) (xy 184.042164 -317.58519) (xy 184.072208 -317.545661)
			(xy 184.108252 -317.511514) (xy 184.149345 -317.483647) (xy 184.194406 -317.462797) (xy 184.242247 -317.449512)
			(xy 184.291606 -317.444141) (xy 184.341184 -317.446828) (xy 184.389674 -317.4575) (xy 184.435799 -317.475877)
			(xy 184.478343 -317.501475) (xy 184.516185 -317.533618) (xy 184.548328 -317.57146) (xy 184.573925 -317.614004)
			(xy 184.592301 -317.660129) (xy 184.602973 -317.70862) (xy 184.605658 -317.758198) (xy 184.600288 -317.807557)
			(xy 184.587002 -317.855398) (xy 184.566151 -317.900458) (xy 184.538284 -317.941551) (xy 184.504136 -317.977594)
			(xy 184.464606 -318.007638) (xy 184.420737 -318.03089) (xy 184.373683 -318.046739) (xy 184.324685 -318.054765)
			(xy 184.29986 -318.055244) (xy 184.290756 -318.055146) (xy 184.272583 -318.054003) (xy 184.263538 -318.052958)
			(xy 184.251346 -318.051688) (xy 184.240424 -318.055498) (xy 184.234841 -318.057656) (xy 184.224816 -318.064192)
			(xy 184.220612 -318.068452) (xy 184.164224 -318.12738) (xy 184.16143 -318.130428) (xy 184.15853 -318.134223)
			(xy 184.154055 -318.142662) (xy 184.15254 -318.147192) (xy 184.148984 -318.158622) (xy 184.151016 -318.17056)
			(xy 184.153146 -318.184048) (xy 184.155433 -318.211261) (xy 184.155588 -318.224916) (xy 184.155588 -318.295274)
			(xy 184.155842 -318.299084) (xy 184.155842 -318.299592) (xy 184.156806 -318.307693) (xy 184.163158 -318.322712)
			(xy 184.168288 -318.329056) (xy 184.172352 -318.33312) (xy 184.22874 -318.383666) (xy 184.232746 -318.387057)
			(xy 184.241836 -318.3923) (xy 184.246774 -318.39408) (xy 184.256934 -318.397382) (xy 184.267856 -318.396366)
			(xy 184.29986 -318.394588) (xy 184.325587 -318.395117) (xy 184.376312 -318.403738) (xy 184.424874 -318.420743)
			(xy 184.469898 -318.44565) (xy 184.510107 -318.477753) (xy 184.544363 -318.516145) (xy 184.571698 -318.559737)
			(xy 184.591335 -318.607295) (xy 184.60272 -318.657473) (xy 184.60466 -318.683132) (xy 184.605168 -318.693038)
			(xy 184.609232 -318.701674) (xy 184.611353 -318.705992) (xy 184.616981 -318.713792) (xy 184.620408 -318.717168)
			(xy 184.671208 -318.765174) (xy 184.678475 -318.771522) (xy 184.696367 -318.778706) (xy 184.706006 -318.779144)
			(xy 184.843928 -318.779144) (xy 184.853561 -318.778676) (xy 184.871444 -318.771497) (xy 184.878726 -318.765174)
			(xy 184.929526 -318.717168) (xy 184.93294 -318.713781) (xy 184.938559 -318.705979) (xy 184.940702 -318.701674)
			(xy 184.944766 -318.693038) (xy 184.945274 -318.683132) (xy 184.947217 -318.657473) (xy 184.958613 -318.607297)
			(xy 184.978256 -318.55974) (xy 185.005591 -318.516147) (xy 185.039846 -318.477752) (xy 185.08005 -318.445641)
			(xy 185.125068 -318.420722) (xy 185.173624 -318.4037) (xy 185.224347 -318.395056) (xy 185.250074 -318.394588)
			(xy 185.281824 -318.396366) (xy 185.292746 -318.397382) (xy 185.302906 -318.39408) (xy 185.311288 -318.390524)
			(xy 185.321448 -318.383412) (xy 185.377328 -318.332866) (xy 185.384835 -318.325321) (xy 185.393488 -318.305901)
			(xy 185.394092 -318.295274) (xy 185.394092 -318.224916) (xy 185.394255 -318.211262) (xy 185.396545 -318.18405)
			(xy 185.398664 -318.17056) (xy 185.400696 -318.158622) (xy 185.39714 -318.147192) (xy 185.395625 -318.142662)
			(xy 185.39115 -318.134224) (xy 185.38825 -318.130428) (xy 185.385456 -318.12738) (xy 185.329068 -318.068452)
			(xy 185.324841 -318.064217) (xy 185.314833 -318.057663) (xy 185.309256 -318.055498) (xy 185.298334 -318.051688)
			(xy 185.286396 -318.053212) (xy 185.277349 -318.054203) (xy 185.259175 -318.055222) (xy 185.250074 -318.055244)
			(xy 185.22525 -318.054756) (xy 185.176257 -318.04672) (xy 185.129209 -318.030863) (xy 185.085347 -318.007603)
			(xy 185.045825 -317.977554) (xy 185.011686 -317.941507) (xy 184.983828 -317.900411) (xy 184.962985 -317.85535)
			(xy 184.949708 -317.807511) (xy 184.944344 -317.758153) (xy 184.947037 -317.708579) (xy 184.957715 -317.660092)
			(xy 184.976096 -317.613973) (xy 185.001696 -317.571434) (xy 185.033841 -317.533597) (xy 185.071684 -317.50146)
			(xy 185.114228 -317.475868) (xy 185.160352 -317.457496) (xy 185.20884 -317.446829) (xy 185.258415 -317.444146)
			(xy 185.307772 -317.449519) (xy 185.355609 -317.462807) (xy 185.400665 -317.483658) (xy 185.441755 -317.511525)
			(xy 185.477796 -317.545671) (xy 185.507837 -317.585199) (xy 185.531087 -317.629066) (xy 185.546935 -317.676117)
			(xy 185.554961 -317.725112) (xy 185.555382 -317.749936) (xy 185.555342 -317.759037) (xy 185.554323 -317.777209)
			(xy 185.55335 -317.786258) (xy 185.551826 -317.798196) (xy 185.555636 -317.809118) (xy 185.557799 -317.814698)
			(xy 185.564345 -317.824712) (xy 185.56859 -317.82893) (xy 185.627518 -317.885318) (xy 185.630566 -317.888112)
			(xy 185.634361 -317.891013) (xy 185.6428 -317.895486) (xy 185.64733 -317.897002) (xy 185.65876 -317.900558)
			(xy 185.670698 -317.898526) (xy 185.684186 -317.896398) (xy 185.7114 -317.894113) (xy 185.725054 -317.893954)
			(xy 185.738708 -317.894116) (xy 185.765921 -317.896404) (xy 185.77941 -317.898526) (xy 185.791348 -317.900558)
			(xy 185.802778 -317.897002) (xy 185.807309 -317.895489) (xy 185.815748 -317.891014) (xy 185.819542 -317.888112)
			(xy 185.82259 -317.885318) (xy 185.881518 -317.82893) (xy 185.885752 -317.824702) (xy 185.892302 -317.814693)
			(xy 185.894472 -317.809118) (xy 185.898282 -317.798196) (xy 185.896758 -317.786258) (xy 185.895769 -317.777211)
			(xy 185.894752 -317.759037) (xy 185.894726 -317.749936) (xy 185.895209 -317.725118) (xy 185.903233 -317.676134)
			(xy 185.919077 -317.629095) (xy 185.942322 -317.585238) (xy 185.972356 -317.545719) (xy 186.008387 -317.51158)
			(xy 186.049467 -317.48372) (xy 186.094514 -317.462873) (xy 186.142339 -317.449588) (xy 186.191684 -317.444216)
			(xy 186.241248 -317.446898) (xy 186.289725 -317.457562) (xy 186.335838 -317.475929) (xy 186.378372 -317.501515)
			(xy 186.416206 -317.533644) (xy 186.448345 -317.571471) (xy 186.47394 -317.614) (xy 186.492317 -317.660108)
			(xy 186.502993 -317.708583) (xy 186.505686 -317.758146) (xy 186.500325 -317.807492) (xy 186.487051 -317.855321)
			(xy 186.466214 -317.900372) (xy 186.438364 -317.941458) (xy 186.404233 -317.977498) (xy 186.364721 -318.007541)
			(xy 186.32087 -318.030796) (xy 186.273834 -318.04665) (xy 186.224852 -318.054685) (xy 186.200034 -318.055244)
			(xy 186.190933 -318.055206) (xy 186.17276 -318.054191) (xy 186.163712 -318.053212) (xy 186.151774 -318.051688)
			(xy 186.140852 -318.055498) (xy 186.135273 -318.057662) (xy 186.125259 -318.064209) (xy 186.12104 -318.068452)
			(xy 186.064652 -318.12738) (xy 186.061858 -318.130428) (xy 186.058956 -318.134223) (xy 186.05448 -318.142661)
			(xy 186.052968 -318.147192) (xy 186.049412 -318.158622) (xy 186.051444 -318.17056) (xy 186.053573 -318.184048)
			(xy 186.055862 -318.211262) (xy 186.056016 -318.224916) (xy 186.056016 -318.295274) (xy 186.056471 -318.305935)
			(xy 186.065149 -318.325408) (xy 186.07278 -318.332866) (xy 186.12866 -318.383412) (xy 186.13882 -318.390524)
			(xy 186.147202 -318.39408) (xy 186.157362 -318.397382) (xy 186.168284 -318.396366) (xy 186.200034 -318.394588)
			(xy 186.225762 -318.395115) (xy 186.276491 -318.403732) (xy 186.325057 -318.420735) (xy 186.370084 -318.44564)
			(xy 186.410297 -318.477744) (xy 186.444557 -318.516136) (xy 186.471894 -318.55973) (xy 186.491534 -318.60729)
			(xy 186.50292 -318.65747) (xy 186.504834 -318.683132) (xy 186.505342 -318.693038) (xy 186.509406 -318.701674)
			(xy 186.51153 -318.70599) (xy 186.517164 -318.713784) (xy 186.520582 -318.717168) (xy 186.571382 -318.765174)
			(xy 186.578648 -318.771526) (xy 186.596539 -318.77872) (xy 186.60618 -318.779144) (xy 186.743848 -318.779144)
			(xy 186.753479 -318.778673) (xy 186.771358 -318.771489) (xy 186.778646 -318.765174) (xy 186.829446 -318.717168)
			(xy 186.832859 -318.71378) (xy 186.838476 -318.705977) (xy 186.840622 -318.701674) (xy 186.844686 -318.693038)
			(xy 186.845194 -318.683132) (xy 186.847138 -318.657474) (xy 186.858533 -318.607299) (xy 186.878177 -318.559743)
			(xy 186.905512 -318.516152) (xy 186.939767 -318.47776) (xy 186.979972 -318.445651) (xy 187.024989 -318.420734)
			(xy 187.073546 -318.403715) (xy 187.124268 -318.395074) (xy 187.149994 -318.394588) (xy 187.181744 -318.396366)
			(xy 187.192666 -318.397382) (xy 187.202826 -318.39408) (xy 187.211208 -318.390524) (xy 187.221368 -318.383412)
			(xy 187.277248 -318.332866) (xy 187.284753 -318.32532) (xy 187.293402 -318.3059) (xy 187.294012 -318.295274)
			(xy 187.294012 -318.224916) (xy 187.294175 -318.211262) (xy 187.296465 -318.18405) (xy 187.298584 -318.17056)
			(xy 187.300616 -318.158622) (xy 187.29706 -318.147192) (xy 187.295546 -318.142661) (xy 187.291072 -318.134223)
			(xy 187.28817 -318.130428) (xy 187.285376 -318.12738) (xy 187.228988 -318.068452) (xy 187.224757 -318.064223)
			(xy 187.214744 -318.057684) (xy 187.209176 -318.055498) (xy 187.198254 -318.051688) (xy 187.186316 -318.053212)
			(xy 187.177269 -318.0542) (xy 187.159095 -318.055215) (xy 187.149994 -318.055244) (xy 187.12517 -318.054757)
			(xy 187.076175 -318.046724) (xy 187.029126 -318.03087) (xy 186.985262 -318.007613) (xy 186.945738 -317.977566)
			(xy 186.911596 -317.94152) (xy 186.883735 -317.900425) (xy 186.86289 -317.855364) (xy 186.84961 -317.807525)
			(xy 186.844245 -317.758167) (xy 186.846935 -317.708591) (xy 186.857611 -317.660104) (xy 186.875991 -317.613983)
			(xy 186.90159 -317.571443) (xy 186.933734 -317.533604) (xy 186.971577 -317.501465) (xy 187.01412 -317.475872)
			(xy 187.060244 -317.457499) (xy 187.108733 -317.44683) (xy 187.158309 -317.444146) (xy 187.207666 -317.449518)
			(xy 187.255504 -317.462805) (xy 187.300562 -317.483656) (xy 187.341652 -317.511522) (xy 187.377694 -317.545669)
			(xy 187.407736 -317.585197) (xy 187.430987 -317.629065) (xy 187.446834 -317.676116) (xy 187.454861 -317.725112)
			(xy 187.455302 -317.749936) (xy 187.455262 -317.759037) (xy 187.454243 -317.777209) (xy 187.45327 -317.786258)
			(xy 187.451746 -317.798196) (xy 187.455556 -317.809118) (xy 187.45772 -317.814697) (xy 187.464267 -317.82471)
			(xy 187.46851 -317.82893) (xy 187.527438 -317.885318) (xy 187.530486 -317.888112) (xy 187.534282 -317.891011)
			(xy 187.542722 -317.895481) (xy 187.54725 -317.897002) (xy 187.55868 -317.900558) (xy 187.570618 -317.898526)
			(xy 187.584106 -317.896395) (xy 187.611319 -317.894103) (xy 187.624974 -317.893954) (xy 187.638628 -317.894116)
			(xy 187.66584 -317.896406) (xy 187.67933 -317.898526) (xy 187.691268 -317.900558) (xy 187.702698 -317.897002)
			(xy 187.707228 -317.895487) (xy 187.715665 -317.89101) (xy 187.719462 -317.888112) (xy 187.72251 -317.885318)
			(xy 187.781438 -317.82893) (xy 187.78567 -317.824701) (xy 187.792218 -317.814692) (xy 187.794392 -317.809118)
			(xy 187.798202 -317.798196) (xy 187.796678 -317.786258) (xy 187.795689 -317.777211) (xy 187.794672 -317.759037)
			(xy 187.794646 -317.749936) (xy 187.795129 -317.72511) (xy 187.803156 -317.676111) (xy 187.819006 -317.629057)
			(xy 187.842259 -317.585186) (xy 187.872304 -317.545656) (xy 187.908349 -317.511508) (xy 187.949443 -317.483641)
			(xy 187.994505 -317.46279) (xy 188.042347 -317.449505) (xy 188.091708 -317.444135) (xy 188.141287 -317.446822)
			(xy 188.189779 -317.457495) (xy 188.235904 -317.475873) (xy 188.278449 -317.501471) (xy 188.316292 -317.533615)
			(xy 188.348435 -317.571459) (xy 188.374032 -317.614005) (xy 188.392408 -317.660131) (xy 188.40308 -317.708623)
			(xy 188.405765 -317.758202) (xy 188.400393 -317.807563) (xy 188.387106 -317.855404) (xy 188.366254 -317.900465)
			(xy 188.338386 -317.941559) (xy 188.304236 -317.977603) (xy 188.264705 -318.007646) (xy 188.220834 -318.030898)
			(xy 188.173779 -318.046746) (xy 188.12478 -318.054772) (xy 188.099954 -318.055244) (xy 188.090853 -318.055203)
			(xy 188.072681 -318.054184) (xy 188.063632 -318.053212) (xy 188.051694 -318.051688) (xy 188.040772 -318.055498)
			(xy 188.035192 -318.057661) (xy 188.025175 -318.064204) (xy 188.02096 -318.068452) (xy 187.964572 -318.12738)
			(xy 187.961778 -318.130428) (xy 187.958875 -318.134222) (xy 187.954397 -318.14266) (xy 187.952888 -318.147192)
			(xy 187.949332 -318.158622) (xy 187.951364 -318.17056) (xy 187.953493 -318.184048) (xy 187.955782 -318.211262)
			(xy 187.955936 -318.224916) (xy 187.955936 -318.295274) (xy 187.956391 -318.305934) (xy 187.965072 -318.325406)
			(xy 187.9727 -318.332866) (xy 188.02858 -318.383412) (xy 188.03874 -318.390524) (xy 188.047122 -318.39408)
			(xy 188.057282 -318.397382) (xy 188.068204 -318.396366) (xy 188.099954 -318.394588) (xy 188.125681 -318.395116)
			(xy 188.176408 -318.403737) (xy 188.22497 -318.420741) (xy 188.269994 -318.445647) (xy 188.310204 -318.477751)
			(xy 188.344462 -318.516143) (xy 188.371797 -318.559735) (xy 188.391435 -318.607294) (xy 188.40282 -318.657472)
			(xy 188.404754 -318.683132) (xy 188.405262 -318.693038) (xy 188.409326 -318.701674) (xy 188.411446 -318.705992)
			(xy 188.417074 -318.713793) (xy 188.420502 -318.717168) (xy 188.471302 -318.765174) (xy 188.478569 -318.771523)
			(xy 188.49646 -318.778709) (xy 188.5061 -318.779144) (xy 188.643768 -318.779144) (xy 188.653405 -318.778687)
			(xy 188.671304 -318.771523) (xy 188.678566 -318.765174) (xy 188.729366 -318.717168) (xy 188.732783 -318.713783)
			(xy 188.738408 -318.705984) (xy 188.740542 -318.701674) (xy 188.744606 -318.693038) (xy 188.745114 -318.683132)
			(xy 188.747058 -318.657474) (xy 188.758453 -318.607301) (xy 188.778097 -318.559747) (xy 188.805433 -318.516158)
			(xy 188.839689 -318.477767) (xy 188.879894 -318.44566) (xy 188.924911 -318.420746) (xy 188.973467 -318.40373)
			(xy 189.024188 -318.395092) (xy 189.049914 -318.394588) (xy 189.081664 -318.396366) (xy 189.092586 -318.397382)
			(xy 189.102746 -318.39408) (xy 189.111128 -318.390524) (xy 189.121288 -318.383412) (xy 189.177168 -318.332866)
			(xy 189.184671 -318.325319) (xy 189.193316 -318.305899) (xy 189.193932 -318.295274) (xy 189.193932 -318.224916)
			(xy 189.194095 -318.211262) (xy 189.196386 -318.18405) (xy 189.198504 -318.17056) (xy 189.200536 -318.158622)
			(xy 189.19698 -318.147192) (xy 189.195464 -318.142663) (xy 189.190984 -318.134228) (xy 189.18809 -318.130428)
			(xy 189.185296 -318.12738) (xy 189.128908 -318.068452) (xy 189.124678 -318.064222) (xy 189.114666 -318.057679)
			(xy 189.109096 -318.055498) (xy 189.098174 -318.051688) (xy 189.086236 -318.053212) (xy 189.077189 -318.054201)
			(xy 189.059015 -318.055217) (xy 189.049914 -318.055244) (xy 189.025089 -318.054759) (xy 188.976094 -318.046729)
			(xy 188.929043 -318.030877) (xy 188.885177 -318.007622) (xy 188.84565 -317.977577) (xy 188.811506 -317.941532)
			(xy 188.783643 -317.900438) (xy 188.762796 -317.855378) (xy 188.749513 -317.807539) (xy 188.744145 -317.75818)
			(xy 188.746834 -317.708604) (xy 188.757507 -317.660116) (xy 188.775886 -317.613993) (xy 188.801484 -317.571451)
			(xy 188.833627 -317.533612) (xy 188.871469 -317.501471) (xy 188.914013 -317.475876) (xy 188.960137 -317.457501)
			(xy 189.008626 -317.446831) (xy 189.058202 -317.444146) (xy 189.10756 -317.449517) (xy 189.155399 -317.462803)
			(xy 189.200458 -317.483654) (xy 189.241549 -317.51152) (xy 189.277592 -317.545667) (xy 189.307634 -317.585195)
			(xy 189.330886 -317.629063) (xy 189.346734 -317.676115) (xy 189.354761 -317.725111) (xy 189.355222 -317.749936)
			(xy 189.355182 -317.759037) (xy 189.354163 -317.777209) (xy 189.35319 -317.786258) (xy 189.351666 -317.798196)
			(xy 189.355476 -317.809118) (xy 189.357641 -317.814697) (xy 189.36419 -317.824707) (xy 189.36843 -317.82893)
			(xy 189.427358 -317.885318) (xy 189.430406 -317.888112) (xy 189.434199 -317.891017) (xy 189.442635 -317.895499)
			(xy 189.44717 -317.897002) (xy 189.4586 -317.900558) (xy 189.470538 -317.898526) (xy 189.484026 -317.896396)
			(xy 189.511239 -317.894106) (xy 189.524894 -317.893954) (xy 189.538548 -317.894117) (xy 189.56576 -317.896409)
			(xy 189.57925 -317.898526) (xy 189.591188 -317.900558) (xy 189.602618 -317.897002) (xy 189.607147 -317.895485)
			(xy 189.615582 -317.891006) (xy 189.619382 -317.888112) (xy 189.62243 -317.885318) (xy 189.681358 -317.82893)
			(xy 189.685589 -317.824701) (xy 189.692135 -317.81469) (xy 189.694312 -317.809118) (xy 189.698122 -317.798196)
			(xy 189.696598 -317.786258) (xy 189.695609 -317.777211) (xy 189.694591 -317.759037) (xy 189.694566 -317.749936)
			(xy 189.695049 -317.725112) (xy 189.703076 -317.676117) (xy 189.718924 -317.629066) (xy 189.742175 -317.585199)
			(xy 189.772217 -317.545672) (xy 189.808259 -317.511526) (xy 189.84935 -317.483661) (xy 189.894408 -317.462811)
			(xy 189.942245 -317.449526) (xy 189.991602 -317.444156) (xy 190.041177 -317.446841) (xy 190.089665 -317.457512)
			(xy 190.135788 -317.475887) (xy 190.17833 -317.501482) (xy 190.21617 -317.533623) (xy 190.248312 -317.571462)
			(xy 190.273908 -317.614004) (xy 190.292285 -317.660125) (xy 190.302958 -317.708613) (xy 190.305645 -317.758188)
			(xy 190.300276 -317.807545) (xy 190.286992 -317.855383) (xy 190.266144 -317.900442) (xy 190.23828 -317.941534)
			(xy 190.204135 -317.977576) (xy 190.164609 -318.00762) (xy 190.120743 -318.030872) (xy 190.073693 -318.046722)
			(xy 190.024698 -318.05475) (xy 189.999874 -318.055244) (xy 189.990773 -318.055204) (xy 189.972601 -318.054186)
			(xy 189.963552 -318.053212) (xy 189.951614 -318.051688) (xy 189.940692 -318.055498) (xy 189.935111 -318.057659)
			(xy 189.925091 -318.0642) (xy 189.92088 -318.068452) (xy 189.864492 -318.12738) (xy 189.861698 -318.130428)
			(xy 189.858794 -318.134222) (xy 189.854314 -318.142658) (xy 189.852808 -318.147192) (xy 189.849252 -318.158622)
			(xy 189.851284 -318.17056) (xy 189.853413 -318.184048) (xy 189.855701 -318.211262) (xy 189.855856 -318.224916)
			(xy 189.855856 -318.295274) (xy 189.856312 -318.305934) (xy 189.864995 -318.325403) (xy 189.87262 -318.332866)
			(xy 189.9285 -318.383412) (xy 189.93866 -318.390524) (xy 189.947042 -318.39408) (xy 189.957202 -318.397382)
			(xy 189.968124 -318.396366) (xy 189.999874 -318.394588) (xy 190.0256 -318.395118) (xy 190.076324 -318.403741)
			(xy 190.124884 -318.420747) (xy 190.169905 -318.445654) (xy 190.210112 -318.477758) (xy 190.244367 -318.51615)
			(xy 190.2717 -318.559741) (xy 190.291336 -318.607298) (xy 190.30272 -318.657475) (xy 190.304674 -318.683132)
			(xy 190.305182 -318.693038) (xy 190.309246 -318.701674) (xy 190.311367 -318.705991) (xy 190.316997 -318.71379)
			(xy 190.320422 -318.717168) (xy 190.371222 -318.765174) (xy 190.37849 -318.77152) (xy 190.396382 -318.7787)
			(xy 190.40602 -318.779144) (xy 190.524638 -318.779144) (xy 190.532998 -318.778428) (xy 190.548566 -318.772194)
			(xy 190.555118 -318.766952) (xy 190.555626 -318.766444) (xy 190.55715 -318.765174) (xy 190.607696 -318.716914)
			(xy 190.611114 -318.71353) (xy 190.616742 -318.705732) (xy 190.618872 -318.70142) (xy 190.622936 -318.692784)
			(xy 190.623444 -318.682878) (xy 190.625204 -318.6581) (xy 190.635271 -318.609458) (xy 190.652575 -318.562896)
			(xy 190.676718 -318.519485) (xy 190.707145 -318.480222) (xy 190.743157 -318.446009) (xy 190.783927 -318.417633)
			(xy 190.828518 -318.395745) (xy 190.875904 -318.380848) (xy 190.924998 -318.373285) (xy 190.949834 -318.372744)
			(xy 190.950342 -318.372744) (xy 190.9826 -318.374522) (xy 190.993522 -318.375538) (xy 191.003428 -318.372236)
			(xy 191.00852 -318.370453) (xy 191.017866 -318.36507) (xy 191.02197 -318.361568) (xy 191.077596 -318.311022)
			(xy 191.085104 -318.303476) (xy 191.093766 -318.284058) (xy 191.09436 -318.27343) (xy 191.09436 -318.224916)
			(xy 191.094403 -318.215562) (xy 191.095418 -318.196881) (xy 191.096392 -318.187578) (xy 191.097916 -318.175894)
			(xy 191.094106 -318.165226) (xy 191.0921 -318.159915) (xy 191.086072 -318.150298) (xy 191.082168 -318.146176)
			(xy 191.02578 -318.089534) (xy 191.021759 -318.085734) (xy 191.012402 -318.079836) (xy 191.007238 -318.07785)
			(xy 190.996316 -318.073786) (xy 190.984632 -318.075056) (xy 190.950342 -318.077088) (xy 190.949834 -318.077088)
			(xy 190.924139 -318.076564) (xy 190.873386 -318.068488) (xy 190.824521 -318.052577) (xy 190.778743 -318.029221)
			(xy 190.737181 -317.998996) (xy 190.700854 -317.962644) (xy 190.670658 -317.92106) (xy 190.647335 -317.875267)
			(xy 190.631458 -317.82639) (xy 190.623418 -317.775631) (xy 190.622936 -317.749936) (xy 190.623411 -317.724224)
			(xy 190.631451 -317.673432) (xy 190.647337 -317.624524) (xy 190.670679 -317.578703) (xy 190.700902 -317.537098)
			(xy 190.737261 -317.500733) (xy 190.778862 -317.470504) (xy 190.82468 -317.447155) (xy 190.873586 -317.431262)
			(xy 190.924376 -317.423215) (xy 190.950088 -317.422784) (xy 190.975783 -317.423286) (xy 191.02654 -317.43132)
			(xy 191.075417 -317.447192) (xy 191.12121 -317.470512) (xy 191.162794 -317.500706) (xy 191.199144 -317.537031)
			(xy 191.229367 -317.578593) (xy 191.252719 -317.62437) (xy 191.268626 -317.673236) (xy 191.276696 -317.723988)
			(xy 191.27724 -317.749682) (xy 191.27724 -317.75019) (xy 191.275208 -317.78448) (xy 191.273938 -317.796164)
			(xy 191.278002 -317.807086) (xy 191.280022 -317.812233) (xy 191.285909 -317.821591) (xy 191.289686 -317.825628)
			(xy 191.346328 -317.882016) (xy 191.350465 -317.8859) (xy 191.36008 -317.891922) (xy 191.365378 -317.893954)
			(xy 191.376046 -317.897764) (xy 191.38773 -317.89624) (xy 191.397034 -317.895272) (xy 191.415714 -317.894256)
			(xy 191.425068 -317.894208) (xy 191.438722 -317.89437) (xy 191.465935 -317.896659) (xy 191.479424 -317.89878)
			(xy 191.491362 -317.900812) (xy 191.502792 -317.897256) (xy 191.507323 -317.895743) (xy 191.515763 -317.891271)
			(xy 191.519556 -317.888366) (xy 191.522604 -317.885572) (xy 191.581532 -317.829184) (xy 191.585761 -317.824954)
			(xy 191.592302 -317.814941) (xy 191.594486 -317.809372) (xy 191.598296 -317.79845) (xy 191.597026 -317.786258)
			(xy 191.595977 -317.777214) (xy 191.594831 -317.75904) (xy 191.59474 -317.749936) (xy 191.595223 -317.725119)
			(xy 191.603247 -317.676139) (xy 191.619089 -317.629101) (xy 191.642333 -317.585247) (xy 191.672365 -317.54573)
			(xy 191.708394 -317.511593) (xy 191.749472 -317.483734) (xy 191.794515 -317.462887) (xy 191.842338 -317.449603)
			(xy 191.89168 -317.44423) (xy 191.941241 -317.446911) (xy 191.989715 -317.457574) (xy 192.035826 -317.475939)
			(xy 192.078358 -317.501522) (xy 192.116191 -317.533649) (xy 192.148329 -317.571473) (xy 192.173923 -317.613999)
			(xy 192.192301 -317.660104) (xy 192.202978 -317.708576) (xy 192.205672 -317.758136) (xy 192.200313 -317.80748)
			(xy 192.187042 -317.855306) (xy 192.166208 -317.900355) (xy 192.13836 -317.94144) (xy 192.104233 -317.977479)
			(xy 192.064724 -318.007522) (xy 192.020876 -318.030778) (xy 191.973843 -318.046633) (xy 191.924865 -318.05467)
			(xy 191.900048 -318.055244) (xy 191.890944 -318.055146) (xy 191.872771 -318.054001) (xy 191.863726 -318.052958)
			(xy 191.851534 -318.051688) (xy 191.840612 -318.055498) (xy 191.835029 -318.057657) (xy 191.825007 -318.064195)
			(xy 191.8208 -318.068452) (xy 191.764412 -318.12738) (xy 191.761618 -318.130428) (xy 191.758713 -318.134221)
			(xy 191.754232 -318.142657) (xy 191.752728 -318.147192) (xy 191.749172 -318.158622) (xy 191.751204 -318.17056)
			(xy 191.753334 -318.184048) (xy 191.75562 -318.211262) (xy 191.755776 -318.224916) (xy 191.755776 -318.295274)
			(xy 191.75603 -318.299084) (xy 191.75603 -318.299592) (xy 191.756993 -318.307694) (xy 191.763344 -318.322713)
			(xy 191.768476 -318.329056) (xy 191.77254 -318.33312) (xy 191.828928 -318.383666) (xy 191.832933 -318.387058)
			(xy 191.842023 -318.392303) (xy 191.846962 -318.39408) (xy 191.857122 -318.397382) (xy 191.868044 -318.396366)
			(xy 191.900048 -318.394588) (xy 191.925775 -318.395116) (xy 191.976503 -318.403735) (xy 192.025066 -318.420739)
			(xy 192.070091 -318.445645) (xy 192.110302 -318.477749) (xy 192.14456 -318.516141) (xy 192.171896 -318.559734)
			(xy 192.191534 -318.607293) (xy 192.20292 -318.657472) (xy 192.204848 -318.683132) (xy 192.205356 -318.693038)
			(xy 192.20942 -318.701674) (xy 192.21154 -318.705992) (xy 192.217168 -318.713793) (xy 192.220596 -318.717168)
			(xy 192.271396 -318.765174) (xy 192.278663 -318.771524) (xy 192.296554 -318.778712) (xy 192.306194 -318.779144)
			(xy 192.424558 -318.779144) (xy 192.432917 -318.778425) (xy 192.448481 -318.772187) (xy 192.455038 -318.766952)
			(xy 192.455546 -318.766444) (xy 192.45707 -318.765174) (xy 192.507616 -318.716914) (xy 192.511033 -318.713529)
			(xy 192.516659 -318.705731) (xy 192.518792 -318.70142) (xy 192.522856 -318.692784) (xy 192.523364 -318.682878)
			(xy 192.525124 -318.6581) (xy 192.535192 -318.609459) (xy 192.552496 -318.562899) (xy 192.576639 -318.51949)
			(xy 192.607067 -318.480228) (xy 192.643079 -318.446017) (xy 192.683849 -318.417643) (xy 192.728439 -318.395757)
			(xy 192.775826 -318.380863) (xy 192.824919 -318.373303) (xy 192.849754 -318.372744) (xy 192.850262 -318.372744)
			(xy 192.88252 -318.374522) (xy 192.893442 -318.375538) (xy 192.903348 -318.372236) (xy 192.908439 -318.370451)
			(xy 192.917783 -318.365066) (xy 192.92189 -318.361568) (xy 192.977516 -318.311022) (xy 192.985022 -318.303476)
			(xy 192.99368 -318.284057) (xy 192.99428 -318.27343) (xy 192.99428 -318.224916) (xy 192.994323 -318.215562)
			(xy 192.995338 -318.196881) (xy 192.996312 -318.187578) (xy 192.997836 -318.175894) (xy 192.994026 -318.165226)
			(xy 192.992021 -318.159914) (xy 192.985995 -318.150296) (xy 192.982088 -318.146176) (xy 192.9257 -318.089534)
			(xy 192.92168 -318.085733) (xy 192.912324 -318.079831) (xy 192.907158 -318.07785) (xy 192.896236 -318.073786)
			(xy 192.884552 -318.075056) (xy 192.850262 -318.077088) (xy 192.849754 -318.077088) (xy 192.824058 -318.076566)
			(xy 192.773303 -318.068492) (xy 192.724435 -318.052583) (xy 192.678655 -318.029228) (xy 192.637089 -317.999003)
			(xy 192.60076 -317.962651) (xy 192.570562 -317.921066) (xy 192.547237 -317.875271) (xy 192.531359 -317.826393)
			(xy 192.523318 -317.775632) (xy 192.522856 -317.749936) (xy 192.523331 -317.724225) (xy 192.531371 -317.673434)
			(xy 192.547257 -317.624527) (xy 192.570599 -317.578707) (xy 192.600823 -317.537104) (xy 192.637182 -317.500741)
			(xy 192.678783 -317.470514) (xy 192.724601 -317.447168) (xy 192.773507 -317.431277) (xy 192.824297 -317.423234)
			(xy 192.850008 -317.422784) (xy 192.875702 -317.423288) (xy 192.926457 -317.431324) (xy 192.975331 -317.447198)
			(xy 193.021121 -317.470519) (xy 193.062702 -317.500713) (xy 193.09905 -317.537038) (xy 193.129271 -317.578599)
			(xy 193.152621 -317.624375) (xy 193.168527 -317.673239) (xy 193.176596 -317.723989) (xy 193.17716 -317.749682)
			(xy 193.17716 -317.75019) (xy 193.175128 -317.78448) (xy 193.173858 -317.796164) (xy 193.177922 -317.807086)
			(xy 193.179943 -317.812232) (xy 193.185831 -317.821588) (xy 193.189606 -317.825628) (xy 193.246248 -317.882016)
			(xy 193.250386 -317.885899) (xy 193.260002 -317.891917) (xy 193.265298 -317.893954) (xy 193.275966 -317.897764)
			(xy 193.28765 -317.89624) (xy 193.296954 -317.895273) (xy 193.315634 -317.894258) (xy 193.324988 -317.894208)
			(xy 193.338642 -317.894371) (xy 193.365854 -317.896662) (xy 193.379344 -317.89878) (xy 193.391282 -317.900812)
			(xy 193.402712 -317.897256) (xy 193.407242 -317.895741) (xy 193.41568 -317.891266) (xy 193.419476 -317.888366)
			(xy 193.422524 -317.885572) (xy 193.481452 -317.829184) (xy 193.48568 -317.824953) (xy 193.492218 -317.814939)
			(xy 193.494406 -317.809372) (xy 193.498216 -317.79845) (xy 193.496946 -317.786258) (xy 193.495897 -317.777214)
			(xy 193.494751 -317.75904) (xy 193.49466 -317.749936) (xy 193.495143 -317.725111) (xy 193.50317 -317.676115)
			(xy 193.519018 -317.629063) (xy 193.54227 -317.585195) (xy 193.572313 -317.545667) (xy 193.608356 -317.511521)
			(xy 193.649448 -317.483655) (xy 193.694507 -317.462805) (xy 193.742346 -317.44952) (xy 193.791704 -317.44415)
			(xy 193.84128 -317.446835) (xy 193.889769 -317.457507) (xy 193.935893 -317.475883) (xy 193.978435 -317.501479)
			(xy 194.016276 -317.533621) (xy 194.048419 -317.571461) (xy 194.074015 -317.614004) (xy 194.092392 -317.660127)
			(xy 194.103064 -317.708616) (xy 194.105751 -317.758192) (xy 194.100381 -317.80755) (xy 194.087096 -317.855389)
			(xy 194.066247 -317.900449) (xy 194.038382 -317.941541) (xy 194.004236 -317.977584) (xy 193.964708 -318.007628)
			(xy 193.92084 -318.03088) (xy 193.873789 -318.046729) (xy 193.824793 -318.054757) (xy 193.799968 -318.055244)
			(xy 193.790864 -318.055146) (xy 193.772691 -318.054003) (xy 193.763646 -318.052958) (xy 193.751454 -318.051688)
			(xy 193.740532 -318.055498) (xy 193.734954 -318.057664) (xy 193.724943 -318.064213) (xy 193.72072 -318.068452)
			(xy 193.664332 -318.12738) (xy 193.661538 -318.130428) (xy 193.658637 -318.134223) (xy 193.654162 -318.142662)
			(xy 193.652648 -318.147192) (xy 193.649092 -318.158622) (xy 193.651124 -318.17056) (xy 193.653254 -318.184048)
			(xy 193.655541 -318.211261) (xy 193.655696 -318.224916) (xy 193.655696 -318.295274) (xy 193.65595 -318.299084)
			(xy 193.65595 -318.299592) (xy 193.656914 -318.307693) (xy 193.663267 -318.322711) (xy 193.668396 -318.329056)
			(xy 193.67246 -318.33312) (xy 193.728848 -318.383666) (xy 193.732854 -318.387057) (xy 193.741945 -318.392298)
			(xy 193.746882 -318.39408) (xy 193.757042 -318.397382) (xy 193.767964 -318.396366) (xy 193.799968 -318.394588)
			(xy 193.825694 -318.395117) (xy 193.876419 -318.40374) (xy 193.92498 -318.420745) (xy 193.970002 -318.445652)
			(xy 194.01021 -318.477756) (xy 194.044465 -318.516147) (xy 194.071799 -318.559739) (xy 194.091436 -318.607297)
			(xy 194.10282 -318.657474) (xy 194.104768 -318.683132) (xy 194.105276 -318.693038) (xy 194.10934 -318.701674)
			(xy 194.111461 -318.705992) (xy 194.11709 -318.713791) (xy 194.120516 -318.717168) (xy 194.171316 -318.765174)
			(xy 194.178584 -318.771521) (xy 194.196475 -318.778703) (xy 194.206114 -318.779144) (xy 194.324478 -318.779144)
			(xy 194.332842 -318.778437) (xy 194.348423 -318.772218) (xy 194.354958 -318.766952) (xy 194.355466 -318.766444)
			(xy 194.35699 -318.765174) (xy 194.407536 -318.716914) (xy 194.410952 -318.713529) (xy 194.416576 -318.705729)
			(xy 194.418712 -318.70142) (xy 194.422776 -318.692784) (xy 194.423284 -318.682878) (xy 194.425044 -318.658101)
			(xy 194.435112 -318.609461) (xy 194.452416 -318.562902) (xy 194.47656 -318.519494) (xy 194.506988 -318.480235)
			(xy 194.543001 -318.446026) (xy 194.583771 -318.417653) (xy 194.628361 -318.39577) (xy 194.675747 -318.380879)
			(xy 194.724839 -318.373322) (xy 194.749674 -318.372744) (xy 194.750182 -318.372744) (xy 194.78244 -318.374522)
			(xy 194.793362 -318.375538) (xy 194.803268 -318.372236) (xy 194.808363 -318.370458) (xy 194.817717 -318.365083)
			(xy 194.82181 -318.361568) (xy 194.877436 -318.311022) (xy 194.884951 -318.30348) (xy 194.893623 -318.28406)
			(xy 194.8942 -318.27343) (xy 194.8942 -318.224916) (xy 194.894243 -318.215562) (xy 194.895258 -318.196881)
			(xy 194.896232 -318.187578) (xy 194.897756 -318.175894) (xy 194.893946 -318.165226) (xy 194.891942 -318.159914)
			(xy 194.885917 -318.150293) (xy 194.882008 -318.146176) (xy 194.82562 -318.089534) (xy 194.821601 -318.085731)
			(xy 194.812246 -318.079826) (xy 194.807078 -318.07785) (xy 194.796156 -318.073786) (xy 194.784472 -318.075056)
			(xy 194.750182 -318.077088) (xy 194.749674 -318.077088) (xy 194.723977 -318.076567) (xy 194.67322 -318.068496)
			(xy 194.624348 -318.052588) (xy 194.578566 -318.029235) (xy 194.536997 -317.99901) (xy 194.500666 -317.962658)
			(xy 194.470466 -317.921072) (xy 194.447139 -317.875276) (xy 194.431259 -317.826395) (xy 194.423218 -317.775633)
			(xy 194.422776 -317.749936) (xy 194.423251 -317.724225) (xy 194.431291 -317.673436) (xy 194.447178 -317.62453)
			(xy 194.47052 -317.578712) (xy 194.500744 -317.53711) (xy 194.537104 -317.500749) (xy 194.578705 -317.470524)
			(xy 194.624523 -317.447181) (xy 194.673428 -317.431293) (xy 194.724217 -317.423252) (xy 194.749928 -317.422784)
			(xy 194.775621 -317.423289) (xy 194.826373 -317.431328) (xy 194.875245 -317.447204) (xy 194.921032 -317.470526)
			(xy 194.96261 -317.500721) (xy 194.998956 -317.537045) (xy 195.029175 -317.578605) (xy 195.052523 -317.62438)
			(xy 195.068427 -317.673242) (xy 195.076496 -317.72399) (xy 195.07708 -317.749682) (xy 195.07708 -317.75019)
			(xy 195.075048 -317.78448) (xy 195.073778 -317.796164) (xy 195.077842 -317.807086) (xy 195.079864 -317.812232)
			(xy 195.085754 -317.821586) (xy 195.089526 -317.825628) (xy 195.146168 -317.882016) (xy 195.150307 -317.885897)
			(xy 195.159924 -317.891912) (xy 195.165218 -317.893954) (xy 195.175886 -317.897764) (xy 195.18757 -317.89624)
			(xy 195.196874 -317.89527) (xy 195.215554 -317.894251) (xy 195.224908 -317.894208) (xy 195.238562 -317.894372)
			(xy 195.265774 -317.896664) (xy 195.279264 -317.89878) (xy 195.291202 -317.900812) (xy 195.302632 -317.897256)
			(xy 195.307162 -317.89574) (xy 195.315597 -317.891262) (xy 195.319396 -317.888366) (xy 195.322444 -317.885572)
			(xy 195.381372 -317.829184) (xy 195.385599 -317.824952) (xy 195.392134 -317.814938) (xy 195.394326 -317.809372)
			(xy 195.398136 -317.79845) (xy 195.396866 -317.786258) (xy 195.395817 -317.777214) (xy 195.394671 -317.75904)
			(xy 195.39458 -317.749936) (xy 195.395063 -317.725113) (xy 195.403089 -317.676121) (xy 195.418936 -317.629073)
			(xy 195.442186 -317.585208) (xy 195.472226 -317.545683) (xy 195.508265 -317.511539) (xy 195.549354 -317.483675)
			(xy 195.594409 -317.462826) (xy 195.642244 -317.449541) (xy 195.691598 -317.44417) (xy 195.74117 -317.446854)
			(xy 195.789656 -317.457524) (xy 195.835776 -317.475897) (xy 195.878316 -317.50149) (xy 195.916155 -317.533628)
			(xy 195.948296 -317.571464) (xy 195.973892 -317.614003) (xy 195.992269 -317.660121) (xy 196.002942 -317.708606)
			(xy 196.005631 -317.758178) (xy 196.000264 -317.807533) (xy 195.986982 -317.855368) (xy 195.966137 -317.900425)
			(xy 195.938276 -317.941516) (xy 195.904135 -317.977558) (xy 195.864612 -318.007601) (xy 195.820749 -318.030854)
			(xy 195.773702 -318.046705) (xy 195.724711 -318.054735) (xy 195.699888 -318.055244) (xy 195.690784 -318.055147)
			(xy 195.67261 -318.054005) (xy 195.663566 -318.052958) (xy 195.651374 -318.051688) (xy 195.640452 -318.055498)
			(xy 195.634873 -318.057662) (xy 195.624859 -318.064209) (xy 195.62064 -318.068452) (xy 195.564252 -318.12738)
			(xy 195.561458 -318.130428) (xy 195.558556 -318.134223) (xy 195.55408 -318.142661) (xy 195.552568 -318.147192)
			(xy 195.549012 -318.158622) (xy 195.551044 -318.17056) (xy 195.553174 -318.184048) (xy 195.555461 -318.211262)
			(xy 195.555616 -318.224916) (xy 195.555616 -318.295274) (xy 195.55587 -318.299084) (xy 195.55587 -318.299592)
			(xy 195.556834 -318.307693) (xy 195.563189 -318.322709) (xy 195.568316 -318.329056) (xy 195.57238 -318.33312)
			(xy 195.628768 -318.383666) (xy 195.632775 -318.387055) (xy 195.641867 -318.392293) (xy 195.646802 -318.39408)
			(xy 195.656962 -318.397382) (xy 195.667884 -318.396366) (xy 195.699888 -318.394588) (xy 195.725613 -318.395119)
			(xy 195.776335 -318.403744) (xy 195.824893 -318.420751) (xy 195.869912 -318.445659) (xy 195.910117 -318.477763)
			(xy 195.944371 -318.516154) (xy 195.971702 -318.559745) (xy 195.991337 -318.607301) (xy 196.002721 -318.657476)
			(xy 196.004688 -318.683132) (xy 196.005196 -318.693038) (xy 196.00926 -318.701674) (xy 196.011382 -318.705991)
			(xy 196.017013 -318.713789) (xy 196.020436 -318.717168) (xy 196.071236 -318.765174) (xy 196.078505 -318.771518)
			(xy 196.096396 -318.778693) (xy 196.106034 -318.779144) (xy 196.224398 -318.779144) (xy 196.232761 -318.778434)
			(xy 196.248337 -318.77221) (xy 196.254878 -318.766952) (xy 196.255386 -318.766444) (xy 196.25691 -318.765174)
			(xy 196.307456 -318.716914) (xy 196.310871 -318.713528) (xy 196.316494 -318.705728) (xy 196.318632 -318.70142)
			(xy 196.322696 -318.692784) (xy 196.323204 -318.682878) (xy 196.324964 -318.658099) (xy 196.335031 -318.609454)
			(xy 196.352334 -318.56289) (xy 196.376476 -318.519476) (xy 196.406903 -318.480209) (xy 196.442914 -318.445993)
			(xy 196.483684 -318.417612) (xy 196.528275 -318.395719) (xy 196.575662 -318.380817) (xy 196.624757 -318.373248)
			(xy 196.649594 -318.372744) (xy 196.650102 -318.372744) (xy 196.68236 -318.374522) (xy 196.693282 -318.375538)
			(xy 196.703188 -318.372236) (xy 196.708282 -318.370457) (xy 196.717633 -318.365079) (xy 196.72173 -318.361568)
			(xy 196.777356 -318.311022) (xy 196.784869 -318.303479) (xy 196.793538 -318.28406) (xy 196.79412 -318.27343)
			(xy 196.79412 -318.224916) (xy 196.794163 -318.215562) (xy 196.795178 -318.196881) (xy 196.796152 -318.187578)
			(xy 196.797676 -318.175894) (xy 196.793866 -318.165226) (xy 196.791863 -318.159913) (xy 196.78584 -318.150291)
			(xy 196.781928 -318.146176) (xy 196.72554 -318.089534) (xy 196.721517 -318.085737) (xy 196.712157 -318.079846)
			(xy 196.706998 -318.07785) (xy 196.696076 -318.073786) (xy 196.684392 -318.075056) (xy 196.650102 -318.077088)
			(xy 196.649594 -318.077088) (xy 196.623896 -318.076569) (xy 196.573136 -318.0685) (xy 196.524262 -318.052594)
			(xy 196.478477 -318.029242) (xy 196.436906 -317.999017) (xy 196.400572 -317.962665) (xy 196.370369 -317.921078)
			(xy 196.347041 -317.87528) (xy 196.33116 -317.826398) (xy 196.323118 -317.775634) (xy 196.322696 -317.749936)
			(xy 196.323171 -317.724226) (xy 196.331211 -317.673438) (xy 196.347098 -317.624533) (xy 196.370441 -317.578716)
			(xy 196.400665 -317.537116) (xy 196.437025 -317.500757) (xy 196.478627 -317.470535) (xy 196.524444 -317.447193)
			(xy 196.573349 -317.431308) (xy 196.624138 -317.423271) (xy 196.649848 -317.422784) (xy 196.67554 -317.423291)
			(xy 196.72629 -317.431332) (xy 196.775158 -317.44721) (xy 196.820944 -317.470533) (xy 196.862519 -317.500728)
			(xy 196.898862 -317.537052) (xy 196.929078 -317.578611) (xy 196.952425 -317.624384) (xy 196.968328 -317.673245)
			(xy 196.976396 -317.723991) (xy 196.977 -317.749682) (xy 196.977 -317.75019) (xy 196.974968 -317.78448)
			(xy 196.973698 -317.796164) (xy 196.977762 -317.807086) (xy 196.979781 -317.812234) (xy 196.985664 -317.821595)
			(xy 196.989446 -317.825628) (xy 197.046088 -317.882016) (xy 197.050223 -317.885903) (xy 197.059835 -317.891933)
			(xy 197.065138 -317.893954) (xy 197.075806 -317.897764) (xy 197.08749 -317.89624) (xy 197.096794 -317.895271)
			(xy 197.115474 -317.894253) (xy 197.124828 -317.894208) (xy 197.138546 -317.894363) (xy 197.165885 -317.896653)
			(xy 197.179438 -317.89878) (xy 197.191376 -317.900812) (xy 197.202806 -317.897256) (xy 197.207337 -317.895742)
			(xy 197.215775 -317.891268) (xy 197.21957 -317.888366) (xy 197.222618 -317.885572) (xy 197.281546 -317.829184)
			(xy 197.285774 -317.824953) (xy 197.292313 -317.81494) (xy 197.2945 -317.809372) (xy 197.29831 -317.79845)
			(xy 197.29704 -317.786512) (xy 197.295985 -317.777404) (xy 197.294841 -317.759104) (xy 197.294754 -317.749936)
			(xy 197.295237 -317.725111) (xy 197.303264 -317.676113) (xy 197.319113 -317.629061) (xy 197.342366 -317.585192)
			(xy 197.372409 -317.545663) (xy 197.408453 -317.511515) (xy 197.449546 -317.483649) (xy 197.494606 -317.462799)
			(xy 197.542446 -317.449514) (xy 197.591805 -317.444143) (xy 197.641383 -317.44683) (xy 197.689873 -317.457502)
			(xy 197.735997 -317.475879) (xy 197.778541 -317.501476) (xy 197.816383 -317.533619) (xy 197.848525 -317.571461)
			(xy 197.874122 -317.614004) (xy 197.892499 -317.660129) (xy 197.90317 -317.708619) (xy 197.905408 -317.749936)
			(xy 198.244218 -317.749936) (xy 198.248178 -317.700882) (xy 198.259955 -317.653098) (xy 198.279246 -317.607822)
			(xy 198.305549 -317.566226) (xy 198.338184 -317.529389) (xy 198.376305 -317.498264) (xy 198.418926 -317.473657)
			(xy 198.464942 -317.456205) (xy 198.513161 -317.446361) (xy 198.562336 -317.44438) (xy 198.611191 -317.450312)
			(xy 198.658462 -317.464004) (xy 198.702924 -317.485102) (xy 198.743427 -317.513058) (xy 198.77892 -317.54715)
			(xy 198.808485 -317.586494) (xy 198.831356 -317.630071) (xy 198.84694 -317.676752) (xy 198.854835 -317.725329)
			(xy 198.85533 -317.749936) (xy 198.854835 -317.774543) (xy 198.84694 -317.82312) (xy 198.831356 -317.869801)
			(xy 198.808485 -317.913378) (xy 198.77892 -317.952722) (xy 198.743427 -317.986814) (xy 198.702924 -318.01477)
			(xy 198.658462 -318.035868) (xy 198.611191 -318.04956) (xy 198.562336 -318.055492) (xy 198.513161 -318.053511)
			(xy 198.464942 -318.043667) (xy 198.418926 -318.026215) (xy 198.376305 -318.001608) (xy 198.338184 -317.970483)
			(xy 198.305549 -317.933646) (xy 198.279246 -317.89205) (xy 198.259955 -317.846774) (xy 198.248178 -317.79899)
			(xy 198.244218 -317.749936) (xy 197.905408 -317.749936) (xy 197.905856 -317.758197) (xy 197.900486 -317.807556)
			(xy 197.8872 -317.855396) (xy 197.86635 -317.900456) (xy 197.838483 -317.941549) (xy 197.804336 -317.977592)
			(xy 197.764807 -318.007635) (xy 197.720938 -318.030888) (xy 197.673885 -318.046736) (xy 197.624887 -318.054763)
			(xy 197.600062 -318.055244) (xy 197.590894 -318.05515) (xy 197.572594 -318.054004) (xy 197.563486 -318.052958)
			(xy 197.551294 -318.051688) (xy 197.540626 -318.055498) (xy 197.536967 -318.056876) (xy 197.53008 -318.060575)
			(xy 197.52691 -318.062864) (xy 197.520814 -318.068452) (xy 197.464426 -318.127126) (xy 197.461877 -318.129809)
			(xy 197.457538 -318.135802) (xy 197.45579 -318.139064) (xy 197.452488 -318.147446) (xy 197.448932 -318.158622)
			(xy 197.450964 -318.17056) (xy 197.453094 -318.184048) (xy 197.455381 -318.211262) (xy 197.455536 -318.224916)
			(xy 197.455536 -318.295274) (xy 197.45579 -318.299592) (xy 197.45579 -318.3001) (xy 197.456805 -318.307983)
			(xy 197.463004 -318.322607) (xy 197.467982 -318.328802) (xy 197.4723 -318.33312) (xy 197.528688 -318.383666)
			(xy 197.532692 -318.387061) (xy 197.541779 -318.392312) (xy 197.546722 -318.39408) (xy 197.556882 -318.397382)
			(xy 197.567804 -318.396366) (xy 197.600062 -318.394588) (xy 197.625789 -318.395117) (xy 197.676514 -318.403738)
			(xy 197.725076 -318.420743) (xy 197.770099 -318.44565) (xy 197.810308 -318.477754) (xy 197.844564 -318.516145)
			(xy 197.871898 -318.559737) (xy 197.891535 -318.607296) (xy 197.90292 -318.657473) (xy 197.904862 -318.683132)
			(xy 197.90537 -318.693038) (xy 197.909434 -318.701674) (xy 197.911555 -318.705992) (xy 197.917183 -318.713792)
			(xy 197.92061 -318.717168) (xy 197.97141 -318.765174) (xy 197.978678 -318.771521) (xy 197.996569 -318.778705)
			(xy 198.006208 -318.779144) (xy 201.424032 -318.779144) (xy 201.431398 -318.778636) (xy 201.432922 -318.778382)
			(xy 201.434192 -318.778128) (xy 201.438261 -318.777157) (xy 201.446046 -318.774094) (xy 201.449686 -318.772032)
			(xy 201.471022 -318.759586) (xy 201.476356 -318.753744) (xy 201.491088 -318.737996) (xy 201.494136 -318.731646)
			(xy 201.534391 -318.653589) (xy 201.619889 -318.500153) (xy 201.710969 -318.349962) (xy 201.807508 -318.203221)
			(xy 201.858118 -318.131444) (xy 201.908739 -318.061005) (xy 202.014403 -317.923416) (xy 202.124992 -317.789754)
			(xy 202.240361 -317.660194) (xy 202.300078 -317.597282) (xy 202.314302 -317.582296) (xy 202.319636 -317.576708)
			(xy 202.389565 -317.50528) (xy 202.534561 -317.367644) (xy 202.685188 -317.236197) (xy 202.841184 -317.111167)
			(xy 203.002276 -316.992775) (xy 203.16818 -316.881227) (xy 203.338607 -316.776719) (xy 203.513258 -316.679434)
			(xy 203.691826 -316.589542) (xy 203.874 -316.507202) (xy 204.05946 -316.432557) (xy 204.24788 -316.365737)
			(xy 204.438932 -316.306861) (xy 204.63228 -316.256031) (xy 204.827586 -316.213336) (xy 205.024507 -316.178851)
			(xy 205.222699 -316.152636) (xy 205.421814 -316.134738) (xy 205.621504 -316.125187) (xy 205.721458 -316.124082)
			(xy 205.770734 -316.124336) (xy 205.867741 -316.125247) (xy 206.061564 -316.133973) (xy 206.254873 -316.150563)
			(xy 206.447349 -316.174991) (xy 206.638674 -316.207215) (xy 206.828532 -316.247183) (xy 207.01661 -316.29483)
			(xy 207.202598 -316.350075) (xy 207.386189 -316.412829) (xy 207.56708 -316.482987) (xy 207.744972 -316.560434)
			(xy 207.919572 -316.645041) (xy 208.090591 -316.73667) (xy 208.257748 -316.83517) (xy 208.420767 -316.940377)
			(xy 208.579378 -317.052117) (xy 208.733321 -317.170208) (xy 208.88234 -317.294453) (xy 209.02619 -317.424648)
			(xy 209.164634 -317.560578) (xy 209.297443 -317.702018) (xy 209.424398 -317.848736) (xy 209.545289 -318.000488)
			(xy 209.659918 -318.157026) (xy 209.768094 -318.318089) (xy 209.86964 -318.483413) (xy 209.964387 -318.652725)
			(xy 210.008724 -318.739012) (xy 210.011518 -318.744854) (xy 210.01609 -318.749934) (xy 210.025234 -318.758062)
			(xy 210.043776 -318.770508) (xy 210.050137 -318.774483) (xy 210.064473 -318.778872) (xy 210.07197 -318.779144)
			(xy 213.825328 -318.779144) (xy 213.833456 -318.778382) (xy 213.833964 -318.778382) (xy 213.84148 -318.776776)
			(xy 213.855161 -318.769792) (xy 213.860888 -318.764666) (xy 215.799924 -316.82563) (xy 215.800432 -316.825122)
			(xy 215.805627 -316.819444) (xy 215.812612 -316.805739) (xy 215.814148 -316.798198) (xy 215.814148 -316.79769)
			(xy 215.81491 -316.789562) (xy 215.81491 -314.38596) (xy 215.813894 -314.376562) (xy 215.813894 -314.376054)
			(xy 215.811894 -314.367695) (xy 215.803175 -314.352894) (xy 215.790064 -314.341796) (xy 215.782144 -314.338462)
			(xy 215.705697 -314.308755) (xy 215.555471 -314.242896) (xy 215.408617 -314.169825) (xy 215.265482 -314.089713)
			(xy 215.126404 -314.00275) (xy 214.99171 -313.90914) (xy 214.861717 -313.809103) (xy 214.736732 -313.702877)
			(xy 214.617049 -313.59071) (xy 214.502951 -313.472867) (xy 214.394705 -313.349626) (xy 214.292568 -313.221277)
			(xy 214.19678 -313.088123) (xy 214.107566 -312.950477) (xy 214.025137 -312.808664) (xy 213.949688 -312.663019)
			(xy 213.881395 -312.513883) (xy 213.82042 -312.361609) (xy 213.766906 -312.206555) (xy 213.72098 -312.049087)
			(xy 213.682749 -311.889575) (xy 213.652305 -311.728397) (xy 213.629718 -311.565931) (xy 213.615042 -311.40256)
			(xy 213.608311 -311.238669) (xy 213.609542 -311.074645) (xy 213.61873 -310.910874) (xy 213.635856 -310.747742)
			(xy 213.660878 -310.585633) (xy 213.693737 -310.42493) (xy 213.734357 -310.26601) (xy 213.78264 -310.109249)
			(xy 213.838475 -309.955015) (xy 213.901727 -309.803673) (xy 213.97225 -309.655579) (xy 214.049877 -309.511081)
			(xy 214.134424 -309.370521) (xy 214.225693 -309.234229) (xy 214.323468 -309.102527) (xy 214.42752 -308.975726)
			(xy 214.537602 -308.854123) (xy 214.653456 -308.738005) (xy 214.774808 -308.627646) (xy 214.901373 -308.523307)
			(xy 214.966804 -308.473856) (xy 215.033837 -308.424383) (xy 215.172048 -308.331319) (xy 215.314678 -308.24518)
			(xy 215.461381 -308.166176) (xy 215.611799 -308.0945) (xy 215.765567 -308.030324) (xy 215.922312 -307.973806)
			(xy 216.081652 -307.925082) (xy 216.2432 -307.884271) (xy 216.406563 -307.851473) (xy 216.571344 -307.826766)
			(xy 216.737142 -307.810211) (xy 216.903555 -307.801849) (xy 216.986866 -307.801264) (xy 216.990168 -307.801264)
			(xy 217.069093 -307.801716) (xy 217.226772 -307.809076) (xy 217.383935 -307.823792) (xy 217.540239 -307.84583)
			(xy 217.695344 -307.875143) (xy 217.772234 -307.892958) (xy 217.783664 -307.895752) (xy 217.795094 -307.893212)
			(xy 217.799032 -307.892297) (xy 217.806564 -307.889365) (xy 217.81008 -307.88737) (xy 217.815668 -307.88356)
			(xy 217.877898 -307.83403) (xy 217.88501 -307.83403) (xy 221.97187 -303.74717) (xy 221.979269 -303.740327)
			(xy 221.997868 -303.732607) (xy 222.007938 -303.732184) (xy 232.00106 -303.732184) (xy 232.009188 -303.731422)
			(xy 232.009696 -303.731422) (xy 232.017217 -303.729826) (xy 232.030914 -303.722859) (xy 232.03662 -303.717706)
			(xy 232.382314 -303.372012) (xy 232.38714 -303.366424) (xy 232.391815 -303.359685) (xy 232.39701 -303.344139)
			(xy 232.3973 -303.335944) (xy 232.3973 -288.165794) (xy 232.396855 -288.156248) (xy 232.389816 -288.138494)
			(xy 232.383584 -288.13125) (xy 232.335832 -288.080196) (xy 232.332404 -288.076745) (xy 232.324476 -288.07111)
			(xy 232.320084 -288.06902) (xy 232.311448 -288.064956) (xy 232.301542 -288.064194) (xy 232.272772 -288.061968)
			(xy 232.216337 -288.049936) (xy 232.162358 -288.029545) (xy 232.112065 -288.001257) (xy 232.066604 -287.96572)
			(xy 232.027013 -287.923742) (xy 231.994194 -287.876281) (xy 231.968896 -287.82442) (xy 231.951696 -287.76934)
			(xy 231.942985 -287.712299) (xy 231.942386 -287.683448) (xy 231.942847 -287.656171) (xy 231.950608 -287.602173)
			(xy 231.96598 -287.54983) (xy 231.988649 -287.500209) (xy 232.018153 -287.454322) (xy 232.05389 -287.413104)
			(xy 232.074212 -287.394904) (xy 232.074466 -287.39465) (xy 232.078933 -287.390534) (xy 232.085993 -287.380653)
			(xy 232.088436 -287.375092) (xy 232.090722 -287.36925) (xy 232.092246 -287.357058) (xy 232.082086 -287.267396)
			(xy 232.079292 -287.255966) (xy 232.07345 -287.244282) (xy 232.069894 -287.239202) (xy 232.06075 -287.23082)
			(xy 232.055162 -287.228026) (xy 232.032441 -287.215656) (xy 231.990262 -287.185703) (xy 231.971088 -287.168336)
			(xy 231.963976 -287.161478) (xy 231.955086 -287.157922) (xy 231.950677 -287.156363) (xy 231.941474 -287.154703)
			(xy 231.936798 -287.15462) (xy 231.866694 -287.15462) (xy 231.862019 -287.154708) (xy 231.852819 -287.156376)
			(xy 231.848406 -287.157922) (xy 231.839516 -287.161478) (xy 231.832404 -287.168336) (xy 231.811077 -287.187607)
			(xy 231.763714 -287.220173) (xy 231.712003 -287.245266) (xy 231.657112 -287.26232) (xy 231.600285 -287.270948)
			(xy 231.571546 -287.27146) (xy 231.544292 -287.271) (xy 231.490339 -287.263248) (xy 231.438038 -287.247895)
			(xy 231.388455 -287.225255) (xy 231.3426 -287.195787) (xy 231.301406 -287.160093) (xy 231.265712 -287.118898)
			(xy 231.236244 -287.073043) (xy 231.213604 -287.02346) (xy 231.198252 -286.971159) (xy 231.1905 -286.917206)
			(xy 231.190038 -286.889952) (xy 231.190471 -286.863727) (xy 231.197651 -286.811772) (xy 231.211884 -286.761292)
			(xy 231.2329 -286.713237) (xy 231.260303 -286.668516) (xy 231.293576 -286.627973) (xy 231.332091 -286.592371)
			(xy 231.35336 -286.577024) (xy 231.353614 -286.577024) (xy 231.358656 -286.573266) (xy 231.366885 -286.563762)
			(xy 231.36987 -286.558228) (xy 231.372664 -286.552894) (xy 231.375458 -286.540956) (xy 231.37368 -286.451548)
			(xy 231.373052 -286.441846) (xy 231.36547 -286.423961) (xy 231.358948 -286.41675) (xy 231.350312 -286.408114)
			(xy 231.346248 -286.40532) (xy 231.332957 -286.39636) (xy 231.307777 -286.376522) (xy 231.295956 -286.365696)
			(xy 231.288844 -286.358838) (xy 231.279954 -286.355282) (xy 231.275545 -286.353724) (xy 231.266342 -286.352068)
			(xy 231.261666 -286.35198) (xy 231.191562 -286.35198) (xy 231.186886 -286.352062) (xy 231.177683 -286.353721)
			(xy 231.173274 -286.355282) (xy 231.164384 -286.358838) (xy 231.157272 -286.365696) (xy 231.135945 -286.384967)
			(xy 231.088582 -286.417532) (xy 231.036871 -286.442624) (xy 230.98198 -286.459675) (xy 230.925153 -286.468299)
			(xy 230.896414 -286.46882) (xy 230.86916 -286.468358) (xy 230.815207 -286.460603) (xy 230.762907 -286.445248)
			(xy 230.713324 -286.422607) (xy 230.667468 -286.393139) (xy 230.626273 -286.357446) (xy 230.590577 -286.316253)
			(xy 230.561106 -286.270399) (xy 230.538461 -286.220818) (xy 230.523103 -286.168518) (xy 230.515344 -286.114566)
			(xy 230.514906 -286.087312) (xy 230.514906 -286.086804) (xy 230.515542 -286.055185) (xy 230.525997 -285.992815)
			(xy 230.546588 -285.933022) (xy 230.561134 -285.90494) (xy 230.56596 -285.896304) (xy 230.566976 -285.886652)
			(xy 230.567442 -285.881869) (xy 230.566807 -285.87228) (xy 230.565706 -285.867602) (xy 230.547672 -285.800546)
			(xy 230.546346 -285.795835) (xy 230.542127 -285.787007) (xy 230.53929 -285.78302) (xy 230.533448 -285.7754)
			(xy 230.525066 -285.77032) (xy 230.525066 -285.770066) (xy 230.509175 -285.759957) (xy 230.479275 -285.737055)
			(xy 230.465376 -285.724346) (xy 230.45801 -285.717488) (xy 230.449374 -285.714186) (xy 230.444911 -285.712556)
			(xy 230.435581 -285.71076) (xy 230.430832 -285.71063) (xy 230.360982 -285.71063) (xy 230.356305 -285.71071)
			(xy 230.3471 -285.712364) (xy 230.342694 -285.713932) (xy 230.333804 -285.717488) (xy 230.326692 -285.724346)
			(xy 230.305365 -285.743616) (xy 230.258002 -285.776181) (xy 230.206291 -285.801272) (xy 230.1514 -285.818322)
			(xy 230.094573 -285.826944) (xy 230.037095 -285.826944) (xy 229.980268 -285.818322) (xy 229.925377 -285.801272)
			(xy 229.873666 -285.776181) (xy 229.826303 -285.743616) (xy 229.804976 -285.724346) (xy 229.797864 -285.717488)
			(xy 229.788974 -285.713932) (xy 229.784565 -285.712374) (xy 229.775362 -285.710716) (xy 229.770686 -285.71063)
			(xy 229.700582 -285.71063) (xy 229.695905 -285.71071) (xy 229.6867 -285.712364) (xy 229.682294 -285.713932)
			(xy 229.673404 -285.717488) (xy 229.666292 -285.724346) (xy 229.644964 -285.743616) (xy 229.597601 -285.776179)
			(xy 229.545889 -285.801271) (xy 229.490999 -285.818322) (xy 229.434173 -285.826948) (xy 229.405434 -285.82747)
			(xy 229.378182 -285.827009) (xy 229.324233 -285.819257) (xy 229.271936 -285.803905) (xy 229.222357 -285.781267)
			(xy 229.176504 -285.751803) (xy 229.135311 -285.716113) (xy 229.099618 -285.674923) (xy 229.070149 -285.629073)
			(xy 229.047507 -285.579496) (xy 229.03215 -285.5272) (xy 229.024393 -285.473252) (xy 229.024393 -285.418748)
			(xy 229.03215 -285.3648) (xy 229.047507 -285.312504) (xy 229.070149 -285.262927) (xy 229.099618 -285.217077)
			(xy 229.135311 -285.175887) (xy 229.176504 -285.140197) (xy 229.222357 -285.110733) (xy 229.271936 -285.088095)
			(xy 229.324233 -285.072743) (xy 229.378182 -285.064991) (xy 229.405434 -285.064454) (xy 229.434172 -285.064978)
			(xy 229.490996 -285.073606) (xy 229.545883 -285.090662) (xy 229.597589 -285.115759) (xy 229.644945 -285.14833)
			(xy 229.666292 -285.167578) (xy 229.673404 -285.174436) (xy 229.682294 -285.177992) (xy 229.686702 -285.179555)
			(xy 229.695905 -285.181222) (xy 229.700582 -285.181294) (xy 229.770686 -285.181294) (xy 229.775362 -285.181208)
			(xy 229.784562 -285.179543) (xy 229.788974 -285.177992) (xy 229.797864 -285.174436) (xy 229.804976 -285.167578)
			(xy 229.826303 -285.148308) (xy 229.873666 -285.115743) (xy 229.925377 -285.090652) (xy 229.980268 -285.073602)
			(xy 230.037095 -285.06498) (xy 230.094573 -285.06498) (xy 230.1514 -285.073602) (xy 230.206291 -285.090652)
			(xy 230.258002 -285.115743) (xy 230.305365 -285.148308) (xy 230.326692 -285.167578) (xy 230.333804 -285.174436)
			(xy 230.342694 -285.177992) (xy 230.347102 -285.179555) (xy 230.356305 -285.181222) (xy 230.360982 -285.181294)
			(xy 230.431086 -285.181294) (xy 230.435762 -285.181208) (xy 230.444962 -285.179543) (xy 230.449374 -285.177992)
			(xy 230.458264 -285.174436) (xy 230.465376 -285.167578) (xy 230.486703 -285.148305) (xy 230.534064 -285.115736)
			(xy 230.585776 -285.090638) (xy 230.640666 -285.073581) (xy 230.697494 -285.06495) (xy 230.726234 -285.064454)
			(xy 230.75636 -285.065018) (xy 230.815863 -285.074482) (xy 230.873138 -285.093185) (xy 230.926759 -285.120662)
			(xy 230.975392 -285.156229) (xy 230.996998 -285.17723) (xy 231.000614 -285.180666) (xy 231.00893 -285.186173)
			(xy 231.013508 -285.188152) (xy 231.022906 -285.192216) (xy 231.105202 -285.192216) (xy 231.110235 -285.19208)
			(xy 231.120093 -285.190041) (xy 231.12476 -285.188152) (xy 231.134412 -285.184088) (xy 231.152502 -285.165559)
			(xy 231.192817 -285.133059) (xy 231.237154 -285.106307) (xy 231.284701 -285.085793) (xy 231.334584 -285.071893)
			(xy 231.385889 -285.064865) (xy 231.41178 -285.064454) (xy 231.412034 -285.064454) (xy 231.439008 -285.064922)
			(xy 231.492417 -285.072526) (xy 231.544223 -285.087578) (xy 231.593392 -285.109776) (xy 231.638944 -285.138679)
			(xy 231.679971 -285.173711) (xy 231.715653 -285.214172) (xy 231.745281 -285.259256) (xy 231.768263 -285.308064)
			(xy 231.784141 -285.359623) (xy 231.792597 -285.412904) (xy 231.793542 -285.439866) (xy 231.793542 -285.445962)
			(xy 231.793157 -285.471084) (xy 231.786592 -285.520896) (xy 231.773544 -285.569415) (xy 231.754239 -285.615801)
			(xy 231.74198 -285.637732) (xy 231.7369 -285.646114) (xy 231.73563 -285.655512) (xy 231.734973 -285.6602)
			(xy 231.735226 -285.669663) (xy 231.736138 -285.674308) (xy 231.751632 -285.741872) (xy 231.752755 -285.746463)
			(xy 231.756468 -285.755152) (xy 231.758998 -285.759144) (xy 231.764332 -285.767018) (xy 231.77246 -285.772606)
			(xy 231.784355 -285.780924) (xy 231.806984 -285.799107) (xy 231.817672 -285.808928) (xy 231.824784 -285.815786)
			(xy 231.833674 -285.819342) (xy 231.838082 -285.820906) (xy 231.847285 -285.822574) (xy 231.851962 -285.822644)
			(xy 231.922066 -285.822644) (xy 231.926742 -285.82256) (xy 231.935943 -285.820897) (xy 231.940354 -285.819342)
			(xy 231.949244 -285.815786) (xy 231.956356 -285.808928) (xy 231.977683 -285.789658) (xy 232.025046 -285.757094)
			(xy 232.076758 -285.732004) (xy 232.131648 -285.714956) (xy 232.188475 -285.706335) (xy 232.217214 -285.705804)
			(xy 232.23278 -285.705957) (xy 232.263807 -285.708499) (xy 232.27919 -285.710884) (xy 232.290366 -285.712662)
			(xy 232.30078 -285.709868) (xy 232.306135 -285.70825) (xy 232.316009 -285.702997) (xy 232.320338 -285.699454)
			(xy 232.379266 -285.649416) (xy 232.379774 -285.648908) (xy 232.380028 -285.648908) (xy 232.387875 -285.641325)
			(xy 232.396844 -285.621455) (xy 232.3973 -285.610554) (xy 232.3973 -283.346144) (xy 232.397163 -283.341253)
			(xy 232.395244 -283.331661) (xy 232.39349 -283.327094) (xy 232.38968 -283.317442) (xy 232.382314 -283.31033)
			(xy 231.939846 -282.867862) (xy 231.932173 -282.860825) (xy 231.912861 -282.853107) (xy 231.892074 -282.853746)
			(xy 231.882442 -282.857702) (xy 231.796082 -282.897834) (xy 231.795828 -282.898088) (xy 231.788899 -282.901542)
			(xy 231.777384 -282.91188) (xy 231.773222 -282.918408) (xy 231.769412 -282.925266) (xy 231.765856 -282.94076)
			(xy 231.766618 -282.94838) (xy 231.768142 -282.982162) (xy 231.767682 -283.009418) (xy 231.759929 -283.063374)
			(xy 231.744577 -283.115679) (xy 231.721937 -283.165266) (xy 231.692471 -283.211126) (xy 231.656777 -283.252326)
			(xy 231.615584 -283.288027) (xy 231.569729 -283.317503) (xy 231.520146 -283.340152) (xy 231.467845 -283.355514)
			(xy 231.413889 -283.363277) (xy 231.386634 -283.36367) (xy 231.356509 -283.363103) (xy 231.297008 -283.353635)
			(xy 231.239736 -283.33493) (xy 231.186117 -283.307451) (xy 231.137486 -283.271884) (xy 231.11587 -283.250894)
			(xy 231.112253 -283.247459) (xy 231.103937 -283.241955) (xy 231.09936 -283.239972) (xy 231.089962 -283.235908)
			(xy 231.007666 -283.235908) (xy 231.002634 -283.236047) (xy 230.992778 -283.238093) (xy 230.988108 -283.239972)
			(xy 230.978456 -283.244036) (xy 230.960365 -283.262562) (xy 230.920049 -283.295057) (xy 230.87571 -283.321804)
			(xy 230.828164 -283.342313) (xy 230.778281 -283.356207) (xy 230.726978 -283.363231) (xy 230.701088 -283.36367)
			(xy 230.700834 -283.36367) (xy 230.672094 -283.363151) (xy 230.615264 -283.354533) (xy 230.560371 -283.337485)
			(xy 230.508656 -283.312395) (xy 230.461291 -283.27983) (xy 230.439976 -283.260546) (xy 230.432864 -283.253688)
			(xy 230.423974 -283.250132) (xy 230.419565 -283.248574) (xy 230.410362 -283.246916) (xy 230.405686 -283.24683)
			(xy 230.335582 -283.24683) (xy 230.330905 -283.24691) (xy 230.3217 -283.248564) (xy 230.317294 -283.250132)
			(xy 230.308404 -283.253688) (xy 230.301292 -283.260546) (xy 230.279965 -283.279816) (xy 230.232602 -283.312381)
			(xy 230.180891 -283.337472) (xy 230.126 -283.354522) (xy 230.069173 -283.363144) (xy 230.011695 -283.363144)
			(xy 229.954868 -283.354522) (xy 229.899977 -283.337472) (xy 229.848266 -283.312381) (xy 229.800903 -283.279816)
			(xy 229.779576 -283.260546) (xy 229.772464 -283.253688) (xy 229.763574 -283.250132) (xy 229.759165 -283.248574)
			(xy 229.749962 -283.246916) (xy 229.745286 -283.24683) (xy 229.675182 -283.24683) (xy 229.670505 -283.24691)
			(xy 229.6613 -283.248564) (xy 229.656894 -283.250132) (xy 229.648004 -283.253688) (xy 229.640892 -283.260546)
			(xy 229.619564 -283.279816) (xy 229.572201 -283.312379) (xy 229.520489 -283.337471) (xy 229.465599 -283.354522)
			(xy 229.408773 -283.363148) (xy 229.380034 -283.36367) (xy 229.352782 -283.363209) (xy 229.298833 -283.355457)
			(xy 229.246536 -283.340105) (xy 229.196957 -283.317467) (xy 229.151104 -283.288003) (xy 229.109911 -283.252313)
			(xy 229.074218 -283.211123) (xy 229.044749 -283.165273) (xy 229.022107 -283.115696) (xy 229.00675 -283.0634)
			(xy 228.998993 -283.009452) (xy 228.998993 -282.954948) (xy 229.00675 -282.901) (xy 229.022107 -282.848704)
			(xy 229.044749 -282.799127) (xy 229.074218 -282.753277) (xy 229.109911 -282.712087) (xy 229.151104 -282.676397)
			(xy 229.196957 -282.646933) (xy 229.246536 -282.624295) (xy 229.298833 -282.608943) (xy 229.352782 -282.601191)
			(xy 229.380034 -282.600654) (xy 229.408772 -282.601178) (xy 229.465596 -282.609806) (xy 229.520483 -282.626862)
			(xy 229.572189 -282.651959) (xy 229.619545 -282.68453) (xy 229.640892 -282.703778) (xy 229.648004 -282.710636)
			(xy 229.656894 -282.714192) (xy 229.661302 -282.715755) (xy 229.670505 -282.717422) (xy 229.675182 -282.717494)
			(xy 229.745286 -282.717494) (xy 229.749962 -282.717408) (xy 229.759162 -282.715743) (xy 229.763574 -282.714192)
			(xy 229.772464 -282.710636) (xy 229.779576 -282.703778) (xy 229.800903 -282.684508) (xy 229.848266 -282.651943)
			(xy 229.899977 -282.626852) (xy 229.954868 -282.609802) (xy 230.011695 -282.60118) (xy 230.069173 -282.60118)
			(xy 230.126 -282.609802) (xy 230.180891 -282.626852) (xy 230.232602 -282.651943) (xy 230.279965 -282.684508)
			(xy 230.301292 -282.703778) (xy 230.308404 -282.710636) (xy 230.317294 -282.714192) (xy 230.321702 -282.715755)
			(xy 230.330905 -282.717422) (xy 230.335582 -282.717494) (xy 230.405686 -282.717494) (xy 230.410362 -282.717408)
			(xy 230.419562 -282.715743) (xy 230.423974 -282.714192) (xy 230.432864 -282.710636) (xy 230.439976 -282.703778)
			(xy 230.461303 -282.684505) (xy 230.508664 -282.651936) (xy 230.560376 -282.626838) (xy 230.615266 -282.609781)
			(xy 230.672094 -282.60115) (xy 230.700834 -282.600654) (xy 230.73096 -282.601218) (xy 230.790463 -282.610682)
			(xy 230.847738 -282.629385) (xy 230.901359 -282.656862) (xy 230.949992 -282.692429) (xy 230.971598 -282.71343)
			(xy 230.975214 -282.716866) (xy 230.98353 -282.722373) (xy 230.988108 -282.724352) (xy 230.997506 -282.728416)
			(xy 231.079802 -282.728416) (xy 231.084835 -282.72828) (xy 231.094693 -282.726241) (xy 231.09936 -282.724352)
			(xy 231.109012 -282.720288) (xy 231.127102 -282.701759) (xy 231.167417 -282.669259) (xy 231.211754 -282.642507)
			(xy 231.259301 -282.621993) (xy 231.309184 -282.608093) (xy 231.360489 -282.601065) (xy 231.38638 -282.600654)
			(xy 231.386634 -282.600654) (xy 231.420416 -282.602178) (xy 231.428036 -282.60294) (xy 231.44353 -282.599384)
			(xy 231.450388 -282.595574) (xy 231.456901 -282.591394) (xy 231.467238 -282.579886) (xy 231.470708 -282.572968)
			(xy 231.470962 -282.572714) (xy 231.511094 -282.486354) (xy 231.514995 -282.476723) (xy 231.515547 -282.455971)
			(xy 231.507884 -282.436678) (xy 231.500934 -282.42895) (xy 229.923086 -280.851102) (xy 229.91623 -280.843708)
			(xy 229.908481 -280.825109) (xy 229.9081 -280.815034) (xy 229.9081 -256.28219) (xy 229.907967 -256.277299)
			(xy 229.906056 -256.267703) (xy 229.90429 -256.26314) (xy 229.90048 -256.253488) (xy 229.893114 -256.246376)
			(xy 228.303328 -254.65659) (xy 228.29774 -254.651764) (xy 228.290998 -254.647101) (xy 228.275452 -254.64193)
			(xy 228.26726 -254.641604) (xy 224.31883 -254.641604) (xy 224.308765 -254.641168) (xy 224.290179 -254.633436)
			(xy 224.282762 -254.626618) (xy 223.394016 -253.737872) (xy 223.388428 -253.733046) (xy 223.381689 -253.728372)
			(xy 223.366143 -253.723177) (xy 223.357948 -253.722886) (xy 220.897196 -253.722886) (xy 220.883988 -253.721108)
			(xy 220.880686 -253.720092) (xy 220.877384 -253.718822) (xy 220.872932 -253.717152) (xy 220.863596 -253.715355)
			(xy 220.858842 -253.715266) (xy 199.670162 -253.715266) (xy 199.668638 -253.71679) (xy 199.662542 -253.715266)
			(xy 178.781456 -253.715266) (xy 178.776565 -253.715402) (xy 178.766972 -253.717317) (xy 178.762406 -253.719076)
			(xy 178.752754 -253.722886) (xy 178.745642 -253.730252) (xy 177.538888 -254.937006) (xy 177.533554 -254.943356)
			(xy 177.53045 -254.947982) (xy 177.526085 -254.958229) (xy 177.524918 -254.963676) (xy 177.493828 -255.13284)
			(xy 188.35573 -255.13284) (xy 188.359801 -255.077218) (xy 188.371927 -255.022781) (xy 188.39185 -254.97069)
			(xy 188.419146 -254.922055) (xy 188.453232 -254.877912) (xy 188.493381 -254.839203) (xy 188.538739 -254.806752)
			(xy 188.588339 -254.781251) (xy 188.641123 -254.763244) (xy 188.695966 -254.753114) (xy 188.7517 -254.751077)
			(xy 188.807137 -254.757177) (xy 188.861094 -254.771283) (xy 188.912423 -254.793095) (xy 188.960029 -254.822149)
			(xy 189.002897 -254.857824) (xy 189.040114 -254.899361) (xy 189.070887 -254.945874) (xy 189.094559 -254.996371)
			(xy 189.110627 -255.049778) (xy 189.118747 -255.104954) (xy 189.119256 -255.13284) (xy 189.118747 -255.160726)
			(xy 189.110627 -255.215902) (xy 189.094559 -255.269309) (xy 189.070887 -255.319806) (xy 189.040114 -255.366319)
			(xy 189.002897 -255.407856) (xy 188.960029 -255.443531) (xy 188.912423 -255.472585) (xy 188.861094 -255.494397)
			(xy 188.807137 -255.508503) (xy 188.7517 -255.514603) (xy 188.695966 -255.512566) (xy 188.641123 -255.502436)
			(xy 188.588339 -255.484429) (xy 188.538739 -255.458928) (xy 188.493381 -255.426477) (xy 188.453232 -255.387768)
			(xy 188.419146 -255.343625) (xy 188.39185 -255.29499) (xy 188.371927 -255.242899) (xy 188.359801 -255.188462)
			(xy 188.35573 -255.13284) (xy 177.493828 -255.13284) (xy 177.374834 -255.780286) (xy 189.018924 -255.780286)
			(xy 189.022995 -255.724664) (xy 189.035121 -255.670227) (xy 189.055044 -255.618136) (xy 189.08234 -255.569501)
			(xy 189.116426 -255.525358) (xy 189.156575 -255.486649) (xy 189.201933 -255.454198) (xy 189.251533 -255.428697)
			(xy 189.304317 -255.41069) (xy 189.35916 -255.40056) (xy 189.414894 -255.398523) (xy 189.470331 -255.404623)
			(xy 189.524288 -255.418729) (xy 189.575617 -255.440541) (xy 189.623223 -255.469595) (xy 189.666091 -255.50527)
			(xy 189.703308 -255.546807) (xy 189.734081 -255.59332) (xy 189.757753 -255.643817) (xy 189.773821 -255.697224)
			(xy 189.781941 -255.7524) (xy 189.782051 -255.758442) (xy 199.922382 -255.758442) (xy 199.926453 -255.70282)
			(xy 199.938579 -255.648383) (xy 199.958502 -255.596292) (xy 199.985798 -255.547657) (xy 200.019884 -255.503514)
			(xy 200.060033 -255.464805) (xy 200.105391 -255.432354) (xy 200.154991 -255.406853) (xy 200.207775 -255.388846)
			(xy 200.262618 -255.378716) (xy 200.318352 -255.376679) (xy 200.373789 -255.382779) (xy 200.427746 -255.396885)
			(xy 200.479075 -255.418697) (xy 200.526681 -255.447751) (xy 200.569549 -255.483426) (xy 200.606766 -255.524963)
			(xy 200.637539 -255.571476) (xy 200.661211 -255.621973) (xy 200.677279 -255.67538) (xy 200.685399 -255.730556)
			(xy 200.685908 -255.758442) (xy 215.692736 -255.758442) (xy 215.693195 -255.731188) (xy 215.700947 -255.677235)
			(xy 215.7163 -255.624934) (xy 215.738941 -255.575351) (xy 215.768408 -255.529496) (xy 215.804103 -255.488301)
			(xy 215.845297 -255.452607) (xy 215.891153 -255.42314) (xy 215.940736 -255.400499) (xy 215.993037 -255.385146)
			(xy 216.04699 -255.377394) (xy 216.074244 -255.376934) (xy 216.101583 -255.377377) (xy 216.155701 -255.385171)
			(xy 216.208154 -255.400608) (xy 216.257867 -255.423372) (xy 216.303824 -255.452996) (xy 216.345083 -255.488875)
			(xy 216.363296 -255.509268) (xy 216.370154 -255.517396) (xy 216.379044 -255.521714) (xy 216.38384 -255.52396)
			(xy 216.394083 -255.526647) (xy 216.399364 -255.527048) (xy 216.473786 -255.530096) (xy 216.478835 -255.530205)
			(xy 216.488817 -255.528674) (xy 216.493598 -255.527048) (xy 216.502996 -255.523492) (xy 216.510616 -255.51638)
			(xy 216.51087 -255.516126) (xy 216.511632 -255.515364) (xy 216.533099 -255.495512) (xy 216.580917 -255.461868)
			(xy 216.633304 -255.435906) (xy 216.689037 -255.418236) (xy 216.746813 -255.409268) (xy 216.776046 -255.408684)
			(xy 216.803298 -255.409135) (xy 216.857247 -255.416898) (xy 216.909541 -255.432258) (xy 216.959118 -255.454904)
			(xy 217.004968 -255.484374) (xy 217.046158 -255.520069) (xy 217.081848 -255.561262) (xy 217.111314 -255.607115)
			(xy 217.133955 -255.656694) (xy 217.149311 -255.708991) (xy 217.157068 -255.76294) (xy 217.157554 -255.790192)
			(xy 217.156995 -255.819405) (xy 217.148102 -255.877149) (xy 217.130508 -255.932861) (xy 217.104623 -255.985239)
			(xy 217.071053 -256.033057) (xy 217.030585 -256.075197) (xy 216.984163 -256.110672) (xy 216.932875 -256.138653)
			(xy 216.905586 -256.149094) (xy 216.895934 -256.152396) (xy 216.888568 -256.159254) (xy 216.885022 -256.162715)
			(xy 216.879269 -256.170782) (xy 216.877138 -256.175256) (xy 216.846404 -256.241296) (xy 216.84439 -256.245885)
			(xy 216.841956 -256.255603) (xy 216.841578 -256.2606) (xy 216.841324 -256.270506) (xy 216.845134 -256.280158)
			(xy 216.853162 -256.302647) (xy 216.864383 -256.349064) (xy 216.868723 -256.385822) (xy 218.904818 -256.385822)
			(xy 218.908889 -256.3302) (xy 218.921015 -256.275763) (xy 218.940938 -256.223672) (xy 218.968234 -256.175037)
			(xy 219.00232 -256.130894) (xy 219.042469 -256.092185) (xy 219.087827 -256.059734) (xy 219.137427 -256.034233)
			(xy 219.190211 -256.016226) (xy 219.245054 -256.006096) (xy 219.300788 -256.004059) (xy 219.356225 -256.010159)
			(xy 219.410182 -256.024265) (xy 219.461511 -256.046077) (xy 219.509117 -256.075131) (xy 219.551985 -256.110806)
			(xy 219.589202 -256.152343) (xy 219.619975 -256.198856) (xy 219.643647 -256.249353) (xy 219.659715 -256.30276)
			(xy 219.667835 -256.357936) (xy 219.668344 -256.385822) (xy 219.667835 -256.413708) (xy 219.659715 -256.468884)
			(xy 219.643647 -256.522291) (xy 219.619975 -256.572788) (xy 219.589202 -256.619301) (xy 219.551985 -256.660838)
			(xy 219.509117 -256.696513) (xy 219.461511 -256.725567) (xy 219.410182 -256.747379) (xy 219.356225 -256.761485)
			(xy 219.300788 -256.767585) (xy 219.245054 -256.765548) (xy 219.190211 -256.755418) (xy 219.137427 -256.737411)
			(xy 219.087827 -256.71191) (xy 219.042469 -256.679459) (xy 219.00232 -256.64075) (xy 218.968234 -256.596607)
			(xy 218.940938 -256.547972) (xy 218.921015 -256.495881) (xy 218.908889 -256.441444) (xy 218.904818 -256.385822)
			(xy 216.868723 -256.385822) (xy 216.869982 -256.396488) (xy 216.87028 -256.420366) (xy 216.869771 -256.448905)
			(xy 216.861648 -256.505403) (xy 216.845567 -256.56017) (xy 216.821856 -256.612091) (xy 216.790997 -256.660109)
			(xy 216.753618 -256.703246) (xy 216.710481 -256.740625) (xy 216.662463 -256.771484) (xy 216.610542 -256.795195)
			(xy 216.555775 -256.811276) (xy 216.499277 -256.819399) (xy 216.442199 -256.819399) (xy 216.385701 -256.811276)
			(xy 216.330934 -256.795195) (xy 216.279013 -256.771484) (xy 216.230995 -256.740625) (xy 216.187858 -256.703246)
			(xy 216.150479 -256.660109) (xy 216.11962 -256.612091) (xy 216.095909 -256.56017) (xy 216.079828 -256.505403)
			(xy 216.071705 -256.448905) (xy 216.071196 -256.420366) (xy 216.071196 -256.419604) (xy 216.071615 -256.394719)
			(xy 216.077844 -256.345339) (xy 216.090143 -256.297112) (xy 216.098882 -256.273808) (xy 216.098882 -256.273554)
			(xy 216.1032 -256.262632) (xy 216.102438 -256.25171) (xy 216.10188 -256.245976) (xy 216.098539 -256.234953)
			(xy 216.095834 -256.229866) (xy 216.055702 -256.160524) (xy 216.052631 -256.155594) (xy 216.044687 -256.147125)
			(xy 216.039954 -256.14376) (xy 216.03081 -256.137664) (xy 216.019126 -256.135886) (xy 215.992272 -256.13148)
			(xy 215.940085 -256.116061) (xy 215.89062 -256.093381) (xy 215.844881 -256.063899) (xy 215.803797 -256.028216)
			(xy 215.768203 -255.987054) (xy 215.738821 -255.941251) (xy 215.716248 -255.891737) (xy 215.700942 -255.839516)
			(xy 215.693215 -255.785651) (xy 215.692736 -255.758442) (xy 200.685908 -255.758442) (xy 200.685399 -255.786328)
			(xy 200.677279 -255.841504) (xy 200.661211 -255.894911) (xy 200.637539 -255.945408) (xy 200.606766 -255.991921)
			(xy 200.569549 -256.033458) (xy 200.526681 -256.069133) (xy 200.479075 -256.098187) (xy 200.427746 -256.119999)
			(xy 200.373789 -256.134105) (xy 200.318352 -256.140205) (xy 200.262618 -256.138168) (xy 200.207775 -256.128038)
			(xy 200.154991 -256.110031) (xy 200.105391 -256.08453) (xy 200.060033 -256.052079) (xy 200.019884 -256.01337)
			(xy 199.985798 -255.969227) (xy 199.958502 -255.920592) (xy 199.938579 -255.868501) (xy 199.926453 -255.814064)
			(xy 199.922382 -255.758442) (xy 189.782051 -255.758442) (xy 189.78245 -255.780286) (xy 189.781941 -255.808172)
			(xy 189.773821 -255.863348) (xy 189.757753 -255.916755) (xy 189.734081 -255.967252) (xy 189.703308 -256.013765)
			(xy 189.666091 -256.055302) (xy 189.623223 -256.090977) (xy 189.575617 -256.120031) (xy 189.524288 -256.141843)
			(xy 189.470331 -256.155949) (xy 189.414894 -256.162049) (xy 189.35916 -256.160012) (xy 189.304317 -256.149882)
			(xy 189.251533 -256.131875) (xy 189.201933 -256.106374) (xy 189.156575 -256.073923) (xy 189.116426 -256.035214)
			(xy 189.08234 -255.991071) (xy 189.055044 -255.942436) (xy 189.035121 -255.890345) (xy 189.022995 -255.835908)
			(xy 189.018924 -255.780286) (xy 177.374834 -255.780286) (xy 177.160231 -256.947947) (xy 213.216524 -256.947947)
			(xy 213.216524 -256.893453) (xy 213.224279 -256.839512) (xy 213.239632 -256.787225) (xy 213.26227 -256.737654)
			(xy 213.291732 -256.69181) (xy 213.327418 -256.650625) (xy 213.368602 -256.614938) (xy 213.414445 -256.585475)
			(xy 213.464015 -256.562836) (xy 213.516302 -256.547482) (xy 213.570243 -256.539725) (xy 213.59749 -256.539238)
			(xy 213.62595 -256.53978) (xy 213.68224 -256.548229) (xy 213.736647 -256.564955) (xy 213.787961 -256.589586)
			(xy 213.835042 -256.621575) (xy 213.876842 -256.66021) (xy 213.912432 -256.704631) (xy 213.927182 -256.728976)
			(xy 213.93023 -256.73431) (xy 213.938866 -256.7432) (xy 213.943946 -256.746502) (xy 213.94802 -256.748919)
			(xy 213.956837 -256.75238) (xy 213.961472 -256.75336) (xy 213.967314 -256.754122) (xy 214.05723 -256.760726)
			(xy 214.068914 -256.758948) (xy 214.074502 -256.756408) (xy 214.080037 -256.753845) (xy 214.089788 -256.74652)
			(xy 214.093806 -256.74193) (xy 214.094314 -256.741422) (xy 214.112094 -256.720848) (xy 214.119714 -256.71272)
			(xy 214.12327 -256.702052) (xy 214.12485 -256.696612) (xy 214.12588 -256.685335) (xy 214.125302 -256.6797)
			(xy 214.11565 -256.602738) (xy 214.114888 -256.597912) (xy 214.11057 -256.585974) (xy 214.108284 -256.58191)
			(xy 214.102188 -256.572258) (xy 214.093298 -256.566162) (xy 214.092282 -256.565654) (xy 214.068527 -256.549834)
			(xy 214.025398 -256.51245) (xy 213.988022 -256.469315) (xy 213.957158 -256.421305) (xy 213.933432 -256.369394)
			(xy 213.917327 -256.314639) (xy 213.909169 -256.258149) (xy 213.90864 -256.229612) (xy 213.909149 -256.201054)
			(xy 213.917278 -256.144521) (xy 213.933369 -256.089719) (xy 213.957095 -256.037766) (xy 213.987974 -255.989717)
			(xy 214.025377 -255.946553) (xy 214.068541 -255.90915) (xy 214.11659 -255.878271) (xy 214.168543 -255.854545)
			(xy 214.223345 -255.838454) (xy 214.279878 -255.830325) (xy 214.336994 -255.830325) (xy 214.393527 -255.838454)
			(xy 214.448329 -255.854545) (xy 214.500282 -255.878271) (xy 214.548331 -255.90915) (xy 214.591495 -255.946553)
			(xy 214.628898 -255.989717) (xy 214.659777 -256.037766) (xy 214.683503 -256.089719) (xy 214.699594 -256.144521)
			(xy 214.707723 -256.201054) (xy 214.708232 -256.229612) (xy 214.707793 -256.255677) (xy 214.700988 -256.307362)
			(xy 214.687523 -256.357724) (xy 214.667624 -256.405908) (xy 214.641631 -256.451096) (xy 214.609984 -256.492521)
			(xy 214.5919 -256.511298) (xy 214.583772 -256.519426) (xy 214.579962 -256.530094) (xy 214.578184 -256.535682)
			(xy 214.577354 -256.539754) (xy 214.576842 -256.548049) (xy 214.577168 -256.552192) (xy 214.584788 -256.629662)
			(xy 214.585419 -256.63514) (xy 214.588753 -256.645648) (xy 214.591392 -256.65049) (xy 214.59444 -256.65557)
			(xy 214.601806 -256.663698) (xy 214.606378 -256.666746) (xy 214.627952 -256.682049) (xy 214.667037 -256.717686)
			(xy 214.700824 -256.758382) (xy 214.728664 -256.803355) (xy 214.750023 -256.851743) (xy 214.764492 -256.902619)
			(xy 214.771792 -256.955005) (xy 214.77224 -256.981452) (xy 214.7717 -257.008702) (xy 214.763951 -257.062649)
			(xy 214.748602 -257.114943) (xy 214.725968 -257.164521) (xy 214.696508 -257.210373) (xy 214.660822 -257.251565)
			(xy 214.619637 -257.28726) (xy 214.573791 -257.316729) (xy 214.524218 -257.339374) (xy 214.471927 -257.354734)
			(xy 214.417982 -257.362494) (xy 214.390732 -257.36296) (xy 214.36227 -257.36248) (xy 214.305977 -257.35402)
			(xy 214.251569 -257.337283) (xy 214.200254 -257.312642) (xy 214.153174 -257.280643) (xy 214.111376 -257.242)
			(xy 214.075789 -257.197571) (xy 214.06104 -257.173222) (xy 214.057992 -257.167888) (xy 214.049356 -257.158998)
			(xy 214.044276 -257.155696) (xy 214.040212 -257.15326) (xy 214.031387 -257.149811) (xy 214.02675 -257.148838)
			(xy 214.020908 -257.148076) (xy 213.930992 -257.141472) (xy 213.919308 -257.14325) (xy 213.91372 -257.14579)
			(xy 213.908188 -257.148359) (xy 213.898435 -257.15568) (xy 213.894416 -257.160268) (xy 213.894162 -257.160268)
			(xy 213.894162 -257.160776) (xy 213.875991 -257.182494) (xy 213.83426 -257.220772) (xy 213.787325 -257.252452)
			(xy 213.736218 -257.276837) (xy 213.682064 -257.293391) (xy 213.626058 -257.301748) (xy 213.597744 -257.302254)
			(xy 213.59749 -257.302254) (xy 213.570243 -257.301675) (xy 213.516302 -257.293918) (xy 213.464015 -257.278564)
			(xy 213.414445 -257.255925) (xy 213.368602 -257.226462) (xy 213.327418 -257.190775) (xy 213.291732 -257.14959)
			(xy 213.26227 -257.103746) (xy 213.239632 -257.054175) (xy 213.224279 -257.001888) (xy 213.216524 -256.947947)
			(xy 177.160231 -256.947947) (xy 176.800594 -258.90474) (xy 215.021922 -258.90474) (xy 215.022453 -258.877063)
			(xy 215.030453 -258.822291) (xy 215.046289 -258.769252) (xy 215.069629 -258.71906) (xy 215.099983 -258.672771)
			(xy 215.136711 -258.631359) (xy 215.157558 -258.613148) (xy 215.16467 -258.607052) (xy 215.168988 -258.599432)
			(xy 215.171274 -258.59486) (xy 215.17483 -258.582922) (xy 215.186006 -258.518406) (xy 215.186594 -258.514623)
			(xy 215.186716 -258.506967) (xy 215.18626 -258.503166) (xy 215.185752 -258.499864) (xy 215.184228 -258.491736)
			(xy 215.179656 -258.483862) (xy 215.166514 -258.460745) (xy 215.145821 -258.41176) (xy 215.131812 -258.360462)
			(xy 215.124733 -258.307758) (xy 215.124284 -258.28117) (xy 215.124793 -258.252612) (xy 215.132922 -258.196079)
			(xy 215.149013 -258.141277) (xy 215.172739 -258.089324) (xy 215.203618 -258.041275) (xy 215.241021 -257.998111)
			(xy 215.284185 -257.960708) (xy 215.332234 -257.929829) (xy 215.384187 -257.906103) (xy 215.438989 -257.890012)
			(xy 215.495522 -257.881883) (xy 215.552638 -257.881883) (xy 215.609171 -257.890012) (xy 215.663973 -257.906103)
			(xy 215.715926 -257.929829) (xy 215.763975 -257.960708) (xy 215.807139 -257.998111) (xy 215.844542 -258.041275)
			(xy 215.875421 -258.089324) (xy 215.899147 -258.141277) (xy 215.915238 -258.196079) (xy 215.923367 -258.252612)
			(xy 215.923876 -258.28117) (xy 215.923323 -258.311628) (xy 215.914067 -258.371836) (xy 215.89578 -258.429942)
			(xy 215.868885 -258.4846) (xy 215.834007 -258.534542) (xy 215.791952 -258.578612) (xy 215.768174 -258.597654)
			(xy 215.760808 -258.603242) (xy 215.756236 -258.610608) (xy 215.753981 -258.614401) (xy 215.750656 -258.622572)
			(xy 215.749632 -258.626864) (xy 215.735662 -258.69138) (xy 215.734762 -258.695831) (xy 215.734385 -258.704902)
			(xy 215.7349 -258.709414) (xy 215.73617 -258.717796) (xy 215.740488 -258.725924) (xy 215.75447 -258.753589)
			(xy 215.771077 -258.802886) (xy 218.32392 -258.802886) (xy 218.327991 -258.747264) (xy 218.340117 -258.692827)
			(xy 218.36004 -258.640736) (xy 218.387336 -258.592101) (xy 218.421422 -258.547958) (xy 218.461571 -258.509249)
			(xy 218.506929 -258.476798) (xy 218.556529 -258.451297) (xy 218.609313 -258.43329) (xy 218.664156 -258.42316)
			(xy 218.71989 -258.421123) (xy 218.775327 -258.427223) (xy 218.829284 -258.441329) (xy 218.880613 -258.463141)
			(xy 218.928219 -258.492195) (xy 218.971087 -258.52787) (xy 219.008304 -258.569407) (xy 219.039077 -258.61592)
			(xy 219.062749 -258.666417) (xy 219.078817 -258.719824) (xy 219.085135 -258.762754) (xy 219.812106 -258.762754)
			(xy 219.816177 -258.707132) (xy 219.828303 -258.652695) (xy 219.848226 -258.600604) (xy 219.875522 -258.551969)
			(xy 219.909608 -258.507826) (xy 219.949757 -258.469117) (xy 219.995115 -258.436666) (xy 220.044715 -258.411165)
			(xy 220.097499 -258.393158) (xy 220.152342 -258.383028) (xy 220.208076 -258.380991) (xy 220.263513 -258.387091)
			(xy 220.31747 -258.401197) (xy 220.368799 -258.423009) (xy 220.416405 -258.452063) (xy 220.459273 -258.487738)
			(xy 220.49649 -258.529275) (xy 220.527263 -258.575788) (xy 220.550935 -258.626285) (xy 220.567003 -258.679692)
			(xy 220.575123 -258.734868) (xy 220.575632 -258.762754) (xy 220.575123 -258.79064) (xy 220.570368 -258.822952)
			(xy 221.320612 -258.822952) (xy 221.324683 -258.76733) (xy 221.336809 -258.712893) (xy 221.356732 -258.660802)
			(xy 221.384028 -258.612167) (xy 221.418114 -258.568024) (xy 221.458263 -258.529315) (xy 221.503621 -258.496864)
			(xy 221.553221 -258.471363) (xy 221.606005 -258.453356) (xy 221.660848 -258.443226) (xy 221.716582 -258.441189)
			(xy 221.772019 -258.447289) (xy 221.825976 -258.461395) (xy 221.877305 -258.483207) (xy 221.924911 -258.512261)
			(xy 221.967779 -258.547936) (xy 222.004996 -258.589473) (xy 222.035769 -258.635986) (xy 222.059441 -258.686483)
			(xy 222.075509 -258.73989) (xy 222.078874 -258.762754) (xy 222.828864 -258.762754) (xy 222.832935 -258.707132)
			(xy 222.845061 -258.652695) (xy 222.864984 -258.600604) (xy 222.89228 -258.551969) (xy 222.926366 -258.507826)
			(xy 222.966515 -258.469117) (xy 223.011873 -258.436666) (xy 223.061473 -258.411165) (xy 223.114257 -258.393158)
			(xy 223.1691 -258.383028) (xy 223.224834 -258.380991) (xy 223.280271 -258.387091) (xy 223.334228 -258.401197)
			(xy 223.385557 -258.423009) (xy 223.433163 -258.452063) (xy 223.476031 -258.487738) (xy 223.513248 -258.529275)
			(xy 223.544021 -258.575788) (xy 223.567693 -258.626285) (xy 223.583761 -258.679692) (xy 223.591881 -258.734868)
			(xy 223.59239 -258.762754) (xy 223.591881 -258.79064) (xy 223.583761 -258.845816) (xy 223.567693 -258.899223)
			(xy 223.544021 -258.94972) (xy 223.513248 -258.996233) (xy 223.476031 -259.03777) (xy 223.433163 -259.073445)
			(xy 223.385557 -259.102499) (xy 223.334228 -259.124311) (xy 223.280271 -259.138417) (xy 223.224834 -259.144517)
			(xy 223.1691 -259.14248) (xy 223.114257 -259.13235) (xy 223.061473 -259.114343) (xy 223.011873 -259.088842)
			(xy 222.966515 -259.056391) (xy 222.926366 -259.017682) (xy 222.89228 -258.973539) (xy 222.864984 -258.924904)
			(xy 222.845061 -258.872813) (xy 222.832935 -258.818376) (xy 222.828864 -258.762754) (xy 222.078874 -258.762754)
			(xy 222.083629 -258.795066) (xy 222.084138 -258.822952) (xy 222.083629 -258.850838) (xy 222.075509 -258.906014)
			(xy 222.059441 -258.959421) (xy 222.035769 -259.009918) (xy 222.004996 -259.056431) (xy 221.967779 -259.097968)
			(xy 221.924911 -259.133643) (xy 221.877305 -259.162697) (xy 221.825976 -259.184509) (xy 221.772019 -259.198615)
			(xy 221.716582 -259.204715) (xy 221.660848 -259.202678) (xy 221.606005 -259.192548) (xy 221.553221 -259.174541)
			(xy 221.503621 -259.14904) (xy 221.458263 -259.116589) (xy 221.418114 -259.07788) (xy 221.384028 -259.033737)
			(xy 221.356732 -258.985102) (xy 221.336809 -258.933011) (xy 221.324683 -258.878574) (xy 221.320612 -258.822952)
			(xy 220.570368 -258.822952) (xy 220.567003 -258.845816) (xy 220.550935 -258.899223) (xy 220.527263 -258.94972)
			(xy 220.49649 -258.996233) (xy 220.459273 -259.03777) (xy 220.416405 -259.073445) (xy 220.368799 -259.102499)
			(xy 220.31747 -259.124311) (xy 220.263513 -259.138417) (xy 220.208076 -259.144517) (xy 220.152342 -259.14248)
			(xy 220.097499 -259.13235) (xy 220.044715 -259.114343) (xy 219.995115 -259.088842) (xy 219.949757 -259.056391)
			(xy 219.909608 -259.017682) (xy 219.875522 -258.973539) (xy 219.848226 -258.924904) (xy 219.828303 -258.872813)
			(xy 219.816177 -258.818376) (xy 219.812106 -258.762754) (xy 219.085135 -258.762754) (xy 219.086937 -258.775)
			(xy 219.087446 -258.802886) (xy 219.086937 -258.830772) (xy 219.078817 -258.885948) (xy 219.062749 -258.939355)
			(xy 219.039077 -258.989852) (xy 219.008304 -259.036365) (xy 218.971087 -259.077902) (xy 218.928219 -259.113577)
			(xy 218.880613 -259.142631) (xy 218.829284 -259.164443) (xy 218.775327 -259.178549) (xy 218.71989 -259.184649)
			(xy 218.664156 -259.182612) (xy 218.609313 -259.172482) (xy 218.556529 -259.154475) (xy 218.506929 -259.128974)
			(xy 218.461571 -259.096523) (xy 218.421422 -259.057814) (xy 218.387336 -259.013671) (xy 218.36004 -258.965036)
			(xy 218.340117 -258.912945) (xy 218.327991 -258.858508) (xy 218.32392 -258.802886) (xy 215.771077 -258.802886)
			(xy 215.774259 -258.81233) (xy 215.784311 -258.873494) (xy 215.784938 -258.904486) (xy 215.784938 -258.90474)
			(xy 215.784443 -258.931788) (xy 215.776802 -258.985342) (xy 215.761678 -259.037281) (xy 215.739375 -259.086566)
			(xy 215.710339 -259.13221) (xy 215.675151 -259.173298) (xy 215.655144 -259.191506) (xy 215.646762 -259.198872)
			(xy 215.642444 -259.208524) (xy 215.640999 -259.211811) (xy 215.638958 -259.218696) (xy 215.63838 -259.22224)
			(xy 215.637872 -259.230114) (xy 215.63825 -259.273802) (xy 219.062806 -259.273802) (xy 219.066877 -259.21818)
			(xy 219.079003 -259.163743) (xy 219.098926 -259.111652) (xy 219.126222 -259.063017) (xy 219.160308 -259.018874)
			(xy 219.200457 -258.980165) (xy 219.245815 -258.947714) (xy 219.295415 -258.922213) (xy 219.348199 -258.904206)
			(xy 219.403042 -258.894076) (xy 219.458776 -258.892039) (xy 219.514213 -258.898139) (xy 219.56817 -258.912245)
			(xy 219.619499 -258.934057) (xy 219.667105 -258.963111) (xy 219.709973 -258.998786) (xy 219.74719 -259.040323)
			(xy 219.777963 -259.086836) (xy 219.801635 -259.137333) (xy 219.817703 -259.19074) (xy 219.825823 -259.245916)
			(xy 219.826332 -259.273802) (xy 219.825823 -259.301688) (xy 219.817703 -259.356864) (xy 219.801635 -259.410271)
			(xy 219.777963 -259.460768) (xy 219.74719 -259.507281) (xy 219.709973 -259.548818) (xy 219.667105 -259.584493)
			(xy 219.619499 -259.613547) (xy 219.56817 -259.635359) (xy 219.514213 -259.649465) (xy 219.458776 -259.655565)
			(xy 219.403042 -259.653528) (xy 219.348199 -259.643398) (xy 219.295415 -259.625391) (xy 219.245815 -259.59989)
			(xy 219.200457 -259.567439) (xy 219.160308 -259.52873) (xy 219.126222 -259.484587) (xy 219.098926 -259.435952)
			(xy 219.079003 -259.383861) (xy 219.066877 -259.329424) (xy 219.062806 -259.273802) (xy 215.63825 -259.273802)
			(xy 215.638634 -259.318252) (xy 215.643206 -259.327904) (xy 215.64562 -259.332729) (xy 215.652151 -259.341313)
			(xy 215.65616 -259.344922) (xy 215.656414 -259.345176) (xy 215.677148 -259.363406) (xy 215.713683 -259.404797)
			(xy 215.743871 -259.45102) (xy 215.767084 -259.501111) (xy 215.782835 -259.554025) (xy 215.790797 -259.608656)
			(xy 215.791288 -259.63626) (xy 215.790802 -259.663511) (xy 215.783046 -259.717459) (xy 215.767691 -259.769754)
			(xy 215.745049 -259.819331) (xy 215.715583 -259.865181) (xy 215.679892 -259.906372) (xy 215.661808 -259.922041)
			(xy 218.284257 -259.922041) (xy 218.284258 -259.867535) (xy 218.292017 -259.813584) (xy 218.307375 -259.761286)
			(xy 218.33002 -259.711706) (xy 218.35949 -259.665853) (xy 218.395186 -259.624662) (xy 218.436381 -259.58897)
			(xy 218.482236 -259.559504) (xy 218.531818 -259.536863) (xy 218.584117 -259.52151) (xy 218.638069 -259.513756)
			(xy 218.692575 -259.513759) (xy 218.746526 -259.521519) (xy 218.798824 -259.536879) (xy 218.848403 -259.559525)
			(xy 218.894255 -259.588996) (xy 218.935445 -259.624693) (xy 218.971136 -259.665889) (xy 219.000601 -259.711745)
			(xy 219.02324 -259.761327) (xy 219.038592 -259.813627) (xy 219.046345 -259.867579) (xy 219.046806 -259.894832)
			(xy 219.80728 -259.894832) (xy 219.811351 -259.83921) (xy 219.823477 -259.784773) (xy 219.8434 -259.732682)
			(xy 219.870696 -259.684047) (xy 219.904782 -259.639904) (xy 219.944931 -259.601195) (xy 219.990289 -259.568744)
			(xy 220.039889 -259.543243) (xy 220.092673 -259.525236) (xy 220.147516 -259.515106) (xy 220.20325 -259.513069)
			(xy 220.258687 -259.519169) (xy 220.312644 -259.533275) (xy 220.363973 -259.555087) (xy 220.411579 -259.584141)
			(xy 220.454447 -259.619816) (xy 220.491664 -259.661353) (xy 220.522437 -259.707866) (xy 220.546109 -259.758363)
			(xy 220.562177 -259.81177) (xy 220.570297 -259.866946) (xy 220.570806 -259.894832) (xy 220.570297 -259.922718)
			(xy 220.562177 -259.977894) (xy 220.546109 -260.031301) (xy 220.522437 -260.081798) (xy 220.491664 -260.128311)
			(xy 220.454447 -260.169848) (xy 220.411579 -260.205523) (xy 220.363973 -260.234577) (xy 220.312644 -260.256389)
			(xy 220.258687 -260.270495) (xy 220.20325 -260.276595) (xy 220.147516 -260.274558) (xy 220.092673 -260.264428)
			(xy 220.039889 -260.246421) (xy 219.990289 -260.22092) (xy 219.944931 -260.188469) (xy 219.904782 -260.14976)
			(xy 219.870696 -260.105617) (xy 219.8434 -260.056982) (xy 219.823477 -260.004891) (xy 219.811351 -259.950454)
			(xy 219.80728 -259.894832) (xy 219.046806 -259.894832) (xy 219.046298 -259.91312) (xy 219.04579 -259.92709)
			(xy 219.051632 -259.938774) (xy 219.054197 -259.943495) (xy 219.060986 -259.95182) (xy 219.065094 -259.955284)
			(xy 219.06992 -259.958586) (xy 219.145104 -260.00583) (xy 219.150843 -260.009248) (xy 219.163586 -260.013239)
			(xy 219.17025 -260.013704) (xy 219.176854 -260.013958) (xy 219.189808 -260.01091) (xy 219.195904 -260.007608)
			(xy 219.223904 -259.99323) (xy 219.283452 -259.972857) (xy 219.345537 -259.962531) (xy 219.377006 -259.961888)
			(xy 219.404257 -259.962382) (xy 219.458203 -259.970139) (xy 219.510497 -259.985495) (xy 219.560073 -260.008136)
			(xy 219.605922 -260.037602) (xy 219.647111 -260.073293) (xy 219.682801 -260.114483) (xy 219.712267 -260.160333)
			(xy 219.734907 -260.209909) (xy 219.750262 -260.262203) (xy 219.758018 -260.316149) (xy 219.758018 -260.370651)
			(xy 219.750262 -260.424597) (xy 219.734907 -260.476891) (xy 219.712267 -260.526467) (xy 219.682801 -260.572317)
			(xy 219.647111 -260.613507) (xy 219.605922 -260.649198) (xy 219.560073 -260.678664) (xy 219.510497 -260.701305)
			(xy 219.458203 -260.716661) (xy 219.404257 -260.724418) (xy 219.377006 -260.724904) (xy 219.345537 -260.724274)
			(xy 219.283452 -260.713942) (xy 219.223906 -260.693558) (xy 219.195904 -260.679184) (xy 219.183712 -260.67258)
			(xy 219.169742 -260.673088) (xy 219.163015 -260.673532) (xy 219.150145 -260.677531) (xy 219.144342 -260.680962)
			(xy 219.069666 -260.728206) (xy 219.063824 -260.732524) (xy 219.060039 -260.735953) (xy 219.053767 -260.744012)
			(xy 219.051378 -260.748526) (xy 219.045282 -260.760718) (xy 219.046044 -260.774688) (xy 219.046806 -260.797548)
			(xy 219.046271 -260.824748) (xy 219.808326 -260.824748) (xy 219.808326 -260.770252) (xy 219.816082 -260.716312)
			(xy 219.831435 -260.664024) (xy 219.854073 -260.614453) (xy 219.883535 -260.568608) (xy 219.919222 -260.527423)
			(xy 219.960407 -260.491736) (xy 220.006251 -260.462274) (xy 220.055822 -260.439635) (xy 220.10811 -260.424282)
			(xy 220.16205 -260.416526) (xy 220.189298 -260.41604) (xy 220.2182 -260.416621) (xy 220.275338 -260.425377)
			(xy 220.330499 -260.44266) (xy 220.382419 -260.468072) (xy 220.406468 -260.484112) (xy 220.406976 -260.484112)
			(xy 220.416374 -260.490716) (xy 220.42755 -260.492494) (xy 220.432438 -260.493125) (xy 220.442285 -260.492747)
			(xy 220.447108 -260.491732) (xy 220.450156 -260.49097) (xy 220.52661 -260.467856) (xy 220.537786 -260.46303)
			(xy 220.542358 -260.460236) (xy 220.546168 -260.456934) (xy 220.550355 -260.45289) (xy 220.556889 -260.44326)
			(xy 220.559122 -260.437884) (xy 220.559122 -260.43763) (xy 220.569672 -260.412025) (xy 220.597175 -260.363958)
			(xy 220.63134 -260.320373) (xy 220.671447 -260.282186) (xy 220.716655 -260.2502) (xy 220.766013 -260.225087)
			(xy 220.818483 -260.207375) (xy 220.845634 -260.201918) (xy 220.857572 -260.199886) (xy 220.867478 -260.192266)
			(xy 220.873574 -260.186678) (xy 220.876304 -260.183776) (xy 220.880896 -260.177267) (xy 220.882718 -260.173724)
			(xy 220.923104 -260.088634) (xy 220.922596 -260.076442) (xy 220.922275 -260.070471) (xy 220.919194 -260.05892)
			(xy 220.9165 -260.053582) (xy 220.901907 -260.025419) (xy 220.881205 -259.965467) (xy 220.870675 -259.902922)
			(xy 220.870018 -259.87121) (xy 220.870018 -259.870956) (xy 220.870504 -259.843705) (xy 220.87826 -259.789757)
			(xy 220.893615 -259.737462) (xy 220.916257 -259.687885) (xy 220.945723 -259.642035) (xy 220.981414 -259.600844)
			(xy 221.022605 -259.565153) (xy 221.068455 -259.535687) (xy 221.118032 -259.513045) (xy 221.170327 -259.49769)
			(xy 221.224275 -259.489934) (xy 221.278777 -259.489934) (xy 221.332725 -259.49769) (xy 221.38502 -259.513045)
			(xy 221.434597 -259.535687) (xy 221.480447 -259.565153) (xy 221.521638 -259.600844) (xy 221.557329 -259.642035)
			(xy 221.586795 -259.687885) (xy 221.609437 -259.737462) (xy 221.624792 -259.789757) (xy 221.632548 -259.843705)
			(xy 221.633034 -259.870956) (xy 221.63257 -259.897484) (xy 221.629126 -259.922049) (xy 222.09431 -259.922049)
			(xy 222.09431 -259.867551) (xy 222.102066 -259.813608) (xy 222.11742 -259.761318) (xy 222.140059 -259.711745)
			(xy 222.169522 -259.665899) (xy 222.205211 -259.624712) (xy 222.246397 -259.589024) (xy 222.292243 -259.55956)
			(xy 222.341816 -259.53692) (xy 222.394106 -259.521566) (xy 222.448049 -259.51381) (xy 222.475298 -259.513324)
			(xy 222.475552 -259.513324) (xy 222.502682 -259.513848) (xy 222.556394 -259.521551) (xy 222.608474 -259.53678)
			(xy 222.657873 -259.559228) (xy 222.703597 -259.588444) (xy 222.724472 -259.60578) (xy 222.734124 -259.614162)
			(xy 222.746062 -259.616956) (xy 222.752177 -259.61818) (xy 222.764641 -259.617926) (xy 222.7707 -259.616448)
			(xy 222.85198 -259.594604) (xy 222.857897 -259.592802) (xy 222.868688 -259.586769) (xy 222.873316 -259.582666)
			(xy 222.878142 -259.578348) (xy 222.884746 -259.567934) (xy 222.886778 -259.562092) (xy 222.895716 -259.53738)
			(xy 222.919477 -259.490508) (xy 222.949448 -259.447341) (xy 222.985061 -259.408698) (xy 223.025643 -259.37531)
			(xy 223.070423 -259.347809) (xy 223.118556 -259.326717) (xy 223.169128 -259.312432) (xy 223.221182 -259.305226)
			(xy 223.247458 -259.30479) (xy 223.276335 -259.305319) (xy 223.333429 -259.314026) (xy 223.388561 -259.331233)
			(xy 223.440472 -259.356546) (xy 223.487979 -259.389389) (xy 223.529997 -259.429013) (xy 223.565569 -259.474513)
			(xy 223.593882 -259.524851) (xy 223.604582 -259.551678) (xy 223.606868 -259.55752) (xy 223.613472 -259.567426)
			(xy 223.617282 -259.571236) (xy 223.621879 -259.575236) (xy 223.632537 -259.581136) (xy 223.638364 -259.58292)
			(xy 223.729296 -259.608066) (xy 223.74098 -259.60578) (xy 223.74677 -259.604432) (xy 223.757552 -259.59943)
			(xy 223.762316 -259.595874) (xy 223.76257 -259.59562) (xy 223.782847 -259.580074) (xy 223.826799 -259.554018)
			(xy 223.873834 -259.534057) (xy 223.923112 -259.520548) (xy 223.97375 -259.513733) (xy 223.999298 -259.513324)
			(xy 224.026553 -259.513723) (xy 224.080509 -259.52148) (xy 224.127427 -259.535256) (xy 224.434045 -259.535256)
			(xy 224.434045 -259.480744) (xy 224.441803 -259.426788) (xy 224.457162 -259.374485) (xy 224.479809 -259.3249)
			(xy 224.509282 -259.279044) (xy 224.544981 -259.237849) (xy 224.586181 -259.202154) (xy 224.632041 -259.172687)
			(xy 224.681628 -259.150046) (xy 224.733933 -259.134694) (xy 224.78789 -259.126942) (xy 224.815146 -259.126482)
			(xy 224.843547 -259.127031) (xy 224.899723 -259.135445) (xy 224.95403 -259.152096) (xy 225.005267 -259.176616)
			(xy 225.052303 -259.208462) (xy 225.094096 -259.24693) (xy 225.129724 -259.291169) (xy 225.158398 -259.340203)
			(xy 225.179485 -259.392946) (xy 225.192518 -259.448233) (xy 225.195384 -259.476494) (xy 225.1964 -259.489448)
			(xy 225.203512 -259.500116) (xy 225.207042 -259.505251) (xy 225.21617 -259.513729) (xy 225.221546 -259.51688)
			(xy 225.307398 -259.56387) (xy 225.320606 -259.56387) (xy 225.326613 -259.563678) (xy 225.338293 -259.560862)
			(xy 225.34372 -259.558282) (xy 225.344482 -259.557774) (xy 225.367478 -259.54606) (xy 225.415902 -259.528215)
			(xy 225.441002 -259.522214) (xy 225.447799 -259.520509) (xy 225.460172 -259.513942) (xy 225.465386 -259.50926)
			(xy 225.470291 -259.504234) (xy 225.477387 -259.492124) (xy 225.479356 -259.485384) (xy 225.503994 -259.390896)
			(xy 225.50374 -259.37718) (xy 225.501708 -259.37083) (xy 225.499467 -259.364093) (xy 225.491858 -259.352111)
			(xy 225.486722 -259.347208) (xy 225.467038 -259.329023) (xy 225.43244 -259.288097) (xy 225.403909 -259.242734)
			(xy 225.382005 -259.193825) (xy 225.36716 -259.142332) (xy 225.359665 -259.089269) (xy 225.359214 -259.062474)
			(xy 225.3597 -259.035223) (xy 225.367456 -258.981275) (xy 225.382811 -258.92898) (xy 225.405453 -258.879403)
			(xy 225.434919 -258.833553) (xy 225.47061 -258.792362) (xy 225.511801 -258.756671) (xy 225.557651 -258.727205)
			(xy 225.607228 -258.704563) (xy 225.659523 -258.689208) (xy 225.713471 -258.681452) (xy 225.767973 -258.681452)
			(xy 225.821921 -258.689208) (xy 225.874216 -258.704563) (xy 225.923793 -258.727205) (xy 225.969643 -258.756671)
			(xy 226.010834 -258.792362) (xy 226.046525 -258.833553) (xy 226.075991 -258.879403) (xy 226.098633 -258.92898)
			(xy 226.113988 -258.981275) (xy 226.121744 -259.035223) (xy 226.12223 -259.062474) (xy 226.121754 -259.08635)
			(xy 226.47783 -259.08635) (xy 226.478316 -259.059099) (xy 226.486072 -259.005151) (xy 226.501427 -258.952856)
			(xy 226.524069 -258.903279) (xy 226.553535 -258.857429) (xy 226.589226 -258.816238) (xy 226.630417 -258.780547)
			(xy 226.676267 -258.751081) (xy 226.725844 -258.728439) (xy 226.778139 -258.713084) (xy 226.832087 -258.705328)
			(xy 226.886589 -258.705328) (xy 226.940537 -258.713084) (xy 226.992832 -258.728439) (xy 227.042409 -258.751081)
			(xy 227.088259 -258.780547) (xy 227.12945 -258.816238) (xy 227.165141 -258.857429) (xy 227.194607 -258.903279)
			(xy 227.217249 -258.952856) (xy 227.232604 -259.005151) (xy 227.240261 -259.05841) (xy 227.6381 -259.05841)
			(xy 227.642171 -259.002788) (xy 227.654297 -258.948351) (xy 227.67422 -258.89626) (xy 227.701516 -258.847625)
			(xy 227.735602 -258.803482) (xy 227.775751 -258.764773) (xy 227.821109 -258.732322) (xy 227.870709 -258.706821)
			(xy 227.923493 -258.688814) (xy 227.978336 -258.678684) (xy 228.03407 -258.676647) (xy 228.089507 -258.682747)
			(xy 228.143464 -258.696853) (xy 228.194793 -258.718665) (xy 228.242399 -258.747719) (xy 228.285267 -258.783394)
			(xy 228.322484 -258.824931) (xy 228.353257 -258.871444) (xy 228.376929 -258.921941) (xy 228.392997 -258.975348)
			(xy 228.401117 -259.030524) (xy 228.401626 -259.05841) (xy 228.401117 -259.086296) (xy 228.392997 -259.141472)
			(xy 228.376929 -259.194879) (xy 228.353257 -259.245376) (xy 228.322484 -259.291889) (xy 228.285267 -259.333426)
			(xy 228.242399 -259.369101) (xy 228.194793 -259.398155) (xy 228.143464 -259.419967) (xy 228.089507 -259.434073)
			(xy 228.03407 -259.440173) (xy 227.978336 -259.438136) (xy 227.923493 -259.428006) (xy 227.870709 -259.409999)
			(xy 227.821109 -259.384498) (xy 227.775751 -259.352047) (xy 227.735602 -259.313338) (xy 227.701516 -259.269195)
			(xy 227.67422 -259.22056) (xy 227.654297 -259.168469) (xy 227.642171 -259.114032) (xy 227.6381 -259.05841)
			(xy 227.240261 -259.05841) (xy 227.24036 -259.059099) (xy 227.240846 -259.08635) (xy 227.240446 -259.111959)
			(xy 227.233581 -259.162717) (xy 227.219995 -259.212101) (xy 227.199931 -259.259227) (xy 227.173749 -259.303249)
			(xy 227.14192 -259.343378) (xy 227.123752 -259.361432) (xy 227.113279 -259.372223) (xy 227.098618 -259.398462)
			(xy 227.092232 -259.427832) (xy 227.094676 -259.45779) (xy 227.105738 -259.485737) (xy 227.124458 -259.509252)
			(xy 227.149215 -259.526296) (xy 227.163376 -259.531358) (xy 227.188707 -259.539976) (xy 227.236898 -259.563222)
			(xy 227.281369 -259.592973) (xy 227.321249 -259.628643) (xy 227.355755 -259.669535) (xy 227.38421 -259.714845)
			(xy 227.406057 -259.763687) (xy 227.420868 -259.815101) (xy 227.428351 -259.86808) (xy 227.428806 -259.894832)
			(xy 228.18928 -259.894832) (xy 228.193351 -259.83921) (xy 228.205477 -259.784773) (xy 228.2254 -259.732682)
			(xy 228.252696 -259.684047) (xy 228.286782 -259.639904) (xy 228.326931 -259.601195) (xy 228.372289 -259.568744)
			(xy 228.421889 -259.543243) (xy 228.474673 -259.525236) (xy 228.529516 -259.515106) (xy 228.58525 -259.513069)
			(xy 228.640687 -259.519169) (xy 228.694644 -259.533275) (xy 228.745973 -259.555087) (xy 228.793579 -259.584141)
			(xy 228.836447 -259.619816) (xy 228.873664 -259.661353) (xy 228.904437 -259.707866) (xy 228.928109 -259.758363)
			(xy 228.944177 -259.81177) (xy 228.952297 -259.866946) (xy 228.952806 -259.894832) (xy 228.952297 -259.922718)
			(xy 228.944177 -259.977894) (xy 228.928109 -260.031301) (xy 228.904437 -260.081798) (xy 228.873664 -260.128311)
			(xy 228.836447 -260.169848) (xy 228.793579 -260.205523) (xy 228.745973 -260.234577) (xy 228.694644 -260.256389)
			(xy 228.640687 -260.270495) (xy 228.58525 -260.276595) (xy 228.529516 -260.274558) (xy 228.474673 -260.264428)
			(xy 228.421889 -260.246421) (xy 228.372289 -260.22092) (xy 228.326931 -260.188469) (xy 228.286782 -260.14976)
			(xy 228.252696 -260.105617) (xy 228.2254 -260.056982) (xy 228.205477 -260.004891) (xy 228.193351 -259.950454)
			(xy 228.18928 -259.894832) (xy 227.428806 -259.894832) (xy 227.42832 -259.922083) (xy 227.420564 -259.976031)
			(xy 227.405209 -260.028326) (xy 227.382567 -260.077903) (xy 227.353101 -260.123753) (xy 227.31741 -260.164944)
			(xy 227.276219 -260.200635) (xy 227.230369 -260.230101) (xy 227.180792 -260.252743) (xy 227.128497 -260.268098)
			(xy 227.074549 -260.275854) (xy 227.020047 -260.275854) (xy 226.966099 -260.268098) (xy 226.913804 -260.252743)
			(xy 226.864227 -260.230101) (xy 226.818377 -260.200635) (xy 226.777186 -260.164944) (xy 226.741495 -260.123753)
			(xy 226.712029 -260.077903) (xy 226.689387 -260.028326) (xy 226.674032 -259.976031) (xy 226.666276 -259.922083)
			(xy 226.66579 -259.894832) (xy 226.666234 -259.869224) (xy 226.673088 -259.818468) (xy 226.686665 -259.769084)
			(xy 226.706721 -259.721958) (xy 226.732895 -259.677935) (xy 226.764719 -259.637805) (xy 226.782884 -259.61975)
			(xy 226.793403 -259.608997) (xy 226.808076 -259.582749) (xy 226.814466 -259.553366) (xy 226.812018 -259.523395)
			(xy 226.800945 -259.495437) (xy 226.782207 -259.471919) (xy 226.75743 -259.454879) (xy 226.74326 -259.449824)
			(xy 226.71791 -259.44126) (xy 226.669719 -259.418004) (xy 226.625249 -259.388245) (xy 226.585372 -259.352567)
			(xy 226.550869 -259.311669) (xy 226.522416 -259.266352) (xy 226.500572 -259.217506) (xy 226.485764 -259.166087)
			(xy 226.478284 -259.113104) (xy 226.47783 -259.08635) (xy 226.121754 -259.08635) (xy 226.121658 -259.091178)
			(xy 226.113087 -259.147942) (xy 226.096104 -259.202781) (xy 226.071094 -259.254454) (xy 226.038621 -259.301795)
			(xy 225.99942 -259.343733) (xy 225.954375 -259.379322) (xy 225.904504 -259.407758) (xy 225.850935 -259.428397)
			(xy 225.823018 -259.435092) (xy 225.816222 -259.436802) (xy 225.803848 -259.443365) (xy 225.798634 -259.448046)
			(xy 225.79373 -259.453073) (xy 225.786633 -259.465182) (xy 225.784664 -259.471922) (xy 225.760026 -259.56641)
			(xy 225.76028 -259.580126) (xy 225.762312 -259.586476) (xy 225.764578 -259.593203) (xy 225.772169 -259.605191)
			(xy 225.777298 -259.610098) (xy 225.796989 -259.628276) (xy 225.831586 -259.669203) (xy 225.860115 -259.714568)
			(xy 225.882018 -259.763479) (xy 225.896862 -259.814973) (xy 225.904355 -259.868037) (xy 225.904806 -259.894832)
			(xy 225.904352 -259.922084) (xy 225.896591 -259.976033) (xy 225.881232 -260.028329) (xy 225.858587 -260.077906)
			(xy 225.829117 -260.123756) (xy 225.793422 -260.164946) (xy 225.752229 -260.200637) (xy 225.706376 -260.230103)
			(xy 225.656797 -260.252744) (xy 225.6045 -260.268098) (xy 225.55055 -260.275854) (xy 225.523298 -260.27634)
			(xy 225.494895 -260.275822) (xy 225.438714 -260.267411) (xy 225.384402 -260.250762) (xy 225.33316 -260.226242)
			(xy 225.286121 -260.194393) (xy 225.244326 -260.155921) (xy 225.208699 -260.111675) (xy 225.180027 -260.062635)
			(xy 225.158946 -260.009885) (xy 225.145921 -259.954592) (xy 225.14306 -259.926328) (xy 225.142044 -259.913374)
			(xy 225.134932 -259.902706) (xy 225.131411 -259.897564) (xy 225.122277 -259.88909) (xy 225.116898 -259.885942)
			(xy 225.031046 -259.838952) (xy 225.017838 -259.838952) (xy 225.01183 -259.839123) (xy 225.00015 -259.841953)
			(xy 224.994724 -259.84454) (xy 224.99447 -259.84454) (xy 224.993962 -259.845048) (xy 224.966301 -259.85904)
			(xy 224.907558 -259.878824) (xy 224.846392 -259.888872) (xy 224.8154 -259.889498) (xy 224.815146 -259.889498)
			(xy 224.78789 -259.889058) (xy 224.733933 -259.881306) (xy 224.681628 -259.865954) (xy 224.632041 -259.843313)
			(xy 224.586181 -259.813846) (xy 224.544981 -259.778151) (xy 224.509282 -259.736956) (xy 224.479809 -259.6911)
			(xy 224.457162 -259.641515) (xy 224.441803 -259.589212) (xy 224.434045 -259.535256) (xy 224.127427 -259.535256)
			(xy 224.132812 -259.536837) (xy 224.182396 -259.559482) (xy 224.228253 -259.588952) (xy 224.26945 -259.624649)
			(xy 224.305147 -259.665845) (xy 224.334617 -259.711702) (xy 224.357262 -259.761287) (xy 224.372619 -259.813589)
			(xy 224.380377 -259.867545) (xy 224.380377 -259.922055) (xy 224.372619 -259.976011) (xy 224.357262 -260.028313)
			(xy 224.334617 -260.077898) (xy 224.305147 -260.123755) (xy 224.26945 -260.164951) (xy 224.228253 -260.200648)
			(xy 224.182396 -260.230118) (xy 224.132812 -260.252763) (xy 224.080509 -260.26812) (xy 224.026553 -260.275877)
			(xy 223.999298 -260.27634) (xy 223.970424 -260.275743) (xy 223.913333 -260.267045) (xy 223.858204 -260.249848)
			(xy 223.806294 -260.224544) (xy 223.758788 -260.19171) (xy 223.716768 -260.152096) (xy 223.681194 -260.106605)
			(xy 223.652877 -260.056275) (xy 223.642174 -260.029452) (xy 223.639888 -260.02361) (xy 223.633284 -260.013704)
			(xy 223.629474 -260.009894) (xy 223.624863 -260.005911) (xy 223.614215 -260) (xy 223.608392 -259.99821)
			(xy 223.51746 -259.973064) (xy 223.505776 -259.97535) (xy 223.499985 -259.976696) (xy 223.489204 -259.9817)
			(xy 223.48444 -259.985256) (xy 223.484186 -259.98551) (xy 223.463883 -260.001021) (xy 223.419939 -260.027085)
			(xy 223.372911 -260.047053) (xy 223.323639 -260.06057) (xy 223.273004 -260.067393) (xy 223.247458 -260.067806)
			(xy 223.247204 -260.067806) (xy 223.220072 -260.067324) (xy 223.166358 -260.059613) (xy 223.114277 -260.044376)
			(xy 223.064878 -260.021917) (xy 223.019156 -259.992691) (xy 222.998284 -259.97535) (xy 222.988632 -259.966968)
			(xy 222.976694 -259.964174) (xy 222.970581 -259.962933) (xy 222.958115 -259.963198) (xy 222.952056 -259.964682)
			(xy 222.870776 -259.986526) (xy 222.864853 -259.988309) (xy 222.854065 -259.994355) (xy 222.84944 -259.998464)
			(xy 222.844614 -260.002782) (xy 222.83801 -260.013196) (xy 222.835978 -260.019038) (xy 222.827009 -260.043738)
			(xy 222.803249 -260.090607) (xy 222.773281 -260.133771) (xy 222.737671 -260.172413) (xy 222.697093 -260.205801)
			(xy 222.652317 -260.233303) (xy 222.60419 -260.254399) (xy 222.553622 -260.268688) (xy 222.501572 -260.275901)
			(xy 222.475298 -260.27634) (xy 222.448049 -260.27579) (xy 222.394106 -260.268034) (xy 222.341816 -260.25268)
			(xy 222.292243 -260.23004) (xy 222.246397 -260.200576) (xy 222.205211 -260.164888) (xy 222.169522 -260.123701)
			(xy 222.140059 -260.077855) (xy 222.11742 -260.028282) (xy 222.102066 -259.975992) (xy 222.09431 -259.922049)
			(xy 221.629126 -259.922049) (xy 221.625203 -259.950027) (xy 221.610633 -260.001044) (xy 221.58914 -260.049552)
			(xy 221.561137 -260.094617) (xy 221.527166 -260.135372) (xy 221.487879 -260.171031) (xy 221.444034 -260.200907)
			(xy 221.396474 -260.224425) (xy 221.346117 -260.241133) (xy 221.320106 -260.246368) (xy 221.308168 -260.2484)
			(xy 221.298262 -260.25602) (xy 221.292166 -260.261608) (xy 221.289442 -260.264515) (xy 221.284846 -260.271021)
			(xy 221.283022 -260.274562) (xy 221.242636 -260.359652) (xy 221.243144 -260.371844) (xy 221.243476 -260.377814)
			(xy 221.24655 -260.389365) (xy 221.24924 -260.394704) (xy 221.259371 -260.413967) (xy 221.27567 -260.454325)
			(xy 221.281752 -260.475222) (xy 221.283784 -260.48208) (xy 221.290134 -260.493002) (xy 221.294706 -260.497574)
			(xy 221.29949 -260.502039) (xy 221.310805 -260.5086) (xy 221.317058 -260.510528) (xy 221.401386 -260.533896)
			(xy 221.402148 -260.53415) (xy 221.40842 -260.535574) (xy 221.421276 -260.535574) (xy 221.427548 -260.53415)
			(xy 221.43359 -260.532373) (xy 221.444641 -260.526345) (xy 221.449392 -260.522212) (xy 221.449646 -260.521958)
			(xy 221.4499 -260.521704) (xy 221.450662 -260.520942) (xy 221.472045 -260.501361) (xy 221.519627 -260.468234)
			(xy 221.571678 -260.442698) (xy 221.626998 -260.425345) (xy 221.684309 -260.416575) (xy 221.713298 -260.41604)
			(xy 221.740554 -260.416407) (xy 221.794512 -260.424165) (xy 221.846817 -260.439522) (xy 221.896404 -260.462168)
			(xy 221.942263 -260.491639) (xy 221.983461 -260.527337) (xy 222.019159 -260.568535) (xy 222.048631 -260.614394)
			(xy 222.071277 -260.663981) (xy 222.086635 -260.716286) (xy 222.094393 -260.770244) (xy 222.094393 -260.797548)
			(xy 222.85528 -260.797548) (xy 222.859351 -260.741926) (xy 222.871477 -260.687489) (xy 222.8914 -260.635398)
			(xy 222.918696 -260.586763) (xy 222.952782 -260.54262) (xy 222.992931 -260.503911) (xy 223.038289 -260.47146)
			(xy 223.087889 -260.445959) (xy 223.140673 -260.427952) (xy 223.195516 -260.417822) (xy 223.25125 -260.415785)
			(xy 223.306687 -260.421885) (xy 223.360644 -260.435991) (xy 223.411973 -260.457803) (xy 223.459579 -260.486857)
			(xy 223.502447 -260.522532) (xy 223.539664 -260.564069) (xy 223.570437 -260.610582) (xy 223.594109 -260.661079)
			(xy 223.610177 -260.714486) (xy 223.618297 -260.769662) (xy 223.618806 -260.797548) (xy 224.37928 -260.797548)
			(xy 224.383351 -260.741926) (xy 224.395477 -260.687489) (xy 224.4154 -260.635398) (xy 224.442696 -260.586763)
			(xy 224.476782 -260.54262) (xy 224.516931 -260.503911) (xy 224.562289 -260.47146) (xy 224.611889 -260.445959)
			(xy 224.664673 -260.427952) (xy 224.719516 -260.417822) (xy 224.77525 -260.415785) (xy 224.830687 -260.421885)
			(xy 224.884644 -260.435991) (xy 224.935973 -260.457803) (xy 224.983579 -260.486857) (xy 225.026447 -260.522532)
			(xy 225.063664 -260.564069) (xy 225.094437 -260.610582) (xy 225.118109 -260.661079) (xy 225.134177 -260.714486)
			(xy 225.142297 -260.769662) (xy 225.142806 -260.797548) (xy 225.90328 -260.797548) (xy 225.907351 -260.741926)
			(xy 225.919477 -260.687489) (xy 225.9394 -260.635398) (xy 225.966696 -260.586763) (xy 226.000782 -260.54262)
			(xy 226.040931 -260.503911) (xy 226.086289 -260.47146) (xy 226.135889 -260.445959) (xy 226.188673 -260.427952)
			(xy 226.243516 -260.417822) (xy 226.29925 -260.415785) (xy 226.354687 -260.421885) (xy 226.408644 -260.435991)
			(xy 226.459973 -260.457803) (xy 226.507579 -260.486857) (xy 226.550447 -260.522532) (xy 226.587664 -260.564069)
			(xy 226.618437 -260.610582) (xy 226.642109 -260.661079) (xy 226.658177 -260.714486) (xy 226.666297 -260.769662)
			(xy 226.666806 -260.797548) (xy 226.666297 -260.825434) (xy 226.662065 -260.85419) (xy 227.048058 -260.85419)
			(xy 227.052129 -260.798568) (xy 227.064255 -260.744131) (xy 227.084178 -260.69204) (xy 227.111474 -260.643405)
			(xy 227.14556 -260.599262) (xy 227.185709 -260.560553) (xy 227.231067 -260.528102) (xy 227.280667 -260.502601)
			(xy 227.333451 -260.484594) (xy 227.388294 -260.474464) (xy 227.444028 -260.472427) (xy 227.499465 -260.478527)
			(xy 227.553422 -260.492633) (xy 227.604751 -260.514445) (xy 227.652357 -260.543499) (xy 227.695225 -260.579174)
			(xy 227.732442 -260.620711) (xy 227.763215 -260.667224) (xy 227.786887 -260.717721) (xy 227.802955 -260.771128)
			(xy 227.806843 -260.797548) (xy 228.18928 -260.797548) (xy 228.193351 -260.741926) (xy 228.205477 -260.687489)
			(xy 228.2254 -260.635398) (xy 228.252696 -260.586763) (xy 228.286782 -260.54262) (xy 228.326931 -260.503911)
			(xy 228.372289 -260.47146) (xy 228.421889 -260.445959) (xy 228.474673 -260.427952) (xy 228.529516 -260.417822)
			(xy 228.58525 -260.415785) (xy 228.640687 -260.421885) (xy 228.694644 -260.435991) (xy 228.745973 -260.457803)
			(xy 228.793579 -260.486857) (xy 228.836447 -260.522532) (xy 228.873664 -260.564069) (xy 228.904437 -260.610582)
			(xy 228.928109 -260.661079) (xy 228.944177 -260.714486) (xy 228.952297 -260.769662) (xy 228.952806 -260.797548)
			(xy 228.952297 -260.825434) (xy 228.944177 -260.88061) (xy 228.928109 -260.934017) (xy 228.904437 -260.984514)
			(xy 228.873664 -261.031027) (xy 228.836447 -261.072564) (xy 228.793579 -261.108239) (xy 228.745973 -261.137293)
			(xy 228.694644 -261.159105) (xy 228.640687 -261.173211) (xy 228.58525 -261.179311) (xy 228.529516 -261.177274)
			(xy 228.474673 -261.167144) (xy 228.421889 -261.149137) (xy 228.372289 -261.123636) (xy 228.326931 -261.091185)
			(xy 228.286782 -261.052476) (xy 228.252696 -261.008333) (xy 228.2254 -260.959698) (xy 228.205477 -260.907607)
			(xy 228.193351 -260.85317) (xy 228.18928 -260.797548) (xy 227.806843 -260.797548) (xy 227.811075 -260.826304)
			(xy 227.811584 -260.85419) (xy 227.811075 -260.882076) (xy 227.802955 -260.937252) (xy 227.786887 -260.990659)
			(xy 227.763215 -261.041156) (xy 227.732442 -261.087669) (xy 227.695225 -261.129206) (xy 227.652357 -261.164881)
			(xy 227.604751 -261.193935) (xy 227.553422 -261.215747) (xy 227.499465 -261.229853) (xy 227.444028 -261.235953)
			(xy 227.388294 -261.233916) (xy 227.333451 -261.223786) (xy 227.280667 -261.205779) (xy 227.231067 -261.180278)
			(xy 227.185709 -261.147827) (xy 227.14556 -261.109118) (xy 227.111474 -261.064975) (xy 227.084178 -261.01634)
			(xy 227.064255 -260.964249) (xy 227.052129 -260.909812) (xy 227.048058 -260.85419) (xy 226.662065 -260.85419)
			(xy 226.658177 -260.88061) (xy 226.642109 -260.934017) (xy 226.618437 -260.984514) (xy 226.587664 -261.031027)
			(xy 226.550447 -261.072564) (xy 226.507579 -261.108239) (xy 226.459973 -261.137293) (xy 226.408644 -261.159105)
			(xy 226.354687 -261.173211) (xy 226.29925 -261.179311) (xy 226.243516 -261.177274) (xy 226.188673 -261.167144)
			(xy 226.135889 -261.149137) (xy 226.086289 -261.123636) (xy 226.040931 -261.091185) (xy 226.000782 -261.052476)
			(xy 225.966696 -261.008333) (xy 225.9394 -260.959698) (xy 225.919477 -260.907607) (xy 225.907351 -260.85317)
			(xy 225.90328 -260.797548) (xy 225.142806 -260.797548) (xy 225.142297 -260.825434) (xy 225.134177 -260.88061)
			(xy 225.118109 -260.934017) (xy 225.094437 -260.984514) (xy 225.063664 -261.031027) (xy 225.026447 -261.072564)
			(xy 224.983579 -261.108239) (xy 224.935973 -261.137293) (xy 224.884644 -261.159105) (xy 224.830687 -261.173211)
			(xy 224.77525 -261.179311) (xy 224.719516 -261.177274) (xy 224.664673 -261.167144) (xy 224.611889 -261.149137)
			(xy 224.562289 -261.123636) (xy 224.516931 -261.091185) (xy 224.476782 -261.052476) (xy 224.442696 -261.008333)
			(xy 224.4154 -260.959698) (xy 224.395477 -260.907607) (xy 224.383351 -260.85317) (xy 224.37928 -260.797548)
			(xy 223.618806 -260.797548) (xy 223.618297 -260.825434) (xy 223.610177 -260.88061) (xy 223.594109 -260.934017)
			(xy 223.570437 -260.984514) (xy 223.539664 -261.031027) (xy 223.502447 -261.072564) (xy 223.459579 -261.108239)
			(xy 223.411973 -261.137293) (xy 223.360644 -261.159105) (xy 223.306687 -261.173211) (xy 223.25125 -261.179311)
			(xy 223.195516 -261.177274) (xy 223.140673 -261.167144) (xy 223.087889 -261.149137) (xy 223.038289 -261.123636)
			(xy 222.992931 -261.091185) (xy 222.952782 -261.052476) (xy 222.918696 -261.008333) (xy 222.8914 -260.959698)
			(xy 222.871477 -260.907607) (xy 222.859351 -260.85317) (xy 222.85528 -260.797548) (xy 222.094393 -260.797548)
			(xy 222.094393 -260.824756) (xy 222.086635 -260.878714) (xy 222.071277 -260.931019) (xy 222.048631 -260.980606)
			(xy 222.019159 -261.026465) (xy 221.983461 -261.067663) (xy 221.942263 -261.103361) (xy 221.896404 -261.132832)
			(xy 221.846817 -261.155478) (xy 221.794512 -261.170835) (xy 221.740554 -261.178593) (xy 221.713298 -261.179056)
			(xy 221.685738 -261.178577) (xy 221.631194 -261.170631) (xy 221.57836 -261.15492) (xy 221.528337 -261.13177)
			(xy 221.482166 -261.101664) (xy 221.440807 -261.065227) (xy 221.405121 -261.023218) (xy 221.375851 -260.976512)
			(xy 221.353606 -260.92608) (xy 221.34576 -260.899656) (xy 221.343728 -260.892798) (xy 221.337378 -260.881876)
			(xy 221.332806 -260.877304) (xy 221.328022 -260.87284) (xy 221.316707 -260.866278) (xy 221.310454 -260.86435)
			(xy 221.226126 -260.840982) (xy 221.225364 -260.840728) (xy 221.219092 -260.839304) (xy 221.206236 -260.839304)
			(xy 221.199964 -260.840728) (xy 221.193915 -260.842483) (xy 221.182868 -260.848527) (xy 221.17812 -260.852666)
			(xy 221.177612 -260.853174) (xy 221.156211 -260.872888) (xy 221.10851 -260.906208) (xy 221.056308 -260.93191)
			(xy 221.000812 -260.949398) (xy 220.943307 -260.958268) (xy 220.914214 -260.958838) (xy 220.88531 -260.958305)
			(xy 220.82817 -260.949534) (xy 220.773009 -260.932238) (xy 220.721091 -260.906813) (xy 220.697044 -260.890766)
			(xy 220.696536 -260.890766) (xy 220.687138 -260.884162) (xy 220.675962 -260.882384) (xy 220.671073 -260.881757)
			(xy 220.661227 -260.882132) (xy 220.656404 -260.883146) (xy 220.653356 -260.883908) (xy 220.576902 -260.907022)
			(xy 220.565726 -260.911848) (xy 220.561154 -260.914642) (xy 220.557344 -260.917944) (xy 220.553163 -260.921994)
			(xy 220.546625 -260.93162) (xy 220.54439 -260.936994) (xy 220.54439 -260.937248) (xy 220.533428 -260.963594)
			(xy 220.504841 -261.012979) (xy 220.469222 -261.057558) (xy 220.427364 -261.096339) (xy 220.3802 -261.128457)
			(xy 220.328781 -261.153198) (xy 220.274252 -261.17001) (xy 220.217829 -261.178518) (xy 220.189298 -261.179056)
			(xy 220.16205 -261.178474) (xy 220.10811 -261.170718) (xy 220.055822 -261.155365) (xy 220.006251 -261.132726)
			(xy 219.960407 -261.103264) (xy 219.919222 -261.067577) (xy 219.883535 -261.026392) (xy 219.854073 -260.980547)
			(xy 219.831435 -260.930976) (xy 219.816082 -260.878688) (xy 219.808326 -260.824748) (xy 219.046271 -260.824748)
			(xy 219.04627 -260.824795) (xy 219.038509 -260.878733) (xy 219.02315 -260.931018) (xy 219.000506 -260.980585)
			(xy 218.97104 -261.026425) (xy 218.935349 -261.067605) (xy 218.894162 -261.103287) (xy 218.848316 -261.132744)
			(xy 218.798744 -261.155377) (xy 218.746456 -261.170725) (xy 218.692516 -261.178476) (xy 218.638022 -261.178472)
			(xy 218.584083 -261.170712) (xy 218.531797 -261.155355) (xy 218.482229 -261.132714) (xy 218.436388 -261.10325)
			(xy 218.395206 -261.067561) (xy 218.359523 -261.026375) (xy 218.330064 -260.98053) (xy 218.307428 -260.930959)
			(xy 218.292078 -260.878672) (xy 218.284325 -260.824732) (xy 218.284327 -260.770238) (xy 218.292084 -260.716299)
			(xy 218.307439 -260.664013) (xy 218.330078 -260.614444) (xy 218.35954 -260.568601) (xy 218.395227 -260.527418)
			(xy 218.436412 -260.491733) (xy 218.482255 -260.462272) (xy 218.531825 -260.439634) (xy 218.584112 -260.424282)
			(xy 218.638051 -260.416526) (xy 218.665298 -260.41604) (xy 218.696767 -260.416675) (xy 218.758851 -260.427006)
			(xy 218.818397 -260.447388) (xy 218.8464 -260.46176) (xy 218.858592 -260.468364) (xy 218.872562 -260.467856)
			(xy 218.879288 -260.467407) (xy 218.892158 -260.463411) (xy 218.897962 -260.459982) (xy 218.972638 -260.412738)
			(xy 218.97848 -260.40842) (xy 218.982275 -260.405001) (xy 218.988541 -260.396936) (xy 218.990926 -260.392418)
			(xy 218.997022 -260.380226) (xy 218.99626 -260.366256) (xy 218.995498 -260.34365) (xy 218.995498 -260.343142)
			(xy 218.996006 -260.325108) (xy 218.996514 -260.311138) (xy 218.990672 -260.299454) (xy 218.988101 -260.294736)
			(xy 218.981316 -260.286409) (xy 218.97721 -260.282944) (xy 218.972384 -260.279642) (xy 218.8972 -260.232398)
			(xy 218.891459 -260.228984) (xy 218.878717 -260.224989) (xy 218.872054 -260.224524) (xy 218.86545 -260.22427)
			(xy 218.852496 -260.227318) (xy 218.8464 -260.23062) (xy 218.818397 -260.244991) (xy 218.75885 -260.265368)
			(xy 218.696766 -260.275696) (xy 218.665298 -260.27634) (xy 218.638045 -260.275842) (xy 218.584093 -260.268085)
			(xy 218.531795 -260.252728) (xy 218.482215 -260.230085) (xy 218.436361 -260.200616) (xy 218.395169 -260.164921)
			(xy 218.359476 -260.123727) (xy 218.330008 -260.077873) (xy 218.307367 -260.028292) (xy 218.292012 -259.975993)
			(xy 218.284257 -259.922041) (xy 215.661808 -259.922041) (xy 215.638701 -259.942063) (xy 215.592851 -259.971529)
			(xy 215.543274 -259.994171) (xy 215.490979 -260.009526) (xy 215.437031 -260.017282) (xy 215.382529 -260.017282)
			(xy 215.328581 -260.009526) (xy 215.276286 -259.994171) (xy 215.226709 -259.971529) (xy 215.180859 -259.942063)
			(xy 215.139668 -259.906372) (xy 215.103977 -259.865181) (xy 215.074511 -259.819331) (xy 215.051869 -259.769754)
			(xy 215.036514 -259.717459) (xy 215.028758 -259.663511) (xy 215.028272 -259.63626) (xy 215.028797 -259.609213)
			(xy 215.036436 -259.555662) (xy 215.051556 -259.503724) (xy 215.073854 -259.45444) (xy 215.102883 -259.408796)
			(xy 215.138063 -259.367705) (xy 215.158066 -259.349494) (xy 215.166448 -259.342128) (xy 215.170766 -259.332476)
			(xy 215.172212 -259.329189) (xy 215.174252 -259.322304) (xy 215.17483 -259.31876) (xy 215.175338 -259.310886)
			(xy 215.174576 -259.222748) (xy 215.170004 -259.213096) (xy 215.167589 -259.208272) (xy 215.161059 -259.199688)
			(xy 215.15705 -259.196078) (xy 215.156796 -259.195824) (xy 215.136064 -259.177591) (xy 215.099529 -259.136202)
			(xy 215.069339 -259.089979) (xy 215.046127 -259.039888) (xy 215.030375 -258.986975) (xy 215.022413 -258.932344)
			(xy 215.021922 -258.90474) (xy 176.800594 -258.90474) (xy 176.476277 -260.669351) (xy 200.037678 -260.669351)
			(xy 200.037678 -260.614849) (xy 200.045434 -260.560901) (xy 200.060789 -260.508606) (xy 200.083431 -260.459029)
			(xy 200.112897 -260.413179) (xy 200.148588 -260.371988) (xy 200.189779 -260.336297) (xy 200.235629 -260.306831)
			(xy 200.285206 -260.284189) (xy 200.337501 -260.268834) (xy 200.391449 -260.261078) (xy 200.4187 -260.260592)
			(xy 200.444345 -260.260996) (xy 200.495172 -260.267883) (xy 200.544617 -260.281519) (xy 200.591789 -260.301658)
			(xy 200.614026 -260.31444) (xy 200.622916 -260.31952) (xy 200.632822 -260.321044) (xy 200.637981 -260.321674)
			(xy 200.648353 -260.321032) (xy 200.653396 -260.319774) (xy 200.7235 -260.300978) (xy 200.728451 -260.299451)
			(xy 200.737662 -260.294713) (xy 200.741788 -260.29158) (xy 200.749662 -260.285484) (xy 200.754742 -260.27634)
			(xy 200.769319 -260.25127) (xy 200.804849 -260.205441) (xy 200.846905 -260.165516) (xy 200.894518 -260.132414)
			(xy 200.946592 -260.106899) (xy 201.001927 -260.089557) (xy 201.059249 -260.080789) (xy 201.088244 -260.080252)
			(xy 201.11549 -260.080821) (xy 201.169428 -260.088582) (xy 201.221711 -260.103939) (xy 201.271278 -260.126581)
			(xy 201.317118 -260.156045) (xy 201.358299 -260.191733) (xy 201.393982 -260.232917) (xy 201.423441 -260.278761)
			(xy 201.446076 -260.32833) (xy 201.461427 -260.380615) (xy 201.469182 -260.434554) (xy 201.469182 -260.46176)
			(xy 201.708256 -260.46176) (xy 201.712327 -260.406138) (xy 201.724453 -260.351701) (xy 201.744376 -260.29961)
			(xy 201.771672 -260.250975) (xy 201.805758 -260.206832) (xy 201.845907 -260.168123) (xy 201.891265 -260.135672)
			(xy 201.940865 -260.110171) (xy 201.993649 -260.092164) (xy 202.048492 -260.082034) (xy 202.104226 -260.079997)
			(xy 202.159663 -260.086097) (xy 202.21362 -260.100203) (xy 202.264949 -260.122015) (xy 202.312555 -260.151069)
			(xy 202.355423 -260.186744) (xy 202.39264 -260.228281) (xy 202.423413 -260.274794) (xy 202.447085 -260.325291)
			(xy 202.463153 -260.378698) (xy 202.471273 -260.433874) (xy 202.471782 -260.46176) (xy 202.724256 -260.46176)
			(xy 202.728327 -260.406138) (xy 202.740453 -260.351701) (xy 202.760376 -260.29961) (xy 202.787672 -260.250975)
			(xy 202.821758 -260.206832) (xy 202.861907 -260.168123) (xy 202.907265 -260.135672) (xy 202.956865 -260.110171)
			(xy 203.009649 -260.092164) (xy 203.064492 -260.082034) (xy 203.120226 -260.079997) (xy 203.175663 -260.086097)
			(xy 203.22962 -260.100203) (xy 203.280949 -260.122015) (xy 203.328555 -260.151069) (xy 203.371423 -260.186744)
			(xy 203.40864 -260.228281) (xy 203.439413 -260.274794) (xy 203.463085 -260.325291) (xy 203.479153 -260.378698)
			(xy 203.487273 -260.433874) (xy 203.487782 -260.46176) (xy 203.750924 -260.46176) (xy 203.754995 -260.406138)
			(xy 203.767121 -260.351701) (xy 203.787044 -260.29961) (xy 203.81434 -260.250975) (xy 203.848426 -260.206832)
			(xy 203.888575 -260.168123) (xy 203.933933 -260.135672) (xy 203.983533 -260.110171) (xy 204.036317 -260.092164)
			(xy 204.09116 -260.082034) (xy 204.146894 -260.079997) (xy 204.202331 -260.086097) (xy 204.256288 -260.100203)
			(xy 204.307617 -260.122015) (xy 204.355223 -260.151069) (xy 204.398091 -260.186744) (xy 204.435308 -260.228281)
			(xy 204.466081 -260.274794) (xy 204.489753 -260.325291) (xy 204.505821 -260.378698) (xy 204.513941 -260.433874)
			(xy 204.51445 -260.46176) (xy 204.513941 -260.489646) (xy 204.505821 -260.544822) (xy 204.489753 -260.598229)
			(xy 204.466081 -260.648726) (xy 204.435308 -260.695239) (xy 204.398091 -260.736776) (xy 204.355223 -260.772451)
			(xy 204.307617 -260.801505) (xy 204.256288 -260.823317) (xy 204.202331 -260.837423) (xy 204.146894 -260.843523)
			(xy 204.09116 -260.841486) (xy 204.036317 -260.831356) (xy 203.983533 -260.813349) (xy 203.933933 -260.787848)
			(xy 203.888575 -260.755397) (xy 203.848426 -260.716688) (xy 203.81434 -260.672545) (xy 203.787044 -260.62391)
			(xy 203.767121 -260.571819) (xy 203.754995 -260.517382) (xy 203.750924 -260.46176) (xy 203.487782 -260.46176)
			(xy 203.487273 -260.489646) (xy 203.479153 -260.544822) (xy 203.463085 -260.598229) (xy 203.439413 -260.648726)
			(xy 203.40864 -260.695239) (xy 203.371423 -260.736776) (xy 203.328555 -260.772451) (xy 203.280949 -260.801505)
			(xy 203.22962 -260.823317) (xy 203.175663 -260.837423) (xy 203.120226 -260.843523) (xy 203.064492 -260.841486)
			(xy 203.009649 -260.831356) (xy 202.956865 -260.813349) (xy 202.907265 -260.787848) (xy 202.861907 -260.755397)
			(xy 202.821758 -260.716688) (xy 202.787672 -260.672545) (xy 202.760376 -260.62391) (xy 202.740453 -260.571819)
			(xy 202.728327 -260.517382) (xy 202.724256 -260.46176) (xy 202.471782 -260.46176) (xy 202.471273 -260.489646)
			(xy 202.463153 -260.544822) (xy 202.447085 -260.598229) (xy 202.423413 -260.648726) (xy 202.39264 -260.695239)
			(xy 202.355423 -260.736776) (xy 202.312555 -260.772451) (xy 202.264949 -260.801505) (xy 202.21362 -260.823317)
			(xy 202.159663 -260.837423) (xy 202.104226 -260.843523) (xy 202.048492 -260.841486) (xy 201.993649 -260.831356)
			(xy 201.940865 -260.813349) (xy 201.891265 -260.787848) (xy 201.845907 -260.755397) (xy 201.805758 -260.716688)
			(xy 201.771672 -260.672545) (xy 201.744376 -260.62391) (xy 201.724453 -260.571819) (xy 201.712327 -260.517382)
			(xy 201.708256 -260.46176) (xy 201.469182 -260.46176) (xy 201.469182 -260.489046) (xy 201.461427 -260.542985)
			(xy 201.446076 -260.59527) (xy 201.423441 -260.644839) (xy 201.393982 -260.690683) (xy 201.358299 -260.731867)
			(xy 201.317118 -260.767555) (xy 201.271278 -260.797019) (xy 201.221711 -260.819661) (xy 201.169428 -260.835018)
			(xy 201.11549 -260.842779) (xy 201.088244 -260.843268) (xy 201.062599 -260.84285) (xy 201.011773 -260.835968)
			(xy 200.962327 -260.822336) (xy 200.915155 -260.8022) (xy 200.892918 -260.78942) (xy 200.884028 -260.78434)
			(xy 200.874122 -260.782816) (xy 200.868962 -260.782197) (xy 200.858591 -260.782831) (xy 200.853548 -260.784086)
			(xy 200.783444 -260.802882) (xy 200.778499 -260.804425) (xy 200.769284 -260.809152) (xy 200.765156 -260.81228)
			(xy 200.757282 -260.818376) (xy 200.752202 -260.82752) (xy 200.737649 -260.852605) (xy 200.702117 -260.898437)
			(xy 200.660058 -260.938363) (xy 200.612441 -260.971464) (xy 200.560362 -260.996976) (xy 200.505022 -261.014313)
			(xy 200.447696 -261.023075) (xy 200.4187 -261.023608) (xy 200.391449 -261.023122) (xy 200.337501 -261.015366)
			(xy 200.285206 -261.000011) (xy 200.235629 -260.977369) (xy 200.189779 -260.947903) (xy 200.148588 -260.912212)
			(xy 200.112897 -260.871021) (xy 200.083431 -260.825171) (xy 200.060789 -260.775594) (xy 200.045434 -260.723299)
			(xy 200.037678 -260.669351) (xy 176.476277 -260.669351) (xy 175.464216 -266.175998) (xy 175.4632 -266.185142)
			(xy 175.4632 -270.89989) (xy 200.998589 -270.89989) (xy 201.002595 -270.704835) (xy 201.014605 -270.510109)
			(xy 201.0346 -270.31604) (xy 201.062545 -270.122956) (xy 201.098394 -269.931181) (xy 201.142086 -269.741041)
			(xy 201.193547 -269.552854) (xy 201.252691 -269.366939) (xy 201.319418 -269.183608) (xy 201.393615 -269.003172)
			(xy 201.475157 -268.825934) (xy 201.563908 -268.652193) (xy 201.659716 -268.482242) (xy 201.762421 -268.316368)
			(xy 201.871849 -268.15485) (xy 201.987816 -267.997961) (xy 202.110127 -267.845966) (xy 202.238574 -267.69912)
			(xy 202.372942 -267.557671) (xy 202.513004 -267.421858) (xy 202.658523 -267.291909) (xy 202.809255 -267.168045)
			(xy 202.964945 -267.050473) (xy 203.125331 -266.939393) (xy 203.290142 -266.83499) (xy 203.4591 -266.737442)
			(xy 203.631921 -266.646913) (xy 203.808313 -266.563555) (xy 203.987978 -266.487509) (xy 204.170613 -266.418904)
			(xy 204.355912 -266.357854) (xy 204.54356 -266.304464) (xy 204.733242 -266.258822) (xy 204.924639 -266.221006)
			(xy 205.117426 -266.19108) (xy 205.311279 -266.169094) (xy 205.505872 -266.155085) (xy 205.700875 -266.149077)
			(xy 205.895961 -266.15108) (xy 206.0908 -266.161091) (xy 206.285064 -266.179092) (xy 206.478425 -266.205054)
			(xy 206.670558 -266.238932) (xy 206.861137 -266.280669) (xy 207.049842 -266.330196) (xy 207.236355 -266.387428)
			(xy 207.420361 -266.452269) (xy 207.601549 -266.52461) (xy 207.779615 -266.604328) (xy 207.954258 -266.69129)
			(xy 208.125184 -266.785349) (xy 208.292103 -266.886345) (xy 208.454736 -266.99411) (xy 208.612807 -267.10846)
			(xy 208.76605 -267.229203) (xy 208.914207 -267.356137) (xy 209.057028 -267.489045) (xy 209.194272 -267.627705)
			(xy 209.325708 -267.771883) (xy 209.451113 -267.921336) (xy 209.570277 -268.07581) (xy 209.682998 -268.235047)
			(xy 209.789087 -268.398778) (xy 209.888365 -268.566725) (xy 209.980663 -268.738608) (xy 210.065828 -268.914134)
			(xy 210.143714 -269.093009) (xy 210.214191 -269.274931) (xy 210.277139 -269.459593) (xy 210.332454 -269.646683)
			(xy 210.38004 -269.835887) (xy 210.419819 -270.026884) (xy 210.451723 -270.219354) (xy 210.475698 -270.412972)
			(xy 210.491704 -270.60741) (xy 210.499713 -270.802342) (xy 210.500214 -270.89989) (xy 210.499713 -270.997438)
			(xy 210.491704 -271.19237) (xy 210.475698 -271.386808) (xy 210.451723 -271.580426) (xy 210.419819 -271.772896)
			(xy 210.38004 -271.963893) (xy 210.332454 -272.153097) (xy 210.277139 -272.340187) (xy 210.214191 -272.524849)
			(xy 210.143714 -272.706771) (xy 210.065828 -272.885646) (xy 209.980663 -273.061172) (xy 209.888365 -273.233055)
			(xy 209.789087 -273.401002) (xy 209.682998 -273.564733) (xy 209.570277 -273.72397) (xy 209.49414 -273.822668)
			(xy 227.662992 -273.822668) (xy 227.667063 -273.767046) (xy 227.679189 -273.712609) (xy 227.699112 -273.660518)
			(xy 227.726408 -273.611883) (xy 227.760494 -273.56774) (xy 227.800643 -273.529031) (xy 227.846001 -273.49658)
			(xy 227.895601 -273.471079) (xy 227.948385 -273.453072) (xy 228.003228 -273.442942) (xy 228.058962 -273.440905)
			(xy 228.114399 -273.447005) (xy 228.168356 -273.461111) (xy 228.219685 -273.482923) (xy 228.267291 -273.511977)
			(xy 228.310159 -273.547652) (xy 228.347376 -273.589189) (xy 228.378149 -273.635702) (xy 228.401821 -273.686199)
			(xy 228.417889 -273.739606) (xy 228.426009 -273.794782) (xy 228.426518 -273.822668) (xy 228.426393 -273.829526)
			(xy 228.564946 -273.829526) (xy 228.569017 -273.773904) (xy 228.581143 -273.719467) (xy 228.601066 -273.667376)
			(xy 228.628362 -273.618741) (xy 228.662448 -273.574598) (xy 228.702597 -273.535889) (xy 228.747955 -273.503438)
			(xy 228.797555 -273.477937) (xy 228.850339 -273.45993) (xy 228.905182 -273.4498) (xy 228.960916 -273.447763)
			(xy 229.016353 -273.453863) (xy 229.07031 -273.467969) (xy 229.121639 -273.489781) (xy 229.169245 -273.518835)
			(xy 229.212113 -273.55451) (xy 229.24933 -273.596047) (xy 229.280103 -273.64256) (xy 229.303775 -273.693057)
			(xy 229.319843 -273.746464) (xy 229.327963 -273.80164) (xy 229.328472 -273.829526) (xy 229.327963 -273.857412)
			(xy 229.319843 -273.912588) (xy 229.303775 -273.965995) (xy 229.280103 -274.016492) (xy 229.24933 -274.063005)
			(xy 229.212113 -274.104542) (xy 229.169245 -274.140217) (xy 229.121639 -274.169271) (xy 229.07031 -274.191083)
			(xy 229.016353 -274.205189) (xy 228.960916 -274.211289) (xy 228.905182 -274.209252) (xy 228.850339 -274.199122)
			(xy 228.797555 -274.181115) (xy 228.747955 -274.155614) (xy 228.702597 -274.123163) (xy 228.662448 -274.084454)
			(xy 228.628362 -274.040311) (xy 228.601066 -273.991676) (xy 228.581143 -273.939585) (xy 228.569017 -273.885148)
			(xy 228.564946 -273.829526) (xy 228.426393 -273.829526) (xy 228.426009 -273.850554) (xy 228.417889 -273.90573)
			(xy 228.401821 -273.959137) (xy 228.378149 -274.009634) (xy 228.347376 -274.056147) (xy 228.310159 -274.097684)
			(xy 228.267291 -274.133359) (xy 228.219685 -274.162413) (xy 228.168356 -274.184225) (xy 228.114399 -274.198331)
			(xy 228.058962 -274.204431) (xy 228.003228 -274.202394) (xy 227.948385 -274.192264) (xy 227.895601 -274.174257)
			(xy 227.846001 -274.148756) (xy 227.800643 -274.116305) (xy 227.760494 -274.077596) (xy 227.726408 -274.033453)
			(xy 227.699112 -273.984818) (xy 227.679189 -273.932727) (xy 227.667063 -273.87829) (xy 227.662992 -273.822668)
			(xy 209.49414 -273.822668) (xy 209.451113 -273.878444) (xy 209.325708 -274.027897) (xy 209.194272 -274.172075)
			(xy 209.057028 -274.310735) (xy 208.914207 -274.443643) (xy 208.76605 -274.570577) (xy 208.687239 -274.632674)
			(xy 226.694998 -274.632674) (xy 226.699069 -274.577052) (xy 226.711195 -274.522615) (xy 226.731118 -274.470524)
			(xy 226.758414 -274.421889) (xy 226.7925 -274.377746) (xy 226.832649 -274.339037) (xy 226.878007 -274.306586)
			(xy 226.927607 -274.281085) (xy 226.980391 -274.263078) (xy 227.035234 -274.252948) (xy 227.090968 -274.250911)
			(xy 227.146405 -274.257011) (xy 227.200362 -274.271117) (xy 227.251691 -274.292929) (xy 227.299297 -274.321983)
			(xy 227.342165 -274.357658) (xy 227.379382 -274.399195) (xy 227.410155 -274.445708) (xy 227.433827 -274.496205)
			(xy 227.449895 -274.549612) (xy 227.458015 -274.604788) (xy 227.458524 -274.632674) (xy 227.458015 -274.66056)
			(xy 227.449895 -274.715736) (xy 227.434154 -274.768056) (xy 228.824788 -274.768056) (xy 228.828859 -274.712434)
			(xy 228.840985 -274.657997) (xy 228.860908 -274.605906) (xy 228.888204 -274.557271) (xy 228.92229 -274.513128)
			(xy 228.962439 -274.474419) (xy 229.007797 -274.441968) (xy 229.057397 -274.416467) (xy 229.110181 -274.39846)
			(xy 229.165024 -274.38833) (xy 229.220758 -274.386293) (xy 229.276195 -274.392393) (xy 229.330152 -274.406499)
			(xy 229.381481 -274.428311) (xy 229.429087 -274.457365) (xy 229.471955 -274.49304) (xy 229.509172 -274.534577)
			(xy 229.539945 -274.58109) (xy 229.563617 -274.631587) (xy 229.579685 -274.684994) (xy 229.587805 -274.74017)
			(xy 229.588314 -274.768056) (xy 229.587805 -274.795942) (xy 229.579685 -274.851118) (xy 229.563617 -274.904525)
			(xy 229.539945 -274.955022) (xy 229.509172 -275.001535) (xy 229.471955 -275.043072) (xy 229.429087 -275.078747)
			(xy 229.381481 -275.107801) (xy 229.330152 -275.129613) (xy 229.276195 -275.143719) (xy 229.220758 -275.149819)
			(xy 229.165024 -275.147782) (xy 229.110181 -275.137652) (xy 229.057397 -275.119645) (xy 229.007797 -275.094144)
			(xy 228.962439 -275.061693) (xy 228.92229 -275.022984) (xy 228.888204 -274.978841) (xy 228.860908 -274.930206)
			(xy 228.840985 -274.878115) (xy 228.828859 -274.823678) (xy 228.824788 -274.768056) (xy 227.434154 -274.768056)
			(xy 227.433827 -274.769143) (xy 227.410155 -274.81964) (xy 227.379382 -274.866153) (xy 227.342165 -274.90769)
			(xy 227.299297 -274.943365) (xy 227.251691 -274.972419) (xy 227.200362 -274.994231) (xy 227.146405 -275.008337)
			(xy 227.090968 -275.014437) (xy 227.035234 -275.0124) (xy 226.980391 -275.00227) (xy 226.927607 -274.984263)
			(xy 226.878007 -274.958762) (xy 226.832649 -274.926311) (xy 226.7925 -274.887602) (xy 226.758414 -274.843459)
			(xy 226.731118 -274.794824) (xy 226.711195 -274.742733) (xy 226.699069 -274.688296) (xy 226.694998 -274.632674)
			(xy 208.687239 -274.632674) (xy 208.612807 -274.69132) (xy 208.454736 -274.80567) (xy 208.292103 -274.913435)
			(xy 208.125184 -275.014431) (xy 207.954258 -275.10849) (xy 207.779615 -275.195452) (xy 207.601549 -275.27517)
			(xy 207.420361 -275.347511) (xy 207.236355 -275.412352) (xy 207.049842 -275.469584) (xy 206.861137 -275.519111)
			(xy 206.670558 -275.560848) (xy 206.478425 -275.594726) (xy 206.285064 -275.620688) (xy 206.0908 -275.638689)
			(xy 205.895961 -275.6487) (xy 205.700875 -275.650703) (xy 205.505872 -275.644695) (xy 205.311279 -275.630686)
			(xy 205.117426 -275.6087) (xy 204.924639 -275.578774) (xy 204.733242 -275.540958) (xy 204.54356 -275.495316)
			(xy 204.355912 -275.441926) (xy 204.170613 -275.380876) (xy 203.987978 -275.312271) (xy 203.808313 -275.236225)
			(xy 203.631921 -275.152867) (xy 203.4591 -275.062338) (xy 203.290142 -274.96479) (xy 203.125331 -274.860387)
			(xy 202.964945 -274.749307) (xy 202.809255 -274.631735) (xy 202.658523 -274.507871) (xy 202.513004 -274.377922)
			(xy 202.372942 -274.242109) (xy 202.238574 -274.10066) (xy 202.110127 -273.953814) (xy 201.987816 -273.801819)
			(xy 201.871849 -273.64493) (xy 201.762421 -273.483412) (xy 201.659716 -273.317538) (xy 201.563908 -273.147587)
			(xy 201.475157 -272.973846) (xy 201.393615 -272.796608) (xy 201.319418 -272.616172) (xy 201.252691 -272.432841)
			(xy 201.193547 -272.246926) (xy 201.142086 -272.058739) (xy 201.098394 -271.868599) (xy 201.062545 -271.676824)
			(xy 201.0346 -271.48374) (xy 201.014605 -271.289671) (xy 201.002595 -271.094945) (xy 200.998589 -270.89989)
			(xy 175.4632 -270.89989) (xy 175.4632 -271.399762) (xy 175.462974 -271.428914) (xy 175.459544 -271.487117)
			(xy 175.456342 -271.516094) (xy 175.456088 -271.518888) (xy 175.456088 -271.790668) (xy 175.456432 -271.799401)
			(xy 175.462304 -271.81585) (xy 175.4734 -271.829337) (xy 175.480726 -271.834102) (xy 175.555148 -271.878806)
			(xy 175.565308 -271.883632) (xy 175.569012 -271.884791) (xy 175.576668 -271.886063) (xy 175.580548 -271.886172)
			(xy 175.593756 -271.886426) (xy 175.605694 -271.880076) (xy 175.627987 -271.868731) (xy 175.675353 -271.85266)
			(xy 175.724703 -271.844516) (xy 175.749712 -271.844008) (xy 175.774965 -271.84453) (xy 175.824783 -271.852845)
			(xy 175.872553 -271.869246) (xy 175.916971 -271.893286) (xy 175.956828 -271.924309) (xy 175.991034 -271.961469)
			(xy 176.018658 -272.003751) (xy 176.038946 -272.050004) (xy 176.051344 -272.098966) (xy 176.055515 -272.1493)
			(xy 176.055493 -272.14957) (xy 177.343828 -272.14957) (xy 177.347788 -272.100516) (xy 177.359565 -272.052732)
			(xy 177.378856 -272.007456) (xy 177.405159 -271.96586) (xy 177.437794 -271.929023) (xy 177.475915 -271.897898)
			(xy 177.518536 -271.873291) (xy 177.564552 -271.855839) (xy 177.612771 -271.845995) (xy 177.661946 -271.844014)
			(xy 177.710801 -271.849946) (xy 177.758072 -271.863638) (xy 177.802534 -271.884736) (xy 177.843037 -271.912692)
			(xy 177.87853 -271.946784) (xy 177.908095 -271.986128) (xy 177.930966 -272.029705) (xy 177.94655 -272.076386)
			(xy 177.954445 -272.124963) (xy 177.95494 -272.14957) (xy 179.244002 -272.14957) (xy 179.247962 -272.100516)
			(xy 179.259739 -272.052732) (xy 179.27903 -272.007456) (xy 179.305333 -271.96586) (xy 179.337968 -271.929023)
			(xy 179.376089 -271.897898) (xy 179.41871 -271.873291) (xy 179.464726 -271.855839) (xy 179.512945 -271.845995)
			(xy 179.56212 -271.844014) (xy 179.610975 -271.849946) (xy 179.658246 -271.863638) (xy 179.702708 -271.884736)
			(xy 179.743211 -271.912692) (xy 179.778704 -271.946784) (xy 179.808269 -271.986128) (xy 179.83114 -272.029705)
			(xy 179.846724 -272.076386) (xy 179.854619 -272.124963) (xy 179.855114 -272.14957) (xy 181.143922 -272.14957)
			(xy 181.147882 -272.100516) (xy 181.159659 -272.052732) (xy 181.17895 -272.007456) (xy 181.205253 -271.96586)
			(xy 181.237888 -271.929023) (xy 181.276009 -271.897898) (xy 181.31863 -271.873291) (xy 181.364646 -271.855839)
			(xy 181.412865 -271.845995) (xy 181.46204 -271.844014) (xy 181.510895 -271.849946) (xy 181.558166 -271.863638)
			(xy 181.602628 -271.884736) (xy 181.643131 -271.912692) (xy 181.678624 -271.946784) (xy 181.708189 -271.986128)
			(xy 181.73106 -272.029705) (xy 181.746644 -272.076386) (xy 181.754539 -272.124963) (xy 181.755034 -272.14957)
			(xy 183.043842 -272.14957) (xy 183.047802 -272.100516) (xy 183.059579 -272.052732) (xy 183.07887 -272.007456)
			(xy 183.105173 -271.96586) (xy 183.137808 -271.929023) (xy 183.175929 -271.897898) (xy 183.21855 -271.873291)
			(xy 183.264566 -271.855839) (xy 183.312785 -271.845995) (xy 183.36196 -271.844014) (xy 183.410815 -271.849946)
			(xy 183.458086 -271.863638) (xy 183.502548 -271.884736) (xy 183.543051 -271.912692) (xy 183.578544 -271.946784)
			(xy 183.608109 -271.986128) (xy 183.63098 -272.029705) (xy 183.646564 -272.076386) (xy 183.654459 -272.124963)
			(xy 183.654954 -272.14957) (xy 184.944016 -272.14957) (xy 184.947976 -272.100516) (xy 184.959753 -272.052732)
			(xy 184.979044 -272.007456) (xy 185.005347 -271.96586) (xy 185.037982 -271.929023) (xy 185.076103 -271.897898)
			(xy 185.118724 -271.873291) (xy 185.16474 -271.855839) (xy 185.212959 -271.845995) (xy 185.262134 -271.844014)
			(xy 185.310989 -271.849946) (xy 185.35826 -271.863638) (xy 185.402722 -271.884736) (xy 185.443225 -271.912692)
			(xy 185.478718 -271.946784) (xy 185.508283 -271.986128) (xy 185.531154 -272.029705) (xy 185.546738 -272.076386)
			(xy 185.554633 -272.124963) (xy 185.555128 -272.14957) (xy 186.843936 -272.14957) (xy 186.847896 -272.100516)
			(xy 186.859673 -272.052732) (xy 186.878964 -272.007456) (xy 186.905267 -271.96586) (xy 186.937902 -271.929023)
			(xy 186.976023 -271.897898) (xy 187.018644 -271.873291) (xy 187.06466 -271.855839) (xy 187.112879 -271.845995)
			(xy 187.162054 -271.844014) (xy 187.210909 -271.849946) (xy 187.25818 -271.863638) (xy 187.302642 -271.884736)
			(xy 187.343145 -271.912692) (xy 187.378638 -271.946784) (xy 187.408203 -271.986128) (xy 187.431074 -272.029705)
			(xy 187.446658 -272.076386) (xy 187.454553 -272.124963) (xy 187.455048 -272.14957) (xy 188.743856 -272.14957)
			(xy 188.747816 -272.100516) (xy 188.759593 -272.052732) (xy 188.778884 -272.007456) (xy 188.805187 -271.96586)
			(xy 188.837822 -271.929023) (xy 188.875943 -271.897898) (xy 188.918564 -271.873291) (xy 188.96458 -271.855839)
			(xy 189.012799 -271.845995) (xy 189.061974 -271.844014) (xy 189.110829 -271.849946) (xy 189.1581 -271.863638)
			(xy 189.202562 -271.884736) (xy 189.243065 -271.912692) (xy 189.278558 -271.946784) (xy 189.308123 -271.986128)
			(xy 189.330994 -272.029705) (xy 189.346578 -272.076386) (xy 189.354473 -272.124963) (xy 189.354968 -272.14957)
			(xy 190.64403 -272.14957) (xy 190.64799 -272.100516) (xy 190.659767 -272.052732) (xy 190.679058 -272.007456)
			(xy 190.705361 -271.96586) (xy 190.737996 -271.929023) (xy 190.776117 -271.897898) (xy 190.818738 -271.873291)
			(xy 190.864754 -271.855839) (xy 190.912973 -271.845995) (xy 190.962148 -271.844014) (xy 191.011003 -271.849946)
			(xy 191.058274 -271.863638) (xy 191.102736 -271.884736) (xy 191.143239 -271.912692) (xy 191.178732 -271.946784)
			(xy 191.208297 -271.986128) (xy 191.231168 -272.029705) (xy 191.246752 -272.076386) (xy 191.254647 -272.124963)
			(xy 191.255142 -272.14957) (xy 192.544204 -272.14957) (xy 192.548164 -272.100516) (xy 192.559941 -272.052732)
			(xy 192.579232 -272.007456) (xy 192.605535 -271.96586) (xy 192.63817 -271.929023) (xy 192.676291 -271.897898)
			(xy 192.718912 -271.873291) (xy 192.764928 -271.855839) (xy 192.813147 -271.845995) (xy 192.862322 -271.844014)
			(xy 192.911177 -271.849946) (xy 192.958448 -271.863638) (xy 193.00291 -271.884736) (xy 193.043413 -271.912692)
			(xy 193.078906 -271.946784) (xy 193.108471 -271.986128) (xy 193.131342 -272.029705) (xy 193.146926 -272.076386)
			(xy 193.154821 -272.124963) (xy 193.155316 -272.14957) (xy 194.444124 -272.14957) (xy 194.448084 -272.100516)
			(xy 194.459861 -272.052732) (xy 194.479152 -272.007456) (xy 194.505455 -271.96586) (xy 194.53809 -271.929023)
			(xy 194.576211 -271.897898) (xy 194.618832 -271.873291) (xy 194.664848 -271.855839) (xy 194.713067 -271.845995)
			(xy 194.762242 -271.844014) (xy 194.811097 -271.849946) (xy 194.858368 -271.863638) (xy 194.90283 -271.884736)
			(xy 194.943333 -271.912692) (xy 194.978826 -271.946784) (xy 195.008391 -271.986128) (xy 195.031262 -272.029705)
			(xy 195.046846 -272.076386) (xy 195.054741 -272.124963) (xy 195.055236 -272.14957) (xy 196.344044 -272.14957)
			(xy 196.348004 -272.100516) (xy 196.359781 -272.052732) (xy 196.379072 -272.007456) (xy 196.405375 -271.96586)
			(xy 196.43801 -271.929023) (xy 196.476131 -271.897898) (xy 196.518752 -271.873291) (xy 196.564768 -271.855839)
			(xy 196.612987 -271.845995) (xy 196.662162 -271.844014) (xy 196.711017 -271.849946) (xy 196.758288 -271.863638)
			(xy 196.80275 -271.884736) (xy 196.843253 -271.912692) (xy 196.878746 -271.946784) (xy 196.908311 -271.986128)
			(xy 196.931182 -272.029705) (xy 196.946766 -272.076386) (xy 196.954661 -272.124963) (xy 196.955156 -272.14957)
			(xy 196.954661 -272.174177) (xy 196.946766 -272.222754) (xy 196.931182 -272.269435) (xy 196.908311 -272.313012)
			(xy 196.878746 -272.352356) (xy 196.843253 -272.386448) (xy 196.80275 -272.414404) (xy 196.758288 -272.435502)
			(xy 196.711017 -272.449194) (xy 196.662162 -272.455126) (xy 196.612987 -272.453145) (xy 196.564768 -272.443301)
			(xy 196.518752 -272.425849) (xy 196.476131 -272.401242) (xy 196.43801 -272.370117) (xy 196.405375 -272.33328)
			(xy 196.379072 -272.291684) (xy 196.359781 -272.246408) (xy 196.348004 -272.198624) (xy 196.344044 -272.14957)
			(xy 195.055236 -272.14957) (xy 195.054741 -272.174177) (xy 195.046846 -272.222754) (xy 195.031262 -272.269435)
			(xy 195.008391 -272.313012) (xy 194.978826 -272.352356) (xy 194.943333 -272.386448) (xy 194.90283 -272.414404)
			(xy 194.858368 -272.435502) (xy 194.811097 -272.449194) (xy 194.762242 -272.455126) (xy 194.713067 -272.453145)
			(xy 194.664848 -272.443301) (xy 194.618832 -272.425849) (xy 194.576211 -272.401242) (xy 194.53809 -272.370117)
			(xy 194.505455 -272.33328) (xy 194.479152 -272.291684) (xy 194.459861 -272.246408) (xy 194.448084 -272.198624)
			(xy 194.444124 -272.14957) (xy 193.155316 -272.14957) (xy 193.154821 -272.174177) (xy 193.146926 -272.222754)
			(xy 193.131342 -272.269435) (xy 193.108471 -272.313012) (xy 193.078906 -272.352356) (xy 193.043413 -272.386448)
			(xy 193.00291 -272.414404) (xy 192.958448 -272.435502) (xy 192.911177 -272.449194) (xy 192.862322 -272.455126)
			(xy 192.813147 -272.453145) (xy 192.764928 -272.443301) (xy 192.718912 -272.425849) (xy 192.676291 -272.401242)
			(xy 192.63817 -272.370117) (xy 192.605535 -272.33328) (xy 192.579232 -272.291684) (xy 192.559941 -272.246408)
			(xy 192.548164 -272.198624) (xy 192.544204 -272.14957) (xy 191.255142 -272.14957) (xy 191.254647 -272.174177)
			(xy 191.246752 -272.222754) (xy 191.231168 -272.269435) (xy 191.208297 -272.313012) (xy 191.178732 -272.352356)
			(xy 191.143239 -272.386448) (xy 191.102736 -272.414404) (xy 191.058274 -272.435502) (xy 191.011003 -272.449194)
			(xy 190.962148 -272.455126) (xy 190.912973 -272.453145) (xy 190.864754 -272.443301) (xy 190.818738 -272.425849)
			(xy 190.776117 -272.401242) (xy 190.737996 -272.370117) (xy 190.705361 -272.33328) (xy 190.679058 -272.291684)
			(xy 190.659767 -272.246408) (xy 190.64799 -272.198624) (xy 190.64403 -272.14957) (xy 189.354968 -272.14957)
			(xy 189.354473 -272.174177) (xy 189.346578 -272.222754) (xy 189.330994 -272.269435) (xy 189.308123 -272.313012)
			(xy 189.278558 -272.352356) (xy 189.243065 -272.386448) (xy 189.202562 -272.414404) (xy 189.1581 -272.435502)
			(xy 189.110829 -272.449194) (xy 189.061974 -272.455126) (xy 189.012799 -272.453145) (xy 188.96458 -272.443301)
			(xy 188.918564 -272.425849) (xy 188.875943 -272.401242) (xy 188.837822 -272.370117) (xy 188.805187 -272.33328)
			(xy 188.778884 -272.291684) (xy 188.759593 -272.246408) (xy 188.747816 -272.198624) (xy 188.743856 -272.14957)
			(xy 187.455048 -272.14957) (xy 187.454553 -272.174177) (xy 187.446658 -272.222754) (xy 187.431074 -272.269435)
			(xy 187.408203 -272.313012) (xy 187.378638 -272.352356) (xy 187.343145 -272.386448) (xy 187.302642 -272.414404)
			(xy 187.25818 -272.435502) (xy 187.210909 -272.449194) (xy 187.162054 -272.455126) (xy 187.112879 -272.453145)
			(xy 187.06466 -272.443301) (xy 187.018644 -272.425849) (xy 186.976023 -272.401242) (xy 186.937902 -272.370117)
			(xy 186.905267 -272.33328) (xy 186.878964 -272.291684) (xy 186.859673 -272.246408) (xy 186.847896 -272.198624)
			(xy 186.843936 -272.14957) (xy 185.555128 -272.14957) (xy 185.554633 -272.174177) (xy 185.546738 -272.222754)
			(xy 185.531154 -272.269435) (xy 185.508283 -272.313012) (xy 185.478718 -272.352356) (xy 185.443225 -272.386448)
			(xy 185.402722 -272.414404) (xy 185.35826 -272.435502) (xy 185.310989 -272.449194) (xy 185.262134 -272.455126)
			(xy 185.212959 -272.453145) (xy 185.16474 -272.443301) (xy 185.118724 -272.425849) (xy 185.076103 -272.401242)
			(xy 185.037982 -272.370117) (xy 185.005347 -272.33328) (xy 184.979044 -272.291684) (xy 184.959753 -272.246408)
			(xy 184.947976 -272.198624) (xy 184.944016 -272.14957) (xy 183.654954 -272.14957) (xy 183.654459 -272.174177)
			(xy 183.646564 -272.222754) (xy 183.63098 -272.269435) (xy 183.608109 -272.313012) (xy 183.578544 -272.352356)
			(xy 183.543051 -272.386448) (xy 183.502548 -272.414404) (xy 183.458086 -272.435502) (xy 183.410815 -272.449194)
			(xy 183.36196 -272.455126) (xy 183.312785 -272.453145) (xy 183.264566 -272.443301) (xy 183.21855 -272.425849)
			(xy 183.175929 -272.401242) (xy 183.137808 -272.370117) (xy 183.105173 -272.33328) (xy 183.07887 -272.291684)
			(xy 183.059579 -272.246408) (xy 183.047802 -272.198624) (xy 183.043842 -272.14957) (xy 181.755034 -272.14957)
			(xy 181.754539 -272.174177) (xy 181.746644 -272.222754) (xy 181.73106 -272.269435) (xy 181.708189 -272.313012)
			(xy 181.678624 -272.352356) (xy 181.643131 -272.386448) (xy 181.602628 -272.414404) (xy 181.558166 -272.435502)
			(xy 181.510895 -272.449194) (xy 181.46204 -272.455126) (xy 181.412865 -272.453145) (xy 181.364646 -272.443301)
			(xy 181.31863 -272.425849) (xy 181.276009 -272.401242) (xy 181.237888 -272.370117) (xy 181.205253 -272.33328)
			(xy 181.17895 -272.291684) (xy 181.159659 -272.246408) (xy 181.147882 -272.198624) (xy 181.143922 -272.14957)
			(xy 179.855114 -272.14957) (xy 179.854619 -272.174177) (xy 179.846724 -272.222754) (xy 179.83114 -272.269435)
			(xy 179.808269 -272.313012) (xy 179.778704 -272.352356) (xy 179.743211 -272.386448) (xy 179.702708 -272.414404)
			(xy 179.658246 -272.435502) (xy 179.610975 -272.449194) (xy 179.56212 -272.455126) (xy 179.512945 -272.453145)
			(xy 179.464726 -272.443301) (xy 179.41871 -272.425849) (xy 179.376089 -272.401242) (xy 179.337968 -272.370117)
			(xy 179.305333 -272.33328) (xy 179.27903 -272.291684) (xy 179.259739 -272.246408) (xy 179.247962 -272.198624)
			(xy 179.244002 -272.14957) (xy 177.95494 -272.14957) (xy 177.954445 -272.174177) (xy 177.94655 -272.222754)
			(xy 177.930966 -272.269435) (xy 177.908095 -272.313012) (xy 177.87853 -272.352356) (xy 177.843037 -272.386448)
			(xy 177.802534 -272.414404) (xy 177.758072 -272.435502) (xy 177.710801 -272.449194) (xy 177.661946 -272.455126)
			(xy 177.612771 -272.453145) (xy 177.564552 -272.443301) (xy 177.518536 -272.425849) (xy 177.475915 -272.401242)
			(xy 177.437794 -272.370117) (xy 177.405159 -272.33328) (xy 177.378856 -272.291684) (xy 177.359565 -272.246408)
			(xy 177.347788 -272.198624) (xy 177.343828 -272.14957) (xy 176.055493 -272.14957) (xy 176.051344 -272.199634)
			(xy 176.038946 -272.248596) (xy 176.018658 -272.294849) (xy 175.991034 -272.337131) (xy 175.956828 -272.374291)
			(xy 175.916971 -272.405314) (xy 175.872553 -272.429354) (xy 175.824783 -272.445755) (xy 175.774965 -272.45407)
			(xy 175.749712 -272.454624) (xy 175.724703 -272.454125) (xy 175.675351 -272.445979) (xy 175.627986 -272.429904)
			(xy 175.605694 -272.418556) (xy 175.60544 -272.418302) (xy 175.59962 -272.41547) (xy 175.587021 -272.412524)
			(xy 175.580548 -272.41246) (xy 175.567086 -272.412714) (xy 175.480726 -272.46453) (xy 175.473453 -272.469348)
			(xy 175.462418 -272.482844) (xy 175.456522 -272.499249) (xy 175.456088 -272.507964) (xy 175.456088 -272.716498)
			(xy 175.456596 -272.723864) (xy 175.458706 -272.734466) (xy 175.470422 -272.752609) (xy 175.479202 -272.758916)
			(xy 175.47971 -272.759424) (xy 175.480218 -272.759678) (xy 175.553624 -272.80489) (xy 175.559318 -272.808225)
			(xy 175.571931 -272.812092) (xy 175.578516 -272.81251) (xy 175.591216 -272.813018) (xy 175.6029 -272.807176)
			(xy 175.603408 -272.807176) (xy 175.626161 -272.796309) (xy 175.674181 -272.780936) (xy 175.723994 -272.773126)
			(xy 175.749204 -272.772632) (xy 175.749712 -272.772632) (xy 175.775397 -272.773137) (xy 175.826134 -272.781174)
			(xy 175.874989 -272.79705) (xy 175.920759 -272.820372) (xy 175.962317 -272.850568) (xy 175.99864 -272.886892)
			(xy 176.028834 -272.928451) (xy 176.052155 -272.974222) (xy 176.068029 -273.023078) (xy 176.076064 -273.073815)
			(xy 176.076064 -273.099784) (xy 176.394122 -273.099784) (xy 176.398082 -273.05073) (xy 176.409859 -273.002946)
			(xy 176.42915 -272.95767) (xy 176.455453 -272.916074) (xy 176.488088 -272.879237) (xy 176.526209 -272.848112)
			(xy 176.56883 -272.823505) (xy 176.614846 -272.806053) (xy 176.663065 -272.796209) (xy 176.71224 -272.794228)
			(xy 176.761095 -272.80016) (xy 176.808366 -272.813852) (xy 176.852828 -272.83495) (xy 176.893331 -272.862906)
			(xy 176.928824 -272.896998) (xy 176.958389 -272.936342) (xy 176.98126 -272.979919) (xy 176.996844 -273.0266)
			(xy 177.004739 -273.075177) (xy 177.005234 -273.099784) (xy 177.004739 -273.124391) (xy 177.00456 -273.125492)
			(xy 177.322984 -273.125492) (xy 177.322984 -273.074076) (xy 177.331027 -273.023294) (xy 177.346915 -272.974395)
			(xy 177.370258 -272.928583) (xy 177.400479 -272.886987) (xy 177.436835 -272.850631) (xy 177.478431 -272.82041)
			(xy 177.524243 -272.797067) (xy 177.573142 -272.781179) (xy 177.623924 -272.773136) (xy 177.67534 -272.773136)
			(xy 177.726122 -272.781179) (xy 177.775021 -272.797067) (xy 177.820833 -272.82041) (xy 177.862429 -272.850631)
			(xy 177.898785 -272.886987) (xy 177.929006 -272.928583) (xy 177.952349 -272.974395) (xy 177.968237 -273.023294)
			(xy 177.97628 -273.074076) (xy 177.976784 -273.099784) (xy 178.294042 -273.099784) (xy 178.298002 -273.05073)
			(xy 178.309779 -273.002946) (xy 178.32907 -272.95767) (xy 178.355373 -272.916074) (xy 178.388008 -272.879237)
			(xy 178.426129 -272.848112) (xy 178.46875 -272.823505) (xy 178.514766 -272.806053) (xy 178.562985 -272.796209)
			(xy 178.61216 -272.794228) (xy 178.661015 -272.80016) (xy 178.708286 -272.813852) (xy 178.752748 -272.83495)
			(xy 178.793251 -272.862906) (xy 178.828744 -272.896998) (xy 178.858309 -272.936342) (xy 178.88118 -272.979919)
			(xy 178.896764 -273.0266) (xy 178.904659 -273.075177) (xy 178.905154 -273.099784) (xy 178.904659 -273.124391)
			(xy 178.90448 -273.125492) (xy 179.223158 -273.125492) (xy 179.223158 -273.074076) (xy 179.231201 -273.023294)
			(xy 179.247089 -272.974395) (xy 179.270432 -272.928583) (xy 179.300653 -272.886987) (xy 179.337009 -272.850631)
			(xy 179.378605 -272.82041) (xy 179.424417 -272.797067) (xy 179.473316 -272.781179) (xy 179.524098 -272.773136)
			(xy 179.575514 -272.773136) (xy 179.626296 -272.781179) (xy 179.675195 -272.797067) (xy 179.721007 -272.82041)
			(xy 179.762603 -272.850631) (xy 179.798959 -272.886987) (xy 179.82918 -272.928583) (xy 179.852523 -272.974395)
			(xy 179.868411 -273.023294) (xy 179.876454 -273.074076) (xy 179.876958 -273.099784) (xy 180.194216 -273.099784)
			(xy 180.198176 -273.05073) (xy 180.209953 -273.002946) (xy 180.229244 -272.95767) (xy 180.255547 -272.916074)
			(xy 180.288182 -272.879237) (xy 180.326303 -272.848112) (xy 180.368924 -272.823505) (xy 180.41494 -272.806053)
			(xy 180.463159 -272.796209) (xy 180.512334 -272.794228) (xy 180.561189 -272.80016) (xy 180.60846 -272.813852)
			(xy 180.652922 -272.83495) (xy 180.693425 -272.862906) (xy 180.728918 -272.896998) (xy 180.758483 -272.936342)
			(xy 180.781354 -272.979919) (xy 180.796938 -273.0266) (xy 180.804833 -273.075177) (xy 180.805328 -273.099784)
			(xy 180.804833 -273.124391) (xy 180.804654 -273.125492) (xy 181.123078 -273.125492) (xy 181.123078 -273.074076)
			(xy 181.131121 -273.023294) (xy 181.147009 -272.974395) (xy 181.170352 -272.928583) (xy 181.200573 -272.886987)
			(xy 181.236929 -272.850631) (xy 181.278525 -272.82041) (xy 181.324337 -272.797067) (xy 181.373236 -272.781179)
			(xy 181.424018 -272.773136) (xy 181.475434 -272.773136) (xy 181.526216 -272.781179) (xy 181.575115 -272.797067)
			(xy 181.620927 -272.82041) (xy 181.662523 -272.850631) (xy 181.698879 -272.886987) (xy 181.7291 -272.928583)
			(xy 181.752443 -272.974395) (xy 181.768331 -273.023294) (xy 181.776374 -273.074076) (xy 181.776878 -273.099784)
			(xy 182.094136 -273.099784) (xy 182.098096 -273.05073) (xy 182.109873 -273.002946) (xy 182.129164 -272.95767)
			(xy 182.155467 -272.916074) (xy 182.188102 -272.879237) (xy 182.226223 -272.848112) (xy 182.268844 -272.823505)
			(xy 182.31486 -272.806053) (xy 182.363079 -272.796209) (xy 182.412254 -272.794228) (xy 182.461109 -272.80016)
			(xy 182.50838 -272.813852) (xy 182.552842 -272.83495) (xy 182.593345 -272.862906) (xy 182.628838 -272.896998)
			(xy 182.658403 -272.936342) (xy 182.681274 -272.979919) (xy 182.696858 -273.0266) (xy 182.704753 -273.075177)
			(xy 182.705248 -273.099784) (xy 182.704753 -273.124391) (xy 182.704574 -273.125492) (xy 183.022998 -273.125492)
			(xy 183.022998 -273.074076) (xy 183.031041 -273.023294) (xy 183.046929 -272.974395) (xy 183.070272 -272.928583)
			(xy 183.100493 -272.886987) (xy 183.136849 -272.850631) (xy 183.178445 -272.82041) (xy 183.224257 -272.797067)
			(xy 183.273156 -272.781179) (xy 183.323938 -272.773136) (xy 183.375354 -272.773136) (xy 183.426136 -272.781179)
			(xy 183.475035 -272.797067) (xy 183.520847 -272.82041) (xy 183.562443 -272.850631) (xy 183.598799 -272.886987)
			(xy 183.62902 -272.928583) (xy 183.652363 -272.974395) (xy 183.668251 -273.023294) (xy 183.676294 -273.074076)
			(xy 183.676798 -273.099784) (xy 183.994056 -273.099784) (xy 183.998016 -273.05073) (xy 184.009793 -273.002946)
			(xy 184.029084 -272.95767) (xy 184.055387 -272.916074) (xy 184.088022 -272.879237) (xy 184.126143 -272.848112)
			(xy 184.168764 -272.823505) (xy 184.21478 -272.806053) (xy 184.262999 -272.796209) (xy 184.312174 -272.794228)
			(xy 184.361029 -272.80016) (xy 184.4083 -272.813852) (xy 184.452762 -272.83495) (xy 184.493265 -272.862906)
			(xy 184.528758 -272.896998) (xy 184.558323 -272.936342) (xy 184.581194 -272.979919) (xy 184.596778 -273.0266)
			(xy 184.604673 -273.075177) (xy 184.605168 -273.099784) (xy 184.604673 -273.124391) (xy 184.604494 -273.125492)
			(xy 184.923172 -273.125492) (xy 184.923172 -273.074076) (xy 184.931215 -273.023294) (xy 184.947103 -272.974395)
			(xy 184.970446 -272.928583) (xy 185.000667 -272.886987) (xy 185.037023 -272.850631) (xy 185.078619 -272.82041)
			(xy 185.124431 -272.797067) (xy 185.17333 -272.781179) (xy 185.224112 -272.773136) (xy 185.275528 -272.773136)
			(xy 185.32631 -272.781179) (xy 185.375209 -272.797067) (xy 185.421021 -272.82041) (xy 185.462617 -272.850631)
			(xy 185.498973 -272.886987) (xy 185.529194 -272.928583) (xy 185.552537 -272.974395) (xy 185.568425 -273.023294)
			(xy 185.576468 -273.074076) (xy 185.576972 -273.099784) (xy 185.89423 -273.099784) (xy 185.89819 -273.05073)
			(xy 185.909967 -273.002946) (xy 185.929258 -272.95767) (xy 185.955561 -272.916074) (xy 185.988196 -272.879237)
			(xy 186.026317 -272.848112) (xy 186.068938 -272.823505) (xy 186.114954 -272.806053) (xy 186.163173 -272.796209)
			(xy 186.212348 -272.794228) (xy 186.261203 -272.80016) (xy 186.308474 -272.813852) (xy 186.352936 -272.83495)
			(xy 186.393439 -272.862906) (xy 186.428932 -272.896998) (xy 186.458497 -272.936342) (xy 186.481368 -272.979919)
			(xy 186.496952 -273.0266) (xy 186.504847 -273.075177) (xy 186.505342 -273.099784) (xy 186.504847 -273.124391)
			(xy 186.504668 -273.125492) (xy 186.823092 -273.125492) (xy 186.823092 -273.074076) (xy 186.831135 -273.023294)
			(xy 186.847023 -272.974395) (xy 186.870366 -272.928583) (xy 186.900587 -272.886987) (xy 186.936943 -272.850631)
			(xy 186.978539 -272.82041) (xy 187.024351 -272.797067) (xy 187.07325 -272.781179) (xy 187.124032 -272.773136)
			(xy 187.175448 -272.773136) (xy 187.22623 -272.781179) (xy 187.275129 -272.797067) (xy 187.320941 -272.82041)
			(xy 187.362537 -272.850631) (xy 187.398893 -272.886987) (xy 187.429114 -272.928583) (xy 187.452457 -272.974395)
			(xy 187.468345 -273.023294) (xy 187.476388 -273.074076) (xy 187.476892 -273.099784) (xy 187.79415 -273.099784)
			(xy 187.79811 -273.05073) (xy 187.809887 -273.002946) (xy 187.829178 -272.95767) (xy 187.855481 -272.916074)
			(xy 187.888116 -272.879237) (xy 187.926237 -272.848112) (xy 187.968858 -272.823505) (xy 188.014874 -272.806053)
			(xy 188.063093 -272.796209) (xy 188.112268 -272.794228) (xy 188.161123 -272.80016) (xy 188.208394 -272.813852)
			(xy 188.252856 -272.83495) (xy 188.293359 -272.862906) (xy 188.328852 -272.896998) (xy 188.358417 -272.936342)
			(xy 188.381288 -272.979919) (xy 188.396872 -273.0266) (xy 188.404767 -273.075177) (xy 188.405262 -273.099784)
			(xy 188.404767 -273.124391) (xy 188.404588 -273.125492) (xy 188.723012 -273.125492) (xy 188.723012 -273.074076)
			(xy 188.731055 -273.023294) (xy 188.746943 -272.974395) (xy 188.770286 -272.928583) (xy 188.800507 -272.886987)
			(xy 188.836863 -272.850631) (xy 188.878459 -272.82041) (xy 188.924271 -272.797067) (xy 188.97317 -272.781179)
			(xy 189.023952 -272.773136) (xy 189.075368 -272.773136) (xy 189.12615 -272.781179) (xy 189.175049 -272.797067)
			(xy 189.220861 -272.82041) (xy 189.262457 -272.850631) (xy 189.298813 -272.886987) (xy 189.329034 -272.928583)
			(xy 189.352377 -272.974395) (xy 189.368265 -273.023294) (xy 189.376308 -273.074076) (xy 189.376812 -273.099784)
			(xy 189.69407 -273.099784) (xy 189.69803 -273.05073) (xy 189.709807 -273.002946) (xy 189.729098 -272.95767)
			(xy 189.755401 -272.916074) (xy 189.788036 -272.879237) (xy 189.826157 -272.848112) (xy 189.868778 -272.823505)
			(xy 189.914794 -272.806053) (xy 189.963013 -272.796209) (xy 190.012188 -272.794228) (xy 190.061043 -272.80016)
			(xy 190.108314 -272.813852) (xy 190.152776 -272.83495) (xy 190.193279 -272.862906) (xy 190.228772 -272.896998)
			(xy 190.258337 -272.936342) (xy 190.281208 -272.979919) (xy 190.296792 -273.0266) (xy 190.304687 -273.075177)
			(xy 190.305182 -273.099784) (xy 190.304687 -273.124391) (xy 190.304508 -273.125492) (xy 190.623186 -273.125492)
			(xy 190.623186 -273.074076) (xy 190.631229 -273.023294) (xy 190.647117 -272.974395) (xy 190.67046 -272.928583)
			(xy 190.700681 -272.886987) (xy 190.737037 -272.850631) (xy 190.778633 -272.82041) (xy 190.824445 -272.797067)
			(xy 190.873344 -272.781179) (xy 190.924126 -272.773136) (xy 190.975542 -272.773136) (xy 191.026324 -272.781179)
			(xy 191.075223 -272.797067) (xy 191.121035 -272.82041) (xy 191.162631 -272.850631) (xy 191.198987 -272.886987)
			(xy 191.229208 -272.928583) (xy 191.252551 -272.974395) (xy 191.268439 -273.023294) (xy 191.276482 -273.074076)
			(xy 191.276986 -273.099784) (xy 191.594244 -273.099784) (xy 191.598204 -273.05073) (xy 191.609981 -273.002946)
			(xy 191.629272 -272.95767) (xy 191.655575 -272.916074) (xy 191.68821 -272.879237) (xy 191.726331 -272.848112)
			(xy 191.768952 -272.823505) (xy 191.814968 -272.806053) (xy 191.863187 -272.796209) (xy 191.912362 -272.794228)
			(xy 191.961217 -272.80016) (xy 192.008488 -272.813852) (xy 192.05295 -272.83495) (xy 192.093453 -272.862906)
			(xy 192.128946 -272.896998) (xy 192.158511 -272.936342) (xy 192.181382 -272.979919) (xy 192.196966 -273.0266)
			(xy 192.204861 -273.075177) (xy 192.205356 -273.099784) (xy 192.204861 -273.124391) (xy 192.204682 -273.125492)
			(xy 192.523106 -273.125492) (xy 192.523106 -273.074076) (xy 192.531149 -273.023294) (xy 192.547037 -272.974395)
			(xy 192.57038 -272.928583) (xy 192.600601 -272.886987) (xy 192.636957 -272.850631) (xy 192.678553 -272.82041)
			(xy 192.724365 -272.797067) (xy 192.773264 -272.781179) (xy 192.824046 -272.773136) (xy 192.875462 -272.773136)
			(xy 192.926244 -272.781179) (xy 192.975143 -272.797067) (xy 193.020955 -272.82041) (xy 193.062551 -272.850631)
			(xy 193.098907 -272.886987) (xy 193.129128 -272.928583) (xy 193.152471 -272.974395) (xy 193.168359 -273.023294)
			(xy 193.176402 -273.074076) (xy 193.176906 -273.099784) (xy 193.494418 -273.099784) (xy 193.498378 -273.05073)
			(xy 193.510155 -273.002946) (xy 193.529446 -272.95767) (xy 193.555749 -272.916074) (xy 193.588384 -272.879237)
			(xy 193.626505 -272.848112) (xy 193.669126 -272.823505) (xy 193.715142 -272.806053) (xy 193.763361 -272.796209)
			(xy 193.812536 -272.794228) (xy 193.861391 -272.80016) (xy 193.908662 -272.813852) (xy 193.953124 -272.83495)
			(xy 193.993627 -272.862906) (xy 194.02912 -272.896998) (xy 194.058685 -272.936342) (xy 194.081556 -272.979919)
			(xy 194.09714 -273.0266) (xy 194.105035 -273.075177) (xy 194.10553 -273.099784) (xy 194.105035 -273.124391)
			(xy 194.104856 -273.125492) (xy 194.423026 -273.125492) (xy 194.423026 -273.074076) (xy 194.431069 -273.023294)
			(xy 194.446957 -272.974395) (xy 194.4703 -272.928583) (xy 194.500521 -272.886987) (xy 194.536877 -272.850631)
			(xy 194.578473 -272.82041) (xy 194.624285 -272.797067) (xy 194.673184 -272.781179) (xy 194.723966 -272.773136)
			(xy 194.775382 -272.773136) (xy 194.826164 -272.781179) (xy 194.875063 -272.797067) (xy 194.920875 -272.82041)
			(xy 194.962471 -272.850631) (xy 194.998827 -272.886987) (xy 195.029048 -272.928583) (xy 195.052391 -272.974395)
			(xy 195.068279 -273.023294) (xy 195.076322 -273.074076) (xy 195.076826 -273.099784) (xy 195.394338 -273.099784)
			(xy 195.398298 -273.05073) (xy 195.410075 -273.002946) (xy 195.429366 -272.95767) (xy 195.455669 -272.916074)
			(xy 195.488304 -272.879237) (xy 195.526425 -272.848112) (xy 195.569046 -272.823505) (xy 195.615062 -272.806053)
			(xy 195.663281 -272.796209) (xy 195.712456 -272.794228) (xy 195.761311 -272.80016) (xy 195.808582 -272.813852)
			(xy 195.853044 -272.83495) (xy 195.893547 -272.862906) (xy 195.92904 -272.896998) (xy 195.958605 -272.936342)
			(xy 195.981476 -272.979919) (xy 195.99706 -273.0266) (xy 196.004955 -273.075177) (xy 196.00545 -273.099784)
			(xy 196.004955 -273.124391) (xy 196.004776 -273.125492) (xy 196.322946 -273.125492) (xy 196.322946 -273.074076)
			(xy 196.330989 -273.023294) (xy 196.346877 -272.974395) (xy 196.37022 -272.928583) (xy 196.400441 -272.886987)
			(xy 196.436797 -272.850631) (xy 196.478393 -272.82041) (xy 196.524205 -272.797067) (xy 196.573104 -272.781179)
			(xy 196.623886 -272.773136) (xy 196.675302 -272.773136) (xy 196.726084 -272.781179) (xy 196.774983 -272.797067)
			(xy 196.820795 -272.82041) (xy 196.862391 -272.850631) (xy 196.898747 -272.886987) (xy 196.928968 -272.928583)
			(xy 196.952311 -272.974395) (xy 196.968199 -273.023294) (xy 196.976242 -273.074076) (xy 196.976746 -273.099784)
			(xy 197.294258 -273.099784) (xy 197.298218 -273.05073) (xy 197.309995 -273.002946) (xy 197.329286 -272.95767)
			(xy 197.355589 -272.916074) (xy 197.388224 -272.879237) (xy 197.426345 -272.848112) (xy 197.468966 -272.823505)
			(xy 197.514982 -272.806053) (xy 197.563201 -272.796209) (xy 197.612376 -272.794228) (xy 197.661231 -272.80016)
			(xy 197.708502 -272.813852) (xy 197.752964 -272.83495) (xy 197.793467 -272.862906) (xy 197.82896 -272.896998)
			(xy 197.858525 -272.936342) (xy 197.881396 -272.979919) (xy 197.89698 -273.0266) (xy 197.904875 -273.075177)
			(xy 197.90537 -273.099784) (xy 197.904875 -273.124391) (xy 197.89698 -273.172968) (xy 197.881396 -273.219649)
			(xy 197.858525 -273.263226) (xy 197.82896 -273.30257) (xy 197.793467 -273.336662) (xy 197.752964 -273.364618)
			(xy 197.708502 -273.385716) (xy 197.661231 -273.399408) (xy 197.612376 -273.40534) (xy 197.563201 -273.403359)
			(xy 197.514982 -273.393515) (xy 197.468966 -273.376063) (xy 197.426345 -273.351456) (xy 197.388224 -273.320331)
			(xy 197.355589 -273.283494) (xy 197.329286 -273.241898) (xy 197.309995 -273.196622) (xy 197.298218 -273.148838)
			(xy 197.294258 -273.099784) (xy 196.976746 -273.099784) (xy 196.976242 -273.125492) (xy 196.968199 -273.176274)
			(xy 196.952311 -273.225173) (xy 196.928968 -273.270985) (xy 196.898747 -273.312581) (xy 196.862391 -273.348937)
			(xy 196.820795 -273.379158) (xy 196.774983 -273.402501) (xy 196.726084 -273.418389) (xy 196.675302 -273.426432)
			(xy 196.623886 -273.426432) (xy 196.573104 -273.418389) (xy 196.524205 -273.402501) (xy 196.478393 -273.379158)
			(xy 196.436797 -273.348937) (xy 196.400441 -273.312581) (xy 196.37022 -273.270985) (xy 196.346877 -273.225173)
			(xy 196.330989 -273.176274) (xy 196.322946 -273.125492) (xy 196.004776 -273.125492) (xy 195.99706 -273.172968)
			(xy 195.981476 -273.219649) (xy 195.958605 -273.263226) (xy 195.92904 -273.30257) (xy 195.893547 -273.336662)
			(xy 195.853044 -273.364618) (xy 195.808582 -273.385716) (xy 195.761311 -273.399408) (xy 195.712456 -273.40534)
			(xy 195.663281 -273.403359) (xy 195.615062 -273.393515) (xy 195.569046 -273.376063) (xy 195.526425 -273.351456)
			(xy 195.488304 -273.320331) (xy 195.455669 -273.283494) (xy 195.429366 -273.241898) (xy 195.410075 -273.196622)
			(xy 195.398298 -273.148838) (xy 195.394338 -273.099784) (xy 195.076826 -273.099784) (xy 195.076322 -273.125492)
			(xy 195.068279 -273.176274) (xy 195.052391 -273.225173) (xy 195.029048 -273.270985) (xy 194.998827 -273.312581)
			(xy 194.962471 -273.348937) (xy 194.920875 -273.379158) (xy 194.875063 -273.402501) (xy 194.826164 -273.418389)
			(xy 194.775382 -273.426432) (xy 194.723966 -273.426432) (xy 194.673184 -273.418389) (xy 194.624285 -273.402501)
			(xy 194.578473 -273.379158) (xy 194.536877 -273.348937) (xy 194.500521 -273.312581) (xy 194.4703 -273.270985)
			(xy 194.446957 -273.225173) (xy 194.431069 -273.176274) (xy 194.423026 -273.125492) (xy 194.104856 -273.125492)
			(xy 194.09714 -273.172968) (xy 194.081556 -273.219649) (xy 194.058685 -273.263226) (xy 194.02912 -273.30257)
			(xy 193.993627 -273.336662) (xy 193.953124 -273.364618) (xy 193.908662 -273.385716) (xy 193.861391 -273.399408)
			(xy 193.812536 -273.40534) (xy 193.763361 -273.403359) (xy 193.715142 -273.393515) (xy 193.669126 -273.376063)
			(xy 193.626505 -273.351456) (xy 193.588384 -273.320331) (xy 193.555749 -273.283494) (xy 193.529446 -273.241898)
			(xy 193.510155 -273.196622) (xy 193.498378 -273.148838) (xy 193.494418 -273.099784) (xy 193.176906 -273.099784)
			(xy 193.176402 -273.125492) (xy 193.168359 -273.176274) (xy 193.152471 -273.225173) (xy 193.129128 -273.270985)
			(xy 193.098907 -273.312581) (xy 193.062551 -273.348937) (xy 193.020955 -273.379158) (xy 192.975143 -273.402501)
			(xy 192.926244 -273.418389) (xy 192.875462 -273.426432) (xy 192.824046 -273.426432) (xy 192.773264 -273.418389)
			(xy 192.724365 -273.402501) (xy 192.678553 -273.379158) (xy 192.636957 -273.348937) (xy 192.600601 -273.312581)
			(xy 192.57038 -273.270985) (xy 192.547037 -273.225173) (xy 192.531149 -273.176274) (xy 192.523106 -273.125492)
			(xy 192.204682 -273.125492) (xy 192.196966 -273.172968) (xy 192.181382 -273.219649) (xy 192.158511 -273.263226)
			(xy 192.128946 -273.30257) (xy 192.093453 -273.336662) (xy 192.05295 -273.364618) (xy 192.008488 -273.385716)
			(xy 191.961217 -273.399408) (xy 191.912362 -273.40534) (xy 191.863187 -273.403359) (xy 191.814968 -273.393515)
			(xy 191.768952 -273.376063) (xy 191.726331 -273.351456) (xy 191.68821 -273.320331) (xy 191.655575 -273.283494)
			(xy 191.629272 -273.241898) (xy 191.609981 -273.196622) (xy 191.598204 -273.148838) (xy 191.594244 -273.099784)
			(xy 191.276986 -273.099784) (xy 191.276482 -273.125492) (xy 191.268439 -273.176274) (xy 191.252551 -273.225173)
			(xy 191.229208 -273.270985) (xy 191.198987 -273.312581) (xy 191.162631 -273.348937) (xy 191.121035 -273.379158)
			(xy 191.075223 -273.402501) (xy 191.026324 -273.418389) (xy 190.975542 -273.426432) (xy 190.924126 -273.426432)
			(xy 190.873344 -273.418389) (xy 190.824445 -273.402501) (xy 190.778633 -273.379158) (xy 190.737037 -273.348937)
			(xy 190.700681 -273.312581) (xy 190.67046 -273.270985) (xy 190.647117 -273.225173) (xy 190.631229 -273.176274)
			(xy 190.623186 -273.125492) (xy 190.304508 -273.125492) (xy 190.296792 -273.172968) (xy 190.281208 -273.219649)
			(xy 190.258337 -273.263226) (xy 190.228772 -273.30257) (xy 190.193279 -273.336662) (xy 190.152776 -273.364618)
			(xy 190.108314 -273.385716) (xy 190.061043 -273.399408) (xy 190.012188 -273.40534) (xy 189.963013 -273.403359)
			(xy 189.914794 -273.393515) (xy 189.868778 -273.376063) (xy 189.826157 -273.351456) (xy 189.788036 -273.320331)
			(xy 189.755401 -273.283494) (xy 189.729098 -273.241898) (xy 189.709807 -273.196622) (xy 189.69803 -273.148838)
			(xy 189.69407 -273.099784) (xy 189.376812 -273.099784) (xy 189.376308 -273.125492) (xy 189.368265 -273.176274)
			(xy 189.352377 -273.225173) (xy 189.329034 -273.270985) (xy 189.298813 -273.312581) (xy 189.262457 -273.348937)
			(xy 189.220861 -273.379158) (xy 189.175049 -273.402501) (xy 189.12615 -273.418389) (xy 189.075368 -273.426432)
			(xy 189.023952 -273.426432) (xy 188.97317 -273.418389) (xy 188.924271 -273.402501) (xy 188.878459 -273.379158)
			(xy 188.836863 -273.348937) (xy 188.800507 -273.312581) (xy 188.770286 -273.270985) (xy 188.746943 -273.225173)
			(xy 188.731055 -273.176274) (xy 188.723012 -273.125492) (xy 188.404588 -273.125492) (xy 188.396872 -273.172968)
			(xy 188.381288 -273.219649) (xy 188.358417 -273.263226) (xy 188.328852 -273.30257) (xy 188.293359 -273.336662)
			(xy 188.252856 -273.364618) (xy 188.208394 -273.385716) (xy 188.161123 -273.399408) (xy 188.112268 -273.40534)
			(xy 188.063093 -273.403359) (xy 188.014874 -273.393515) (xy 187.968858 -273.376063) (xy 187.926237 -273.351456)
			(xy 187.888116 -273.320331) (xy 187.855481 -273.283494) (xy 187.829178 -273.241898) (xy 187.809887 -273.196622)
			(xy 187.79811 -273.148838) (xy 187.79415 -273.099784) (xy 187.476892 -273.099784) (xy 187.476388 -273.125492)
			(xy 187.468345 -273.176274) (xy 187.452457 -273.225173) (xy 187.429114 -273.270985) (xy 187.398893 -273.312581)
			(xy 187.362537 -273.348937) (xy 187.320941 -273.379158) (xy 187.275129 -273.402501) (xy 187.22623 -273.418389)
			(xy 187.175448 -273.426432) (xy 187.124032 -273.426432) (xy 187.07325 -273.418389) (xy 187.024351 -273.402501)
			(xy 186.978539 -273.379158) (xy 186.936943 -273.348937) (xy 186.900587 -273.312581) (xy 186.870366 -273.270985)
			(xy 186.847023 -273.225173) (xy 186.831135 -273.176274) (xy 186.823092 -273.125492) (xy 186.504668 -273.125492)
			(xy 186.496952 -273.172968) (xy 186.481368 -273.219649) (xy 186.458497 -273.263226) (xy 186.428932 -273.30257)
			(xy 186.393439 -273.336662) (xy 186.352936 -273.364618) (xy 186.308474 -273.385716) (xy 186.261203 -273.399408)
			(xy 186.212348 -273.40534) (xy 186.163173 -273.403359) (xy 186.114954 -273.393515) (xy 186.068938 -273.376063)
			(xy 186.026317 -273.351456) (xy 185.988196 -273.320331) (xy 185.955561 -273.283494) (xy 185.929258 -273.241898)
			(xy 185.909967 -273.196622) (xy 185.89819 -273.148838) (xy 185.89423 -273.099784) (xy 185.576972 -273.099784)
			(xy 185.576468 -273.125492) (xy 185.568425 -273.176274) (xy 185.552537 -273.225173) (xy 185.529194 -273.270985)
			(xy 185.498973 -273.312581) (xy 185.462617 -273.348937) (xy 185.421021 -273.379158) (xy 185.375209 -273.402501)
			(xy 185.32631 -273.418389) (xy 185.275528 -273.426432) (xy 185.224112 -273.426432) (xy 185.17333 -273.418389)
			(xy 185.124431 -273.402501) (xy 185.078619 -273.379158) (xy 185.037023 -273.348937) (xy 185.000667 -273.312581)
			(xy 184.970446 -273.270985) (xy 184.947103 -273.225173) (xy 184.931215 -273.176274) (xy 184.923172 -273.125492)
			(xy 184.604494 -273.125492) (xy 184.596778 -273.172968) (xy 184.581194 -273.219649) (xy 184.558323 -273.263226)
			(xy 184.528758 -273.30257) (xy 184.493265 -273.336662) (xy 184.452762 -273.364618) (xy 184.4083 -273.385716)
			(xy 184.361029 -273.399408) (xy 184.312174 -273.40534) (xy 184.262999 -273.403359) (xy 184.21478 -273.393515)
			(xy 184.168764 -273.376063) (xy 184.126143 -273.351456) (xy 184.088022 -273.320331) (xy 184.055387 -273.283494)
			(xy 184.029084 -273.241898) (xy 184.009793 -273.196622) (xy 183.998016 -273.148838) (xy 183.994056 -273.099784)
			(xy 183.676798 -273.099784) (xy 183.676294 -273.125492) (xy 183.668251 -273.176274) (xy 183.652363 -273.225173)
			(xy 183.62902 -273.270985) (xy 183.598799 -273.312581) (xy 183.562443 -273.348937) (xy 183.520847 -273.379158)
			(xy 183.475035 -273.402501) (xy 183.426136 -273.418389) (xy 183.375354 -273.426432) (xy 183.323938 -273.426432)
			(xy 183.273156 -273.418389) (xy 183.224257 -273.402501) (xy 183.178445 -273.379158) (xy 183.136849 -273.348937)
			(xy 183.100493 -273.312581) (xy 183.070272 -273.270985) (xy 183.046929 -273.225173) (xy 183.031041 -273.176274)
			(xy 183.022998 -273.125492) (xy 182.704574 -273.125492) (xy 182.696858 -273.172968) (xy 182.681274 -273.219649)
			(xy 182.658403 -273.263226) (xy 182.628838 -273.30257) (xy 182.593345 -273.336662) (xy 182.552842 -273.364618)
			(xy 182.50838 -273.385716) (xy 182.461109 -273.399408) (xy 182.412254 -273.40534) (xy 182.363079 -273.403359)
			(xy 182.31486 -273.393515) (xy 182.268844 -273.376063) (xy 182.226223 -273.351456) (xy 182.188102 -273.320331)
			(xy 182.155467 -273.283494) (xy 182.129164 -273.241898) (xy 182.109873 -273.196622) (xy 182.098096 -273.148838)
			(xy 182.094136 -273.099784) (xy 181.776878 -273.099784) (xy 181.776374 -273.125492) (xy 181.768331 -273.176274)
			(xy 181.752443 -273.225173) (xy 181.7291 -273.270985) (xy 181.698879 -273.312581) (xy 181.662523 -273.348937)
			(xy 181.620927 -273.379158) (xy 181.575115 -273.402501) (xy 181.526216 -273.418389) (xy 181.475434 -273.426432)
			(xy 181.424018 -273.426432) (xy 181.373236 -273.418389) (xy 181.324337 -273.402501) (xy 181.278525 -273.379158)
			(xy 181.236929 -273.348937) (xy 181.200573 -273.312581) (xy 181.170352 -273.270985) (xy 181.147009 -273.225173)
			(xy 181.131121 -273.176274) (xy 181.123078 -273.125492) (xy 180.804654 -273.125492) (xy 180.796938 -273.172968)
			(xy 180.781354 -273.219649) (xy 180.758483 -273.263226) (xy 180.728918 -273.30257) (xy 180.693425 -273.336662)
			(xy 180.652922 -273.364618) (xy 180.60846 -273.385716) (xy 180.561189 -273.399408) (xy 180.512334 -273.40534)
			(xy 180.463159 -273.403359) (xy 180.41494 -273.393515) (xy 180.368924 -273.376063) (xy 180.326303 -273.351456)
			(xy 180.288182 -273.320331) (xy 180.255547 -273.283494) (xy 180.229244 -273.241898) (xy 180.209953 -273.196622)
			(xy 180.198176 -273.148838) (xy 180.194216 -273.099784) (xy 179.876958 -273.099784) (xy 179.876454 -273.125492)
			(xy 179.868411 -273.176274) (xy 179.852523 -273.225173) (xy 179.82918 -273.270985) (xy 179.798959 -273.312581)
			(xy 179.762603 -273.348937) (xy 179.721007 -273.379158) (xy 179.675195 -273.402501) (xy 179.626296 -273.418389)
			(xy 179.575514 -273.426432) (xy 179.524098 -273.426432) (xy 179.473316 -273.418389) (xy 179.424417 -273.402501)
			(xy 179.378605 -273.379158) (xy 179.337009 -273.348937) (xy 179.300653 -273.312581) (xy 179.270432 -273.270985)
			(xy 179.247089 -273.225173) (xy 179.231201 -273.176274) (xy 179.223158 -273.125492) (xy 178.90448 -273.125492)
			(xy 178.896764 -273.172968) (xy 178.88118 -273.219649) (xy 178.858309 -273.263226) (xy 178.828744 -273.30257)
			(xy 178.793251 -273.336662) (xy 178.752748 -273.364618) (xy 178.708286 -273.385716) (xy 178.661015 -273.399408)
			(xy 178.61216 -273.40534) (xy 178.562985 -273.403359) (xy 178.514766 -273.393515) (xy 178.46875 -273.376063)
			(xy 178.426129 -273.351456) (xy 178.388008 -273.320331) (xy 178.355373 -273.283494) (xy 178.32907 -273.241898)
			(xy 178.309779 -273.196622) (xy 178.298002 -273.148838) (xy 178.294042 -273.099784) (xy 177.976784 -273.099784)
			(xy 177.97628 -273.125492) (xy 177.968237 -273.176274) (xy 177.952349 -273.225173) (xy 177.929006 -273.270985)
			(xy 177.898785 -273.312581) (xy 177.862429 -273.348937) (xy 177.820833 -273.379158) (xy 177.775021 -273.402501)
			(xy 177.726122 -273.418389) (xy 177.67534 -273.426432) (xy 177.623924 -273.426432) (xy 177.573142 -273.418389)
			(xy 177.524243 -273.402501) (xy 177.478431 -273.379158) (xy 177.436835 -273.348937) (xy 177.400479 -273.312581)
			(xy 177.370258 -273.270985) (xy 177.346915 -273.225173) (xy 177.331027 -273.176274) (xy 177.322984 -273.125492)
			(xy 177.00456 -273.125492) (xy 176.996844 -273.172968) (xy 176.98126 -273.219649) (xy 176.958389 -273.263226)
			(xy 176.928824 -273.30257) (xy 176.893331 -273.336662) (xy 176.852828 -273.364618) (xy 176.808366 -273.385716)
			(xy 176.761095 -273.399408) (xy 176.71224 -273.40534) (xy 176.663065 -273.403359) (xy 176.614846 -273.393515)
			(xy 176.56883 -273.376063) (xy 176.526209 -273.351456) (xy 176.488088 -273.320331) (xy 176.455453 -273.283494)
			(xy 176.42915 -273.241898) (xy 176.409859 -273.196622) (xy 176.398082 -273.148838) (xy 176.394122 -273.099784)
			(xy 176.076064 -273.099784) (xy 176.076064 -273.125185) (xy 176.068029 -273.175922) (xy 176.052155 -273.224778)
			(xy 176.028834 -273.270549) (xy 175.99864 -273.312108) (xy 175.962317 -273.348432) (xy 175.920759 -273.378628)
			(xy 175.874989 -273.40195) (xy 175.826134 -273.417826) (xy 175.775397 -273.425863) (xy 175.749712 -273.426428)
			(xy 175.749204 -273.426428) (xy 175.723996 -273.425917) (xy 175.674189 -273.418096) (xy 175.62617 -273.40273)
			(xy 175.603408 -273.391884) (xy 175.6029 -273.391884) (xy 175.602646 -273.39163) (xy 175.596949 -273.389095)
			(xy 175.584751 -273.386522) (xy 175.578516 -273.38655) (xy 175.565054 -273.387058) (xy 175.480218 -273.439382)
			(xy 175.47971 -273.439636) (xy 175.479202 -273.440144) (xy 175.470412 -273.446437) (xy 175.458711 -273.464593)
			(xy 175.456596 -273.475196) (xy 175.456088 -273.482562) (xy 175.456088 -273.666458) (xy 175.456596 -273.673824)
			(xy 175.4587 -273.68443) (xy 175.470408 -273.702585) (xy 175.479202 -273.708876) (xy 175.47971 -273.709384)
			(xy 175.480218 -273.709638) (xy 175.553624 -273.75485) (xy 175.559318 -273.758187) (xy 175.57193 -273.762058)
			(xy 175.578516 -273.76247) (xy 175.591216 -273.762978) (xy 175.6029 -273.757136) (xy 175.603408 -273.757136)
			(xy 175.62616 -273.746267) (xy 175.674181 -273.730891) (xy 175.723994 -273.723079) (xy 175.749204 -273.722592)
			(xy 175.749712 -273.722592) (xy 175.7754 -273.723097) (xy 175.826143 -273.731135) (xy 175.875004 -273.747013)
			(xy 175.92078 -273.770338) (xy 175.962343 -273.800537) (xy 175.998671 -273.836866) (xy 176.028868 -273.878431)
			(xy 176.052192 -273.924207) (xy 176.068067 -273.973069) (xy 176.076104 -274.023812) (xy 176.076104 -274.049744)
			(xy 176.394122 -274.049744) (xy 176.398082 -274.00069) (xy 176.409859 -273.952906) (xy 176.42915 -273.90763)
			(xy 176.455453 -273.866034) (xy 176.488088 -273.829197) (xy 176.526209 -273.798072) (xy 176.56883 -273.773465)
			(xy 176.614846 -273.756013) (xy 176.663065 -273.746169) (xy 176.71224 -273.744188) (xy 176.761095 -273.75012)
			(xy 176.808366 -273.763812) (xy 176.852828 -273.78491) (xy 176.893331 -273.812866) (xy 176.928824 -273.846958)
			(xy 176.958389 -273.886302) (xy 176.98126 -273.929879) (xy 176.996844 -273.97656) (xy 177.004739 -274.025137)
			(xy 177.005234 -274.049744) (xy 177.004739 -274.074351) (xy 177.00456 -274.075452) (xy 177.322984 -274.075452)
			(xy 177.322984 -274.024036) (xy 177.331027 -273.973254) (xy 177.346915 -273.924355) (xy 177.370258 -273.878543)
			(xy 177.400479 -273.836947) (xy 177.436835 -273.800591) (xy 177.478431 -273.77037) (xy 177.524243 -273.747027)
			(xy 177.573142 -273.731139) (xy 177.623924 -273.723096) (xy 177.67534 -273.723096) (xy 177.726122 -273.731139)
			(xy 177.775021 -273.747027) (xy 177.820833 -273.77037) (xy 177.862429 -273.800591) (xy 177.898785 -273.836947)
			(xy 177.929006 -273.878543) (xy 177.952349 -273.924355) (xy 177.968237 -273.973254) (xy 177.97628 -274.024036)
			(xy 177.976784 -274.049744) (xy 178.294042 -274.049744) (xy 178.298002 -274.00069) (xy 178.309779 -273.952906)
			(xy 178.32907 -273.90763) (xy 178.355373 -273.866034) (xy 178.388008 -273.829197) (xy 178.426129 -273.798072)
			(xy 178.46875 -273.773465) (xy 178.514766 -273.756013) (xy 178.562985 -273.746169) (xy 178.61216 -273.744188)
			(xy 178.661015 -273.75012) (xy 178.708286 -273.763812) (xy 178.752748 -273.78491) (xy 178.793251 -273.812866)
			(xy 178.828744 -273.846958) (xy 178.858309 -273.886302) (xy 178.88118 -273.929879) (xy 178.896764 -273.97656)
			(xy 178.904659 -274.025137) (xy 178.905154 -274.049744) (xy 178.904659 -274.074351) (xy 178.90448 -274.075452)
			(xy 179.223158 -274.075452) (xy 179.223158 -274.024036) (xy 179.231201 -273.973254) (xy 179.247089 -273.924355)
			(xy 179.270432 -273.878543) (xy 179.300653 -273.836947) (xy 179.337009 -273.800591) (xy 179.378605 -273.77037)
			(xy 179.424417 -273.747027) (xy 179.473316 -273.731139) (xy 179.524098 -273.723096) (xy 179.575514 -273.723096)
			(xy 179.626296 -273.731139) (xy 179.675195 -273.747027) (xy 179.721007 -273.77037) (xy 179.762603 -273.800591)
			(xy 179.798959 -273.836947) (xy 179.82918 -273.878543) (xy 179.852523 -273.924355) (xy 179.868411 -273.973254)
			(xy 179.876454 -274.024036) (xy 179.876958 -274.049744) (xy 180.194216 -274.049744) (xy 180.198176 -274.00069)
			(xy 180.209953 -273.952906) (xy 180.229244 -273.90763) (xy 180.255547 -273.866034) (xy 180.288182 -273.829197)
			(xy 180.326303 -273.798072) (xy 180.368924 -273.773465) (xy 180.41494 -273.756013) (xy 180.463159 -273.746169)
			(xy 180.512334 -273.744188) (xy 180.561189 -273.75012) (xy 180.60846 -273.763812) (xy 180.652922 -273.78491)
			(xy 180.693425 -273.812866) (xy 180.728918 -273.846958) (xy 180.758483 -273.886302) (xy 180.781354 -273.929879)
			(xy 180.796938 -273.97656) (xy 180.804833 -274.025137) (xy 180.805328 -274.049744) (xy 180.804833 -274.074351)
			(xy 180.804654 -274.075452) (xy 181.123078 -274.075452) (xy 181.123078 -274.024036) (xy 181.131121 -273.973254)
			(xy 181.147009 -273.924355) (xy 181.170352 -273.878543) (xy 181.200573 -273.836947) (xy 181.236929 -273.800591)
			(xy 181.278525 -273.77037) (xy 181.324337 -273.747027) (xy 181.373236 -273.731139) (xy 181.424018 -273.723096)
			(xy 181.475434 -273.723096) (xy 181.526216 -273.731139) (xy 181.575115 -273.747027) (xy 181.620927 -273.77037)
			(xy 181.662523 -273.800591) (xy 181.698879 -273.836947) (xy 181.7291 -273.878543) (xy 181.752443 -273.924355)
			(xy 181.768331 -273.973254) (xy 181.776374 -274.024036) (xy 181.776878 -274.049744) (xy 182.094136 -274.049744)
			(xy 182.098096 -274.00069) (xy 182.109873 -273.952906) (xy 182.129164 -273.90763) (xy 182.155467 -273.866034)
			(xy 182.188102 -273.829197) (xy 182.226223 -273.798072) (xy 182.268844 -273.773465) (xy 182.31486 -273.756013)
			(xy 182.363079 -273.746169) (xy 182.412254 -273.744188) (xy 182.461109 -273.75012) (xy 182.50838 -273.763812)
			(xy 182.552842 -273.78491) (xy 182.593345 -273.812866) (xy 182.628838 -273.846958) (xy 182.658403 -273.886302)
			(xy 182.681274 -273.929879) (xy 182.696858 -273.97656) (xy 182.704753 -274.025137) (xy 182.705248 -274.049744)
			(xy 182.704753 -274.074351) (xy 182.704574 -274.075452) (xy 183.022998 -274.075452) (xy 183.022998 -274.024036)
			(xy 183.031041 -273.973254) (xy 183.046929 -273.924355) (xy 183.070272 -273.878543) (xy 183.100493 -273.836947)
			(xy 183.136849 -273.800591) (xy 183.178445 -273.77037) (xy 183.224257 -273.747027) (xy 183.273156 -273.731139)
			(xy 183.323938 -273.723096) (xy 183.375354 -273.723096) (xy 183.426136 -273.731139) (xy 183.475035 -273.747027)
			(xy 183.520847 -273.77037) (xy 183.562443 -273.800591) (xy 183.598799 -273.836947) (xy 183.62902 -273.878543)
			(xy 183.652363 -273.924355) (xy 183.668251 -273.973254) (xy 183.676294 -274.024036) (xy 183.676798 -274.049744)
			(xy 183.994056 -274.049744) (xy 183.998016 -274.00069) (xy 184.009793 -273.952906) (xy 184.029084 -273.90763)
			(xy 184.055387 -273.866034) (xy 184.088022 -273.829197) (xy 184.126143 -273.798072) (xy 184.168764 -273.773465)
			(xy 184.21478 -273.756013) (xy 184.262999 -273.746169) (xy 184.312174 -273.744188) (xy 184.361029 -273.75012)
			(xy 184.4083 -273.763812) (xy 184.452762 -273.78491) (xy 184.493265 -273.812866) (xy 184.528758 -273.846958)
			(xy 184.558323 -273.886302) (xy 184.581194 -273.929879) (xy 184.596778 -273.97656) (xy 184.604673 -274.025137)
			(xy 184.605168 -274.049744) (xy 184.604673 -274.074351) (xy 184.604494 -274.075452) (xy 184.923172 -274.075452)
			(xy 184.923172 -274.024036) (xy 184.931215 -273.973254) (xy 184.947103 -273.924355) (xy 184.970446 -273.878543)
			(xy 185.000667 -273.836947) (xy 185.037023 -273.800591) (xy 185.078619 -273.77037) (xy 185.124431 -273.747027)
			(xy 185.17333 -273.731139) (xy 185.224112 -273.723096) (xy 185.275528 -273.723096) (xy 185.32631 -273.731139)
			(xy 185.375209 -273.747027) (xy 185.421021 -273.77037) (xy 185.462617 -273.800591) (xy 185.498973 -273.836947)
			(xy 185.529194 -273.878543) (xy 185.552537 -273.924355) (xy 185.568425 -273.973254) (xy 185.576468 -274.024036)
			(xy 185.576972 -274.049744) (xy 185.89423 -274.049744) (xy 185.89819 -274.00069) (xy 185.909967 -273.952906)
			(xy 185.929258 -273.90763) (xy 185.955561 -273.866034) (xy 185.988196 -273.829197) (xy 186.026317 -273.798072)
			(xy 186.068938 -273.773465) (xy 186.114954 -273.756013) (xy 186.163173 -273.746169) (xy 186.212348 -273.744188)
			(xy 186.261203 -273.75012) (xy 186.308474 -273.763812) (xy 186.352936 -273.78491) (xy 186.393439 -273.812866)
			(xy 186.428932 -273.846958) (xy 186.458497 -273.886302) (xy 186.481368 -273.929879) (xy 186.496952 -273.97656)
			(xy 186.504847 -274.025137) (xy 186.505342 -274.049744) (xy 186.504847 -274.074351) (xy 186.504668 -274.075452)
			(xy 186.823092 -274.075452) (xy 186.823092 -274.024036) (xy 186.831135 -273.973254) (xy 186.847023 -273.924355)
			(xy 186.870366 -273.878543) (xy 186.900587 -273.836947) (xy 186.936943 -273.800591) (xy 186.978539 -273.77037)
			(xy 187.024351 -273.747027) (xy 187.07325 -273.731139) (xy 187.124032 -273.723096) (xy 187.175448 -273.723096)
			(xy 187.22623 -273.731139) (xy 187.275129 -273.747027) (xy 187.320941 -273.77037) (xy 187.362537 -273.800591)
			(xy 187.398893 -273.836947) (xy 187.429114 -273.878543) (xy 187.452457 -273.924355) (xy 187.468345 -273.973254)
			(xy 187.476388 -274.024036) (xy 187.476892 -274.049744) (xy 187.79415 -274.049744) (xy 187.79811 -274.00069)
			(xy 187.809887 -273.952906) (xy 187.829178 -273.90763) (xy 187.855481 -273.866034) (xy 187.888116 -273.829197)
			(xy 187.926237 -273.798072) (xy 187.968858 -273.773465) (xy 188.014874 -273.756013) (xy 188.063093 -273.746169)
			(xy 188.112268 -273.744188) (xy 188.161123 -273.75012) (xy 188.208394 -273.763812) (xy 188.252856 -273.78491)
			(xy 188.293359 -273.812866) (xy 188.328852 -273.846958) (xy 188.358417 -273.886302) (xy 188.381288 -273.929879)
			(xy 188.396872 -273.97656) (xy 188.404767 -274.025137) (xy 188.405262 -274.049744) (xy 188.404767 -274.074351)
			(xy 188.404588 -274.075452) (xy 188.723012 -274.075452) (xy 188.723012 -274.024036) (xy 188.731055 -273.973254)
			(xy 188.746943 -273.924355) (xy 188.770286 -273.878543) (xy 188.800507 -273.836947) (xy 188.836863 -273.800591)
			(xy 188.878459 -273.77037) (xy 188.924271 -273.747027) (xy 188.97317 -273.731139) (xy 189.023952 -273.723096)
			(xy 189.075368 -273.723096) (xy 189.12615 -273.731139) (xy 189.175049 -273.747027) (xy 189.220861 -273.77037)
			(xy 189.262457 -273.800591) (xy 189.298813 -273.836947) (xy 189.329034 -273.878543) (xy 189.352377 -273.924355)
			(xy 189.368265 -273.973254) (xy 189.376308 -274.024036) (xy 189.376812 -274.049744) (xy 189.69407 -274.049744)
			(xy 189.69803 -274.00069) (xy 189.709807 -273.952906) (xy 189.729098 -273.90763) (xy 189.755401 -273.866034)
			(xy 189.788036 -273.829197) (xy 189.826157 -273.798072) (xy 189.868778 -273.773465) (xy 189.914794 -273.756013)
			(xy 189.963013 -273.746169) (xy 190.012188 -273.744188) (xy 190.061043 -273.75012) (xy 190.108314 -273.763812)
			(xy 190.152776 -273.78491) (xy 190.193279 -273.812866) (xy 190.228772 -273.846958) (xy 190.258337 -273.886302)
			(xy 190.281208 -273.929879) (xy 190.296792 -273.97656) (xy 190.304687 -274.025137) (xy 190.305182 -274.049744)
			(xy 190.304687 -274.074351) (xy 190.304508 -274.075452) (xy 190.623186 -274.075452) (xy 190.623186 -274.024036)
			(xy 190.631229 -273.973254) (xy 190.647117 -273.924355) (xy 190.67046 -273.878543) (xy 190.700681 -273.836947)
			(xy 190.737037 -273.800591) (xy 190.778633 -273.77037) (xy 190.824445 -273.747027) (xy 190.873344 -273.731139)
			(xy 190.924126 -273.723096) (xy 190.975542 -273.723096) (xy 191.026324 -273.731139) (xy 191.075223 -273.747027)
			(xy 191.121035 -273.77037) (xy 191.162631 -273.800591) (xy 191.198987 -273.836947) (xy 191.229208 -273.878543)
			(xy 191.252551 -273.924355) (xy 191.268439 -273.973254) (xy 191.276482 -274.024036) (xy 191.276986 -274.049744)
			(xy 191.594498 -274.049744) (xy 191.598458 -274.00069) (xy 191.610235 -273.952906) (xy 191.629526 -273.90763)
			(xy 191.655829 -273.866034) (xy 191.688464 -273.829197) (xy 191.726585 -273.798072) (xy 191.769206 -273.773465)
			(xy 191.815222 -273.756013) (xy 191.863441 -273.746169) (xy 191.912616 -273.744188) (xy 191.961471 -273.75012)
			(xy 192.008742 -273.763812) (xy 192.053204 -273.78491) (xy 192.093707 -273.812866) (xy 192.1292 -273.846958)
			(xy 192.158765 -273.886302) (xy 192.181636 -273.929879) (xy 192.19722 -273.97656) (xy 192.205115 -274.025137)
			(xy 192.20561 -274.049744) (xy 192.205115 -274.074351) (xy 192.204936 -274.075452) (xy 192.523106 -274.075452)
			(xy 192.523106 -274.024036) (xy 192.531149 -273.973254) (xy 192.547037 -273.924355) (xy 192.57038 -273.878543)
			(xy 192.600601 -273.836947) (xy 192.636957 -273.800591) (xy 192.678553 -273.77037) (xy 192.724365 -273.747027)
			(xy 192.773264 -273.731139) (xy 192.824046 -273.723096) (xy 192.875462 -273.723096) (xy 192.926244 -273.731139)
			(xy 192.975143 -273.747027) (xy 193.020955 -273.77037) (xy 193.062551 -273.800591) (xy 193.098907 -273.836947)
			(xy 193.129128 -273.878543) (xy 193.152471 -273.924355) (xy 193.168359 -273.973254) (xy 193.176402 -274.024036)
			(xy 193.176906 -274.049744) (xy 193.494418 -274.049744) (xy 193.498378 -274.00069) (xy 193.510155 -273.952906)
			(xy 193.529446 -273.90763) (xy 193.555749 -273.866034) (xy 193.588384 -273.829197) (xy 193.626505 -273.798072)
			(xy 193.669126 -273.773465) (xy 193.715142 -273.756013) (xy 193.763361 -273.746169) (xy 193.812536 -273.744188)
			(xy 193.861391 -273.75012) (xy 193.908662 -273.763812) (xy 193.953124 -273.78491) (xy 193.993627 -273.812866)
			(xy 194.02912 -273.846958) (xy 194.058685 -273.886302) (xy 194.081556 -273.929879) (xy 194.09714 -273.97656)
			(xy 194.105035 -274.025137) (xy 194.10553 -274.049744) (xy 194.105035 -274.074351) (xy 194.104856 -274.075452)
			(xy 194.423026 -274.075452) (xy 194.423026 -274.024036) (xy 194.431069 -273.973254) (xy 194.446957 -273.924355)
			(xy 194.4703 -273.878543) (xy 194.500521 -273.836947) (xy 194.536877 -273.800591) (xy 194.578473 -273.77037)
			(xy 194.624285 -273.747027) (xy 194.673184 -273.731139) (xy 194.723966 -273.723096) (xy 194.775382 -273.723096)
			(xy 194.826164 -273.731139) (xy 194.875063 -273.747027) (xy 194.920875 -273.77037) (xy 194.962471 -273.800591)
			(xy 194.998827 -273.836947) (xy 195.029048 -273.878543) (xy 195.052391 -273.924355) (xy 195.068279 -273.973254)
			(xy 195.076322 -274.024036) (xy 195.076826 -274.049744) (xy 195.394338 -274.049744) (xy 195.398298 -274.00069)
			(xy 195.410075 -273.952906) (xy 195.429366 -273.90763) (xy 195.455669 -273.866034) (xy 195.488304 -273.829197)
			(xy 195.526425 -273.798072) (xy 195.569046 -273.773465) (xy 195.615062 -273.756013) (xy 195.663281 -273.746169)
			(xy 195.712456 -273.744188) (xy 195.761311 -273.75012) (xy 195.808582 -273.763812) (xy 195.853044 -273.78491)
			(xy 195.893547 -273.812866) (xy 195.92904 -273.846958) (xy 195.958605 -273.886302) (xy 195.981476 -273.929879)
			(xy 195.99706 -273.97656) (xy 196.004955 -274.025137) (xy 196.00545 -274.049744) (xy 196.004955 -274.074351)
			(xy 196.004776 -274.075452) (xy 196.322946 -274.075452) (xy 196.322946 -274.024036) (xy 196.330989 -273.973254)
			(xy 196.346877 -273.924355) (xy 196.37022 -273.878543) (xy 196.400441 -273.836947) (xy 196.436797 -273.800591)
			(xy 196.478393 -273.77037) (xy 196.524205 -273.747027) (xy 196.573104 -273.731139) (xy 196.623886 -273.723096)
			(xy 196.675302 -273.723096) (xy 196.726084 -273.731139) (xy 196.774983 -273.747027) (xy 196.820795 -273.77037)
			(xy 196.862391 -273.800591) (xy 196.898747 -273.836947) (xy 196.928968 -273.878543) (xy 196.952311 -273.924355)
			(xy 196.968199 -273.973254) (xy 196.976242 -274.024036) (xy 196.976746 -274.049744) (xy 197.294258 -274.049744)
			(xy 197.298218 -274.00069) (xy 197.309995 -273.952906) (xy 197.329286 -273.90763) (xy 197.355589 -273.866034)
			(xy 197.388224 -273.829197) (xy 197.426345 -273.798072) (xy 197.468966 -273.773465) (xy 197.514982 -273.756013)
			(xy 197.563201 -273.746169) (xy 197.612376 -273.744188) (xy 197.661231 -273.75012) (xy 197.708502 -273.763812)
			(xy 197.752964 -273.78491) (xy 197.793467 -273.812866) (xy 197.82896 -273.846958) (xy 197.858525 -273.886302)
			(xy 197.881396 -273.929879) (xy 197.89698 -273.97656) (xy 197.904875 -274.025137) (xy 197.90537 -274.049744)
			(xy 198.244218 -274.049744) (xy 198.248178 -274.00069) (xy 198.259955 -273.952906) (xy 198.279246 -273.90763)
			(xy 198.305549 -273.866034) (xy 198.338184 -273.829197) (xy 198.376305 -273.798072) (xy 198.418926 -273.773465)
			(xy 198.464942 -273.756013) (xy 198.513161 -273.746169) (xy 198.562336 -273.744188) (xy 198.611191 -273.75012)
			(xy 198.658462 -273.763812) (xy 198.702924 -273.78491) (xy 198.743427 -273.812866) (xy 198.77892 -273.846958)
			(xy 198.808485 -273.886302) (xy 198.831356 -273.929879) (xy 198.84694 -273.97656) (xy 198.854835 -274.025137)
			(xy 198.85533 -274.049744) (xy 198.854835 -274.074351) (xy 198.84694 -274.122928) (xy 198.831356 -274.169609)
			(xy 198.808485 -274.213186) (xy 198.77892 -274.25253) (xy 198.743427 -274.286622) (xy 198.702924 -274.314578)
			(xy 198.658462 -274.335676) (xy 198.611191 -274.349368) (xy 198.562336 -274.3553) (xy 198.513161 -274.353319)
			(xy 198.464942 -274.343475) (xy 198.418926 -274.326023) (xy 198.376305 -274.301416) (xy 198.338184 -274.270291)
			(xy 198.305549 -274.233454) (xy 198.279246 -274.191858) (xy 198.259955 -274.146582) (xy 198.248178 -274.098798)
			(xy 198.244218 -274.049744) (xy 197.90537 -274.049744) (xy 197.904875 -274.074351) (xy 197.89698 -274.122928)
			(xy 197.881396 -274.169609) (xy 197.858525 -274.213186) (xy 197.82896 -274.25253) (xy 197.793467 -274.286622)
			(xy 197.752964 -274.314578) (xy 197.708502 -274.335676) (xy 197.661231 -274.349368) (xy 197.612376 -274.3553)
			(xy 197.563201 -274.353319) (xy 197.514982 -274.343475) (xy 197.468966 -274.326023) (xy 197.426345 -274.301416)
			(xy 197.388224 -274.270291) (xy 197.355589 -274.233454) (xy 197.329286 -274.191858) (xy 197.309995 -274.146582)
			(xy 197.298218 -274.098798) (xy 197.294258 -274.049744) (xy 196.976746 -274.049744) (xy 196.976242 -274.075452)
			(xy 196.968199 -274.126234) (xy 196.952311 -274.175133) (xy 196.928968 -274.220945) (xy 196.898747 -274.262541)
			(xy 196.862391 -274.298897) (xy 196.820795 -274.329118) (xy 196.774983 -274.352461) (xy 196.726084 -274.368349)
			(xy 196.675302 -274.376392) (xy 196.623886 -274.376392) (xy 196.573104 -274.368349) (xy 196.524205 -274.352461)
			(xy 196.478393 -274.329118) (xy 196.436797 -274.298897) (xy 196.400441 -274.262541) (xy 196.37022 -274.220945)
			(xy 196.346877 -274.175133) (xy 196.330989 -274.126234) (xy 196.322946 -274.075452) (xy 196.004776 -274.075452)
			(xy 195.99706 -274.122928) (xy 195.981476 -274.169609) (xy 195.958605 -274.213186) (xy 195.92904 -274.25253)
			(xy 195.893547 -274.286622) (xy 195.853044 -274.314578) (xy 195.808582 -274.335676) (xy 195.761311 -274.349368)
			(xy 195.712456 -274.3553) (xy 195.663281 -274.353319) (xy 195.615062 -274.343475) (xy 195.569046 -274.326023)
			(xy 195.526425 -274.301416) (xy 195.488304 -274.270291) (xy 195.455669 -274.233454) (xy 195.429366 -274.191858)
			(xy 195.410075 -274.146582) (xy 195.398298 -274.098798) (xy 195.394338 -274.049744) (xy 195.076826 -274.049744)
			(xy 195.076322 -274.075452) (xy 195.068279 -274.126234) (xy 195.052391 -274.175133) (xy 195.029048 -274.220945)
			(xy 194.998827 -274.262541) (xy 194.962471 -274.298897) (xy 194.920875 -274.329118) (xy 194.875063 -274.352461)
			(xy 194.826164 -274.368349) (xy 194.775382 -274.376392) (xy 194.723966 -274.376392) (xy 194.673184 -274.368349)
			(xy 194.624285 -274.352461) (xy 194.578473 -274.329118) (xy 194.536877 -274.298897) (xy 194.500521 -274.262541)
			(xy 194.4703 -274.220945) (xy 194.446957 -274.175133) (xy 194.431069 -274.126234) (xy 194.423026 -274.075452)
			(xy 194.104856 -274.075452) (xy 194.09714 -274.122928) (xy 194.081556 -274.169609) (xy 194.058685 -274.213186)
			(xy 194.02912 -274.25253) (xy 193.993627 -274.286622) (xy 193.953124 -274.314578) (xy 193.908662 -274.335676)
			(xy 193.861391 -274.349368) (xy 193.812536 -274.3553) (xy 193.763361 -274.353319) (xy 193.715142 -274.343475)
			(xy 193.669126 -274.326023) (xy 193.626505 -274.301416) (xy 193.588384 -274.270291) (xy 193.555749 -274.233454)
			(xy 193.529446 -274.191858) (xy 193.510155 -274.146582) (xy 193.498378 -274.098798) (xy 193.494418 -274.049744)
			(xy 193.176906 -274.049744) (xy 193.176402 -274.075452) (xy 193.168359 -274.126234) (xy 193.152471 -274.175133)
			(xy 193.129128 -274.220945) (xy 193.098907 -274.262541) (xy 193.062551 -274.298897) (xy 193.020955 -274.329118)
			(xy 192.975143 -274.352461) (xy 192.926244 -274.368349) (xy 192.875462 -274.376392) (xy 192.824046 -274.376392)
			(xy 192.773264 -274.368349) (xy 192.724365 -274.352461) (xy 192.678553 -274.329118) (xy 192.636957 -274.298897)
			(xy 192.600601 -274.262541) (xy 192.57038 -274.220945) (xy 192.547037 -274.175133) (xy 192.531149 -274.126234)
			(xy 192.523106 -274.075452) (xy 192.204936 -274.075452) (xy 192.19722 -274.122928) (xy 192.181636 -274.169609)
			(xy 192.158765 -274.213186) (xy 192.1292 -274.25253) (xy 192.093707 -274.286622) (xy 192.053204 -274.314578)
			(xy 192.008742 -274.335676) (xy 191.961471 -274.349368) (xy 191.912616 -274.3553) (xy 191.863441 -274.353319)
			(xy 191.815222 -274.343475) (xy 191.769206 -274.326023) (xy 191.726585 -274.301416) (xy 191.688464 -274.270291)
			(xy 191.655829 -274.233454) (xy 191.629526 -274.191858) (xy 191.610235 -274.146582) (xy 191.598458 -274.098798)
			(xy 191.594498 -274.049744) (xy 191.276986 -274.049744) (xy 191.276482 -274.075452) (xy 191.268439 -274.126234)
			(xy 191.252551 -274.175133) (xy 191.229208 -274.220945) (xy 191.198987 -274.262541) (xy 191.162631 -274.298897)
			(xy 191.121035 -274.329118) (xy 191.075223 -274.352461) (xy 191.026324 -274.368349) (xy 190.975542 -274.376392)
			(xy 190.924126 -274.376392) (xy 190.873344 -274.368349) (xy 190.824445 -274.352461) (xy 190.778633 -274.329118)
			(xy 190.737037 -274.298897) (xy 190.700681 -274.262541) (xy 190.67046 -274.220945) (xy 190.647117 -274.175133)
			(xy 190.631229 -274.126234) (xy 190.623186 -274.075452) (xy 190.304508 -274.075452) (xy 190.296792 -274.122928)
			(xy 190.281208 -274.169609) (xy 190.258337 -274.213186) (xy 190.228772 -274.25253) (xy 190.193279 -274.286622)
			(xy 190.152776 -274.314578) (xy 190.108314 -274.335676) (xy 190.061043 -274.349368) (xy 190.012188 -274.3553)
			(xy 189.963013 -274.353319) (xy 189.914794 -274.343475) (xy 189.868778 -274.326023) (xy 189.826157 -274.301416)
			(xy 189.788036 -274.270291) (xy 189.755401 -274.233454) (xy 189.729098 -274.191858) (xy 189.709807 -274.146582)
			(xy 189.69803 -274.098798) (xy 189.69407 -274.049744) (xy 189.376812 -274.049744) (xy 189.376308 -274.075452)
			(xy 189.368265 -274.126234) (xy 189.352377 -274.175133) (xy 189.329034 -274.220945) (xy 189.298813 -274.262541)
			(xy 189.262457 -274.298897) (xy 189.220861 -274.329118) (xy 189.175049 -274.352461) (xy 189.12615 -274.368349)
			(xy 189.075368 -274.376392) (xy 189.023952 -274.376392) (xy 188.97317 -274.368349) (xy 188.924271 -274.352461)
			(xy 188.878459 -274.329118) (xy 188.836863 -274.298897) (xy 188.800507 -274.262541) (xy 188.770286 -274.220945)
			(xy 188.746943 -274.175133) (xy 188.731055 -274.126234) (xy 188.723012 -274.075452) (xy 188.404588 -274.075452)
			(xy 188.396872 -274.122928) (xy 188.381288 -274.169609) (xy 188.358417 -274.213186) (xy 188.328852 -274.25253)
			(xy 188.293359 -274.286622) (xy 188.252856 -274.314578) (xy 188.208394 -274.335676) (xy 188.161123 -274.349368)
			(xy 188.112268 -274.3553) (xy 188.063093 -274.353319) (xy 188.014874 -274.343475) (xy 187.968858 -274.326023)
			(xy 187.926237 -274.301416) (xy 187.888116 -274.270291) (xy 187.855481 -274.233454) (xy 187.829178 -274.191858)
			(xy 187.809887 -274.146582) (xy 187.79811 -274.098798) (xy 187.79415 -274.049744) (xy 187.476892 -274.049744)
			(xy 187.476388 -274.075452) (xy 187.468345 -274.126234) (xy 187.452457 -274.175133) (xy 187.429114 -274.220945)
			(xy 187.398893 -274.262541) (xy 187.362537 -274.298897) (xy 187.320941 -274.329118) (xy 187.275129 -274.352461)
			(xy 187.22623 -274.368349) (xy 187.175448 -274.376392) (xy 187.124032 -274.376392) (xy 187.07325 -274.368349)
			(xy 187.024351 -274.352461) (xy 186.978539 -274.329118) (xy 186.936943 -274.298897) (xy 186.900587 -274.262541)
			(xy 186.870366 -274.220945) (xy 186.847023 -274.175133) (xy 186.831135 -274.126234) (xy 186.823092 -274.075452)
			(xy 186.504668 -274.075452) (xy 186.496952 -274.122928) (xy 186.481368 -274.169609) (xy 186.458497 -274.213186)
			(xy 186.428932 -274.25253) (xy 186.393439 -274.286622) (xy 186.352936 -274.314578) (xy 186.308474 -274.335676)
			(xy 186.261203 -274.349368) (xy 186.212348 -274.3553) (xy 186.163173 -274.353319) (xy 186.114954 -274.343475)
			(xy 186.068938 -274.326023) (xy 186.026317 -274.301416) (xy 185.988196 -274.270291) (xy 185.955561 -274.233454)
			(xy 185.929258 -274.191858) (xy 185.909967 -274.146582) (xy 185.89819 -274.098798) (xy 185.89423 -274.049744)
			(xy 185.576972 -274.049744) (xy 185.576468 -274.075452) (xy 185.568425 -274.126234) (xy 185.552537 -274.175133)
			(xy 185.529194 -274.220945) (xy 185.498973 -274.262541) (xy 185.462617 -274.298897) (xy 185.421021 -274.329118)
			(xy 185.375209 -274.352461) (xy 185.32631 -274.368349) (xy 185.275528 -274.376392) (xy 185.224112 -274.376392)
			(xy 185.17333 -274.368349) (xy 185.124431 -274.352461) (xy 185.078619 -274.329118) (xy 185.037023 -274.298897)
			(xy 185.000667 -274.262541) (xy 184.970446 -274.220945) (xy 184.947103 -274.175133) (xy 184.931215 -274.126234)
			(xy 184.923172 -274.075452) (xy 184.604494 -274.075452) (xy 184.596778 -274.122928) (xy 184.581194 -274.169609)
			(xy 184.558323 -274.213186) (xy 184.528758 -274.25253) (xy 184.493265 -274.286622) (xy 184.452762 -274.314578)
			(xy 184.4083 -274.335676) (xy 184.361029 -274.349368) (xy 184.312174 -274.3553) (xy 184.262999 -274.353319)
			(xy 184.21478 -274.343475) (xy 184.168764 -274.326023) (xy 184.126143 -274.301416) (xy 184.088022 -274.270291)
			(xy 184.055387 -274.233454) (xy 184.029084 -274.191858) (xy 184.009793 -274.146582) (xy 183.998016 -274.098798)
			(xy 183.994056 -274.049744) (xy 183.676798 -274.049744) (xy 183.676294 -274.075452) (xy 183.668251 -274.126234)
			(xy 183.652363 -274.175133) (xy 183.62902 -274.220945) (xy 183.598799 -274.262541) (xy 183.562443 -274.298897)
			(xy 183.520847 -274.329118) (xy 183.475035 -274.352461) (xy 183.426136 -274.368349) (xy 183.375354 -274.376392)
			(xy 183.323938 -274.376392) (xy 183.273156 -274.368349) (xy 183.224257 -274.352461) (xy 183.178445 -274.329118)
			(xy 183.136849 -274.298897) (xy 183.100493 -274.262541) (xy 183.070272 -274.220945) (xy 183.046929 -274.175133)
			(xy 183.031041 -274.126234) (xy 183.022998 -274.075452) (xy 182.704574 -274.075452) (xy 182.696858 -274.122928)
			(xy 182.681274 -274.169609) (xy 182.658403 -274.213186) (xy 182.628838 -274.25253) (xy 182.593345 -274.286622)
			(xy 182.552842 -274.314578) (xy 182.50838 -274.335676) (xy 182.461109 -274.349368) (xy 182.412254 -274.3553)
			(xy 182.363079 -274.353319) (xy 182.31486 -274.343475) (xy 182.268844 -274.326023) (xy 182.226223 -274.301416)
			(xy 182.188102 -274.270291) (xy 182.155467 -274.233454) (xy 182.129164 -274.191858) (xy 182.109873 -274.146582)
			(xy 182.098096 -274.098798) (xy 182.094136 -274.049744) (xy 181.776878 -274.049744) (xy 181.776374 -274.075452)
			(xy 181.768331 -274.126234) (xy 181.752443 -274.175133) (xy 181.7291 -274.220945) (xy 181.698879 -274.262541)
			(xy 181.662523 -274.298897) (xy 181.620927 -274.329118) (xy 181.575115 -274.352461) (xy 181.526216 -274.368349)
			(xy 181.475434 -274.376392) (xy 181.424018 -274.376392) (xy 181.373236 -274.368349) (xy 181.324337 -274.352461)
			(xy 181.278525 -274.329118) (xy 181.236929 -274.298897) (xy 181.200573 -274.262541) (xy 181.170352 -274.220945)
			(xy 181.147009 -274.175133) (xy 181.131121 -274.126234) (xy 181.123078 -274.075452) (xy 180.804654 -274.075452)
			(xy 180.796938 -274.122928) (xy 180.781354 -274.169609) (xy 180.758483 -274.213186) (xy 180.728918 -274.25253)
			(xy 180.693425 -274.286622) (xy 180.652922 -274.314578) (xy 180.60846 -274.335676) (xy 180.561189 -274.349368)
			(xy 180.512334 -274.3553) (xy 180.463159 -274.353319) (xy 180.41494 -274.343475) (xy 180.368924 -274.326023)
			(xy 180.326303 -274.301416) (xy 180.288182 -274.270291) (xy 180.255547 -274.233454) (xy 180.229244 -274.191858)
			(xy 180.209953 -274.146582) (xy 180.198176 -274.098798) (xy 180.194216 -274.049744) (xy 179.876958 -274.049744)
			(xy 179.876454 -274.075452) (xy 179.868411 -274.126234) (xy 179.852523 -274.175133) (xy 179.82918 -274.220945)
			(xy 179.798959 -274.262541) (xy 179.762603 -274.298897) (xy 179.721007 -274.329118) (xy 179.675195 -274.352461)
			(xy 179.626296 -274.368349) (xy 179.575514 -274.376392) (xy 179.524098 -274.376392) (xy 179.473316 -274.368349)
			(xy 179.424417 -274.352461) (xy 179.378605 -274.329118) (xy 179.337009 -274.298897) (xy 179.300653 -274.262541)
			(xy 179.270432 -274.220945) (xy 179.247089 -274.175133) (xy 179.231201 -274.126234) (xy 179.223158 -274.075452)
			(xy 178.90448 -274.075452) (xy 178.896764 -274.122928) (xy 178.88118 -274.169609) (xy 178.858309 -274.213186)
			(xy 178.828744 -274.25253) (xy 178.793251 -274.286622) (xy 178.752748 -274.314578) (xy 178.708286 -274.335676)
			(xy 178.661015 -274.349368) (xy 178.61216 -274.3553) (xy 178.562985 -274.353319) (xy 178.514766 -274.343475)
			(xy 178.46875 -274.326023) (xy 178.426129 -274.301416) (xy 178.388008 -274.270291) (xy 178.355373 -274.233454)
			(xy 178.32907 -274.191858) (xy 178.309779 -274.146582) (xy 178.298002 -274.098798) (xy 178.294042 -274.049744)
			(xy 177.976784 -274.049744) (xy 177.97628 -274.075452) (xy 177.968237 -274.126234) (xy 177.952349 -274.175133)
			(xy 177.929006 -274.220945) (xy 177.898785 -274.262541) (xy 177.862429 -274.298897) (xy 177.820833 -274.329118)
			(xy 177.775021 -274.352461) (xy 177.726122 -274.368349) (xy 177.67534 -274.376392) (xy 177.623924 -274.376392)
			(xy 177.573142 -274.368349) (xy 177.524243 -274.352461) (xy 177.478431 -274.329118) (xy 177.436835 -274.298897)
			(xy 177.400479 -274.262541) (xy 177.370258 -274.220945) (xy 177.346915 -274.175133) (xy 177.331027 -274.126234)
			(xy 177.322984 -274.075452) (xy 177.00456 -274.075452) (xy 176.996844 -274.122928) (xy 176.98126 -274.169609)
			(xy 176.958389 -274.213186) (xy 176.928824 -274.25253) (xy 176.893331 -274.286622) (xy 176.852828 -274.314578)
			(xy 176.808366 -274.335676) (xy 176.761095 -274.349368) (xy 176.71224 -274.3553) (xy 176.663065 -274.353319)
			(xy 176.614846 -274.343475) (xy 176.56883 -274.326023) (xy 176.526209 -274.301416) (xy 176.488088 -274.270291)
			(xy 176.455453 -274.233454) (xy 176.42915 -274.191858) (xy 176.409859 -274.146582) (xy 176.398082 -274.098798)
			(xy 176.394122 -274.049744) (xy 176.076104 -274.049744) (xy 176.076104 -274.075188) (xy 176.068067 -274.125931)
			(xy 176.052192 -274.174793) (xy 176.028868 -274.220569) (xy 175.998671 -274.262134) (xy 175.962343 -274.298463)
			(xy 175.92078 -274.328662) (xy 175.875004 -274.351987) (xy 175.826143 -274.367865) (xy 175.7754 -274.375903)
			(xy 175.749712 -274.376388) (xy 175.749204 -274.376388) (xy 175.723996 -274.375877) (xy 175.674189 -274.368055)
			(xy 175.626171 -274.352687) (xy 175.603408 -274.341844) (xy 175.6029 -274.341844) (xy 175.602646 -274.34159)
			(xy 175.596948 -274.339057) (xy 175.584751 -274.336486) (xy 175.578516 -274.33651) (xy 175.565054 -274.337018)
			(xy 175.480218 -274.389342) (xy 175.47971 -274.389596) (xy 175.479202 -274.390104) (xy 175.470406 -274.396394)
			(xy 175.458692 -274.414548) (xy 175.456596 -274.425156) (xy 175.456088 -274.432522) (xy 175.456088 -274.641564)
			(xy 175.456342 -274.646898) (xy 175.457749 -274.656229) (xy 175.466496 -274.672934) (xy 175.47336 -274.67941)
			(xy 175.48098 -274.684998) (xy 175.55591 -274.729702) (xy 175.561592 -274.732848) (xy 175.574064 -274.736459)
			(xy 175.580548 -274.736814) (xy 175.593756 -274.737322) (xy 175.605694 -274.730972) (xy 175.62801 -274.719552)
			(xy 175.675451 -274.703367) (xy 175.724903 -274.695169) (xy 175.749966 -274.69465) (xy 175.775229 -274.69514)
			(xy 175.825067 -274.703451) (xy 175.872856 -274.719853) (xy 175.917295 -274.743897) (xy 175.957169 -274.774928)
			(xy 175.991391 -274.8121) (xy 176.019028 -274.854397) (xy 176.039325 -274.900667) (xy 176.051729 -274.949647)
			(xy 176.055902 -275) (xy 176.053796 -275.025412) (xy 176.373024 -275.025412) (xy 176.373024 -274.973996)
			(xy 176.381067 -274.923214) (xy 176.396955 -274.874315) (xy 176.420298 -274.828503) (xy 176.450519 -274.786907)
			(xy 176.486875 -274.750551) (xy 176.528471 -274.72033) (xy 176.574283 -274.696987) (xy 176.623182 -274.681099)
			(xy 176.673964 -274.673056) (xy 176.72538 -274.673056) (xy 176.776162 -274.681099) (xy 176.825061 -274.696987)
			(xy 176.870873 -274.72033) (xy 176.912469 -274.750551) (xy 176.948825 -274.786907) (xy 176.979046 -274.828503)
			(xy 177.002389 -274.874315) (xy 177.018277 -274.923214) (xy 177.02632 -274.973996) (xy 177.026824 -274.999704)
			(xy 177.026819 -274.999958) (xy 177.344082 -274.999958) (xy 177.348042 -274.950904) (xy 177.359819 -274.90312)
			(xy 177.37911 -274.857844) (xy 177.405413 -274.816248) (xy 177.438048 -274.779411) (xy 177.476169 -274.748286)
			(xy 177.51879 -274.723679) (xy 177.564806 -274.706227) (xy 177.613025 -274.696383) (xy 177.6622 -274.694402)
			(xy 177.711055 -274.700334) (xy 177.758326 -274.714026) (xy 177.802788 -274.735124) (xy 177.843291 -274.76308)
			(xy 177.878784 -274.797172) (xy 177.908349 -274.836516) (xy 177.93122 -274.880093) (xy 177.946804 -274.926774)
			(xy 177.954699 -274.975351) (xy 177.955194 -274.999958) (xy 177.954699 -275.024565) (xy 177.95452 -275.025666)
			(xy 178.272944 -275.025666) (xy 178.272944 -274.97425) (xy 178.280987 -274.923468) (xy 178.296875 -274.874569)
			(xy 178.320218 -274.828757) (xy 178.350439 -274.787161) (xy 178.386795 -274.750805) (xy 178.428391 -274.720584)
			(xy 178.474203 -274.697241) (xy 178.523102 -274.681353) (xy 178.573884 -274.67331) (xy 178.6253 -274.67331)
			(xy 178.676082 -274.681353) (xy 178.724981 -274.697241) (xy 178.770793 -274.720584) (xy 178.812389 -274.750805)
			(xy 178.848745 -274.787161) (xy 178.878966 -274.828757) (xy 178.902309 -274.874569) (xy 178.918197 -274.923468)
			(xy 178.92624 -274.97425) (xy 178.926744 -274.999958) (xy 179.244256 -274.999958) (xy 179.248216 -274.950904)
			(xy 179.259993 -274.90312) (xy 179.279284 -274.857844) (xy 179.305587 -274.816248) (xy 179.338222 -274.779411)
			(xy 179.376343 -274.748286) (xy 179.418964 -274.723679) (xy 179.46498 -274.706227) (xy 179.513199 -274.696383)
			(xy 179.562374 -274.694402) (xy 179.611229 -274.700334) (xy 179.6585 -274.714026) (xy 179.702962 -274.735124)
			(xy 179.743465 -274.76308) (xy 179.778958 -274.797172) (xy 179.808523 -274.836516) (xy 179.831394 -274.880093)
			(xy 179.846978 -274.926774) (xy 179.854873 -274.975351) (xy 179.855368 -274.999958) (xy 179.854873 -275.024565)
			(xy 179.854735 -275.025412) (xy 180.173118 -275.025412) (xy 180.173118 -274.973996) (xy 180.181161 -274.923214)
			(xy 180.197049 -274.874315) (xy 180.220392 -274.828503) (xy 180.250613 -274.786907) (xy 180.286969 -274.750551)
			(xy 180.328565 -274.72033) (xy 180.374377 -274.696987) (xy 180.423276 -274.681099) (xy 180.474058 -274.673056)
			(xy 180.525474 -274.673056) (xy 180.576256 -274.681099) (xy 180.625155 -274.696987) (xy 180.670967 -274.72033)
			(xy 180.712563 -274.750551) (xy 180.748919 -274.786907) (xy 180.77914 -274.828503) (xy 180.802483 -274.874315)
			(xy 180.818371 -274.923214) (xy 180.826414 -274.973996) (xy 180.826918 -274.999704) (xy 180.826913 -274.999958)
			(xy 181.144176 -274.999958) (xy 181.148136 -274.950904) (xy 181.159913 -274.90312) (xy 181.179204 -274.857844)
			(xy 181.205507 -274.816248) (xy 181.238142 -274.779411) (xy 181.276263 -274.748286) (xy 181.318884 -274.723679)
			(xy 181.3649 -274.706227) (xy 181.413119 -274.696383) (xy 181.462294 -274.694402) (xy 181.511149 -274.700334)
			(xy 181.55842 -274.714026) (xy 181.602882 -274.735124) (xy 181.643385 -274.76308) (xy 181.678878 -274.797172)
			(xy 181.708443 -274.836516) (xy 181.731314 -274.880093) (xy 181.746898 -274.926774) (xy 181.754793 -274.975351)
			(xy 181.755288 -274.999958) (xy 181.754793 -275.024565) (xy 181.754614 -275.025666) (xy 182.073038 -275.025666)
			(xy 182.073038 -274.97425) (xy 182.081081 -274.923468) (xy 182.096969 -274.874569) (xy 182.120312 -274.828757)
			(xy 182.150533 -274.787161) (xy 182.186889 -274.750805) (xy 182.228485 -274.720584) (xy 182.274297 -274.697241)
			(xy 182.323196 -274.681353) (xy 182.373978 -274.67331) (xy 182.425394 -274.67331) (xy 182.476176 -274.681353)
			(xy 182.525075 -274.697241) (xy 182.570887 -274.720584) (xy 182.612483 -274.750805) (xy 182.648839 -274.787161)
			(xy 182.67906 -274.828757) (xy 182.702403 -274.874569) (xy 182.718291 -274.923468) (xy 182.726334 -274.97425)
			(xy 182.726838 -274.999958) (xy 183.044096 -274.999958) (xy 183.048056 -274.950904) (xy 183.059833 -274.90312)
			(xy 183.079124 -274.857844) (xy 183.105427 -274.816248) (xy 183.138062 -274.779411) (xy 183.176183 -274.748286)
			(xy 183.218804 -274.723679) (xy 183.26482 -274.706227) (xy 183.313039 -274.696383) (xy 183.362214 -274.694402)
			(xy 183.411069 -274.700334) (xy 183.45834 -274.714026) (xy 183.502802 -274.735124) (xy 183.543305 -274.76308)
			(xy 183.578798 -274.797172) (xy 183.608363 -274.836516) (xy 183.631234 -274.880093) (xy 183.646818 -274.926774)
			(xy 183.654713 -274.975351) (xy 183.655208 -274.999958) (xy 183.654713 -275.024565) (xy 183.654575 -275.025412)
			(xy 183.972958 -275.025412) (xy 183.972958 -274.973996) (xy 183.981001 -274.923214) (xy 183.996889 -274.874315)
			(xy 184.020232 -274.828503) (xy 184.050453 -274.786907) (xy 184.086809 -274.750551) (xy 184.128405 -274.72033)
			(xy 184.174217 -274.696987) (xy 184.223116 -274.681099) (xy 184.273898 -274.673056) (xy 184.325314 -274.673056)
			(xy 184.376096 -274.681099) (xy 184.424995 -274.696987) (xy 184.470807 -274.72033) (xy 184.512403 -274.750551)
			(xy 184.548759 -274.786907) (xy 184.57898 -274.828503) (xy 184.602323 -274.874315) (xy 184.618211 -274.923214)
			(xy 184.626254 -274.973996) (xy 184.626758 -274.999704) (xy 184.626753 -274.999958) (xy 184.94427 -274.999958)
			(xy 184.94823 -274.950904) (xy 184.960007 -274.90312) (xy 184.979298 -274.857844) (xy 185.005601 -274.816248)
			(xy 185.038236 -274.779411) (xy 185.076357 -274.748286) (xy 185.118978 -274.723679) (xy 185.164994 -274.706227)
			(xy 185.213213 -274.696383) (xy 185.262388 -274.694402) (xy 185.311243 -274.700334) (xy 185.358514 -274.714026)
			(xy 185.402976 -274.735124) (xy 185.443479 -274.76308) (xy 185.478972 -274.797172) (xy 185.508537 -274.836516)
			(xy 185.531408 -274.880093) (xy 185.546992 -274.926774) (xy 185.554887 -274.975351) (xy 185.555382 -274.999958)
			(xy 185.554887 -275.024565) (xy 185.554708 -275.025666) (xy 185.872878 -275.025666) (xy 185.872878 -274.97425)
			(xy 185.880921 -274.923468) (xy 185.896809 -274.874569) (xy 185.920152 -274.828757) (xy 185.950373 -274.787161)
			(xy 185.986729 -274.750805) (xy 186.028325 -274.720584) (xy 186.074137 -274.697241) (xy 186.123036 -274.681353)
			(xy 186.173818 -274.67331) (xy 186.225234 -274.67331) (xy 186.276016 -274.681353) (xy 186.324915 -274.697241)
			(xy 186.370727 -274.720584) (xy 186.412323 -274.750805) (xy 186.448679 -274.787161) (xy 186.4789 -274.828757)
			(xy 186.502243 -274.874569) (xy 186.518131 -274.923468) (xy 186.526174 -274.97425) (xy 186.526678 -274.999958)
			(xy 186.84419 -274.999958) (xy 186.84815 -274.950904) (xy 186.859927 -274.90312) (xy 186.879218 -274.857844)
			(xy 186.905521 -274.816248) (xy 186.938156 -274.779411) (xy 186.976277 -274.748286) (xy 187.018898 -274.723679)
			(xy 187.064914 -274.706227) (xy 187.113133 -274.696383) (xy 187.162308 -274.694402) (xy 187.211163 -274.700334)
			(xy 187.258434 -274.714026) (xy 187.302896 -274.735124) (xy 187.343399 -274.76308) (xy 187.378892 -274.797172)
			(xy 187.408457 -274.836516) (xy 187.431328 -274.880093) (xy 187.446912 -274.926774) (xy 187.454807 -274.975351)
			(xy 187.455302 -274.999958) (xy 187.454807 -275.024565) (xy 187.454669 -275.025412) (xy 187.773052 -275.025412)
			(xy 187.773052 -274.973996) (xy 187.781095 -274.923214) (xy 187.796983 -274.874315) (xy 187.820326 -274.828503)
			(xy 187.850547 -274.786907) (xy 187.886903 -274.750551) (xy 187.928499 -274.72033) (xy 187.974311 -274.696987)
			(xy 188.02321 -274.681099) (xy 188.073992 -274.673056) (xy 188.125408 -274.673056) (xy 188.17619 -274.681099)
			(xy 188.225089 -274.696987) (xy 188.270901 -274.72033) (xy 188.312497 -274.750551) (xy 188.348853 -274.786907)
			(xy 188.379074 -274.828503) (xy 188.402417 -274.874315) (xy 188.418305 -274.923214) (xy 188.426348 -274.973996)
			(xy 188.426852 -274.999704) (xy 188.426847 -274.999958) (xy 188.74411 -274.999958) (xy 188.74807 -274.950904)
			(xy 188.759847 -274.90312) (xy 188.779138 -274.857844) (xy 188.805441 -274.816248) (xy 188.838076 -274.779411)
			(xy 188.876197 -274.748286) (xy 188.918818 -274.723679) (xy 188.964834 -274.706227) (xy 189.013053 -274.696383)
			(xy 189.062228 -274.694402) (xy 189.111083 -274.700334) (xy 189.158354 -274.714026) (xy 189.202816 -274.735124)
			(xy 189.243319 -274.76308) (xy 189.278812 -274.797172) (xy 189.308377 -274.836516) (xy 189.331248 -274.880093)
			(xy 189.346832 -274.926774) (xy 189.354727 -274.975351) (xy 189.355222 -274.999958) (xy 189.354727 -275.024565)
			(xy 189.354548 -275.025666) (xy 189.672972 -275.025666) (xy 189.672972 -274.97425) (xy 189.681015 -274.923468)
			(xy 189.696903 -274.874569) (xy 189.720246 -274.828757) (xy 189.750467 -274.787161) (xy 189.786823 -274.750805)
			(xy 189.828419 -274.720584) (xy 189.874231 -274.697241) (xy 189.92313 -274.681353) (xy 189.973912 -274.67331)
			(xy 190.025328 -274.67331) (xy 190.07611 -274.681353) (xy 190.125009 -274.697241) (xy 190.170821 -274.720584)
			(xy 190.212417 -274.750805) (xy 190.248773 -274.787161) (xy 190.278994 -274.828757) (xy 190.302337 -274.874569)
			(xy 190.318225 -274.923468) (xy 190.326268 -274.97425) (xy 190.326772 -274.999958) (xy 190.64403 -274.999958)
			(xy 190.64799 -274.950904) (xy 190.659767 -274.90312) (xy 190.679058 -274.857844) (xy 190.705361 -274.816248)
			(xy 190.737996 -274.779411) (xy 190.776117 -274.748286) (xy 190.818738 -274.723679) (xy 190.864754 -274.706227)
			(xy 190.912973 -274.696383) (xy 190.962148 -274.694402) (xy 191.011003 -274.700334) (xy 191.058274 -274.714026)
			(xy 191.102736 -274.735124) (xy 191.143239 -274.76308) (xy 191.178732 -274.797172) (xy 191.208297 -274.836516)
			(xy 191.231168 -274.880093) (xy 191.246752 -274.926774) (xy 191.254647 -274.975351) (xy 191.255142 -274.999958)
			(xy 191.254647 -275.024565) (xy 191.254509 -275.025412) (xy 191.573146 -275.025412) (xy 191.573146 -274.973996)
			(xy 191.581189 -274.923214) (xy 191.597077 -274.874315) (xy 191.62042 -274.828503) (xy 191.650641 -274.786907)
			(xy 191.686997 -274.750551) (xy 191.728593 -274.72033) (xy 191.774405 -274.696987) (xy 191.823304 -274.681099)
			(xy 191.874086 -274.673056) (xy 191.925502 -274.673056) (xy 191.976284 -274.681099) (xy 192.025183 -274.696987)
			(xy 192.070995 -274.72033) (xy 192.112591 -274.750551) (xy 192.148947 -274.786907) (xy 192.179168 -274.828503)
			(xy 192.202511 -274.874315) (xy 192.218399 -274.923214) (xy 192.226442 -274.973996) (xy 192.226946 -274.999704)
			(xy 192.226941 -274.999958) (xy 192.54395 -274.999958) (xy 192.54791 -274.950904) (xy 192.559687 -274.90312)
			(xy 192.578978 -274.857844) (xy 192.605281 -274.816248) (xy 192.637916 -274.779411) (xy 192.676037 -274.748286)
			(xy 192.718658 -274.723679) (xy 192.764674 -274.706227) (xy 192.812893 -274.696383) (xy 192.862068 -274.694402)
			(xy 192.910923 -274.700334) (xy 192.958194 -274.714026) (xy 193.002656 -274.735124) (xy 193.043159 -274.76308)
			(xy 193.078652 -274.797172) (xy 193.108217 -274.836516) (xy 193.131088 -274.880093) (xy 193.146672 -274.926774)
			(xy 193.154567 -274.975351) (xy 193.155062 -274.999958) (xy 193.154567 -275.024565) (xy 193.154388 -275.025666)
			(xy 193.473066 -275.025666) (xy 193.473066 -274.97425) (xy 193.481109 -274.923468) (xy 193.496997 -274.874569)
			(xy 193.52034 -274.828757) (xy 193.550561 -274.787161) (xy 193.586917 -274.750805) (xy 193.628513 -274.720584)
			(xy 193.674325 -274.697241) (xy 193.723224 -274.681353) (xy 193.774006 -274.67331) (xy 193.825422 -274.67331)
			(xy 193.876204 -274.681353) (xy 193.925103 -274.697241) (xy 193.970915 -274.720584) (xy 194.012511 -274.750805)
			(xy 194.048867 -274.787161) (xy 194.079088 -274.828757) (xy 194.102431 -274.874569) (xy 194.118319 -274.923468)
			(xy 194.126362 -274.97425) (xy 194.126866 -274.999958) (xy 194.44387 -274.999958) (xy 194.44783 -274.950904)
			(xy 194.459607 -274.90312) (xy 194.478898 -274.857844) (xy 194.505201 -274.816248) (xy 194.537836 -274.779411)
			(xy 194.575957 -274.748286) (xy 194.618578 -274.723679) (xy 194.664594 -274.706227) (xy 194.712813 -274.696383)
			(xy 194.761988 -274.694402) (xy 194.810843 -274.700334) (xy 194.858114 -274.714026) (xy 194.902576 -274.735124)
			(xy 194.943079 -274.76308) (xy 194.978572 -274.797172) (xy 195.008137 -274.836516) (xy 195.031008 -274.880093)
			(xy 195.046592 -274.926774) (xy 195.054487 -274.975351) (xy 195.054982 -274.999958) (xy 195.054487 -275.024565)
			(xy 195.054308 -275.025666) (xy 195.372986 -275.025666) (xy 195.372986 -274.97425) (xy 195.381029 -274.923468)
			(xy 195.396917 -274.874569) (xy 195.42026 -274.828757) (xy 195.450481 -274.787161) (xy 195.486837 -274.750805)
			(xy 195.528433 -274.720584) (xy 195.574245 -274.697241) (xy 195.623144 -274.681353) (xy 195.673926 -274.67331)
			(xy 195.725342 -274.67331) (xy 195.776124 -274.681353) (xy 195.825023 -274.697241) (xy 195.870835 -274.720584)
			(xy 195.912431 -274.750805) (xy 195.948787 -274.787161) (xy 195.979008 -274.828757) (xy 196.002351 -274.874569)
			(xy 196.018239 -274.923468) (xy 196.026282 -274.97425) (xy 196.026786 -274.999958) (xy 196.344044 -274.999958)
			(xy 196.348004 -274.950904) (xy 196.359781 -274.90312) (xy 196.379072 -274.857844) (xy 196.405375 -274.816248)
			(xy 196.43801 -274.779411) (xy 196.476131 -274.748286) (xy 196.518752 -274.723679) (xy 196.564768 -274.706227)
			(xy 196.612987 -274.696383) (xy 196.662162 -274.694402) (xy 196.711017 -274.700334) (xy 196.758288 -274.714026)
			(xy 196.80275 -274.735124) (xy 196.843253 -274.76308) (xy 196.878746 -274.797172) (xy 196.908311 -274.836516)
			(xy 196.931182 -274.880093) (xy 196.946766 -274.926774) (xy 196.954661 -274.975351) (xy 196.955156 -274.999958)
			(xy 196.954661 -275.024565) (xy 196.954523 -275.025412) (xy 197.273414 -275.025412) (xy 197.273414 -274.973996)
			(xy 197.281457 -274.923214) (xy 197.297345 -274.874315) (xy 197.320688 -274.828503) (xy 197.350909 -274.786907)
			(xy 197.387265 -274.750551) (xy 197.428861 -274.72033) (xy 197.474673 -274.696987) (xy 197.523572 -274.681099)
			(xy 197.574354 -274.673056) (xy 197.62577 -274.673056) (xy 197.676552 -274.681099) (xy 197.725451 -274.696987)
			(xy 197.771263 -274.72033) (xy 197.812859 -274.750551) (xy 197.849215 -274.786907) (xy 197.879436 -274.828503)
			(xy 197.902779 -274.874315) (xy 197.918667 -274.923214) (xy 197.92671 -274.973996) (xy 197.927214 -274.999704)
			(xy 197.92671 -275.025412) (xy 198.223374 -275.025412) (xy 198.223374 -274.973996) (xy 198.231417 -274.923214)
			(xy 198.247305 -274.874315) (xy 198.270648 -274.828503) (xy 198.300869 -274.786907) (xy 198.337225 -274.750551)
			(xy 198.378821 -274.72033) (xy 198.424633 -274.696987) (xy 198.473532 -274.681099) (xy 198.524314 -274.673056)
			(xy 198.57573 -274.673056) (xy 198.626512 -274.681099) (xy 198.675411 -274.696987) (xy 198.721223 -274.72033)
			(xy 198.762819 -274.750551) (xy 198.799175 -274.786907) (xy 198.829396 -274.828503) (xy 198.852739 -274.874315)
			(xy 198.868627 -274.923214) (xy 198.87667 -274.973996) (xy 198.877174 -274.999704) (xy 198.877169 -274.999958)
			(xy 199.194432 -274.999958) (xy 199.198392 -274.950904) (xy 199.210169 -274.90312) (xy 199.22946 -274.857844)
			(xy 199.255763 -274.816248) (xy 199.288398 -274.779411) (xy 199.326519 -274.748286) (xy 199.36914 -274.723679)
			(xy 199.415156 -274.706227) (xy 199.463375 -274.696383) (xy 199.51255 -274.694402) (xy 199.561405 -274.700334)
			(xy 199.608676 -274.714026) (xy 199.653138 -274.735124) (xy 199.693641 -274.76308) (xy 199.729134 -274.797172)
			(xy 199.758699 -274.836516) (xy 199.78157 -274.880093) (xy 199.797154 -274.926774) (xy 199.805049 -274.975351)
			(xy 199.805544 -274.999958) (xy 199.805049 -275.024565) (xy 199.797154 -275.073142) (xy 199.78157 -275.119823)
			(xy 199.758699 -275.1634) (xy 199.729134 -275.202744) (xy 199.693641 -275.236836) (xy 199.653138 -275.264792)
			(xy 199.608676 -275.28589) (xy 199.561405 -275.299582) (xy 199.51255 -275.305514) (xy 199.463375 -275.303533)
			(xy 199.415156 -275.293689) (xy 199.36914 -275.276237) (xy 199.326519 -275.25163) (xy 199.288398 -275.220505)
			(xy 199.255763 -275.183668) (xy 199.22946 -275.142072) (xy 199.210169 -275.096796) (xy 199.198392 -275.049012)
			(xy 199.194432 -274.999958) (xy 198.877169 -274.999958) (xy 198.87667 -275.025412) (xy 198.868627 -275.076194)
			(xy 198.852739 -275.125093) (xy 198.829396 -275.170905) (xy 198.799175 -275.212501) (xy 198.762819 -275.248857)
			(xy 198.721223 -275.279078) (xy 198.675411 -275.302421) (xy 198.626512 -275.318309) (xy 198.57573 -275.326352)
			(xy 198.524314 -275.326352) (xy 198.473532 -275.318309) (xy 198.424633 -275.302421) (xy 198.378821 -275.279078)
			(xy 198.337225 -275.248857) (xy 198.300869 -275.212501) (xy 198.270648 -275.170905) (xy 198.247305 -275.125093)
			(xy 198.231417 -275.076194) (xy 198.223374 -275.025412) (xy 197.92671 -275.025412) (xy 197.918667 -275.076194)
			(xy 197.902779 -275.125093) (xy 197.879436 -275.170905) (xy 197.849215 -275.212501) (xy 197.812859 -275.248857)
			(xy 197.771263 -275.279078) (xy 197.725451 -275.302421) (xy 197.676552 -275.318309) (xy 197.62577 -275.326352)
			(xy 197.574354 -275.326352) (xy 197.523572 -275.318309) (xy 197.474673 -275.302421) (xy 197.428861 -275.279078)
			(xy 197.387265 -275.248857) (xy 197.350909 -275.212501) (xy 197.320688 -275.170905) (xy 197.297345 -275.125093)
			(xy 197.281457 -275.076194) (xy 197.273414 -275.025412) (xy 196.954523 -275.025412) (xy 196.946766 -275.073142)
			(xy 196.931182 -275.119823) (xy 196.908311 -275.1634) (xy 196.878746 -275.202744) (xy 196.843253 -275.236836)
			(xy 196.80275 -275.264792) (xy 196.758288 -275.28589) (xy 196.711017 -275.299582) (xy 196.662162 -275.305514)
			(xy 196.612987 -275.303533) (xy 196.564768 -275.293689) (xy 196.518752 -275.276237) (xy 196.476131 -275.25163)
			(xy 196.43801 -275.220505) (xy 196.405375 -275.183668) (xy 196.379072 -275.142072) (xy 196.359781 -275.096796)
			(xy 196.348004 -275.049012) (xy 196.344044 -274.999958) (xy 196.026786 -274.999958) (xy 196.026282 -275.025666)
			(xy 196.018239 -275.076448) (xy 196.002351 -275.125347) (xy 195.979008 -275.171159) (xy 195.948787 -275.212755)
			(xy 195.912431 -275.249111) (xy 195.870835 -275.279332) (xy 195.825023 -275.302675) (xy 195.776124 -275.318563)
			(xy 195.725342 -275.326606) (xy 195.673926 -275.326606) (xy 195.623144 -275.318563) (xy 195.574245 -275.302675)
			(xy 195.528433 -275.279332) (xy 195.486837 -275.249111) (xy 195.450481 -275.212755) (xy 195.42026 -275.171159)
			(xy 195.396917 -275.125347) (xy 195.381029 -275.076448) (xy 195.372986 -275.025666) (xy 195.054308 -275.025666)
			(xy 195.046592 -275.073142) (xy 195.031008 -275.119823) (xy 195.008137 -275.1634) (xy 194.978572 -275.202744)
			(xy 194.943079 -275.236836) (xy 194.902576 -275.264792) (xy 194.858114 -275.28589) (xy 194.810843 -275.299582)
			(xy 194.761988 -275.305514) (xy 194.712813 -275.303533) (xy 194.664594 -275.293689) (xy 194.618578 -275.276237)
			(xy 194.575957 -275.25163) (xy 194.537836 -275.220505) (xy 194.505201 -275.183668) (xy 194.478898 -275.142072)
			(xy 194.459607 -275.096796) (xy 194.44783 -275.049012) (xy 194.44387 -274.999958) (xy 194.126866 -274.999958)
			(xy 194.126362 -275.025666) (xy 194.118319 -275.076448) (xy 194.102431 -275.125347) (xy 194.079088 -275.171159)
			(xy 194.048867 -275.212755) (xy 194.012511 -275.249111) (xy 193.970915 -275.279332) (xy 193.925103 -275.302675)
			(xy 193.876204 -275.318563) (xy 193.825422 -275.326606) (xy 193.774006 -275.326606) (xy 193.723224 -275.318563)
			(xy 193.674325 -275.302675) (xy 193.628513 -275.279332) (xy 193.586917 -275.249111) (xy 193.550561 -275.212755)
			(xy 193.52034 -275.171159) (xy 193.496997 -275.125347) (xy 193.481109 -275.076448) (xy 193.473066 -275.025666)
			(xy 193.154388 -275.025666) (xy 193.146672 -275.073142) (xy 193.131088 -275.119823) (xy 193.108217 -275.1634)
			(xy 193.078652 -275.202744) (xy 193.043159 -275.236836) (xy 193.002656 -275.264792) (xy 192.958194 -275.28589)
			(xy 192.910923 -275.299582) (xy 192.862068 -275.305514) (xy 192.812893 -275.303533) (xy 192.764674 -275.293689)
			(xy 192.718658 -275.276237) (xy 192.676037 -275.25163) (xy 192.637916 -275.220505) (xy 192.605281 -275.183668)
			(xy 192.578978 -275.142072) (xy 192.559687 -275.096796) (xy 192.54791 -275.049012) (xy 192.54395 -274.999958)
			(xy 192.226941 -274.999958) (xy 192.226442 -275.025412) (xy 192.218399 -275.076194) (xy 192.202511 -275.125093)
			(xy 192.179168 -275.170905) (xy 192.148947 -275.212501) (xy 192.112591 -275.248857) (xy 192.070995 -275.279078)
			(xy 192.025183 -275.302421) (xy 191.976284 -275.318309) (xy 191.925502 -275.326352) (xy 191.874086 -275.326352)
			(xy 191.823304 -275.318309) (xy 191.774405 -275.302421) (xy 191.728593 -275.279078) (xy 191.686997 -275.248857)
			(xy 191.650641 -275.212501) (xy 191.62042 -275.170905) (xy 191.597077 -275.125093) (xy 191.581189 -275.076194)
			(xy 191.573146 -275.025412) (xy 191.254509 -275.025412) (xy 191.246752 -275.073142) (xy 191.231168 -275.119823)
			(xy 191.208297 -275.1634) (xy 191.178732 -275.202744) (xy 191.143239 -275.236836) (xy 191.102736 -275.264792)
			(xy 191.058274 -275.28589) (xy 191.011003 -275.299582) (xy 190.962148 -275.305514) (xy 190.912973 -275.303533)
			(xy 190.864754 -275.293689) (xy 190.818738 -275.276237) (xy 190.776117 -275.25163) (xy 190.737996 -275.220505)
			(xy 190.705361 -275.183668) (xy 190.679058 -275.142072) (xy 190.659767 -275.096796) (xy 190.64799 -275.049012)
			(xy 190.64403 -274.999958) (xy 190.326772 -274.999958) (xy 190.326268 -275.025666) (xy 190.318225 -275.076448)
			(xy 190.302337 -275.125347) (xy 190.278994 -275.171159) (xy 190.248773 -275.212755) (xy 190.212417 -275.249111)
			(xy 190.170821 -275.279332) (xy 190.125009 -275.302675) (xy 190.07611 -275.318563) (xy 190.025328 -275.326606)
			(xy 189.973912 -275.326606) (xy 189.92313 -275.318563) (xy 189.874231 -275.302675) (xy 189.828419 -275.279332)
			(xy 189.786823 -275.249111) (xy 189.750467 -275.212755) (xy 189.720246 -275.171159) (xy 189.696903 -275.125347)
			(xy 189.681015 -275.076448) (xy 189.672972 -275.025666) (xy 189.354548 -275.025666) (xy 189.346832 -275.073142)
			(xy 189.331248 -275.119823) (xy 189.308377 -275.1634) (xy 189.278812 -275.202744) (xy 189.243319 -275.236836)
			(xy 189.202816 -275.264792) (xy 189.158354 -275.28589) (xy 189.111083 -275.299582) (xy 189.062228 -275.305514)
			(xy 189.013053 -275.303533) (xy 188.964834 -275.293689) (xy 188.918818 -275.276237) (xy 188.876197 -275.25163)
			(xy 188.838076 -275.220505) (xy 188.805441 -275.183668) (xy 188.779138 -275.142072) (xy 188.759847 -275.096796)
			(xy 188.74807 -275.049012) (xy 188.74411 -274.999958) (xy 188.426847 -274.999958) (xy 188.426348 -275.025412)
			(xy 188.418305 -275.076194) (xy 188.402417 -275.125093) (xy 188.379074 -275.170905) (xy 188.348853 -275.212501)
			(xy 188.312497 -275.248857) (xy 188.270901 -275.279078) (xy 188.225089 -275.302421) (xy 188.17619 -275.318309)
			(xy 188.125408 -275.326352) (xy 188.073992 -275.326352) (xy 188.02321 -275.318309) (xy 187.974311 -275.302421)
			(xy 187.928499 -275.279078) (xy 187.886903 -275.248857) (xy 187.850547 -275.212501) (xy 187.820326 -275.170905)
			(xy 187.796983 -275.125093) (xy 187.781095 -275.076194) (xy 187.773052 -275.025412) (xy 187.454669 -275.025412)
			(xy 187.446912 -275.073142) (xy 187.431328 -275.119823) (xy 187.408457 -275.1634) (xy 187.378892 -275.202744)
			(xy 187.343399 -275.236836) (xy 187.302896 -275.264792) (xy 187.258434 -275.28589) (xy 187.211163 -275.299582)
			(xy 187.162308 -275.305514) (xy 187.113133 -275.303533) (xy 187.064914 -275.293689) (xy 187.018898 -275.276237)
			(xy 186.976277 -275.25163) (xy 186.938156 -275.220505) (xy 186.905521 -275.183668) (xy 186.879218 -275.142072)
			(xy 186.859927 -275.096796) (xy 186.84815 -275.049012) (xy 186.84419 -274.999958) (xy 186.526678 -274.999958)
			(xy 186.526174 -275.025666) (xy 186.518131 -275.076448) (xy 186.502243 -275.125347) (xy 186.4789 -275.171159)
			(xy 186.448679 -275.212755) (xy 186.412323 -275.249111) (xy 186.370727 -275.279332) (xy 186.324915 -275.302675)
			(xy 186.276016 -275.318563) (xy 186.225234 -275.326606) (xy 186.173818 -275.326606) (xy 186.123036 -275.318563)
			(xy 186.074137 -275.302675) (xy 186.028325 -275.279332) (xy 185.986729 -275.249111) (xy 185.950373 -275.212755)
			(xy 185.920152 -275.171159) (xy 185.896809 -275.125347) (xy 185.880921 -275.076448) (xy 185.872878 -275.025666)
			(xy 185.554708 -275.025666) (xy 185.546992 -275.073142) (xy 185.531408 -275.119823) (xy 185.508537 -275.1634)
			(xy 185.478972 -275.202744) (xy 185.443479 -275.236836) (xy 185.402976 -275.264792) (xy 185.358514 -275.28589)
			(xy 185.311243 -275.299582) (xy 185.262388 -275.305514) (xy 185.213213 -275.303533) (xy 185.164994 -275.293689)
			(xy 185.118978 -275.276237) (xy 185.076357 -275.25163) (xy 185.038236 -275.220505) (xy 185.005601 -275.183668)
			(xy 184.979298 -275.142072) (xy 184.960007 -275.096796) (xy 184.94823 -275.049012) (xy 184.94427 -274.999958)
			(xy 184.626753 -274.999958) (xy 184.626254 -275.025412) (xy 184.618211 -275.076194) (xy 184.602323 -275.125093)
			(xy 184.57898 -275.170905) (xy 184.548759 -275.212501) (xy 184.512403 -275.248857) (xy 184.470807 -275.279078)
			(xy 184.424995 -275.302421) (xy 184.376096 -275.318309) (xy 184.325314 -275.326352) (xy 184.273898 -275.326352)
			(xy 184.223116 -275.318309) (xy 184.174217 -275.302421) (xy 184.128405 -275.279078) (xy 184.086809 -275.248857)
			(xy 184.050453 -275.212501) (xy 184.020232 -275.170905) (xy 183.996889 -275.125093) (xy 183.981001 -275.076194)
			(xy 183.972958 -275.025412) (xy 183.654575 -275.025412) (xy 183.646818 -275.073142) (xy 183.631234 -275.119823)
			(xy 183.608363 -275.1634) (xy 183.578798 -275.202744) (xy 183.543305 -275.236836) (xy 183.502802 -275.264792)
			(xy 183.45834 -275.28589) (xy 183.411069 -275.299582) (xy 183.362214 -275.305514) (xy 183.313039 -275.303533)
			(xy 183.26482 -275.293689) (xy 183.218804 -275.276237) (xy 183.176183 -275.25163) (xy 183.138062 -275.220505)
			(xy 183.105427 -275.183668) (xy 183.079124 -275.142072) (xy 183.059833 -275.096796) (xy 183.048056 -275.049012)
			(xy 183.044096 -274.999958) (xy 182.726838 -274.999958) (xy 182.726334 -275.025666) (xy 182.718291 -275.076448)
			(xy 182.702403 -275.125347) (xy 182.67906 -275.171159) (xy 182.648839 -275.212755) (xy 182.612483 -275.249111)
			(xy 182.570887 -275.279332) (xy 182.525075 -275.302675) (xy 182.476176 -275.318563) (xy 182.425394 -275.326606)
			(xy 182.373978 -275.326606) (xy 182.323196 -275.318563) (xy 182.274297 -275.302675) (xy 182.228485 -275.279332)
			(xy 182.186889 -275.249111) (xy 182.150533 -275.212755) (xy 182.120312 -275.171159) (xy 182.096969 -275.125347)
			(xy 182.081081 -275.076448) (xy 182.073038 -275.025666) (xy 181.754614 -275.025666) (xy 181.746898 -275.073142)
			(xy 181.731314 -275.119823) (xy 181.708443 -275.1634) (xy 181.678878 -275.202744) (xy 181.643385 -275.236836)
			(xy 181.602882 -275.264792) (xy 181.55842 -275.28589) (xy 181.511149 -275.299582) (xy 181.462294 -275.305514)
			(xy 181.413119 -275.303533) (xy 181.3649 -275.293689) (xy 181.318884 -275.276237) (xy 181.276263 -275.25163)
			(xy 181.238142 -275.220505) (xy 181.205507 -275.183668) (xy 181.179204 -275.142072) (xy 181.159913 -275.096796)
			(xy 181.148136 -275.049012) (xy 181.144176 -274.999958) (xy 180.826913 -274.999958) (xy 180.826414 -275.025412)
			(xy 180.818371 -275.076194) (xy 180.802483 -275.125093) (xy 180.77914 -275.170905) (xy 180.748919 -275.212501)
			(xy 180.712563 -275.248857) (xy 180.670967 -275.279078) (xy 180.625155 -275.302421) (xy 180.576256 -275.318309)
			(xy 180.525474 -275.326352) (xy 180.474058 -275.326352) (xy 180.423276 -275.318309) (xy 180.374377 -275.302421)
			(xy 180.328565 -275.279078) (xy 180.286969 -275.248857) (xy 180.250613 -275.212501) (xy 180.220392 -275.170905)
			(xy 180.197049 -275.125093) (xy 180.181161 -275.076194) (xy 180.173118 -275.025412) (xy 179.854735 -275.025412)
			(xy 179.846978 -275.073142) (xy 179.831394 -275.119823) (xy 179.808523 -275.1634) (xy 179.778958 -275.202744)
			(xy 179.743465 -275.236836) (xy 179.702962 -275.264792) (xy 179.6585 -275.28589) (xy 179.611229 -275.299582)
			(xy 179.562374 -275.305514) (xy 179.513199 -275.303533) (xy 179.46498 -275.293689) (xy 179.418964 -275.276237)
			(xy 179.376343 -275.25163) (xy 179.338222 -275.220505) (xy 179.305587 -275.183668) (xy 179.279284 -275.142072)
			(xy 179.259993 -275.096796) (xy 179.248216 -275.049012) (xy 179.244256 -274.999958) (xy 178.926744 -274.999958)
			(xy 178.92624 -275.025666) (xy 178.918197 -275.076448) (xy 178.902309 -275.125347) (xy 178.878966 -275.171159)
			(xy 178.848745 -275.212755) (xy 178.812389 -275.249111) (xy 178.770793 -275.279332) (xy 178.724981 -275.302675)
			(xy 178.676082 -275.318563) (xy 178.6253 -275.326606) (xy 178.573884 -275.326606) (xy 178.523102 -275.318563)
			(xy 178.474203 -275.302675) (xy 178.428391 -275.279332) (xy 178.386795 -275.249111) (xy 178.350439 -275.212755)
			(xy 178.320218 -275.171159) (xy 178.296875 -275.125347) (xy 178.280987 -275.076448) (xy 178.272944 -275.025666)
			(xy 177.95452 -275.025666) (xy 177.946804 -275.073142) (xy 177.93122 -275.119823) (xy 177.908349 -275.1634)
			(xy 177.878784 -275.202744) (xy 177.843291 -275.236836) (xy 177.802788 -275.264792) (xy 177.758326 -275.28589)
			(xy 177.711055 -275.299582) (xy 177.6622 -275.305514) (xy 177.613025 -275.303533) (xy 177.564806 -275.293689)
			(xy 177.51879 -275.276237) (xy 177.476169 -275.25163) (xy 177.438048 -275.220505) (xy 177.405413 -275.183668)
			(xy 177.37911 -275.142072) (xy 177.359819 -275.096796) (xy 177.348042 -275.049012) (xy 177.344082 -274.999958)
			(xy 177.026819 -274.999958) (xy 177.02632 -275.025412) (xy 177.018277 -275.076194) (xy 177.002389 -275.125093)
			(xy 176.979046 -275.170905) (xy 176.948825 -275.212501) (xy 176.912469 -275.248857) (xy 176.870873 -275.279078)
			(xy 176.825061 -275.302421) (xy 176.776162 -275.318309) (xy 176.72538 -275.326352) (xy 176.673964 -275.326352)
			(xy 176.623182 -275.318309) (xy 176.574283 -275.302421) (xy 176.528471 -275.279078) (xy 176.486875 -275.248857)
			(xy 176.450519 -275.212501) (xy 176.420298 -275.170905) (xy 176.396955 -275.125093) (xy 176.381067 -275.076194)
			(xy 176.373024 -275.025412) (xy 176.053796 -275.025412) (xy 176.051729 -275.050353) (xy 176.039325 -275.099333)
			(xy 176.019028 -275.145603) (xy 175.991391 -275.1879) (xy 175.957169 -275.225072) (xy 175.917295 -275.256103)
			(xy 175.872856 -275.280147) (xy 175.825067 -275.296549) (xy 175.775229 -275.30486) (xy 175.749966 -275.305266)
			(xy 175.724905 -275.304737) (xy 175.67546 -275.296516) (xy 175.628016 -275.280348) (xy 175.605694 -275.268944)
			(xy 175.599598 -275.265642) (xy 175.587152 -275.262848) (xy 175.580548 -275.263102) (xy 175.574064 -275.263463)
			(xy 175.561596 -275.267075) (xy 175.55591 -275.270214) (xy 175.48098 -275.314918) (xy 175.47336 -275.320506)
			(xy 175.466585 -275.32705) (xy 175.457854 -275.343722) (xy 175.456342 -275.353018) (xy 175.456088 -275.358352)
			(xy 175.456088 -275.591524) (xy 175.456342 -275.596858) (xy 175.457742 -275.606193) (xy 175.466481 -275.622908)
			(xy 175.47336 -275.62937) (xy 175.48098 -275.634958) (xy 175.55591 -275.679662) (xy 175.561593 -275.682806)
			(xy 175.574064 -275.686412) (xy 175.580548 -275.686774) (xy 175.593756 -275.687282) (xy 175.605694 -275.680932)
			(xy 175.628011 -275.669514) (xy 175.675452 -275.65333) (xy 175.724903 -275.645133) (xy 175.749966 -275.64461)
			(xy 175.775224 -275.6451) (xy 175.825052 -275.65341) (xy 175.872832 -275.669808) (xy 175.917262 -275.693848)
			(xy 175.957128 -275.724873) (xy 175.991344 -275.762037) (xy 176.018975 -275.804326) (xy 176.039268 -275.850586)
			(xy 176.05167 -275.899557) (xy 176.055842 -275.9499) (xy 176.053731 -275.975372) (xy 176.373024 -275.975372)
			(xy 176.373024 -275.923956) (xy 176.381067 -275.873174) (xy 176.396955 -275.824275) (xy 176.420298 -275.778463)
			(xy 176.450519 -275.736867) (xy 176.486875 -275.700511) (xy 176.528471 -275.67029) (xy 176.574283 -275.646947)
			(xy 176.623182 -275.631059) (xy 176.673964 -275.623016) (xy 176.72538 -275.623016) (xy 176.776162 -275.631059)
			(xy 176.825061 -275.646947) (xy 176.870873 -275.67029) (xy 176.912469 -275.700511) (xy 176.948825 -275.736867)
			(xy 176.979046 -275.778463) (xy 177.002389 -275.824275) (xy 177.018277 -275.873174) (xy 177.02632 -275.923956)
			(xy 177.026824 -275.949664) (xy 177.026819 -275.949918) (xy 177.344082 -275.949918) (xy 177.348042 -275.900864)
			(xy 177.359819 -275.85308) (xy 177.37911 -275.807804) (xy 177.405413 -275.766208) (xy 177.438048 -275.729371)
			(xy 177.476169 -275.698246) (xy 177.51879 -275.673639) (xy 177.564806 -275.656187) (xy 177.613025 -275.646343)
			(xy 177.6622 -275.644362) (xy 177.711055 -275.650294) (xy 177.758326 -275.663986) (xy 177.802788 -275.685084)
			(xy 177.843291 -275.71304) (xy 177.878784 -275.747132) (xy 177.908349 -275.786476) (xy 177.93122 -275.830053)
			(xy 177.946804 -275.876734) (xy 177.954699 -275.925311) (xy 177.955194 -275.949918) (xy 177.954699 -275.974525)
			(xy 177.95452 -275.975626) (xy 178.272944 -275.975626) (xy 178.272944 -275.92421) (xy 178.280987 -275.873428)
			(xy 178.296875 -275.824529) (xy 178.320218 -275.778717) (xy 178.350439 -275.737121) (xy 178.386795 -275.700765)
			(xy 178.428391 -275.670544) (xy 178.474203 -275.647201) (xy 178.523102 -275.631313) (xy 178.573884 -275.62327)
			(xy 178.6253 -275.62327) (xy 178.676082 -275.631313) (xy 178.724981 -275.647201) (xy 178.770793 -275.670544)
			(xy 178.812389 -275.700765) (xy 178.848745 -275.737121) (xy 178.878966 -275.778717) (xy 178.902309 -275.824529)
			(xy 178.918197 -275.873428) (xy 178.92624 -275.92421) (xy 178.926744 -275.949918) (xy 179.244256 -275.949918)
			(xy 179.248216 -275.900864) (xy 179.259993 -275.85308) (xy 179.279284 -275.807804) (xy 179.305587 -275.766208)
			(xy 179.338222 -275.729371) (xy 179.376343 -275.698246) (xy 179.418964 -275.673639) (xy 179.46498 -275.656187)
			(xy 179.513199 -275.646343) (xy 179.562374 -275.644362) (xy 179.611229 -275.650294) (xy 179.6585 -275.663986)
			(xy 179.702962 -275.685084) (xy 179.743465 -275.71304) (xy 179.778958 -275.747132) (xy 179.808523 -275.786476)
			(xy 179.831394 -275.830053) (xy 179.846978 -275.876734) (xy 179.854873 -275.925311) (xy 179.855368 -275.949918)
			(xy 179.854873 -275.974525) (xy 179.854735 -275.975372) (xy 180.173118 -275.975372) (xy 180.173118 -275.923956)
			(xy 180.181161 -275.873174) (xy 180.197049 -275.824275) (xy 180.220392 -275.778463) (xy 180.250613 -275.736867)
			(xy 180.286969 -275.700511) (xy 180.328565 -275.67029) (xy 180.374377 -275.646947) (xy 180.423276 -275.631059)
			(xy 180.474058 -275.623016) (xy 180.525474 -275.623016) (xy 180.576256 -275.631059) (xy 180.625155 -275.646947)
			(xy 180.670967 -275.67029) (xy 180.712563 -275.700511) (xy 180.748919 -275.736867) (xy 180.77914 -275.778463)
			(xy 180.802483 -275.824275) (xy 180.818371 -275.873174) (xy 180.826414 -275.923956) (xy 180.826918 -275.949664)
			(xy 180.826913 -275.949918) (xy 181.144176 -275.949918) (xy 181.148136 -275.900864) (xy 181.159913 -275.85308)
			(xy 181.179204 -275.807804) (xy 181.205507 -275.766208) (xy 181.238142 -275.729371) (xy 181.276263 -275.698246)
			(xy 181.318884 -275.673639) (xy 181.3649 -275.656187) (xy 181.413119 -275.646343) (xy 181.462294 -275.644362)
			(xy 181.511149 -275.650294) (xy 181.55842 -275.663986) (xy 181.602882 -275.685084) (xy 181.643385 -275.71304)
			(xy 181.678878 -275.747132) (xy 181.708443 -275.786476) (xy 181.731314 -275.830053) (xy 181.746898 -275.876734)
			(xy 181.754793 -275.925311) (xy 181.755288 -275.949918) (xy 181.754793 -275.974525) (xy 181.754614 -275.975626)
			(xy 182.073038 -275.975626) (xy 182.073038 -275.92421) (xy 182.081081 -275.873428) (xy 182.096969 -275.824529)
			(xy 182.120312 -275.778717) (xy 182.150533 -275.737121) (xy 182.186889 -275.700765) (xy 182.228485 -275.670544)
			(xy 182.274297 -275.647201) (xy 182.323196 -275.631313) (xy 182.373978 -275.62327) (xy 182.425394 -275.62327)
			(xy 182.476176 -275.631313) (xy 182.525075 -275.647201) (xy 182.570887 -275.670544) (xy 182.612483 -275.700765)
			(xy 182.648839 -275.737121) (xy 182.67906 -275.778717) (xy 182.702403 -275.824529) (xy 182.718291 -275.873428)
			(xy 182.726334 -275.92421) (xy 182.726838 -275.949918) (xy 183.044096 -275.949918) (xy 183.048056 -275.900864)
			(xy 183.059833 -275.85308) (xy 183.079124 -275.807804) (xy 183.105427 -275.766208) (xy 183.138062 -275.729371)
			(xy 183.176183 -275.698246) (xy 183.218804 -275.673639) (xy 183.26482 -275.656187) (xy 183.313039 -275.646343)
			(xy 183.362214 -275.644362) (xy 183.411069 -275.650294) (xy 183.45834 -275.663986) (xy 183.502802 -275.685084)
			(xy 183.543305 -275.71304) (xy 183.578798 -275.747132) (xy 183.608363 -275.786476) (xy 183.631234 -275.830053)
			(xy 183.646818 -275.876734) (xy 183.654713 -275.925311) (xy 183.655208 -275.949918) (xy 183.654713 -275.974525)
			(xy 183.654575 -275.975372) (xy 183.972958 -275.975372) (xy 183.972958 -275.923956) (xy 183.981001 -275.873174)
			(xy 183.996889 -275.824275) (xy 184.020232 -275.778463) (xy 184.050453 -275.736867) (xy 184.086809 -275.700511)
			(xy 184.128405 -275.67029) (xy 184.174217 -275.646947) (xy 184.223116 -275.631059) (xy 184.273898 -275.623016)
			(xy 184.325314 -275.623016) (xy 184.376096 -275.631059) (xy 184.424995 -275.646947) (xy 184.470807 -275.67029)
			(xy 184.512403 -275.700511) (xy 184.548759 -275.736867) (xy 184.57898 -275.778463) (xy 184.602323 -275.824275)
			(xy 184.618211 -275.873174) (xy 184.626254 -275.923956) (xy 184.626758 -275.949664) (xy 184.626753 -275.949918)
			(xy 184.94427 -275.949918) (xy 184.94823 -275.900864) (xy 184.960007 -275.85308) (xy 184.979298 -275.807804)
			(xy 185.005601 -275.766208) (xy 185.038236 -275.729371) (xy 185.076357 -275.698246) (xy 185.118978 -275.673639)
			(xy 185.164994 -275.656187) (xy 185.213213 -275.646343) (xy 185.262388 -275.644362) (xy 185.311243 -275.650294)
			(xy 185.358514 -275.663986) (xy 185.402976 -275.685084) (xy 185.443479 -275.71304) (xy 185.478972 -275.747132)
			(xy 185.508537 -275.786476) (xy 185.531408 -275.830053) (xy 185.546992 -275.876734) (xy 185.554887 -275.925311)
			(xy 185.555382 -275.949918) (xy 185.554887 -275.974525) (xy 185.554708 -275.975626) (xy 185.872878 -275.975626)
			(xy 185.872878 -275.92421) (xy 185.880921 -275.873428) (xy 185.896809 -275.824529) (xy 185.920152 -275.778717)
			(xy 185.950373 -275.737121) (xy 185.986729 -275.700765) (xy 186.028325 -275.670544) (xy 186.074137 -275.647201)
			(xy 186.123036 -275.631313) (xy 186.173818 -275.62327) (xy 186.225234 -275.62327) (xy 186.276016 -275.631313)
			(xy 186.324915 -275.647201) (xy 186.370727 -275.670544) (xy 186.412323 -275.700765) (xy 186.448679 -275.737121)
			(xy 186.4789 -275.778717) (xy 186.502243 -275.824529) (xy 186.518131 -275.873428) (xy 186.526174 -275.92421)
			(xy 186.526678 -275.949918) (xy 186.84419 -275.949918) (xy 186.84815 -275.900864) (xy 186.859927 -275.85308)
			(xy 186.879218 -275.807804) (xy 186.905521 -275.766208) (xy 186.938156 -275.729371) (xy 186.976277 -275.698246)
			(xy 187.018898 -275.673639) (xy 187.064914 -275.656187) (xy 187.113133 -275.646343) (xy 187.162308 -275.644362)
			(xy 187.211163 -275.650294) (xy 187.258434 -275.663986) (xy 187.302896 -275.685084) (xy 187.343399 -275.71304)
			(xy 187.378892 -275.747132) (xy 187.408457 -275.786476) (xy 187.431328 -275.830053) (xy 187.446912 -275.876734)
			(xy 187.454807 -275.925311) (xy 187.455302 -275.949918) (xy 187.454807 -275.974525) (xy 187.454669 -275.975372)
			(xy 187.773052 -275.975372) (xy 187.773052 -275.923956) (xy 187.781095 -275.873174) (xy 187.796983 -275.824275)
			(xy 187.820326 -275.778463) (xy 187.850547 -275.736867) (xy 187.886903 -275.700511) (xy 187.928499 -275.67029)
			(xy 187.974311 -275.646947) (xy 188.02321 -275.631059) (xy 188.073992 -275.623016) (xy 188.125408 -275.623016)
			(xy 188.17619 -275.631059) (xy 188.225089 -275.646947) (xy 188.270901 -275.67029) (xy 188.312497 -275.700511)
			(xy 188.348853 -275.736867) (xy 188.379074 -275.778463) (xy 188.402417 -275.824275) (xy 188.418305 -275.873174)
			(xy 188.426348 -275.923956) (xy 188.426852 -275.949664) (xy 188.426847 -275.949918) (xy 188.74411 -275.949918)
			(xy 188.74807 -275.900864) (xy 188.759847 -275.85308) (xy 188.779138 -275.807804) (xy 188.805441 -275.766208)
			(xy 188.838076 -275.729371) (xy 188.876197 -275.698246) (xy 188.918818 -275.673639) (xy 188.964834 -275.656187)
			(xy 189.013053 -275.646343) (xy 189.062228 -275.644362) (xy 189.111083 -275.650294) (xy 189.158354 -275.663986)
			(xy 189.202816 -275.685084) (xy 189.243319 -275.71304) (xy 189.278812 -275.747132) (xy 189.308377 -275.786476)
			(xy 189.331248 -275.830053) (xy 189.346832 -275.876734) (xy 189.354727 -275.925311) (xy 189.355222 -275.949918)
			(xy 189.354727 -275.974525) (xy 189.354548 -275.975626) (xy 189.672972 -275.975626) (xy 189.672972 -275.92421)
			(xy 189.681015 -275.873428) (xy 189.696903 -275.824529) (xy 189.720246 -275.778717) (xy 189.750467 -275.737121)
			(xy 189.786823 -275.700765) (xy 189.828419 -275.670544) (xy 189.874231 -275.647201) (xy 189.92313 -275.631313)
			(xy 189.973912 -275.62327) (xy 190.025328 -275.62327) (xy 190.07611 -275.631313) (xy 190.125009 -275.647201)
			(xy 190.170821 -275.670544) (xy 190.212417 -275.700765) (xy 190.248773 -275.737121) (xy 190.278994 -275.778717)
			(xy 190.302337 -275.824529) (xy 190.318225 -275.873428) (xy 190.326268 -275.92421) (xy 190.326772 -275.949918)
			(xy 190.644284 -275.949918) (xy 190.648244 -275.900864) (xy 190.660021 -275.85308) (xy 190.679312 -275.807804)
			(xy 190.705615 -275.766208) (xy 190.73825 -275.729371) (xy 190.776371 -275.698246) (xy 190.818992 -275.673639)
			(xy 190.865008 -275.656187) (xy 190.913227 -275.646343) (xy 190.962402 -275.644362) (xy 191.011257 -275.650294)
			(xy 191.058528 -275.663986) (xy 191.10299 -275.685084) (xy 191.143493 -275.71304) (xy 191.178986 -275.747132)
			(xy 191.208551 -275.786476) (xy 191.231422 -275.830053) (xy 191.247006 -275.876734) (xy 191.254901 -275.925311)
			(xy 191.255396 -275.949918) (xy 191.254901 -275.974525) (xy 191.254763 -275.975372) (xy 191.573146 -275.975372)
			(xy 191.573146 -275.923956) (xy 191.581189 -275.873174) (xy 191.597077 -275.824275) (xy 191.62042 -275.778463)
			(xy 191.650641 -275.736867) (xy 191.686997 -275.700511) (xy 191.728593 -275.67029) (xy 191.774405 -275.646947)
			(xy 191.823304 -275.631059) (xy 191.874086 -275.623016) (xy 191.925502 -275.623016) (xy 191.976284 -275.631059)
			(xy 192.025183 -275.646947) (xy 192.070995 -275.67029) (xy 192.112591 -275.700511) (xy 192.148947 -275.736867)
			(xy 192.179168 -275.778463) (xy 192.202511 -275.824275) (xy 192.218399 -275.873174) (xy 192.226442 -275.923956)
			(xy 192.226946 -275.949664) (xy 192.226941 -275.949918) (xy 192.544204 -275.949918) (xy 192.548164 -275.900864)
			(xy 192.559941 -275.85308) (xy 192.579232 -275.807804) (xy 192.605535 -275.766208) (xy 192.63817 -275.729371)
			(xy 192.676291 -275.698246) (xy 192.718912 -275.673639) (xy 192.764928 -275.656187) (xy 192.813147 -275.646343)
			(xy 192.862322 -275.644362) (xy 192.911177 -275.650294) (xy 192.958448 -275.663986) (xy 193.00291 -275.685084)
			(xy 193.043413 -275.71304) (xy 193.078906 -275.747132) (xy 193.108471 -275.786476) (xy 193.131342 -275.830053)
			(xy 193.146926 -275.876734) (xy 193.154821 -275.925311) (xy 193.155316 -275.949918) (xy 193.154821 -275.974525)
			(xy 193.154642 -275.975626) (xy 193.473066 -275.975626) (xy 193.473066 -275.92421) (xy 193.481109 -275.873428)
			(xy 193.496997 -275.824529) (xy 193.52034 -275.778717) (xy 193.550561 -275.737121) (xy 193.586917 -275.700765)
			(xy 193.628513 -275.670544) (xy 193.674325 -275.647201) (xy 193.723224 -275.631313) (xy 193.774006 -275.62327)
			(xy 193.825422 -275.62327) (xy 193.876204 -275.631313) (xy 193.925103 -275.647201) (xy 193.970915 -275.670544)
			(xy 194.012511 -275.700765) (xy 194.048867 -275.737121) (xy 194.079088 -275.778717) (xy 194.102431 -275.824529)
			(xy 194.118319 -275.873428) (xy 194.126362 -275.92421) (xy 194.126866 -275.949918) (xy 194.444124 -275.949918)
			(xy 194.448084 -275.900864) (xy 194.459861 -275.85308) (xy 194.479152 -275.807804) (xy 194.505455 -275.766208)
			(xy 194.53809 -275.729371) (xy 194.576211 -275.698246) (xy 194.618832 -275.673639) (xy 194.664848 -275.656187)
			(xy 194.713067 -275.646343) (xy 194.762242 -275.644362) (xy 194.811097 -275.650294) (xy 194.858368 -275.663986)
			(xy 194.90283 -275.685084) (xy 194.943333 -275.71304) (xy 194.978826 -275.747132) (xy 195.008391 -275.786476)
			(xy 195.031262 -275.830053) (xy 195.046846 -275.876734) (xy 195.054741 -275.925311) (xy 195.055236 -275.949918)
			(xy 195.054741 -275.974525) (xy 195.054562 -275.975626) (xy 195.372986 -275.975626) (xy 195.372986 -275.92421)
			(xy 195.381029 -275.873428) (xy 195.396917 -275.824529) (xy 195.42026 -275.778717) (xy 195.450481 -275.737121)
			(xy 195.486837 -275.700765) (xy 195.528433 -275.670544) (xy 195.574245 -275.647201) (xy 195.623144 -275.631313)
			(xy 195.673926 -275.62327) (xy 195.725342 -275.62327) (xy 195.776124 -275.631313) (xy 195.825023 -275.647201)
			(xy 195.870835 -275.670544) (xy 195.912431 -275.700765) (xy 195.948787 -275.737121) (xy 195.979008 -275.778717)
			(xy 196.002351 -275.824529) (xy 196.018239 -275.873428) (xy 196.026282 -275.92421) (xy 196.026786 -275.949918)
			(xy 196.344298 -275.949918) (xy 196.348258 -275.900864) (xy 196.360035 -275.85308) (xy 196.379326 -275.807804)
			(xy 196.405629 -275.766208) (xy 196.438264 -275.729371) (xy 196.476385 -275.698246) (xy 196.519006 -275.673639)
			(xy 196.565022 -275.656187) (xy 196.613241 -275.646343) (xy 196.662416 -275.644362) (xy 196.711271 -275.650294)
			(xy 196.758542 -275.663986) (xy 196.803004 -275.685084) (xy 196.843507 -275.71304) (xy 196.879 -275.747132)
			(xy 196.908565 -275.786476) (xy 196.931436 -275.830053) (xy 196.94702 -275.876734) (xy 196.954915 -275.925311)
			(xy 196.95541 -275.949918) (xy 197.294258 -275.949918) (xy 197.298218 -275.900864) (xy 197.309995 -275.85308)
			(xy 197.329286 -275.807804) (xy 197.355589 -275.766208) (xy 197.388224 -275.729371) (xy 197.426345 -275.698246)
			(xy 197.468966 -275.673639) (xy 197.514982 -275.656187) (xy 197.563201 -275.646343) (xy 197.612376 -275.644362)
			(xy 197.661231 -275.650294) (xy 197.708502 -275.663986) (xy 197.752964 -275.685084) (xy 197.793467 -275.71304)
			(xy 197.82896 -275.747132) (xy 197.858525 -275.786476) (xy 197.881396 -275.830053) (xy 197.89698 -275.876734)
			(xy 197.904875 -275.925311) (xy 197.90537 -275.949918) (xy 198.244218 -275.949918) (xy 198.248178 -275.900864)
			(xy 198.259955 -275.85308) (xy 198.279246 -275.807804) (xy 198.305549 -275.766208) (xy 198.338184 -275.729371)
			(xy 198.376305 -275.698246) (xy 198.418926 -275.673639) (xy 198.464942 -275.656187) (xy 198.513161 -275.646343)
			(xy 198.562336 -275.644362) (xy 198.611191 -275.650294) (xy 198.658462 -275.663986) (xy 198.702924 -275.685084)
			(xy 198.743427 -275.71304) (xy 198.77892 -275.747132) (xy 198.808485 -275.786476) (xy 198.831356 -275.830053)
			(xy 198.84694 -275.876734) (xy 198.854835 -275.925311) (xy 198.85533 -275.949918) (xy 198.854835 -275.974525)
			(xy 198.84694 -276.023102) (xy 198.831356 -276.069783) (xy 198.808485 -276.11336) (xy 198.77892 -276.152704)
			(xy 198.743427 -276.186796) (xy 198.702924 -276.214752) (xy 198.658462 -276.23585) (xy 198.611191 -276.249542)
			(xy 198.562336 -276.255474) (xy 198.513161 -276.253493) (xy 198.464942 -276.243649) (xy 198.418926 -276.226197)
			(xy 198.376305 -276.20159) (xy 198.338184 -276.170465) (xy 198.305549 -276.133628) (xy 198.279246 -276.092032)
			(xy 198.259955 -276.046756) (xy 198.248178 -275.998972) (xy 198.244218 -275.949918) (xy 197.90537 -275.949918)
			(xy 197.904875 -275.974525) (xy 197.89698 -276.023102) (xy 197.881396 -276.069783) (xy 197.858525 -276.11336)
			(xy 197.82896 -276.152704) (xy 197.793467 -276.186796) (xy 197.752964 -276.214752) (xy 197.708502 -276.23585)
			(xy 197.661231 -276.249542) (xy 197.612376 -276.255474) (xy 197.563201 -276.253493) (xy 197.514982 -276.243649)
			(xy 197.468966 -276.226197) (xy 197.426345 -276.20159) (xy 197.388224 -276.170465) (xy 197.355589 -276.133628)
			(xy 197.329286 -276.092032) (xy 197.309995 -276.046756) (xy 197.298218 -275.998972) (xy 197.294258 -275.949918)
			(xy 196.95541 -275.949918) (xy 196.954915 -275.974525) (xy 196.94702 -276.023102) (xy 196.931436 -276.069783)
			(xy 196.908565 -276.11336) (xy 196.879 -276.152704) (xy 196.843507 -276.186796) (xy 196.803004 -276.214752)
			(xy 196.758542 -276.23585) (xy 196.711271 -276.249542) (xy 196.662416 -276.255474) (xy 196.613241 -276.253493)
			(xy 196.565022 -276.243649) (xy 196.519006 -276.226197) (xy 196.476385 -276.20159) (xy 196.438264 -276.170465)
			(xy 196.405629 -276.133628) (xy 196.379326 -276.092032) (xy 196.360035 -276.046756) (xy 196.348258 -275.998972)
			(xy 196.344298 -275.949918) (xy 196.026786 -275.949918) (xy 196.026282 -275.975626) (xy 196.018239 -276.026408)
			(xy 196.002351 -276.075307) (xy 195.979008 -276.121119) (xy 195.948787 -276.162715) (xy 195.912431 -276.199071)
			(xy 195.870835 -276.229292) (xy 195.825023 -276.252635) (xy 195.776124 -276.268523) (xy 195.725342 -276.276566)
			(xy 195.673926 -276.276566) (xy 195.623144 -276.268523) (xy 195.574245 -276.252635) (xy 195.528433 -276.229292)
			(xy 195.486837 -276.199071) (xy 195.450481 -276.162715) (xy 195.42026 -276.121119) (xy 195.396917 -276.075307)
			(xy 195.381029 -276.026408) (xy 195.372986 -275.975626) (xy 195.054562 -275.975626) (xy 195.046846 -276.023102)
			(xy 195.031262 -276.069783) (xy 195.008391 -276.11336) (xy 194.978826 -276.152704) (xy 194.943333 -276.186796)
			(xy 194.90283 -276.214752) (xy 194.858368 -276.23585) (xy 194.811097 -276.249542) (xy 194.762242 -276.255474)
			(xy 194.713067 -276.253493) (xy 194.664848 -276.243649) (xy 194.618832 -276.226197) (xy 194.576211 -276.20159)
			(xy 194.53809 -276.170465) (xy 194.505455 -276.133628) (xy 194.479152 -276.092032) (xy 194.459861 -276.046756)
			(xy 194.448084 -275.998972) (xy 194.444124 -275.949918) (xy 194.126866 -275.949918) (xy 194.126362 -275.975626)
			(xy 194.118319 -276.026408) (xy 194.102431 -276.075307) (xy 194.079088 -276.121119) (xy 194.048867 -276.162715)
			(xy 194.012511 -276.199071) (xy 193.970915 -276.229292) (xy 193.925103 -276.252635) (xy 193.876204 -276.268523)
			(xy 193.825422 -276.276566) (xy 193.774006 -276.276566) (xy 193.723224 -276.268523) (xy 193.674325 -276.252635)
			(xy 193.628513 -276.229292) (xy 193.586917 -276.199071) (xy 193.550561 -276.162715) (xy 193.52034 -276.121119)
			(xy 193.496997 -276.075307) (xy 193.481109 -276.026408) (xy 193.473066 -275.975626) (xy 193.154642 -275.975626)
			(xy 193.146926 -276.023102) (xy 193.131342 -276.069783) (xy 193.108471 -276.11336) (xy 193.078906 -276.152704)
			(xy 193.043413 -276.186796) (xy 193.00291 -276.214752) (xy 192.958448 -276.23585) (xy 192.911177 -276.249542)
			(xy 192.862322 -276.255474) (xy 192.813147 -276.253493) (xy 192.764928 -276.243649) (xy 192.718912 -276.226197)
			(xy 192.676291 -276.20159) (xy 192.63817 -276.170465) (xy 192.605535 -276.133628) (xy 192.579232 -276.092032)
			(xy 192.559941 -276.046756) (xy 192.548164 -275.998972) (xy 192.544204 -275.949918) (xy 192.226941 -275.949918)
			(xy 192.226442 -275.975372) (xy 192.218399 -276.026154) (xy 192.202511 -276.075053) (xy 192.179168 -276.120865)
			(xy 192.148947 -276.162461) (xy 192.112591 -276.198817) (xy 192.070995 -276.229038) (xy 192.025183 -276.252381)
			(xy 191.976284 -276.268269) (xy 191.925502 -276.276312) (xy 191.874086 -276.276312) (xy 191.823304 -276.268269)
			(xy 191.774405 -276.252381) (xy 191.728593 -276.229038) (xy 191.686997 -276.198817) (xy 191.650641 -276.162461)
			(xy 191.62042 -276.120865) (xy 191.597077 -276.075053) (xy 191.581189 -276.026154) (xy 191.573146 -275.975372)
			(xy 191.254763 -275.975372) (xy 191.247006 -276.023102) (xy 191.231422 -276.069783) (xy 191.208551 -276.11336)
			(xy 191.178986 -276.152704) (xy 191.143493 -276.186796) (xy 191.10299 -276.214752) (xy 191.058528 -276.23585)
			(xy 191.011257 -276.249542) (xy 190.962402 -276.255474) (xy 190.913227 -276.253493) (xy 190.865008 -276.243649)
			(xy 190.818992 -276.226197) (xy 190.776371 -276.20159) (xy 190.73825 -276.170465) (xy 190.705615 -276.133628)
			(xy 190.679312 -276.092032) (xy 190.660021 -276.046756) (xy 190.648244 -275.998972) (xy 190.644284 -275.949918)
			(xy 190.326772 -275.949918) (xy 190.326268 -275.975626) (xy 190.318225 -276.026408) (xy 190.302337 -276.075307)
			(xy 190.278994 -276.121119) (xy 190.248773 -276.162715) (xy 190.212417 -276.199071) (xy 190.170821 -276.229292)
			(xy 190.125009 -276.252635) (xy 190.07611 -276.268523) (xy 190.025328 -276.276566) (xy 189.973912 -276.276566)
			(xy 189.92313 -276.268523) (xy 189.874231 -276.252635) (xy 189.828419 -276.229292) (xy 189.786823 -276.199071)
			(xy 189.750467 -276.162715) (xy 189.720246 -276.121119) (xy 189.696903 -276.075307) (xy 189.681015 -276.026408)
			(xy 189.672972 -275.975626) (xy 189.354548 -275.975626) (xy 189.346832 -276.023102) (xy 189.331248 -276.069783)
			(xy 189.308377 -276.11336) (xy 189.278812 -276.152704) (xy 189.243319 -276.186796) (xy 189.202816 -276.214752)
			(xy 189.158354 -276.23585) (xy 189.111083 -276.249542) (xy 189.062228 -276.255474) (xy 189.013053 -276.253493)
			(xy 188.964834 -276.243649) (xy 188.918818 -276.226197) (xy 188.876197 -276.20159) (xy 188.838076 -276.170465)
			(xy 188.805441 -276.133628) (xy 188.779138 -276.092032) (xy 188.759847 -276.046756) (xy 188.74807 -275.998972)
			(xy 188.74411 -275.949918) (xy 188.426847 -275.949918) (xy 188.426348 -275.975372) (xy 188.418305 -276.026154)
			(xy 188.402417 -276.075053) (xy 188.379074 -276.120865) (xy 188.348853 -276.162461) (xy 188.312497 -276.198817)
			(xy 188.270901 -276.229038) (xy 188.225089 -276.252381) (xy 188.17619 -276.268269) (xy 188.125408 -276.276312)
			(xy 188.073992 -276.276312) (xy 188.02321 -276.268269) (xy 187.974311 -276.252381) (xy 187.928499 -276.229038)
			(xy 187.886903 -276.198817) (xy 187.850547 -276.162461) (xy 187.820326 -276.120865) (xy 187.796983 -276.075053)
			(xy 187.781095 -276.026154) (xy 187.773052 -275.975372) (xy 187.454669 -275.975372) (xy 187.446912 -276.023102)
			(xy 187.431328 -276.069783) (xy 187.408457 -276.11336) (xy 187.378892 -276.152704) (xy 187.343399 -276.186796)
			(xy 187.302896 -276.214752) (xy 187.258434 -276.23585) (xy 187.211163 -276.249542) (xy 187.162308 -276.255474)
			(xy 187.113133 -276.253493) (xy 187.064914 -276.243649) (xy 187.018898 -276.226197) (xy 186.976277 -276.20159)
			(xy 186.938156 -276.170465) (xy 186.905521 -276.133628) (xy 186.879218 -276.092032) (xy 186.859927 -276.046756)
			(xy 186.84815 -275.998972) (xy 186.84419 -275.949918) (xy 186.526678 -275.949918) (xy 186.526174 -275.975626)
			(xy 186.518131 -276.026408) (xy 186.502243 -276.075307) (xy 186.4789 -276.121119) (xy 186.448679 -276.162715)
			(xy 186.412323 -276.199071) (xy 186.370727 -276.229292) (xy 186.324915 -276.252635) (xy 186.276016 -276.268523)
			(xy 186.225234 -276.276566) (xy 186.173818 -276.276566) (xy 186.123036 -276.268523) (xy 186.074137 -276.252635)
			(xy 186.028325 -276.229292) (xy 185.986729 -276.199071) (xy 185.950373 -276.162715) (xy 185.920152 -276.121119)
			(xy 185.896809 -276.075307) (xy 185.880921 -276.026408) (xy 185.872878 -275.975626) (xy 185.554708 -275.975626)
			(xy 185.546992 -276.023102) (xy 185.531408 -276.069783) (xy 185.508537 -276.11336) (xy 185.478972 -276.152704)
			(xy 185.443479 -276.186796) (xy 185.402976 -276.214752) (xy 185.358514 -276.23585) (xy 185.311243 -276.249542)
			(xy 185.262388 -276.255474) (xy 185.213213 -276.253493) (xy 185.164994 -276.243649) (xy 185.118978 -276.226197)
			(xy 185.076357 -276.20159) (xy 185.038236 -276.170465) (xy 185.005601 -276.133628) (xy 184.979298 -276.092032)
			(xy 184.960007 -276.046756) (xy 184.94823 -275.998972) (xy 184.94427 -275.949918) (xy 184.626753 -275.949918)
			(xy 184.626254 -275.975372) (xy 184.618211 -276.026154) (xy 184.602323 -276.075053) (xy 184.57898 -276.120865)
			(xy 184.548759 -276.162461) (xy 184.512403 -276.198817) (xy 184.470807 -276.229038) (xy 184.424995 -276.252381)
			(xy 184.376096 -276.268269) (xy 184.325314 -276.276312) (xy 184.273898 -276.276312) (xy 184.223116 -276.268269)
			(xy 184.174217 -276.252381) (xy 184.128405 -276.229038) (xy 184.086809 -276.198817) (xy 184.050453 -276.162461)
			(xy 184.020232 -276.120865) (xy 183.996889 -276.075053) (xy 183.981001 -276.026154) (xy 183.972958 -275.975372)
			(xy 183.654575 -275.975372) (xy 183.646818 -276.023102) (xy 183.631234 -276.069783) (xy 183.608363 -276.11336)
			(xy 183.578798 -276.152704) (xy 183.543305 -276.186796) (xy 183.502802 -276.214752) (xy 183.45834 -276.23585)
			(xy 183.411069 -276.249542) (xy 183.362214 -276.255474) (xy 183.313039 -276.253493) (xy 183.26482 -276.243649)
			(xy 183.218804 -276.226197) (xy 183.176183 -276.20159) (xy 183.138062 -276.170465) (xy 183.105427 -276.133628)
			(xy 183.079124 -276.092032) (xy 183.059833 -276.046756) (xy 183.048056 -275.998972) (xy 183.044096 -275.949918)
			(xy 182.726838 -275.949918) (xy 182.726334 -275.975626) (xy 182.718291 -276.026408) (xy 182.702403 -276.075307)
			(xy 182.67906 -276.121119) (xy 182.648839 -276.162715) (xy 182.612483 -276.199071) (xy 182.570887 -276.229292)
			(xy 182.525075 -276.252635) (xy 182.476176 -276.268523) (xy 182.425394 -276.276566) (xy 182.373978 -276.276566)
			(xy 182.323196 -276.268523) (xy 182.274297 -276.252635) (xy 182.228485 -276.229292) (xy 182.186889 -276.199071)
			(xy 182.150533 -276.162715) (xy 182.120312 -276.121119) (xy 182.096969 -276.075307) (xy 182.081081 -276.026408)
			(xy 182.073038 -275.975626) (xy 181.754614 -275.975626) (xy 181.746898 -276.023102) (xy 181.731314 -276.069783)
			(xy 181.708443 -276.11336) (xy 181.678878 -276.152704) (xy 181.643385 -276.186796) (xy 181.602882 -276.214752)
			(xy 181.55842 -276.23585) (xy 181.511149 -276.249542) (xy 181.462294 -276.255474) (xy 181.413119 -276.253493)
			(xy 181.3649 -276.243649) (xy 181.318884 -276.226197) (xy 181.276263 -276.20159) (xy 181.238142 -276.170465)
			(xy 181.205507 -276.133628) (xy 181.179204 -276.092032) (xy 181.159913 -276.046756) (xy 181.148136 -275.998972)
			(xy 181.144176 -275.949918) (xy 180.826913 -275.949918) (xy 180.826414 -275.975372) (xy 180.818371 -276.026154)
			(xy 180.802483 -276.075053) (xy 180.77914 -276.120865) (xy 180.748919 -276.162461) (xy 180.712563 -276.198817)
			(xy 180.670967 -276.229038) (xy 180.625155 -276.252381) (xy 180.576256 -276.268269) (xy 180.525474 -276.276312)
			(xy 180.474058 -276.276312) (xy 180.423276 -276.268269) (xy 180.374377 -276.252381) (xy 180.328565 -276.229038)
			(xy 180.286969 -276.198817) (xy 180.250613 -276.162461) (xy 180.220392 -276.120865) (xy 180.197049 -276.075053)
			(xy 180.181161 -276.026154) (xy 180.173118 -275.975372) (xy 179.854735 -275.975372) (xy 179.846978 -276.023102)
			(xy 179.831394 -276.069783) (xy 179.808523 -276.11336) (xy 179.778958 -276.152704) (xy 179.743465 -276.186796)
			(xy 179.702962 -276.214752) (xy 179.6585 -276.23585) (xy 179.611229 -276.249542) (xy 179.562374 -276.255474)
			(xy 179.513199 -276.253493) (xy 179.46498 -276.243649) (xy 179.418964 -276.226197) (xy 179.376343 -276.20159)
			(xy 179.338222 -276.170465) (xy 179.305587 -276.133628) (xy 179.279284 -276.092032) (xy 179.259993 -276.046756)
			(xy 179.248216 -275.998972) (xy 179.244256 -275.949918) (xy 178.926744 -275.949918) (xy 178.92624 -275.975626)
			(xy 178.918197 -276.026408) (xy 178.902309 -276.075307) (xy 178.878966 -276.121119) (xy 178.848745 -276.162715)
			(xy 178.812389 -276.199071) (xy 178.770793 -276.229292) (xy 178.724981 -276.252635) (xy 178.676082 -276.268523)
			(xy 178.6253 -276.276566) (xy 178.573884 -276.276566) (xy 178.523102 -276.268523) (xy 178.474203 -276.252635)
			(xy 178.428391 -276.229292) (xy 178.386795 -276.199071) (xy 178.350439 -276.162715) (xy 178.320218 -276.121119)
			(xy 178.296875 -276.075307) (xy 178.280987 -276.026408) (xy 178.272944 -275.975626) (xy 177.95452 -275.975626)
			(xy 177.946804 -276.023102) (xy 177.93122 -276.069783) (xy 177.908349 -276.11336) (xy 177.878784 -276.152704)
			(xy 177.843291 -276.186796) (xy 177.802788 -276.214752) (xy 177.758326 -276.23585) (xy 177.711055 -276.249542)
			(xy 177.6622 -276.255474) (xy 177.613025 -276.253493) (xy 177.564806 -276.243649) (xy 177.51879 -276.226197)
			(xy 177.476169 -276.20159) (xy 177.438048 -276.170465) (xy 177.405413 -276.133628) (xy 177.37911 -276.092032)
			(xy 177.359819 -276.046756) (xy 177.348042 -275.998972) (xy 177.344082 -275.949918) (xy 177.026819 -275.949918)
			(xy 177.02632 -275.975372) (xy 177.018277 -276.026154) (xy 177.002389 -276.075053) (xy 176.979046 -276.120865)
			(xy 176.948825 -276.162461) (xy 176.912469 -276.198817) (xy 176.870873 -276.229038) (xy 176.825061 -276.252381)
			(xy 176.776162 -276.268269) (xy 176.72538 -276.276312) (xy 176.673964 -276.276312) (xy 176.623182 -276.268269)
			(xy 176.574283 -276.252381) (xy 176.528471 -276.229038) (xy 176.486875 -276.198817) (xy 176.450519 -276.162461)
			(xy 176.420298 -276.120865) (xy 176.396955 -276.075053) (xy 176.381067 -276.026154) (xy 176.373024 -275.975372)
			(xy 176.053731 -275.975372) (xy 176.05167 -276.000243) (xy 176.039268 -276.049214) (xy 176.018975 -276.095474)
			(xy 175.991344 -276.137763) (xy 175.957128 -276.174927) (xy 175.917262 -276.205952) (xy 175.872832 -276.229992)
			(xy 175.825052 -276.24639) (xy 175.775224 -276.2547) (xy 175.749966 -276.255226) (xy 175.724905 -276.254697)
			(xy 175.675461 -276.246475) (xy 175.628017 -276.230306) (xy 175.605694 -276.218904) (xy 175.599598 -276.215602)
			(xy 175.587152 -276.212808) (xy 175.580548 -276.213062) (xy 175.574064 -276.213423) (xy 175.561594 -276.217032)
			(xy 175.55591 -276.220174) (xy 175.48098 -276.264878) (xy 175.47336 -276.270466) (xy 175.46658 -276.277007)
			(xy 175.457836 -276.293678) (xy 175.456342 -276.302978) (xy 175.456088 -276.308312) (xy 175.456088 -276.369018)
			(xy 225.13493 -276.369018) (xy 225.139001 -276.313396) (xy 225.151127 -276.258959) (xy 225.17105 -276.206868)
			(xy 225.198346 -276.158233) (xy 225.232432 -276.11409) (xy 225.272581 -276.075381) (xy 225.317939 -276.04293)
			(xy 225.367539 -276.017429) (xy 225.420323 -275.999422) (xy 225.475166 -275.989292) (xy 225.5309 -275.987255)
			(xy 225.586337 -275.993355) (xy 225.640294 -276.007461) (xy 225.691623 -276.029273) (xy 225.739229 -276.058327)
			(xy 225.782097 -276.094002) (xy 225.819314 -276.135539) (xy 225.850087 -276.182052) (xy 225.873759 -276.232549)
			(xy 225.889827 -276.285956) (xy 225.897947 -276.341132) (xy 225.898456 -276.369018) (xy 225.897947 -276.396904)
			(xy 225.889827 -276.45208) (xy 225.873759 -276.505487) (xy 225.850087 -276.555984) (xy 225.819314 -276.602497)
			(xy 225.782097 -276.644034) (xy 225.739229 -276.679709) (xy 225.691623 -276.708763) (xy 225.640294 -276.730575)
			(xy 225.586337 -276.744681) (xy 225.5309 -276.750781) (xy 225.475166 -276.748744) (xy 225.420323 -276.738614)
			(xy 225.367539 -276.720607) (xy 225.317939 -276.695106) (xy 225.272581 -276.662655) (xy 225.232432 -276.623946)
			(xy 225.198346 -276.579803) (xy 225.17105 -276.531168) (xy 225.151127 -276.479077) (xy 225.139001 -276.42464)
			(xy 225.13493 -276.369018) (xy 175.456088 -276.369018) (xy 175.456088 -276.541484) (xy 175.456342 -276.546818)
			(xy 175.457752 -276.556147) (xy 175.466504 -276.572847) (xy 175.47336 -276.57933) (xy 175.48098 -276.584918)
			(xy 175.55591 -276.629622) (xy 175.561592 -276.632768) (xy 175.574064 -276.636377) (xy 175.580548 -276.636734)
			(xy 175.593756 -276.637242) (xy 175.605694 -276.630892) (xy 175.62801 -276.619472) (xy 175.675451 -276.603285)
			(xy 175.724903 -276.595086) (xy 175.749966 -276.59457) (xy 175.775227 -276.59506) (xy 175.825062 -276.603371)
			(xy 175.872848 -276.619771) (xy 175.917284 -276.643814) (xy 175.957155 -276.674843) (xy 175.991375 -276.712012)
			(xy 176.01901 -276.754307) (xy 176.039306 -276.800573) (xy 176.05171 -276.84955) (xy 176.05588 -276.899878)
			(xy 176.394122 -276.899878) (xy 176.398082 -276.850824) (xy 176.409859 -276.80304) (xy 176.42915 -276.757764)
			(xy 176.455453 -276.716168) (xy 176.488088 -276.679331) (xy 176.526209 -276.648206) (xy 176.56883 -276.623599)
			(xy 176.614846 -276.606147) (xy 176.663065 -276.596303) (xy 176.71224 -276.594322) (xy 176.761095 -276.600254)
			(xy 176.808366 -276.613946) (xy 176.852828 -276.635044) (xy 176.893331 -276.663) (xy 176.928824 -276.697092)
			(xy 176.958389 -276.736436) (xy 176.98126 -276.780013) (xy 176.996844 -276.826694) (xy 177.004739 -276.875271)
			(xy 177.005234 -276.899878) (xy 177.344082 -276.899878) (xy 177.348042 -276.850824) (xy 177.359819 -276.80304)
			(xy 177.37911 -276.757764) (xy 177.405413 -276.716168) (xy 177.438048 -276.679331) (xy 177.476169 -276.648206)
			(xy 177.51879 -276.623599) (xy 177.564806 -276.606147) (xy 177.613025 -276.596303) (xy 177.6622 -276.594322)
			(xy 177.711055 -276.600254) (xy 177.758326 -276.613946) (xy 177.802788 -276.635044) (xy 177.843291 -276.663)
			(xy 177.878784 -276.697092) (xy 177.908349 -276.736436) (xy 177.93122 -276.780013) (xy 177.946804 -276.826694)
			(xy 177.954699 -276.875271) (xy 177.955194 -276.899878) (xy 178.294042 -276.899878) (xy 178.298002 -276.850824)
			(xy 178.309779 -276.80304) (xy 178.32907 -276.757764) (xy 178.355373 -276.716168) (xy 178.388008 -276.679331)
			(xy 178.426129 -276.648206) (xy 178.46875 -276.623599) (xy 178.514766 -276.606147) (xy 178.562985 -276.596303)
			(xy 178.61216 -276.594322) (xy 178.661015 -276.600254) (xy 178.708286 -276.613946) (xy 178.752748 -276.635044)
			(xy 178.793251 -276.663) (xy 178.828744 -276.697092) (xy 178.858309 -276.736436) (xy 178.88118 -276.780013)
			(xy 178.896764 -276.826694) (xy 178.904659 -276.875271) (xy 178.905154 -276.899878) (xy 179.244256 -276.899878)
			(xy 179.248216 -276.850824) (xy 179.259993 -276.80304) (xy 179.279284 -276.757764) (xy 179.305587 -276.716168)
			(xy 179.338222 -276.679331) (xy 179.376343 -276.648206) (xy 179.418964 -276.623599) (xy 179.46498 -276.606147)
			(xy 179.513199 -276.596303) (xy 179.562374 -276.594322) (xy 179.611229 -276.600254) (xy 179.6585 -276.613946)
			(xy 179.702962 -276.635044) (xy 179.743465 -276.663) (xy 179.778958 -276.697092) (xy 179.808523 -276.736436)
			(xy 179.831394 -276.780013) (xy 179.846978 -276.826694) (xy 179.854873 -276.875271) (xy 179.855368 -276.899878)
			(xy 180.194216 -276.899878) (xy 180.198176 -276.850824) (xy 180.209953 -276.80304) (xy 180.229244 -276.757764)
			(xy 180.255547 -276.716168) (xy 180.288182 -276.679331) (xy 180.326303 -276.648206) (xy 180.368924 -276.623599)
			(xy 180.41494 -276.606147) (xy 180.463159 -276.596303) (xy 180.512334 -276.594322) (xy 180.561189 -276.600254)
			(xy 180.60846 -276.613946) (xy 180.652922 -276.635044) (xy 180.693425 -276.663) (xy 180.728918 -276.697092)
			(xy 180.758483 -276.736436) (xy 180.781354 -276.780013) (xy 180.796938 -276.826694) (xy 180.804833 -276.875271)
			(xy 180.805328 -276.899878) (xy 181.144176 -276.899878) (xy 181.148136 -276.850824) (xy 181.159913 -276.80304)
			(xy 181.179204 -276.757764) (xy 181.205507 -276.716168) (xy 181.238142 -276.679331) (xy 181.276263 -276.648206)
			(xy 181.318884 -276.623599) (xy 181.3649 -276.606147) (xy 181.413119 -276.596303) (xy 181.462294 -276.594322)
			(xy 181.511149 -276.600254) (xy 181.55842 -276.613946) (xy 181.602882 -276.635044) (xy 181.643385 -276.663)
			(xy 181.678878 -276.697092) (xy 181.708443 -276.736436) (xy 181.731314 -276.780013) (xy 181.746898 -276.826694)
			(xy 181.754793 -276.875271) (xy 181.755288 -276.899878) (xy 182.094136 -276.899878) (xy 182.098096 -276.850824)
			(xy 182.109873 -276.80304) (xy 182.129164 -276.757764) (xy 182.155467 -276.716168) (xy 182.188102 -276.679331)
			(xy 182.226223 -276.648206) (xy 182.268844 -276.623599) (xy 182.31486 -276.606147) (xy 182.363079 -276.596303)
			(xy 182.412254 -276.594322) (xy 182.461109 -276.600254) (xy 182.50838 -276.613946) (xy 182.552842 -276.635044)
			(xy 182.593345 -276.663) (xy 182.628838 -276.697092) (xy 182.658403 -276.736436) (xy 182.681274 -276.780013)
			(xy 182.696858 -276.826694) (xy 182.704753 -276.875271) (xy 182.705248 -276.899878) (xy 183.044096 -276.899878)
			(xy 183.048056 -276.850824) (xy 183.059833 -276.80304) (xy 183.079124 -276.757764) (xy 183.105427 -276.716168)
			(xy 183.138062 -276.679331) (xy 183.176183 -276.648206) (xy 183.218804 -276.623599) (xy 183.26482 -276.606147)
			(xy 183.313039 -276.596303) (xy 183.362214 -276.594322) (xy 183.411069 -276.600254) (xy 183.45834 -276.613946)
			(xy 183.502802 -276.635044) (xy 183.543305 -276.663) (xy 183.578798 -276.697092) (xy 183.608363 -276.736436)
			(xy 183.631234 -276.780013) (xy 183.646818 -276.826694) (xy 183.654713 -276.875271) (xy 183.655208 -276.899878)
			(xy 183.994056 -276.899878) (xy 183.998016 -276.850824) (xy 184.009793 -276.80304) (xy 184.029084 -276.757764)
			(xy 184.055387 -276.716168) (xy 184.088022 -276.679331) (xy 184.126143 -276.648206) (xy 184.168764 -276.623599)
			(xy 184.21478 -276.606147) (xy 184.262999 -276.596303) (xy 184.312174 -276.594322) (xy 184.361029 -276.600254)
			(xy 184.4083 -276.613946) (xy 184.452762 -276.635044) (xy 184.493265 -276.663) (xy 184.528758 -276.697092)
			(xy 184.558323 -276.736436) (xy 184.581194 -276.780013) (xy 184.596778 -276.826694) (xy 184.604673 -276.875271)
			(xy 184.605168 -276.899878) (xy 184.94427 -276.899878) (xy 184.94823 -276.850824) (xy 184.960007 -276.80304)
			(xy 184.979298 -276.757764) (xy 185.005601 -276.716168) (xy 185.038236 -276.679331) (xy 185.076357 -276.648206)
			(xy 185.118978 -276.623599) (xy 185.164994 -276.606147) (xy 185.213213 -276.596303) (xy 185.262388 -276.594322)
			(xy 185.311243 -276.600254) (xy 185.358514 -276.613946) (xy 185.402976 -276.635044) (xy 185.443479 -276.663)
			(xy 185.478972 -276.697092) (xy 185.508537 -276.736436) (xy 185.531408 -276.780013) (xy 185.546992 -276.826694)
			(xy 185.554887 -276.875271) (xy 185.555382 -276.899878) (xy 185.89423 -276.899878) (xy 185.89819 -276.850824)
			(xy 185.909967 -276.80304) (xy 185.929258 -276.757764) (xy 185.955561 -276.716168) (xy 185.988196 -276.679331)
			(xy 186.026317 -276.648206) (xy 186.068938 -276.623599) (xy 186.114954 -276.606147) (xy 186.163173 -276.596303)
			(xy 186.212348 -276.594322) (xy 186.261203 -276.600254) (xy 186.308474 -276.613946) (xy 186.352936 -276.635044)
			(xy 186.393439 -276.663) (xy 186.428932 -276.697092) (xy 186.458497 -276.736436) (xy 186.481368 -276.780013)
			(xy 186.496952 -276.826694) (xy 186.504847 -276.875271) (xy 186.505342 -276.899878) (xy 186.84419 -276.899878)
			(xy 186.84815 -276.850824) (xy 186.859927 -276.80304) (xy 186.879218 -276.757764) (xy 186.905521 -276.716168)
			(xy 186.938156 -276.679331) (xy 186.976277 -276.648206) (xy 187.018898 -276.623599) (xy 187.064914 -276.606147)
			(xy 187.113133 -276.596303) (xy 187.162308 -276.594322) (xy 187.211163 -276.600254) (xy 187.258434 -276.613946)
			(xy 187.302896 -276.635044) (xy 187.343399 -276.663) (xy 187.378892 -276.697092) (xy 187.408457 -276.736436)
			(xy 187.431328 -276.780013) (xy 187.446912 -276.826694) (xy 187.454807 -276.875271) (xy 187.455302 -276.899878)
			(xy 187.79415 -276.899878) (xy 187.79811 -276.850824) (xy 187.809887 -276.80304) (xy 187.829178 -276.757764)
			(xy 187.855481 -276.716168) (xy 187.888116 -276.679331) (xy 187.926237 -276.648206) (xy 187.968858 -276.623599)
			(xy 188.014874 -276.606147) (xy 188.063093 -276.596303) (xy 188.112268 -276.594322) (xy 188.161123 -276.600254)
			(xy 188.208394 -276.613946) (xy 188.252856 -276.635044) (xy 188.293359 -276.663) (xy 188.328852 -276.697092)
			(xy 188.358417 -276.736436) (xy 188.381288 -276.780013) (xy 188.396872 -276.826694) (xy 188.404767 -276.875271)
			(xy 188.405262 -276.899878) (xy 188.74411 -276.899878) (xy 188.74807 -276.850824) (xy 188.759847 -276.80304)
			(xy 188.779138 -276.757764) (xy 188.805441 -276.716168) (xy 188.838076 -276.679331) (xy 188.876197 -276.648206)
			(xy 188.918818 -276.623599) (xy 188.964834 -276.606147) (xy 189.013053 -276.596303) (xy 189.062228 -276.594322)
			(xy 189.111083 -276.600254) (xy 189.158354 -276.613946) (xy 189.202816 -276.635044) (xy 189.243319 -276.663)
			(xy 189.278812 -276.697092) (xy 189.308377 -276.736436) (xy 189.331248 -276.780013) (xy 189.346832 -276.826694)
			(xy 189.354727 -276.875271) (xy 189.355222 -276.899878) (xy 189.693816 -276.899878) (xy 189.697776 -276.850824)
			(xy 189.709553 -276.80304) (xy 189.728844 -276.757764) (xy 189.755147 -276.716168) (xy 189.787782 -276.679331)
			(xy 189.825903 -276.648206) (xy 189.868524 -276.623599) (xy 189.91454 -276.606147) (xy 189.962759 -276.596303)
			(xy 190.011934 -276.594322) (xy 190.060789 -276.600254) (xy 190.10806 -276.613946) (xy 190.152522 -276.635044)
			(xy 190.193025 -276.663) (xy 190.228518 -276.697092) (xy 190.258083 -276.736436) (xy 190.280954 -276.780013)
			(xy 190.296538 -276.826694) (xy 190.304433 -276.875271) (xy 190.304928 -276.899878) (xy 190.64403 -276.899878)
			(xy 190.64799 -276.850824) (xy 190.659767 -276.80304) (xy 190.679058 -276.757764) (xy 190.705361 -276.716168)
			(xy 190.737996 -276.679331) (xy 190.776117 -276.648206) (xy 190.818738 -276.623599) (xy 190.864754 -276.606147)
			(xy 190.912973 -276.596303) (xy 190.962148 -276.594322) (xy 191.011003 -276.600254) (xy 191.058274 -276.613946)
			(xy 191.102736 -276.635044) (xy 191.143239 -276.663) (xy 191.178732 -276.697092) (xy 191.208297 -276.736436)
			(xy 191.231168 -276.780013) (xy 191.246752 -276.826694) (xy 191.254647 -276.875271) (xy 191.255142 -276.899878)
			(xy 191.59399 -276.899878) (xy 191.59795 -276.850824) (xy 191.609727 -276.80304) (xy 191.629018 -276.757764)
			(xy 191.655321 -276.716168) (xy 191.687956 -276.679331) (xy 191.726077 -276.648206) (xy 191.768698 -276.623599)
			(xy 191.814714 -276.606147) (xy 191.862933 -276.596303) (xy 191.912108 -276.594322) (xy 191.960963 -276.600254)
			(xy 192.008234 -276.613946) (xy 192.052696 -276.635044) (xy 192.093199 -276.663) (xy 192.128692 -276.697092)
			(xy 192.158257 -276.736436) (xy 192.181128 -276.780013) (xy 192.196712 -276.826694) (xy 192.204607 -276.875271)
			(xy 192.205102 -276.899878) (xy 192.54395 -276.899878) (xy 192.54791 -276.850824) (xy 192.559687 -276.80304)
			(xy 192.578978 -276.757764) (xy 192.605281 -276.716168) (xy 192.637916 -276.679331) (xy 192.676037 -276.648206)
			(xy 192.718658 -276.623599) (xy 192.764674 -276.606147) (xy 192.812893 -276.596303) (xy 192.862068 -276.594322)
			(xy 192.910923 -276.600254) (xy 192.958194 -276.613946) (xy 193.002656 -276.635044) (xy 193.043159 -276.663)
			(xy 193.078652 -276.697092) (xy 193.108217 -276.736436) (xy 193.131088 -276.780013) (xy 193.146672 -276.826694)
			(xy 193.154567 -276.875271) (xy 193.155062 -276.899878) (xy 193.49391 -276.899878) (xy 193.49787 -276.850824)
			(xy 193.509647 -276.80304) (xy 193.528938 -276.757764) (xy 193.555241 -276.716168) (xy 193.587876 -276.679331)
			(xy 193.625997 -276.648206) (xy 193.668618 -276.623599) (xy 193.714634 -276.606147) (xy 193.762853 -276.596303)
			(xy 193.812028 -276.594322) (xy 193.860883 -276.600254) (xy 193.908154 -276.613946) (xy 193.952616 -276.635044)
			(xy 193.993119 -276.663) (xy 194.028612 -276.697092) (xy 194.058177 -276.736436) (xy 194.081048 -276.780013)
			(xy 194.096632 -276.826694) (xy 194.104527 -276.875271) (xy 194.105022 -276.899878) (xy 194.44387 -276.899878)
			(xy 194.44783 -276.850824) (xy 194.459607 -276.80304) (xy 194.478898 -276.757764) (xy 194.505201 -276.716168)
			(xy 194.537836 -276.679331) (xy 194.575957 -276.648206) (xy 194.618578 -276.623599) (xy 194.664594 -276.606147)
			(xy 194.712813 -276.596303) (xy 194.761988 -276.594322) (xy 194.810843 -276.600254) (xy 194.858114 -276.613946)
			(xy 194.902576 -276.635044) (xy 194.943079 -276.663) (xy 194.978572 -276.697092) (xy 195.008137 -276.736436)
			(xy 195.031008 -276.780013) (xy 195.046592 -276.826694) (xy 195.054487 -276.875271) (xy 195.054982 -276.899878)
			(xy 195.39383 -276.899878) (xy 195.39779 -276.850824) (xy 195.409567 -276.80304) (xy 195.428858 -276.757764)
			(xy 195.455161 -276.716168) (xy 195.487796 -276.679331) (xy 195.525917 -276.648206) (xy 195.568538 -276.623599)
			(xy 195.614554 -276.606147) (xy 195.662773 -276.596303) (xy 195.711948 -276.594322) (xy 195.760803 -276.600254)
			(xy 195.808074 -276.613946) (xy 195.852536 -276.635044) (xy 195.893039 -276.663) (xy 195.928532 -276.697092)
			(xy 195.958097 -276.736436) (xy 195.980968 -276.780013) (xy 195.996552 -276.826694) (xy 196.004447 -276.875271)
			(xy 196.004942 -276.899878) (xy 196.344044 -276.899878) (xy 196.348004 -276.850824) (xy 196.359781 -276.80304)
			(xy 196.379072 -276.757764) (xy 196.405375 -276.716168) (xy 196.43801 -276.679331) (xy 196.476131 -276.648206)
			(xy 196.518752 -276.623599) (xy 196.564768 -276.606147) (xy 196.612987 -276.596303) (xy 196.662162 -276.594322)
			(xy 196.711017 -276.600254) (xy 196.758288 -276.613946) (xy 196.80275 -276.635044) (xy 196.843253 -276.663)
			(xy 196.878746 -276.697092) (xy 196.908311 -276.736436) (xy 196.931182 -276.780013) (xy 196.946766 -276.826694)
			(xy 196.954661 -276.875271) (xy 196.955156 -276.899878) (xy 196.954661 -276.924485) (xy 196.954482 -276.925586)
			(xy 197.273414 -276.925586) (xy 197.273414 -276.87417) (xy 197.281457 -276.823388) (xy 197.297345 -276.774489)
			(xy 197.320688 -276.728677) (xy 197.350909 -276.687081) (xy 197.387265 -276.650725) (xy 197.428861 -276.620504)
			(xy 197.474673 -276.597161) (xy 197.523572 -276.581273) (xy 197.574354 -276.57323) (xy 197.62577 -276.57323)
			(xy 197.676552 -276.581273) (xy 197.725451 -276.597161) (xy 197.771263 -276.620504) (xy 197.812859 -276.650725)
			(xy 197.849215 -276.687081) (xy 197.879436 -276.728677) (xy 197.902779 -276.774489) (xy 197.918667 -276.823388)
			(xy 197.92671 -276.87417) (xy 197.927214 -276.899878) (xy 197.92671 -276.925586) (xy 198.223374 -276.925586)
			(xy 198.223374 -276.87417) (xy 198.231417 -276.823388) (xy 198.247305 -276.774489) (xy 198.270648 -276.728677)
			(xy 198.300869 -276.687081) (xy 198.337225 -276.650725) (xy 198.378821 -276.620504) (xy 198.424633 -276.597161)
			(xy 198.473532 -276.581273) (xy 198.524314 -276.57323) (xy 198.57573 -276.57323) (xy 198.626512 -276.581273)
			(xy 198.675411 -276.597161) (xy 198.721223 -276.620504) (xy 198.762819 -276.650725) (xy 198.799175 -276.687081)
			(xy 198.829396 -276.728677) (xy 198.852739 -276.774489) (xy 198.868627 -276.823388) (xy 198.87667 -276.87417)
			(xy 198.877174 -276.899878) (xy 198.877169 -276.900132) (xy 199.194432 -276.900132) (xy 199.198392 -276.851078)
			(xy 199.210169 -276.803294) (xy 199.22946 -276.758018) (xy 199.255763 -276.716422) (xy 199.288398 -276.679585)
			(xy 199.326519 -276.64846) (xy 199.36914 -276.623853) (xy 199.415156 -276.606401) (xy 199.463375 -276.596557)
			(xy 199.51255 -276.594576) (xy 199.561405 -276.600508) (xy 199.608676 -276.6142) (xy 199.653138 -276.635298)
			(xy 199.693641 -276.663254) (xy 199.729134 -276.697346) (xy 199.758699 -276.73669) (xy 199.78157 -276.780267)
			(xy 199.797154 -276.826948) (xy 199.805049 -276.875525) (xy 199.805544 -276.900132) (xy 199.805049 -276.924739)
			(xy 199.797154 -276.973316) (xy 199.78157 -277.019997) (xy 199.758699 -277.063574) (xy 199.729134 -277.102918)
			(xy 199.698293 -277.132542) (xy 215.516966 -277.132542) (xy 215.521037 -277.07692) (xy 215.533163 -277.022483)
			(xy 215.553086 -276.970392) (xy 215.580382 -276.921757) (xy 215.614468 -276.877614) (xy 215.654617 -276.838905)
			(xy 215.699975 -276.806454) (xy 215.749575 -276.780953) (xy 215.802359 -276.762946) (xy 215.857202 -276.752816)
			(xy 215.912936 -276.750779) (xy 215.968373 -276.756879) (xy 216.02233 -276.770985) (xy 216.073659 -276.792797)
			(xy 216.121265 -276.821851) (xy 216.164133 -276.857526) (xy 216.20135 -276.899063) (xy 216.232123 -276.945576)
			(xy 216.255795 -276.996073) (xy 216.271863 -277.04948) (xy 216.279983 -277.104656) (xy 216.280492 -277.132542)
			(xy 216.279983 -277.160428) (xy 216.2722 -277.213314) (xy 227.470206 -277.213314) (xy 227.474277 -277.157692)
			(xy 227.486403 -277.103255) (xy 227.506326 -277.051164) (xy 227.533622 -277.002529) (xy 227.567708 -276.958386)
			(xy 227.607857 -276.919677) (xy 227.653215 -276.887226) (xy 227.702815 -276.861725) (xy 227.755599 -276.843718)
			(xy 227.810442 -276.833588) (xy 227.866176 -276.831551) (xy 227.921613 -276.837651) (xy 227.97557 -276.851757)
			(xy 228.026899 -276.873569) (xy 228.074505 -276.902623) (xy 228.117373 -276.938298) (xy 228.15459 -276.979835)
			(xy 228.185363 -277.026348) (xy 228.209035 -277.076845) (xy 228.225103 -277.130252) (xy 228.233223 -277.185428)
			(xy 228.233523 -277.201884) (xy 228.659688 -277.201884) (xy 228.663759 -277.146262) (xy 228.675885 -277.091825)
			(xy 228.695808 -277.039734) (xy 228.723104 -276.991099) (xy 228.75719 -276.946956) (xy 228.797339 -276.908247)
			(xy 228.842697 -276.875796) (xy 228.892297 -276.850295) (xy 228.945081 -276.832288) (xy 228.999924 -276.822158)
			(xy 229.055658 -276.820121) (xy 229.111095 -276.826221) (xy 229.165052 -276.840327) (xy 229.216381 -276.862139)
			(xy 229.263987 -276.891193) (xy 229.306855 -276.926868) (xy 229.344072 -276.968405) (xy 229.374845 -277.014918)
			(xy 229.398517 -277.065415) (xy 229.414585 -277.118822) (xy 229.422705 -277.173998) (xy 229.423214 -277.201884)
			(xy 229.422705 -277.22977) (xy 229.414585 -277.284946) (xy 229.398517 -277.338353) (xy 229.374845 -277.38885)
			(xy 229.344072 -277.435363) (xy 229.306855 -277.4769) (xy 229.263987 -277.512575) (xy 229.216381 -277.541629)
			(xy 229.165052 -277.563441) (xy 229.111095 -277.577547) (xy 229.055658 -277.583647) (xy 228.999924 -277.58161)
			(xy 228.945081 -277.57148) (xy 228.892297 -277.553473) (xy 228.842697 -277.527972) (xy 228.797339 -277.495521)
			(xy 228.75719 -277.456812) (xy 228.723104 -277.412669) (xy 228.695808 -277.364034) (xy 228.675885 -277.311943)
			(xy 228.663759 -277.257506) (xy 228.659688 -277.201884) (xy 228.233523 -277.201884) (xy 228.233732 -277.213314)
			(xy 228.233223 -277.2412) (xy 228.225103 -277.296376) (xy 228.209035 -277.349783) (xy 228.185363 -277.40028)
			(xy 228.15459 -277.446793) (xy 228.117373 -277.48833) (xy 228.074505 -277.524005) (xy 228.026899 -277.553059)
			(xy 227.97557 -277.574871) (xy 227.921613 -277.588977) (xy 227.866176 -277.595077) (xy 227.810442 -277.59304)
			(xy 227.755599 -277.58291) (xy 227.702815 -277.564903) (xy 227.653215 -277.539402) (xy 227.607857 -277.506951)
			(xy 227.567708 -277.468242) (xy 227.533622 -277.424099) (xy 227.506326 -277.375464) (xy 227.486403 -277.323373)
			(xy 227.474277 -277.268936) (xy 227.470206 -277.213314) (xy 216.2722 -277.213314) (xy 216.271863 -277.215604)
			(xy 216.255795 -277.269011) (xy 216.232123 -277.319508) (xy 216.20135 -277.366021) (xy 216.164133 -277.407558)
			(xy 216.121265 -277.443233) (xy 216.073659 -277.472287) (xy 216.02233 -277.494099) (xy 215.968373 -277.508205)
			(xy 215.912936 -277.514305) (xy 215.857202 -277.512268) (xy 215.802359 -277.502138) (xy 215.749575 -277.484131)
			(xy 215.699975 -277.45863) (xy 215.654617 -277.426179) (xy 215.614468 -277.38747) (xy 215.580382 -277.343327)
			(xy 215.553086 -277.294692) (xy 215.533163 -277.242601) (xy 215.521037 -277.188164) (xy 215.516966 -277.132542)
			(xy 199.698293 -277.132542) (xy 199.693641 -277.13701) (xy 199.653138 -277.164966) (xy 199.608676 -277.186064)
			(xy 199.561405 -277.199756) (xy 199.51255 -277.205688) (xy 199.463375 -277.203707) (xy 199.415156 -277.193863)
			(xy 199.36914 -277.176411) (xy 199.326519 -277.151804) (xy 199.288398 -277.120679) (xy 199.255763 -277.083842)
			(xy 199.22946 -277.042246) (xy 199.210169 -276.99697) (xy 199.198392 -276.949186) (xy 199.194432 -276.900132)
			(xy 198.877169 -276.900132) (xy 198.87667 -276.925586) (xy 198.868627 -276.976368) (xy 198.852739 -277.025267)
			(xy 198.829396 -277.071079) (xy 198.799175 -277.112675) (xy 198.762819 -277.149031) (xy 198.721223 -277.179252)
			(xy 198.675411 -277.202595) (xy 198.626512 -277.218483) (xy 198.57573 -277.226526) (xy 198.524314 -277.226526)
			(xy 198.473532 -277.218483) (xy 198.424633 -277.202595) (xy 198.378821 -277.179252) (xy 198.337225 -277.149031)
			(xy 198.300869 -277.112675) (xy 198.270648 -277.071079) (xy 198.247305 -277.025267) (xy 198.231417 -276.976368)
			(xy 198.223374 -276.925586) (xy 197.92671 -276.925586) (xy 197.918667 -276.976368) (xy 197.902779 -277.025267)
			(xy 197.879436 -277.071079) (xy 197.849215 -277.112675) (xy 197.812859 -277.149031) (xy 197.771263 -277.179252)
			(xy 197.725451 -277.202595) (xy 197.676552 -277.218483) (xy 197.62577 -277.226526) (xy 197.574354 -277.226526)
			(xy 197.523572 -277.218483) (xy 197.474673 -277.202595) (xy 197.428861 -277.179252) (xy 197.387265 -277.149031)
			(xy 197.350909 -277.112675) (xy 197.320688 -277.071079) (xy 197.297345 -277.025267) (xy 197.281457 -276.976368)
			(xy 197.273414 -276.925586) (xy 196.954482 -276.925586) (xy 196.946766 -276.973062) (xy 196.931182 -277.019743)
			(xy 196.908311 -277.06332) (xy 196.878746 -277.102664) (xy 196.843253 -277.136756) (xy 196.80275 -277.164712)
			(xy 196.758288 -277.18581) (xy 196.711017 -277.199502) (xy 196.662162 -277.205434) (xy 196.612987 -277.203453)
			(xy 196.564768 -277.193609) (xy 196.518752 -277.176157) (xy 196.476131 -277.15155) (xy 196.43801 -277.120425)
			(xy 196.405375 -277.083588) (xy 196.379072 -277.041992) (xy 196.359781 -276.996716) (xy 196.348004 -276.948932)
			(xy 196.344044 -276.899878) (xy 196.004942 -276.899878) (xy 196.004447 -276.924485) (xy 195.996552 -276.973062)
			(xy 195.980968 -277.019743) (xy 195.958097 -277.06332) (xy 195.928532 -277.102664) (xy 195.893039 -277.136756)
			(xy 195.852536 -277.164712) (xy 195.808074 -277.18581) (xy 195.760803 -277.199502) (xy 195.711948 -277.205434)
			(xy 195.662773 -277.203453) (xy 195.614554 -277.193609) (xy 195.568538 -277.176157) (xy 195.525917 -277.15155)
			(xy 195.487796 -277.120425) (xy 195.455161 -277.083588) (xy 195.428858 -277.041992) (xy 195.409567 -276.996716)
			(xy 195.39779 -276.948932) (xy 195.39383 -276.899878) (xy 195.054982 -276.899878) (xy 195.054487 -276.924485)
			(xy 195.046592 -276.973062) (xy 195.031008 -277.019743) (xy 195.008137 -277.06332) (xy 194.978572 -277.102664)
			(xy 194.943079 -277.136756) (xy 194.902576 -277.164712) (xy 194.858114 -277.18581) (xy 194.810843 -277.199502)
			(xy 194.761988 -277.205434) (xy 194.712813 -277.203453) (xy 194.664594 -277.193609) (xy 194.618578 -277.176157)
			(xy 194.575957 -277.15155) (xy 194.537836 -277.120425) (xy 194.505201 -277.083588) (xy 194.478898 -277.041992)
			(xy 194.459607 -276.996716) (xy 194.44783 -276.948932) (xy 194.44387 -276.899878) (xy 194.105022 -276.899878)
			(xy 194.104527 -276.924485) (xy 194.096632 -276.973062) (xy 194.081048 -277.019743) (xy 194.058177 -277.06332)
			(xy 194.028612 -277.102664) (xy 193.993119 -277.136756) (xy 193.952616 -277.164712) (xy 193.908154 -277.18581)
			(xy 193.860883 -277.199502) (xy 193.812028 -277.205434) (xy 193.762853 -277.203453) (xy 193.714634 -277.193609)
			(xy 193.668618 -277.176157) (xy 193.625997 -277.15155) (xy 193.587876 -277.120425) (xy 193.555241 -277.083588)
			(xy 193.528938 -277.041992) (xy 193.509647 -276.996716) (xy 193.49787 -276.948932) (xy 193.49391 -276.899878)
			(xy 193.155062 -276.899878) (xy 193.154567 -276.924485) (xy 193.146672 -276.973062) (xy 193.131088 -277.019743)
			(xy 193.108217 -277.06332) (xy 193.078652 -277.102664) (xy 193.043159 -277.136756) (xy 193.002656 -277.164712)
			(xy 192.958194 -277.18581) (xy 192.910923 -277.199502) (xy 192.862068 -277.205434) (xy 192.812893 -277.203453)
			(xy 192.764674 -277.193609) (xy 192.718658 -277.176157) (xy 192.676037 -277.15155) (xy 192.637916 -277.120425)
			(xy 192.605281 -277.083588) (xy 192.578978 -277.041992) (xy 192.559687 -276.996716) (xy 192.54791 -276.948932)
			(xy 192.54395 -276.899878) (xy 192.205102 -276.899878) (xy 192.204607 -276.924485) (xy 192.196712 -276.973062)
			(xy 192.181128 -277.019743) (xy 192.158257 -277.06332) (xy 192.128692 -277.102664) (xy 192.093199 -277.136756)
			(xy 192.052696 -277.164712) (xy 192.008234 -277.18581) (xy 191.960963 -277.199502) (xy 191.912108 -277.205434)
			(xy 191.862933 -277.203453) (xy 191.814714 -277.193609) (xy 191.768698 -277.176157) (xy 191.726077 -277.15155)
			(xy 191.687956 -277.120425) (xy 191.655321 -277.083588) (xy 191.629018 -277.041992) (xy 191.609727 -276.996716)
			(xy 191.59795 -276.948932) (xy 191.59399 -276.899878) (xy 191.255142 -276.899878) (xy 191.254647 -276.924485)
			(xy 191.246752 -276.973062) (xy 191.231168 -277.019743) (xy 191.208297 -277.06332) (xy 191.178732 -277.102664)
			(xy 191.143239 -277.136756) (xy 191.102736 -277.164712) (xy 191.058274 -277.18581) (xy 191.011003 -277.199502)
			(xy 190.962148 -277.205434) (xy 190.912973 -277.203453) (xy 190.864754 -277.193609) (xy 190.818738 -277.176157)
			(xy 190.776117 -277.15155) (xy 190.737996 -277.120425) (xy 190.705361 -277.083588) (xy 190.679058 -277.041992)
			(xy 190.659767 -276.996716) (xy 190.64799 -276.948932) (xy 190.64403 -276.899878) (xy 190.304928 -276.899878)
			(xy 190.304433 -276.924485) (xy 190.296538 -276.973062) (xy 190.280954 -277.019743) (xy 190.258083 -277.06332)
			(xy 190.228518 -277.102664) (xy 190.193025 -277.136756) (xy 190.152522 -277.164712) (xy 190.10806 -277.18581)
			(xy 190.060789 -277.199502) (xy 190.011934 -277.205434) (xy 189.962759 -277.203453) (xy 189.91454 -277.193609)
			(xy 189.868524 -277.176157) (xy 189.825903 -277.15155) (xy 189.787782 -277.120425) (xy 189.755147 -277.083588)
			(xy 189.728844 -277.041992) (xy 189.709553 -276.996716) (xy 189.697776 -276.948932) (xy 189.693816 -276.899878)
			(xy 189.355222 -276.899878) (xy 189.354727 -276.924485) (xy 189.346832 -276.973062) (xy 189.331248 -277.019743)
			(xy 189.308377 -277.06332) (xy 189.278812 -277.102664) (xy 189.243319 -277.136756) (xy 189.202816 -277.164712)
			(xy 189.158354 -277.18581) (xy 189.111083 -277.199502) (xy 189.062228 -277.205434) (xy 189.013053 -277.203453)
			(xy 188.964834 -277.193609) (xy 188.918818 -277.176157) (xy 188.876197 -277.15155) (xy 188.838076 -277.120425)
			(xy 188.805441 -277.083588) (xy 188.779138 -277.041992) (xy 188.759847 -276.996716) (xy 188.74807 -276.948932)
			(xy 188.74411 -276.899878) (xy 188.405262 -276.899878) (xy 188.404767 -276.924485) (xy 188.396872 -276.973062)
			(xy 188.381288 -277.019743) (xy 188.358417 -277.06332) (xy 188.328852 -277.102664) (xy 188.293359 -277.136756)
			(xy 188.252856 -277.164712) (xy 188.208394 -277.18581) (xy 188.161123 -277.199502) (xy 188.112268 -277.205434)
			(xy 188.063093 -277.203453) (xy 188.014874 -277.193609) (xy 187.968858 -277.176157) (xy 187.926237 -277.15155)
			(xy 187.888116 -277.120425) (xy 187.855481 -277.083588) (xy 187.829178 -277.041992) (xy 187.809887 -276.996716)
			(xy 187.79811 -276.948932) (xy 187.79415 -276.899878) (xy 187.455302 -276.899878) (xy 187.454807 -276.924485)
			(xy 187.446912 -276.973062) (xy 187.431328 -277.019743) (xy 187.408457 -277.06332) (xy 187.378892 -277.102664)
			(xy 187.343399 -277.136756) (xy 187.302896 -277.164712) (xy 187.258434 -277.18581) (xy 187.211163 -277.199502)
			(xy 187.162308 -277.205434) (xy 187.113133 -277.203453) (xy 187.064914 -277.193609) (xy 187.018898 -277.176157)
			(xy 186.976277 -277.15155) (xy 186.938156 -277.120425) (xy 186.905521 -277.083588) (xy 186.879218 -277.041992)
			(xy 186.859927 -276.996716) (xy 186.84815 -276.948932) (xy 186.84419 -276.899878) (xy 186.505342 -276.899878)
			(xy 186.504847 -276.924485) (xy 186.496952 -276.973062) (xy 186.481368 -277.019743) (xy 186.458497 -277.06332)
			(xy 186.428932 -277.102664) (xy 186.393439 -277.136756) (xy 186.352936 -277.164712) (xy 186.308474 -277.18581)
			(xy 186.261203 -277.199502) (xy 186.212348 -277.205434) (xy 186.163173 -277.203453) (xy 186.114954 -277.193609)
			(xy 186.068938 -277.176157) (xy 186.026317 -277.15155) (xy 185.988196 -277.120425) (xy 185.955561 -277.083588)
			(xy 185.929258 -277.041992) (xy 185.909967 -276.996716) (xy 185.89819 -276.948932) (xy 185.89423 -276.899878)
			(xy 185.555382 -276.899878) (xy 185.554887 -276.924485) (xy 185.546992 -276.973062) (xy 185.531408 -277.019743)
			(xy 185.508537 -277.06332) (xy 185.478972 -277.102664) (xy 185.443479 -277.136756) (xy 185.402976 -277.164712)
			(xy 185.358514 -277.18581) (xy 185.311243 -277.199502) (xy 185.262388 -277.205434) (xy 185.213213 -277.203453)
			(xy 185.164994 -277.193609) (xy 185.118978 -277.176157) (xy 185.076357 -277.15155) (xy 185.038236 -277.120425)
			(xy 185.005601 -277.083588) (xy 184.979298 -277.041992) (xy 184.960007 -276.996716) (xy 184.94823 -276.948932)
			(xy 184.94427 -276.899878) (xy 184.605168 -276.899878) (xy 184.604673 -276.924485) (xy 184.596778 -276.973062)
			(xy 184.581194 -277.019743) (xy 184.558323 -277.06332) (xy 184.528758 -277.102664) (xy 184.493265 -277.136756)
			(xy 184.452762 -277.164712) (xy 184.4083 -277.18581) (xy 184.361029 -277.199502) (xy 184.312174 -277.205434)
			(xy 184.262999 -277.203453) (xy 184.21478 -277.193609) (xy 184.168764 -277.176157) (xy 184.126143 -277.15155)
			(xy 184.088022 -277.120425) (xy 184.055387 -277.083588) (xy 184.029084 -277.041992) (xy 184.009793 -276.996716)
			(xy 183.998016 -276.948932) (xy 183.994056 -276.899878) (xy 183.655208 -276.899878) (xy 183.654713 -276.924485)
			(xy 183.646818 -276.973062) (xy 183.631234 -277.019743) (xy 183.608363 -277.06332) (xy 183.578798 -277.102664)
			(xy 183.543305 -277.136756) (xy 183.502802 -277.164712) (xy 183.45834 -277.18581) (xy 183.411069 -277.199502)
			(xy 183.362214 -277.205434) (xy 183.313039 -277.203453) (xy 183.26482 -277.193609) (xy 183.218804 -277.176157)
			(xy 183.176183 -277.15155) (xy 183.138062 -277.120425) (xy 183.105427 -277.083588) (xy 183.079124 -277.041992)
			(xy 183.059833 -276.996716) (xy 183.048056 -276.948932) (xy 183.044096 -276.899878) (xy 182.705248 -276.899878)
			(xy 182.704753 -276.924485) (xy 182.696858 -276.973062) (xy 182.681274 -277.019743) (xy 182.658403 -277.06332)
			(xy 182.628838 -277.102664) (xy 182.593345 -277.136756) (xy 182.552842 -277.164712) (xy 182.50838 -277.18581)
			(xy 182.461109 -277.199502) (xy 182.412254 -277.205434) (xy 182.363079 -277.203453) (xy 182.31486 -277.193609)
			(xy 182.268844 -277.176157) (xy 182.226223 -277.15155) (xy 182.188102 -277.120425) (xy 182.155467 -277.083588)
			(xy 182.129164 -277.041992) (xy 182.109873 -276.996716) (xy 182.098096 -276.948932) (xy 182.094136 -276.899878)
			(xy 181.755288 -276.899878) (xy 181.754793 -276.924485) (xy 181.746898 -276.973062) (xy 181.731314 -277.019743)
			(xy 181.708443 -277.06332) (xy 181.678878 -277.102664) (xy 181.643385 -277.136756) (xy 181.602882 -277.164712)
			(xy 181.55842 -277.18581) (xy 181.511149 -277.199502) (xy 181.462294 -277.205434) (xy 181.413119 -277.203453)
			(xy 181.3649 -277.193609) (xy 181.318884 -277.176157) (xy 181.276263 -277.15155) (xy 181.238142 -277.120425)
			(xy 181.205507 -277.083588) (xy 181.179204 -277.041992) (xy 181.159913 -276.996716) (xy 181.148136 -276.948932)
			(xy 181.144176 -276.899878) (xy 180.805328 -276.899878) (xy 180.804833 -276.924485) (xy 180.796938 -276.973062)
			(xy 180.781354 -277.019743) (xy 180.758483 -277.06332) (xy 180.728918 -277.102664) (xy 180.693425 -277.136756)
			(xy 180.652922 -277.164712) (xy 180.60846 -277.18581) (xy 180.561189 -277.199502) (xy 180.512334 -277.205434)
			(xy 180.463159 -277.203453) (xy 180.41494 -277.193609) (xy 180.368924 -277.176157) (xy 180.326303 -277.15155)
			(xy 180.288182 -277.120425) (xy 180.255547 -277.083588) (xy 180.229244 -277.041992) (xy 180.209953 -276.996716)
			(xy 180.198176 -276.948932) (xy 180.194216 -276.899878) (xy 179.855368 -276.899878) (xy 179.854873 -276.924485)
			(xy 179.846978 -276.973062) (xy 179.831394 -277.019743) (xy 179.808523 -277.06332) (xy 179.778958 -277.102664)
			(xy 179.743465 -277.136756) (xy 179.702962 -277.164712) (xy 179.6585 -277.18581) (xy 179.611229 -277.199502)
			(xy 179.562374 -277.205434) (xy 179.513199 -277.203453) (xy 179.46498 -277.193609) (xy 179.418964 -277.176157)
			(xy 179.376343 -277.15155) (xy 179.338222 -277.120425) (xy 179.305587 -277.083588) (xy 179.279284 -277.041992)
			(xy 179.259993 -276.996716) (xy 179.248216 -276.948932) (xy 179.244256 -276.899878) (xy 178.905154 -276.899878)
			(xy 178.904659 -276.924485) (xy 178.896764 -276.973062) (xy 178.88118 -277.019743) (xy 178.858309 -277.06332)
			(xy 178.828744 -277.102664) (xy 178.793251 -277.136756) (xy 178.752748 -277.164712) (xy 178.708286 -277.18581)
			(xy 178.661015 -277.199502) (xy 178.61216 -277.205434) (xy 178.562985 -277.203453) (xy 178.514766 -277.193609)
			(xy 178.46875 -277.176157) (xy 178.426129 -277.15155) (xy 178.388008 -277.120425) (xy 178.355373 -277.083588)
			(xy 178.32907 -277.041992) (xy 178.309779 -276.996716) (xy 178.298002 -276.948932) (xy 178.294042 -276.899878)
			(xy 177.955194 -276.899878) (xy 177.954699 -276.924485) (xy 177.946804 -276.973062) (xy 177.93122 -277.019743)
			(xy 177.908349 -277.06332) (xy 177.878784 -277.102664) (xy 177.843291 -277.136756) (xy 177.802788 -277.164712)
			(xy 177.758326 -277.18581) (xy 177.711055 -277.199502) (xy 177.6622 -277.205434) (xy 177.613025 -277.203453)
			(xy 177.564806 -277.193609) (xy 177.51879 -277.176157) (xy 177.476169 -277.15155) (xy 177.438048 -277.120425)
			(xy 177.405413 -277.083588) (xy 177.37911 -277.041992) (xy 177.359819 -276.996716) (xy 177.348042 -276.948932)
			(xy 177.344082 -276.899878) (xy 177.005234 -276.899878) (xy 177.004739 -276.924485) (xy 176.996844 -276.973062)
			(xy 176.98126 -277.019743) (xy 176.958389 -277.06332) (xy 176.928824 -277.102664) (xy 176.893331 -277.136756)
			(xy 176.852828 -277.164712) (xy 176.808366 -277.18581) (xy 176.761095 -277.199502) (xy 176.71224 -277.205434)
			(xy 176.663065 -277.203453) (xy 176.614846 -277.193609) (xy 176.56883 -277.176157) (xy 176.526209 -277.15155)
			(xy 176.488088 -277.120425) (xy 176.455453 -277.083588) (xy 176.42915 -277.041992) (xy 176.409859 -276.996716)
			(xy 176.398082 -276.948932) (xy 176.394122 -276.899878) (xy 176.05588 -276.899878) (xy 176.055882 -276.8999)
			(xy 176.05171 -276.95025) (xy 176.039306 -276.999227) (xy 176.01901 -277.045493) (xy 175.991375 -277.087788)
			(xy 175.957155 -277.124957) (xy 175.917284 -277.155986) (xy 175.872848 -277.180029) (xy 175.825062 -277.196429)
			(xy 175.775227 -277.20474) (xy 175.749966 -277.205186) (xy 175.724905 -277.204657) (xy 175.67546 -277.196437)
			(xy 175.628015 -277.18027) (xy 175.605694 -277.168864) (xy 175.599598 -277.165562) (xy 175.587152 -277.162768)
			(xy 175.580548 -277.163022) (xy 175.574064 -277.163382) (xy 175.561592 -277.166989) (xy 175.55591 -277.170134)
			(xy 175.48098 -277.214838) (xy 175.47336 -277.220426) (xy 175.466588 -277.226971) (xy 175.457863 -277.243644)
			(xy 175.456342 -277.252938) (xy 175.456088 -277.258272) (xy 175.456088 -277.466806) (xy 175.456596 -277.474172)
			(xy 175.458691 -277.484784) (xy 175.470389 -277.502956) (xy 175.479202 -277.509224) (xy 175.47971 -277.509732)
			(xy 175.480218 -277.509986) (xy 175.553624 -277.555198) (xy 175.559318 -277.558533) (xy 175.571931 -277.562399)
			(xy 175.578516 -277.562818) (xy 175.591216 -277.563326) (xy 175.6029 -277.557484) (xy 175.603408 -277.557484)
			(xy 175.626161 -277.546617) (xy 175.674181 -277.531243) (xy 175.723994 -277.523433) (xy 175.749204 -277.52294)
			(xy 175.749712 -277.52294) (xy 175.775396 -277.523445) (xy 175.826132 -277.531482) (xy 175.874986 -277.547357)
			(xy 175.920755 -277.570679) (xy 175.962312 -277.600874) (xy 175.998634 -277.637197) (xy 176.028827 -277.678756)
			(xy 176.052147 -277.724525) (xy 176.068021 -277.77338) (xy 176.076056 -277.824116) (xy 176.076056 -277.849838)
			(xy 176.394122 -277.849838) (xy 176.398082 -277.800784) (xy 176.409859 -277.753) (xy 176.42915 -277.707724)
			(xy 176.455453 -277.666128) (xy 176.488088 -277.629291) (xy 176.526209 -277.598166) (xy 176.56883 -277.573559)
			(xy 176.614846 -277.556107) (xy 176.663065 -277.546263) (xy 176.71224 -277.544282) (xy 176.761095 -277.550214)
			(xy 176.808366 -277.563906) (xy 176.852828 -277.585004) (xy 176.893331 -277.61296) (xy 176.928824 -277.647052)
			(xy 176.958389 -277.686396) (xy 176.98126 -277.729973) (xy 176.996844 -277.776654) (xy 177.004739 -277.825231)
			(xy 177.005234 -277.849838) (xy 177.004739 -277.874445) (xy 177.00456 -277.875546) (xy 177.322984 -277.875546)
			(xy 177.322984 -277.82413) (xy 177.331027 -277.773348) (xy 177.346915 -277.724449) (xy 177.370258 -277.678637)
			(xy 177.400479 -277.637041) (xy 177.436835 -277.600685) (xy 177.478431 -277.570464) (xy 177.524243 -277.547121)
			(xy 177.573142 -277.531233) (xy 177.623924 -277.52319) (xy 177.67534 -277.52319) (xy 177.726122 -277.531233)
			(xy 177.775021 -277.547121) (xy 177.820833 -277.570464) (xy 177.862429 -277.600685) (xy 177.898785 -277.637041)
			(xy 177.929006 -277.678637) (xy 177.952349 -277.724449) (xy 177.968237 -277.773348) (xy 177.97628 -277.82413)
			(xy 177.976784 -277.849838) (xy 178.294042 -277.849838) (xy 178.298002 -277.800784) (xy 178.309779 -277.753)
			(xy 178.32907 -277.707724) (xy 178.355373 -277.666128) (xy 178.388008 -277.629291) (xy 178.426129 -277.598166)
			(xy 178.46875 -277.573559) (xy 178.514766 -277.556107) (xy 178.562985 -277.546263) (xy 178.61216 -277.544282)
			(xy 178.661015 -277.550214) (xy 178.708286 -277.563906) (xy 178.752748 -277.585004) (xy 178.793251 -277.61296)
			(xy 178.828744 -277.647052) (xy 178.858309 -277.686396) (xy 178.88118 -277.729973) (xy 178.896764 -277.776654)
			(xy 178.904659 -277.825231) (xy 178.905154 -277.849838) (xy 178.904659 -277.874445) (xy 178.90448 -277.875546)
			(xy 179.223158 -277.875546) (xy 179.223158 -277.82413) (xy 179.231201 -277.773348) (xy 179.247089 -277.724449)
			(xy 179.270432 -277.678637) (xy 179.300653 -277.637041) (xy 179.337009 -277.600685) (xy 179.378605 -277.570464)
			(xy 179.424417 -277.547121) (xy 179.473316 -277.531233) (xy 179.524098 -277.52319) (xy 179.575514 -277.52319)
			(xy 179.626296 -277.531233) (xy 179.675195 -277.547121) (xy 179.721007 -277.570464) (xy 179.762603 -277.600685)
			(xy 179.798959 -277.637041) (xy 179.82918 -277.678637) (xy 179.852523 -277.724449) (xy 179.868411 -277.773348)
			(xy 179.876454 -277.82413) (xy 179.876958 -277.849838) (xy 180.194216 -277.849838) (xy 180.198176 -277.800784)
			(xy 180.209953 -277.753) (xy 180.229244 -277.707724) (xy 180.255547 -277.666128) (xy 180.288182 -277.629291)
			(xy 180.326303 -277.598166) (xy 180.368924 -277.573559) (xy 180.41494 -277.556107) (xy 180.463159 -277.546263)
			(xy 180.512334 -277.544282) (xy 180.561189 -277.550214) (xy 180.60846 -277.563906) (xy 180.652922 -277.585004)
			(xy 180.693425 -277.61296) (xy 180.728918 -277.647052) (xy 180.758483 -277.686396) (xy 180.781354 -277.729973)
			(xy 180.796938 -277.776654) (xy 180.804833 -277.825231) (xy 180.805328 -277.849838) (xy 180.804833 -277.874445)
			(xy 180.804654 -277.875546) (xy 181.123078 -277.875546) (xy 181.123078 -277.82413) (xy 181.131121 -277.773348)
			(xy 181.147009 -277.724449) (xy 181.170352 -277.678637) (xy 181.200573 -277.637041) (xy 181.236929 -277.600685)
			(xy 181.278525 -277.570464) (xy 181.324337 -277.547121) (xy 181.373236 -277.531233) (xy 181.424018 -277.52319)
			(xy 181.475434 -277.52319) (xy 181.526216 -277.531233) (xy 181.575115 -277.547121) (xy 181.620927 -277.570464)
			(xy 181.662523 -277.600685) (xy 181.698879 -277.637041) (xy 181.7291 -277.678637) (xy 181.752443 -277.724449)
			(xy 181.768331 -277.773348) (xy 181.776374 -277.82413) (xy 181.776878 -277.849838) (xy 182.094136 -277.849838)
			(xy 182.098096 -277.800784) (xy 182.109873 -277.753) (xy 182.129164 -277.707724) (xy 182.155467 -277.666128)
			(xy 182.188102 -277.629291) (xy 182.226223 -277.598166) (xy 182.268844 -277.573559) (xy 182.31486 -277.556107)
			(xy 182.363079 -277.546263) (xy 182.412254 -277.544282) (xy 182.461109 -277.550214) (xy 182.50838 -277.563906)
			(xy 182.552842 -277.585004) (xy 182.593345 -277.61296) (xy 182.628838 -277.647052) (xy 182.658403 -277.686396)
			(xy 182.681274 -277.729973) (xy 182.696858 -277.776654) (xy 182.704753 -277.825231) (xy 182.705248 -277.849838)
			(xy 182.704753 -277.874445) (xy 182.704574 -277.875546) (xy 183.022998 -277.875546) (xy 183.022998 -277.82413)
			(xy 183.031041 -277.773348) (xy 183.046929 -277.724449) (xy 183.070272 -277.678637) (xy 183.100493 -277.637041)
			(xy 183.136849 -277.600685) (xy 183.178445 -277.570464) (xy 183.224257 -277.547121) (xy 183.273156 -277.531233)
			(xy 183.323938 -277.52319) (xy 183.375354 -277.52319) (xy 183.426136 -277.531233) (xy 183.475035 -277.547121)
			(xy 183.520847 -277.570464) (xy 183.562443 -277.600685) (xy 183.598799 -277.637041) (xy 183.62902 -277.678637)
			(xy 183.652363 -277.724449) (xy 183.668251 -277.773348) (xy 183.676294 -277.82413) (xy 183.676798 -277.849838)
			(xy 183.994056 -277.849838) (xy 183.998016 -277.800784) (xy 184.009793 -277.753) (xy 184.029084 -277.707724)
			(xy 184.055387 -277.666128) (xy 184.088022 -277.629291) (xy 184.126143 -277.598166) (xy 184.168764 -277.573559)
			(xy 184.21478 -277.556107) (xy 184.262999 -277.546263) (xy 184.312174 -277.544282) (xy 184.361029 -277.550214)
			(xy 184.4083 -277.563906) (xy 184.452762 -277.585004) (xy 184.493265 -277.61296) (xy 184.528758 -277.647052)
			(xy 184.558323 -277.686396) (xy 184.581194 -277.729973) (xy 184.596778 -277.776654) (xy 184.604673 -277.825231)
			(xy 184.605168 -277.849838) (xy 184.604673 -277.874445) (xy 184.604494 -277.875546) (xy 184.923172 -277.875546)
			(xy 184.923172 -277.82413) (xy 184.931215 -277.773348) (xy 184.947103 -277.724449) (xy 184.970446 -277.678637)
			(xy 185.000667 -277.637041) (xy 185.037023 -277.600685) (xy 185.078619 -277.570464) (xy 185.124431 -277.547121)
			(xy 185.17333 -277.531233) (xy 185.224112 -277.52319) (xy 185.275528 -277.52319) (xy 185.32631 -277.531233)
			(xy 185.375209 -277.547121) (xy 185.421021 -277.570464) (xy 185.462617 -277.600685) (xy 185.498973 -277.637041)
			(xy 185.529194 -277.678637) (xy 185.552537 -277.724449) (xy 185.568425 -277.773348) (xy 185.576468 -277.82413)
			(xy 185.576972 -277.849838) (xy 185.89423 -277.849838) (xy 185.89819 -277.800784) (xy 185.909967 -277.753)
			(xy 185.929258 -277.707724) (xy 185.955561 -277.666128) (xy 185.988196 -277.629291) (xy 186.026317 -277.598166)
			(xy 186.068938 -277.573559) (xy 186.114954 -277.556107) (xy 186.163173 -277.546263) (xy 186.212348 -277.544282)
			(xy 186.261203 -277.550214) (xy 186.308474 -277.563906) (xy 186.352936 -277.585004) (xy 186.393439 -277.61296)
			(xy 186.428932 -277.647052) (xy 186.458497 -277.686396) (xy 186.481368 -277.729973) (xy 186.496952 -277.776654)
			(xy 186.504847 -277.825231) (xy 186.505342 -277.849838) (xy 186.504847 -277.874445) (xy 186.504668 -277.875546)
			(xy 186.823092 -277.875546) (xy 186.823092 -277.82413) (xy 186.831135 -277.773348) (xy 186.847023 -277.724449)
			(xy 186.870366 -277.678637) (xy 186.900587 -277.637041) (xy 186.936943 -277.600685) (xy 186.978539 -277.570464)
			(xy 187.024351 -277.547121) (xy 187.07325 -277.531233) (xy 187.124032 -277.52319) (xy 187.175448 -277.52319)
			(xy 187.22623 -277.531233) (xy 187.275129 -277.547121) (xy 187.320941 -277.570464) (xy 187.362537 -277.600685)
			(xy 187.398893 -277.637041) (xy 187.429114 -277.678637) (xy 187.452457 -277.724449) (xy 187.468345 -277.773348)
			(xy 187.476388 -277.82413) (xy 187.476892 -277.849838) (xy 187.79415 -277.849838) (xy 187.79811 -277.800784)
			(xy 187.809887 -277.753) (xy 187.829178 -277.707724) (xy 187.855481 -277.666128) (xy 187.888116 -277.629291)
			(xy 187.926237 -277.598166) (xy 187.968858 -277.573559) (xy 188.014874 -277.556107) (xy 188.063093 -277.546263)
			(xy 188.112268 -277.544282) (xy 188.161123 -277.550214) (xy 188.208394 -277.563906) (xy 188.252856 -277.585004)
			(xy 188.293359 -277.61296) (xy 188.328852 -277.647052) (xy 188.358417 -277.686396) (xy 188.381288 -277.729973)
			(xy 188.396872 -277.776654) (xy 188.404767 -277.825231) (xy 188.405262 -277.849838) (xy 188.404767 -277.874445)
			(xy 188.404588 -277.875546) (xy 188.723012 -277.875546) (xy 188.723012 -277.82413) (xy 188.731055 -277.773348)
			(xy 188.746943 -277.724449) (xy 188.770286 -277.678637) (xy 188.800507 -277.637041) (xy 188.836863 -277.600685)
			(xy 188.878459 -277.570464) (xy 188.924271 -277.547121) (xy 188.97317 -277.531233) (xy 189.023952 -277.52319)
			(xy 189.075368 -277.52319) (xy 189.12615 -277.531233) (xy 189.175049 -277.547121) (xy 189.220861 -277.570464)
			(xy 189.262457 -277.600685) (xy 189.298813 -277.637041) (xy 189.329034 -277.678637) (xy 189.352377 -277.724449)
			(xy 189.368265 -277.773348) (xy 189.376308 -277.82413) (xy 189.376812 -277.849838) (xy 189.69407 -277.849838)
			(xy 189.69803 -277.800784) (xy 189.709807 -277.753) (xy 189.729098 -277.707724) (xy 189.755401 -277.666128)
			(xy 189.788036 -277.629291) (xy 189.826157 -277.598166) (xy 189.868778 -277.573559) (xy 189.914794 -277.556107)
			(xy 189.963013 -277.546263) (xy 190.012188 -277.544282) (xy 190.061043 -277.550214) (xy 190.108314 -277.563906)
			(xy 190.152776 -277.585004) (xy 190.193279 -277.61296) (xy 190.228772 -277.647052) (xy 190.258337 -277.686396)
			(xy 190.281208 -277.729973) (xy 190.296792 -277.776654) (xy 190.304687 -277.825231) (xy 190.305182 -277.849838)
			(xy 190.304687 -277.874445) (xy 190.304508 -277.875546) (xy 190.623186 -277.875546) (xy 190.623186 -277.82413)
			(xy 190.631229 -277.773348) (xy 190.647117 -277.724449) (xy 190.67046 -277.678637) (xy 190.700681 -277.637041)
			(xy 190.737037 -277.600685) (xy 190.778633 -277.570464) (xy 190.824445 -277.547121) (xy 190.873344 -277.531233)
			(xy 190.924126 -277.52319) (xy 190.975542 -277.52319) (xy 191.026324 -277.531233) (xy 191.075223 -277.547121)
			(xy 191.121035 -277.570464) (xy 191.162631 -277.600685) (xy 191.198987 -277.637041) (xy 191.229208 -277.678637)
			(xy 191.252551 -277.724449) (xy 191.268439 -277.773348) (xy 191.276482 -277.82413) (xy 191.276986 -277.849838)
			(xy 191.594244 -277.849838) (xy 191.598204 -277.800784) (xy 191.609981 -277.753) (xy 191.629272 -277.707724)
			(xy 191.655575 -277.666128) (xy 191.68821 -277.629291) (xy 191.726331 -277.598166) (xy 191.768952 -277.573559)
			(xy 191.814968 -277.556107) (xy 191.863187 -277.546263) (xy 191.912362 -277.544282) (xy 191.961217 -277.550214)
			(xy 192.008488 -277.563906) (xy 192.05295 -277.585004) (xy 192.093453 -277.61296) (xy 192.128946 -277.647052)
			(xy 192.158511 -277.686396) (xy 192.181382 -277.729973) (xy 192.196966 -277.776654) (xy 192.204861 -277.825231)
			(xy 192.205356 -277.849838) (xy 192.204861 -277.874445) (xy 192.204682 -277.875546) (xy 192.523106 -277.875546)
			(xy 192.523106 -277.82413) (xy 192.531149 -277.773348) (xy 192.547037 -277.724449) (xy 192.57038 -277.678637)
			(xy 192.600601 -277.637041) (xy 192.636957 -277.600685) (xy 192.678553 -277.570464) (xy 192.724365 -277.547121)
			(xy 192.773264 -277.531233) (xy 192.824046 -277.52319) (xy 192.875462 -277.52319) (xy 192.926244 -277.531233)
			(xy 192.975143 -277.547121) (xy 193.020955 -277.570464) (xy 193.062551 -277.600685) (xy 193.098907 -277.637041)
			(xy 193.129128 -277.678637) (xy 193.152471 -277.724449) (xy 193.168359 -277.773348) (xy 193.176402 -277.82413)
			(xy 193.176906 -277.849838) (xy 193.494164 -277.849838) (xy 193.498124 -277.800784) (xy 193.509901 -277.753)
			(xy 193.529192 -277.707724) (xy 193.555495 -277.666128) (xy 193.58813 -277.629291) (xy 193.626251 -277.598166)
			(xy 193.668872 -277.573559) (xy 193.714888 -277.556107) (xy 193.763107 -277.546263) (xy 193.812282 -277.544282)
			(xy 193.861137 -277.550214) (xy 193.908408 -277.563906) (xy 193.95287 -277.585004) (xy 193.993373 -277.61296)
			(xy 194.028866 -277.647052) (xy 194.058431 -277.686396) (xy 194.081302 -277.729973) (xy 194.096886 -277.776654)
			(xy 194.104781 -277.825231) (xy 194.105276 -277.849838) (xy 194.104781 -277.874445) (xy 194.104602 -277.875546)
			(xy 194.423026 -277.875546) (xy 194.423026 -277.82413) (xy 194.431069 -277.773348) (xy 194.446957 -277.724449)
			(xy 194.4703 -277.678637) (xy 194.500521 -277.637041) (xy 194.536877 -277.600685) (xy 194.578473 -277.570464)
			(xy 194.624285 -277.547121) (xy 194.673184 -277.531233) (xy 194.723966 -277.52319) (xy 194.775382 -277.52319)
			(xy 194.826164 -277.531233) (xy 194.875063 -277.547121) (xy 194.920875 -277.570464) (xy 194.962471 -277.600685)
			(xy 194.998827 -277.637041) (xy 195.029048 -277.678637) (xy 195.052391 -277.724449) (xy 195.068279 -277.773348)
			(xy 195.076322 -277.82413) (xy 195.076826 -277.849838) (xy 195.394084 -277.849838) (xy 195.398044 -277.800784)
			(xy 195.409821 -277.753) (xy 195.429112 -277.707724) (xy 195.455415 -277.666128) (xy 195.48805 -277.629291)
			(xy 195.526171 -277.598166) (xy 195.568792 -277.573559) (xy 195.614808 -277.556107) (xy 195.663027 -277.546263)
			(xy 195.712202 -277.544282) (xy 195.761057 -277.550214) (xy 195.808328 -277.563906) (xy 195.85279 -277.585004)
			(xy 195.893293 -277.61296) (xy 195.928786 -277.647052) (xy 195.958351 -277.686396) (xy 195.981222 -277.729973)
			(xy 195.996806 -277.776654) (xy 196.004701 -277.825231) (xy 196.005196 -277.849838) (xy 196.004701 -277.874445)
			(xy 196.004522 -277.875546) (xy 196.3232 -277.875546) (xy 196.3232 -277.82413) (xy 196.331243 -277.773348)
			(xy 196.347131 -277.724449) (xy 196.370474 -277.678637) (xy 196.400695 -277.637041) (xy 196.437051 -277.600685)
			(xy 196.478647 -277.570464) (xy 196.524459 -277.547121) (xy 196.573358 -277.531233) (xy 196.62414 -277.52319)
			(xy 196.675556 -277.52319) (xy 196.726338 -277.531233) (xy 196.775237 -277.547121) (xy 196.821049 -277.570464)
			(xy 196.862645 -277.600685) (xy 196.899001 -277.637041) (xy 196.929222 -277.678637) (xy 196.952565 -277.724449)
			(xy 196.968453 -277.773348) (xy 196.976496 -277.82413) (xy 196.977 -277.849838) (xy 197.294258 -277.849838)
			(xy 197.298218 -277.800784) (xy 197.309995 -277.753) (xy 197.329286 -277.707724) (xy 197.355589 -277.666128)
			(xy 197.388224 -277.629291) (xy 197.426345 -277.598166) (xy 197.468966 -277.573559) (xy 197.514982 -277.556107)
			(xy 197.563201 -277.546263) (xy 197.612376 -277.544282) (xy 197.661231 -277.550214) (xy 197.708502 -277.563906)
			(xy 197.752964 -277.585004) (xy 197.793467 -277.61296) (xy 197.82896 -277.647052) (xy 197.858525 -277.686396)
			(xy 197.881396 -277.729973) (xy 197.89698 -277.776654) (xy 197.904875 -277.825231) (xy 197.90537 -277.849838)
			(xy 198.244218 -277.849838) (xy 198.248178 -277.800784) (xy 198.259955 -277.753) (xy 198.279246 -277.707724)
			(xy 198.305549 -277.666128) (xy 198.338184 -277.629291) (xy 198.376305 -277.598166) (xy 198.418926 -277.573559)
			(xy 198.464942 -277.556107) (xy 198.513161 -277.546263) (xy 198.562336 -277.544282) (xy 198.611191 -277.550214)
			(xy 198.658462 -277.563906) (xy 198.702924 -277.585004) (xy 198.743427 -277.61296) (xy 198.77892 -277.647052)
			(xy 198.808485 -277.686396) (xy 198.831356 -277.729973) (xy 198.84694 -277.776654) (xy 198.854835 -277.825231)
			(xy 198.85533 -277.849838) (xy 198.854835 -277.874445) (xy 198.84694 -277.923022) (xy 198.831356 -277.969703)
			(xy 198.808485 -278.01328) (xy 198.77892 -278.052624) (xy 198.743427 -278.086716) (xy 198.702924 -278.114672)
			(xy 198.658462 -278.13577) (xy 198.611191 -278.149462) (xy 198.562336 -278.155394) (xy 198.513161 -278.153413)
			(xy 198.464942 -278.143569) (xy 198.418926 -278.126117) (xy 198.376305 -278.10151) (xy 198.338184 -278.070385)
			(xy 198.305549 -278.033548) (xy 198.279246 -277.991952) (xy 198.259955 -277.946676) (xy 198.248178 -277.898892)
			(xy 198.244218 -277.849838) (xy 197.90537 -277.849838) (xy 197.904875 -277.874445) (xy 197.89698 -277.923022)
			(xy 197.881396 -277.969703) (xy 197.858525 -278.01328) (xy 197.82896 -278.052624) (xy 197.793467 -278.086716)
			(xy 197.752964 -278.114672) (xy 197.708502 -278.13577) (xy 197.661231 -278.149462) (xy 197.612376 -278.155394)
			(xy 197.563201 -278.153413) (xy 197.514982 -278.143569) (xy 197.468966 -278.126117) (xy 197.426345 -278.10151)
			(xy 197.388224 -278.070385) (xy 197.355589 -278.033548) (xy 197.329286 -277.991952) (xy 197.309995 -277.946676)
			(xy 197.298218 -277.898892) (xy 197.294258 -277.849838) (xy 196.977 -277.849838) (xy 196.976496 -277.875546)
			(xy 196.968453 -277.926328) (xy 196.952565 -277.975227) (xy 196.929222 -278.021039) (xy 196.899001 -278.062635)
			(xy 196.862645 -278.098991) (xy 196.821049 -278.129212) (xy 196.775237 -278.152555) (xy 196.726338 -278.168443)
			(xy 196.681996 -278.175466) (xy 215.523824 -278.175466) (xy 215.527895 -278.119844) (xy 215.540021 -278.065407)
			(xy 215.559944 -278.013316) (xy 215.58724 -277.964681) (xy 215.621326 -277.920538) (xy 215.661475 -277.881829)
			(xy 215.706833 -277.849378) (xy 215.756433 -277.823877) (xy 215.809217 -277.80587) (xy 215.86406 -277.79574)
			(xy 215.919794 -277.793703) (xy 215.975231 -277.799803) (xy 216.029188 -277.813909) (xy 216.080517 -277.835721)
			(xy 216.128123 -277.864775) (xy 216.170991 -277.90045) (xy 216.208208 -277.941987) (xy 216.238981 -277.9885)
			(xy 216.262653 -278.038997) (xy 216.278721 -278.092404) (xy 216.286841 -278.14758) (xy 216.28735 -278.175466)
			(xy 216.286841 -278.203352) (xy 216.282422 -278.233378) (xy 225.945952 -278.233378) (xy 225.950023 -278.177756)
			(xy 225.962149 -278.123319) (xy 225.982072 -278.071228) (xy 226.009368 -278.022593) (xy 226.043454 -277.97845)
			(xy 226.083603 -277.939741) (xy 226.128961 -277.90729) (xy 226.178561 -277.881789) (xy 226.231345 -277.863782)
			(xy 226.286188 -277.853652) (xy 226.341922 -277.851615) (xy 226.397359 -277.857715) (xy 226.451316 -277.871821)
			(xy 226.502645 -277.893633) (xy 226.550251 -277.922687) (xy 226.593119 -277.958362) (xy 226.630336 -277.999899)
			(xy 226.661109 -278.046412) (xy 226.684781 -278.096909) (xy 226.700849 -278.150316) (xy 226.708969 -278.205492)
			(xy 226.709478 -278.233378) (xy 226.708969 -278.261264) (xy 226.700849 -278.31644) (xy 226.684781 -278.369847)
			(xy 226.680051 -278.379936) (xy 227.470206 -278.379936) (xy 227.474277 -278.324314) (xy 227.486403 -278.269877)
			(xy 227.506326 -278.217786) (xy 227.533622 -278.169151) (xy 227.567708 -278.125008) (xy 227.607857 -278.086299)
			(xy 227.653215 -278.053848) (xy 227.702815 -278.028347) (xy 227.755599 -278.01034) (xy 227.810442 -278.00021)
			(xy 227.866176 -277.998173) (xy 227.921613 -278.004273) (xy 227.97557 -278.018379) (xy 228.026899 -278.040191)
			(xy 228.074505 -278.069245) (xy 228.117373 -278.10492) (xy 228.15459 -278.146457) (xy 228.185363 -278.19297)
			(xy 228.209035 -278.243467) (xy 228.225103 -278.296874) (xy 228.233223 -278.35205) (xy 228.233528 -278.36876)
			(xy 228.648258 -278.36876) (xy 228.652329 -278.313138) (xy 228.664455 -278.258701) (xy 228.684378 -278.20661)
			(xy 228.711674 -278.157975) (xy 228.74576 -278.113832) (xy 228.785909 -278.075123) (xy 228.831267 -278.042672)
			(xy 228.880867 -278.017171) (xy 228.933651 -277.999164) (xy 228.988494 -277.989034) (xy 229.044228 -277.986997)
			(xy 229.099665 -277.993097) (xy 229.153622 -278.007203) (xy 229.204951 -278.029015) (xy 229.252557 -278.058069)
			(xy 229.295425 -278.093744) (xy 229.332642 -278.135281) (xy 229.363415 -278.181794) (xy 229.387087 -278.232291)
			(xy 229.403155 -278.285698) (xy 229.411275 -278.340874) (xy 229.411784 -278.36876) (xy 229.411275 -278.396646)
			(xy 229.403155 -278.451822) (xy 229.387087 -278.505229) (xy 229.363415 -278.555726) (xy 229.332642 -278.602239)
			(xy 229.295425 -278.643776) (xy 229.252557 -278.679451) (xy 229.204951 -278.708505) (xy 229.153622 -278.730317)
			(xy 229.099665 -278.744423) (xy 229.044228 -278.750523) (xy 228.988494 -278.748486) (xy 228.933651 -278.738356)
			(xy 228.880867 -278.720349) (xy 228.831267 -278.694848) (xy 228.785909 -278.662397) (xy 228.74576 -278.623688)
			(xy 228.711674 -278.579545) (xy 228.684378 -278.53091) (xy 228.664455 -278.478819) (xy 228.652329 -278.424382)
			(xy 228.648258 -278.36876) (xy 228.233528 -278.36876) (xy 228.233732 -278.379936) (xy 228.233223 -278.407822)
			(xy 228.225103 -278.462998) (xy 228.209035 -278.516405) (xy 228.185363 -278.566902) (xy 228.15459 -278.613415)
			(xy 228.117373 -278.654952) (xy 228.074505 -278.690627) (xy 228.026899 -278.719681) (xy 227.97557 -278.741493)
			(xy 227.921613 -278.755599) (xy 227.866176 -278.761699) (xy 227.810442 -278.759662) (xy 227.755599 -278.749532)
			(xy 227.702815 -278.731525) (xy 227.653215 -278.706024) (xy 227.607857 -278.673573) (xy 227.567708 -278.634864)
			(xy 227.533622 -278.590721) (xy 227.506326 -278.542086) (xy 227.486403 -278.489995) (xy 227.474277 -278.435558)
			(xy 227.470206 -278.379936) (xy 226.680051 -278.379936) (xy 226.661109 -278.420344) (xy 226.630336 -278.466857)
			(xy 226.593119 -278.508394) (xy 226.550251 -278.544069) (xy 226.502645 -278.573123) (xy 226.451316 -278.594935)
			(xy 226.397359 -278.609041) (xy 226.341922 -278.615141) (xy 226.286188 -278.613104) (xy 226.231345 -278.602974)
			(xy 226.178561 -278.584967) (xy 226.128961 -278.559466) (xy 226.083603 -278.527015) (xy 226.043454 -278.488306)
			(xy 226.009368 -278.444163) (xy 225.982072 -278.395528) (xy 225.962149 -278.343437) (xy 225.950023 -278.289)
			(xy 225.945952 -278.233378) (xy 216.282422 -278.233378) (xy 216.278721 -278.258528) (xy 216.262653 -278.311935)
			(xy 216.238981 -278.362432) (xy 216.208208 -278.408945) (xy 216.170991 -278.450482) (xy 216.128123 -278.486157)
			(xy 216.080517 -278.515211) (xy 216.029188 -278.537023) (xy 215.975231 -278.551129) (xy 215.919794 -278.557229)
			(xy 215.86406 -278.555192) (xy 215.809217 -278.545062) (xy 215.756433 -278.527055) (xy 215.706833 -278.501554)
			(xy 215.661475 -278.469103) (xy 215.621326 -278.430394) (xy 215.58724 -278.386251) (xy 215.559944 -278.337616)
			(xy 215.540021 -278.285525) (xy 215.527895 -278.231088) (xy 215.523824 -278.175466) (xy 196.681996 -278.175466)
			(xy 196.675556 -278.176486) (xy 196.62414 -278.176486) (xy 196.573358 -278.168443) (xy 196.524459 -278.152555)
			(xy 196.478647 -278.129212) (xy 196.437051 -278.098991) (xy 196.400695 -278.062635) (xy 196.370474 -278.021039)
			(xy 196.347131 -277.975227) (xy 196.331243 -277.926328) (xy 196.3232 -277.875546) (xy 196.004522 -277.875546)
			(xy 195.996806 -277.923022) (xy 195.981222 -277.969703) (xy 195.958351 -278.01328) (xy 195.928786 -278.052624)
			(xy 195.893293 -278.086716) (xy 195.85279 -278.114672) (xy 195.808328 -278.13577) (xy 195.761057 -278.149462)
			(xy 195.712202 -278.155394) (xy 195.663027 -278.153413) (xy 195.614808 -278.143569) (xy 195.568792 -278.126117)
			(xy 195.526171 -278.10151) (xy 195.48805 -278.070385) (xy 195.455415 -278.033548) (xy 195.429112 -277.991952)
			(xy 195.409821 -277.946676) (xy 195.398044 -277.898892) (xy 195.394084 -277.849838) (xy 195.076826 -277.849838)
			(xy 195.076322 -277.875546) (xy 195.068279 -277.926328) (xy 195.052391 -277.975227) (xy 195.029048 -278.021039)
			(xy 194.998827 -278.062635) (xy 194.962471 -278.098991) (xy 194.920875 -278.129212) (xy 194.875063 -278.152555)
			(xy 194.826164 -278.168443) (xy 194.775382 -278.176486) (xy 194.723966 -278.176486) (xy 194.673184 -278.168443)
			(xy 194.624285 -278.152555) (xy 194.578473 -278.129212) (xy 194.536877 -278.098991) (xy 194.500521 -278.062635)
			(xy 194.4703 -278.021039) (xy 194.446957 -277.975227) (xy 194.431069 -277.926328) (xy 194.423026 -277.875546)
			(xy 194.104602 -277.875546) (xy 194.096886 -277.923022) (xy 194.081302 -277.969703) (xy 194.058431 -278.01328)
			(xy 194.028866 -278.052624) (xy 193.993373 -278.086716) (xy 193.95287 -278.114672) (xy 193.908408 -278.13577)
			(xy 193.861137 -278.149462) (xy 193.812282 -278.155394) (xy 193.763107 -278.153413) (xy 193.714888 -278.143569)
			(xy 193.668872 -278.126117) (xy 193.626251 -278.10151) (xy 193.58813 -278.070385) (xy 193.555495 -278.033548)
			(xy 193.529192 -277.991952) (xy 193.509901 -277.946676) (xy 193.498124 -277.898892) (xy 193.494164 -277.849838)
			(xy 193.176906 -277.849838) (xy 193.176402 -277.875546) (xy 193.168359 -277.926328) (xy 193.152471 -277.975227)
			(xy 193.129128 -278.021039) (xy 193.098907 -278.062635) (xy 193.062551 -278.098991) (xy 193.020955 -278.129212)
			(xy 192.975143 -278.152555) (xy 192.926244 -278.168443) (xy 192.875462 -278.176486) (xy 192.824046 -278.176486)
			(xy 192.773264 -278.168443) (xy 192.724365 -278.152555) (xy 192.678553 -278.129212) (xy 192.636957 -278.098991)
			(xy 192.600601 -278.062635) (xy 192.57038 -278.021039) (xy 192.547037 -277.975227) (xy 192.531149 -277.926328)
			(xy 192.523106 -277.875546) (xy 192.204682 -277.875546) (xy 192.196966 -277.923022) (xy 192.181382 -277.969703)
			(xy 192.158511 -278.01328) (xy 192.128946 -278.052624) (xy 192.093453 -278.086716) (xy 192.05295 -278.114672)
			(xy 192.008488 -278.13577) (xy 191.961217 -278.149462) (xy 191.912362 -278.155394) (xy 191.863187 -278.153413)
			(xy 191.814968 -278.143569) (xy 191.768952 -278.126117) (xy 191.726331 -278.10151) (xy 191.68821 -278.070385)
			(xy 191.655575 -278.033548) (xy 191.629272 -277.991952) (xy 191.609981 -277.946676) (xy 191.598204 -277.898892)
			(xy 191.594244 -277.849838) (xy 191.276986 -277.849838) (xy 191.276482 -277.875546) (xy 191.268439 -277.926328)
			(xy 191.252551 -277.975227) (xy 191.229208 -278.021039) (xy 191.198987 -278.062635) (xy 191.162631 -278.098991)
			(xy 191.121035 -278.129212) (xy 191.075223 -278.152555) (xy 191.026324 -278.168443) (xy 190.975542 -278.176486)
			(xy 190.924126 -278.176486) (xy 190.873344 -278.168443) (xy 190.824445 -278.152555) (xy 190.778633 -278.129212)
			(xy 190.737037 -278.098991) (xy 190.700681 -278.062635) (xy 190.67046 -278.021039) (xy 190.647117 -277.975227)
			(xy 190.631229 -277.926328) (xy 190.623186 -277.875546) (xy 190.304508 -277.875546) (xy 190.296792 -277.923022)
			(xy 190.281208 -277.969703) (xy 190.258337 -278.01328) (xy 190.228772 -278.052624) (xy 190.193279 -278.086716)
			(xy 190.152776 -278.114672) (xy 190.108314 -278.13577) (xy 190.061043 -278.149462) (xy 190.012188 -278.155394)
			(xy 189.963013 -278.153413) (xy 189.914794 -278.143569) (xy 189.868778 -278.126117) (xy 189.826157 -278.10151)
			(xy 189.788036 -278.070385) (xy 189.755401 -278.033548) (xy 189.729098 -277.991952) (xy 189.709807 -277.946676)
			(xy 189.69803 -277.898892) (xy 189.69407 -277.849838) (xy 189.376812 -277.849838) (xy 189.376308 -277.875546)
			(xy 189.368265 -277.926328) (xy 189.352377 -277.975227) (xy 189.329034 -278.021039) (xy 189.298813 -278.062635)
			(xy 189.262457 -278.098991) (xy 189.220861 -278.129212) (xy 189.175049 -278.152555) (xy 189.12615 -278.168443)
			(xy 189.075368 -278.176486) (xy 189.023952 -278.176486) (xy 188.97317 -278.168443) (xy 188.924271 -278.152555)
			(xy 188.878459 -278.129212) (xy 188.836863 -278.098991) (xy 188.800507 -278.062635) (xy 188.770286 -278.021039)
			(xy 188.746943 -277.975227) (xy 188.731055 -277.926328) (xy 188.723012 -277.875546) (xy 188.404588 -277.875546)
			(xy 188.396872 -277.923022) (xy 188.381288 -277.969703) (xy 188.358417 -278.01328) (xy 188.328852 -278.052624)
			(xy 188.293359 -278.086716) (xy 188.252856 -278.114672) (xy 188.208394 -278.13577) (xy 188.161123 -278.149462)
			(xy 188.112268 -278.155394) (xy 188.063093 -278.153413) (xy 188.014874 -278.143569) (xy 187.968858 -278.126117)
			(xy 187.926237 -278.10151) (xy 187.888116 -278.070385) (xy 187.855481 -278.033548) (xy 187.829178 -277.991952)
			(xy 187.809887 -277.946676) (xy 187.79811 -277.898892) (xy 187.79415 -277.849838) (xy 187.476892 -277.849838)
			(xy 187.476388 -277.875546) (xy 187.468345 -277.926328) (xy 187.452457 -277.975227) (xy 187.429114 -278.021039)
			(xy 187.398893 -278.062635) (xy 187.362537 -278.098991) (xy 187.320941 -278.129212) (xy 187.275129 -278.152555)
			(xy 187.22623 -278.168443) (xy 187.175448 -278.176486) (xy 187.124032 -278.176486) (xy 187.07325 -278.168443)
			(xy 187.024351 -278.152555) (xy 186.978539 -278.129212) (xy 186.936943 -278.098991) (xy 186.900587 -278.062635)
			(xy 186.870366 -278.021039) (xy 186.847023 -277.975227) (xy 186.831135 -277.926328) (xy 186.823092 -277.875546)
			(xy 186.504668 -277.875546) (xy 186.496952 -277.923022) (xy 186.481368 -277.969703) (xy 186.458497 -278.01328)
			(xy 186.428932 -278.052624) (xy 186.393439 -278.086716) (xy 186.352936 -278.114672) (xy 186.308474 -278.13577)
			(xy 186.261203 -278.149462) (xy 186.212348 -278.155394) (xy 186.163173 -278.153413) (xy 186.114954 -278.143569)
			(xy 186.068938 -278.126117) (xy 186.026317 -278.10151) (xy 185.988196 -278.070385) (xy 185.955561 -278.033548)
			(xy 185.929258 -277.991952) (xy 185.909967 -277.946676) (xy 185.89819 -277.898892) (xy 185.89423 -277.849838)
			(xy 185.576972 -277.849838) (xy 185.576468 -277.875546) (xy 185.568425 -277.926328) (xy 185.552537 -277.975227)
			(xy 185.529194 -278.021039) (xy 185.498973 -278.062635) (xy 185.462617 -278.098991) (xy 185.421021 -278.129212)
			(xy 185.375209 -278.152555) (xy 185.32631 -278.168443) (xy 185.275528 -278.176486) (xy 185.224112 -278.176486)
			(xy 185.17333 -278.168443) (xy 185.124431 -278.152555) (xy 185.078619 -278.129212) (xy 185.037023 -278.098991)
			(xy 185.000667 -278.062635) (xy 184.970446 -278.021039) (xy 184.947103 -277.975227) (xy 184.931215 -277.926328)
			(xy 184.923172 -277.875546) (xy 184.604494 -277.875546) (xy 184.596778 -277.923022) (xy 184.581194 -277.969703)
			(xy 184.558323 -278.01328) (xy 184.528758 -278.052624) (xy 184.493265 -278.086716) (xy 184.452762 -278.114672)
			(xy 184.4083 -278.13577) (xy 184.361029 -278.149462) (xy 184.312174 -278.155394) (xy 184.262999 -278.153413)
			(xy 184.21478 -278.143569) (xy 184.168764 -278.126117) (xy 184.126143 -278.10151) (xy 184.088022 -278.070385)
			(xy 184.055387 -278.033548) (xy 184.029084 -277.991952) (xy 184.009793 -277.946676) (xy 183.998016 -277.898892)
			(xy 183.994056 -277.849838) (xy 183.676798 -277.849838) (xy 183.676294 -277.875546) (xy 183.668251 -277.926328)
			(xy 183.652363 -277.975227) (xy 183.62902 -278.021039) (xy 183.598799 -278.062635) (xy 183.562443 -278.098991)
			(xy 183.520847 -278.129212) (xy 183.475035 -278.152555) (xy 183.426136 -278.168443) (xy 183.375354 -278.176486)
			(xy 183.323938 -278.176486) (xy 183.273156 -278.168443) (xy 183.224257 -278.152555) (xy 183.178445 -278.129212)
			(xy 183.136849 -278.098991) (xy 183.100493 -278.062635) (xy 183.070272 -278.021039) (xy 183.046929 -277.975227)
			(xy 183.031041 -277.926328) (xy 183.022998 -277.875546) (xy 182.704574 -277.875546) (xy 182.696858 -277.923022)
			(xy 182.681274 -277.969703) (xy 182.658403 -278.01328) (xy 182.628838 -278.052624) (xy 182.593345 -278.086716)
			(xy 182.552842 -278.114672) (xy 182.50838 -278.13577) (xy 182.461109 -278.149462) (xy 182.412254 -278.155394)
			(xy 182.363079 -278.153413) (xy 182.31486 -278.143569) (xy 182.268844 -278.126117) (xy 182.226223 -278.10151)
			(xy 182.188102 -278.070385) (xy 182.155467 -278.033548) (xy 182.129164 -277.991952) (xy 182.109873 -277.946676)
			(xy 182.098096 -277.898892) (xy 182.094136 -277.849838) (xy 181.776878 -277.849838) (xy 181.776374 -277.875546)
			(xy 181.768331 -277.926328) (xy 181.752443 -277.975227) (xy 181.7291 -278.021039) (xy 181.698879 -278.062635)
			(xy 181.662523 -278.098991) (xy 181.620927 -278.129212) (xy 181.575115 -278.152555) (xy 181.526216 -278.168443)
			(xy 181.475434 -278.176486) (xy 181.424018 -278.176486) (xy 181.373236 -278.168443) (xy 181.324337 -278.152555)
			(xy 181.278525 -278.129212) (xy 181.236929 -278.098991) (xy 181.200573 -278.062635) (xy 181.170352 -278.021039)
			(xy 181.147009 -277.975227) (xy 181.131121 -277.926328) (xy 181.123078 -277.875546) (xy 180.804654 -277.875546)
			(xy 180.796938 -277.923022) (xy 180.781354 -277.969703) (xy 180.758483 -278.01328) (xy 180.728918 -278.052624)
			(xy 180.693425 -278.086716) (xy 180.652922 -278.114672) (xy 180.60846 -278.13577) (xy 180.561189 -278.149462)
			(xy 180.512334 -278.155394) (xy 180.463159 -278.153413) (xy 180.41494 -278.143569) (xy 180.368924 -278.126117)
			(xy 180.326303 -278.10151) (xy 180.288182 -278.070385) (xy 180.255547 -278.033548) (xy 180.229244 -277.991952)
			(xy 180.209953 -277.946676) (xy 180.198176 -277.898892) (xy 180.194216 -277.849838) (xy 179.876958 -277.849838)
			(xy 179.876454 -277.875546) (xy 179.868411 -277.926328) (xy 179.852523 -277.975227) (xy 179.82918 -278.021039)
			(xy 179.798959 -278.062635) (xy 179.762603 -278.098991) (xy 179.721007 -278.129212) (xy 179.675195 -278.152555)
			(xy 179.626296 -278.168443) (xy 179.575514 -278.176486) (xy 179.524098 -278.176486) (xy 179.473316 -278.168443)
			(xy 179.424417 -278.152555) (xy 179.378605 -278.129212) (xy 179.337009 -278.098991) (xy 179.300653 -278.062635)
			(xy 179.270432 -278.021039) (xy 179.247089 -277.975227) (xy 179.231201 -277.926328) (xy 179.223158 -277.875546)
			(xy 178.90448 -277.875546) (xy 178.896764 -277.923022) (xy 178.88118 -277.969703) (xy 178.858309 -278.01328)
			(xy 178.828744 -278.052624) (xy 178.793251 -278.086716) (xy 178.752748 -278.114672) (xy 178.708286 -278.13577)
			(xy 178.661015 -278.149462) (xy 178.61216 -278.155394) (xy 178.562985 -278.153413) (xy 178.514766 -278.143569)
			(xy 178.46875 -278.126117) (xy 178.426129 -278.10151) (xy 178.388008 -278.070385) (xy 178.355373 -278.033548)
			(xy 178.32907 -277.991952) (xy 178.309779 -277.946676) (xy 178.298002 -277.898892) (xy 178.294042 -277.849838)
			(xy 177.976784 -277.849838) (xy 177.97628 -277.875546) (xy 177.968237 -277.926328) (xy 177.952349 -277.975227)
			(xy 177.929006 -278.021039) (xy 177.898785 -278.062635) (xy 177.862429 -278.098991) (xy 177.820833 -278.129212)
			(xy 177.775021 -278.152555) (xy 177.726122 -278.168443) (xy 177.67534 -278.176486) (xy 177.623924 -278.176486)
			(xy 177.573142 -278.168443) (xy 177.524243 -278.152555) (xy 177.478431 -278.129212) (xy 177.436835 -278.098991)
			(xy 177.400479 -278.062635) (xy 177.370258 -278.021039) (xy 177.346915 -277.975227) (xy 177.331027 -277.926328)
			(xy 177.322984 -277.875546) (xy 177.00456 -277.875546) (xy 176.996844 -277.923022) (xy 176.98126 -277.969703)
			(xy 176.958389 -278.01328) (xy 176.928824 -278.052624) (xy 176.893331 -278.086716) (xy 176.852828 -278.114672)
			(xy 176.808366 -278.13577) (xy 176.761095 -278.149462) (xy 176.71224 -278.155394) (xy 176.663065 -278.153413)
			(xy 176.614846 -278.143569) (xy 176.56883 -278.126117) (xy 176.526209 -278.10151) (xy 176.488088 -278.070385)
			(xy 176.455453 -278.033548) (xy 176.42915 -277.991952) (xy 176.409859 -277.946676) (xy 176.398082 -277.898892)
			(xy 176.394122 -277.849838) (xy 176.076056 -277.849838) (xy 176.076056 -277.875484) (xy 176.068021 -277.92622)
			(xy 176.052147 -277.975075) (xy 176.028827 -278.020844) (xy 175.998634 -278.062403) (xy 175.962312 -278.098726)
			(xy 175.920755 -278.128921) (xy 175.874986 -278.152243) (xy 175.826132 -278.168118) (xy 175.775396 -278.176155)
			(xy 175.749712 -278.176736) (xy 175.749204 -278.176736) (xy 175.723996 -278.176225) (xy 175.67419 -278.168402)
			(xy 175.626172 -278.153032) (xy 175.603408 -278.142192) (xy 175.6029 -278.142192) (xy 175.602646 -278.141938)
			(xy 175.596949 -278.139403) (xy 175.584751 -278.13683) (xy 175.578516 -278.136858) (xy 175.565054 -278.137366)
			(xy 175.480218 -278.18969) (xy 175.47971 -278.189944) (xy 175.479202 -278.190452) (xy 175.470413 -278.196746)
			(xy 175.458715 -278.214902) (xy 175.456596 -278.225504) (xy 175.456088 -278.23287) (xy 175.456088 -278.416766)
			(xy 175.456596 -278.424132) (xy 175.458701 -278.434737) (xy 175.470411 -278.45289) (xy 175.479202 -278.459184)
			(xy 175.47971 -278.459692) (xy 175.480218 -278.459946) (xy 175.553624 -278.505158) (xy 175.559318 -278.508494)
			(xy 175.57193 -278.512364) (xy 175.578516 -278.512778) (xy 175.591216 -278.513286) (xy 175.6029 -278.507444)
			(xy 175.603408 -278.507444) (xy 175.62616 -278.496575) (xy 175.674181 -278.481198) (xy 175.723994 -278.473387)
			(xy 175.749204 -278.4729) (xy 175.749712 -278.4729) (xy 175.775399 -278.473405) (xy 175.826141 -278.481443)
			(xy 175.875001 -278.49732) (xy 175.920776 -278.520645) (xy 175.962338 -278.550843) (xy 175.998665 -278.587171)
			(xy 176.028861 -278.628735) (xy 176.052184 -278.67451) (xy 176.06806 -278.72337) (xy 176.076096 -278.774113)
			(xy 176.076096 -278.799798) (xy 176.394122 -278.799798) (xy 176.398082 -278.750744) (xy 176.409859 -278.70296)
			(xy 176.42915 -278.657684) (xy 176.455453 -278.616088) (xy 176.488088 -278.579251) (xy 176.526209 -278.548126)
			(xy 176.56883 -278.523519) (xy 176.614846 -278.506067) (xy 176.663065 -278.496223) (xy 176.71224 -278.494242)
			(xy 176.761095 -278.500174) (xy 176.808366 -278.513866) (xy 176.852828 -278.534964) (xy 176.893331 -278.56292)
			(xy 176.928824 -278.597012) (xy 176.958389 -278.636356) (xy 176.98126 -278.679933) (xy 176.996844 -278.726614)
			(xy 177.004739 -278.775191) (xy 177.005234 -278.799798) (xy 177.004739 -278.824405) (xy 177.00456 -278.825506)
			(xy 177.322984 -278.825506) (xy 177.322984 -278.77409) (xy 177.331027 -278.723308) (xy 177.346915 -278.674409)
			(xy 177.370258 -278.628597) (xy 177.400479 -278.587001) (xy 177.436835 -278.550645) (xy 177.478431 -278.520424)
			(xy 177.524243 -278.497081) (xy 177.573142 -278.481193) (xy 177.623924 -278.47315) (xy 177.67534 -278.47315)
			(xy 177.726122 -278.481193) (xy 177.775021 -278.497081) (xy 177.820833 -278.520424) (xy 177.862429 -278.550645)
			(xy 177.898785 -278.587001) (xy 177.929006 -278.628597) (xy 177.952349 -278.674409) (xy 177.968237 -278.723308)
			(xy 177.97628 -278.77409) (xy 177.976784 -278.799798) (xy 178.294042 -278.799798) (xy 178.298002 -278.750744)
			(xy 178.309779 -278.70296) (xy 178.32907 -278.657684) (xy 178.355373 -278.616088) (xy 178.388008 -278.579251)
			(xy 178.426129 -278.548126) (xy 178.46875 -278.523519) (xy 178.514766 -278.506067) (xy 178.562985 -278.496223)
			(xy 178.61216 -278.494242) (xy 178.661015 -278.500174) (xy 178.708286 -278.513866) (xy 178.752748 -278.534964)
			(xy 178.793251 -278.56292) (xy 178.828744 -278.597012) (xy 178.858309 -278.636356) (xy 178.88118 -278.679933)
			(xy 178.896764 -278.726614) (xy 178.904659 -278.775191) (xy 178.905154 -278.799798) (xy 178.904659 -278.824405)
			(xy 178.90448 -278.825506) (xy 179.223158 -278.825506) (xy 179.223158 -278.77409) (xy 179.231201 -278.723308)
			(xy 179.247089 -278.674409) (xy 179.270432 -278.628597) (xy 179.300653 -278.587001) (xy 179.337009 -278.550645)
			(xy 179.378605 -278.520424) (xy 179.424417 -278.497081) (xy 179.473316 -278.481193) (xy 179.524098 -278.47315)
			(xy 179.575514 -278.47315) (xy 179.626296 -278.481193) (xy 179.675195 -278.497081) (xy 179.721007 -278.520424)
			(xy 179.762603 -278.550645) (xy 179.798959 -278.587001) (xy 179.82918 -278.628597) (xy 179.852523 -278.674409)
			(xy 179.868411 -278.723308) (xy 179.876454 -278.77409) (xy 179.876958 -278.799798) (xy 180.194216 -278.799798)
			(xy 180.198176 -278.750744) (xy 180.209953 -278.70296) (xy 180.229244 -278.657684) (xy 180.255547 -278.616088)
			(xy 180.288182 -278.579251) (xy 180.326303 -278.548126) (xy 180.368924 -278.523519) (xy 180.41494 -278.506067)
			(xy 180.463159 -278.496223) (xy 180.512334 -278.494242) (xy 180.561189 -278.500174) (xy 180.60846 -278.513866)
			(xy 180.652922 -278.534964) (xy 180.693425 -278.56292) (xy 180.728918 -278.597012) (xy 180.758483 -278.636356)
			(xy 180.781354 -278.679933) (xy 180.796938 -278.726614) (xy 180.804833 -278.775191) (xy 180.805328 -278.799798)
			(xy 180.804833 -278.824405) (xy 180.804654 -278.825506) (xy 181.123078 -278.825506) (xy 181.123078 -278.77409)
			(xy 181.131121 -278.723308) (xy 181.147009 -278.674409) (xy 181.170352 -278.628597) (xy 181.200573 -278.587001)
			(xy 181.236929 -278.550645) (xy 181.278525 -278.520424) (xy 181.324337 -278.497081) (xy 181.373236 -278.481193)
			(xy 181.424018 -278.47315) (xy 181.475434 -278.47315) (xy 181.526216 -278.481193) (xy 181.575115 -278.497081)
			(xy 181.620927 -278.520424) (xy 181.662523 -278.550645) (xy 181.698879 -278.587001) (xy 181.7291 -278.628597)
			(xy 181.752443 -278.674409) (xy 181.768331 -278.723308) (xy 181.776374 -278.77409) (xy 181.776878 -278.799798)
			(xy 182.094136 -278.799798) (xy 182.098096 -278.750744) (xy 182.109873 -278.70296) (xy 182.129164 -278.657684)
			(xy 182.155467 -278.616088) (xy 182.188102 -278.579251) (xy 182.226223 -278.548126) (xy 182.268844 -278.523519)
			(xy 182.31486 -278.506067) (xy 182.363079 -278.496223) (xy 182.412254 -278.494242) (xy 182.461109 -278.500174)
			(xy 182.50838 -278.513866) (xy 182.552842 -278.534964) (xy 182.593345 -278.56292) (xy 182.628838 -278.597012)
			(xy 182.658403 -278.636356) (xy 182.681274 -278.679933) (xy 182.696858 -278.726614) (xy 182.704753 -278.775191)
			(xy 182.705248 -278.799798) (xy 182.704753 -278.824405) (xy 182.704574 -278.825506) (xy 183.022998 -278.825506)
			(xy 183.022998 -278.77409) (xy 183.031041 -278.723308) (xy 183.046929 -278.674409) (xy 183.070272 -278.628597)
			(xy 183.100493 -278.587001) (xy 183.136849 -278.550645) (xy 183.178445 -278.520424) (xy 183.224257 -278.497081)
			(xy 183.273156 -278.481193) (xy 183.323938 -278.47315) (xy 183.375354 -278.47315) (xy 183.426136 -278.481193)
			(xy 183.475035 -278.497081) (xy 183.520847 -278.520424) (xy 183.562443 -278.550645) (xy 183.598799 -278.587001)
			(xy 183.62902 -278.628597) (xy 183.652363 -278.674409) (xy 183.668251 -278.723308) (xy 183.676294 -278.77409)
			(xy 183.676798 -278.799798) (xy 183.994056 -278.799798) (xy 183.998016 -278.750744) (xy 184.009793 -278.70296)
			(xy 184.029084 -278.657684) (xy 184.055387 -278.616088) (xy 184.088022 -278.579251) (xy 184.126143 -278.548126)
			(xy 184.168764 -278.523519) (xy 184.21478 -278.506067) (xy 184.262999 -278.496223) (xy 184.312174 -278.494242)
			(xy 184.361029 -278.500174) (xy 184.4083 -278.513866) (xy 184.452762 -278.534964) (xy 184.493265 -278.56292)
			(xy 184.528758 -278.597012) (xy 184.558323 -278.636356) (xy 184.581194 -278.679933) (xy 184.596778 -278.726614)
			(xy 184.604673 -278.775191) (xy 184.605168 -278.799798) (xy 184.604673 -278.824405) (xy 184.604494 -278.825506)
			(xy 184.923172 -278.825506) (xy 184.923172 -278.77409) (xy 184.931215 -278.723308) (xy 184.947103 -278.674409)
			(xy 184.970446 -278.628597) (xy 185.000667 -278.587001) (xy 185.037023 -278.550645) (xy 185.078619 -278.520424)
			(xy 185.124431 -278.497081) (xy 185.17333 -278.481193) (xy 185.224112 -278.47315) (xy 185.275528 -278.47315)
			(xy 185.32631 -278.481193) (xy 185.375209 -278.497081) (xy 185.421021 -278.520424) (xy 185.462617 -278.550645)
			(xy 185.498973 -278.587001) (xy 185.529194 -278.628597) (xy 185.552537 -278.674409) (xy 185.568425 -278.723308)
			(xy 185.576468 -278.77409) (xy 185.576972 -278.799798) (xy 185.89423 -278.799798) (xy 185.89819 -278.750744)
			(xy 185.909967 -278.70296) (xy 185.929258 -278.657684) (xy 185.955561 -278.616088) (xy 185.988196 -278.579251)
			(xy 186.026317 -278.548126) (xy 186.068938 -278.523519) (xy 186.114954 -278.506067) (xy 186.163173 -278.496223)
			(xy 186.212348 -278.494242) (xy 186.261203 -278.500174) (xy 186.308474 -278.513866) (xy 186.352936 -278.534964)
			(xy 186.393439 -278.56292) (xy 186.428932 -278.597012) (xy 186.458497 -278.636356) (xy 186.481368 -278.679933)
			(xy 186.496952 -278.726614) (xy 186.504847 -278.775191) (xy 186.505342 -278.799798) (xy 186.504847 -278.824405)
			(xy 186.504668 -278.825506) (xy 186.823092 -278.825506) (xy 186.823092 -278.77409) (xy 186.831135 -278.723308)
			(xy 186.847023 -278.674409) (xy 186.870366 -278.628597) (xy 186.900587 -278.587001) (xy 186.936943 -278.550645)
			(xy 186.978539 -278.520424) (xy 187.024351 -278.497081) (xy 187.07325 -278.481193) (xy 187.124032 -278.47315)
			(xy 187.175448 -278.47315) (xy 187.22623 -278.481193) (xy 187.275129 -278.497081) (xy 187.320941 -278.520424)
			(xy 187.362537 -278.550645) (xy 187.398893 -278.587001) (xy 187.429114 -278.628597) (xy 187.452457 -278.674409)
			(xy 187.468345 -278.723308) (xy 187.476388 -278.77409) (xy 187.476892 -278.799798) (xy 187.79415 -278.799798)
			(xy 187.79811 -278.750744) (xy 187.809887 -278.70296) (xy 187.829178 -278.657684) (xy 187.855481 -278.616088)
			(xy 187.888116 -278.579251) (xy 187.926237 -278.548126) (xy 187.968858 -278.523519) (xy 188.014874 -278.506067)
			(xy 188.063093 -278.496223) (xy 188.112268 -278.494242) (xy 188.161123 -278.500174) (xy 188.208394 -278.513866)
			(xy 188.252856 -278.534964) (xy 188.293359 -278.56292) (xy 188.328852 -278.597012) (xy 188.358417 -278.636356)
			(xy 188.381288 -278.679933) (xy 188.396872 -278.726614) (xy 188.404767 -278.775191) (xy 188.405262 -278.799798)
			(xy 188.404767 -278.824405) (xy 188.404588 -278.825506) (xy 188.723012 -278.825506) (xy 188.723012 -278.77409)
			(xy 188.731055 -278.723308) (xy 188.746943 -278.674409) (xy 188.770286 -278.628597) (xy 188.800507 -278.587001)
			(xy 188.836863 -278.550645) (xy 188.878459 -278.520424) (xy 188.924271 -278.497081) (xy 188.97317 -278.481193)
			(xy 189.023952 -278.47315) (xy 189.075368 -278.47315) (xy 189.12615 -278.481193) (xy 189.175049 -278.497081)
			(xy 189.220861 -278.520424) (xy 189.262457 -278.550645) (xy 189.298813 -278.587001) (xy 189.329034 -278.628597)
			(xy 189.352377 -278.674409) (xy 189.368265 -278.723308) (xy 189.376308 -278.77409) (xy 189.376812 -278.799798)
			(xy 189.69407 -278.799798) (xy 189.69803 -278.750744) (xy 189.709807 -278.70296) (xy 189.729098 -278.657684)
			(xy 189.755401 -278.616088) (xy 189.788036 -278.579251) (xy 189.826157 -278.548126) (xy 189.868778 -278.523519)
			(xy 189.914794 -278.506067) (xy 189.963013 -278.496223) (xy 190.012188 -278.494242) (xy 190.061043 -278.500174)
			(xy 190.108314 -278.513866) (xy 190.152776 -278.534964) (xy 190.193279 -278.56292) (xy 190.228772 -278.597012)
			(xy 190.258337 -278.636356) (xy 190.281208 -278.679933) (xy 190.296792 -278.726614) (xy 190.304687 -278.775191)
			(xy 190.305182 -278.799798) (xy 190.304687 -278.824405) (xy 190.304508 -278.825506) (xy 190.623186 -278.825506)
			(xy 190.623186 -278.77409) (xy 190.631229 -278.723308) (xy 190.647117 -278.674409) (xy 190.67046 -278.628597)
			(xy 190.700681 -278.587001) (xy 190.737037 -278.550645) (xy 190.778633 -278.520424) (xy 190.824445 -278.497081)
			(xy 190.873344 -278.481193) (xy 190.924126 -278.47315) (xy 190.975542 -278.47315) (xy 191.026324 -278.481193)
			(xy 191.075223 -278.497081) (xy 191.121035 -278.520424) (xy 191.162631 -278.550645) (xy 191.198987 -278.587001)
			(xy 191.229208 -278.628597) (xy 191.252551 -278.674409) (xy 191.268439 -278.723308) (xy 191.276482 -278.77409)
			(xy 191.276986 -278.799798) (xy 191.594244 -278.799798) (xy 191.598204 -278.750744) (xy 191.609981 -278.70296)
			(xy 191.629272 -278.657684) (xy 191.655575 -278.616088) (xy 191.68821 -278.579251) (xy 191.726331 -278.548126)
			(xy 191.768952 -278.523519) (xy 191.814968 -278.506067) (xy 191.863187 -278.496223) (xy 191.912362 -278.494242)
			(xy 191.961217 -278.500174) (xy 192.008488 -278.513866) (xy 192.05295 -278.534964) (xy 192.093453 -278.56292)
			(xy 192.128946 -278.597012) (xy 192.158511 -278.636356) (xy 192.181382 -278.679933) (xy 192.196966 -278.726614)
			(xy 192.204861 -278.775191) (xy 192.205356 -278.799798) (xy 192.204861 -278.824405) (xy 192.204682 -278.825506)
			(xy 192.523106 -278.825506) (xy 192.523106 -278.77409) (xy 192.531149 -278.723308) (xy 192.547037 -278.674409)
			(xy 192.57038 -278.628597) (xy 192.600601 -278.587001) (xy 192.636957 -278.550645) (xy 192.678553 -278.520424)
			(xy 192.724365 -278.497081) (xy 192.773264 -278.481193) (xy 192.824046 -278.47315) (xy 192.875462 -278.47315)
			(xy 192.926244 -278.481193) (xy 192.975143 -278.497081) (xy 193.020955 -278.520424) (xy 193.062551 -278.550645)
			(xy 193.098907 -278.587001) (xy 193.129128 -278.628597) (xy 193.152471 -278.674409) (xy 193.168359 -278.723308)
			(xy 193.176402 -278.77409) (xy 193.176906 -278.799798) (xy 193.494164 -278.799798) (xy 193.498124 -278.750744)
			(xy 193.509901 -278.70296) (xy 193.529192 -278.657684) (xy 193.555495 -278.616088) (xy 193.58813 -278.579251)
			(xy 193.626251 -278.548126) (xy 193.668872 -278.523519) (xy 193.714888 -278.506067) (xy 193.763107 -278.496223)
			(xy 193.812282 -278.494242) (xy 193.861137 -278.500174) (xy 193.908408 -278.513866) (xy 193.95287 -278.534964)
			(xy 193.993373 -278.56292) (xy 194.028866 -278.597012) (xy 194.058431 -278.636356) (xy 194.081302 -278.679933)
			(xy 194.096886 -278.726614) (xy 194.104781 -278.775191) (xy 194.105276 -278.799798) (xy 194.104781 -278.824405)
			(xy 194.104602 -278.825506) (xy 194.423026 -278.825506) (xy 194.423026 -278.77409) (xy 194.431069 -278.723308)
			(xy 194.446957 -278.674409) (xy 194.4703 -278.628597) (xy 194.500521 -278.587001) (xy 194.536877 -278.550645)
			(xy 194.578473 -278.520424) (xy 194.624285 -278.497081) (xy 194.673184 -278.481193) (xy 194.723966 -278.47315)
			(xy 194.775382 -278.47315) (xy 194.826164 -278.481193) (xy 194.875063 -278.497081) (xy 194.920875 -278.520424)
			(xy 194.962471 -278.550645) (xy 194.998827 -278.587001) (xy 195.029048 -278.628597) (xy 195.052391 -278.674409)
			(xy 195.068279 -278.723308) (xy 195.076322 -278.77409) (xy 195.076826 -278.799798) (xy 195.394084 -278.799798)
			(xy 195.398044 -278.750744) (xy 195.409821 -278.70296) (xy 195.429112 -278.657684) (xy 195.455415 -278.616088)
			(xy 195.48805 -278.579251) (xy 195.526171 -278.548126) (xy 195.568792 -278.523519) (xy 195.614808 -278.506067)
			(xy 195.663027 -278.496223) (xy 195.712202 -278.494242) (xy 195.761057 -278.500174) (xy 195.808328 -278.513866)
			(xy 195.85279 -278.534964) (xy 195.893293 -278.56292) (xy 195.928786 -278.597012) (xy 195.958351 -278.636356)
			(xy 195.981222 -278.679933) (xy 195.996806 -278.726614) (xy 196.004701 -278.775191) (xy 196.005196 -278.799798)
			(xy 196.004701 -278.824405) (xy 196.004522 -278.825506) (xy 196.3232 -278.825506) (xy 196.3232 -278.77409)
			(xy 196.331243 -278.723308) (xy 196.347131 -278.674409) (xy 196.370474 -278.628597) (xy 196.400695 -278.587001)
			(xy 196.437051 -278.550645) (xy 196.478647 -278.520424) (xy 196.524459 -278.497081) (xy 196.573358 -278.481193)
			(xy 196.62414 -278.47315) (xy 196.675556 -278.47315) (xy 196.726338 -278.481193) (xy 196.775237 -278.497081)
			(xy 196.821049 -278.520424) (xy 196.862645 -278.550645) (xy 196.899001 -278.587001) (xy 196.929222 -278.628597)
			(xy 196.952565 -278.674409) (xy 196.968453 -278.723308) (xy 196.976496 -278.77409) (xy 196.977 -278.799798)
			(xy 197.294258 -278.799798) (xy 197.298218 -278.750744) (xy 197.309995 -278.70296) (xy 197.329286 -278.657684)
			(xy 197.355589 -278.616088) (xy 197.388224 -278.579251) (xy 197.426345 -278.548126) (xy 197.468966 -278.523519)
			(xy 197.514982 -278.506067) (xy 197.563201 -278.496223) (xy 197.612376 -278.494242) (xy 197.661231 -278.500174)
			(xy 197.708502 -278.513866) (xy 197.752964 -278.534964) (xy 197.793467 -278.56292) (xy 197.82896 -278.597012)
			(xy 197.858525 -278.636356) (xy 197.881396 -278.679933) (xy 197.89698 -278.726614) (xy 197.904875 -278.775191)
			(xy 197.90537 -278.799798) (xy 198.244218 -278.799798) (xy 198.248178 -278.750744) (xy 198.259955 -278.70296)
			(xy 198.279246 -278.657684) (xy 198.305549 -278.616088) (xy 198.338184 -278.579251) (xy 198.376305 -278.548126)
			(xy 198.418926 -278.523519) (xy 198.464942 -278.506067) (xy 198.513161 -278.496223) (xy 198.562336 -278.494242)
			(xy 198.611191 -278.500174) (xy 198.658462 -278.513866) (xy 198.702924 -278.534964) (xy 198.743427 -278.56292)
			(xy 198.77892 -278.597012) (xy 198.808485 -278.636356) (xy 198.831356 -278.679933) (xy 198.84694 -278.726614)
			(xy 198.854835 -278.775191) (xy 198.85533 -278.799798) (xy 198.854835 -278.824405) (xy 198.84694 -278.872982)
			(xy 198.831356 -278.919663) (xy 198.808485 -278.96324) (xy 198.77892 -279.002584) (xy 198.743427 -279.036676)
			(xy 198.702924 -279.064632) (xy 198.679186 -279.075896) (xy 224.380042 -279.075896) (xy 224.384113 -279.020274)
			(xy 224.396239 -278.965837) (xy 224.416162 -278.913746) (xy 224.443458 -278.865111) (xy 224.477544 -278.820968)
			(xy 224.517693 -278.782259) (xy 224.563051 -278.749808) (xy 224.612651 -278.724307) (xy 224.665435 -278.7063)
			(xy 224.720278 -278.69617) (xy 224.776012 -278.694133) (xy 224.831449 -278.700233) (xy 224.885406 -278.714339)
			(xy 224.936735 -278.736151) (xy 224.984341 -278.765205) (xy 225.027209 -278.80088) (xy 225.064426 -278.842417)
			(xy 225.095199 -278.88893) (xy 225.118871 -278.939427) (xy 225.134939 -278.992834) (xy 225.143059 -279.04801)
			(xy 225.143568 -279.075896) (xy 225.143059 -279.103782) (xy 225.134939 -279.158958) (xy 225.118871 -279.212365)
			(xy 225.095199 -279.262862) (xy 225.064426 -279.309375) (xy 225.027209 -279.350912) (xy 224.984341 -279.386587)
			(xy 224.936735 -279.415641) (xy 224.885406 -279.437453) (xy 224.831449 -279.451559) (xy 224.776012 -279.457659)
			(xy 224.720278 -279.455622) (xy 224.665435 -279.445492) (xy 224.612651 -279.427485) (xy 224.563051 -279.401984)
			(xy 224.517693 -279.369533) (xy 224.477544 -279.330824) (xy 224.443458 -279.286681) (xy 224.416162 -279.238046)
			(xy 224.396239 -279.185955) (xy 224.384113 -279.131518) (xy 224.380042 -279.075896) (xy 198.679186 -279.075896)
			(xy 198.658462 -279.08573) (xy 198.611191 -279.099422) (xy 198.562336 -279.105354) (xy 198.513161 -279.103373)
			(xy 198.464942 -279.093529) (xy 198.418926 -279.076077) (xy 198.376305 -279.05147) (xy 198.338184 -279.020345)
			(xy 198.305549 -278.983508) (xy 198.279246 -278.941912) (xy 198.259955 -278.896636) (xy 198.248178 -278.848852)
			(xy 198.244218 -278.799798) (xy 197.90537 -278.799798) (xy 197.904875 -278.824405) (xy 197.89698 -278.872982)
			(xy 197.881396 -278.919663) (xy 197.858525 -278.96324) (xy 197.82896 -279.002584) (xy 197.793467 -279.036676)
			(xy 197.752964 -279.064632) (xy 197.708502 -279.08573) (xy 197.661231 -279.099422) (xy 197.612376 -279.105354)
			(xy 197.563201 -279.103373) (xy 197.514982 -279.093529) (xy 197.468966 -279.076077) (xy 197.426345 -279.05147)
			(xy 197.388224 -279.020345) (xy 197.355589 -278.983508) (xy 197.329286 -278.941912) (xy 197.309995 -278.896636)
			(xy 197.298218 -278.848852) (xy 197.294258 -278.799798) (xy 196.977 -278.799798) (xy 196.976496 -278.825506)
			(xy 196.968453 -278.876288) (xy 196.952565 -278.925187) (xy 196.929222 -278.970999) (xy 196.899001 -279.012595)
			(xy 196.862645 -279.048951) (xy 196.821049 -279.079172) (xy 196.775237 -279.102515) (xy 196.726338 -279.118403)
			(xy 196.675556 -279.126446) (xy 196.62414 -279.126446) (xy 196.573358 -279.118403) (xy 196.524459 -279.102515)
			(xy 196.478647 -279.079172) (xy 196.437051 -279.048951) (xy 196.400695 -279.012595) (xy 196.370474 -278.970999)
			(xy 196.347131 -278.925187) (xy 196.331243 -278.876288) (xy 196.3232 -278.825506) (xy 196.004522 -278.825506)
			(xy 195.996806 -278.872982) (xy 195.981222 -278.919663) (xy 195.958351 -278.96324) (xy 195.928786 -279.002584)
			(xy 195.893293 -279.036676) (xy 195.85279 -279.064632) (xy 195.808328 -279.08573) (xy 195.761057 -279.099422)
			(xy 195.712202 -279.105354) (xy 195.663027 -279.103373) (xy 195.614808 -279.093529) (xy 195.568792 -279.076077)
			(xy 195.526171 -279.05147) (xy 195.48805 -279.020345) (xy 195.455415 -278.983508) (xy 195.429112 -278.941912)
			(xy 195.409821 -278.896636) (xy 195.398044 -278.848852) (xy 195.394084 -278.799798) (xy 195.076826 -278.799798)
			(xy 195.076322 -278.825506) (xy 195.068279 -278.876288) (xy 195.052391 -278.925187) (xy 195.029048 -278.970999)
			(xy 194.998827 -279.012595) (xy 194.962471 -279.048951) (xy 194.920875 -279.079172) (xy 194.875063 -279.102515)
			(xy 194.826164 -279.118403) (xy 194.775382 -279.126446) (xy 194.723966 -279.126446) (xy 194.673184 -279.118403)
			(xy 194.624285 -279.102515) (xy 194.578473 -279.079172) (xy 194.536877 -279.048951) (xy 194.500521 -279.012595)
			(xy 194.4703 -278.970999) (xy 194.446957 -278.925187) (xy 194.431069 -278.876288) (xy 194.423026 -278.825506)
			(xy 194.104602 -278.825506) (xy 194.096886 -278.872982) (xy 194.081302 -278.919663) (xy 194.058431 -278.96324)
			(xy 194.028866 -279.002584) (xy 193.993373 -279.036676) (xy 193.95287 -279.064632) (xy 193.908408 -279.08573)
			(xy 193.861137 -279.099422) (xy 193.812282 -279.105354) (xy 193.763107 -279.103373) (xy 193.714888 -279.093529)
			(xy 193.668872 -279.076077) (xy 193.626251 -279.05147) (xy 193.58813 -279.020345) (xy 193.555495 -278.983508)
			(xy 193.529192 -278.941912) (xy 193.509901 -278.896636) (xy 193.498124 -278.848852) (xy 193.494164 -278.799798)
			(xy 193.176906 -278.799798) (xy 193.176402 -278.825506) (xy 193.168359 -278.876288) (xy 193.152471 -278.925187)
			(xy 193.129128 -278.970999) (xy 193.098907 -279.012595) (xy 193.062551 -279.048951) (xy 193.020955 -279.079172)
			(xy 192.975143 -279.102515) (xy 192.926244 -279.118403) (xy 192.875462 -279.126446) (xy 192.824046 -279.126446)
			(xy 192.773264 -279.118403) (xy 192.724365 -279.102515) (xy 192.678553 -279.079172) (xy 192.636957 -279.048951)
			(xy 192.600601 -279.012595) (xy 192.57038 -278.970999) (xy 192.547037 -278.925187) (xy 192.531149 -278.876288)
			(xy 192.523106 -278.825506) (xy 192.204682 -278.825506) (xy 192.196966 -278.872982) (xy 192.181382 -278.919663)
			(xy 192.158511 -278.96324) (xy 192.128946 -279.002584) (xy 192.093453 -279.036676) (xy 192.05295 -279.064632)
			(xy 192.008488 -279.08573) (xy 191.961217 -279.099422) (xy 191.912362 -279.105354) (xy 191.863187 -279.103373)
			(xy 191.814968 -279.093529) (xy 191.768952 -279.076077) (xy 191.726331 -279.05147) (xy 191.68821 -279.020345)
			(xy 191.655575 -278.983508) (xy 191.629272 -278.941912) (xy 191.609981 -278.896636) (xy 191.598204 -278.848852)
			(xy 191.594244 -278.799798) (xy 191.276986 -278.799798) (xy 191.276482 -278.825506) (xy 191.268439 -278.876288)
			(xy 191.252551 -278.925187) (xy 191.229208 -278.970999) (xy 191.198987 -279.012595) (xy 191.162631 -279.048951)
			(xy 191.121035 -279.079172) (xy 191.075223 -279.102515) (xy 191.026324 -279.118403) (xy 190.975542 -279.126446)
			(xy 190.924126 -279.126446) (xy 190.873344 -279.118403) (xy 190.824445 -279.102515) (xy 190.778633 -279.079172)
			(xy 190.737037 -279.048951) (xy 190.700681 -279.012595) (xy 190.67046 -278.970999) (xy 190.647117 -278.925187)
			(xy 190.631229 -278.876288) (xy 190.623186 -278.825506) (xy 190.304508 -278.825506) (xy 190.296792 -278.872982)
			(xy 190.281208 -278.919663) (xy 190.258337 -278.96324) (xy 190.228772 -279.002584) (xy 190.193279 -279.036676)
			(xy 190.152776 -279.064632) (xy 190.108314 -279.08573) (xy 190.061043 -279.099422) (xy 190.012188 -279.105354)
			(xy 189.963013 -279.103373) (xy 189.914794 -279.093529) (xy 189.868778 -279.076077) (xy 189.826157 -279.05147)
			(xy 189.788036 -279.020345) (xy 189.755401 -278.983508) (xy 189.729098 -278.941912) (xy 189.709807 -278.896636)
			(xy 189.69803 -278.848852) (xy 189.69407 -278.799798) (xy 189.376812 -278.799798) (xy 189.376308 -278.825506)
			(xy 189.368265 -278.876288) (xy 189.352377 -278.925187) (xy 189.329034 -278.970999) (xy 189.298813 -279.012595)
			(xy 189.262457 -279.048951) (xy 189.220861 -279.079172) (xy 189.175049 -279.102515) (xy 189.12615 -279.118403)
			(xy 189.075368 -279.126446) (xy 189.023952 -279.126446) (xy 188.97317 -279.118403) (xy 188.924271 -279.102515)
			(xy 188.878459 -279.079172) (xy 188.836863 -279.048951) (xy 188.800507 -279.012595) (xy 188.770286 -278.970999)
			(xy 188.746943 -278.925187) (xy 188.731055 -278.876288) (xy 188.723012 -278.825506) (xy 188.404588 -278.825506)
			(xy 188.396872 -278.872982) (xy 188.381288 -278.919663) (xy 188.358417 -278.96324) (xy 188.328852 -279.002584)
			(xy 188.293359 -279.036676) (xy 188.252856 -279.064632) (xy 188.208394 -279.08573) (xy 188.161123 -279.099422)
			(xy 188.112268 -279.105354) (xy 188.063093 -279.103373) (xy 188.014874 -279.093529) (xy 187.968858 -279.076077)
			(xy 187.926237 -279.05147) (xy 187.888116 -279.020345) (xy 187.855481 -278.983508) (xy 187.829178 -278.941912)
			(xy 187.809887 -278.896636) (xy 187.79811 -278.848852) (xy 187.79415 -278.799798) (xy 187.476892 -278.799798)
			(xy 187.476388 -278.825506) (xy 187.468345 -278.876288) (xy 187.452457 -278.925187) (xy 187.429114 -278.970999)
			(xy 187.398893 -279.012595) (xy 187.362537 -279.048951) (xy 187.320941 -279.079172) (xy 187.275129 -279.102515)
			(xy 187.22623 -279.118403) (xy 187.175448 -279.126446) (xy 187.124032 -279.126446) (xy 187.07325 -279.118403)
			(xy 187.024351 -279.102515) (xy 186.978539 -279.079172) (xy 186.936943 -279.048951) (xy 186.900587 -279.012595)
			(xy 186.870366 -278.970999) (xy 186.847023 -278.925187) (xy 186.831135 -278.876288) (xy 186.823092 -278.825506)
			(xy 186.504668 -278.825506) (xy 186.496952 -278.872982) (xy 186.481368 -278.919663) (xy 186.458497 -278.96324)
			(xy 186.428932 -279.002584) (xy 186.393439 -279.036676) (xy 186.352936 -279.064632) (xy 186.308474 -279.08573)
			(xy 186.261203 -279.099422) (xy 186.212348 -279.105354) (xy 186.163173 -279.103373) (xy 186.114954 -279.093529)
			(xy 186.068938 -279.076077) (xy 186.026317 -279.05147) (xy 185.988196 -279.020345) (xy 185.955561 -278.983508)
			(xy 185.929258 -278.941912) (xy 185.909967 -278.896636) (xy 185.89819 -278.848852) (xy 185.89423 -278.799798)
			(xy 185.576972 -278.799798) (xy 185.576468 -278.825506) (xy 185.568425 -278.876288) (xy 185.552537 -278.925187)
			(xy 185.529194 -278.970999) (xy 185.498973 -279.012595) (xy 185.462617 -279.048951) (xy 185.421021 -279.079172)
			(xy 185.375209 -279.102515) (xy 185.32631 -279.118403) (xy 185.275528 -279.126446) (xy 185.224112 -279.126446)
			(xy 185.17333 -279.118403) (xy 185.124431 -279.102515) (xy 185.078619 -279.079172) (xy 185.037023 -279.048951)
			(xy 185.000667 -279.012595) (xy 184.970446 -278.970999) (xy 184.947103 -278.925187) (xy 184.931215 -278.876288)
			(xy 184.923172 -278.825506) (xy 184.604494 -278.825506) (xy 184.596778 -278.872982) (xy 184.581194 -278.919663)
			(xy 184.558323 -278.96324) (xy 184.528758 -279.002584) (xy 184.493265 -279.036676) (xy 184.452762 -279.064632)
			(xy 184.4083 -279.08573) (xy 184.361029 -279.099422) (xy 184.312174 -279.105354) (xy 184.262999 -279.103373)
			(xy 184.21478 -279.093529) (xy 184.168764 -279.076077) (xy 184.126143 -279.05147) (xy 184.088022 -279.020345)
			(xy 184.055387 -278.983508) (xy 184.029084 -278.941912) (xy 184.009793 -278.896636) (xy 183.998016 -278.848852)
			(xy 183.994056 -278.799798) (xy 183.676798 -278.799798) (xy 183.676294 -278.825506) (xy 183.668251 -278.876288)
			(xy 183.652363 -278.925187) (xy 183.62902 -278.970999) (xy 183.598799 -279.012595) (xy 183.562443 -279.048951)
			(xy 183.520847 -279.079172) (xy 183.475035 -279.102515) (xy 183.426136 -279.118403) (xy 183.375354 -279.126446)
			(xy 183.323938 -279.126446) (xy 183.273156 -279.118403) (xy 183.224257 -279.102515) (xy 183.178445 -279.079172)
			(xy 183.136849 -279.048951) (xy 183.100493 -279.012595) (xy 183.070272 -278.970999) (xy 183.046929 -278.925187)
			(xy 183.031041 -278.876288) (xy 183.022998 -278.825506) (xy 182.704574 -278.825506) (xy 182.696858 -278.872982)
			(xy 182.681274 -278.919663) (xy 182.658403 -278.96324) (xy 182.628838 -279.002584) (xy 182.593345 -279.036676)
			(xy 182.552842 -279.064632) (xy 182.50838 -279.08573) (xy 182.461109 -279.099422) (xy 182.412254 -279.105354)
			(xy 182.363079 -279.103373) (xy 182.31486 -279.093529) (xy 182.268844 -279.076077) (xy 182.226223 -279.05147)
			(xy 182.188102 -279.020345) (xy 182.155467 -278.983508) (xy 182.129164 -278.941912) (xy 182.109873 -278.896636)
			(xy 182.098096 -278.848852) (xy 182.094136 -278.799798) (xy 181.776878 -278.799798) (xy 181.776374 -278.825506)
			(xy 181.768331 -278.876288) (xy 181.752443 -278.925187) (xy 181.7291 -278.970999) (xy 181.698879 -279.012595)
			(xy 181.662523 -279.048951) (xy 181.620927 -279.079172) (xy 181.575115 -279.102515) (xy 181.526216 -279.118403)
			(xy 181.475434 -279.126446) (xy 181.424018 -279.126446) (xy 181.373236 -279.118403) (xy 181.324337 -279.102515)
			(xy 181.278525 -279.079172) (xy 181.236929 -279.048951) (xy 181.200573 -279.012595) (xy 181.170352 -278.970999)
			(xy 181.147009 -278.925187) (xy 181.131121 -278.876288) (xy 181.123078 -278.825506) (xy 180.804654 -278.825506)
			(xy 180.796938 -278.872982) (xy 180.781354 -278.919663) (xy 180.758483 -278.96324) (xy 180.728918 -279.002584)
			(xy 180.693425 -279.036676) (xy 180.652922 -279.064632) (xy 180.60846 -279.08573) (xy 180.561189 -279.099422)
			(xy 180.512334 -279.105354) (xy 180.463159 -279.103373) (xy 180.41494 -279.093529) (xy 180.368924 -279.076077)
			(xy 180.326303 -279.05147) (xy 180.288182 -279.020345) (xy 180.255547 -278.983508) (xy 180.229244 -278.941912)
			(xy 180.209953 -278.896636) (xy 180.198176 -278.848852) (xy 180.194216 -278.799798) (xy 179.876958 -278.799798)
			(xy 179.876454 -278.825506) (xy 179.868411 -278.876288) (xy 179.852523 -278.925187) (xy 179.82918 -278.970999)
			(xy 179.798959 -279.012595) (xy 179.762603 -279.048951) (xy 179.721007 -279.079172) (xy 179.675195 -279.102515)
			(xy 179.626296 -279.118403) (xy 179.575514 -279.126446) (xy 179.524098 -279.126446) (xy 179.473316 -279.118403)
			(xy 179.424417 -279.102515) (xy 179.378605 -279.079172) (xy 179.337009 -279.048951) (xy 179.300653 -279.012595)
			(xy 179.270432 -278.970999) (xy 179.247089 -278.925187) (xy 179.231201 -278.876288) (xy 179.223158 -278.825506)
			(xy 178.90448 -278.825506) (xy 178.896764 -278.872982) (xy 178.88118 -278.919663) (xy 178.858309 -278.96324)
			(xy 178.828744 -279.002584) (xy 178.793251 -279.036676) (xy 178.752748 -279.064632) (xy 178.708286 -279.08573)
			(xy 178.661015 -279.099422) (xy 178.61216 -279.105354) (xy 178.562985 -279.103373) (xy 178.514766 -279.093529)
			(xy 178.46875 -279.076077) (xy 178.426129 -279.05147) (xy 178.388008 -279.020345) (xy 178.355373 -278.983508)
			(xy 178.32907 -278.941912) (xy 178.309779 -278.896636) (xy 178.298002 -278.848852) (xy 178.294042 -278.799798)
			(xy 177.976784 -278.799798) (xy 177.97628 -278.825506) (xy 177.968237 -278.876288) (xy 177.952349 -278.925187)
			(xy 177.929006 -278.970999) (xy 177.898785 -279.012595) (xy 177.862429 -279.048951) (xy 177.820833 -279.079172)
			(xy 177.775021 -279.102515) (xy 177.726122 -279.118403) (xy 177.67534 -279.126446) (xy 177.623924 -279.126446)
			(xy 177.573142 -279.118403) (xy 177.524243 -279.102515) (xy 177.478431 -279.079172) (xy 177.436835 -279.048951)
			(xy 177.400479 -279.012595) (xy 177.370258 -278.970999) (xy 177.346915 -278.925187) (xy 177.331027 -278.876288)
			(xy 177.322984 -278.825506) (xy 177.00456 -278.825506) (xy 176.996844 -278.872982) (xy 176.98126 -278.919663)
			(xy 176.958389 -278.96324) (xy 176.928824 -279.002584) (xy 176.893331 -279.036676) (xy 176.852828 -279.064632)
			(xy 176.808366 -279.08573) (xy 176.761095 -279.099422) (xy 176.71224 -279.105354) (xy 176.663065 -279.103373)
			(xy 176.614846 -279.093529) (xy 176.56883 -279.076077) (xy 176.526209 -279.05147) (xy 176.488088 -279.020345)
			(xy 176.455453 -278.983508) (xy 176.42915 -278.941912) (xy 176.409859 -278.896636) (xy 176.398082 -278.848852)
			(xy 176.394122 -278.799798) (xy 176.076096 -278.799798) (xy 176.076096 -278.825487) (xy 176.06806 -278.87623)
			(xy 176.052184 -278.92509) (xy 176.028861 -278.970865) (xy 175.998665 -279.012429) (xy 175.962338 -279.048757)
			(xy 175.920776 -279.078955) (xy 175.875001 -279.10228) (xy 175.826141 -279.118157) (xy 175.775399 -279.126195)
			(xy 175.749712 -279.126696) (xy 175.741076 -279.126696) (xy 175.72736 -279.126442) (xy 175.715676 -279.132792)
			(xy 175.70704 -279.138634) (xy 175.703926 -279.141406) (xy 175.698563 -279.147787) (xy 175.696372 -279.151334)
			(xy 175.650652 -279.226772) (xy 175.647343 -279.232603) (xy 175.643616 -279.245476) (xy 175.643286 -279.252172)
			(xy 175.643032 -279.265634) (xy 175.649636 -279.277572) (xy 175.667267 -279.309978) (xy 175.69816 -279.37698)
			(xy 175.711358 -279.41143) (xy 175.715306 -279.420727) (xy 175.729112 -279.435451) (xy 175.747511 -279.443748)
			(xy 175.757586 -279.44445) (xy 175.781183 -279.445478) (xy 175.827655 -279.453911) (xy 175.872273 -279.469401)
			(xy 175.913973 -279.491578) (xy 175.95176 -279.519914) (xy 175.98473 -279.553732) (xy 176.012099 -279.592225)
			(xy 176.033211 -279.634475) (xy 176.047564 -279.679472) (xy 176.054815 -279.726142) (xy 176.055274 -279.749758)
			(xy 176.054749 -279.775212) (xy 176.373278 -279.775212) (xy 176.373278 -279.723796) (xy 176.381321 -279.673014)
			(xy 176.397209 -279.624115) (xy 176.420552 -279.578303) (xy 176.450773 -279.536707) (xy 176.487129 -279.500351)
			(xy 176.528725 -279.47013) (xy 176.574537 -279.446787) (xy 176.623436 -279.430899) (xy 176.674218 -279.422856)
			(xy 176.725634 -279.422856) (xy 176.776416 -279.430899) (xy 176.825315 -279.446787) (xy 176.871127 -279.47013)
			(xy 176.912723 -279.500351) (xy 176.949079 -279.536707) (xy 176.9793 -279.578303) (xy 177.002643 -279.624115)
			(xy 177.018531 -279.673014) (xy 177.026574 -279.723796) (xy 177.027078 -279.749504) (xy 177.027073 -279.749758)
			(xy 177.344082 -279.749758) (xy 177.348042 -279.700704) (xy 177.359819 -279.65292) (xy 177.37911 -279.607644)
			(xy 177.405413 -279.566048) (xy 177.438048 -279.529211) (xy 177.476169 -279.498086) (xy 177.51879 -279.473479)
			(xy 177.564806 -279.456027) (xy 177.613025 -279.446183) (xy 177.6622 -279.444202) (xy 177.711055 -279.450134)
			(xy 177.758326 -279.463826) (xy 177.802788 -279.484924) (xy 177.843291 -279.51288) (xy 177.878784 -279.546972)
			(xy 177.908349 -279.586316) (xy 177.93122 -279.629893) (xy 177.946804 -279.676574) (xy 177.954699 -279.725151)
			(xy 177.955194 -279.749758) (xy 177.954699 -279.774365) (xy 177.954561 -279.775212) (xy 178.273198 -279.775212)
			(xy 178.273198 -279.723796) (xy 178.281241 -279.673014) (xy 178.297129 -279.624115) (xy 178.320472 -279.578303)
			(xy 178.350693 -279.536707) (xy 178.387049 -279.500351) (xy 178.428645 -279.47013) (xy 178.474457 -279.446787)
			(xy 178.523356 -279.430899) (xy 178.574138 -279.422856) (xy 178.625554 -279.422856) (xy 178.676336 -279.430899)
			(xy 178.725235 -279.446787) (xy 178.771047 -279.47013) (xy 178.812643 -279.500351) (xy 178.848999 -279.536707)
			(xy 178.87922 -279.578303) (xy 178.902563 -279.624115) (xy 178.918451 -279.673014) (xy 178.926494 -279.723796)
			(xy 178.926998 -279.749504) (xy 178.926993 -279.749758) (xy 179.244256 -279.749758) (xy 179.248216 -279.700704)
			(xy 179.259993 -279.65292) (xy 179.279284 -279.607644) (xy 179.305587 -279.566048) (xy 179.338222 -279.529211)
			(xy 179.376343 -279.498086) (xy 179.418964 -279.473479) (xy 179.46498 -279.456027) (xy 179.513199 -279.446183)
			(xy 179.562374 -279.444202) (xy 179.611229 -279.450134) (xy 179.6585 -279.463826) (xy 179.702962 -279.484924)
			(xy 179.743465 -279.51288) (xy 179.778958 -279.546972) (xy 179.808523 -279.586316) (xy 179.831394 -279.629893)
			(xy 179.846978 -279.676574) (xy 179.854873 -279.725151) (xy 179.855368 -279.749758) (xy 179.854873 -279.774365)
			(xy 179.854735 -279.775212) (xy 180.173372 -279.775212) (xy 180.173372 -279.723796) (xy 180.181415 -279.673014)
			(xy 180.197303 -279.624115) (xy 180.220646 -279.578303) (xy 180.250867 -279.536707) (xy 180.287223 -279.500351)
			(xy 180.328819 -279.47013) (xy 180.374631 -279.446787) (xy 180.42353 -279.430899) (xy 180.474312 -279.422856)
			(xy 180.525728 -279.422856) (xy 180.57651 -279.430899) (xy 180.625409 -279.446787) (xy 180.671221 -279.47013)
			(xy 180.712817 -279.500351) (xy 180.749173 -279.536707) (xy 180.779394 -279.578303) (xy 180.802737 -279.624115)
			(xy 180.818625 -279.673014) (xy 180.826668 -279.723796) (xy 180.827172 -279.749504) (xy 180.827167 -279.749758)
			(xy 181.144176 -279.749758) (xy 181.148136 -279.700704) (xy 181.159913 -279.65292) (xy 181.179204 -279.607644)
			(xy 181.205507 -279.566048) (xy 181.238142 -279.529211) (xy 181.276263 -279.498086) (xy 181.318884 -279.473479)
			(xy 181.3649 -279.456027) (xy 181.413119 -279.446183) (xy 181.462294 -279.444202) (xy 181.511149 -279.450134)
			(xy 181.55842 -279.463826) (xy 181.602882 -279.484924) (xy 181.643385 -279.51288) (xy 181.678878 -279.546972)
			(xy 181.708443 -279.586316) (xy 181.731314 -279.629893) (xy 181.746898 -279.676574) (xy 181.754793 -279.725151)
			(xy 181.755288 -279.749758) (xy 181.754793 -279.774365) (xy 181.754655 -279.775212) (xy 182.073292 -279.775212)
			(xy 182.073292 -279.723796) (xy 182.081335 -279.673014) (xy 182.097223 -279.624115) (xy 182.120566 -279.578303)
			(xy 182.150787 -279.536707) (xy 182.187143 -279.500351) (xy 182.228739 -279.47013) (xy 182.274551 -279.446787)
			(xy 182.32345 -279.430899) (xy 182.374232 -279.422856) (xy 182.425648 -279.422856) (xy 182.47643 -279.430899)
			(xy 182.525329 -279.446787) (xy 182.571141 -279.47013) (xy 182.612737 -279.500351) (xy 182.649093 -279.536707)
			(xy 182.679314 -279.578303) (xy 182.702657 -279.624115) (xy 182.718545 -279.673014) (xy 182.726588 -279.723796)
			(xy 182.727092 -279.749504) (xy 182.727087 -279.749758) (xy 183.044096 -279.749758) (xy 183.048056 -279.700704)
			(xy 183.059833 -279.65292) (xy 183.079124 -279.607644) (xy 183.105427 -279.566048) (xy 183.138062 -279.529211)
			(xy 183.176183 -279.498086) (xy 183.218804 -279.473479) (xy 183.26482 -279.456027) (xy 183.313039 -279.446183)
			(xy 183.362214 -279.444202) (xy 183.411069 -279.450134) (xy 183.45834 -279.463826) (xy 183.502802 -279.484924)
			(xy 183.543305 -279.51288) (xy 183.578798 -279.546972) (xy 183.608363 -279.586316) (xy 183.631234 -279.629893)
			(xy 183.646818 -279.676574) (xy 183.654713 -279.725151) (xy 183.655208 -279.749758) (xy 183.654713 -279.774365)
			(xy 183.654575 -279.775212) (xy 183.973212 -279.775212) (xy 183.973212 -279.723796) (xy 183.981255 -279.673014)
			(xy 183.997143 -279.624115) (xy 184.020486 -279.578303) (xy 184.050707 -279.536707) (xy 184.087063 -279.500351)
			(xy 184.128659 -279.47013) (xy 184.174471 -279.446787) (xy 184.22337 -279.430899) (xy 184.274152 -279.422856)
			(xy 184.325568 -279.422856) (xy 184.37635 -279.430899) (xy 184.425249 -279.446787) (xy 184.471061 -279.47013)
			(xy 184.512657 -279.500351) (xy 184.549013 -279.536707) (xy 184.579234 -279.578303) (xy 184.602577 -279.624115)
			(xy 184.618465 -279.673014) (xy 184.626508 -279.723796) (xy 184.627012 -279.749504) (xy 184.627007 -279.749758)
			(xy 184.94427 -279.749758) (xy 184.94823 -279.700704) (xy 184.960007 -279.65292) (xy 184.979298 -279.607644)
			(xy 185.005601 -279.566048) (xy 185.038236 -279.529211) (xy 185.076357 -279.498086) (xy 185.118978 -279.473479)
			(xy 185.164994 -279.456027) (xy 185.213213 -279.446183) (xy 185.262388 -279.444202) (xy 185.311243 -279.450134)
			(xy 185.358514 -279.463826) (xy 185.402976 -279.484924) (xy 185.443479 -279.51288) (xy 185.478972 -279.546972)
			(xy 185.508537 -279.586316) (xy 185.531408 -279.629893) (xy 185.546992 -279.676574) (xy 185.554887 -279.725151)
			(xy 185.555382 -279.749758) (xy 185.554887 -279.774365) (xy 185.554749 -279.775212) (xy 185.873386 -279.775212)
			(xy 185.873386 -279.723796) (xy 185.881429 -279.673014) (xy 185.897317 -279.624115) (xy 185.92066 -279.578303)
			(xy 185.950881 -279.536707) (xy 185.987237 -279.500351) (xy 186.028833 -279.47013) (xy 186.074645 -279.446787)
			(xy 186.123544 -279.430899) (xy 186.174326 -279.422856) (xy 186.225742 -279.422856) (xy 186.276524 -279.430899)
			(xy 186.325423 -279.446787) (xy 186.371235 -279.47013) (xy 186.412831 -279.500351) (xy 186.449187 -279.536707)
			(xy 186.479408 -279.578303) (xy 186.502751 -279.624115) (xy 186.518639 -279.673014) (xy 186.526682 -279.723796)
			(xy 186.527186 -279.749504) (xy 186.527181 -279.749758) (xy 186.84419 -279.749758) (xy 186.84815 -279.700704)
			(xy 186.859927 -279.65292) (xy 186.879218 -279.607644) (xy 186.905521 -279.566048) (xy 186.938156 -279.529211)
			(xy 186.976277 -279.498086) (xy 187.018898 -279.473479) (xy 187.064914 -279.456027) (xy 187.113133 -279.446183)
			(xy 187.162308 -279.444202) (xy 187.211163 -279.450134) (xy 187.258434 -279.463826) (xy 187.302896 -279.484924)
			(xy 187.343399 -279.51288) (xy 187.378892 -279.546972) (xy 187.408457 -279.586316) (xy 187.431328 -279.629893)
			(xy 187.446912 -279.676574) (xy 187.454807 -279.725151) (xy 187.455302 -279.749758) (xy 187.454807 -279.774365)
			(xy 187.454669 -279.775212) (xy 187.773306 -279.775212) (xy 187.773306 -279.723796) (xy 187.781349 -279.673014)
			(xy 187.797237 -279.624115) (xy 187.82058 -279.578303) (xy 187.850801 -279.536707) (xy 187.887157 -279.500351)
			(xy 187.928753 -279.47013) (xy 187.974565 -279.446787) (xy 188.023464 -279.430899) (xy 188.074246 -279.422856)
			(xy 188.125662 -279.422856) (xy 188.176444 -279.430899) (xy 188.225343 -279.446787) (xy 188.271155 -279.47013)
			(xy 188.312751 -279.500351) (xy 188.349107 -279.536707) (xy 188.379328 -279.578303) (xy 188.402671 -279.624115)
			(xy 188.418559 -279.673014) (xy 188.426602 -279.723796) (xy 188.427106 -279.749504) (xy 188.427101 -279.749758)
			(xy 188.74411 -279.749758) (xy 188.74807 -279.700704) (xy 188.759847 -279.65292) (xy 188.779138 -279.607644)
			(xy 188.805441 -279.566048) (xy 188.838076 -279.529211) (xy 188.876197 -279.498086) (xy 188.918818 -279.473479)
			(xy 188.964834 -279.456027) (xy 189.013053 -279.446183) (xy 189.062228 -279.444202) (xy 189.111083 -279.450134)
			(xy 189.158354 -279.463826) (xy 189.202816 -279.484924) (xy 189.243319 -279.51288) (xy 189.278812 -279.546972)
			(xy 189.308377 -279.586316) (xy 189.331248 -279.629893) (xy 189.346832 -279.676574) (xy 189.354727 -279.725151)
			(xy 189.355222 -279.749758) (xy 189.354727 -279.774365) (xy 189.354589 -279.775212) (xy 189.673226 -279.775212)
			(xy 189.673226 -279.723796) (xy 189.681269 -279.673014) (xy 189.697157 -279.624115) (xy 189.7205 -279.578303)
			(xy 189.750721 -279.536707) (xy 189.787077 -279.500351) (xy 189.828673 -279.47013) (xy 189.874485 -279.446787)
			(xy 189.923384 -279.430899) (xy 189.974166 -279.422856) (xy 190.025582 -279.422856) (xy 190.076364 -279.430899)
			(xy 190.125263 -279.446787) (xy 190.171075 -279.47013) (xy 190.212671 -279.500351) (xy 190.249027 -279.536707)
			(xy 190.279248 -279.578303) (xy 190.302591 -279.624115) (xy 190.318479 -279.673014) (xy 190.326522 -279.723796)
			(xy 190.327026 -279.749504) (xy 190.327021 -279.749758) (xy 190.64403 -279.749758) (xy 190.64799 -279.700704)
			(xy 190.659767 -279.65292) (xy 190.679058 -279.607644) (xy 190.705361 -279.566048) (xy 190.737996 -279.529211)
			(xy 190.776117 -279.498086) (xy 190.818738 -279.473479) (xy 190.864754 -279.456027) (xy 190.912973 -279.446183)
			(xy 190.962148 -279.444202) (xy 191.011003 -279.450134) (xy 191.058274 -279.463826) (xy 191.102736 -279.484924)
			(xy 191.143239 -279.51288) (xy 191.178732 -279.546972) (xy 191.208297 -279.586316) (xy 191.231168 -279.629893)
			(xy 191.246752 -279.676574) (xy 191.254647 -279.725151) (xy 191.255142 -279.749758) (xy 191.254647 -279.774365)
			(xy 191.254509 -279.775212) (xy 191.5734 -279.775212) (xy 191.5734 -279.723796) (xy 191.581443 -279.673014)
			(xy 191.597331 -279.624115) (xy 191.620674 -279.578303) (xy 191.650895 -279.536707) (xy 191.687251 -279.500351)
			(xy 191.728847 -279.47013) (xy 191.774659 -279.446787) (xy 191.823558 -279.430899) (xy 191.87434 -279.422856)
			(xy 191.925756 -279.422856) (xy 191.976538 -279.430899) (xy 192.025437 -279.446787) (xy 192.071249 -279.47013)
			(xy 192.112845 -279.500351) (xy 192.149201 -279.536707) (xy 192.179422 -279.578303) (xy 192.202765 -279.624115)
			(xy 192.218653 -279.673014) (xy 192.226696 -279.723796) (xy 192.2272 -279.749504) (xy 192.227195 -279.749758)
			(xy 192.544204 -279.749758) (xy 192.548164 -279.700704) (xy 192.559941 -279.65292) (xy 192.579232 -279.607644)
			(xy 192.605535 -279.566048) (xy 192.63817 -279.529211) (xy 192.676291 -279.498086) (xy 192.718912 -279.473479)
			(xy 192.764928 -279.456027) (xy 192.813147 -279.446183) (xy 192.862322 -279.444202) (xy 192.911177 -279.450134)
			(xy 192.958448 -279.463826) (xy 193.00291 -279.484924) (xy 193.043413 -279.51288) (xy 193.078906 -279.546972)
			(xy 193.108471 -279.586316) (xy 193.131342 -279.629893) (xy 193.146926 -279.676574) (xy 193.154821 -279.725151)
			(xy 193.155316 -279.749758) (xy 193.154821 -279.774365) (xy 193.154683 -279.775212) (xy 193.47332 -279.775212)
			(xy 193.47332 -279.723796) (xy 193.481363 -279.673014) (xy 193.497251 -279.624115) (xy 193.520594 -279.578303)
			(xy 193.550815 -279.536707) (xy 193.587171 -279.500351) (xy 193.628767 -279.47013) (xy 193.674579 -279.446787)
			(xy 193.723478 -279.430899) (xy 193.77426 -279.422856) (xy 193.825676 -279.422856) (xy 193.876458 -279.430899)
			(xy 193.925357 -279.446787) (xy 193.971169 -279.47013) (xy 194.012765 -279.500351) (xy 194.049121 -279.536707)
			(xy 194.079342 -279.578303) (xy 194.102685 -279.624115) (xy 194.118573 -279.673014) (xy 194.126616 -279.723796)
			(xy 194.12712 -279.749504) (xy 194.127115 -279.749758) (xy 194.444124 -279.749758) (xy 194.448084 -279.700704)
			(xy 194.459861 -279.65292) (xy 194.479152 -279.607644) (xy 194.505455 -279.566048) (xy 194.53809 -279.529211)
			(xy 194.576211 -279.498086) (xy 194.618832 -279.473479) (xy 194.664848 -279.456027) (xy 194.713067 -279.446183)
			(xy 194.762242 -279.444202) (xy 194.811097 -279.450134) (xy 194.858368 -279.463826) (xy 194.90283 -279.484924)
			(xy 194.943333 -279.51288) (xy 194.978826 -279.546972) (xy 195.008391 -279.586316) (xy 195.031262 -279.629893)
			(xy 195.046846 -279.676574) (xy 195.054741 -279.725151) (xy 195.055236 -279.749758) (xy 195.054741 -279.774365)
			(xy 195.054562 -279.775466) (xy 195.37324 -279.775466) (xy 195.37324 -279.72405) (xy 195.381283 -279.673268)
			(xy 195.397171 -279.624369) (xy 195.420514 -279.578557) (xy 195.450735 -279.536961) (xy 195.487091 -279.500605)
			(xy 195.528687 -279.470384) (xy 195.574499 -279.447041) (xy 195.623398 -279.431153) (xy 195.67418 -279.42311)
			(xy 195.725596 -279.42311) (xy 195.776378 -279.431153) (xy 195.825277 -279.447041) (xy 195.871089 -279.470384)
			(xy 195.912685 -279.500605) (xy 195.949041 -279.536961) (xy 195.979262 -279.578557) (xy 196.002605 -279.624369)
			(xy 196.018493 -279.673268) (xy 196.026536 -279.72405) (xy 196.02704 -279.749758) (xy 196.344044 -279.749758)
			(xy 196.348004 -279.700704) (xy 196.359781 -279.65292) (xy 196.379072 -279.607644) (xy 196.405375 -279.566048)
			(xy 196.43801 -279.529211) (xy 196.476131 -279.498086) (xy 196.518752 -279.473479) (xy 196.564768 -279.456027)
			(xy 196.612987 -279.446183) (xy 196.662162 -279.444202) (xy 196.711017 -279.450134) (xy 196.758288 -279.463826)
			(xy 196.80275 -279.484924) (xy 196.843253 -279.51288) (xy 196.878746 -279.546972) (xy 196.908311 -279.586316)
			(xy 196.931182 -279.629893) (xy 196.946766 -279.676574) (xy 196.954661 -279.725151) (xy 196.955156 -279.749758)
			(xy 196.954661 -279.774365) (xy 196.954482 -279.775466) (xy 197.273414 -279.775466) (xy 197.273414 -279.72405)
			(xy 197.281457 -279.673268) (xy 197.297345 -279.624369) (xy 197.320688 -279.578557) (xy 197.350909 -279.536961)
			(xy 197.387265 -279.500605) (xy 197.428861 -279.470384) (xy 197.474673 -279.447041) (xy 197.523572 -279.431153)
			(xy 197.574354 -279.42311) (xy 197.62577 -279.42311) (xy 197.676552 -279.431153) (xy 197.725451 -279.447041)
			(xy 197.771263 -279.470384) (xy 197.812859 -279.500605) (xy 197.849215 -279.536961) (xy 197.879436 -279.578557)
			(xy 197.902779 -279.624369) (xy 197.918667 -279.673268) (xy 197.92671 -279.72405) (xy 197.927214 -279.749758)
			(xy 197.92671 -279.775466) (xy 198.223374 -279.775466) (xy 198.223374 -279.72405) (xy 198.231417 -279.673268)
			(xy 198.247305 -279.624369) (xy 198.270648 -279.578557) (xy 198.300869 -279.536961) (xy 198.337225 -279.500605)
			(xy 198.378821 -279.470384) (xy 198.424633 -279.447041) (xy 198.473532 -279.431153) (xy 198.524314 -279.42311)
			(xy 198.57573 -279.42311) (xy 198.626512 -279.431153) (xy 198.675411 -279.447041) (xy 198.721223 -279.470384)
			(xy 198.762819 -279.500605) (xy 198.799175 -279.536961) (xy 198.829396 -279.578557) (xy 198.852739 -279.624369)
			(xy 198.868627 -279.673268) (xy 198.87667 -279.72405) (xy 198.877174 -279.749758) (xy 198.877169 -279.750012)
			(xy 199.194432 -279.750012) (xy 199.198392 -279.700958) (xy 199.210169 -279.653174) (xy 199.22946 -279.607898)
			(xy 199.255763 -279.566302) (xy 199.288398 -279.529465) (xy 199.326519 -279.49834) (xy 199.36914 -279.473733)
			(xy 199.415156 -279.456281) (xy 199.463375 -279.446437) (xy 199.51255 -279.444456) (xy 199.561405 -279.450388)
			(xy 199.608676 -279.46408) (xy 199.653138 -279.485178) (xy 199.693641 -279.513134) (xy 199.729134 -279.547226)
			(xy 199.758699 -279.58657) (xy 199.78157 -279.630147) (xy 199.797154 -279.676828) (xy 199.805049 -279.725405)
			(xy 199.805544 -279.750012) (xy 199.805049 -279.774619) (xy 199.797154 -279.823196) (xy 199.78157 -279.869877)
			(xy 199.758699 -279.913454) (xy 199.729134 -279.952798) (xy 199.693641 -279.98689) (xy 199.653138 -280.014846)
			(xy 199.608676 -280.035944) (xy 199.561405 -280.049636) (xy 199.51255 -280.055568) (xy 199.463375 -280.053587)
			(xy 199.415156 -280.043743) (xy 199.36914 -280.026291) (xy 199.326519 -280.001684) (xy 199.288398 -279.970559)
			(xy 199.255763 -279.933722) (xy 199.22946 -279.892126) (xy 199.210169 -279.84685) (xy 199.198392 -279.799066)
			(xy 199.194432 -279.750012) (xy 198.877169 -279.750012) (xy 198.87667 -279.775466) (xy 198.868627 -279.826248)
			(xy 198.852739 -279.875147) (xy 198.829396 -279.920959) (xy 198.799175 -279.962555) (xy 198.762819 -279.998911)
			(xy 198.721223 -280.029132) (xy 198.675411 -280.052475) (xy 198.626512 -280.068363) (xy 198.57573 -280.076406)
			(xy 198.524314 -280.076406) (xy 198.473532 -280.068363) (xy 198.424633 -280.052475) (xy 198.378821 -280.029132)
			(xy 198.337225 -279.998911) (xy 198.300869 -279.962555) (xy 198.270648 -279.920959) (xy 198.247305 -279.875147)
			(xy 198.231417 -279.826248) (xy 198.223374 -279.775466) (xy 197.92671 -279.775466) (xy 197.918667 -279.826248)
			(xy 197.902779 -279.875147) (xy 197.879436 -279.920959) (xy 197.849215 -279.962555) (xy 197.812859 -279.998911)
			(xy 197.771263 -280.029132) (xy 197.725451 -280.052475) (xy 197.676552 -280.068363) (xy 197.62577 -280.076406)
			(xy 197.574354 -280.076406) (xy 197.523572 -280.068363) (xy 197.474673 -280.052475) (xy 197.428861 -280.029132)
			(xy 197.387265 -279.998911) (xy 197.350909 -279.962555) (xy 197.320688 -279.920959) (xy 197.297345 -279.875147)
			(xy 197.281457 -279.826248) (xy 197.273414 -279.775466) (xy 196.954482 -279.775466) (xy 196.946766 -279.822942)
			(xy 196.931182 -279.869623) (xy 196.908311 -279.9132) (xy 196.878746 -279.952544) (xy 196.843253 -279.986636)
			(xy 196.80275 -280.014592) (xy 196.758288 -280.03569) (xy 196.711017 -280.049382) (xy 196.662162 -280.055314)
			(xy 196.612987 -280.053333) (xy 196.564768 -280.043489) (xy 196.518752 -280.026037) (xy 196.476131 -280.00143)
			(xy 196.43801 -279.970305) (xy 196.405375 -279.933468) (xy 196.379072 -279.891872) (xy 196.359781 -279.846596)
			(xy 196.348004 -279.798812) (xy 196.344044 -279.749758) (xy 196.02704 -279.749758) (xy 196.026536 -279.775466)
			(xy 196.018493 -279.826248) (xy 196.002605 -279.875147) (xy 195.979262 -279.920959) (xy 195.949041 -279.962555)
			(xy 195.912685 -279.998911) (xy 195.871089 -280.029132) (xy 195.825277 -280.052475) (xy 195.776378 -280.068363)
			(xy 195.725596 -280.076406) (xy 195.67418 -280.076406) (xy 195.623398 -280.068363) (xy 195.574499 -280.052475)
			(xy 195.528687 -280.029132) (xy 195.487091 -279.998911) (xy 195.450735 -279.962555) (xy 195.420514 -279.920959)
			(xy 195.397171 -279.875147) (xy 195.381283 -279.826248) (xy 195.37324 -279.775466) (xy 195.054562 -279.775466)
			(xy 195.046846 -279.822942) (xy 195.031262 -279.869623) (xy 195.008391 -279.9132) (xy 194.978826 -279.952544)
			(xy 194.943333 -279.986636) (xy 194.90283 -280.014592) (xy 194.858368 -280.03569) (xy 194.811097 -280.049382)
			(xy 194.762242 -280.055314) (xy 194.713067 -280.053333) (xy 194.664848 -280.043489) (xy 194.618832 -280.026037)
			(xy 194.576211 -280.00143) (xy 194.53809 -279.970305) (xy 194.505455 -279.933468) (xy 194.479152 -279.891872)
			(xy 194.459861 -279.846596) (xy 194.448084 -279.798812) (xy 194.444124 -279.749758) (xy 194.127115 -279.749758)
			(xy 194.126616 -279.775212) (xy 194.118573 -279.825994) (xy 194.102685 -279.874893) (xy 194.079342 -279.920705)
			(xy 194.049121 -279.962301) (xy 194.012765 -279.998657) (xy 193.971169 -280.028878) (xy 193.925357 -280.052221)
			(xy 193.876458 -280.068109) (xy 193.825676 -280.076152) (xy 193.77426 -280.076152) (xy 193.723478 -280.068109)
			(xy 193.674579 -280.052221) (xy 193.628767 -280.028878) (xy 193.587171 -279.998657) (xy 193.550815 -279.962301)
			(xy 193.520594 -279.920705) (xy 193.497251 -279.874893) (xy 193.481363 -279.825994) (xy 193.47332 -279.775212)
			(xy 193.154683 -279.775212) (xy 193.146926 -279.822942) (xy 193.131342 -279.869623) (xy 193.108471 -279.9132)
			(xy 193.078906 -279.952544) (xy 193.043413 -279.986636) (xy 193.00291 -280.014592) (xy 192.958448 -280.03569)
			(xy 192.911177 -280.049382) (xy 192.862322 -280.055314) (xy 192.813147 -280.053333) (xy 192.764928 -280.043489)
			(xy 192.718912 -280.026037) (xy 192.676291 -280.00143) (xy 192.63817 -279.970305) (xy 192.605535 -279.933468)
			(xy 192.579232 -279.891872) (xy 192.559941 -279.846596) (xy 192.548164 -279.798812) (xy 192.544204 -279.749758)
			(xy 192.227195 -279.749758) (xy 192.226696 -279.775212) (xy 192.218653 -279.825994) (xy 192.202765 -279.874893)
			(xy 192.179422 -279.920705) (xy 192.149201 -279.962301) (xy 192.112845 -279.998657) (xy 192.071249 -280.028878)
			(xy 192.025437 -280.052221) (xy 191.976538 -280.068109) (xy 191.925756 -280.076152) (xy 191.87434 -280.076152)
			(xy 191.823558 -280.068109) (xy 191.774659 -280.052221) (xy 191.728847 -280.028878) (xy 191.687251 -279.998657)
			(xy 191.650895 -279.962301) (xy 191.620674 -279.920705) (xy 191.597331 -279.874893) (xy 191.581443 -279.825994)
			(xy 191.5734 -279.775212) (xy 191.254509 -279.775212) (xy 191.246752 -279.822942) (xy 191.231168 -279.869623)
			(xy 191.208297 -279.9132) (xy 191.178732 -279.952544) (xy 191.143239 -279.986636) (xy 191.102736 -280.014592)
			(xy 191.058274 -280.03569) (xy 191.011003 -280.049382) (xy 190.962148 -280.055314) (xy 190.912973 -280.053333)
			(xy 190.864754 -280.043489) (xy 190.818738 -280.026037) (xy 190.776117 -280.00143) (xy 190.737996 -279.970305)
			(xy 190.705361 -279.933468) (xy 190.679058 -279.891872) (xy 190.659767 -279.846596) (xy 190.64799 -279.798812)
			(xy 190.64403 -279.749758) (xy 190.327021 -279.749758) (xy 190.326522 -279.775212) (xy 190.318479 -279.825994)
			(xy 190.302591 -279.874893) (xy 190.279248 -279.920705) (xy 190.249027 -279.962301) (xy 190.212671 -279.998657)
			(xy 190.171075 -280.028878) (xy 190.125263 -280.052221) (xy 190.076364 -280.068109) (xy 190.025582 -280.076152)
			(xy 189.974166 -280.076152) (xy 189.923384 -280.068109) (xy 189.874485 -280.052221) (xy 189.828673 -280.028878)
			(xy 189.787077 -279.998657) (xy 189.750721 -279.962301) (xy 189.7205 -279.920705) (xy 189.697157 -279.874893)
			(xy 189.681269 -279.825994) (xy 189.673226 -279.775212) (xy 189.354589 -279.775212) (xy 189.346832 -279.822942)
			(xy 189.331248 -279.869623) (xy 189.308377 -279.9132) (xy 189.278812 -279.952544) (xy 189.243319 -279.986636)
			(xy 189.202816 -280.014592) (xy 189.158354 -280.03569) (xy 189.111083 -280.049382) (xy 189.062228 -280.055314)
			(xy 189.013053 -280.053333) (xy 188.964834 -280.043489) (xy 188.918818 -280.026037) (xy 188.876197 -280.00143)
			(xy 188.838076 -279.970305) (xy 188.805441 -279.933468) (xy 188.779138 -279.891872) (xy 188.759847 -279.846596)
			(xy 188.74807 -279.798812) (xy 188.74411 -279.749758) (xy 188.427101 -279.749758) (xy 188.426602 -279.775212)
			(xy 188.418559 -279.825994) (xy 188.402671 -279.874893) (xy 188.379328 -279.920705) (xy 188.349107 -279.962301)
			(xy 188.312751 -279.998657) (xy 188.271155 -280.028878) (xy 188.225343 -280.052221) (xy 188.176444 -280.068109)
			(xy 188.125662 -280.076152) (xy 188.074246 -280.076152) (xy 188.023464 -280.068109) (xy 187.974565 -280.052221)
			(xy 187.928753 -280.028878) (xy 187.887157 -279.998657) (xy 187.850801 -279.962301) (xy 187.82058 -279.920705)
			(xy 187.797237 -279.874893) (xy 187.781349 -279.825994) (xy 187.773306 -279.775212) (xy 187.454669 -279.775212)
			(xy 187.446912 -279.822942) (xy 187.431328 -279.869623) (xy 187.408457 -279.9132) (xy 187.378892 -279.952544)
			(xy 187.343399 -279.986636) (xy 187.302896 -280.014592) (xy 187.258434 -280.03569) (xy 187.211163 -280.049382)
			(xy 187.162308 -280.055314) (xy 187.113133 -280.053333) (xy 187.064914 -280.043489) (xy 187.018898 -280.026037)
			(xy 186.976277 -280.00143) (xy 186.938156 -279.970305) (xy 186.905521 -279.933468) (xy 186.879218 -279.891872)
			(xy 186.859927 -279.846596) (xy 186.84815 -279.798812) (xy 186.84419 -279.749758) (xy 186.527181 -279.749758)
			(xy 186.526682 -279.775212) (xy 186.518639 -279.825994) (xy 186.502751 -279.874893) (xy 186.479408 -279.920705)
			(xy 186.449187 -279.962301) (xy 186.412831 -279.998657) (xy 186.371235 -280.028878) (xy 186.325423 -280.052221)
			(xy 186.276524 -280.068109) (xy 186.225742 -280.076152) (xy 186.174326 -280.076152) (xy 186.123544 -280.068109)
			(xy 186.074645 -280.052221) (xy 186.028833 -280.028878) (xy 185.987237 -279.998657) (xy 185.950881 -279.962301)
			(xy 185.92066 -279.920705) (xy 185.897317 -279.874893) (xy 185.881429 -279.825994) (xy 185.873386 -279.775212)
			(xy 185.554749 -279.775212) (xy 185.546992 -279.822942) (xy 185.531408 -279.869623) (xy 185.508537 -279.9132)
			(xy 185.478972 -279.952544) (xy 185.443479 -279.986636) (xy 185.402976 -280.014592) (xy 185.358514 -280.03569)
			(xy 185.311243 -280.049382) (xy 185.262388 -280.055314) (xy 185.213213 -280.053333) (xy 185.164994 -280.043489)
			(xy 185.118978 -280.026037) (xy 185.076357 -280.00143) (xy 185.038236 -279.970305) (xy 185.005601 -279.933468)
			(xy 184.979298 -279.891872) (xy 184.960007 -279.846596) (xy 184.94823 -279.798812) (xy 184.94427 -279.749758)
			(xy 184.627007 -279.749758) (xy 184.626508 -279.775212) (xy 184.618465 -279.825994) (xy 184.602577 -279.874893)
			(xy 184.579234 -279.920705) (xy 184.549013 -279.962301) (xy 184.512657 -279.998657) (xy 184.471061 -280.028878)
			(xy 184.425249 -280.052221) (xy 184.37635 -280.068109) (xy 184.325568 -280.076152) (xy 184.274152 -280.076152)
			(xy 184.22337 -280.068109) (xy 184.174471 -280.052221) (xy 184.128659 -280.028878) (xy 184.087063 -279.998657)
			(xy 184.050707 -279.962301) (xy 184.020486 -279.920705) (xy 183.997143 -279.874893) (xy 183.981255 -279.825994)
			(xy 183.973212 -279.775212) (xy 183.654575 -279.775212) (xy 183.646818 -279.822942) (xy 183.631234 -279.869623)
			(xy 183.608363 -279.9132) (xy 183.578798 -279.952544) (xy 183.543305 -279.986636) (xy 183.502802 -280.014592)
			(xy 183.45834 -280.03569) (xy 183.411069 -280.049382) (xy 183.362214 -280.055314) (xy 183.313039 -280.053333)
			(xy 183.26482 -280.043489) (xy 183.218804 -280.026037) (xy 183.176183 -280.00143) (xy 183.138062 -279.970305)
			(xy 183.105427 -279.933468) (xy 183.079124 -279.891872) (xy 183.059833 -279.846596) (xy 183.048056 -279.798812)
			(xy 183.044096 -279.749758) (xy 182.727087 -279.749758) (xy 182.726588 -279.775212) (xy 182.718545 -279.825994)
			(xy 182.702657 -279.874893) (xy 182.679314 -279.920705) (xy 182.649093 -279.962301) (xy 182.612737 -279.998657)
			(xy 182.571141 -280.028878) (xy 182.525329 -280.052221) (xy 182.47643 -280.068109) (xy 182.425648 -280.076152)
			(xy 182.374232 -280.076152) (xy 182.32345 -280.068109) (xy 182.274551 -280.052221) (xy 182.228739 -280.028878)
			(xy 182.187143 -279.998657) (xy 182.150787 -279.962301) (xy 182.120566 -279.920705) (xy 182.097223 -279.874893)
			(xy 182.081335 -279.825994) (xy 182.073292 -279.775212) (xy 181.754655 -279.775212) (xy 181.746898 -279.822942)
			(xy 181.731314 -279.869623) (xy 181.708443 -279.9132) (xy 181.678878 -279.952544) (xy 181.643385 -279.986636)
			(xy 181.602882 -280.014592) (xy 181.55842 -280.03569) (xy 181.511149 -280.049382) (xy 181.462294 -280.055314)
			(xy 181.413119 -280.053333) (xy 181.3649 -280.043489) (xy 181.318884 -280.026037) (xy 181.276263 -280.00143)
			(xy 181.238142 -279.970305) (xy 181.205507 -279.933468) (xy 181.179204 -279.891872) (xy 181.159913 -279.846596)
			(xy 181.148136 -279.798812) (xy 181.144176 -279.749758) (xy 180.827167 -279.749758) (xy 180.826668 -279.775212)
			(xy 180.818625 -279.825994) (xy 180.802737 -279.874893) (xy 180.779394 -279.920705) (xy 180.749173 -279.962301)
			(xy 180.712817 -279.998657) (xy 180.671221 -280.028878) (xy 180.625409 -280.052221) (xy 180.57651 -280.068109)
			(xy 180.525728 -280.076152) (xy 180.474312 -280.076152) (xy 180.42353 -280.068109) (xy 180.374631 -280.052221)
			(xy 180.328819 -280.028878) (xy 180.287223 -279.998657) (xy 180.250867 -279.962301) (xy 180.220646 -279.920705)
			(xy 180.197303 -279.874893) (xy 180.181415 -279.825994) (xy 180.173372 -279.775212) (xy 179.854735 -279.775212)
			(xy 179.846978 -279.822942) (xy 179.831394 -279.869623) (xy 179.808523 -279.9132) (xy 179.778958 -279.952544)
			(xy 179.743465 -279.986636) (xy 179.702962 -280.014592) (xy 179.6585 -280.03569) (xy 179.611229 -280.049382)
			(xy 179.562374 -280.055314) (xy 179.513199 -280.053333) (xy 179.46498 -280.043489) (xy 179.418964 -280.026037)
			(xy 179.376343 -280.00143) (xy 179.338222 -279.970305) (xy 179.305587 -279.933468) (xy 179.279284 -279.891872)
			(xy 179.259993 -279.846596) (xy 179.248216 -279.798812) (xy 179.244256 -279.749758) (xy 178.926993 -279.749758)
			(xy 178.926494 -279.775212) (xy 178.918451 -279.825994) (xy 178.902563 -279.874893) (xy 178.87922 -279.920705)
			(xy 178.848999 -279.962301) (xy 178.812643 -279.998657) (xy 178.771047 -280.028878) (xy 178.725235 -280.052221)
			(xy 178.676336 -280.068109) (xy 178.625554 -280.076152) (xy 178.574138 -280.076152) (xy 178.523356 -280.068109)
			(xy 178.474457 -280.052221) (xy 178.428645 -280.028878) (xy 178.387049 -279.998657) (xy 178.350693 -279.962301)
			(xy 178.320472 -279.920705) (xy 178.297129 -279.874893) (xy 178.281241 -279.825994) (xy 178.273198 -279.775212)
			(xy 177.954561 -279.775212) (xy 177.946804 -279.822942) (xy 177.93122 -279.869623) (xy 177.908349 -279.9132)
			(xy 177.878784 -279.952544) (xy 177.843291 -279.986636) (xy 177.802788 -280.014592) (xy 177.758326 -280.03569)
			(xy 177.711055 -280.049382) (xy 177.6622 -280.055314) (xy 177.613025 -280.053333) (xy 177.564806 -280.043489)
			(xy 177.51879 -280.026037) (xy 177.476169 -280.00143) (xy 177.438048 -279.970305) (xy 177.405413 -279.933468)
			(xy 177.37911 -279.891872) (xy 177.359819 -279.846596) (xy 177.348042 -279.798812) (xy 177.344082 -279.749758)
			(xy 177.027073 -279.749758) (xy 177.026574 -279.775212) (xy 177.018531 -279.825994) (xy 177.002643 -279.874893)
			(xy 176.9793 -279.920705) (xy 176.949079 -279.962301) (xy 176.912723 -279.998657) (xy 176.871127 -280.028878)
			(xy 176.825315 -280.052221) (xy 176.776416 -280.068109) (xy 176.725634 -280.076152) (xy 176.674218 -280.076152)
			(xy 176.623436 -280.068109) (xy 176.574537 -280.052221) (xy 176.528725 -280.028878) (xy 176.487129 -279.998657)
			(xy 176.450773 -279.962301) (xy 176.420552 -279.920705) (xy 176.397209 -279.874893) (xy 176.381321 -279.825994)
			(xy 176.373278 -279.775212) (xy 176.054749 -279.775212) (xy 176.054732 -279.776012) (xy 176.045758 -279.827747)
			(xy 176.028067 -279.877185) (xy 176.002182 -279.922869) (xy 175.968863 -279.963452) (xy 175.929095 -279.997738)
			(xy 175.884048 -280.024717) (xy 175.835051 -280.043594) (xy 175.809402 -280.049224) (xy 175.798709 -280.051888)
			(xy 175.780888 -280.064809) (xy 175.770125 -280.084011) (xy 175.768762 -280.094944) (xy 175.768204 -280.10104)
			(xy 224.384106 -280.10104) (xy 224.388177 -280.045418) (xy 224.400303 -279.990981) (xy 224.420226 -279.93889)
			(xy 224.447522 -279.890255) (xy 224.481608 -279.846112) (xy 224.521757 -279.807403) (xy 224.567115 -279.774952)
			(xy 224.616715 -279.749451) (xy 224.669499 -279.731444) (xy 224.724342 -279.721314) (xy 224.780076 -279.719277)
			(xy 224.835513 -279.725377) (xy 224.88947 -279.739483) (xy 224.940799 -279.761295) (xy 224.988405 -279.790349)
			(xy 225.031273 -279.826024) (xy 225.06849 -279.867561) (xy 225.099263 -279.914074) (xy 225.122935 -279.964571)
			(xy 225.139003 -280.017978) (xy 225.147123 -280.073154) (xy 225.147632 -280.10104) (xy 226.403406 -280.10104)
			(xy 226.407477 -280.045418) (xy 226.419603 -279.990981) (xy 226.439526 -279.93889) (xy 226.466822 -279.890255)
			(xy 226.500908 -279.846112) (xy 226.541057 -279.807403) (xy 226.586415 -279.774952) (xy 226.636015 -279.749451)
			(xy 226.688799 -279.731444) (xy 226.743642 -279.721314) (xy 226.799376 -279.719277) (xy 226.854813 -279.725377)
			(xy 226.90877 -279.739483) (xy 226.960099 -279.761295) (xy 227.007705 -279.790349) (xy 227.050573 -279.826024)
			(xy 227.08779 -279.867561) (xy 227.118563 -279.914074) (xy 227.142235 -279.964571) (xy 227.158303 -280.017978)
			(xy 227.166423 -280.073154) (xy 227.166932 -280.10104) (xy 227.166423 -280.128926) (xy 227.158303 -280.184102)
			(xy 227.142235 -280.237509) (xy 227.118563 -280.288006) (xy 227.08779 -280.334519) (xy 227.050573 -280.376056)
			(xy 227.007705 -280.411731) (xy 226.960099 -280.440785) (xy 226.90877 -280.462597) (xy 226.854813 -280.476703)
			(xy 226.799376 -280.482803) (xy 226.743642 -280.480766) (xy 226.688799 -280.470636) (xy 226.636015 -280.452629)
			(xy 226.586415 -280.427128) (xy 226.541057 -280.394677) (xy 226.500908 -280.355968) (xy 226.466822 -280.311825)
			(xy 226.439526 -280.26319) (xy 226.419603 -280.211099) (xy 226.407477 -280.156662) (xy 226.403406 -280.10104)
			(xy 225.147632 -280.10104) (xy 225.147123 -280.128926) (xy 225.139003 -280.184102) (xy 225.122935 -280.237509)
			(xy 225.099263 -280.288006) (xy 225.06849 -280.334519) (xy 225.031273 -280.376056) (xy 224.988405 -280.411731)
			(xy 224.940799 -280.440785) (xy 224.88947 -280.462597) (xy 224.835513 -280.476703) (xy 224.780076 -280.482803)
			(xy 224.724342 -280.480766) (xy 224.669499 -280.470636) (xy 224.616715 -280.452629) (xy 224.567115 -280.427128)
			(xy 224.521757 -280.394677) (xy 224.481608 -280.355968) (xy 224.447522 -280.311825) (xy 224.420226 -280.26319)
			(xy 224.400303 -280.211099) (xy 224.388177 -280.156662) (xy 224.384106 -280.10104) (xy 175.768204 -280.10104)
			(xy 175.766038 -280.124683) (xy 175.757396 -280.18378) (xy 175.75149 -280.213054) (xy 175.750982 -280.215086)
			(xy 175.750728 -280.216356) (xy 175.750124 -280.220525) (xy 175.75013 -280.228949) (xy 175.750728 -280.23312)
			(xy 175.750982 -280.23439) (xy 175.75149 -280.236422) (xy 175.757393 -280.265696) (xy 175.766035 -280.324793)
			(xy 175.768762 -280.354532) (xy 175.770188 -280.365443) (xy 175.780956 -280.384607) (xy 175.798738 -280.39753)
			(xy 175.809402 -280.400252) (xy 175.835048 -280.405896) (xy 175.884045 -280.424771) (xy 175.929092 -280.451748)
			(xy 175.968861 -280.486032) (xy 176.00218 -280.526613) (xy 176.028068 -280.572294) (xy 176.045761 -280.621731)
			(xy 176.054739 -280.673464) (xy 176.055274 -280.699718) (xy 176.054825 -280.723328) (xy 176.054497 -280.725426)
			(xy 176.373278 -280.725426) (xy 176.373278 -280.67401) (xy 176.381321 -280.623228) (xy 176.397209 -280.574329)
			(xy 176.420552 -280.528517) (xy 176.450773 -280.486921) (xy 176.487129 -280.450565) (xy 176.528725 -280.420344)
			(xy 176.574537 -280.397001) (xy 176.623436 -280.381113) (xy 176.674218 -280.37307) (xy 176.725634 -280.37307)
			(xy 176.776416 -280.381113) (xy 176.825315 -280.397001) (xy 176.871127 -280.420344) (xy 176.912723 -280.450565)
			(xy 176.949079 -280.486921) (xy 176.9793 -280.528517) (xy 177.002643 -280.574329) (xy 177.018531 -280.623228)
			(xy 177.026574 -280.67401) (xy 177.027078 -280.699718) (xy 177.344082 -280.699718) (xy 177.348042 -280.650664)
			(xy 177.359819 -280.60288) (xy 177.37911 -280.557604) (xy 177.405413 -280.516008) (xy 177.438048 -280.479171)
			(xy 177.476169 -280.448046) (xy 177.51879 -280.423439) (xy 177.564806 -280.405987) (xy 177.613025 -280.396143)
			(xy 177.6622 -280.394162) (xy 177.711055 -280.400094) (xy 177.758326 -280.413786) (xy 177.802788 -280.434884)
			(xy 177.843291 -280.46284) (xy 177.878784 -280.496932) (xy 177.908349 -280.536276) (xy 177.93122 -280.579853)
			(xy 177.946804 -280.626534) (xy 177.954699 -280.675111) (xy 177.955194 -280.699718) (xy 177.954699 -280.724325)
			(xy 177.95452 -280.725426) (xy 178.273198 -280.725426) (xy 178.273198 -280.67401) (xy 178.281241 -280.623228)
			(xy 178.297129 -280.574329) (xy 178.320472 -280.528517) (xy 178.350693 -280.486921) (xy 178.387049 -280.450565)
			(xy 178.428645 -280.420344) (xy 178.474457 -280.397001) (xy 178.523356 -280.381113) (xy 178.574138 -280.37307)
			(xy 178.625554 -280.37307) (xy 178.676336 -280.381113) (xy 178.725235 -280.397001) (xy 178.771047 -280.420344)
			(xy 178.812643 -280.450565) (xy 178.848999 -280.486921) (xy 178.87922 -280.528517) (xy 178.902563 -280.574329)
			(xy 178.918451 -280.623228) (xy 178.926494 -280.67401) (xy 178.926998 -280.699718) (xy 179.244256 -280.699718)
			(xy 179.248216 -280.650664) (xy 179.259993 -280.60288) (xy 179.279284 -280.557604) (xy 179.305587 -280.516008)
			(xy 179.338222 -280.479171) (xy 179.376343 -280.448046) (xy 179.418964 -280.423439) (xy 179.46498 -280.405987)
			(xy 179.513199 -280.396143) (xy 179.562374 -280.394162) (xy 179.611229 -280.400094) (xy 179.6585 -280.413786)
			(xy 179.702962 -280.434884) (xy 179.743465 -280.46284) (xy 179.778958 -280.496932) (xy 179.808523 -280.536276)
			(xy 179.831394 -280.579853) (xy 179.846978 -280.626534) (xy 179.854873 -280.675111) (xy 179.855368 -280.699718)
			(xy 179.854873 -280.724325) (xy 179.854694 -280.725426) (xy 180.173372 -280.725426) (xy 180.173372 -280.67401)
			(xy 180.181415 -280.623228) (xy 180.197303 -280.574329) (xy 180.220646 -280.528517) (xy 180.250867 -280.486921)
			(xy 180.287223 -280.450565) (xy 180.328819 -280.420344) (xy 180.374631 -280.397001) (xy 180.42353 -280.381113)
			(xy 180.474312 -280.37307) (xy 180.525728 -280.37307) (xy 180.57651 -280.381113) (xy 180.625409 -280.397001)
			(xy 180.671221 -280.420344) (xy 180.712817 -280.450565) (xy 180.749173 -280.486921) (xy 180.779394 -280.528517)
			(xy 180.802737 -280.574329) (xy 180.818625 -280.623228) (xy 180.826668 -280.67401) (xy 180.827172 -280.699718)
			(xy 181.144176 -280.699718) (xy 181.148136 -280.650664) (xy 181.159913 -280.60288) (xy 181.179204 -280.557604)
			(xy 181.205507 -280.516008) (xy 181.238142 -280.479171) (xy 181.276263 -280.448046) (xy 181.318884 -280.423439)
			(xy 181.3649 -280.405987) (xy 181.413119 -280.396143) (xy 181.462294 -280.394162) (xy 181.511149 -280.400094)
			(xy 181.55842 -280.413786) (xy 181.602882 -280.434884) (xy 181.643385 -280.46284) (xy 181.678878 -280.496932)
			(xy 181.708443 -280.536276) (xy 181.731314 -280.579853) (xy 181.746898 -280.626534) (xy 181.754793 -280.675111)
			(xy 181.755288 -280.699718) (xy 181.754793 -280.724325) (xy 181.754614 -280.725426) (xy 182.073292 -280.725426)
			(xy 182.073292 -280.67401) (xy 182.081335 -280.623228) (xy 182.097223 -280.574329) (xy 182.120566 -280.528517)
			(xy 182.150787 -280.486921) (xy 182.187143 -280.450565) (xy 182.228739 -280.420344) (xy 182.274551 -280.397001)
			(xy 182.32345 -280.381113) (xy 182.374232 -280.37307) (xy 182.425648 -280.37307) (xy 182.47643 -280.381113)
			(xy 182.525329 -280.397001) (xy 182.571141 -280.420344) (xy 182.612737 -280.450565) (xy 182.649093 -280.486921)
			(xy 182.679314 -280.528517) (xy 182.702657 -280.574329) (xy 182.718545 -280.623228) (xy 182.726588 -280.67401)
			(xy 182.727092 -280.699718) (xy 183.044096 -280.699718) (xy 183.048056 -280.650664) (xy 183.059833 -280.60288)
			(xy 183.079124 -280.557604) (xy 183.105427 -280.516008) (xy 183.138062 -280.479171) (xy 183.176183 -280.448046)
			(xy 183.218804 -280.423439) (xy 183.26482 -280.405987) (xy 183.313039 -280.396143) (xy 183.362214 -280.394162)
			(xy 183.411069 -280.400094) (xy 183.45834 -280.413786) (xy 183.502802 -280.434884) (xy 183.543305 -280.46284)
			(xy 183.578798 -280.496932) (xy 183.608363 -280.536276) (xy 183.631234 -280.579853) (xy 183.646818 -280.626534)
			(xy 183.654713 -280.675111) (xy 183.655208 -280.699718) (xy 183.654713 -280.724325) (xy 183.654534 -280.725426)
			(xy 183.973212 -280.725426) (xy 183.973212 -280.67401) (xy 183.981255 -280.623228) (xy 183.997143 -280.574329)
			(xy 184.020486 -280.528517) (xy 184.050707 -280.486921) (xy 184.087063 -280.450565) (xy 184.128659 -280.420344)
			(xy 184.174471 -280.397001) (xy 184.22337 -280.381113) (xy 184.274152 -280.37307) (xy 184.325568 -280.37307)
			(xy 184.37635 -280.381113) (xy 184.425249 -280.397001) (xy 184.471061 -280.420344) (xy 184.512657 -280.450565)
			(xy 184.549013 -280.486921) (xy 184.579234 -280.528517) (xy 184.602577 -280.574329) (xy 184.618465 -280.623228)
			(xy 184.626508 -280.67401) (xy 184.627012 -280.699718) (xy 184.94427 -280.699718) (xy 184.94823 -280.650664)
			(xy 184.960007 -280.60288) (xy 184.979298 -280.557604) (xy 185.005601 -280.516008) (xy 185.038236 -280.479171)
			(xy 185.076357 -280.448046) (xy 185.118978 -280.423439) (xy 185.164994 -280.405987) (xy 185.213213 -280.396143)
			(xy 185.262388 -280.394162) (xy 185.311243 -280.400094) (xy 185.358514 -280.413786) (xy 185.402976 -280.434884)
			(xy 185.443479 -280.46284) (xy 185.478972 -280.496932) (xy 185.508537 -280.536276) (xy 185.531408 -280.579853)
			(xy 185.546992 -280.626534) (xy 185.554887 -280.675111) (xy 185.555382 -280.699718) (xy 185.554887 -280.724325)
			(xy 185.554708 -280.725426) (xy 185.873386 -280.725426) (xy 185.873386 -280.67401) (xy 185.881429 -280.623228)
			(xy 185.897317 -280.574329) (xy 185.92066 -280.528517) (xy 185.950881 -280.486921) (xy 185.987237 -280.450565)
			(xy 186.028833 -280.420344) (xy 186.074645 -280.397001) (xy 186.123544 -280.381113) (xy 186.174326 -280.37307)
			(xy 186.225742 -280.37307) (xy 186.276524 -280.381113) (xy 186.325423 -280.397001) (xy 186.371235 -280.420344)
			(xy 186.412831 -280.450565) (xy 186.449187 -280.486921) (xy 186.479408 -280.528517) (xy 186.502751 -280.574329)
			(xy 186.518639 -280.623228) (xy 186.526682 -280.67401) (xy 186.527186 -280.699718) (xy 186.84419 -280.699718)
			(xy 186.84815 -280.650664) (xy 186.859927 -280.60288) (xy 186.879218 -280.557604) (xy 186.905521 -280.516008)
			(xy 186.938156 -280.479171) (xy 186.976277 -280.448046) (xy 187.018898 -280.423439) (xy 187.064914 -280.405987)
			(xy 187.113133 -280.396143) (xy 187.162308 -280.394162) (xy 187.211163 -280.400094) (xy 187.258434 -280.413786)
			(xy 187.302896 -280.434884) (xy 187.343399 -280.46284) (xy 187.378892 -280.496932) (xy 187.408457 -280.536276)
			(xy 187.431328 -280.579853) (xy 187.446912 -280.626534) (xy 187.454807 -280.675111) (xy 187.455302 -280.699718)
			(xy 187.454807 -280.724325) (xy 187.454628 -280.725426) (xy 187.773306 -280.725426) (xy 187.773306 -280.67401)
			(xy 187.781349 -280.623228) (xy 187.797237 -280.574329) (xy 187.82058 -280.528517) (xy 187.850801 -280.486921)
			(xy 187.887157 -280.450565) (xy 187.928753 -280.420344) (xy 187.974565 -280.397001) (xy 188.023464 -280.381113)
			(xy 188.074246 -280.37307) (xy 188.125662 -280.37307) (xy 188.176444 -280.381113) (xy 188.225343 -280.397001)
			(xy 188.271155 -280.420344) (xy 188.312751 -280.450565) (xy 188.349107 -280.486921) (xy 188.379328 -280.528517)
			(xy 188.402671 -280.574329) (xy 188.418559 -280.623228) (xy 188.426602 -280.67401) (xy 188.427106 -280.699718)
			(xy 188.74411 -280.699718) (xy 188.74807 -280.650664) (xy 188.759847 -280.60288) (xy 188.779138 -280.557604)
			(xy 188.805441 -280.516008) (xy 188.838076 -280.479171) (xy 188.876197 -280.448046) (xy 188.918818 -280.423439)
			(xy 188.964834 -280.405987) (xy 189.013053 -280.396143) (xy 189.062228 -280.394162) (xy 189.111083 -280.400094)
			(xy 189.158354 -280.413786) (xy 189.202816 -280.434884) (xy 189.243319 -280.46284) (xy 189.278812 -280.496932)
			(xy 189.308377 -280.536276) (xy 189.331248 -280.579853) (xy 189.346832 -280.626534) (xy 189.354727 -280.675111)
			(xy 189.355222 -280.699718) (xy 189.354727 -280.724325) (xy 189.354548 -280.725426) (xy 189.673226 -280.725426)
			(xy 189.673226 -280.67401) (xy 189.681269 -280.623228) (xy 189.697157 -280.574329) (xy 189.7205 -280.528517)
			(xy 189.750721 -280.486921) (xy 189.787077 -280.450565) (xy 189.828673 -280.420344) (xy 189.874485 -280.397001)
			(xy 189.923384 -280.381113) (xy 189.974166 -280.37307) (xy 190.025582 -280.37307) (xy 190.076364 -280.381113)
			(xy 190.125263 -280.397001) (xy 190.171075 -280.420344) (xy 190.212671 -280.450565) (xy 190.249027 -280.486921)
			(xy 190.279248 -280.528517) (xy 190.302591 -280.574329) (xy 190.318479 -280.623228) (xy 190.326522 -280.67401)
			(xy 190.327026 -280.699718) (xy 190.644284 -280.699718) (xy 190.648244 -280.650664) (xy 190.660021 -280.60288)
			(xy 190.679312 -280.557604) (xy 190.705615 -280.516008) (xy 190.73825 -280.479171) (xy 190.776371 -280.448046)
			(xy 190.818992 -280.423439) (xy 190.865008 -280.405987) (xy 190.913227 -280.396143) (xy 190.962402 -280.394162)
			(xy 191.011257 -280.400094) (xy 191.058528 -280.413786) (xy 191.10299 -280.434884) (xy 191.143493 -280.46284)
			(xy 191.178986 -280.496932) (xy 191.208551 -280.536276) (xy 191.231422 -280.579853) (xy 191.247006 -280.626534)
			(xy 191.254901 -280.675111) (xy 191.255396 -280.699718) (xy 191.254901 -280.724325) (xy 191.254722 -280.725426)
			(xy 191.5734 -280.725426) (xy 191.5734 -280.67401) (xy 191.581443 -280.623228) (xy 191.597331 -280.574329)
			(xy 191.620674 -280.528517) (xy 191.650895 -280.486921) (xy 191.687251 -280.450565) (xy 191.728847 -280.420344)
			(xy 191.774659 -280.397001) (xy 191.823558 -280.381113) (xy 191.87434 -280.37307) (xy 191.925756 -280.37307)
			(xy 191.976538 -280.381113) (xy 192.025437 -280.397001) (xy 192.071249 -280.420344) (xy 192.112845 -280.450565)
			(xy 192.149201 -280.486921) (xy 192.179422 -280.528517) (xy 192.202765 -280.574329) (xy 192.218653 -280.623228)
			(xy 192.226696 -280.67401) (xy 192.2272 -280.699718) (xy 192.544204 -280.699718) (xy 192.548164 -280.650664)
			(xy 192.559941 -280.60288) (xy 192.579232 -280.557604) (xy 192.605535 -280.516008) (xy 192.63817 -280.479171)
			(xy 192.676291 -280.448046) (xy 192.718912 -280.423439) (xy 192.764928 -280.405987) (xy 192.813147 -280.396143)
			(xy 192.862322 -280.394162) (xy 192.911177 -280.400094) (xy 192.958448 -280.413786) (xy 193.00291 -280.434884)
			(xy 193.043413 -280.46284) (xy 193.078906 -280.496932) (xy 193.108471 -280.536276) (xy 193.131342 -280.579853)
			(xy 193.146926 -280.626534) (xy 193.154821 -280.675111) (xy 193.155316 -280.699718) (xy 193.154821 -280.724325)
			(xy 193.154642 -280.725426) (xy 193.47332 -280.725426) (xy 193.47332 -280.67401) (xy 193.481363 -280.623228)
			(xy 193.497251 -280.574329) (xy 193.520594 -280.528517) (xy 193.550815 -280.486921) (xy 193.587171 -280.450565)
			(xy 193.628767 -280.420344) (xy 193.674579 -280.397001) (xy 193.723478 -280.381113) (xy 193.77426 -280.37307)
			(xy 193.825676 -280.37307) (xy 193.876458 -280.381113) (xy 193.925357 -280.397001) (xy 193.971169 -280.420344)
			(xy 194.012765 -280.450565) (xy 194.049121 -280.486921) (xy 194.079342 -280.528517) (xy 194.102685 -280.574329)
			(xy 194.118573 -280.623228) (xy 194.126616 -280.67401) (xy 194.12712 -280.699718) (xy 194.444124 -280.699718)
			(xy 194.448084 -280.650664) (xy 194.459861 -280.60288) (xy 194.479152 -280.557604) (xy 194.505455 -280.516008)
			(xy 194.53809 -280.479171) (xy 194.576211 -280.448046) (xy 194.618832 -280.423439) (xy 194.664848 -280.405987)
			(xy 194.713067 -280.396143) (xy 194.762242 -280.394162) (xy 194.811097 -280.400094) (xy 194.858368 -280.413786)
			(xy 194.90283 -280.434884) (xy 194.943333 -280.46284) (xy 194.978826 -280.496932) (xy 195.008391 -280.536276)
			(xy 195.031262 -280.579853) (xy 195.046846 -280.626534) (xy 195.054741 -280.675111) (xy 195.055236 -280.699718)
			(xy 195.054741 -280.724325) (xy 195.054562 -280.725426) (xy 195.37324 -280.725426) (xy 195.37324 -280.67401)
			(xy 195.381283 -280.623228) (xy 195.397171 -280.574329) (xy 195.420514 -280.528517) (xy 195.450735 -280.486921)
			(xy 195.487091 -280.450565) (xy 195.528687 -280.420344) (xy 195.574499 -280.397001) (xy 195.623398 -280.381113)
			(xy 195.67418 -280.37307) (xy 195.725596 -280.37307) (xy 195.776378 -280.381113) (xy 195.825277 -280.397001)
			(xy 195.871089 -280.420344) (xy 195.912685 -280.450565) (xy 195.949041 -280.486921) (xy 195.979262 -280.528517)
			(xy 196.002605 -280.574329) (xy 196.018493 -280.623228) (xy 196.026536 -280.67401) (xy 196.02704 -280.699718)
			(xy 196.344298 -280.699718) (xy 196.348258 -280.650664) (xy 196.360035 -280.60288) (xy 196.379326 -280.557604)
			(xy 196.405629 -280.516008) (xy 196.438264 -280.479171) (xy 196.476385 -280.448046) (xy 196.519006 -280.423439)
			(xy 196.565022 -280.405987) (xy 196.613241 -280.396143) (xy 196.662416 -280.394162) (xy 196.711271 -280.400094)
			(xy 196.758542 -280.413786) (xy 196.803004 -280.434884) (xy 196.843507 -280.46284) (xy 196.879 -280.496932)
			(xy 196.908565 -280.536276) (xy 196.931436 -280.579853) (xy 196.94702 -280.626534) (xy 196.954915 -280.675111)
			(xy 196.95541 -280.699718) (xy 197.294258 -280.699718) (xy 197.298218 -280.650664) (xy 197.309995 -280.60288)
			(xy 197.329286 -280.557604) (xy 197.355589 -280.516008) (xy 197.388224 -280.479171) (xy 197.426345 -280.448046)
			(xy 197.468966 -280.423439) (xy 197.514982 -280.405987) (xy 197.563201 -280.396143) (xy 197.612376 -280.394162)
			(xy 197.661231 -280.400094) (xy 197.708502 -280.413786) (xy 197.752964 -280.434884) (xy 197.793467 -280.46284)
			(xy 197.82896 -280.496932) (xy 197.858525 -280.536276) (xy 197.881396 -280.579853) (xy 197.89698 -280.626534)
			(xy 197.904875 -280.675111) (xy 197.90537 -280.699718) (xy 198.244218 -280.699718) (xy 198.248178 -280.650664)
			(xy 198.259955 -280.60288) (xy 198.279246 -280.557604) (xy 198.305549 -280.516008) (xy 198.338184 -280.479171)
			(xy 198.376305 -280.448046) (xy 198.418926 -280.423439) (xy 198.464942 -280.405987) (xy 198.513161 -280.396143)
			(xy 198.562336 -280.394162) (xy 198.611191 -280.400094) (xy 198.658462 -280.413786) (xy 198.702924 -280.434884)
			(xy 198.743427 -280.46284) (xy 198.77892 -280.496932) (xy 198.781663 -280.500582) (xy 228.815644 -280.500582)
			(xy 228.819715 -280.44496) (xy 228.831841 -280.390523) (xy 228.851764 -280.338432) (xy 228.87906 -280.289797)
			(xy 228.913146 -280.245654) (xy 228.953295 -280.206945) (xy 228.998653 -280.174494) (xy 229.048253 -280.148993)
			(xy 229.101037 -280.130986) (xy 229.15588 -280.120856) (xy 229.211614 -280.118819) (xy 229.267051 -280.124919)
			(xy 229.321008 -280.139025) (xy 229.372337 -280.160837) (xy 229.419943 -280.189891) (xy 229.462811 -280.225566)
			(xy 229.500028 -280.267103) (xy 229.530801 -280.313616) (xy 229.554473 -280.364113) (xy 229.570541 -280.41752)
			(xy 229.578661 -280.472696) (xy 229.57917 -280.500582) (xy 229.578661 -280.528468) (xy 229.570541 -280.583644)
			(xy 229.554473 -280.637051) (xy 229.530801 -280.687548) (xy 229.500028 -280.734061) (xy 229.462811 -280.775598)
			(xy 229.419943 -280.811273) (xy 229.372337 -280.840327) (xy 229.321008 -280.862139) (xy 229.267051 -280.876245)
			(xy 229.211614 -280.882345) (xy 229.15588 -280.880308) (xy 229.101037 -280.870178) (xy 229.048253 -280.852171)
			(xy 228.998653 -280.82667) (xy 228.953295 -280.794219) (xy 228.913146 -280.75551) (xy 228.87906 -280.711367)
			(xy 228.851764 -280.662732) (xy 228.831841 -280.610641) (xy 228.819715 -280.556204) (xy 228.815644 -280.500582)
			(xy 198.781663 -280.500582) (xy 198.808485 -280.536276) (xy 198.831356 -280.579853) (xy 198.84694 -280.626534)
			(xy 198.854835 -280.675111) (xy 198.85533 -280.699718) (xy 198.854835 -280.724325) (xy 198.84694 -280.772902)
			(xy 198.831356 -280.819583) (xy 198.808485 -280.86316) (xy 198.77892 -280.902504) (xy 198.743427 -280.936596)
			(xy 198.702924 -280.964552) (xy 198.658462 -280.98565) (xy 198.611191 -280.999342) (xy 198.562336 -281.005274)
			(xy 198.513161 -281.003293) (xy 198.464942 -280.993449) (xy 198.418926 -280.975997) (xy 198.376305 -280.95139)
			(xy 198.338184 -280.920265) (xy 198.305549 -280.883428) (xy 198.279246 -280.841832) (xy 198.259955 -280.796556)
			(xy 198.248178 -280.748772) (xy 198.244218 -280.699718) (xy 197.90537 -280.699718) (xy 197.904875 -280.724325)
			(xy 197.89698 -280.772902) (xy 197.881396 -280.819583) (xy 197.858525 -280.86316) (xy 197.82896 -280.902504)
			(xy 197.793467 -280.936596) (xy 197.752964 -280.964552) (xy 197.708502 -280.98565) (xy 197.661231 -280.999342)
			(xy 197.612376 -281.005274) (xy 197.563201 -281.003293) (xy 197.514982 -280.993449) (xy 197.468966 -280.975997)
			(xy 197.426345 -280.95139) (xy 197.388224 -280.920265) (xy 197.355589 -280.883428) (xy 197.329286 -280.841832)
			(xy 197.309995 -280.796556) (xy 197.298218 -280.748772) (xy 197.294258 -280.699718) (xy 196.95541 -280.699718)
			(xy 196.954915 -280.724325) (xy 196.94702 -280.772902) (xy 196.931436 -280.819583) (xy 196.908565 -280.86316)
			(xy 196.879 -280.902504) (xy 196.843507 -280.936596) (xy 196.803004 -280.964552) (xy 196.758542 -280.98565)
			(xy 196.711271 -280.999342) (xy 196.662416 -281.005274) (xy 196.613241 -281.003293) (xy 196.565022 -280.993449)
			(xy 196.519006 -280.975997) (xy 196.476385 -280.95139) (xy 196.438264 -280.920265) (xy 196.405629 -280.883428)
			(xy 196.379326 -280.841832) (xy 196.360035 -280.796556) (xy 196.348258 -280.748772) (xy 196.344298 -280.699718)
			(xy 196.02704 -280.699718) (xy 196.026536 -280.725426) (xy 196.018493 -280.776208) (xy 196.002605 -280.825107)
			(xy 195.979262 -280.870919) (xy 195.949041 -280.912515) (xy 195.912685 -280.948871) (xy 195.871089 -280.979092)
			(xy 195.825277 -281.002435) (xy 195.776378 -281.018323) (xy 195.725596 -281.026366) (xy 195.67418 -281.026366)
			(xy 195.623398 -281.018323) (xy 195.574499 -281.002435) (xy 195.528687 -280.979092) (xy 195.487091 -280.948871)
			(xy 195.450735 -280.912515) (xy 195.420514 -280.870919) (xy 195.397171 -280.825107) (xy 195.381283 -280.776208)
			(xy 195.37324 -280.725426) (xy 195.054562 -280.725426) (xy 195.046846 -280.772902) (xy 195.031262 -280.819583)
			(xy 195.008391 -280.86316) (xy 194.978826 -280.902504) (xy 194.943333 -280.936596) (xy 194.90283 -280.964552)
			(xy 194.858368 -280.98565) (xy 194.811097 -280.999342) (xy 194.762242 -281.005274) (xy 194.713067 -281.003293)
			(xy 194.664848 -280.993449) (xy 194.618832 -280.975997) (xy 194.576211 -280.95139) (xy 194.53809 -280.920265)
			(xy 194.505455 -280.883428) (xy 194.479152 -280.841832) (xy 194.459861 -280.796556) (xy 194.448084 -280.748772)
			(xy 194.444124 -280.699718) (xy 194.12712 -280.699718) (xy 194.126616 -280.725426) (xy 194.118573 -280.776208)
			(xy 194.102685 -280.825107) (xy 194.079342 -280.870919) (xy 194.049121 -280.912515) (xy 194.012765 -280.948871)
			(xy 193.971169 -280.979092) (xy 193.925357 -281.002435) (xy 193.876458 -281.018323) (xy 193.825676 -281.026366)
			(xy 193.77426 -281.026366) (xy 193.723478 -281.018323) (xy 193.674579 -281.002435) (xy 193.628767 -280.979092)
			(xy 193.587171 -280.948871) (xy 193.550815 -280.912515) (xy 193.520594 -280.870919) (xy 193.497251 -280.825107)
			(xy 193.481363 -280.776208) (xy 193.47332 -280.725426) (xy 193.154642 -280.725426) (xy 193.146926 -280.772902)
			(xy 193.131342 -280.819583) (xy 193.108471 -280.86316) (xy 193.078906 -280.902504) (xy 193.043413 -280.936596)
			(xy 193.00291 -280.964552) (xy 192.958448 -280.98565) (xy 192.911177 -280.999342) (xy 192.862322 -281.005274)
			(xy 192.813147 -281.003293) (xy 192.764928 -280.993449) (xy 192.718912 -280.975997) (xy 192.676291 -280.95139)
			(xy 192.63817 -280.920265) (xy 192.605535 -280.883428) (xy 192.579232 -280.841832) (xy 192.559941 -280.796556)
			(xy 192.548164 -280.748772) (xy 192.544204 -280.699718) (xy 192.2272 -280.699718) (xy 192.226696 -280.725426)
			(xy 192.218653 -280.776208) (xy 192.202765 -280.825107) (xy 192.179422 -280.870919) (xy 192.149201 -280.912515)
			(xy 192.112845 -280.948871) (xy 192.071249 -280.979092) (xy 192.025437 -281.002435) (xy 191.976538 -281.018323)
			(xy 191.925756 -281.026366) (xy 191.87434 -281.026366) (xy 191.823558 -281.018323) (xy 191.774659 -281.002435)
			(xy 191.728847 -280.979092) (xy 191.687251 -280.948871) (xy 191.650895 -280.912515) (xy 191.620674 -280.870919)
			(xy 191.597331 -280.825107) (xy 191.581443 -280.776208) (xy 191.5734 -280.725426) (xy 191.254722 -280.725426)
			(xy 191.247006 -280.772902) (xy 191.231422 -280.819583) (xy 191.208551 -280.86316) (xy 191.178986 -280.902504)
			(xy 191.143493 -280.936596) (xy 191.10299 -280.964552) (xy 191.058528 -280.98565) (xy 191.011257 -280.999342)
			(xy 190.962402 -281.005274) (xy 190.913227 -281.003293) (xy 190.865008 -280.993449) (xy 190.818992 -280.975997)
			(xy 190.776371 -280.95139) (xy 190.73825 -280.920265) (xy 190.705615 -280.883428) (xy 190.679312 -280.841832)
			(xy 190.660021 -280.796556) (xy 190.648244 -280.748772) (xy 190.644284 -280.699718) (xy 190.327026 -280.699718)
			(xy 190.326522 -280.725426) (xy 190.318479 -280.776208) (xy 190.302591 -280.825107) (xy 190.279248 -280.870919)
			(xy 190.249027 -280.912515) (xy 190.212671 -280.948871) (xy 190.171075 -280.979092) (xy 190.125263 -281.002435)
			(xy 190.076364 -281.018323) (xy 190.025582 -281.026366) (xy 189.974166 -281.026366) (xy 189.923384 -281.018323)
			(xy 189.874485 -281.002435) (xy 189.828673 -280.979092) (xy 189.787077 -280.948871) (xy 189.750721 -280.912515)
			(xy 189.7205 -280.870919) (xy 189.697157 -280.825107) (xy 189.681269 -280.776208) (xy 189.673226 -280.725426)
			(xy 189.354548 -280.725426) (xy 189.346832 -280.772902) (xy 189.331248 -280.819583) (xy 189.308377 -280.86316)
			(xy 189.278812 -280.902504) (xy 189.243319 -280.936596) (xy 189.202816 -280.964552) (xy 189.158354 -280.98565)
			(xy 189.111083 -280.999342) (xy 189.062228 -281.005274) (xy 189.013053 -281.003293) (xy 188.964834 -280.993449)
			(xy 188.918818 -280.975997) (xy 188.876197 -280.95139) (xy 188.838076 -280.920265) (xy 188.805441 -280.883428)
			(xy 188.779138 -280.841832) (xy 188.759847 -280.796556) (xy 188.74807 -280.748772) (xy 188.74411 -280.699718)
			(xy 188.427106 -280.699718) (xy 188.426602 -280.725426) (xy 188.418559 -280.776208) (xy 188.402671 -280.825107)
			(xy 188.379328 -280.870919) (xy 188.349107 -280.912515) (xy 188.312751 -280.948871) (xy 188.271155 -280.979092)
			(xy 188.225343 -281.002435) (xy 188.176444 -281.018323) (xy 188.125662 -281.026366) (xy 188.074246 -281.026366)
			(xy 188.023464 -281.018323) (xy 187.974565 -281.002435) (xy 187.928753 -280.979092) (xy 187.887157 -280.948871)
			(xy 187.850801 -280.912515) (xy 187.82058 -280.870919) (xy 187.797237 -280.825107) (xy 187.781349 -280.776208)
			(xy 187.773306 -280.725426) (xy 187.454628 -280.725426) (xy 187.446912 -280.772902) (xy 187.431328 -280.819583)
			(xy 187.408457 -280.86316) (xy 187.378892 -280.902504) (xy 187.343399 -280.936596) (xy 187.302896 -280.964552)
			(xy 187.258434 -280.98565) (xy 187.211163 -280.999342) (xy 187.162308 -281.005274) (xy 187.113133 -281.003293)
			(xy 187.064914 -280.993449) (xy 187.018898 -280.975997) (xy 186.976277 -280.95139) (xy 186.938156 -280.920265)
			(xy 186.905521 -280.883428) (xy 186.879218 -280.841832) (xy 186.859927 -280.796556) (xy 186.84815 -280.748772)
			(xy 186.84419 -280.699718) (xy 186.527186 -280.699718) (xy 186.526682 -280.725426) (xy 186.518639 -280.776208)
			(xy 186.502751 -280.825107) (xy 186.479408 -280.870919) (xy 186.449187 -280.912515) (xy 186.412831 -280.948871)
			(xy 186.371235 -280.979092) (xy 186.325423 -281.002435) (xy 186.276524 -281.018323) (xy 186.225742 -281.026366)
			(xy 186.174326 -281.026366) (xy 186.123544 -281.018323) (xy 186.074645 -281.002435) (xy 186.028833 -280.979092)
			(xy 185.987237 -280.948871) (xy 185.950881 -280.912515) (xy 185.92066 -280.870919) (xy 185.897317 -280.825107)
			(xy 185.881429 -280.776208) (xy 185.873386 -280.725426) (xy 185.554708 -280.725426) (xy 185.546992 -280.772902)
			(xy 185.531408 -280.819583) (xy 185.508537 -280.86316) (xy 185.478972 -280.902504) (xy 185.443479 -280.936596)
			(xy 185.402976 -280.964552) (xy 185.358514 -280.98565) (xy 185.311243 -280.999342) (xy 185.262388 -281.005274)
			(xy 185.213213 -281.003293) (xy 185.164994 -280.993449) (xy 185.118978 -280.975997) (xy 185.076357 -280.95139)
			(xy 185.038236 -280.920265) (xy 185.005601 -280.883428) (xy 184.979298 -280.841832) (xy 184.960007 -280.796556)
			(xy 184.94823 -280.748772) (xy 184.94427 -280.699718) (xy 184.627012 -280.699718) (xy 184.626508 -280.725426)
			(xy 184.618465 -280.776208) (xy 184.602577 -280.825107) (xy 184.579234 -280.870919) (xy 184.549013 -280.912515)
			(xy 184.512657 -280.948871) (xy 184.471061 -280.979092) (xy 184.425249 -281.002435) (xy 184.37635 -281.018323)
			(xy 184.325568 -281.026366) (xy 184.274152 -281.026366) (xy 184.22337 -281.018323) (xy 184.174471 -281.002435)
			(xy 184.128659 -280.979092) (xy 184.087063 -280.948871) (xy 184.050707 -280.912515) (xy 184.020486 -280.870919)
			(xy 183.997143 -280.825107) (xy 183.981255 -280.776208) (xy 183.973212 -280.725426) (xy 183.654534 -280.725426)
			(xy 183.646818 -280.772902) (xy 183.631234 -280.819583) (xy 183.608363 -280.86316) (xy 183.578798 -280.902504)
			(xy 183.543305 -280.936596) (xy 183.502802 -280.964552) (xy 183.45834 -280.98565) (xy 183.411069 -280.999342)
			(xy 183.362214 -281.005274) (xy 183.313039 -281.003293) (xy 183.26482 -280.993449) (xy 183.218804 -280.975997)
			(xy 183.176183 -280.95139) (xy 183.138062 -280.920265) (xy 183.105427 -280.883428) (xy 183.079124 -280.841832)
			(xy 183.059833 -280.796556) (xy 183.048056 -280.748772) (xy 183.044096 -280.699718) (xy 182.727092 -280.699718)
			(xy 182.726588 -280.725426) (xy 182.718545 -280.776208) (xy 182.702657 -280.825107) (xy 182.679314 -280.870919)
			(xy 182.649093 -280.912515) (xy 182.612737 -280.948871) (xy 182.571141 -280.979092) (xy 182.525329 -281.002435)
			(xy 182.47643 -281.018323) (xy 182.425648 -281.026366) (xy 182.374232 -281.026366) (xy 182.32345 -281.018323)
			(xy 182.274551 -281.002435) (xy 182.228739 -280.979092) (xy 182.187143 -280.948871) (xy 182.150787 -280.912515)
			(xy 182.120566 -280.870919) (xy 182.097223 -280.825107) (xy 182.081335 -280.776208) (xy 182.073292 -280.725426)
			(xy 181.754614 -280.725426) (xy 181.746898 -280.772902) (xy 181.731314 -280.819583) (xy 181.708443 -280.86316)
			(xy 181.678878 -280.902504) (xy 181.643385 -280.936596) (xy 181.602882 -280.964552) (xy 181.55842 -280.98565)
			(xy 181.511149 -280.999342) (xy 181.462294 -281.005274) (xy 181.413119 -281.003293) (xy 181.3649 -280.993449)
			(xy 181.318884 -280.975997) (xy 181.276263 -280.95139) (xy 181.238142 -280.920265) (xy 181.205507 -280.883428)
			(xy 181.179204 -280.841832) (xy 181.159913 -280.796556) (xy 181.148136 -280.748772) (xy 181.144176 -280.699718)
			(xy 180.827172 -280.699718) (xy 180.826668 -280.725426) (xy 180.818625 -280.776208) (xy 180.802737 -280.825107)
			(xy 180.779394 -280.870919) (xy 180.749173 -280.912515) (xy 180.712817 -280.948871) (xy 180.671221 -280.979092)
			(xy 180.625409 -281.002435) (xy 180.57651 -281.018323) (xy 180.525728 -281.026366) (xy 180.474312 -281.026366)
			(xy 180.42353 -281.018323) (xy 180.374631 -281.002435) (xy 180.328819 -280.979092) (xy 180.287223 -280.948871)
			(xy 180.250867 -280.912515) (xy 180.220646 -280.870919) (xy 180.197303 -280.825107) (xy 180.181415 -280.776208)
			(xy 180.173372 -280.725426) (xy 179.854694 -280.725426) (xy 179.846978 -280.772902) (xy 179.831394 -280.819583)
			(xy 179.808523 -280.86316) (xy 179.778958 -280.902504) (xy 179.743465 -280.936596) (xy 179.702962 -280.964552)
			(xy 179.6585 -280.98565) (xy 179.611229 -280.999342) (xy 179.562374 -281.005274) (xy 179.513199 -281.003293)
			(xy 179.46498 -280.993449) (xy 179.418964 -280.975997) (xy 179.376343 -280.95139) (xy 179.338222 -280.920265)
			(xy 179.305587 -280.883428) (xy 179.279284 -280.841832) (xy 179.259993 -280.796556) (xy 179.248216 -280.748772)
			(xy 179.244256 -280.699718) (xy 178.926998 -280.699718) (xy 178.926494 -280.725426) (xy 178.918451 -280.776208)
			(xy 178.902563 -280.825107) (xy 178.87922 -280.870919) (xy 178.848999 -280.912515) (xy 178.812643 -280.948871)
			(xy 178.771047 -280.979092) (xy 178.725235 -281.002435) (xy 178.676336 -281.018323) (xy 178.625554 -281.026366)
			(xy 178.574138 -281.026366) (xy 178.523356 -281.018323) (xy 178.474457 -281.002435) (xy 178.428645 -280.979092)
			(xy 178.387049 -280.948871) (xy 178.350693 -280.912515) (xy 178.320472 -280.870919) (xy 178.297129 -280.825107)
			(xy 178.281241 -280.776208) (xy 178.273198 -280.725426) (xy 177.95452 -280.725426) (xy 177.946804 -280.772902)
			(xy 177.93122 -280.819583) (xy 177.908349 -280.86316) (xy 177.878784 -280.902504) (xy 177.843291 -280.936596)
			(xy 177.802788 -280.964552) (xy 177.758326 -280.98565) (xy 177.711055 -280.999342) (xy 177.6622 -281.005274)
			(xy 177.613025 -281.003293) (xy 177.564806 -280.993449) (xy 177.51879 -280.975997) (xy 177.476169 -280.95139)
			(xy 177.438048 -280.920265) (xy 177.405413 -280.883428) (xy 177.37911 -280.841832) (xy 177.359819 -280.796556)
			(xy 177.348042 -280.748772) (xy 177.344082 -280.699718) (xy 177.027078 -280.699718) (xy 177.026574 -280.725426)
			(xy 177.018531 -280.776208) (xy 177.002643 -280.825107) (xy 176.9793 -280.870919) (xy 176.949079 -280.912515)
			(xy 176.912723 -280.948871) (xy 176.871127 -280.979092) (xy 176.825315 -281.002435) (xy 176.776416 -281.018323)
			(xy 176.725634 -281.026366) (xy 176.674218 -281.026366) (xy 176.623436 -281.018323) (xy 176.574537 -281.002435)
			(xy 176.528725 -280.979092) (xy 176.487129 -280.948871) (xy 176.450773 -280.912515) (xy 176.420552 -280.870919)
			(xy 176.397209 -280.825107) (xy 176.381321 -280.776208) (xy 176.373278 -280.725426) (xy 176.054497 -280.725426)
			(xy 176.047541 -280.769982) (xy 176.033165 -280.814959) (xy 176.012038 -280.857189) (xy 175.984665 -280.895665)
			(xy 175.951698 -280.929471) (xy 175.913921 -280.957801) (xy 175.872235 -280.97998) (xy 175.827632 -280.995481)
			(xy 175.781176 -281.003933) (xy 175.757586 -281.005026) (xy 175.747451 -281.00566) (xy 175.728903 -281.013886)
			(xy 175.715013 -281.028675) (xy 175.711104 -281.038046) (xy 175.695819 -281.077946) (xy 175.659187 -281.155146)
			(xy 175.637952 -281.192224) (xy 175.637698 -281.192478) (xy 175.63444 -281.198584) (xy 175.630959 -281.211974)
			(xy 175.63084 -281.218894) (xy 175.63084 -281.232356) (xy 175.685196 -281.321256) (xy 175.688943 -281.327035)
			(xy 175.698991 -281.336447) (xy 175.705008 -281.339798) (xy 175.711104 -281.342846) (xy 175.724566 -281.34564)
			(xy 175.731678 -281.345132) (xy 175.749966 -281.344624) (xy 175.774784 -281.345107) (xy 175.823768 -281.353132)
			(xy 175.870808 -281.368976) (xy 175.914665 -281.392221) (xy 175.954184 -281.422255) (xy 175.988323 -281.458288)
			(xy 176.016183 -281.499368) (xy 176.037029 -281.544415) (xy 176.050314 -281.592241) (xy 176.055686 -281.641586)
			(xy 176.055234 -281.649932) (xy 176.394122 -281.649932) (xy 176.398082 -281.600878) (xy 176.409859 -281.553094)
			(xy 176.42915 -281.507818) (xy 176.455453 -281.466222) (xy 176.488088 -281.429385) (xy 176.526209 -281.39826)
			(xy 176.56883 -281.373653) (xy 176.614846 -281.356201) (xy 176.663065 -281.346357) (xy 176.71224 -281.344376)
			(xy 176.761095 -281.350308) (xy 176.808366 -281.364) (xy 176.852828 -281.385098) (xy 176.893331 -281.413054)
			(xy 176.928824 -281.447146) (xy 176.958389 -281.48649) (xy 176.98126 -281.530067) (xy 176.996844 -281.576748)
			(xy 177.004739 -281.625325) (xy 177.005234 -281.649932) (xy 177.344082 -281.649932) (xy 177.348042 -281.600878)
			(xy 177.359819 -281.553094) (xy 177.37911 -281.507818) (xy 177.405413 -281.466222) (xy 177.438048 -281.429385)
			(xy 177.476169 -281.39826) (xy 177.51879 -281.373653) (xy 177.564806 -281.356201) (xy 177.613025 -281.346357)
			(xy 177.6622 -281.344376) (xy 177.711055 -281.350308) (xy 177.758326 -281.364) (xy 177.802788 -281.385098)
			(xy 177.843291 -281.413054) (xy 177.878784 -281.447146) (xy 177.908349 -281.48649) (xy 177.93122 -281.530067)
			(xy 177.946804 -281.576748) (xy 177.954699 -281.625325) (xy 177.955194 -281.649932) (xy 178.294042 -281.649932)
			(xy 178.298002 -281.600878) (xy 178.309779 -281.553094) (xy 178.32907 -281.507818) (xy 178.355373 -281.466222)
			(xy 178.388008 -281.429385) (xy 178.426129 -281.39826) (xy 178.46875 -281.373653) (xy 178.514766 -281.356201)
			(xy 178.562985 -281.346357) (xy 178.61216 -281.344376) (xy 178.661015 -281.350308) (xy 178.708286 -281.364)
			(xy 178.752748 -281.385098) (xy 178.793251 -281.413054) (xy 178.828744 -281.447146) (xy 178.858309 -281.48649)
			(xy 178.88118 -281.530067) (xy 178.896764 -281.576748) (xy 178.904659 -281.625325) (xy 178.905154 -281.649932)
			(xy 179.244256 -281.649932) (xy 179.248216 -281.600878) (xy 179.259993 -281.553094) (xy 179.279284 -281.507818)
			(xy 179.305587 -281.466222) (xy 179.338222 -281.429385) (xy 179.376343 -281.39826) (xy 179.418964 -281.373653)
			(xy 179.46498 -281.356201) (xy 179.513199 -281.346357) (xy 179.562374 -281.344376) (xy 179.611229 -281.350308)
			(xy 179.6585 -281.364) (xy 179.702962 -281.385098) (xy 179.743465 -281.413054) (xy 179.778958 -281.447146)
			(xy 179.808523 -281.48649) (xy 179.831394 -281.530067) (xy 179.846978 -281.576748) (xy 179.854873 -281.625325)
			(xy 179.855368 -281.649932) (xy 180.194216 -281.649932) (xy 180.198176 -281.600878) (xy 180.209953 -281.553094)
			(xy 180.229244 -281.507818) (xy 180.255547 -281.466222) (xy 180.288182 -281.429385) (xy 180.326303 -281.39826)
			(xy 180.368924 -281.373653) (xy 180.41494 -281.356201) (xy 180.463159 -281.346357) (xy 180.512334 -281.344376)
			(xy 180.561189 -281.350308) (xy 180.60846 -281.364) (xy 180.652922 -281.385098) (xy 180.693425 -281.413054)
			(xy 180.728918 -281.447146) (xy 180.758483 -281.48649) (xy 180.781354 -281.530067) (xy 180.796938 -281.576748)
			(xy 180.804833 -281.625325) (xy 180.805328 -281.649932) (xy 181.144176 -281.649932) (xy 181.148136 -281.600878)
			(xy 181.159913 -281.553094) (xy 181.179204 -281.507818) (xy 181.205507 -281.466222) (xy 181.238142 -281.429385)
			(xy 181.276263 -281.39826) (xy 181.318884 -281.373653) (xy 181.3649 -281.356201) (xy 181.413119 -281.346357)
			(xy 181.462294 -281.344376) (xy 181.511149 -281.350308) (xy 181.55842 -281.364) (xy 181.602882 -281.385098)
			(xy 181.643385 -281.413054) (xy 181.678878 -281.447146) (xy 181.708443 -281.48649) (xy 181.731314 -281.530067)
			(xy 181.746898 -281.576748) (xy 181.754793 -281.625325) (xy 181.755288 -281.649932) (xy 182.094136 -281.649932)
			(xy 182.098096 -281.600878) (xy 182.109873 -281.553094) (xy 182.129164 -281.507818) (xy 182.155467 -281.466222)
			(xy 182.188102 -281.429385) (xy 182.226223 -281.39826) (xy 182.268844 -281.373653) (xy 182.31486 -281.356201)
			(xy 182.363079 -281.346357) (xy 182.412254 -281.344376) (xy 182.461109 -281.350308) (xy 182.50838 -281.364)
			(xy 182.552842 -281.385098) (xy 182.593345 -281.413054) (xy 182.628838 -281.447146) (xy 182.658403 -281.48649)
			(xy 182.681274 -281.530067) (xy 182.696858 -281.576748) (xy 182.704753 -281.625325) (xy 182.705248 -281.649932)
			(xy 183.044096 -281.649932) (xy 183.048056 -281.600878) (xy 183.059833 -281.553094) (xy 183.079124 -281.507818)
			(xy 183.105427 -281.466222) (xy 183.138062 -281.429385) (xy 183.176183 -281.39826) (xy 183.218804 -281.373653)
			(xy 183.26482 -281.356201) (xy 183.313039 -281.346357) (xy 183.362214 -281.344376) (xy 183.411069 -281.350308)
			(xy 183.45834 -281.364) (xy 183.502802 -281.385098) (xy 183.543305 -281.413054) (xy 183.578798 -281.447146)
			(xy 183.608363 -281.48649) (xy 183.631234 -281.530067) (xy 183.646818 -281.576748) (xy 183.654713 -281.625325)
			(xy 183.655208 -281.649932) (xy 183.994056 -281.649932) (xy 183.998016 -281.600878) (xy 184.009793 -281.553094)
			(xy 184.029084 -281.507818) (xy 184.055387 -281.466222) (xy 184.088022 -281.429385) (xy 184.126143 -281.39826)
			(xy 184.168764 -281.373653) (xy 184.21478 -281.356201) (xy 184.262999 -281.346357) (xy 184.312174 -281.344376)
			(xy 184.361029 -281.350308) (xy 184.4083 -281.364) (xy 184.452762 -281.385098) (xy 184.493265 -281.413054)
			(xy 184.528758 -281.447146) (xy 184.558323 -281.48649) (xy 184.581194 -281.530067) (xy 184.596778 -281.576748)
			(xy 184.604673 -281.625325) (xy 184.605168 -281.649932) (xy 184.94427 -281.649932) (xy 184.94823 -281.600878)
			(xy 184.960007 -281.553094) (xy 184.979298 -281.507818) (xy 185.005601 -281.466222) (xy 185.038236 -281.429385)
			(xy 185.076357 -281.39826) (xy 185.118978 -281.373653) (xy 185.164994 -281.356201) (xy 185.213213 -281.346357)
			(xy 185.262388 -281.344376) (xy 185.311243 -281.350308) (xy 185.358514 -281.364) (xy 185.402976 -281.385098)
			(xy 185.443479 -281.413054) (xy 185.478972 -281.447146) (xy 185.508537 -281.48649) (xy 185.531408 -281.530067)
			(xy 185.546992 -281.576748) (xy 185.554887 -281.625325) (xy 185.555382 -281.649932) (xy 185.89423 -281.649932)
			(xy 185.89819 -281.600878) (xy 185.909967 -281.553094) (xy 185.929258 -281.507818) (xy 185.955561 -281.466222)
			(xy 185.988196 -281.429385) (xy 186.026317 -281.39826) (xy 186.068938 -281.373653) (xy 186.114954 -281.356201)
			(xy 186.163173 -281.346357) (xy 186.212348 -281.344376) (xy 186.261203 -281.350308) (xy 186.308474 -281.364)
			(xy 186.352936 -281.385098) (xy 186.393439 -281.413054) (xy 186.428932 -281.447146) (xy 186.458497 -281.48649)
			(xy 186.481368 -281.530067) (xy 186.496952 -281.576748) (xy 186.504847 -281.625325) (xy 186.505342 -281.649932)
			(xy 186.84419 -281.649932) (xy 186.84815 -281.600878) (xy 186.859927 -281.553094) (xy 186.879218 -281.507818)
			(xy 186.905521 -281.466222) (xy 186.938156 -281.429385) (xy 186.976277 -281.39826) (xy 187.018898 -281.373653)
			(xy 187.064914 -281.356201) (xy 187.113133 -281.346357) (xy 187.162308 -281.344376) (xy 187.211163 -281.350308)
			(xy 187.258434 -281.364) (xy 187.302896 -281.385098) (xy 187.343399 -281.413054) (xy 187.378892 -281.447146)
			(xy 187.408457 -281.48649) (xy 187.431328 -281.530067) (xy 187.446912 -281.576748) (xy 187.454807 -281.625325)
			(xy 187.455302 -281.649932) (xy 187.79415 -281.649932) (xy 187.79811 -281.600878) (xy 187.809887 -281.553094)
			(xy 187.829178 -281.507818) (xy 187.855481 -281.466222) (xy 187.888116 -281.429385) (xy 187.926237 -281.39826)
			(xy 187.968858 -281.373653) (xy 188.014874 -281.356201) (xy 188.063093 -281.346357) (xy 188.112268 -281.344376)
			(xy 188.161123 -281.350308) (xy 188.208394 -281.364) (xy 188.252856 -281.385098) (xy 188.293359 -281.413054)
			(xy 188.328852 -281.447146) (xy 188.358417 -281.48649) (xy 188.381288 -281.530067) (xy 188.396872 -281.576748)
			(xy 188.404767 -281.625325) (xy 188.405262 -281.649932) (xy 188.74411 -281.649932) (xy 188.74807 -281.600878)
			(xy 188.759847 -281.553094) (xy 188.779138 -281.507818) (xy 188.805441 -281.466222) (xy 188.838076 -281.429385)
			(xy 188.876197 -281.39826) (xy 188.918818 -281.373653) (xy 188.964834 -281.356201) (xy 189.013053 -281.346357)
			(xy 189.062228 -281.344376) (xy 189.111083 -281.350308) (xy 189.158354 -281.364) (xy 189.202816 -281.385098)
			(xy 189.243319 -281.413054) (xy 189.278812 -281.447146) (xy 189.308377 -281.48649) (xy 189.331248 -281.530067)
			(xy 189.346832 -281.576748) (xy 189.354727 -281.625325) (xy 189.355222 -281.649932) (xy 189.69407 -281.649932)
			(xy 189.69803 -281.600878) (xy 189.709807 -281.553094) (xy 189.729098 -281.507818) (xy 189.755401 -281.466222)
			(xy 189.788036 -281.429385) (xy 189.826157 -281.39826) (xy 189.868778 -281.373653) (xy 189.914794 -281.356201)
			(xy 189.963013 -281.346357) (xy 190.012188 -281.344376) (xy 190.061043 -281.350308) (xy 190.108314 -281.364)
			(xy 190.152776 -281.385098) (xy 190.193279 -281.413054) (xy 190.228772 -281.447146) (xy 190.258337 -281.48649)
			(xy 190.281208 -281.530067) (xy 190.296792 -281.576748) (xy 190.304687 -281.625325) (xy 190.305182 -281.649932)
			(xy 190.644284 -281.649932) (xy 190.648244 -281.600878) (xy 190.660021 -281.553094) (xy 190.679312 -281.507818)
			(xy 190.705615 -281.466222) (xy 190.73825 -281.429385) (xy 190.776371 -281.39826) (xy 190.818992 -281.373653)
			(xy 190.865008 -281.356201) (xy 190.913227 -281.346357) (xy 190.962402 -281.344376) (xy 191.011257 -281.350308)
			(xy 191.058528 -281.364) (xy 191.10299 -281.385098) (xy 191.143493 -281.413054) (xy 191.178986 -281.447146)
			(xy 191.208551 -281.48649) (xy 191.231422 -281.530067) (xy 191.247006 -281.576748) (xy 191.254901 -281.625325)
			(xy 191.255396 -281.649932) (xy 191.594244 -281.649932) (xy 191.598204 -281.600878) (xy 191.609981 -281.553094)
			(xy 191.629272 -281.507818) (xy 191.655575 -281.466222) (xy 191.68821 -281.429385) (xy 191.726331 -281.39826)
			(xy 191.768952 -281.373653) (xy 191.814968 -281.356201) (xy 191.863187 -281.346357) (xy 191.912362 -281.344376)
			(xy 191.961217 -281.350308) (xy 192.008488 -281.364) (xy 192.05295 -281.385098) (xy 192.093453 -281.413054)
			(xy 192.128946 -281.447146) (xy 192.158511 -281.48649) (xy 192.181382 -281.530067) (xy 192.196966 -281.576748)
			(xy 192.204861 -281.625325) (xy 192.205356 -281.649932) (xy 192.544204 -281.649932) (xy 192.548164 -281.600878)
			(xy 192.559941 -281.553094) (xy 192.579232 -281.507818) (xy 192.605535 -281.466222) (xy 192.63817 -281.429385)
			(xy 192.676291 -281.39826) (xy 192.718912 -281.373653) (xy 192.764928 -281.356201) (xy 192.813147 -281.346357)
			(xy 192.862322 -281.344376) (xy 192.911177 -281.350308) (xy 192.958448 -281.364) (xy 193.00291 -281.385098)
			(xy 193.043413 -281.413054) (xy 193.078906 -281.447146) (xy 193.108471 -281.48649) (xy 193.131342 -281.530067)
			(xy 193.146926 -281.576748) (xy 193.154821 -281.625325) (xy 193.155311 -281.649678) (xy 193.49391 -281.649678)
			(xy 193.49787 -281.600624) (xy 193.509647 -281.55284) (xy 193.528938 -281.507564) (xy 193.555241 -281.465968)
			(xy 193.587876 -281.429131) (xy 193.625997 -281.398006) (xy 193.668618 -281.373399) (xy 193.714634 -281.355947)
			(xy 193.762853 -281.346103) (xy 193.812028 -281.344122) (xy 193.860883 -281.350054) (xy 193.908154 -281.363746)
			(xy 193.952616 -281.384844) (xy 193.993119 -281.4128) (xy 194.028612 -281.446892) (xy 194.058177 -281.486236)
			(xy 194.081048 -281.529813) (xy 194.096632 -281.576494) (xy 194.104527 -281.625071) (xy 194.105022 -281.649678)
			(xy 194.105017 -281.649932) (xy 194.44387 -281.649932) (xy 194.44783 -281.600878) (xy 194.459607 -281.553094)
			(xy 194.478898 -281.507818) (xy 194.505201 -281.466222) (xy 194.537836 -281.429385) (xy 194.575957 -281.39826)
			(xy 194.618578 -281.373653) (xy 194.664594 -281.356201) (xy 194.712813 -281.346357) (xy 194.761988 -281.344376)
			(xy 194.810843 -281.350308) (xy 194.858114 -281.364) (xy 194.902576 -281.385098) (xy 194.943079 -281.413054)
			(xy 194.978572 -281.447146) (xy 195.008137 -281.48649) (xy 195.031008 -281.530067) (xy 195.046592 -281.576748)
			(xy 195.054487 -281.625325) (xy 195.054982 -281.649932) (xy 195.394084 -281.649932) (xy 195.398044 -281.600878)
			(xy 195.409821 -281.553094) (xy 195.429112 -281.507818) (xy 195.455415 -281.466222) (xy 195.48805 -281.429385)
			(xy 195.526171 -281.39826) (xy 195.568792 -281.373653) (xy 195.614808 -281.356201) (xy 195.663027 -281.346357)
			(xy 195.712202 -281.344376) (xy 195.761057 -281.350308) (xy 195.808328 -281.364) (xy 195.85279 -281.385098)
			(xy 195.893293 -281.413054) (xy 195.928786 -281.447146) (xy 195.958351 -281.48649) (xy 195.981222 -281.530067)
			(xy 195.996806 -281.576748) (xy 196.004701 -281.625325) (xy 196.005196 -281.649932) (xy 196.344044 -281.649932)
			(xy 196.348004 -281.600878) (xy 196.359781 -281.553094) (xy 196.379072 -281.507818) (xy 196.405375 -281.466222)
			(xy 196.43801 -281.429385) (xy 196.476131 -281.39826) (xy 196.518752 -281.373653) (xy 196.564768 -281.356201)
			(xy 196.612987 -281.346357) (xy 196.662162 -281.344376) (xy 196.711017 -281.350308) (xy 196.758288 -281.364)
			(xy 196.80275 -281.385098) (xy 196.843253 -281.413054) (xy 196.878746 -281.447146) (xy 196.908311 -281.48649)
			(xy 196.931182 -281.530067) (xy 196.946766 -281.576748) (xy 196.954661 -281.625325) (xy 196.955156 -281.649932)
			(xy 196.954661 -281.674539) (xy 196.954482 -281.67564) (xy 197.273414 -281.67564) (xy 197.273414 -281.624224)
			(xy 197.281457 -281.573442) (xy 197.297345 -281.524543) (xy 197.320688 -281.478731) (xy 197.350909 -281.437135)
			(xy 197.387265 -281.400779) (xy 197.428861 -281.370558) (xy 197.474673 -281.347215) (xy 197.523572 -281.331327)
			(xy 197.574354 -281.323284) (xy 197.62577 -281.323284) (xy 197.676552 -281.331327) (xy 197.725451 -281.347215)
			(xy 197.771263 -281.370558) (xy 197.812859 -281.400779) (xy 197.849215 -281.437135) (xy 197.879436 -281.478731)
			(xy 197.902779 -281.524543) (xy 197.918667 -281.573442) (xy 197.92671 -281.624224) (xy 197.927214 -281.649932)
			(xy 197.92671 -281.67564) (xy 198.223374 -281.67564) (xy 198.223374 -281.624224) (xy 198.231417 -281.573442)
			(xy 198.247305 -281.524543) (xy 198.270648 -281.478731) (xy 198.300869 -281.437135) (xy 198.337225 -281.400779)
			(xy 198.378821 -281.370558) (xy 198.424633 -281.347215) (xy 198.473532 -281.331327) (xy 198.524314 -281.323284)
			(xy 198.57573 -281.323284) (xy 198.626512 -281.331327) (xy 198.660401 -281.342338) (xy 219.957142 -281.342338)
			(xy 219.957591 -281.315084) (xy 219.965344 -281.26113) (xy 219.980698 -281.208829) (xy 220.003339 -281.159245)
			(xy 220.032808 -281.11339) (xy 220.068504 -281.072195) (xy 220.109699 -281.036501) (xy 220.155556 -281.007034)
			(xy 220.20514 -280.984393) (xy 220.257441 -280.969041) (xy 220.311396 -280.96129) (xy 220.33865 -280.96083)
			(xy 220.367389 -280.961342) (xy 220.424216 -280.96997) (xy 220.479106 -280.987024) (xy 220.530818 -281.012118)
			(xy 220.578181 -281.044683) (xy 220.599508 -281.063954) (xy 220.60662 -281.070558) (xy 220.615002 -281.07386)
			(xy 220.619569 -281.075615) (xy 220.629161 -281.077534) (xy 220.634052 -281.07767) (xy 220.703648 -281.07767)
			(xy 220.708539 -281.077534) (xy 220.718131 -281.075615) (xy 220.722698 -281.07386) (xy 220.73108 -281.070558)
			(xy 220.738192 -281.063954) (xy 220.759519 -281.044684) (xy 220.806882 -281.012119) (xy 220.858593 -280.987028)
			(xy 220.913484 -280.969978) (xy 220.970311 -280.961356) (xy 221.027789 -280.961356) (xy 221.084616 -280.969978)
			(xy 221.139507 -280.987028) (xy 221.191218 -281.012119) (xy 221.238581 -281.044684) (xy 221.259908 -281.063954)
			(xy 221.26702 -281.070558) (xy 221.275402 -281.07386) (xy 221.279969 -281.075615) (xy 221.289561 -281.077534)
			(xy 221.294452 -281.07767) (xy 221.364048 -281.07767) (xy 221.368939 -281.077534) (xy 221.378531 -281.075615)
			(xy 221.383098 -281.07386) (xy 221.39148 -281.070558) (xy 221.398592 -281.063954) (xy 221.419901 -281.044662)
			(xy 221.467268 -281.012098) (xy 221.518984 -280.987009) (xy 221.573879 -280.969964) (xy 221.63071 -280.961347)
			(xy 221.65945 -280.96083) (xy 221.689572 -280.961438) (xy 221.749066 -280.970911) (xy 221.806334 -280.989613)
			(xy 221.859951 -281.017081) (xy 221.908588 -281.052631) (xy 221.930214 -281.073606) (xy 221.937326 -281.080972)
			(xy 221.946978 -281.084782) (xy 221.951547 -281.086531) (xy 221.961138 -281.088453) (xy 221.966028 -281.088592)
			(xy 222.038672 -281.088592) (xy 222.043563 -281.088461) (xy 222.053155 -281.086538) (xy 222.057722 -281.084782)
			(xy 222.067374 -281.080972) (xy 222.074486 -281.073606) (xy 222.096095 -281.052608) (xy 222.144728 -281.017042)
			(xy 222.198348 -280.989565) (xy 222.255622 -280.970861) (xy 222.315125 -280.961395) (xy 222.34525 -280.96083)
			(xy 222.372503 -280.961302) (xy 222.426456 -280.969053) (xy 222.478756 -280.984405) (xy 222.528338 -281.007044)
			(xy 222.574194 -281.03651) (xy 222.615388 -281.072204) (xy 222.651082 -281.113397) (xy 222.68055 -281.159251)
			(xy 222.703191 -281.208833) (xy 222.718544 -281.261132) (xy 222.726297 -281.315085) (xy 222.726758 -281.342338)
			(xy 222.726758 -281.342592) (xy 222.726286 -281.370304) (xy 222.718269 -281.425144) (xy 222.702388 -281.478243)
			(xy 222.678979 -281.528479) (xy 222.648536 -281.574793) (xy 222.630492 -281.59583) (xy 222.624142 -281.602688)
			(xy 222.62084 -281.611578) (xy 222.619316 -281.615865) (xy 222.61766 -281.62481) (xy 222.617538 -281.629358)
			(xy 222.617538 -281.697176) (xy 222.617568 -281.701312) (xy 222.618846 -281.709483) (xy 222.620078 -281.713432)
			(xy 222.62084 -281.71521) (xy 222.624142 -281.723846) (xy 222.630492 -281.730704) (xy 222.648552 -281.751802)
			(xy 222.679062 -281.798204) (xy 222.702529 -281.848536) (xy 222.718457 -281.901736) (xy 222.726509 -281.956683)
			(xy 222.727012 -281.98445) (xy 222.726498 -282.011701) (xy 222.718748 -282.06565) (xy 222.703399 -282.117947)
			(xy 222.680762 -282.167527) (xy 222.6513 -282.21338) (xy 222.615611 -282.254573) (xy 222.574423 -282.290267)
			(xy 222.528574 -282.319736) (xy 222.478998 -282.34238) (xy 222.426703 -282.357737) (xy 222.372755 -282.365494)
			(xy 222.345504 -282.365958) (xy 222.315381 -282.365383) (xy 222.255885 -282.355902) (xy 222.198617 -282.337192)
			(xy 222.145 -282.309718) (xy 222.096365 -282.27416) (xy 222.07474 -282.253182) (xy 222.067628 -282.245816)
			(xy 222.057976 -282.242006) (xy 222.053412 -282.240244) (xy 222.043817 -282.23833) (xy 222.038926 -282.238196)
			(xy 221.966282 -282.238196) (xy 221.961392 -282.238343) (xy 221.9518 -282.240255) (xy 221.947232 -282.242006)
			(xy 221.93758 -282.245816) (xy 221.930468 -282.253182) (xy 221.908833 -282.274152) (xy 221.860207 -282.309722)
			(xy 221.806594 -282.337204) (xy 221.749325 -282.355915) (xy 221.689828 -282.365389) (xy 221.659704 -282.365958)
			(xy 221.630966 -282.365416) (xy 221.57414 -282.356796) (xy 221.51925 -282.339749) (xy 221.467538 -282.314662)
			(xy 221.420174 -282.282102) (xy 221.398846 -282.262834) (xy 221.391734 -282.25623) (xy 221.383352 -282.252928)
			(xy 221.37878 -282.251187) (xy 221.369192 -282.24926) (xy 221.364302 -282.249118) (xy 221.294706 -282.249118)
			(xy 221.289815 -282.249242) (xy 221.280222 -282.251169) (xy 221.275656 -282.252928) (xy 221.267274 -282.25623)
			(xy 221.260162 -282.262834) (xy 221.238835 -282.282104) (xy 221.191472 -282.314669) (xy 221.139761 -282.33976)
			(xy 221.08487 -282.35681) (xy 221.028043 -282.365432) (xy 220.970565 -282.365432) (xy 220.913738 -282.35681)
			(xy 220.858847 -282.33976) (xy 220.807136 -282.314669) (xy 220.759773 -282.282104) (xy 220.738446 -282.262834)
			(xy 220.731334 -282.25623) (xy 220.722952 -282.252928) (xy 220.71838 -282.251187) (xy 220.708792 -282.24926)
			(xy 220.703902 -282.249118) (xy 220.634306 -282.249118) (xy 220.629415 -282.249242) (xy 220.619822 -282.251169)
			(xy 220.615256 -282.252928) (xy 220.606874 -282.25623) (xy 220.599762 -282.262834) (xy 220.578429 -282.282098)
			(xy 220.531069 -282.314666) (xy 220.479359 -282.339761) (xy 220.424469 -282.356813) (xy 220.367643 -282.365437)
			(xy 220.338904 -282.365958) (xy 220.311649 -282.365541) (xy 220.257694 -282.357783) (xy 220.205392 -282.342425)
			(xy 220.155809 -282.319779) (xy 220.109953 -282.290307) (xy 220.068759 -282.254608) (xy 220.033065 -282.21341)
			(xy 220.003599 -282.167551) (xy 219.980959 -282.117965) (xy 219.965607 -282.065661) (xy 219.957856 -282.011705)
			(xy 219.957396 -281.98445) (xy 219.957396 -281.984196) (xy 219.957872 -281.956485) (xy 219.96589 -281.901645)
			(xy 219.98177 -281.848547) (xy 220.005178 -281.79831) (xy 220.035619 -281.751996) (xy 220.053662 -281.730958)
			(xy 220.060012 -281.7241) (xy 220.063314 -281.71521) (xy 220.064843 -281.710925) (xy 220.066496 -281.701978)
			(xy 220.066616 -281.69743) (xy 220.066616 -281.629612) (xy 220.066591 -281.625476) (xy 220.06531 -281.617304)
			(xy 220.064076 -281.613356) (xy 220.063314 -281.611578) (xy 220.060012 -281.602942) (xy 220.053662 -281.596084)
			(xy 220.035589 -281.574997) (xy 220.005082 -281.528592) (xy 219.981619 -281.478257) (xy 219.965694 -281.425054)
			(xy 219.957644 -281.370105) (xy 219.957142 -281.342338) (xy 198.660401 -281.342338) (xy 198.675411 -281.347215)
			(xy 198.721223 -281.370558) (xy 198.762819 -281.400779) (xy 198.799175 -281.437135) (xy 198.829396 -281.478731)
			(xy 198.852739 -281.524543) (xy 198.868627 -281.573442) (xy 198.87667 -281.624224) (xy 198.877174 -281.649932)
			(xy 198.877169 -281.650186) (xy 199.194432 -281.650186) (xy 199.198392 -281.601132) (xy 199.210169 -281.553348)
			(xy 199.22946 -281.508072) (xy 199.255763 -281.466476) (xy 199.288398 -281.429639) (xy 199.326519 -281.398514)
			(xy 199.36914 -281.373907) (xy 199.415156 -281.356455) (xy 199.463375 -281.346611) (xy 199.51255 -281.34463)
			(xy 199.561405 -281.350562) (xy 199.608676 -281.364254) (xy 199.653138 -281.385352) (xy 199.693641 -281.413308)
			(xy 199.729134 -281.4474) (xy 199.758699 -281.486744) (xy 199.78157 -281.530321) (xy 199.797154 -281.577002)
			(xy 199.805049 -281.625579) (xy 199.805544 -281.650186) (xy 199.805049 -281.674793) (xy 199.797154 -281.72337)
			(xy 199.78157 -281.770051) (xy 199.758699 -281.813628) (xy 199.729134 -281.852972) (xy 199.693641 -281.887064)
			(xy 199.653138 -281.91502) (xy 199.608676 -281.936118) (xy 199.561405 -281.94981) (xy 199.51255 -281.955742)
			(xy 199.463375 -281.953761) (xy 199.415156 -281.943917) (xy 199.36914 -281.926465) (xy 199.326519 -281.901858)
			(xy 199.288398 -281.870733) (xy 199.255763 -281.833896) (xy 199.22946 -281.7923) (xy 199.210169 -281.747024)
			(xy 199.198392 -281.69924) (xy 199.194432 -281.650186) (xy 198.877169 -281.650186) (xy 198.87667 -281.67564)
			(xy 198.868627 -281.726422) (xy 198.852739 -281.775321) (xy 198.829396 -281.821133) (xy 198.799175 -281.862729)
			(xy 198.762819 -281.899085) (xy 198.721223 -281.929306) (xy 198.675411 -281.952649) (xy 198.626512 -281.968537)
			(xy 198.57573 -281.97658) (xy 198.524314 -281.97658) (xy 198.473532 -281.968537) (xy 198.424633 -281.952649)
			(xy 198.378821 -281.929306) (xy 198.337225 -281.899085) (xy 198.300869 -281.862729) (xy 198.270648 -281.821133)
			(xy 198.247305 -281.775321) (xy 198.231417 -281.726422) (xy 198.223374 -281.67564) (xy 197.92671 -281.67564)
			(xy 197.918667 -281.726422) (xy 197.902779 -281.775321) (xy 197.879436 -281.821133) (xy 197.849215 -281.862729)
			(xy 197.812859 -281.899085) (xy 197.771263 -281.929306) (xy 197.725451 -281.952649) (xy 197.676552 -281.968537)
			(xy 197.62577 -281.97658) (xy 197.574354 -281.97658) (xy 197.523572 -281.968537) (xy 197.474673 -281.952649)
			(xy 197.428861 -281.929306) (xy 197.387265 -281.899085) (xy 197.350909 -281.862729) (xy 197.320688 -281.821133)
			(xy 197.297345 -281.775321) (xy 197.281457 -281.726422) (xy 197.273414 -281.67564) (xy 196.954482 -281.67564)
			(xy 196.946766 -281.723116) (xy 196.931182 -281.769797) (xy 196.908311 -281.813374) (xy 196.878746 -281.852718)
			(xy 196.843253 -281.88681) (xy 196.80275 -281.914766) (xy 196.758288 -281.935864) (xy 196.711017 -281.949556)
			(xy 196.662162 -281.955488) (xy 196.612987 -281.953507) (xy 196.564768 -281.943663) (xy 196.518752 -281.926211)
			(xy 196.476131 -281.901604) (xy 196.43801 -281.870479) (xy 196.405375 -281.833642) (xy 196.379072 -281.792046)
			(xy 196.359781 -281.74677) (xy 196.348004 -281.698986) (xy 196.344044 -281.649932) (xy 196.005196 -281.649932)
			(xy 196.004701 -281.674539) (xy 195.996806 -281.723116) (xy 195.981222 -281.769797) (xy 195.958351 -281.813374)
			(xy 195.928786 -281.852718) (xy 195.893293 -281.88681) (xy 195.85279 -281.914766) (xy 195.808328 -281.935864)
			(xy 195.761057 -281.949556) (xy 195.712202 -281.955488) (xy 195.663027 -281.953507) (xy 195.614808 -281.943663)
			(xy 195.568792 -281.926211) (xy 195.526171 -281.901604) (xy 195.48805 -281.870479) (xy 195.455415 -281.833642)
			(xy 195.429112 -281.792046) (xy 195.409821 -281.74677) (xy 195.398044 -281.698986) (xy 195.394084 -281.649932)
			(xy 195.054982 -281.649932) (xy 195.054487 -281.674539) (xy 195.046592 -281.723116) (xy 195.031008 -281.769797)
			(xy 195.008137 -281.813374) (xy 194.978572 -281.852718) (xy 194.943079 -281.88681) (xy 194.902576 -281.914766)
			(xy 194.858114 -281.935864) (xy 194.810843 -281.949556) (xy 194.761988 -281.955488) (xy 194.712813 -281.953507)
			(xy 194.664594 -281.943663) (xy 194.618578 -281.926211) (xy 194.575957 -281.901604) (xy 194.537836 -281.870479)
			(xy 194.505201 -281.833642) (xy 194.478898 -281.792046) (xy 194.459607 -281.74677) (xy 194.44783 -281.698986)
			(xy 194.44387 -281.649932) (xy 194.105017 -281.649932) (xy 194.104527 -281.674285) (xy 194.096632 -281.722862)
			(xy 194.081048 -281.769543) (xy 194.058177 -281.81312) (xy 194.028612 -281.852464) (xy 193.993119 -281.886556)
			(xy 193.952616 -281.914512) (xy 193.908154 -281.93561) (xy 193.860883 -281.949302) (xy 193.812028 -281.955234)
			(xy 193.762853 -281.953253) (xy 193.714634 -281.943409) (xy 193.668618 -281.925957) (xy 193.625997 -281.90135)
			(xy 193.587876 -281.870225) (xy 193.555241 -281.833388) (xy 193.528938 -281.791792) (xy 193.509647 -281.746516)
			(xy 193.49787 -281.698732) (xy 193.49391 -281.649678) (xy 193.155311 -281.649678) (xy 193.155316 -281.649932)
			(xy 193.154821 -281.674539) (xy 193.146926 -281.723116) (xy 193.131342 -281.769797) (xy 193.108471 -281.813374)
			(xy 193.078906 -281.852718) (xy 193.043413 -281.88681) (xy 193.00291 -281.914766) (xy 192.958448 -281.935864)
			(xy 192.911177 -281.949556) (xy 192.862322 -281.955488) (xy 192.813147 -281.953507) (xy 192.764928 -281.943663)
			(xy 192.718912 -281.926211) (xy 192.676291 -281.901604) (xy 192.63817 -281.870479) (xy 192.605535 -281.833642)
			(xy 192.579232 -281.792046) (xy 192.559941 -281.74677) (xy 192.548164 -281.698986) (xy 192.544204 -281.649932)
			(xy 192.205356 -281.649932) (xy 192.204861 -281.674539) (xy 192.196966 -281.723116) (xy 192.181382 -281.769797)
			(xy 192.158511 -281.813374) (xy 192.128946 -281.852718) (xy 192.093453 -281.88681) (xy 192.05295 -281.914766)
			(xy 192.008488 -281.935864) (xy 191.961217 -281.949556) (xy 191.912362 -281.955488) (xy 191.863187 -281.953507)
			(xy 191.814968 -281.943663) (xy 191.768952 -281.926211) (xy 191.726331 -281.901604) (xy 191.68821 -281.870479)
			(xy 191.655575 -281.833642) (xy 191.629272 -281.792046) (xy 191.609981 -281.74677) (xy 191.598204 -281.698986)
			(xy 191.594244 -281.649932) (xy 191.255396 -281.649932) (xy 191.254901 -281.674539) (xy 191.247006 -281.723116)
			(xy 191.231422 -281.769797) (xy 191.208551 -281.813374) (xy 191.178986 -281.852718) (xy 191.143493 -281.88681)
			(xy 191.10299 -281.914766) (xy 191.058528 -281.935864) (xy 191.011257 -281.949556) (xy 190.962402 -281.955488)
			(xy 190.913227 -281.953507) (xy 190.865008 -281.943663) (xy 190.818992 -281.926211) (xy 190.776371 -281.901604)
			(xy 190.73825 -281.870479) (xy 190.705615 -281.833642) (xy 190.679312 -281.792046) (xy 190.660021 -281.74677)
			(xy 190.648244 -281.698986) (xy 190.644284 -281.649932) (xy 190.305182 -281.649932) (xy 190.304687 -281.674539)
			(xy 190.296792 -281.723116) (xy 190.281208 -281.769797) (xy 190.258337 -281.813374) (xy 190.228772 -281.852718)
			(xy 190.193279 -281.88681) (xy 190.152776 -281.914766) (xy 190.108314 -281.935864) (xy 190.061043 -281.949556)
			(xy 190.012188 -281.955488) (xy 189.963013 -281.953507) (xy 189.914794 -281.943663) (xy 189.868778 -281.926211)
			(xy 189.826157 -281.901604) (xy 189.788036 -281.870479) (xy 189.755401 -281.833642) (xy 189.729098 -281.792046)
			(xy 189.709807 -281.74677) (xy 189.69803 -281.698986) (xy 189.69407 -281.649932) (xy 189.355222 -281.649932)
			(xy 189.354727 -281.674539) (xy 189.346832 -281.723116) (xy 189.331248 -281.769797) (xy 189.308377 -281.813374)
			(xy 189.278812 -281.852718) (xy 189.243319 -281.88681) (xy 189.202816 -281.914766) (xy 189.158354 -281.935864)
			(xy 189.111083 -281.949556) (xy 189.062228 -281.955488) (xy 189.013053 -281.953507) (xy 188.964834 -281.943663)
			(xy 188.918818 -281.926211) (xy 188.876197 -281.901604) (xy 188.838076 -281.870479) (xy 188.805441 -281.833642)
			(xy 188.779138 -281.792046) (xy 188.759847 -281.74677) (xy 188.74807 -281.698986) (xy 188.74411 -281.649932)
			(xy 188.405262 -281.649932) (xy 188.404767 -281.674539) (xy 188.396872 -281.723116) (xy 188.381288 -281.769797)
			(xy 188.358417 -281.813374) (xy 188.328852 -281.852718) (xy 188.293359 -281.88681) (xy 188.252856 -281.914766)
			(xy 188.208394 -281.935864) (xy 188.161123 -281.949556) (xy 188.112268 -281.955488) (xy 188.063093 -281.953507)
			(xy 188.014874 -281.943663) (xy 187.968858 -281.926211) (xy 187.926237 -281.901604) (xy 187.888116 -281.870479)
			(xy 187.855481 -281.833642) (xy 187.829178 -281.792046) (xy 187.809887 -281.74677) (xy 187.79811 -281.698986)
			(xy 187.79415 -281.649932) (xy 187.455302 -281.649932) (xy 187.454807 -281.674539) (xy 187.446912 -281.723116)
			(xy 187.431328 -281.769797) (xy 187.408457 -281.813374) (xy 187.378892 -281.852718) (xy 187.343399 -281.88681)
			(xy 187.302896 -281.914766) (xy 187.258434 -281.935864) (xy 187.211163 -281.949556) (xy 187.162308 -281.955488)
			(xy 187.113133 -281.953507) (xy 187.064914 -281.943663) (xy 187.018898 -281.926211) (xy 186.976277 -281.901604)
			(xy 186.938156 -281.870479) (xy 186.905521 -281.833642) (xy 186.879218 -281.792046) (xy 186.859927 -281.74677)
			(xy 186.84815 -281.698986) (xy 186.84419 -281.649932) (xy 186.505342 -281.649932) (xy 186.504847 -281.674539)
			(xy 186.496952 -281.723116) (xy 186.481368 -281.769797) (xy 186.458497 -281.813374) (xy 186.428932 -281.852718)
			(xy 186.393439 -281.88681) (xy 186.352936 -281.914766) (xy 186.308474 -281.935864) (xy 186.261203 -281.949556)
			(xy 186.212348 -281.955488) (xy 186.163173 -281.953507) (xy 186.114954 -281.943663) (xy 186.068938 -281.926211)
			(xy 186.026317 -281.901604) (xy 185.988196 -281.870479) (xy 185.955561 -281.833642) (xy 185.929258 -281.792046)
			(xy 185.909967 -281.74677) (xy 185.89819 -281.698986) (xy 185.89423 -281.649932) (xy 185.555382 -281.649932)
			(xy 185.554887 -281.674539) (xy 185.546992 -281.723116) (xy 185.531408 -281.769797) (xy 185.508537 -281.813374)
			(xy 185.478972 -281.852718) (xy 185.443479 -281.88681) (xy 185.402976 -281.914766) (xy 185.358514 -281.935864)
			(xy 185.311243 -281.949556) (xy 185.262388 -281.955488) (xy 185.213213 -281.953507) (xy 185.164994 -281.943663)
			(xy 185.118978 -281.926211) (xy 185.076357 -281.901604) (xy 185.038236 -281.870479) (xy 185.005601 -281.833642)
			(xy 184.979298 -281.792046) (xy 184.960007 -281.74677) (xy 184.94823 -281.698986) (xy 184.94427 -281.649932)
			(xy 184.605168 -281.649932) (xy 184.604673 -281.674539) (xy 184.596778 -281.723116) (xy 184.581194 -281.769797)
			(xy 184.558323 -281.813374) (xy 184.528758 -281.852718) (xy 184.493265 -281.88681) (xy 184.452762 -281.914766)
			(xy 184.4083 -281.935864) (xy 184.361029 -281.949556) (xy 184.312174 -281.955488) (xy 184.262999 -281.953507)
			(xy 184.21478 -281.943663) (xy 184.168764 -281.926211) (xy 184.126143 -281.901604) (xy 184.088022 -281.870479)
			(xy 184.055387 -281.833642) (xy 184.029084 -281.792046) (xy 184.009793 -281.74677) (xy 183.998016 -281.698986)
			(xy 183.994056 -281.649932) (xy 183.655208 -281.649932) (xy 183.654713 -281.674539) (xy 183.646818 -281.723116)
			(xy 183.631234 -281.769797) (xy 183.608363 -281.813374) (xy 183.578798 -281.852718) (xy 183.543305 -281.88681)
			(xy 183.502802 -281.914766) (xy 183.45834 -281.935864) (xy 183.411069 -281.949556) (xy 183.362214 -281.955488)
			(xy 183.313039 -281.953507) (xy 183.26482 -281.943663) (xy 183.218804 -281.926211) (xy 183.176183 -281.901604)
			(xy 183.138062 -281.870479) (xy 183.105427 -281.833642) (xy 183.079124 -281.792046) (xy 183.059833 -281.74677)
			(xy 183.048056 -281.698986) (xy 183.044096 -281.649932) (xy 182.705248 -281.649932) (xy 182.704753 -281.674539)
			(xy 182.696858 -281.723116) (xy 182.681274 -281.769797) (xy 182.658403 -281.813374) (xy 182.628838 -281.852718)
			(xy 182.593345 -281.88681) (xy 182.552842 -281.914766) (xy 182.50838 -281.935864) (xy 182.461109 -281.949556)
			(xy 182.412254 -281.955488) (xy 182.363079 -281.953507) (xy 182.31486 -281.943663) (xy 182.268844 -281.926211)
			(xy 182.226223 -281.901604) (xy 182.188102 -281.870479) (xy 182.155467 -281.833642) (xy 182.129164 -281.792046)
			(xy 182.109873 -281.74677) (xy 182.098096 -281.698986) (xy 182.094136 -281.649932) (xy 181.755288 -281.649932)
			(xy 181.754793 -281.674539) (xy 181.746898 -281.723116) (xy 181.731314 -281.769797) (xy 181.708443 -281.813374)
			(xy 181.678878 -281.852718) (xy 181.643385 -281.88681) (xy 181.602882 -281.914766) (xy 181.55842 -281.935864)
			(xy 181.511149 -281.949556) (xy 181.462294 -281.955488) (xy 181.413119 -281.953507) (xy 181.3649 -281.943663)
			(xy 181.318884 -281.926211) (xy 181.276263 -281.901604) (xy 181.238142 -281.870479) (xy 181.205507 -281.833642)
			(xy 181.179204 -281.792046) (xy 181.159913 -281.74677) (xy 181.148136 -281.698986) (xy 181.144176 -281.649932)
			(xy 180.805328 -281.649932) (xy 180.804833 -281.674539) (xy 180.796938 -281.723116) (xy 180.781354 -281.769797)
			(xy 180.758483 -281.813374) (xy 180.728918 -281.852718) (xy 180.693425 -281.88681) (xy 180.652922 -281.914766)
			(xy 180.60846 -281.935864) (xy 180.561189 -281.949556) (xy 180.512334 -281.955488) (xy 180.463159 -281.953507)
			(xy 180.41494 -281.943663) (xy 180.368924 -281.926211) (xy 180.326303 -281.901604) (xy 180.288182 -281.870479)
			(xy 180.255547 -281.833642) (xy 180.229244 -281.792046) (xy 180.209953 -281.74677) (xy 180.198176 -281.698986)
			(xy 180.194216 -281.649932) (xy 179.855368 -281.649932) (xy 179.854873 -281.674539) (xy 179.846978 -281.723116)
			(xy 179.831394 -281.769797) (xy 179.808523 -281.813374) (xy 179.778958 -281.852718) (xy 179.743465 -281.88681)
			(xy 179.702962 -281.914766) (xy 179.6585 -281.935864) (xy 179.611229 -281.949556) (xy 179.562374 -281.955488)
			(xy 179.513199 -281.953507) (xy 179.46498 -281.943663) (xy 179.418964 -281.926211) (xy 179.376343 -281.901604)
			(xy 179.338222 -281.870479) (xy 179.305587 -281.833642) (xy 179.279284 -281.792046) (xy 179.259993 -281.74677)
			(xy 179.248216 -281.698986) (xy 179.244256 -281.649932) (xy 178.905154 -281.649932) (xy 178.904659 -281.674539)
			(xy 178.896764 -281.723116) (xy 178.88118 -281.769797) (xy 178.858309 -281.813374) (xy 178.828744 -281.852718)
			(xy 178.793251 -281.88681) (xy 178.752748 -281.914766) (xy 178.708286 -281.935864) (xy 178.661015 -281.949556)
			(xy 178.61216 -281.955488) (xy 178.562985 -281.953507) (xy 178.514766 -281.943663) (xy 178.46875 -281.926211)
			(xy 178.426129 -281.901604) (xy 178.388008 -281.870479) (xy 178.355373 -281.833642) (xy 178.32907 -281.792046)
			(xy 178.309779 -281.74677) (xy 178.298002 -281.698986) (xy 178.294042 -281.649932) (xy 177.955194 -281.649932)
			(xy 177.954699 -281.674539) (xy 177.946804 -281.723116) (xy 177.93122 -281.769797) (xy 177.908349 -281.813374)
			(xy 177.878784 -281.852718) (xy 177.843291 -281.88681) (xy 177.802788 -281.914766) (xy 177.758326 -281.935864)
			(xy 177.711055 -281.949556) (xy 177.6622 -281.955488) (xy 177.613025 -281.953507) (xy 177.564806 -281.943663)
			(xy 177.51879 -281.926211) (xy 177.476169 -281.901604) (xy 177.438048 -281.870479) (xy 177.405413 -281.833642)
			(xy 177.37911 -281.792046) (xy 177.359819 -281.74677) (xy 177.348042 -281.698986) (xy 177.344082 -281.649932)
			(xy 177.005234 -281.649932) (xy 177.004739 -281.674539) (xy 176.996844 -281.723116) (xy 176.98126 -281.769797)
			(xy 176.958389 -281.813374) (xy 176.928824 -281.852718) (xy 176.893331 -281.88681) (xy 176.852828 -281.914766)
			(xy 176.808366 -281.935864) (xy 176.761095 -281.949556) (xy 176.71224 -281.955488) (xy 176.663065 -281.953507)
			(xy 176.614846 -281.943663) (xy 176.56883 -281.926211) (xy 176.526209 -281.901604) (xy 176.488088 -281.870479)
			(xy 176.455453 -281.833642) (xy 176.42915 -281.792046) (xy 176.409859 -281.74677) (xy 176.398082 -281.698986)
			(xy 176.394122 -281.649932) (xy 176.055234 -281.649932) (xy 176.053004 -281.69115) (xy 176.042339 -281.739627)
			(xy 176.023972 -281.78574) (xy 175.998386 -281.828275) (xy 175.966256 -281.866109) (xy 175.928428 -281.898247)
			(xy 175.8859 -281.923842) (xy 175.83979 -281.94222) (xy 175.791315 -281.952895) (xy 175.741752 -281.955588)
			(xy 175.692406 -281.950226) (xy 175.644577 -281.936952) (xy 175.599526 -281.916115) (xy 175.558439 -281.888264)
			(xy 175.5224 -281.854133) (xy 175.492357 -281.814621) (xy 175.469102 -281.770769) (xy 175.453248 -281.723732)
			(xy 175.445212 -281.67475) (xy 175.444658 -281.649932) (xy 175.445166 -281.63139) (xy 175.445674 -281.624532)
			(xy 175.44288 -281.610562) (xy 175.439832 -281.604974) (xy 175.436487 -281.599065) (xy 175.427214 -281.589152)
			(xy 175.421544 -281.585416) (xy 175.42129 -281.585162) (xy 175.344328 -281.538172) (xy 175.338388 -281.534766)
			(xy 175.325258 -281.530895) (xy 175.31842 -281.530552) (xy 175.304704 -281.530552) (xy 175.292512 -281.53741)
			(xy 175.292004 -281.537918) (xy 175.272867 -281.549046) (xy 175.233736 -281.569755) (xy 175.213772 -281.57932)
			(xy 175.213518 -281.57932) (xy 175.207975 -281.582122) (xy 175.198345 -281.589962) (xy 175.194468 -281.594814)
			(xy 175.189388 -281.602942) (xy 175.166087 -281.648452) (xy 175.111233 -281.73474) (xy 175.079914 -281.775154)
			(xy 175.074072 -281.784552) (xy 175.074072 -281.784806) (xy 175.062542 -281.807125) (xy 175.033318 -281.84798)
			(xy 174.9978 -281.8835) (xy 174.956948 -281.912729) (xy 174.934626 -281.924252) (xy 174.934372 -281.924252)
			(xy 174.924974 -281.930094) (xy 174.888625 -281.95826) (xy 174.811474 -282.008307) (xy 174.729906 -282.050777)
			(xy 174.687484 -282.068524) (xy 174.680567 -282.071625) (xy 174.668806 -282.081175) (xy 174.66437 -282.08732)
			(xy 174.660052 -282.093416) (xy 174.657766 -282.100782) (xy 174.656802 -282.104323) (xy 174.655785 -282.11159)
			(xy 174.655734 -282.11526) (xy 174.655734 -282.124912) (xy 174.655224 -282.150899) (xy 174.647094 -282.202234)
			(xy 174.631033 -282.251664) (xy 174.607437 -282.297974) (xy 174.576887 -282.340022) (xy 174.540136 -282.376773)
			(xy 174.498088 -282.407323) (xy 174.451778 -282.430919) (xy 174.402348 -282.44698) (xy 174.351013 -282.45511)
			(xy 174.299039 -282.45511) (xy 174.247704 -282.44698) (xy 174.198274 -282.430919) (xy 174.151964 -282.407323)
			(xy 174.109916 -282.376773) (xy 174.073165 -282.340022) (xy 174.042615 -282.297974) (xy 174.019019 -282.251664)
			(xy 174.002958 -282.202234) (xy 173.994828 -282.150899) (xy 173.994318 -282.124912) (xy 173.994318 -282.117038)
			(xy 173.994572 -282.109418) (xy 173.990508 -282.094432) (xy 173.98619 -282.088082) (xy 173.981767 -282.081707)
			(xy 173.969881 -282.071743) (xy 173.962822 -282.068524) (xy 173.962568 -282.068524) (xy 173.935367 -282.057247)
			(xy 173.882244 -282.03183) (xy 173.856396 -282.017724) (xy 173.8503 -282.014422) (xy 173.837092 -282.01112)
			(xy 173.830742 -282.01112) (xy 173.824038 -282.011548) (xy 173.811174 -282.015406) (xy 173.805342 -282.01874)
			(xy 173.729396 -282.06573) (xy 173.723803 -282.069418) (xy 173.714661 -282.079203) (xy 173.711362 -282.085034)
			(xy 173.705012 -282.096718) (xy 173.70552 -282.110688) (xy 173.705774 -282.124912) (xy 173.705264 -282.150899)
			(xy 173.697134 -282.202234) (xy 173.681073 -282.251664) (xy 173.657477 -282.297974) (xy 173.626927 -282.340022)
			(xy 173.590176 -282.376773) (xy 173.548128 -282.407323) (xy 173.501818 -282.430919) (xy 173.452388 -282.44698)
			(xy 173.401053 -282.45511) (xy 173.349079 -282.45511) (xy 173.297744 -282.44698) (xy 173.248314 -282.430919)
			(xy 173.202004 -282.407323) (xy 173.159956 -282.376773) (xy 173.123205 -282.340022) (xy 173.092655 -282.297974)
			(xy 173.069059 -282.251664) (xy 173.052998 -282.202234) (xy 173.044868 -282.150899) (xy 173.044358 -282.124912)
			(xy 173.044612 -282.110434) (xy 173.04512 -282.099512) (xy 173.041056 -282.089352) (xy 173.037716 -282.081986)
			(xy 173.027229 -282.069683) (xy 173.020482 -282.065222) (xy 172.945552 -282.01874) (xy 172.939456 -282.01493)
			(xy 172.925994 -282.01112) (xy 172.918374 -282.01112) (xy 172.912786 -282.011374) (xy 172.907572 -282.012107)
			(xy 172.897583 -282.015432) (xy 172.892974 -282.017978) (xy 172.881798 -282.024328) (xy 172.863538 -282.034041)
			(xy 172.826315 -282.052083) (xy 172.807376 -282.060396) (xy 172.807122 -282.060396) (xy 172.79747 -282.06446)
			(xy 172.78731 -282.068778) (xy 172.780198 -282.071572) (xy 172.774102 -282.076652) (xy 172.765822 -282.084255)
			(xy 172.756206 -282.104545) (xy 172.75556 -282.115768) (xy 172.75556 -282.124912) (xy 172.75505 -282.150899)
			(xy 172.74692 -282.202234) (xy 172.730859 -282.251664) (xy 172.707263 -282.297974) (xy 172.676713 -282.340022)
			(xy 172.639962 -282.376773) (xy 172.597914 -282.407323) (xy 172.551604 -282.430919) (xy 172.502174 -282.44698)
			(xy 172.450839 -282.45511) (xy 172.398865 -282.45511) (xy 172.34753 -282.44698) (xy 172.2981 -282.430919)
			(xy 172.25179 -282.407323) (xy 172.209742 -282.376773) (xy 172.172991 -282.340022) (xy 172.142441 -282.297974)
			(xy 172.118845 -282.251664) (xy 172.102784 -282.202234) (xy 172.094654 -282.150899) (xy 172.094144 -282.124912)
			(xy 172.094144 -282.117038) (xy 172.094398 -282.109418) (xy 172.090334 -282.094432) (xy 172.086016 -282.088082)
			(xy 172.081594 -282.081705) (xy 172.069711 -282.071736) (xy 172.062648 -282.068524) (xy 172.062394 -282.068524)
			(xy 172.035194 -282.057245) (xy 171.982072 -282.031825) (xy 171.956222 -282.017724) (xy 171.950126 -282.014422)
			(xy 171.936918 -282.01112) (xy 171.930568 -282.01112) (xy 171.923863 -282.011545) (xy 171.910996 -282.015398)
			(xy 171.905168 -282.01874) (xy 171.829222 -282.06573) (xy 171.823627 -282.069416) (xy 171.81448 -282.079199)
			(xy 171.811188 -282.085034) (xy 171.804838 -282.096718) (xy 171.805346 -282.110688) (xy 171.8056 -282.124912)
			(xy 171.80509 -282.150899) (xy 171.79696 -282.202234) (xy 171.780899 -282.251664) (xy 171.757303 -282.297974)
			(xy 171.726753 -282.340022) (xy 171.690002 -282.376773) (xy 171.647954 -282.407323) (xy 171.601644 -282.430919)
			(xy 171.552214 -282.44698) (xy 171.500879 -282.45511) (xy 171.448905 -282.45511) (xy 171.39757 -282.44698)
			(xy 171.34814 -282.430919) (xy 171.30183 -282.407323) (xy 171.259782 -282.376773) (xy 171.223031 -282.340022)
			(xy 171.192481 -282.297974) (xy 171.168885 -282.251664) (xy 171.152824 -282.202234) (xy 171.144694 -282.150899)
			(xy 171.144184 -282.124912) (xy 171.144438 -282.110688) (xy 171.144946 -282.096718) (xy 171.138596 -282.085034)
			(xy 171.135249 -282.079238) (xy 171.126122 -282.069454) (xy 171.120562 -282.06573) (xy 171.044616 -282.01874)
			(xy 171.038805 -282.015358) (xy 171.025929 -282.011504) (xy 171.019216 -282.01112) (xy 171.005754 -282.010866)
			(xy 170.993562 -282.017724) (xy 170.96772 -282.031841) (xy 170.914596 -282.057258) (xy 170.88739 -282.068524)
			(xy 170.878225 -282.072714) (xy 170.863913 -282.086878) (xy 170.856124 -282.105448) (xy 170.85564 -282.115514)
			(xy 170.85564 -282.124912) (xy 170.85513 -282.150899) (xy 170.847 -282.202234) (xy 170.830939 -282.251664)
			(xy 170.807343 -282.297974) (xy 170.776793 -282.340022) (xy 170.740042 -282.376773) (xy 170.697994 -282.407323)
			(xy 170.651684 -282.430919) (xy 170.602254 -282.44698) (xy 170.550919 -282.45511) (xy 170.498945 -282.45511)
			(xy 170.44761 -282.44698) (xy 170.39818 -282.430919) (xy 170.35187 -282.407323) (xy 170.309822 -282.376773)
			(xy 170.273071 -282.340022) (xy 170.242521 -282.297974) (xy 170.218925 -282.251664) (xy 170.202864 -282.202234)
			(xy 170.194734 -282.150899) (xy 170.194224 -282.124912) (xy 170.194224 -282.117038) (xy 170.194478 -282.109418)
			(xy 170.190414 -282.094432) (xy 170.186096 -282.088082) (xy 170.181673 -282.081707) (xy 170.169788 -282.071742)
			(xy 170.162728 -282.068524) (xy 170.162474 -282.068524) (xy 170.135273 -282.057247) (xy 170.082149 -282.03183)
			(xy 170.056302 -282.017724) (xy 170.050206 -282.014422) (xy 170.036998 -282.01112) (xy 170.030648 -282.01112)
			(xy 170.023943 -282.011547) (xy 170.011079 -282.015404) (xy 170.005248 -282.01874) (xy 169.929302 -282.06573)
			(xy 169.923708 -282.069417) (xy 169.914565 -282.079202) (xy 169.911268 -282.085034) (xy 169.904918 -282.096718)
			(xy 169.905426 -282.110688) (xy 169.90568 -282.124912) (xy 169.90517 -282.150899) (xy 169.89704 -282.202234)
			(xy 169.880979 -282.251664) (xy 169.857383 -282.297974) (xy 169.826833 -282.340022) (xy 169.790082 -282.376773)
			(xy 169.748034 -282.407323) (xy 169.701724 -282.430919) (xy 169.652294 -282.44698) (xy 169.600959 -282.45511)
			(xy 169.548985 -282.45511) (xy 169.49765 -282.44698) (xy 169.44822 -282.430919) (xy 169.40191 -282.407323)
			(xy 169.359862 -282.376773) (xy 169.323111 -282.340022) (xy 169.292561 -282.297974) (xy 169.268965 -282.251664)
			(xy 169.252904 -282.202234) (xy 169.244774 -282.150899) (xy 169.244264 -282.124912) (xy 169.244518 -282.110688)
			(xy 169.245026 -282.096718) (xy 169.238676 -282.085034) (xy 169.235328 -282.079239) (xy 169.226199 -282.069459)
			(xy 169.220642 -282.06573) (xy 169.144696 -282.01874) (xy 169.138887 -282.015349) (xy 169.126012 -282.011475)
			(xy 169.119296 -282.01112) (xy 169.105834 -282.010866) (xy 169.093642 -282.017724) (xy 169.067801 -282.031843)
			(xy 169.014679 -282.057264) (xy 168.98747 -282.068524) (xy 168.978308 -282.072717) (xy 168.964001 -282.086882)
			(xy 168.956216 -282.105449) (xy 168.95572 -282.115514) (xy 168.95572 -282.124912) (xy 168.95521 -282.150899)
			(xy 168.94708 -282.202234) (xy 168.931019 -282.251664) (xy 168.907423 -282.297974) (xy 168.876873 -282.340022)
			(xy 168.840122 -282.376773) (xy 168.798074 -282.407323) (xy 168.751764 -282.430919) (xy 168.702334 -282.44698)
			(xy 168.650999 -282.45511) (xy 168.599025 -282.45511) (xy 168.54769 -282.44698) (xy 168.49826 -282.430919)
			(xy 168.45195 -282.407323) (xy 168.409902 -282.376773) (xy 168.373151 -282.340022) (xy 168.342601 -282.297974)
			(xy 168.319005 -282.251664) (xy 168.302944 -282.202234) (xy 168.294814 -282.150899) (xy 168.294304 -282.124912)
			(xy 168.294304 -282.117038) (xy 168.294558 -282.109418) (xy 168.290494 -282.094432) (xy 168.286176 -282.088082)
			(xy 168.281752 -282.081708) (xy 168.269865 -282.071747) (xy 168.262808 -282.068524) (xy 168.262554 -282.068524)
			(xy 168.235353 -282.057247) (xy 168.18223 -282.031829) (xy 168.156382 -282.017724) (xy 168.150286 -282.014422)
			(xy 168.137078 -282.01112) (xy 168.130728 -282.01112) (xy 168.124024 -282.01155) (xy 168.111163 -282.015411)
			(xy 168.105328 -282.01874) (xy 168.029382 -282.06573) (xy 168.02379 -282.069419) (xy 168.01465 -282.079205)
			(xy 168.011348 -282.085034) (xy 168.004998 -282.096718) (xy 168.005506 -282.110688) (xy 168.00576 -282.124912)
			(xy 168.00525 -282.150899) (xy 167.99712 -282.202234) (xy 167.981059 -282.251664) (xy 167.957463 -282.297974)
			(xy 167.926913 -282.340022) (xy 167.890162 -282.376773) (xy 167.848114 -282.407323) (xy 167.801804 -282.430919)
			(xy 167.752374 -282.44698) (xy 167.701039 -282.45511) (xy 167.649065 -282.45511) (xy 167.59773 -282.44698)
			(xy 167.5483 -282.430919) (xy 167.50199 -282.407323) (xy 167.459942 -282.376773) (xy 167.423191 -282.340022)
			(xy 167.392641 -282.297974) (xy 167.369045 -282.251664) (xy 167.352984 -282.202234) (xy 167.344854 -282.150899)
			(xy 167.344344 -282.124912) (xy 167.344598 -282.110688) (xy 167.345106 -282.096718) (xy 167.338756 -282.085034)
			(xy 167.335407 -282.07924) (xy 167.326276 -282.069463) (xy 167.320722 -282.06573) (xy 167.244776 -282.01874)
			(xy 167.238967 -282.015351) (xy 167.226091 -282.011482) (xy 167.219376 -282.01112) (xy 167.205914 -282.010866)
			(xy 167.193722 -282.017724) (xy 167.167881 -282.031842) (xy 167.114758 -282.057262) (xy 167.08755 -282.068524)
			(xy 167.078391 -282.072719) (xy 167.06409 -282.086885) (xy 167.056308 -282.105451) (xy 167.0558 -282.115514)
			(xy 167.0558 -282.124912) (xy 167.05529 -282.150899) (xy 167.04716 -282.202234) (xy 167.031099 -282.251664)
			(xy 167.007503 -282.297974) (xy 166.976953 -282.340022) (xy 166.940202 -282.376773) (xy 166.898154 -282.407323)
			(xy 166.851844 -282.430919) (xy 166.802414 -282.44698) (xy 166.751079 -282.45511) (xy 166.699105 -282.45511)
			(xy 166.64777 -282.44698) (xy 166.59834 -282.430919) (xy 166.55203 -282.407323) (xy 166.509982 -282.376773)
			(xy 166.473231 -282.340022) (xy 166.442681 -282.297974) (xy 166.419085 -282.251664) (xy 166.403024 -282.202234)
			(xy 166.394894 -282.150899) (xy 166.394384 -282.124912) (xy 166.394384 -282.117038) (xy 166.394638 -282.109164)
			(xy 166.39032 -282.094178) (xy 166.386256 -282.087828) (xy 166.381641 -282.081452) (xy 166.369364 -282.071615)
			(xy 166.362126 -282.068524) (xy 166.354506 -282.065476) (xy 166.329225 -282.054776) (xy 166.279792 -282.030884)
			(xy 166.2557 -282.017724) (xy 166.249604 -282.014422) (xy 166.236396 -282.01112) (xy 166.230046 -282.01112)
			(xy 166.223341 -282.011548) (xy 166.210478 -282.015405) (xy 166.204646 -282.01874) (xy 166.129462 -282.065222)
			(xy 166.122167 -282.070166) (xy 166.111198 -282.083941) (xy 166.105522 -282.100609) (xy 166.105332 -282.109418)
			(xy 166.105332 -282.110942) (xy 166.105586 -282.124912) (xy 166.105076 -282.150899) (xy 166.096946 -282.202234)
			(xy 166.080885 -282.251664) (xy 166.057289 -282.297974) (xy 166.026739 -282.340022) (xy 165.989988 -282.376773)
			(xy 165.94794 -282.407323) (xy 165.90163 -282.430919) (xy 165.8522 -282.44698) (xy 165.800865 -282.45511)
			(xy 165.748891 -282.45511) (xy 165.697556 -282.44698) (xy 165.648126 -282.430919) (xy 165.601816 -282.407323)
			(xy 165.559768 -282.376773) (xy 165.523017 -282.340022) (xy 165.492467 -282.297974) (xy 165.468871 -282.251664)
			(xy 165.45281 -282.202234) (xy 165.44468 -282.150899) (xy 165.44417 -282.124912) (xy 165.444424 -282.110688)
			(xy 165.444932 -282.096718) (xy 165.438582 -282.085034) (xy 165.435234 -282.079239) (xy 165.426106 -282.069457)
			(xy 165.420548 -282.06573) (xy 165.344602 -282.01874) (xy 165.33879 -282.01536) (xy 165.325915 -282.01151)
			(xy 165.319202 -282.01112) (xy 165.30574 -282.010866) (xy 165.293548 -282.017724) (xy 165.267707 -282.031843)
			(xy 165.214585 -282.057264) (xy 165.187376 -282.068524) (xy 165.178213 -282.072716) (xy 165.163905 -282.086881)
			(xy 165.156119 -282.105449) (xy 165.155626 -282.115514) (xy 165.155626 -282.124912) (xy 165.155111 -282.151295)
			(xy 165.14673 -282.203392) (xy 165.130184 -282.253497) (xy 165.105893 -282.300339) (xy 165.074471 -282.34273)
			(xy 165.036717 -282.379594) (xy 164.993589 -282.409996) (xy 164.946181 -282.433164) (xy 164.895696 -282.448511)
			(xy 164.869622 -282.452572) (xy 164.86505 -282.453334) (xy 164.854636 -282.456636) (xy 164.850318 -282.457906)
			(xy 164.826696 -282.468828) (xy 164.819838 -282.47594) (xy 164.804852 -282.491688) (xy 164.800263 -282.496792)
			(xy 164.793814 -282.508904) (xy 164.792152 -282.515564) (xy 164.790882 -282.526486) (xy 164.790882 -282.599892)
			(xy 189.69407 -282.599892) (xy 189.69803 -282.550838) (xy 189.709807 -282.503054) (xy 189.729098 -282.457778)
			(xy 189.755401 -282.416182) (xy 189.788036 -282.379345) (xy 189.826157 -282.34822) (xy 189.868778 -282.323613)
			(xy 189.914794 -282.306161) (xy 189.963013 -282.296317) (xy 190.012188 -282.294336) (xy 190.061043 -282.300268)
			(xy 190.108314 -282.31396) (xy 190.152776 -282.335058) (xy 190.193279 -282.363014) (xy 190.228772 -282.397106)
			(xy 190.258337 -282.43645) (xy 190.281208 -282.480027) (xy 190.296792 -282.526708) (xy 190.304687 -282.575285)
			(xy 190.305182 -282.599892) (xy 190.64403 -282.599892) (xy 190.64799 -282.550838) (xy 190.659767 -282.503054)
			(xy 190.679058 -282.457778) (xy 190.705361 -282.416182) (xy 190.737996 -282.379345) (xy 190.776117 -282.34822)
			(xy 190.818738 -282.323613) (xy 190.864754 -282.306161) (xy 190.912973 -282.296317) (xy 190.962148 -282.294336)
			(xy 191.011003 -282.300268) (xy 191.058274 -282.31396) (xy 191.102736 -282.335058) (xy 191.143239 -282.363014)
			(xy 191.178732 -282.397106) (xy 191.208297 -282.43645) (xy 191.231168 -282.480027) (xy 191.246752 -282.526708)
			(xy 191.254647 -282.575285) (xy 191.255142 -282.599892) (xy 191.254647 -282.624499) (xy 191.254468 -282.6256)
			(xy 192.52336 -282.6256) (xy 192.52336 -282.574184) (xy 192.531403 -282.523402) (xy 192.547291 -282.474503)
			(xy 192.570634 -282.428691) (xy 192.600855 -282.387095) (xy 192.637211 -282.350739) (xy 192.678807 -282.320518)
			(xy 192.724619 -282.297175) (xy 192.773518 -282.281287) (xy 192.8243 -282.273244) (xy 192.875716 -282.273244)
			(xy 192.926498 -282.281287) (xy 192.975397 -282.297175) (xy 193.021209 -282.320518) (xy 193.062805 -282.350739)
			(xy 193.099161 -282.387095) (xy 193.129382 -282.428691) (xy 193.152725 -282.474503) (xy 193.168613 -282.523402)
			(xy 193.176656 -282.574184) (xy 193.17716 -282.599892) (xy 193.176656 -282.6256) (xy 193.47332 -282.6256)
			(xy 193.47332 -282.574184) (xy 193.481363 -282.523402) (xy 193.497251 -282.474503) (xy 193.520594 -282.428691)
			(xy 193.550815 -282.387095) (xy 193.587171 -282.350739) (xy 193.628767 -282.320518) (xy 193.674579 -282.297175)
			(xy 193.723478 -282.281287) (xy 193.77426 -282.273244) (xy 193.825676 -282.273244) (xy 193.876458 -282.281287)
			(xy 193.925357 -282.297175) (xy 193.971169 -282.320518) (xy 194.012765 -282.350739) (xy 194.049121 -282.387095)
			(xy 194.079342 -282.428691) (xy 194.102685 -282.474503) (xy 194.118573 -282.523402) (xy 194.126616 -282.574184)
			(xy 194.12712 -282.599892) (xy 194.444124 -282.599892) (xy 194.448084 -282.550838) (xy 194.459861 -282.503054)
			(xy 194.479152 -282.457778) (xy 194.505455 -282.416182) (xy 194.53809 -282.379345) (xy 194.576211 -282.34822)
			(xy 194.618832 -282.323613) (xy 194.664848 -282.306161) (xy 194.713067 -282.296317) (xy 194.762242 -282.294336)
			(xy 194.811097 -282.300268) (xy 194.858368 -282.31396) (xy 194.90283 -282.335058) (xy 194.943333 -282.363014)
			(xy 194.978826 -282.397106) (xy 195.008391 -282.43645) (xy 195.031262 -282.480027) (xy 195.046846 -282.526708)
			(xy 195.054741 -282.575285) (xy 195.055236 -282.599892) (xy 195.054741 -282.624499) (xy 195.054562 -282.6256)
			(xy 195.37324 -282.6256) (xy 195.37324 -282.574184) (xy 195.381283 -282.523402) (xy 195.397171 -282.474503)
			(xy 195.420514 -282.428691) (xy 195.450735 -282.387095) (xy 195.487091 -282.350739) (xy 195.528687 -282.320518)
			(xy 195.574499 -282.297175) (xy 195.623398 -282.281287) (xy 195.67418 -282.273244) (xy 195.725596 -282.273244)
			(xy 195.776378 -282.281287) (xy 195.825277 -282.297175) (xy 195.871089 -282.320518) (xy 195.912685 -282.350739)
			(xy 195.949041 -282.387095) (xy 195.979262 -282.428691) (xy 196.002605 -282.474503) (xy 196.018493 -282.523402)
			(xy 196.026536 -282.574184) (xy 196.02704 -282.599892) (xy 196.026536 -282.6256) (xy 196.3232 -282.6256)
			(xy 196.3232 -282.574184) (xy 196.331243 -282.523402) (xy 196.347131 -282.474503) (xy 196.370474 -282.428691)
			(xy 196.400695 -282.387095) (xy 196.437051 -282.350739) (xy 196.478647 -282.320518) (xy 196.524459 -282.297175)
			(xy 196.573358 -282.281287) (xy 196.62414 -282.273244) (xy 196.675556 -282.273244) (xy 196.726338 -282.281287)
			(xy 196.775237 -282.297175) (xy 196.821049 -282.320518) (xy 196.862645 -282.350739) (xy 196.899001 -282.387095)
			(xy 196.929222 -282.428691) (xy 196.952565 -282.474503) (xy 196.968453 -282.523402) (xy 196.976496 -282.574184)
			(xy 196.977 -282.599892) (xy 197.294258 -282.599892) (xy 197.298218 -282.550838) (xy 197.309995 -282.503054)
			(xy 197.329286 -282.457778) (xy 197.355589 -282.416182) (xy 197.388224 -282.379345) (xy 197.426345 -282.34822)
			(xy 197.468966 -282.323613) (xy 197.514982 -282.306161) (xy 197.563201 -282.296317) (xy 197.612376 -282.294336)
			(xy 197.661231 -282.300268) (xy 197.708502 -282.31396) (xy 197.752964 -282.335058) (xy 197.793467 -282.363014)
			(xy 197.82896 -282.397106) (xy 197.858525 -282.43645) (xy 197.881396 -282.480027) (xy 197.89698 -282.526708)
			(xy 197.904875 -282.575285) (xy 197.90537 -282.599892) (xy 198.244218 -282.599892) (xy 198.248178 -282.550838)
			(xy 198.259955 -282.503054) (xy 198.279246 -282.457778) (xy 198.305549 -282.416182) (xy 198.338184 -282.379345)
			(xy 198.376305 -282.34822) (xy 198.418926 -282.323613) (xy 198.464942 -282.306161) (xy 198.513161 -282.296317)
			(xy 198.562336 -282.294336) (xy 198.611191 -282.300268) (xy 198.658462 -282.31396) (xy 198.702924 -282.335058)
			(xy 198.743427 -282.363014) (xy 198.77892 -282.397106) (xy 198.808485 -282.43645) (xy 198.831356 -282.480027)
			(xy 198.84694 -282.526708) (xy 198.854835 -282.575285) (xy 198.85533 -282.599892) (xy 198.854835 -282.624499)
			(xy 198.84694 -282.673076) (xy 198.831356 -282.719757) (xy 198.808485 -282.763334) (xy 198.77892 -282.802678)
			(xy 198.743427 -282.83677) (xy 198.702924 -282.864726) (xy 198.658462 -282.885824) (xy 198.611191 -282.899516)
			(xy 198.562336 -282.905448) (xy 198.513161 -282.903467) (xy 198.464942 -282.893623) (xy 198.418926 -282.876171)
			(xy 198.376305 -282.851564) (xy 198.338184 -282.820439) (xy 198.305549 -282.783602) (xy 198.279246 -282.742006)
			(xy 198.259955 -282.69673) (xy 198.248178 -282.648946) (xy 198.244218 -282.599892) (xy 197.90537 -282.599892)
			(xy 197.904875 -282.624499) (xy 197.89698 -282.673076) (xy 197.881396 -282.719757) (xy 197.858525 -282.763334)
			(xy 197.82896 -282.802678) (xy 197.793467 -282.83677) (xy 197.752964 -282.864726) (xy 197.708502 -282.885824)
			(xy 197.661231 -282.899516) (xy 197.612376 -282.905448) (xy 197.563201 -282.903467) (xy 197.514982 -282.893623)
			(xy 197.468966 -282.876171) (xy 197.426345 -282.851564) (xy 197.388224 -282.820439) (xy 197.355589 -282.783602)
			(xy 197.329286 -282.742006) (xy 197.309995 -282.69673) (xy 197.298218 -282.648946) (xy 197.294258 -282.599892)
			(xy 196.977 -282.599892) (xy 196.976496 -282.6256) (xy 196.968453 -282.676382) (xy 196.952565 -282.725281)
			(xy 196.929222 -282.771093) (xy 196.899001 -282.812689) (xy 196.862645 -282.849045) (xy 196.821049 -282.879266)
			(xy 196.775237 -282.902609) (xy 196.726338 -282.918497) (xy 196.675556 -282.92654) (xy 196.62414 -282.92654)
			(xy 196.573358 -282.918497) (xy 196.524459 -282.902609) (xy 196.478647 -282.879266) (xy 196.437051 -282.849045)
			(xy 196.400695 -282.812689) (xy 196.370474 -282.771093) (xy 196.347131 -282.725281) (xy 196.331243 -282.676382)
			(xy 196.3232 -282.6256) (xy 196.026536 -282.6256) (xy 196.018493 -282.676382) (xy 196.002605 -282.725281)
			(xy 195.979262 -282.771093) (xy 195.949041 -282.812689) (xy 195.912685 -282.849045) (xy 195.871089 -282.879266)
			(xy 195.825277 -282.902609) (xy 195.776378 -282.918497) (xy 195.725596 -282.92654) (xy 195.67418 -282.92654)
			(xy 195.623398 -282.918497) (xy 195.574499 -282.902609) (xy 195.528687 -282.879266) (xy 195.487091 -282.849045)
			(xy 195.450735 -282.812689) (xy 195.420514 -282.771093) (xy 195.397171 -282.725281) (xy 195.381283 -282.676382)
			(xy 195.37324 -282.6256) (xy 195.054562 -282.6256) (xy 195.046846 -282.673076) (xy 195.031262 -282.719757)
			(xy 195.008391 -282.763334) (xy 194.978826 -282.802678) (xy 194.943333 -282.83677) (xy 194.90283 -282.864726)
			(xy 194.858368 -282.885824) (xy 194.811097 -282.899516) (xy 194.762242 -282.905448) (xy 194.713067 -282.903467)
			(xy 194.664848 -282.893623) (xy 194.618832 -282.876171) (xy 194.576211 -282.851564) (xy 194.53809 -282.820439)
			(xy 194.505455 -282.783602) (xy 194.479152 -282.742006) (xy 194.459861 -282.69673) (xy 194.448084 -282.648946)
			(xy 194.444124 -282.599892) (xy 194.12712 -282.599892) (xy 194.126616 -282.6256) (xy 194.118573 -282.676382)
			(xy 194.102685 -282.725281) (xy 194.079342 -282.771093) (xy 194.049121 -282.812689) (xy 194.012765 -282.849045)
			(xy 193.971169 -282.879266) (xy 193.925357 -282.902609) (xy 193.876458 -282.918497) (xy 193.825676 -282.92654)
			(xy 193.77426 -282.92654) (xy 193.723478 -282.918497) (xy 193.674579 -282.902609) (xy 193.628767 -282.879266)
			(xy 193.587171 -282.849045) (xy 193.550815 -282.812689) (xy 193.520594 -282.771093) (xy 193.497251 -282.725281)
			(xy 193.481363 -282.676382) (xy 193.47332 -282.6256) (xy 193.176656 -282.6256) (xy 193.168613 -282.676382)
			(xy 193.152725 -282.725281) (xy 193.129382 -282.771093) (xy 193.099161 -282.812689) (xy 193.062805 -282.849045)
			(xy 193.021209 -282.879266) (xy 192.975397 -282.902609) (xy 192.926498 -282.918497) (xy 192.875716 -282.92654)
			(xy 192.8243 -282.92654) (xy 192.773518 -282.918497) (xy 192.724619 -282.902609) (xy 192.678807 -282.879266)
			(xy 192.637211 -282.849045) (xy 192.600855 -282.812689) (xy 192.570634 -282.771093) (xy 192.547291 -282.725281)
			(xy 192.531403 -282.676382) (xy 192.52336 -282.6256) (xy 191.254468 -282.6256) (xy 191.246752 -282.673076)
			(xy 191.231168 -282.719757) (xy 191.208297 -282.763334) (xy 191.178732 -282.802678) (xy 191.143239 -282.83677)
			(xy 191.102736 -282.864726) (xy 191.058274 -282.885824) (xy 191.011003 -282.899516) (xy 190.962148 -282.905448)
			(xy 190.912973 -282.903467) (xy 190.864754 -282.893623) (xy 190.818738 -282.876171) (xy 190.776117 -282.851564)
			(xy 190.737996 -282.820439) (xy 190.705361 -282.783602) (xy 190.679058 -282.742006) (xy 190.659767 -282.69673)
			(xy 190.64799 -282.648946) (xy 190.64403 -282.599892) (xy 190.305182 -282.599892) (xy 190.304687 -282.624499)
			(xy 190.296792 -282.673076) (xy 190.281208 -282.719757) (xy 190.258337 -282.763334) (xy 190.228772 -282.802678)
			(xy 190.193279 -282.83677) (xy 190.152776 -282.864726) (xy 190.108314 -282.885824) (xy 190.061043 -282.899516)
			(xy 190.012188 -282.905448) (xy 189.963013 -282.903467) (xy 189.914794 -282.893623) (xy 189.868778 -282.876171)
			(xy 189.826157 -282.851564) (xy 189.788036 -282.820439) (xy 189.755401 -282.783602) (xy 189.729098 -282.742006)
			(xy 189.709807 -282.69673) (xy 189.69803 -282.648946) (xy 189.69407 -282.599892) (xy 164.790882 -282.599892)
			(xy 164.790882 -282.673298) (xy 164.791345 -282.682932) (xy 164.79852 -282.700821) (xy 164.804852 -282.708096)
			(xy 164.820092 -282.724098) (xy 164.82695 -282.731464) (xy 164.850318 -282.741878) (xy 164.854636 -282.743148)
			(xy 164.86505 -282.74645) (xy 164.869622 -282.747212) (xy 164.895694 -282.751289) (xy 164.94618 -282.766636)
			(xy 164.99359 -282.789805) (xy 165.036719 -282.820207) (xy 165.074473 -282.857072) (xy 165.105895 -282.899464)
			(xy 165.130186 -282.946308) (xy 165.146732 -282.996414) (xy 165.155111 -283.048512) (xy 165.155111 -283.074872)
			(xy 165.469074 -283.074872) (xy 165.473034 -283.025818) (xy 165.484811 -282.978034) (xy 165.504102 -282.932758)
			(xy 165.530405 -282.891162) (xy 165.56304 -282.854325) (xy 165.601161 -282.8232) (xy 165.643782 -282.798593)
			(xy 165.689798 -282.781141) (xy 165.738017 -282.771297) (xy 165.787192 -282.769316) (xy 165.836047 -282.775248)
			(xy 165.883318 -282.78894) (xy 165.92778 -282.810038) (xy 165.968283 -282.837994) (xy 166.003776 -282.872086)
			(xy 166.033341 -282.91143) (xy 166.056212 -282.955007) (xy 166.071796 -283.001688) (xy 166.079691 -283.050265)
			(xy 166.080186 -283.074872) (xy 166.419288 -283.074872) (xy 166.423248 -283.025818) (xy 166.435025 -282.978034)
			(xy 166.454316 -282.932758) (xy 166.480619 -282.891162) (xy 166.513254 -282.854325) (xy 166.551375 -282.8232)
			(xy 166.593996 -282.798593) (xy 166.640012 -282.781141) (xy 166.688231 -282.771297) (xy 166.737406 -282.769316)
			(xy 166.786261 -282.775248) (xy 166.833532 -282.78894) (xy 166.877994 -282.810038) (xy 166.918497 -282.837994)
			(xy 166.95399 -282.872086) (xy 166.983555 -282.91143) (xy 167.006426 -282.955007) (xy 167.02201 -283.001688)
			(xy 167.029905 -283.050265) (xy 167.0304 -283.074872) (xy 167.369248 -283.074872) (xy 167.373208 -283.025818)
			(xy 167.384985 -282.978034) (xy 167.404276 -282.932758) (xy 167.430579 -282.891162) (xy 167.463214 -282.854325)
			(xy 167.501335 -282.8232) (xy 167.543956 -282.798593) (xy 167.589972 -282.781141) (xy 167.638191 -282.771297)
			(xy 167.687366 -282.769316) (xy 167.736221 -282.775248) (xy 167.783492 -282.78894) (xy 167.827954 -282.810038)
			(xy 167.868457 -282.837994) (xy 167.90395 -282.872086) (xy 167.933515 -282.91143) (xy 167.956386 -282.955007)
			(xy 167.97197 -283.001688) (xy 167.979865 -283.050265) (xy 167.98036 -283.074872) (xy 168.319208 -283.074872)
			(xy 168.323168 -283.025818) (xy 168.334945 -282.978034) (xy 168.354236 -282.932758) (xy 168.380539 -282.891162)
			(xy 168.413174 -282.854325) (xy 168.451295 -282.8232) (xy 168.493916 -282.798593) (xy 168.539932 -282.781141)
			(xy 168.588151 -282.771297) (xy 168.637326 -282.769316) (xy 168.686181 -282.775248) (xy 168.733452 -282.78894)
			(xy 168.777914 -282.810038) (xy 168.818417 -282.837994) (xy 168.85391 -282.872086) (xy 168.883475 -282.91143)
			(xy 168.906346 -282.955007) (xy 168.92193 -283.001688) (xy 168.929825 -283.050265) (xy 168.93032 -283.074872)
			(xy 169.269168 -283.074872) (xy 169.273128 -283.025818) (xy 169.284905 -282.978034) (xy 169.304196 -282.932758)
			(xy 169.330499 -282.891162) (xy 169.363134 -282.854325) (xy 169.401255 -282.8232) (xy 169.443876 -282.798593)
			(xy 169.489892 -282.781141) (xy 169.538111 -282.771297) (xy 169.587286 -282.769316) (xy 169.636141 -282.775248)
			(xy 169.683412 -282.78894) (xy 169.727874 -282.810038) (xy 169.768377 -282.837994) (xy 169.80387 -282.872086)
			(xy 169.833435 -282.91143) (xy 169.856306 -282.955007) (xy 169.87189 -283.001688) (xy 169.879785 -283.050265)
			(xy 169.88028 -283.074872) (xy 170.219128 -283.074872) (xy 170.223088 -283.025818) (xy 170.234865 -282.978034)
			(xy 170.254156 -282.932758) (xy 170.280459 -282.891162) (xy 170.313094 -282.854325) (xy 170.351215 -282.8232)
			(xy 170.393836 -282.798593) (xy 170.439852 -282.781141) (xy 170.488071 -282.771297) (xy 170.537246 -282.769316)
			(xy 170.586101 -282.775248) (xy 170.633372 -282.78894) (xy 170.677834 -282.810038) (xy 170.718337 -282.837994)
			(xy 170.75383 -282.872086) (xy 170.783395 -282.91143) (xy 170.806266 -282.955007) (xy 170.82185 -283.001688)
			(xy 170.829745 -283.050265) (xy 170.83024 -283.074872) (xy 171.169088 -283.074872) (xy 171.173048 -283.025818)
			(xy 171.184825 -282.978034) (xy 171.204116 -282.932758) (xy 171.230419 -282.891162) (xy 171.263054 -282.854325)
			(xy 171.301175 -282.8232) (xy 171.343796 -282.798593) (xy 171.389812 -282.781141) (xy 171.438031 -282.771297)
			(xy 171.487206 -282.769316) (xy 171.536061 -282.775248) (xy 171.583332 -282.78894) (xy 171.627794 -282.810038)
			(xy 171.668297 -282.837994) (xy 171.70379 -282.872086) (xy 171.733355 -282.91143) (xy 171.756226 -282.955007)
			(xy 171.77181 -283.001688) (xy 171.779705 -283.050265) (xy 171.7802 -283.074872) (xy 172.119302 -283.074872)
			(xy 172.123262 -283.025818) (xy 172.135039 -282.978034) (xy 172.15433 -282.932758) (xy 172.180633 -282.891162)
			(xy 172.213268 -282.854325) (xy 172.251389 -282.8232) (xy 172.29401 -282.798593) (xy 172.340026 -282.781141)
			(xy 172.388245 -282.771297) (xy 172.43742 -282.769316) (xy 172.486275 -282.775248) (xy 172.533546 -282.78894)
			(xy 172.578008 -282.810038) (xy 172.618511 -282.837994) (xy 172.654004 -282.872086) (xy 172.683569 -282.91143)
			(xy 172.70644 -282.955007) (xy 172.722024 -283.001688) (xy 172.729919 -283.050265) (xy 172.730414 -283.074872)
			(xy 173.069262 -283.074872) (xy 173.073222 -283.025818) (xy 173.084999 -282.978034) (xy 173.10429 -282.932758)
			(xy 173.130593 -282.891162) (xy 173.163228 -282.854325) (xy 173.201349 -282.8232) (xy 173.24397 -282.798593)
			(xy 173.289986 -282.781141) (xy 173.338205 -282.771297) (xy 173.38738 -282.769316) (xy 173.436235 -282.775248)
			(xy 173.483506 -282.78894) (xy 173.527968 -282.810038) (xy 173.568471 -282.837994) (xy 173.603964 -282.872086)
			(xy 173.633529 -282.91143) (xy 173.6564 -282.955007) (xy 173.671984 -283.001688) (xy 173.679879 -283.050265)
			(xy 173.680374 -283.074872) (xy 174.019222 -283.074872) (xy 174.023182 -283.025818) (xy 174.034959 -282.978034)
			(xy 174.05425 -282.932758) (xy 174.080553 -282.891162) (xy 174.113188 -282.854325) (xy 174.151309 -282.8232)
			(xy 174.19393 -282.798593) (xy 174.239946 -282.781141) (xy 174.288165 -282.771297) (xy 174.33734 -282.769316)
			(xy 174.386195 -282.775248) (xy 174.433466 -282.78894) (xy 174.477928 -282.810038) (xy 174.518431 -282.837994)
			(xy 174.553924 -282.872086) (xy 174.583489 -282.91143) (xy 174.60636 -282.955007) (xy 174.621944 -283.001688)
			(xy 174.629839 -283.050265) (xy 174.630334 -283.074872) (xy 175.919142 -283.074872) (xy 175.923102 -283.025818)
			(xy 175.934879 -282.978034) (xy 175.95417 -282.932758) (xy 175.980473 -282.891162) (xy 176.013108 -282.854325)
			(xy 176.051229 -282.8232) (xy 176.09385 -282.798593) (xy 176.139866 -282.781141) (xy 176.188085 -282.771297)
			(xy 176.23726 -282.769316) (xy 176.286115 -282.775248) (xy 176.333386 -282.78894) (xy 176.377848 -282.810038)
			(xy 176.418351 -282.837994) (xy 176.453844 -282.872086) (xy 176.483409 -282.91143) (xy 176.50628 -282.955007)
			(xy 176.521864 -283.001688) (xy 176.529759 -283.050265) (xy 176.530254 -283.074872) (xy 176.869102 -283.074872)
			(xy 176.873062 -283.025818) (xy 176.884839 -282.978034) (xy 176.90413 -282.932758) (xy 176.930433 -282.891162)
			(xy 176.963068 -282.854325) (xy 177.001189 -282.8232) (xy 177.04381 -282.798593) (xy 177.089826 -282.781141)
			(xy 177.138045 -282.771297) (xy 177.18722 -282.769316) (xy 177.236075 -282.775248) (xy 177.283346 -282.78894)
			(xy 177.327808 -282.810038) (xy 177.368311 -282.837994) (xy 177.403804 -282.872086) (xy 177.433369 -282.91143)
			(xy 177.45624 -282.955007) (xy 177.471824 -283.001688) (xy 177.479719 -283.050265) (xy 177.480214 -283.074872)
			(xy 177.819062 -283.074872) (xy 177.823022 -283.025818) (xy 177.834799 -282.978034) (xy 177.85409 -282.932758)
			(xy 177.880393 -282.891162) (xy 177.913028 -282.854325) (xy 177.951149 -282.8232) (xy 177.99377 -282.798593)
			(xy 178.039786 -282.781141) (xy 178.088005 -282.771297) (xy 178.13718 -282.769316) (xy 178.186035 -282.775248)
			(xy 178.233306 -282.78894) (xy 178.277768 -282.810038) (xy 178.318271 -282.837994) (xy 178.353764 -282.872086)
			(xy 178.383329 -282.91143) (xy 178.4062 -282.955007) (xy 178.421784 -283.001688) (xy 178.429679 -283.050265)
			(xy 178.430174 -283.074872) (xy 178.769276 -283.074872) (xy 178.773236 -283.025818) (xy 178.785013 -282.978034)
			(xy 178.804304 -282.932758) (xy 178.830607 -282.891162) (xy 178.863242 -282.854325) (xy 178.901363 -282.8232)
			(xy 178.943984 -282.798593) (xy 178.99 -282.781141) (xy 179.038219 -282.771297) (xy 179.087394 -282.769316)
			(xy 179.136249 -282.775248) (xy 179.18352 -282.78894) (xy 179.227982 -282.810038) (xy 179.268485 -282.837994)
			(xy 179.303978 -282.872086) (xy 179.333543 -282.91143) (xy 179.356414 -282.955007) (xy 179.371998 -283.001688)
			(xy 179.379893 -283.050265) (xy 179.380388 -283.074872) (xy 179.719236 -283.074872) (xy 179.723196 -283.025818)
			(xy 179.734973 -282.978034) (xy 179.754264 -282.932758) (xy 179.780567 -282.891162) (xy 179.813202 -282.854325)
			(xy 179.851323 -282.8232) (xy 179.893944 -282.798593) (xy 179.93996 -282.781141) (xy 179.988179 -282.771297)
			(xy 180.037354 -282.769316) (xy 180.086209 -282.775248) (xy 180.13348 -282.78894) (xy 180.177942 -282.810038)
			(xy 180.218445 -282.837994) (xy 180.253938 -282.872086) (xy 180.283503 -282.91143) (xy 180.306374 -282.955007)
			(xy 180.321958 -283.001688) (xy 180.329853 -283.050265) (xy 180.330348 -283.074872) (xy 180.669196 -283.074872)
			(xy 180.673156 -283.025818) (xy 180.684933 -282.978034) (xy 180.704224 -282.932758) (xy 180.730527 -282.891162)
			(xy 180.763162 -282.854325) (xy 180.801283 -282.8232) (xy 180.843904 -282.798593) (xy 180.88992 -282.781141)
			(xy 180.938139 -282.771297) (xy 180.987314 -282.769316) (xy 181.036169 -282.775248) (xy 181.08344 -282.78894)
			(xy 181.127902 -282.810038) (xy 181.168405 -282.837994) (xy 181.203898 -282.872086) (xy 181.233463 -282.91143)
			(xy 181.256334 -282.955007) (xy 181.271918 -283.001688) (xy 181.279813 -283.050265) (xy 181.280308 -283.074872)
			(xy 181.619156 -283.074872) (xy 181.623116 -283.025818) (xy 181.634893 -282.978034) (xy 181.654184 -282.932758)
			(xy 181.680487 -282.891162) (xy 181.713122 -282.854325) (xy 181.751243 -282.8232) (xy 181.793864 -282.798593)
			(xy 181.83988 -282.781141) (xy 181.888099 -282.771297) (xy 181.937274 -282.769316) (xy 181.986129 -282.775248)
			(xy 182.0334 -282.78894) (xy 182.077862 -282.810038) (xy 182.118365 -282.837994) (xy 182.153858 -282.872086)
			(xy 182.183423 -282.91143) (xy 182.206294 -282.955007) (xy 182.221878 -283.001688) (xy 182.229773 -283.050265)
			(xy 182.230268 -283.074872) (xy 182.569116 -283.074872) (xy 182.573076 -283.025818) (xy 182.584853 -282.978034)
			(xy 182.604144 -282.932758) (xy 182.630447 -282.891162) (xy 182.663082 -282.854325) (xy 182.701203 -282.8232)
			(xy 182.743824 -282.798593) (xy 182.78984 -282.781141) (xy 182.838059 -282.771297) (xy 182.887234 -282.769316)
			(xy 182.936089 -282.775248) (xy 182.98336 -282.78894) (xy 183.027822 -282.810038) (xy 183.068325 -282.837994)
			(xy 183.103818 -282.872086) (xy 183.133383 -282.91143) (xy 183.156254 -282.955007) (xy 183.171838 -283.001688)
			(xy 183.179733 -283.050265) (xy 183.180228 -283.074872) (xy 184.469036 -283.074872) (xy 184.472996 -283.025818)
			(xy 184.484773 -282.978034) (xy 184.504064 -282.932758) (xy 184.530367 -282.891162) (xy 184.563002 -282.854325)
			(xy 184.601123 -282.8232) (xy 184.643744 -282.798593) (xy 184.68976 -282.781141) (xy 184.737979 -282.771297)
			(xy 184.787154 -282.769316) (xy 184.836009 -282.775248) (xy 184.88328 -282.78894) (xy 184.927742 -282.810038)
			(xy 184.968245 -282.837994) (xy 185.003738 -282.872086) (xy 185.033303 -282.91143) (xy 185.056174 -282.955007)
			(xy 185.071758 -283.001688) (xy 185.079653 -283.050265) (xy 185.080148 -283.074872) (xy 185.41925 -283.074872)
			(xy 185.42321 -283.025818) (xy 185.434987 -282.978034) (xy 185.454278 -282.932758) (xy 185.480581 -282.891162)
			(xy 185.513216 -282.854325) (xy 185.551337 -282.8232) (xy 185.593958 -282.798593) (xy 185.639974 -282.781141)
			(xy 185.688193 -282.771297) (xy 185.737368 -282.769316) (xy 185.786223 -282.775248) (xy 185.833494 -282.78894)
			(xy 185.877956 -282.810038) (xy 185.918459 -282.837994) (xy 185.953952 -282.872086) (xy 185.983517 -282.91143)
			(xy 186.006388 -282.955007) (xy 186.021972 -283.001688) (xy 186.029867 -283.050265) (xy 186.030362 -283.074872)
			(xy 186.36921 -283.074872) (xy 186.37317 -283.025818) (xy 186.384947 -282.978034) (xy 186.404238 -282.932758)
			(xy 186.430541 -282.891162) (xy 186.463176 -282.854325) (xy 186.501297 -282.8232) (xy 186.543918 -282.798593)
			(xy 186.589934 -282.781141) (xy 186.638153 -282.771297) (xy 186.687328 -282.769316) (xy 186.736183 -282.775248)
			(xy 186.783454 -282.78894) (xy 186.827916 -282.810038) (xy 186.868419 -282.837994) (xy 186.903912 -282.872086)
			(xy 186.933477 -282.91143) (xy 186.956348 -282.955007) (xy 186.971932 -283.001688) (xy 186.979827 -283.050265)
			(xy 186.980322 -283.074872) (xy 187.31917 -283.074872) (xy 187.32313 -283.025818) (xy 187.334907 -282.978034)
			(xy 187.354198 -282.932758) (xy 187.380501 -282.891162) (xy 187.413136 -282.854325) (xy 187.451257 -282.8232)
			(xy 187.493878 -282.798593) (xy 187.539894 -282.781141) (xy 187.588113 -282.771297) (xy 187.637288 -282.769316)
			(xy 187.686143 -282.775248) (xy 187.733414 -282.78894) (xy 187.777876 -282.810038) (xy 187.818379 -282.837994)
			(xy 187.853872 -282.872086) (xy 187.883437 -282.91143) (xy 187.906308 -282.955007) (xy 187.921892 -283.001688)
			(xy 187.929787 -283.050265) (xy 187.930282 -283.074872) (xy 188.26913 -283.074872) (xy 188.27309 -283.025818)
			(xy 188.284867 -282.978034) (xy 188.304158 -282.932758) (xy 188.330461 -282.891162) (xy 188.363096 -282.854325)
			(xy 188.401217 -282.8232) (xy 188.443838 -282.798593) (xy 188.489854 -282.781141) (xy 188.538073 -282.771297)
			(xy 188.587248 -282.769316) (xy 188.636103 -282.775248) (xy 188.683374 -282.78894) (xy 188.727836 -282.810038)
			(xy 188.768339 -282.837994) (xy 188.803832 -282.872086) (xy 188.833397 -282.91143) (xy 188.856268 -282.955007)
			(xy 188.871852 -283.001688) (xy 188.873115 -283.009458) (xy 224.751517 -283.009458) (xy 224.751517 -282.954942)
			(xy 224.759276 -282.900982) (xy 224.774636 -282.848675) (xy 224.797284 -282.799087) (xy 224.826759 -282.753227)
			(xy 224.862462 -282.712029) (xy 224.903664 -282.676332) (xy 224.949527 -282.646862) (xy 224.999118 -282.62422)
			(xy 225.051427 -282.608866) (xy 225.105388 -282.601114) (xy 225.132646 -282.600654) (xy 225.161385 -282.601162)
			(xy 225.218213 -282.60979) (xy 225.273103 -282.626845) (xy 225.324815 -282.651939) (xy 225.372177 -282.684507)
			(xy 225.393504 -282.703778) (xy 225.400616 -282.710382) (xy 225.408998 -282.713684) (xy 225.413565 -282.715439)
			(xy 225.423157 -282.717357) (xy 225.428048 -282.717494) (xy 225.497644 -282.717494) (xy 225.502534 -282.717355)
			(xy 225.512127 -282.715438) (xy 225.516694 -282.713684) (xy 225.525076 -282.710382) (xy 225.532188 -282.703778)
			(xy 225.553515 -282.684508) (xy 225.600878 -282.651943) (xy 225.652589 -282.626852) (xy 225.70748 -282.609802)
			(xy 225.764307 -282.60118) (xy 225.821785 -282.60118) (xy 225.878612 -282.609802) (xy 225.933503 -282.626852)
			(xy 225.985214 -282.651943) (xy 226.032577 -282.684508) (xy 226.053904 -282.703778) (xy 226.061016 -282.710382)
			(xy 226.069398 -282.713684) (xy 226.073965 -282.715439) (xy 226.083557 -282.717357) (xy 226.088448 -282.717494)
			(xy 226.158044 -282.717494) (xy 226.162934 -282.717355) (xy 226.172527 -282.715438) (xy 226.177094 -282.713684)
			(xy 226.185476 -282.710382) (xy 226.192588 -282.703778) (xy 226.213902 -282.684492) (xy 226.261267 -282.651926)
			(xy 226.312982 -282.626836) (xy 226.367876 -282.609789) (xy 226.424706 -282.601172) (xy 226.453446 -282.600654)
			(xy 226.483568 -282.601258) (xy 226.543063 -282.610731) (xy 226.60033 -282.629434) (xy 226.653948 -282.656902)
			(xy 226.702584 -282.692454) (xy 226.72421 -282.71343) (xy 226.731322 -282.720796) (xy 226.740974 -282.724606)
			(xy 226.745543 -282.726355) (xy 226.755134 -282.728277) (xy 226.760024 -282.728416) (xy 226.832668 -282.728416)
			(xy 226.837559 -282.728282) (xy 226.847151 -282.726361) (xy 226.851718 -282.724606) (xy 226.86137 -282.720796)
			(xy 226.868482 -282.71343) (xy 226.890097 -282.692439) (xy 226.938728 -282.65687) (xy 226.992347 -282.629392)
			(xy 227.049619 -282.610687) (xy 227.109121 -282.60122) (xy 227.139246 -282.600654) (xy 227.166492 -282.601219)
			(xy 227.22043 -282.60898) (xy 227.272714 -282.624338) (xy 227.32228 -282.646979) (xy 227.36812 -282.676444)
			(xy 227.409301 -282.712132) (xy 227.444984 -282.753317) (xy 227.474443 -282.79916) (xy 227.497078 -282.84873)
			(xy 227.512429 -282.901015) (xy 227.520184 -282.954954) (xy 227.520184 -283.009446) (xy 227.512429 -283.063385)
			(xy 227.497078 -283.11567) (xy 227.474443 -283.16524) (xy 227.444984 -283.211083) (xy 227.409301 -283.252268)
			(xy 227.36812 -283.287956) (xy 227.32228 -283.317421) (xy 227.272714 -283.340062) (xy 227.22043 -283.35542)
			(xy 227.166492 -283.363181) (xy 227.139246 -283.36367) (xy 227.109124 -283.363065) (xy 227.04963 -283.353591)
			(xy 226.992362 -283.334888) (xy 226.938745 -283.30742) (xy 226.890108 -283.271869) (xy 226.868482 -283.250894)
			(xy 226.86137 -283.243528) (xy 226.851718 -283.239718) (xy 226.84715 -283.237967) (xy 226.837558 -283.236046)
			(xy 226.832668 -283.235908) (xy 226.760024 -283.235908) (xy 226.755133 -283.236038) (xy 226.745541 -283.237961)
			(xy 226.740974 -283.239718) (xy 226.731322 -283.243528) (xy 226.72421 -283.250894) (xy 226.702603 -283.271894)
			(xy 226.653969 -283.30746) (xy 226.600349 -283.334936) (xy 226.543074 -283.35364) (xy 226.483572 -283.363105)
			(xy 226.453446 -283.36367) (xy 226.424707 -283.36316) (xy 226.36788 -283.354532) (xy 226.312989 -283.337477)
			(xy 226.261278 -283.312383) (xy 226.213915 -283.279817) (xy 226.192588 -283.260546) (xy 226.185476 -283.253942)
			(xy 226.177094 -283.25064) (xy 226.172527 -283.248884) (xy 226.162935 -283.246966) (xy 226.158044 -283.24683)
			(xy 226.088448 -283.24683) (xy 226.083557 -283.246965) (xy 226.073965 -283.248885) (xy 226.069398 -283.25064)
			(xy 226.061016 -283.253942) (xy 226.053904 -283.260546) (xy 226.032577 -283.279816) (xy 225.985214 -283.312381)
			(xy 225.933503 -283.337472) (xy 225.878612 -283.354522) (xy 225.821785 -283.363144) (xy 225.764307 -283.363144)
			(xy 225.70748 -283.354522) (xy 225.652589 -283.337472) (xy 225.600878 -283.312381) (xy 225.553515 -283.279816)
			(xy 225.532188 -283.260546) (xy 225.525076 -283.253942) (xy 225.516694 -283.25064) (xy 225.512127 -283.248884)
			(xy 225.502535 -283.246966) (xy 225.497644 -283.24683) (xy 225.428048 -283.24683) (xy 225.423157 -283.246965)
			(xy 225.413565 -283.248885) (xy 225.408998 -283.25064) (xy 225.400616 -283.253942) (xy 225.393504 -283.260546)
			(xy 225.372197 -283.27984) (xy 225.32483 -283.312403) (xy 225.273113 -283.337492) (xy 225.218218 -283.354537)
			(xy 225.161386 -283.363153) (xy 225.132646 -283.36367) (xy 225.105388 -283.363286) (xy 225.051427 -283.355534)
			(xy 224.999118 -283.34018) (xy 224.949527 -283.317538) (xy 224.903664 -283.288068) (xy 224.862462 -283.252371)
			(xy 224.826759 -283.211173) (xy 224.797284 -283.165313) (xy 224.774636 -283.115725) (xy 224.759276 -283.063418)
			(xy 224.751517 -283.009458) (xy 188.873115 -283.009458) (xy 188.879747 -283.050265) (xy 188.880242 -283.074872)
			(xy 188.879747 -283.099479) (xy 188.871852 -283.148056) (xy 188.856268 -283.194737) (xy 188.833397 -283.238314)
			(xy 188.803832 -283.277658) (xy 188.768339 -283.31175) (xy 188.727836 -283.339706) (xy 188.683374 -283.360804)
			(xy 188.636103 -283.374496) (xy 188.587248 -283.380428) (xy 188.538073 -283.378447) (xy 188.489854 -283.368603)
			(xy 188.443838 -283.351151) (xy 188.401217 -283.326544) (xy 188.363096 -283.295419) (xy 188.330461 -283.258582)
			(xy 188.304158 -283.216986) (xy 188.284867 -283.17171) (xy 188.27309 -283.123926) (xy 188.26913 -283.074872)
			(xy 187.930282 -283.074872) (xy 187.929787 -283.099479) (xy 187.921892 -283.148056) (xy 187.906308 -283.194737)
			(xy 187.883437 -283.238314) (xy 187.853872 -283.277658) (xy 187.818379 -283.31175) (xy 187.777876 -283.339706)
			(xy 187.733414 -283.360804) (xy 187.686143 -283.374496) (xy 187.637288 -283.380428) (xy 187.588113 -283.378447)
			(xy 187.539894 -283.368603) (xy 187.493878 -283.351151) (xy 187.451257 -283.326544) (xy 187.413136 -283.295419)
			(xy 187.380501 -283.258582) (xy 187.354198 -283.216986) (xy 187.334907 -283.17171) (xy 187.32313 -283.123926)
			(xy 187.31917 -283.074872) (xy 186.980322 -283.074872) (xy 186.979827 -283.099479) (xy 186.971932 -283.148056)
			(xy 186.956348 -283.194737) (xy 186.933477 -283.238314) (xy 186.903912 -283.277658) (xy 186.868419 -283.31175)
			(xy 186.827916 -283.339706) (xy 186.783454 -283.360804) (xy 186.736183 -283.374496) (xy 186.687328 -283.380428)
			(xy 186.638153 -283.378447) (xy 186.589934 -283.368603) (xy 186.543918 -283.351151) (xy 186.501297 -283.326544)
			(xy 186.463176 -283.295419) (xy 186.430541 -283.258582) (xy 186.404238 -283.216986) (xy 186.384947 -283.17171)
			(xy 186.37317 -283.123926) (xy 186.36921 -283.074872) (xy 186.030362 -283.074872) (xy 186.029867 -283.099479)
			(xy 186.021972 -283.148056) (xy 186.006388 -283.194737) (xy 185.983517 -283.238314) (xy 185.953952 -283.277658)
			(xy 185.918459 -283.31175) (xy 185.877956 -283.339706) (xy 185.833494 -283.360804) (xy 185.786223 -283.374496)
			(xy 185.737368 -283.380428) (xy 185.688193 -283.378447) (xy 185.639974 -283.368603) (xy 185.593958 -283.351151)
			(xy 185.551337 -283.326544) (xy 185.513216 -283.295419) (xy 185.480581 -283.258582) (xy 185.454278 -283.216986)
			(xy 185.434987 -283.17171) (xy 185.42321 -283.123926) (xy 185.41925 -283.074872) (xy 185.080148 -283.074872)
			(xy 185.079653 -283.099479) (xy 185.071758 -283.148056) (xy 185.056174 -283.194737) (xy 185.033303 -283.238314)
			(xy 185.003738 -283.277658) (xy 184.968245 -283.31175) (xy 184.927742 -283.339706) (xy 184.88328 -283.360804)
			(xy 184.836009 -283.374496) (xy 184.787154 -283.380428) (xy 184.737979 -283.378447) (xy 184.68976 -283.368603)
			(xy 184.643744 -283.351151) (xy 184.601123 -283.326544) (xy 184.563002 -283.295419) (xy 184.530367 -283.258582)
			(xy 184.504064 -283.216986) (xy 184.484773 -283.17171) (xy 184.472996 -283.123926) (xy 184.469036 -283.074872)
			(xy 183.180228 -283.074872) (xy 183.179733 -283.099479) (xy 183.171838 -283.148056) (xy 183.156254 -283.194737)
			(xy 183.133383 -283.238314) (xy 183.103818 -283.277658) (xy 183.068325 -283.31175) (xy 183.027822 -283.339706)
			(xy 182.98336 -283.360804) (xy 182.936089 -283.374496) (xy 182.887234 -283.380428) (xy 182.838059 -283.378447)
			(xy 182.78984 -283.368603) (xy 182.743824 -283.351151) (xy 182.701203 -283.326544) (xy 182.663082 -283.295419)
			(xy 182.630447 -283.258582) (xy 182.604144 -283.216986) (xy 182.584853 -283.17171) (xy 182.573076 -283.123926)
			(xy 182.569116 -283.074872) (xy 182.230268 -283.074872) (xy 182.229773 -283.099479) (xy 182.221878 -283.148056)
			(xy 182.206294 -283.194737) (xy 182.183423 -283.238314) (xy 182.153858 -283.277658) (xy 182.118365 -283.31175)
			(xy 182.077862 -283.339706) (xy 182.0334 -283.360804) (xy 181.986129 -283.374496) (xy 181.937274 -283.380428)
			(xy 181.888099 -283.378447) (xy 181.83988 -283.368603) (xy 181.793864 -283.351151) (xy 181.751243 -283.326544)
			(xy 181.713122 -283.295419) (xy 181.680487 -283.258582) (xy 181.654184 -283.216986) (xy 181.634893 -283.17171)
			(xy 181.623116 -283.123926) (xy 181.619156 -283.074872) (xy 181.280308 -283.074872) (xy 181.279813 -283.099479)
			(xy 181.271918 -283.148056) (xy 181.256334 -283.194737) (xy 181.233463 -283.238314) (xy 181.203898 -283.277658)
			(xy 181.168405 -283.31175) (xy 181.127902 -283.339706) (xy 181.08344 -283.360804) (xy 181.036169 -283.374496)
			(xy 180.987314 -283.380428) (xy 180.938139 -283.378447) (xy 180.88992 -283.368603) (xy 180.843904 -283.351151)
			(xy 180.801283 -283.326544) (xy 180.763162 -283.295419) (xy 180.730527 -283.258582) (xy 180.704224 -283.216986)
			(xy 180.684933 -283.17171) (xy 180.673156 -283.123926) (xy 180.669196 -283.074872) (xy 180.330348 -283.074872)
			(xy 180.329853 -283.099479) (xy 180.321958 -283.148056) (xy 180.306374 -283.194737) (xy 180.283503 -283.238314)
			(xy 180.253938 -283.277658) (xy 180.218445 -283.31175) (xy 180.177942 -283.339706) (xy 180.13348 -283.360804)
			(xy 180.086209 -283.374496) (xy 180.037354 -283.380428) (xy 179.988179 -283.378447) (xy 179.93996 -283.368603)
			(xy 179.893944 -283.351151) (xy 179.851323 -283.326544) (xy 179.813202 -283.295419) (xy 179.780567 -283.258582)
			(xy 179.754264 -283.216986) (xy 179.734973 -283.17171) (xy 179.723196 -283.123926) (xy 179.719236 -283.074872)
			(xy 179.380388 -283.074872) (xy 179.379893 -283.099479) (xy 179.371998 -283.148056) (xy 179.356414 -283.194737)
			(xy 179.333543 -283.238314) (xy 179.303978 -283.277658) (xy 179.268485 -283.31175) (xy 179.227982 -283.339706)
			(xy 179.18352 -283.360804) (xy 179.136249 -283.374496) (xy 179.087394 -283.380428) (xy 179.038219 -283.378447)
			(xy 178.99 -283.368603) (xy 178.943984 -283.351151) (xy 178.901363 -283.326544) (xy 178.863242 -283.295419)
			(xy 178.830607 -283.258582) (xy 178.804304 -283.216986) (xy 178.785013 -283.17171) (xy 178.773236 -283.123926)
			(xy 178.769276 -283.074872) (xy 178.430174 -283.074872) (xy 178.429679 -283.099479) (xy 178.421784 -283.148056)
			(xy 178.4062 -283.194737) (xy 178.383329 -283.238314) (xy 178.353764 -283.277658) (xy 178.318271 -283.31175)
			(xy 178.277768 -283.339706) (xy 178.233306 -283.360804) (xy 178.186035 -283.374496) (xy 178.13718 -283.380428)
			(xy 178.088005 -283.378447) (xy 178.039786 -283.368603) (xy 177.99377 -283.351151) (xy 177.951149 -283.326544)
			(xy 177.913028 -283.295419) (xy 177.880393 -283.258582) (xy 177.85409 -283.216986) (xy 177.834799 -283.17171)
			(xy 177.823022 -283.123926) (xy 177.819062 -283.074872) (xy 177.480214 -283.074872) (xy 177.479719 -283.099479)
			(xy 177.471824 -283.148056) (xy 177.45624 -283.194737) (xy 177.433369 -283.238314) (xy 177.403804 -283.277658)
			(xy 177.368311 -283.31175) (xy 177.327808 -283.339706) (xy 177.283346 -283.360804) (xy 177.236075 -283.374496)
			(xy 177.18722 -283.380428) (xy 177.138045 -283.378447) (xy 177.089826 -283.368603) (xy 177.04381 -283.351151)
			(xy 177.001189 -283.326544) (xy 176.963068 -283.295419) (xy 176.930433 -283.258582) (xy 176.90413 -283.216986)
			(xy 176.884839 -283.17171) (xy 176.873062 -283.123926) (xy 176.869102 -283.074872) (xy 176.530254 -283.074872)
			(xy 176.529759 -283.099479) (xy 176.521864 -283.148056) (xy 176.50628 -283.194737) (xy 176.483409 -283.238314)
			(xy 176.453844 -283.277658) (xy 176.418351 -283.31175) (xy 176.377848 -283.339706) (xy 176.333386 -283.360804)
			(xy 176.286115 -283.374496) (xy 176.23726 -283.380428) (xy 176.188085 -283.378447) (xy 176.139866 -283.368603)
			(xy 176.09385 -283.351151) (xy 176.051229 -283.326544) (xy 176.013108 -283.295419) (xy 175.980473 -283.258582)
			(xy 175.95417 -283.216986) (xy 175.934879 -283.17171) (xy 175.923102 -283.123926) (xy 175.919142 -283.074872)
			(xy 174.630334 -283.074872) (xy 174.629839 -283.099479) (xy 174.621944 -283.148056) (xy 174.60636 -283.194737)
			(xy 174.583489 -283.238314) (xy 174.553924 -283.277658) (xy 174.518431 -283.31175) (xy 174.477928 -283.339706)
			(xy 174.433466 -283.360804) (xy 174.386195 -283.374496) (xy 174.33734 -283.380428) (xy 174.288165 -283.378447)
			(xy 174.239946 -283.368603) (xy 174.19393 -283.351151) (xy 174.151309 -283.326544) (xy 174.113188 -283.295419)
			(xy 174.080553 -283.258582) (xy 174.05425 -283.216986) (xy 174.034959 -283.17171) (xy 174.023182 -283.123926)
			(xy 174.019222 -283.074872) (xy 173.680374 -283.074872) (xy 173.679879 -283.099479) (xy 173.671984 -283.148056)
			(xy 173.6564 -283.194737) (xy 173.633529 -283.238314) (xy 173.603964 -283.277658) (xy 173.568471 -283.31175)
			(xy 173.527968 -283.339706) (xy 173.483506 -283.360804) (xy 173.436235 -283.374496) (xy 173.38738 -283.380428)
			(xy 173.338205 -283.378447) (xy 173.289986 -283.368603) (xy 173.24397 -283.351151) (xy 173.201349 -283.326544)
			(xy 173.163228 -283.295419) (xy 173.130593 -283.258582) (xy 173.10429 -283.216986) (xy 173.084999 -283.17171)
			(xy 173.073222 -283.123926) (xy 173.069262 -283.074872) (xy 172.730414 -283.074872) (xy 172.729919 -283.099479)
			(xy 172.722024 -283.148056) (xy 172.70644 -283.194737) (xy 172.683569 -283.238314) (xy 172.654004 -283.277658)
			(xy 172.618511 -283.31175) (xy 172.578008 -283.339706) (xy 172.533546 -283.360804) (xy 172.486275 -283.374496)
			(xy 172.43742 -283.380428) (xy 172.388245 -283.378447) (xy 172.340026 -283.368603) (xy 172.29401 -283.351151)
			(xy 172.251389 -283.326544) (xy 172.213268 -283.295419) (xy 172.180633 -283.258582) (xy 172.15433 -283.216986)
			(xy 172.135039 -283.17171) (xy 172.123262 -283.123926) (xy 172.119302 -283.074872) (xy 171.7802 -283.074872)
			(xy 171.779705 -283.099479) (xy 171.77181 -283.148056) (xy 171.756226 -283.194737) (xy 171.733355 -283.238314)
			(xy 171.70379 -283.277658) (xy 171.668297 -283.31175) (xy 171.627794 -283.339706) (xy 171.583332 -283.360804)
			(xy 171.536061 -283.374496) (xy 171.487206 -283.380428) (xy 171.438031 -283.378447) (xy 171.389812 -283.368603)
			(xy 171.343796 -283.351151) (xy 171.301175 -283.326544) (xy 171.263054 -283.295419) (xy 171.230419 -283.258582)
			(xy 171.204116 -283.216986) (xy 171.184825 -283.17171) (xy 171.173048 -283.123926) (xy 171.169088 -283.074872)
			(xy 170.83024 -283.074872) (xy 170.829745 -283.099479) (xy 170.82185 -283.148056) (xy 170.806266 -283.194737)
			(xy 170.783395 -283.238314) (xy 170.75383 -283.277658) (xy 170.718337 -283.31175) (xy 170.677834 -283.339706)
			(xy 170.633372 -283.360804) (xy 170.586101 -283.374496) (xy 170.537246 -283.380428) (xy 170.488071 -283.378447)
			(xy 170.439852 -283.368603) (xy 170.393836 -283.351151) (xy 170.351215 -283.326544) (xy 170.313094 -283.295419)
			(xy 170.280459 -283.258582) (xy 170.254156 -283.216986) (xy 170.234865 -283.17171) (xy 170.223088 -283.123926)
			(xy 170.219128 -283.074872) (xy 169.88028 -283.074872) (xy 169.879785 -283.099479) (xy 169.87189 -283.148056)
			(xy 169.856306 -283.194737) (xy 169.833435 -283.238314) (xy 169.80387 -283.277658) (xy 169.768377 -283.31175)
			(xy 169.727874 -283.339706) (xy 169.683412 -283.360804) (xy 169.636141 -283.374496) (xy 169.587286 -283.380428)
			(xy 169.538111 -283.378447) (xy 169.489892 -283.368603) (xy 169.443876 -283.351151) (xy 169.401255 -283.326544)
			(xy 169.363134 -283.295419) (xy 169.330499 -283.258582) (xy 169.304196 -283.216986) (xy 169.284905 -283.17171)
			(xy 169.273128 -283.123926) (xy 169.269168 -283.074872) (xy 168.93032 -283.074872) (xy 168.929825 -283.099479)
			(xy 168.92193 -283.148056) (xy 168.906346 -283.194737) (xy 168.883475 -283.238314) (xy 168.85391 -283.277658)
			(xy 168.818417 -283.31175) (xy 168.777914 -283.339706) (xy 168.733452 -283.360804) (xy 168.686181 -283.374496)
			(xy 168.637326 -283.380428) (xy 168.588151 -283.378447) (xy 168.539932 -283.368603) (xy 168.493916 -283.351151)
			(xy 168.451295 -283.326544) (xy 168.413174 -283.295419) (xy 168.380539 -283.258582) (xy 168.354236 -283.216986)
			(xy 168.334945 -283.17171) (xy 168.323168 -283.123926) (xy 168.319208 -283.074872) (xy 167.98036 -283.074872)
			(xy 167.979865 -283.099479) (xy 167.97197 -283.148056) (xy 167.956386 -283.194737) (xy 167.933515 -283.238314)
			(xy 167.90395 -283.277658) (xy 167.868457 -283.31175) (xy 167.827954 -283.339706) (xy 167.783492 -283.360804)
			(xy 167.736221 -283.374496) (xy 167.687366 -283.380428) (xy 167.638191 -283.378447) (xy 167.589972 -283.368603)
			(xy 167.543956 -283.351151) (xy 167.501335 -283.326544) (xy 167.463214 -283.295419) (xy 167.430579 -283.258582)
			(xy 167.404276 -283.216986) (xy 167.384985 -283.17171) (xy 167.373208 -283.123926) (xy 167.369248 -283.074872)
			(xy 167.0304 -283.074872) (xy 167.029905 -283.099479) (xy 167.02201 -283.148056) (xy 167.006426 -283.194737)
			(xy 166.983555 -283.238314) (xy 166.95399 -283.277658) (xy 166.918497 -283.31175) (xy 166.877994 -283.339706)
			(xy 166.833532 -283.360804) (xy 166.786261 -283.374496) (xy 166.737406 -283.380428) (xy 166.688231 -283.378447)
			(xy 166.640012 -283.368603) (xy 166.593996 -283.351151) (xy 166.551375 -283.326544) (xy 166.513254 -283.295419)
			(xy 166.480619 -283.258582) (xy 166.454316 -283.216986) (xy 166.435025 -283.17171) (xy 166.423248 -283.123926)
			(xy 166.419288 -283.074872) (xy 166.080186 -283.074872) (xy 166.079691 -283.099479) (xy 166.071796 -283.148056)
			(xy 166.056212 -283.194737) (xy 166.033341 -283.238314) (xy 166.003776 -283.277658) (xy 165.968283 -283.31175)
			(xy 165.92778 -283.339706) (xy 165.883318 -283.360804) (xy 165.836047 -283.374496) (xy 165.787192 -283.380428)
			(xy 165.738017 -283.378447) (xy 165.689798 -283.368603) (xy 165.643782 -283.351151) (xy 165.601161 -283.326544)
			(xy 165.56304 -283.295419) (xy 165.530405 -283.258582) (xy 165.504102 -283.216986) (xy 165.484811 -283.17171)
			(xy 165.473034 -283.123926) (xy 165.469074 -283.074872) (xy 165.155111 -283.074872) (xy 165.155112 -283.10128)
			(xy 165.146734 -283.153378) (xy 165.130189 -283.203485) (xy 165.105899 -283.250329) (xy 165.074478 -283.292722)
			(xy 165.036724 -283.329588) (xy 164.993596 -283.359992) (xy 164.946188 -283.383161) (xy 164.895701 -283.398509)
			(xy 164.869622 -283.402532) (xy 164.86505 -283.403294) (xy 164.854636 -283.406596) (xy 164.850318 -283.407866)
			(xy 164.826696 -283.418788) (xy 164.819838 -283.4259) (xy 164.804852 -283.441648) (xy 164.800268 -283.446755)
			(xy 164.793834 -283.45887) (xy 164.792152 -283.465524) (xy 164.790882 -283.476446) (xy 164.790882 -283.549852)
			(xy 189.69407 -283.549852) (xy 189.69803 -283.500798) (xy 189.709807 -283.453014) (xy 189.729098 -283.407738)
			(xy 189.755401 -283.366142) (xy 189.788036 -283.329305) (xy 189.826157 -283.29818) (xy 189.868778 -283.273573)
			(xy 189.914794 -283.256121) (xy 189.963013 -283.246277) (xy 190.012188 -283.244296) (xy 190.061043 -283.250228)
			(xy 190.108314 -283.26392) (xy 190.152776 -283.285018) (xy 190.193279 -283.312974) (xy 190.228772 -283.347066)
			(xy 190.258337 -283.38641) (xy 190.281208 -283.429987) (xy 190.296792 -283.476668) (xy 190.304687 -283.525245)
			(xy 190.305182 -283.549852) (xy 190.304687 -283.574459) (xy 190.304508 -283.57556) (xy 190.623186 -283.57556)
			(xy 190.623186 -283.524144) (xy 190.631229 -283.473362) (xy 190.647117 -283.424463) (xy 190.67046 -283.378651)
			(xy 190.700681 -283.337055) (xy 190.737037 -283.300699) (xy 190.778633 -283.270478) (xy 190.824445 -283.247135)
			(xy 190.873344 -283.231247) (xy 190.924126 -283.223204) (xy 190.975542 -283.223204) (xy 191.026324 -283.231247)
			(xy 191.075223 -283.247135) (xy 191.121035 -283.270478) (xy 191.162631 -283.300699) (xy 191.198987 -283.337055)
			(xy 191.229208 -283.378651) (xy 191.252551 -283.424463) (xy 191.268439 -283.473362) (xy 191.276482 -283.524144)
			(xy 191.276986 -283.549852) (xy 191.276482 -283.57556) (xy 191.5734 -283.57556) (xy 191.5734 -283.524144)
			(xy 191.581443 -283.473362) (xy 191.597331 -283.424463) (xy 191.620674 -283.378651) (xy 191.650895 -283.337055)
			(xy 191.687251 -283.300699) (xy 191.728847 -283.270478) (xy 191.774659 -283.247135) (xy 191.823558 -283.231247)
			(xy 191.87434 -283.223204) (xy 191.925756 -283.223204) (xy 191.976538 -283.231247) (xy 192.025437 -283.247135)
			(xy 192.071249 -283.270478) (xy 192.112845 -283.300699) (xy 192.149201 -283.337055) (xy 192.179422 -283.378651)
			(xy 192.202765 -283.424463) (xy 192.218653 -283.473362) (xy 192.226696 -283.524144) (xy 192.2272 -283.549852)
			(xy 192.544204 -283.549852) (xy 192.548164 -283.500798) (xy 192.559941 -283.453014) (xy 192.579232 -283.407738)
			(xy 192.605535 -283.366142) (xy 192.63817 -283.329305) (xy 192.676291 -283.29818) (xy 192.718912 -283.273573)
			(xy 192.764928 -283.256121) (xy 192.813147 -283.246277) (xy 192.862322 -283.244296) (xy 192.911177 -283.250228)
			(xy 192.958448 -283.26392) (xy 193.00291 -283.285018) (xy 193.043413 -283.312974) (xy 193.078906 -283.347066)
			(xy 193.108471 -283.38641) (xy 193.131342 -283.429987) (xy 193.146926 -283.476668) (xy 193.154821 -283.525245)
			(xy 193.155316 -283.549852) (xy 193.494164 -283.549852) (xy 193.498124 -283.500798) (xy 193.509901 -283.453014)
			(xy 193.529192 -283.407738) (xy 193.555495 -283.366142) (xy 193.58813 -283.329305) (xy 193.626251 -283.29818)
			(xy 193.668872 -283.273573) (xy 193.714888 -283.256121) (xy 193.763107 -283.246277) (xy 193.812282 -283.244296)
			(xy 193.861137 -283.250228) (xy 193.908408 -283.26392) (xy 193.95287 -283.285018) (xy 193.993373 -283.312974)
			(xy 194.028866 -283.347066) (xy 194.058431 -283.38641) (xy 194.081302 -283.429987) (xy 194.096886 -283.476668)
			(xy 194.104781 -283.525245) (xy 194.105276 -283.549852) (xy 194.444124 -283.549852) (xy 194.448084 -283.500798)
			(xy 194.459861 -283.453014) (xy 194.479152 -283.407738) (xy 194.505455 -283.366142) (xy 194.53809 -283.329305)
			(xy 194.576211 -283.29818) (xy 194.618832 -283.273573) (xy 194.664848 -283.256121) (xy 194.713067 -283.246277)
			(xy 194.762242 -283.244296) (xy 194.811097 -283.250228) (xy 194.858368 -283.26392) (xy 194.90283 -283.285018)
			(xy 194.943333 -283.312974) (xy 194.978826 -283.347066) (xy 195.008391 -283.38641) (xy 195.031262 -283.429987)
			(xy 195.046846 -283.476668) (xy 195.054741 -283.525245) (xy 195.055236 -283.549852) (xy 195.394084 -283.549852)
			(xy 195.398044 -283.500798) (xy 195.409821 -283.453014) (xy 195.429112 -283.407738) (xy 195.455415 -283.366142)
			(xy 195.48805 -283.329305) (xy 195.526171 -283.29818) (xy 195.568792 -283.273573) (xy 195.614808 -283.256121)
			(xy 195.663027 -283.246277) (xy 195.712202 -283.244296) (xy 195.761057 -283.250228) (xy 195.808328 -283.26392)
			(xy 195.85279 -283.285018) (xy 195.893293 -283.312974) (xy 195.928786 -283.347066) (xy 195.958351 -283.38641)
			(xy 195.981222 -283.429987) (xy 195.996806 -283.476668) (xy 196.004701 -283.525245) (xy 196.005196 -283.549852)
			(xy 196.344044 -283.549852) (xy 196.348004 -283.500798) (xy 196.359781 -283.453014) (xy 196.379072 -283.407738)
			(xy 196.405375 -283.366142) (xy 196.43801 -283.329305) (xy 196.476131 -283.29818) (xy 196.518752 -283.273573)
			(xy 196.564768 -283.256121) (xy 196.612987 -283.246277) (xy 196.662162 -283.244296) (xy 196.711017 -283.250228)
			(xy 196.758288 -283.26392) (xy 196.80275 -283.285018) (xy 196.843253 -283.312974) (xy 196.878746 -283.347066)
			(xy 196.908311 -283.38641) (xy 196.931182 -283.429987) (xy 196.946766 -283.476668) (xy 196.954661 -283.525245)
			(xy 196.955156 -283.549852) (xy 196.954661 -283.574459) (xy 196.954482 -283.57556) (xy 197.273414 -283.57556)
			(xy 197.273414 -283.524144) (xy 197.281457 -283.473362) (xy 197.297345 -283.424463) (xy 197.320688 -283.378651)
			(xy 197.350909 -283.337055) (xy 197.387265 -283.300699) (xy 197.428861 -283.270478) (xy 197.474673 -283.247135)
			(xy 197.523572 -283.231247) (xy 197.574354 -283.223204) (xy 197.62577 -283.223204) (xy 197.676552 -283.231247)
			(xy 197.725451 -283.247135) (xy 197.771263 -283.270478) (xy 197.812859 -283.300699) (xy 197.849215 -283.337055)
			(xy 197.879436 -283.378651) (xy 197.902779 -283.424463) (xy 197.918667 -283.473362) (xy 197.92671 -283.524144)
			(xy 197.927214 -283.549852) (xy 197.92671 -283.57556) (xy 198.223374 -283.57556) (xy 198.223374 -283.524144)
			(xy 198.231417 -283.473362) (xy 198.247305 -283.424463) (xy 198.270648 -283.378651) (xy 198.300869 -283.337055)
			(xy 198.337225 -283.300699) (xy 198.378821 -283.270478) (xy 198.424633 -283.247135) (xy 198.473532 -283.231247)
			(xy 198.524314 -283.223204) (xy 198.57573 -283.223204) (xy 198.626512 -283.231247) (xy 198.675411 -283.247135)
			(xy 198.721223 -283.270478) (xy 198.762819 -283.300699) (xy 198.799175 -283.337055) (xy 198.829396 -283.378651)
			(xy 198.852739 -283.424463) (xy 198.868627 -283.473362) (xy 198.87667 -283.524144) (xy 198.877174 -283.549852)
			(xy 198.877169 -283.550106) (xy 199.194432 -283.550106) (xy 199.198392 -283.501052) (xy 199.210169 -283.453268)
			(xy 199.22946 -283.407992) (xy 199.255763 -283.366396) (xy 199.288398 -283.329559) (xy 199.326519 -283.298434)
			(xy 199.36914 -283.273827) (xy 199.415156 -283.256375) (xy 199.463375 -283.246531) (xy 199.51255 -283.24455)
			(xy 199.561405 -283.250482) (xy 199.608676 -283.264174) (xy 199.653138 -283.285272) (xy 199.693641 -283.313228)
			(xy 199.729134 -283.34732) (xy 199.758699 -283.386664) (xy 199.78157 -283.430241) (xy 199.797154 -283.476922)
			(xy 199.805049 -283.525499) (xy 199.805544 -283.550106) (xy 199.805444 -283.555057) (xy 209.894309 -283.555057)
			(xy 209.894309 -283.500543) (xy 209.902068 -283.446583) (xy 209.917427 -283.394277) (xy 209.940074 -283.344689)
			(xy 209.969548 -283.298829) (xy 210.005248 -283.257631) (xy 210.046449 -283.221933) (xy 210.09231 -283.192462)
			(xy 210.1419 -283.169818) (xy 210.194207 -283.154462) (xy 210.248167 -283.146707) (xy 210.275424 -283.146246)
			(xy 210.302795 -283.146687) (xy 210.356976 -283.154509) (xy 210.40948 -283.170003) (xy 210.459226 -283.192851)
			(xy 210.505192 -283.222582) (xy 210.526122 -283.240226) (xy 210.533234 -283.246322) (xy 210.541616 -283.24937)
			(xy 210.545908 -283.250878) (xy 210.554849 -283.252545) (xy 210.559396 -283.252672) (xy 210.626452 -283.252672)
			(xy 210.631001 -283.252561) (xy 210.639944 -283.250893) (xy 210.644232 -283.24937) (xy 210.652614 -283.246322)
			(xy 210.659726 -283.240226) (xy 210.680679 -283.222612) (xy 210.726645 -283.192896) (xy 210.776388 -283.170054)
			(xy 210.828884 -283.154558) (xy 210.883056 -283.146723) (xy 210.910424 -283.146246) (xy 210.937671 -283.146826)
			(xy 210.991609 -283.154584) (xy 211.043895 -283.169939) (xy 211.093463 -283.192579) (xy 211.139305 -283.222043)
			(xy 211.180487 -283.25773) (xy 211.216172 -283.298914) (xy 211.245632 -283.344758) (xy 211.268269 -283.394328)
			(xy 211.283621 -283.446614) (xy 211.291376 -283.500553) (xy 211.291376 -283.555047) (xy 211.283621 -283.608986)
			(xy 211.268269 -283.661272) (xy 211.245632 -283.710842) (xy 211.216172 -283.756686) (xy 211.180487 -283.79787)
			(xy 211.139305 -283.833557) (xy 211.093463 -283.863021) (xy 211.043895 -283.885661) (xy 210.991609 -283.901016)
			(xy 210.937671 -283.908774) (xy 210.910424 -283.909262) (xy 210.883054 -283.908791) (xy 210.828875 -283.900976)
			(xy 210.776371 -283.885488) (xy 210.726624 -283.862648) (xy 210.680657 -283.832923) (xy 210.659726 -283.815282)
			(xy 210.652614 -283.809186) (xy 210.644232 -283.806138) (xy 210.639944 -283.804617) (xy 210.631 -283.802958)
			(xy 210.626452 -283.802836) (xy 210.559396 -283.802836) (xy 210.554848 -283.802959) (xy 210.545904 -283.804618)
			(xy 210.541616 -283.806138) (xy 210.533234 -283.809186) (xy 210.526122 -283.815282) (xy 210.50519 -283.832921)
			(xy 210.459218 -283.862634) (xy 210.40947 -283.88547) (xy 210.356969 -283.900961) (xy 210.302793 -283.908788)
			(xy 210.275424 -283.909262) (xy 210.248167 -283.908893) (xy 210.194207 -283.901138) (xy 210.1419 -283.885782)
			(xy 210.09231 -283.863138) (xy 210.046449 -283.833667) (xy 210.005248 -283.797969) (xy 209.969548 -283.756771)
			(xy 209.940074 -283.710911) (xy 209.917427 -283.661323) (xy 209.902068 -283.609017) (xy 209.894309 -283.555057)
			(xy 199.805444 -283.555057) (xy 199.805049 -283.574713) (xy 199.797154 -283.62329) (xy 199.78157 -283.669971)
			(xy 199.758699 -283.713548) (xy 199.729134 -283.752892) (xy 199.693641 -283.786984) (xy 199.653138 -283.81494)
			(xy 199.608676 -283.836038) (xy 199.561405 -283.84973) (xy 199.51255 -283.855662) (xy 199.463375 -283.853681)
			(xy 199.415156 -283.843837) (xy 199.36914 -283.826385) (xy 199.326519 -283.801778) (xy 199.288398 -283.770653)
			(xy 199.255763 -283.733816) (xy 199.22946 -283.69222) (xy 199.210169 -283.646944) (xy 199.198392 -283.59916)
			(xy 199.194432 -283.550106) (xy 198.877169 -283.550106) (xy 198.87667 -283.57556) (xy 198.868627 -283.626342)
			(xy 198.852739 -283.675241) (xy 198.829396 -283.721053) (xy 198.799175 -283.762649) (xy 198.762819 -283.799005)
			(xy 198.721223 -283.829226) (xy 198.675411 -283.852569) (xy 198.626512 -283.868457) (xy 198.57573 -283.8765)
			(xy 198.524314 -283.8765) (xy 198.473532 -283.868457) (xy 198.424633 -283.852569) (xy 198.378821 -283.829226)
			(xy 198.337225 -283.799005) (xy 198.300869 -283.762649) (xy 198.270648 -283.721053) (xy 198.247305 -283.675241)
			(xy 198.231417 -283.626342) (xy 198.223374 -283.57556) (xy 197.92671 -283.57556) (xy 197.918667 -283.626342)
			(xy 197.902779 -283.675241) (xy 197.879436 -283.721053) (xy 197.849215 -283.762649) (xy 197.812859 -283.799005)
			(xy 197.771263 -283.829226) (xy 197.725451 -283.852569) (xy 197.676552 -283.868457) (xy 197.62577 -283.8765)
			(xy 197.574354 -283.8765) (xy 197.523572 -283.868457) (xy 197.474673 -283.852569) (xy 197.428861 -283.829226)
			(xy 197.387265 -283.799005) (xy 197.350909 -283.762649) (xy 197.320688 -283.721053) (xy 197.297345 -283.675241)
			(xy 197.281457 -283.626342) (xy 197.273414 -283.57556) (xy 196.954482 -283.57556) (xy 196.946766 -283.623036)
			(xy 196.931182 -283.669717) (xy 196.908311 -283.713294) (xy 196.878746 -283.752638) (xy 196.843253 -283.78673)
			(xy 196.80275 -283.814686) (xy 196.758288 -283.835784) (xy 196.711017 -283.849476) (xy 196.662162 -283.855408)
			(xy 196.612987 -283.853427) (xy 196.564768 -283.843583) (xy 196.518752 -283.826131) (xy 196.476131 -283.801524)
			(xy 196.43801 -283.770399) (xy 196.405375 -283.733562) (xy 196.379072 -283.691966) (xy 196.359781 -283.64669)
			(xy 196.348004 -283.598906) (xy 196.344044 -283.549852) (xy 196.005196 -283.549852) (xy 196.004701 -283.574459)
			(xy 195.996806 -283.623036) (xy 195.981222 -283.669717) (xy 195.958351 -283.713294) (xy 195.928786 -283.752638)
			(xy 195.893293 -283.78673) (xy 195.85279 -283.814686) (xy 195.808328 -283.835784) (xy 195.761057 -283.849476)
			(xy 195.712202 -283.855408) (xy 195.663027 -283.853427) (xy 195.614808 -283.843583) (xy 195.568792 -283.826131)
			(xy 195.526171 -283.801524) (xy 195.48805 -283.770399) (xy 195.455415 -283.733562) (xy 195.429112 -283.691966)
			(xy 195.409821 -283.64669) (xy 195.398044 -283.598906) (xy 195.394084 -283.549852) (xy 195.055236 -283.549852)
			(xy 195.054741 -283.574459) (xy 195.046846 -283.623036) (xy 195.031262 -283.669717) (xy 195.008391 -283.713294)
			(xy 194.978826 -283.752638) (xy 194.943333 -283.78673) (xy 194.90283 -283.814686) (xy 194.858368 -283.835784)
			(xy 194.811097 -283.849476) (xy 194.762242 -283.855408) (xy 194.713067 -283.853427) (xy 194.664848 -283.843583)
			(xy 194.618832 -283.826131) (xy 194.576211 -283.801524) (xy 194.53809 -283.770399) (xy 194.505455 -283.733562)
			(xy 194.479152 -283.691966) (xy 194.459861 -283.64669) (xy 194.448084 -283.598906) (xy 194.444124 -283.549852)
			(xy 194.105276 -283.549852) (xy 194.104781 -283.574459) (xy 194.096886 -283.623036) (xy 194.081302 -283.669717)
			(xy 194.058431 -283.713294) (xy 194.028866 -283.752638) (xy 193.993373 -283.78673) (xy 193.95287 -283.814686)
			(xy 193.908408 -283.835784) (xy 193.861137 -283.849476) (xy 193.812282 -283.855408) (xy 193.763107 -283.853427)
			(xy 193.714888 -283.843583) (xy 193.668872 -283.826131) (xy 193.626251 -283.801524) (xy 193.58813 -283.770399)
			(xy 193.555495 -283.733562) (xy 193.529192 -283.691966) (xy 193.509901 -283.64669) (xy 193.498124 -283.598906)
			(xy 193.494164 -283.549852) (xy 193.155316 -283.549852) (xy 193.154821 -283.574459) (xy 193.146926 -283.623036)
			(xy 193.131342 -283.669717) (xy 193.108471 -283.713294) (xy 193.078906 -283.752638) (xy 193.043413 -283.78673)
			(xy 193.00291 -283.814686) (xy 192.958448 -283.835784) (xy 192.911177 -283.849476) (xy 192.862322 -283.855408)
			(xy 192.813147 -283.853427) (xy 192.764928 -283.843583) (xy 192.718912 -283.826131) (xy 192.676291 -283.801524)
			(xy 192.63817 -283.770399) (xy 192.605535 -283.733562) (xy 192.579232 -283.691966) (xy 192.559941 -283.64669)
			(xy 192.548164 -283.598906) (xy 192.544204 -283.549852) (xy 192.2272 -283.549852) (xy 192.226696 -283.57556)
			(xy 192.218653 -283.626342) (xy 192.202765 -283.675241) (xy 192.179422 -283.721053) (xy 192.149201 -283.762649)
			(xy 192.112845 -283.799005) (xy 192.071249 -283.829226) (xy 192.025437 -283.852569) (xy 191.976538 -283.868457)
			(xy 191.925756 -283.8765) (xy 191.87434 -283.8765) (xy 191.823558 -283.868457) (xy 191.774659 -283.852569)
			(xy 191.728847 -283.829226) (xy 191.687251 -283.799005) (xy 191.650895 -283.762649) (xy 191.620674 -283.721053)
			(xy 191.597331 -283.675241) (xy 191.581443 -283.626342) (xy 191.5734 -283.57556) (xy 191.276482 -283.57556)
			(xy 191.268439 -283.626342) (xy 191.252551 -283.675241) (xy 191.229208 -283.721053) (xy 191.198987 -283.762649)
			(xy 191.162631 -283.799005) (xy 191.121035 -283.829226) (xy 191.075223 -283.852569) (xy 191.026324 -283.868457)
			(xy 190.975542 -283.8765) (xy 190.924126 -283.8765) (xy 190.873344 -283.868457) (xy 190.824445 -283.852569)
			(xy 190.778633 -283.829226) (xy 190.737037 -283.799005) (xy 190.700681 -283.762649) (xy 190.67046 -283.721053)
			(xy 190.647117 -283.675241) (xy 190.631229 -283.626342) (xy 190.623186 -283.57556) (xy 190.304508 -283.57556)
			(xy 190.296792 -283.623036) (xy 190.281208 -283.669717) (xy 190.258337 -283.713294) (xy 190.228772 -283.752638)
			(xy 190.193279 -283.78673) (xy 190.152776 -283.814686) (xy 190.108314 -283.835784) (xy 190.061043 -283.849476)
			(xy 190.012188 -283.855408) (xy 189.963013 -283.853427) (xy 189.914794 -283.843583) (xy 189.868778 -283.826131)
			(xy 189.826157 -283.801524) (xy 189.788036 -283.770399) (xy 189.755401 -283.733562) (xy 189.729098 -283.691966)
			(xy 189.709807 -283.64669) (xy 189.69803 -283.598906) (xy 189.69407 -283.549852) (xy 164.790882 -283.549852)
			(xy 164.790882 -283.623258) (xy 164.791356 -283.632888) (xy 164.798545 -283.650762) (xy 164.804852 -283.658056)
			(xy 164.820092 -283.674058) (xy 164.82695 -283.681424) (xy 164.850318 -283.691838) (xy 164.854636 -283.693108)
			(xy 164.86505 -283.69641) (xy 164.869622 -283.697172) (xy 164.895689 -283.701249) (xy 164.946166 -283.716594)
			(xy 164.993566 -283.73976) (xy 165.036687 -283.770158) (xy 165.074433 -283.807017) (xy 165.105848 -283.849403)
			(xy 165.130135 -283.896238) (xy 165.146676 -283.946336) (xy 165.155052 -283.998425) (xy 165.155052 -284.024832)
			(xy 165.469074 -284.024832) (xy 165.473034 -283.975778) (xy 165.484811 -283.927994) (xy 165.504102 -283.882718)
			(xy 165.530405 -283.841122) (xy 165.56304 -283.804285) (xy 165.601161 -283.77316) (xy 165.643782 -283.748553)
			(xy 165.689798 -283.731101) (xy 165.738017 -283.721257) (xy 165.787192 -283.719276) (xy 165.836047 -283.725208)
			(xy 165.883318 -283.7389) (xy 165.92778 -283.759998) (xy 165.968283 -283.787954) (xy 166.003776 -283.822046)
			(xy 166.033341 -283.86139) (xy 166.056212 -283.904967) (xy 166.071796 -283.951648) (xy 166.079691 -284.000225)
			(xy 166.080186 -284.024832) (xy 166.419288 -284.024832) (xy 166.423248 -283.975778) (xy 166.435025 -283.927994)
			(xy 166.454316 -283.882718) (xy 166.480619 -283.841122) (xy 166.513254 -283.804285) (xy 166.551375 -283.77316)
			(xy 166.593996 -283.748553) (xy 166.640012 -283.731101) (xy 166.688231 -283.721257) (xy 166.737406 -283.719276)
			(xy 166.786261 -283.725208) (xy 166.833532 -283.7389) (xy 166.877994 -283.759998) (xy 166.918497 -283.787954)
			(xy 166.95399 -283.822046) (xy 166.983555 -283.86139) (xy 167.006426 -283.904967) (xy 167.02201 -283.951648)
			(xy 167.029905 -284.000225) (xy 167.0304 -284.024832) (xy 167.369248 -284.024832) (xy 167.373208 -283.975778)
			(xy 167.384985 -283.927994) (xy 167.404276 -283.882718) (xy 167.430579 -283.841122) (xy 167.463214 -283.804285)
			(xy 167.501335 -283.77316) (xy 167.543956 -283.748553) (xy 167.589972 -283.731101) (xy 167.638191 -283.721257)
			(xy 167.687366 -283.719276) (xy 167.736221 -283.725208) (xy 167.783492 -283.7389) (xy 167.827954 -283.759998)
			(xy 167.868457 -283.787954) (xy 167.90395 -283.822046) (xy 167.933515 -283.86139) (xy 167.956386 -283.904967)
			(xy 167.97197 -283.951648) (xy 167.979865 -284.000225) (xy 167.98036 -284.024832) (xy 168.319208 -284.024832)
			(xy 168.323168 -283.975778) (xy 168.334945 -283.927994) (xy 168.354236 -283.882718) (xy 168.380539 -283.841122)
			(xy 168.413174 -283.804285) (xy 168.451295 -283.77316) (xy 168.493916 -283.748553) (xy 168.539932 -283.731101)
			(xy 168.588151 -283.721257) (xy 168.637326 -283.719276) (xy 168.686181 -283.725208) (xy 168.733452 -283.7389)
			(xy 168.777914 -283.759998) (xy 168.818417 -283.787954) (xy 168.85391 -283.822046) (xy 168.883475 -283.86139)
			(xy 168.906346 -283.904967) (xy 168.92193 -283.951648) (xy 168.929825 -284.000225) (xy 168.93032 -284.024832)
			(xy 169.269168 -284.024832) (xy 169.273128 -283.975778) (xy 169.284905 -283.927994) (xy 169.304196 -283.882718)
			(xy 169.330499 -283.841122) (xy 169.363134 -283.804285) (xy 169.401255 -283.77316) (xy 169.443876 -283.748553)
			(xy 169.489892 -283.731101) (xy 169.538111 -283.721257) (xy 169.587286 -283.719276) (xy 169.636141 -283.725208)
			(xy 169.683412 -283.7389) (xy 169.727874 -283.759998) (xy 169.768377 -283.787954) (xy 169.80387 -283.822046)
			(xy 169.833435 -283.86139) (xy 169.856306 -283.904967) (xy 169.87189 -283.951648) (xy 169.879785 -284.000225)
			(xy 169.88028 -284.024832) (xy 170.219128 -284.024832) (xy 170.223088 -283.975778) (xy 170.234865 -283.927994)
			(xy 170.254156 -283.882718) (xy 170.280459 -283.841122) (xy 170.313094 -283.804285) (xy 170.351215 -283.77316)
			(xy 170.393836 -283.748553) (xy 170.439852 -283.731101) (xy 170.488071 -283.721257) (xy 170.537246 -283.719276)
			(xy 170.586101 -283.725208) (xy 170.633372 -283.7389) (xy 170.677834 -283.759998) (xy 170.718337 -283.787954)
			(xy 170.75383 -283.822046) (xy 170.783395 -283.86139) (xy 170.806266 -283.904967) (xy 170.82185 -283.951648)
			(xy 170.829745 -284.000225) (xy 170.83024 -284.024832) (xy 171.169088 -284.024832) (xy 171.173048 -283.975778)
			(xy 171.184825 -283.927994) (xy 171.204116 -283.882718) (xy 171.230419 -283.841122) (xy 171.263054 -283.804285)
			(xy 171.301175 -283.77316) (xy 171.343796 -283.748553) (xy 171.389812 -283.731101) (xy 171.438031 -283.721257)
			(xy 171.487206 -283.719276) (xy 171.536061 -283.725208) (xy 171.583332 -283.7389) (xy 171.627794 -283.759998)
			(xy 171.668297 -283.787954) (xy 171.70379 -283.822046) (xy 171.733355 -283.86139) (xy 171.756226 -283.904967)
			(xy 171.77181 -283.951648) (xy 171.779705 -284.000225) (xy 171.7802 -284.024832) (xy 172.119048 -284.024832)
			(xy 172.123008 -283.975778) (xy 172.134785 -283.927994) (xy 172.154076 -283.882718) (xy 172.180379 -283.841122)
			(xy 172.213014 -283.804285) (xy 172.251135 -283.77316) (xy 172.293756 -283.748553) (xy 172.339772 -283.731101)
			(xy 172.387991 -283.721257) (xy 172.437166 -283.719276) (xy 172.486021 -283.725208) (xy 172.533292 -283.7389)
			(xy 172.577754 -283.759998) (xy 172.618257 -283.787954) (xy 172.65375 -283.822046) (xy 172.683315 -283.86139)
			(xy 172.706186 -283.904967) (xy 172.72177 -283.951648) (xy 172.729665 -284.000225) (xy 172.73016 -284.024832)
			(xy 173.069262 -284.024832) (xy 173.073222 -283.975778) (xy 173.084999 -283.927994) (xy 173.10429 -283.882718)
			(xy 173.130593 -283.841122) (xy 173.163228 -283.804285) (xy 173.201349 -283.77316) (xy 173.24397 -283.748553)
			(xy 173.289986 -283.731101) (xy 173.338205 -283.721257) (xy 173.38738 -283.719276) (xy 173.436235 -283.725208)
			(xy 173.483506 -283.7389) (xy 173.527968 -283.759998) (xy 173.568471 -283.787954) (xy 173.603964 -283.822046)
			(xy 173.633529 -283.86139) (xy 173.6564 -283.904967) (xy 173.671984 -283.951648) (xy 173.679879 -284.000225)
			(xy 173.680374 -284.024832) (xy 174.019222 -284.024832) (xy 174.023182 -283.975778) (xy 174.034959 -283.927994)
			(xy 174.05425 -283.882718) (xy 174.080553 -283.841122) (xy 174.113188 -283.804285) (xy 174.151309 -283.77316)
			(xy 174.19393 -283.748553) (xy 174.239946 -283.731101) (xy 174.288165 -283.721257) (xy 174.33734 -283.719276)
			(xy 174.386195 -283.725208) (xy 174.433466 -283.7389) (xy 174.477928 -283.759998) (xy 174.518431 -283.787954)
			(xy 174.553924 -283.822046) (xy 174.583489 -283.86139) (xy 174.60636 -283.904967) (xy 174.621944 -283.951648)
			(xy 174.629839 -284.000225) (xy 174.630334 -284.024832) (xy 175.919142 -284.024832) (xy 175.923102 -283.975778)
			(xy 175.934879 -283.927994) (xy 175.95417 -283.882718) (xy 175.980473 -283.841122) (xy 176.013108 -283.804285)
			(xy 176.051229 -283.77316) (xy 176.09385 -283.748553) (xy 176.139866 -283.731101) (xy 176.188085 -283.721257)
			(xy 176.23726 -283.719276) (xy 176.286115 -283.725208) (xy 176.333386 -283.7389) (xy 176.377848 -283.759998)
			(xy 176.418351 -283.787954) (xy 176.453844 -283.822046) (xy 176.483409 -283.86139) (xy 176.50628 -283.904967)
			(xy 176.521864 -283.951648) (xy 176.529759 -284.000225) (xy 176.530254 -284.024832) (xy 176.869102 -284.024832)
			(xy 176.873062 -283.975778) (xy 176.884839 -283.927994) (xy 176.90413 -283.882718) (xy 176.930433 -283.841122)
			(xy 176.963068 -283.804285) (xy 177.001189 -283.77316) (xy 177.04381 -283.748553) (xy 177.089826 -283.731101)
			(xy 177.138045 -283.721257) (xy 177.18722 -283.719276) (xy 177.236075 -283.725208) (xy 177.283346 -283.7389)
			(xy 177.327808 -283.759998) (xy 177.368311 -283.787954) (xy 177.403804 -283.822046) (xy 177.433369 -283.86139)
			(xy 177.45624 -283.904967) (xy 177.471824 -283.951648) (xy 177.479719 -284.000225) (xy 177.480214 -284.024832)
			(xy 177.819062 -284.024832) (xy 177.823022 -283.975778) (xy 177.834799 -283.927994) (xy 177.85409 -283.882718)
			(xy 177.880393 -283.841122) (xy 177.913028 -283.804285) (xy 177.951149 -283.77316) (xy 177.99377 -283.748553)
			(xy 178.039786 -283.731101) (xy 178.088005 -283.721257) (xy 178.13718 -283.719276) (xy 178.186035 -283.725208)
			(xy 178.233306 -283.7389) (xy 178.277768 -283.759998) (xy 178.318271 -283.787954) (xy 178.353764 -283.822046)
			(xy 178.383329 -283.86139) (xy 178.4062 -283.904967) (xy 178.421784 -283.951648) (xy 178.429679 -284.000225)
			(xy 178.430174 -284.024832) (xy 178.769276 -284.024832) (xy 178.773236 -283.975778) (xy 178.785013 -283.927994)
			(xy 178.804304 -283.882718) (xy 178.830607 -283.841122) (xy 178.863242 -283.804285) (xy 178.901363 -283.77316)
			(xy 178.943984 -283.748553) (xy 178.99 -283.731101) (xy 179.038219 -283.721257) (xy 179.087394 -283.719276)
			(xy 179.136249 -283.725208) (xy 179.18352 -283.7389) (xy 179.227982 -283.759998) (xy 179.268485 -283.787954)
			(xy 179.303978 -283.822046) (xy 179.333543 -283.86139) (xy 179.356414 -283.904967) (xy 179.371998 -283.951648)
			(xy 179.379893 -284.000225) (xy 179.380388 -284.024832) (xy 179.719236 -284.024832) (xy 179.723196 -283.975778)
			(xy 179.734973 -283.927994) (xy 179.754264 -283.882718) (xy 179.780567 -283.841122) (xy 179.813202 -283.804285)
			(xy 179.851323 -283.77316) (xy 179.893944 -283.748553) (xy 179.93996 -283.731101) (xy 179.988179 -283.721257)
			(xy 180.037354 -283.719276) (xy 180.086209 -283.725208) (xy 180.13348 -283.7389) (xy 180.177942 -283.759998)
			(xy 180.218445 -283.787954) (xy 180.253938 -283.822046) (xy 180.283503 -283.86139) (xy 180.306374 -283.904967)
			(xy 180.321958 -283.951648) (xy 180.329853 -284.000225) (xy 180.330348 -284.024832) (xy 180.669196 -284.024832)
			(xy 180.673156 -283.975778) (xy 180.684933 -283.927994) (xy 180.704224 -283.882718) (xy 180.730527 -283.841122)
			(xy 180.763162 -283.804285) (xy 180.801283 -283.77316) (xy 180.843904 -283.748553) (xy 180.88992 -283.731101)
			(xy 180.938139 -283.721257) (xy 180.987314 -283.719276) (xy 181.036169 -283.725208) (xy 181.08344 -283.7389)
			(xy 181.127902 -283.759998) (xy 181.168405 -283.787954) (xy 181.203898 -283.822046) (xy 181.233463 -283.86139)
			(xy 181.256334 -283.904967) (xy 181.271918 -283.951648) (xy 181.279813 -284.000225) (xy 181.280308 -284.024832)
			(xy 181.619156 -284.024832) (xy 181.623116 -283.975778) (xy 181.634893 -283.927994) (xy 181.654184 -283.882718)
			(xy 181.680487 -283.841122) (xy 181.713122 -283.804285) (xy 181.751243 -283.77316) (xy 181.793864 -283.748553)
			(xy 181.83988 -283.731101) (xy 181.888099 -283.721257) (xy 181.937274 -283.719276) (xy 181.986129 -283.725208)
			(xy 182.0334 -283.7389) (xy 182.077862 -283.759998) (xy 182.118365 -283.787954) (xy 182.153858 -283.822046)
			(xy 182.183423 -283.86139) (xy 182.206294 -283.904967) (xy 182.221878 -283.951648) (xy 182.229773 -284.000225)
			(xy 182.230268 -284.024832) (xy 182.569116 -284.024832) (xy 182.573076 -283.975778) (xy 182.584853 -283.927994)
			(xy 182.604144 -283.882718) (xy 182.630447 -283.841122) (xy 182.663082 -283.804285) (xy 182.701203 -283.77316)
			(xy 182.743824 -283.748553) (xy 182.78984 -283.731101) (xy 182.838059 -283.721257) (xy 182.887234 -283.719276)
			(xy 182.936089 -283.725208) (xy 182.98336 -283.7389) (xy 183.027822 -283.759998) (xy 183.068325 -283.787954)
			(xy 183.103818 -283.822046) (xy 183.133383 -283.86139) (xy 183.156254 -283.904967) (xy 183.171838 -283.951648)
			(xy 183.179733 -284.000225) (xy 183.180228 -284.024832) (xy 184.469036 -284.024832) (xy 184.472996 -283.975778)
			(xy 184.484773 -283.927994) (xy 184.504064 -283.882718) (xy 184.530367 -283.841122) (xy 184.563002 -283.804285)
			(xy 184.601123 -283.77316) (xy 184.643744 -283.748553) (xy 184.68976 -283.731101) (xy 184.737979 -283.721257)
			(xy 184.787154 -283.719276) (xy 184.836009 -283.725208) (xy 184.88328 -283.7389) (xy 184.927742 -283.759998)
			(xy 184.968245 -283.787954) (xy 185.003738 -283.822046) (xy 185.033303 -283.86139) (xy 185.056174 -283.904967)
			(xy 185.071758 -283.951648) (xy 185.079653 -284.000225) (xy 185.080148 -284.024832) (xy 185.41925 -284.024832)
			(xy 185.42321 -283.975778) (xy 185.434987 -283.927994) (xy 185.454278 -283.882718) (xy 185.480581 -283.841122)
			(xy 185.513216 -283.804285) (xy 185.551337 -283.77316) (xy 185.593958 -283.748553) (xy 185.639974 -283.731101)
			(xy 185.688193 -283.721257) (xy 185.737368 -283.719276) (xy 185.786223 -283.725208) (xy 185.833494 -283.7389)
			(xy 185.877956 -283.759998) (xy 185.918459 -283.787954) (xy 185.953952 -283.822046) (xy 185.983517 -283.86139)
			(xy 186.006388 -283.904967) (xy 186.021972 -283.951648) (xy 186.029867 -284.000225) (xy 186.030362 -284.024832)
			(xy 186.36921 -284.024832) (xy 186.37317 -283.975778) (xy 186.384947 -283.927994) (xy 186.404238 -283.882718)
			(xy 186.430541 -283.841122) (xy 186.463176 -283.804285) (xy 186.501297 -283.77316) (xy 186.543918 -283.748553)
			(xy 186.589934 -283.731101) (xy 186.638153 -283.721257) (xy 186.687328 -283.719276) (xy 186.736183 -283.725208)
			(xy 186.783454 -283.7389) (xy 186.827916 -283.759998) (xy 186.868419 -283.787954) (xy 186.903912 -283.822046)
			(xy 186.933477 -283.86139) (xy 186.956348 -283.904967) (xy 186.971932 -283.951648) (xy 186.979827 -284.000225)
			(xy 186.980322 -284.024832) (xy 187.31917 -284.024832) (xy 187.32313 -283.975778) (xy 187.334907 -283.927994)
			(xy 187.354198 -283.882718) (xy 187.380501 -283.841122) (xy 187.413136 -283.804285) (xy 187.451257 -283.77316)
			(xy 187.493878 -283.748553) (xy 187.539894 -283.731101) (xy 187.588113 -283.721257) (xy 187.637288 -283.719276)
			(xy 187.686143 -283.725208) (xy 187.733414 -283.7389) (xy 187.777876 -283.759998) (xy 187.818379 -283.787954)
			(xy 187.853872 -283.822046) (xy 187.883437 -283.86139) (xy 187.906308 -283.904967) (xy 187.921892 -283.951648)
			(xy 187.929787 -284.000225) (xy 187.930282 -284.024832) (xy 188.26913 -284.024832) (xy 188.27309 -283.975778)
			(xy 188.284867 -283.927994) (xy 188.304158 -283.882718) (xy 188.330461 -283.841122) (xy 188.363096 -283.804285)
			(xy 188.401217 -283.77316) (xy 188.443838 -283.748553) (xy 188.489854 -283.731101) (xy 188.538073 -283.721257)
			(xy 188.587248 -283.719276) (xy 188.636103 -283.725208) (xy 188.683374 -283.7389) (xy 188.727836 -283.759998)
			(xy 188.768339 -283.787954) (xy 188.803832 -283.822046) (xy 188.833397 -283.86139) (xy 188.856268 -283.904967)
			(xy 188.871852 -283.951648) (xy 188.879747 -284.000225) (xy 188.880242 -284.024832) (xy 188.879747 -284.049439)
			(xy 188.871852 -284.098016) (xy 188.856268 -284.144697) (xy 188.833397 -284.188274) (xy 188.803832 -284.227618)
			(xy 188.768339 -284.26171) (xy 188.727836 -284.289666) (xy 188.683374 -284.310764) (xy 188.636103 -284.324456)
			(xy 188.587248 -284.330388) (xy 188.538073 -284.328407) (xy 188.489854 -284.318563) (xy 188.443838 -284.301111)
			(xy 188.401217 -284.276504) (xy 188.363096 -284.245379) (xy 188.330461 -284.208542) (xy 188.304158 -284.166946)
			(xy 188.284867 -284.12167) (xy 188.27309 -284.073886) (xy 188.26913 -284.024832) (xy 187.930282 -284.024832)
			(xy 187.929787 -284.049439) (xy 187.921892 -284.098016) (xy 187.906308 -284.144697) (xy 187.883437 -284.188274)
			(xy 187.853872 -284.227618) (xy 187.818379 -284.26171) (xy 187.777876 -284.289666) (xy 187.733414 -284.310764)
			(xy 187.686143 -284.324456) (xy 187.637288 -284.330388) (xy 187.588113 -284.328407) (xy 187.539894 -284.318563)
			(xy 187.493878 -284.301111) (xy 187.451257 -284.276504) (xy 187.413136 -284.245379) (xy 187.380501 -284.208542)
			(xy 187.354198 -284.166946) (xy 187.334907 -284.12167) (xy 187.32313 -284.073886) (xy 187.31917 -284.024832)
			(xy 186.980322 -284.024832) (xy 186.979827 -284.049439) (xy 186.971932 -284.098016) (xy 186.956348 -284.144697)
			(xy 186.933477 -284.188274) (xy 186.903912 -284.227618) (xy 186.868419 -284.26171) (xy 186.827916 -284.289666)
			(xy 186.783454 -284.310764) (xy 186.736183 -284.324456) (xy 186.687328 -284.330388) (xy 186.638153 -284.328407)
			(xy 186.589934 -284.318563) (xy 186.543918 -284.301111) (xy 186.501297 -284.276504) (xy 186.463176 -284.245379)
			(xy 186.430541 -284.208542) (xy 186.404238 -284.166946) (xy 186.384947 -284.12167) (xy 186.37317 -284.073886)
			(xy 186.36921 -284.024832) (xy 186.030362 -284.024832) (xy 186.029867 -284.049439) (xy 186.021972 -284.098016)
			(xy 186.006388 -284.144697) (xy 185.983517 -284.188274) (xy 185.953952 -284.227618) (xy 185.918459 -284.26171)
			(xy 185.877956 -284.289666) (xy 185.833494 -284.310764) (xy 185.786223 -284.324456) (xy 185.737368 -284.330388)
			(xy 185.688193 -284.328407) (xy 185.639974 -284.318563) (xy 185.593958 -284.301111) (xy 185.551337 -284.276504)
			(xy 185.513216 -284.245379) (xy 185.480581 -284.208542) (xy 185.454278 -284.166946) (xy 185.434987 -284.12167)
			(xy 185.42321 -284.073886) (xy 185.41925 -284.024832) (xy 185.080148 -284.024832) (xy 185.079653 -284.049439)
			(xy 185.071758 -284.098016) (xy 185.056174 -284.144697) (xy 185.033303 -284.188274) (xy 185.003738 -284.227618)
			(xy 184.968245 -284.26171) (xy 184.927742 -284.289666) (xy 184.88328 -284.310764) (xy 184.836009 -284.324456)
			(xy 184.787154 -284.330388) (xy 184.737979 -284.328407) (xy 184.68976 -284.318563) (xy 184.643744 -284.301111)
			(xy 184.601123 -284.276504) (xy 184.563002 -284.245379) (xy 184.530367 -284.208542) (xy 184.504064 -284.166946)
			(xy 184.484773 -284.12167) (xy 184.472996 -284.073886) (xy 184.469036 -284.024832) (xy 183.180228 -284.024832)
			(xy 183.179733 -284.049439) (xy 183.171838 -284.098016) (xy 183.156254 -284.144697) (xy 183.133383 -284.188274)
			(xy 183.103818 -284.227618) (xy 183.068325 -284.26171) (xy 183.027822 -284.289666) (xy 182.98336 -284.310764)
			(xy 182.936089 -284.324456) (xy 182.887234 -284.330388) (xy 182.838059 -284.328407) (xy 182.78984 -284.318563)
			(xy 182.743824 -284.301111) (xy 182.701203 -284.276504) (xy 182.663082 -284.245379) (xy 182.630447 -284.208542)
			(xy 182.604144 -284.166946) (xy 182.584853 -284.12167) (xy 182.573076 -284.073886) (xy 182.569116 -284.024832)
			(xy 182.230268 -284.024832) (xy 182.229773 -284.049439) (xy 182.221878 -284.098016) (xy 182.206294 -284.144697)
			(xy 182.183423 -284.188274) (xy 182.153858 -284.227618) (xy 182.118365 -284.26171) (xy 182.077862 -284.289666)
			(xy 182.0334 -284.310764) (xy 181.986129 -284.324456) (xy 181.937274 -284.330388) (xy 181.888099 -284.328407)
			(xy 181.83988 -284.318563) (xy 181.793864 -284.301111) (xy 181.751243 -284.276504) (xy 181.713122 -284.245379)
			(xy 181.680487 -284.208542) (xy 181.654184 -284.166946) (xy 181.634893 -284.12167) (xy 181.623116 -284.073886)
			(xy 181.619156 -284.024832) (xy 181.280308 -284.024832) (xy 181.279813 -284.049439) (xy 181.271918 -284.098016)
			(xy 181.256334 -284.144697) (xy 181.233463 -284.188274) (xy 181.203898 -284.227618) (xy 181.168405 -284.26171)
			(xy 181.127902 -284.289666) (xy 181.08344 -284.310764) (xy 181.036169 -284.324456) (xy 180.987314 -284.330388)
			(xy 180.938139 -284.328407) (xy 180.88992 -284.318563) (xy 180.843904 -284.301111) (xy 180.801283 -284.276504)
			(xy 180.763162 -284.245379) (xy 180.730527 -284.208542) (xy 180.704224 -284.166946) (xy 180.684933 -284.12167)
			(xy 180.673156 -284.073886) (xy 180.669196 -284.024832) (xy 180.330348 -284.024832) (xy 180.329853 -284.049439)
			(xy 180.321958 -284.098016) (xy 180.306374 -284.144697) (xy 180.283503 -284.188274) (xy 180.253938 -284.227618)
			(xy 180.218445 -284.26171) (xy 180.177942 -284.289666) (xy 180.13348 -284.310764) (xy 180.086209 -284.324456)
			(xy 180.037354 -284.330388) (xy 179.988179 -284.328407) (xy 179.93996 -284.318563) (xy 179.893944 -284.301111)
			(xy 179.851323 -284.276504) (xy 179.813202 -284.245379) (xy 179.780567 -284.208542) (xy 179.754264 -284.166946)
			(xy 179.734973 -284.12167) (xy 179.723196 -284.073886) (xy 179.719236 -284.024832) (xy 179.380388 -284.024832)
			(xy 179.379893 -284.049439) (xy 179.371998 -284.098016) (xy 179.356414 -284.144697) (xy 179.333543 -284.188274)
			(xy 179.303978 -284.227618) (xy 179.268485 -284.26171) (xy 179.227982 -284.289666) (xy 179.18352 -284.310764)
			(xy 179.136249 -284.324456) (xy 179.087394 -284.330388) (xy 179.038219 -284.328407) (xy 178.99 -284.318563)
			(xy 178.943984 -284.301111) (xy 178.901363 -284.276504) (xy 178.863242 -284.245379) (xy 178.830607 -284.208542)
			(xy 178.804304 -284.166946) (xy 178.785013 -284.12167) (xy 178.773236 -284.073886) (xy 178.769276 -284.024832)
			(xy 178.430174 -284.024832) (xy 178.429679 -284.049439) (xy 178.421784 -284.098016) (xy 178.4062 -284.144697)
			(xy 178.383329 -284.188274) (xy 178.353764 -284.227618) (xy 178.318271 -284.26171) (xy 178.277768 -284.289666)
			(xy 178.233306 -284.310764) (xy 178.186035 -284.324456) (xy 178.13718 -284.330388) (xy 178.088005 -284.328407)
			(xy 178.039786 -284.318563) (xy 177.99377 -284.301111) (xy 177.951149 -284.276504) (xy 177.913028 -284.245379)
			(xy 177.880393 -284.208542) (xy 177.85409 -284.166946) (xy 177.834799 -284.12167) (xy 177.823022 -284.073886)
			(xy 177.819062 -284.024832) (xy 177.480214 -284.024832) (xy 177.479719 -284.049439) (xy 177.471824 -284.098016)
			(xy 177.45624 -284.144697) (xy 177.433369 -284.188274) (xy 177.403804 -284.227618) (xy 177.368311 -284.26171)
			(xy 177.327808 -284.289666) (xy 177.283346 -284.310764) (xy 177.236075 -284.324456) (xy 177.18722 -284.330388)
			(xy 177.138045 -284.328407) (xy 177.089826 -284.318563) (xy 177.04381 -284.301111) (xy 177.001189 -284.276504)
			(xy 176.963068 -284.245379) (xy 176.930433 -284.208542) (xy 176.90413 -284.166946) (xy 176.884839 -284.12167)
			(xy 176.873062 -284.073886) (xy 176.869102 -284.024832) (xy 176.530254 -284.024832) (xy 176.529759 -284.049439)
			(xy 176.521864 -284.098016) (xy 176.50628 -284.144697) (xy 176.483409 -284.188274) (xy 176.453844 -284.227618)
			(xy 176.418351 -284.26171) (xy 176.377848 -284.289666) (xy 176.333386 -284.310764) (xy 176.286115 -284.324456)
			(xy 176.23726 -284.330388) (xy 176.188085 -284.328407) (xy 176.139866 -284.318563) (xy 176.09385 -284.301111)
			(xy 176.051229 -284.276504) (xy 176.013108 -284.245379) (xy 175.980473 -284.208542) (xy 175.95417 -284.166946)
			(xy 175.934879 -284.12167) (xy 175.923102 -284.073886) (xy 175.919142 -284.024832) (xy 174.630334 -284.024832)
			(xy 174.629839 -284.049439) (xy 174.621944 -284.098016) (xy 174.60636 -284.144697) (xy 174.583489 -284.188274)
			(xy 174.553924 -284.227618) (xy 174.518431 -284.26171) (xy 174.477928 -284.289666) (xy 174.433466 -284.310764)
			(xy 174.386195 -284.324456) (xy 174.33734 -284.330388) (xy 174.288165 -284.328407) (xy 174.239946 -284.318563)
			(xy 174.19393 -284.301111) (xy 174.151309 -284.276504) (xy 174.113188 -284.245379) (xy 174.080553 -284.208542)
			(xy 174.05425 -284.166946) (xy 174.034959 -284.12167) (xy 174.023182 -284.073886) (xy 174.019222 -284.024832)
			(xy 173.680374 -284.024832) (xy 173.679879 -284.049439) (xy 173.671984 -284.098016) (xy 173.6564 -284.144697)
			(xy 173.633529 -284.188274) (xy 173.603964 -284.227618) (xy 173.568471 -284.26171) (xy 173.527968 -284.289666)
			(xy 173.483506 -284.310764) (xy 173.436235 -284.324456) (xy 173.38738 -284.330388) (xy 173.338205 -284.328407)
			(xy 173.289986 -284.318563) (xy 173.24397 -284.301111) (xy 173.201349 -284.276504) (xy 173.163228 -284.245379)
			(xy 173.130593 -284.208542) (xy 173.10429 -284.166946) (xy 173.084999 -284.12167) (xy 173.073222 -284.073886)
			(xy 173.069262 -284.024832) (xy 172.73016 -284.024832) (xy 172.729665 -284.049439) (xy 172.72177 -284.098016)
			(xy 172.706186 -284.144697) (xy 172.683315 -284.188274) (xy 172.65375 -284.227618) (xy 172.618257 -284.26171)
			(xy 172.577754 -284.289666) (xy 172.533292 -284.310764) (xy 172.486021 -284.324456) (xy 172.437166 -284.330388)
			(xy 172.387991 -284.328407) (xy 172.339772 -284.318563) (xy 172.293756 -284.301111) (xy 172.251135 -284.276504)
			(xy 172.213014 -284.245379) (xy 172.180379 -284.208542) (xy 172.154076 -284.166946) (xy 172.134785 -284.12167)
			(xy 172.123008 -284.073886) (xy 172.119048 -284.024832) (xy 171.7802 -284.024832) (xy 171.779705 -284.049439)
			(xy 171.77181 -284.098016) (xy 171.756226 -284.144697) (xy 171.733355 -284.188274) (xy 171.70379 -284.227618)
			(xy 171.668297 -284.26171) (xy 171.627794 -284.289666) (xy 171.583332 -284.310764) (xy 171.536061 -284.324456)
			(xy 171.487206 -284.330388) (xy 171.438031 -284.328407) (xy 171.389812 -284.318563) (xy 171.343796 -284.301111)
			(xy 171.301175 -284.276504) (xy 171.263054 -284.245379) (xy 171.230419 -284.208542) (xy 171.204116 -284.166946)
			(xy 171.184825 -284.12167) (xy 171.173048 -284.073886) (xy 171.169088 -284.024832) (xy 170.83024 -284.024832)
			(xy 170.829745 -284.049439) (xy 170.82185 -284.098016) (xy 170.806266 -284.144697) (xy 170.783395 -284.188274)
			(xy 170.75383 -284.227618) (xy 170.718337 -284.26171) (xy 170.677834 -284.289666) (xy 170.633372 -284.310764)
			(xy 170.586101 -284.324456) (xy 170.537246 -284.330388) (xy 170.488071 -284.328407) (xy 170.439852 -284.318563)
			(xy 170.393836 -284.301111) (xy 170.351215 -284.276504) (xy 170.313094 -284.245379) (xy 170.280459 -284.208542)
			(xy 170.254156 -284.166946) (xy 170.234865 -284.12167) (xy 170.223088 -284.073886) (xy 170.219128 -284.024832)
			(xy 169.88028 -284.024832) (xy 169.879785 -284.049439) (xy 169.87189 -284.098016) (xy 169.856306 -284.144697)
			(xy 169.833435 -284.188274) (xy 169.80387 -284.227618) (xy 169.768377 -284.26171) (xy 169.727874 -284.289666)
			(xy 169.683412 -284.310764) (xy 169.636141 -284.324456) (xy 169.587286 -284.330388) (xy 169.538111 -284.328407)
			(xy 169.489892 -284.318563) (xy 169.443876 -284.301111) (xy 169.401255 -284.276504) (xy 169.363134 -284.245379)
			(xy 169.330499 -284.208542) (xy 169.304196 -284.166946) (xy 169.284905 -284.12167) (xy 169.273128 -284.073886)
			(xy 169.269168 -284.024832) (xy 168.93032 -284.024832) (xy 168.929825 -284.049439) (xy 168.92193 -284.098016)
			(xy 168.906346 -284.144697) (xy 168.883475 -284.188274) (xy 168.85391 -284.227618) (xy 168.818417 -284.26171)
			(xy 168.777914 -284.289666) (xy 168.733452 -284.310764) (xy 168.686181 -284.324456) (xy 168.637326 -284.330388)
			(xy 168.588151 -284.328407) (xy 168.539932 -284.318563) (xy 168.493916 -284.301111) (xy 168.451295 -284.276504)
			(xy 168.413174 -284.245379) (xy 168.380539 -284.208542) (xy 168.354236 -284.166946) (xy 168.334945 -284.12167)
			(xy 168.323168 -284.073886) (xy 168.319208 -284.024832) (xy 167.98036 -284.024832) (xy 167.979865 -284.049439)
			(xy 167.97197 -284.098016) (xy 167.956386 -284.144697) (xy 167.933515 -284.188274) (xy 167.90395 -284.227618)
			(xy 167.868457 -284.26171) (xy 167.827954 -284.289666) (xy 167.783492 -284.310764) (xy 167.736221 -284.324456)
			(xy 167.687366 -284.330388) (xy 167.638191 -284.328407) (xy 167.589972 -284.318563) (xy 167.543956 -284.301111)
			(xy 167.501335 -284.276504) (xy 167.463214 -284.245379) (xy 167.430579 -284.208542) (xy 167.404276 -284.166946)
			(xy 167.384985 -284.12167) (xy 167.373208 -284.073886) (xy 167.369248 -284.024832) (xy 167.0304 -284.024832)
			(xy 167.029905 -284.049439) (xy 167.02201 -284.098016) (xy 167.006426 -284.144697) (xy 166.983555 -284.188274)
			(xy 166.95399 -284.227618) (xy 166.918497 -284.26171) (xy 166.877994 -284.289666) (xy 166.833532 -284.310764)
			(xy 166.786261 -284.324456) (xy 166.737406 -284.330388) (xy 166.688231 -284.328407) (xy 166.640012 -284.318563)
			(xy 166.593996 -284.301111) (xy 166.551375 -284.276504) (xy 166.513254 -284.245379) (xy 166.480619 -284.208542)
			(xy 166.454316 -284.166946) (xy 166.435025 -284.12167) (xy 166.423248 -284.073886) (xy 166.419288 -284.024832)
			(xy 166.080186 -284.024832) (xy 166.079691 -284.049439) (xy 166.071796 -284.098016) (xy 166.056212 -284.144697)
			(xy 166.033341 -284.188274) (xy 166.003776 -284.227618) (xy 165.968283 -284.26171) (xy 165.92778 -284.289666)
			(xy 165.883318 -284.310764) (xy 165.836047 -284.324456) (xy 165.787192 -284.330388) (xy 165.738017 -284.328407)
			(xy 165.689798 -284.318563) (xy 165.643782 -284.301111) (xy 165.601161 -284.276504) (xy 165.56304 -284.245379)
			(xy 165.530405 -284.208542) (xy 165.504102 -284.166946) (xy 165.484811 -284.12167) (xy 165.473034 -284.073886)
			(xy 165.469074 -284.024832) (xy 165.155052 -284.024832) (xy 165.155052 -284.051183) (xy 165.146674 -284.103272)
			(xy 165.130131 -284.15337) (xy 165.105844 -284.200205) (xy 165.074428 -284.242589) (xy 165.03668 -284.279448)
			(xy 164.993559 -284.309845) (xy 164.946158 -284.333009) (xy 164.895681 -284.348353) (xy 164.869622 -284.352492)
			(xy 164.86505 -284.353254) (xy 164.852858 -284.357064) (xy 164.849556 -284.35808) (xy 164.826188 -284.369002)
			(xy 164.819584 -284.376114) (xy 164.804852 -284.391608) (xy 164.796724 -284.402784) (xy 164.794027 -284.408315)
			(xy 164.791072 -284.420256) (xy 164.790882 -284.426406) (xy 164.790882 -284.499812) (xy 189.69407 -284.499812)
			(xy 189.69803 -284.450758) (xy 189.709807 -284.402974) (xy 189.729098 -284.357698) (xy 189.755401 -284.316102)
			(xy 189.788036 -284.279265) (xy 189.826157 -284.24814) (xy 189.868778 -284.223533) (xy 189.914794 -284.206081)
			(xy 189.963013 -284.196237) (xy 190.012188 -284.194256) (xy 190.061043 -284.200188) (xy 190.108314 -284.21388)
			(xy 190.152776 -284.234978) (xy 190.193279 -284.262934) (xy 190.228772 -284.297026) (xy 190.258337 -284.33637)
			(xy 190.281208 -284.379947) (xy 190.296792 -284.426628) (xy 190.304687 -284.475205) (xy 190.305182 -284.499812)
			(xy 190.64403 -284.499812) (xy 190.64799 -284.450758) (xy 190.659767 -284.402974) (xy 190.679058 -284.357698)
			(xy 190.705361 -284.316102) (xy 190.737996 -284.279265) (xy 190.776117 -284.24814) (xy 190.818738 -284.223533)
			(xy 190.864754 -284.206081) (xy 190.912973 -284.196237) (xy 190.962148 -284.194256) (xy 191.011003 -284.200188)
			(xy 191.058274 -284.21388) (xy 191.102736 -284.234978) (xy 191.143239 -284.262934) (xy 191.178732 -284.297026)
			(xy 191.208297 -284.33637) (xy 191.231168 -284.379947) (xy 191.246752 -284.426628) (xy 191.254647 -284.475205)
			(xy 191.255142 -284.499812) (xy 191.594244 -284.499812) (xy 191.598204 -284.450758) (xy 191.609981 -284.402974)
			(xy 191.629272 -284.357698) (xy 191.655575 -284.316102) (xy 191.68821 -284.279265) (xy 191.726331 -284.24814)
			(xy 191.768952 -284.223533) (xy 191.814968 -284.206081) (xy 191.863187 -284.196237) (xy 191.912362 -284.194256)
			(xy 191.961217 -284.200188) (xy 192.008488 -284.21388) (xy 192.05295 -284.234978) (xy 192.093453 -284.262934)
			(xy 192.128946 -284.297026) (xy 192.158511 -284.33637) (xy 192.181382 -284.379947) (xy 192.196966 -284.426628)
			(xy 192.204861 -284.475205) (xy 192.205356 -284.499812) (xy 192.204861 -284.524419) (xy 192.204682 -284.52552)
			(xy 192.52336 -284.52552) (xy 192.52336 -284.474104) (xy 192.531403 -284.423322) (xy 192.547291 -284.374423)
			(xy 192.570634 -284.328611) (xy 192.600855 -284.287015) (xy 192.637211 -284.250659) (xy 192.678807 -284.220438)
			(xy 192.724619 -284.197095) (xy 192.773518 -284.181207) (xy 192.8243 -284.173164) (xy 192.875716 -284.173164)
			(xy 192.926498 -284.181207) (xy 192.975397 -284.197095) (xy 193.021209 -284.220438) (xy 193.062805 -284.250659)
			(xy 193.099161 -284.287015) (xy 193.129382 -284.328611) (xy 193.152725 -284.374423) (xy 193.168613 -284.423322)
			(xy 193.176656 -284.474104) (xy 193.17716 -284.499812) (xy 193.176656 -284.52552) (xy 193.47332 -284.52552)
			(xy 193.47332 -284.474104) (xy 193.481363 -284.423322) (xy 193.497251 -284.374423) (xy 193.520594 -284.328611)
			(xy 193.550815 -284.287015) (xy 193.587171 -284.250659) (xy 193.628767 -284.220438) (xy 193.674579 -284.197095)
			(xy 193.723478 -284.181207) (xy 193.77426 -284.173164) (xy 193.825676 -284.173164) (xy 193.876458 -284.181207)
			(xy 193.925357 -284.197095) (xy 193.971169 -284.220438) (xy 194.012765 -284.250659) (xy 194.049121 -284.287015)
			(xy 194.079342 -284.328611) (xy 194.102685 -284.374423) (xy 194.118573 -284.423322) (xy 194.126616 -284.474104)
			(xy 194.12712 -284.499812) (xy 194.444124 -284.499812) (xy 194.448084 -284.450758) (xy 194.459861 -284.402974)
			(xy 194.479152 -284.357698) (xy 194.505455 -284.316102) (xy 194.53809 -284.279265) (xy 194.576211 -284.24814)
			(xy 194.618832 -284.223533) (xy 194.664848 -284.206081) (xy 194.713067 -284.196237) (xy 194.762242 -284.194256)
			(xy 194.811097 -284.200188) (xy 194.858368 -284.21388) (xy 194.90283 -284.234978) (xy 194.943333 -284.262934)
			(xy 194.978826 -284.297026) (xy 195.008391 -284.33637) (xy 195.031262 -284.379947) (xy 195.046846 -284.426628)
			(xy 195.054741 -284.475205) (xy 195.055236 -284.499812) (xy 195.054741 -284.524419) (xy 195.054562 -284.52552)
			(xy 195.37324 -284.52552) (xy 195.37324 -284.474104) (xy 195.381283 -284.423322) (xy 195.397171 -284.374423)
			(xy 195.420514 -284.328611) (xy 195.450735 -284.287015) (xy 195.487091 -284.250659) (xy 195.528687 -284.220438)
			(xy 195.574499 -284.197095) (xy 195.623398 -284.181207) (xy 195.67418 -284.173164) (xy 195.725596 -284.173164)
			(xy 195.776378 -284.181207) (xy 195.825277 -284.197095) (xy 195.871089 -284.220438) (xy 195.912685 -284.250659)
			(xy 195.949041 -284.287015) (xy 195.979262 -284.328611) (xy 196.002605 -284.374423) (xy 196.018493 -284.423322)
			(xy 196.026536 -284.474104) (xy 196.02704 -284.499812) (xy 196.026536 -284.52552) (xy 196.3232 -284.52552)
			(xy 196.3232 -284.474104) (xy 196.331243 -284.423322) (xy 196.347131 -284.374423) (xy 196.370474 -284.328611)
			(xy 196.400695 -284.287015) (xy 196.437051 -284.250659) (xy 196.478647 -284.220438) (xy 196.524459 -284.197095)
			(xy 196.573358 -284.181207) (xy 196.62414 -284.173164) (xy 196.675556 -284.173164) (xy 196.726338 -284.181207)
			(xy 196.775237 -284.197095) (xy 196.821049 -284.220438) (xy 196.862645 -284.250659) (xy 196.899001 -284.287015)
			(xy 196.929222 -284.328611) (xy 196.952565 -284.374423) (xy 196.968453 -284.423322) (xy 196.976496 -284.474104)
			(xy 196.977 -284.499812) (xy 197.294258 -284.499812) (xy 197.298218 -284.450758) (xy 197.309995 -284.402974)
			(xy 197.329286 -284.357698) (xy 197.355589 -284.316102) (xy 197.388224 -284.279265) (xy 197.426345 -284.24814)
			(xy 197.468966 -284.223533) (xy 197.514982 -284.206081) (xy 197.563201 -284.196237) (xy 197.612376 -284.194256)
			(xy 197.661231 -284.200188) (xy 197.708502 -284.21388) (xy 197.752964 -284.234978) (xy 197.793467 -284.262934)
			(xy 197.82896 -284.297026) (xy 197.858525 -284.33637) (xy 197.881396 -284.379947) (xy 197.89698 -284.426628)
			(xy 197.904875 -284.475205) (xy 197.90537 -284.499812) (xy 198.244218 -284.499812) (xy 198.248178 -284.450758)
			(xy 198.259955 -284.402974) (xy 198.279246 -284.357698) (xy 198.305549 -284.316102) (xy 198.338184 -284.279265)
			(xy 198.376305 -284.24814) (xy 198.418926 -284.223533) (xy 198.464942 -284.206081) (xy 198.513161 -284.196237)
			(xy 198.562336 -284.194256) (xy 198.611191 -284.200188) (xy 198.658462 -284.21388) (xy 198.702924 -284.234978)
			(xy 198.743427 -284.262934) (xy 198.77892 -284.297026) (xy 198.808485 -284.33637) (xy 198.831356 -284.379947)
			(xy 198.84694 -284.426628) (xy 198.854835 -284.475205) (xy 198.85533 -284.499812) (xy 198.854835 -284.524419)
			(xy 198.84694 -284.572996) (xy 198.831356 -284.619677) (xy 198.824812 -284.632146) (xy 210.027772 -284.632146)
			(xy 210.031843 -284.576524) (xy 210.043969 -284.522087) (xy 210.063892 -284.469996) (xy 210.091188 -284.421361)
			(xy 210.125274 -284.377218) (xy 210.165423 -284.338509) (xy 210.210781 -284.306058) (xy 210.260381 -284.280557)
			(xy 210.313165 -284.26255) (xy 210.368008 -284.25242) (xy 210.423742 -284.250383) (xy 210.479179 -284.256483)
			(xy 210.533136 -284.270589) (xy 210.584465 -284.292401) (xy 210.632071 -284.321455) (xy 210.674939 -284.35713)
			(xy 210.712156 -284.398667) (xy 210.742929 -284.44518) (xy 210.766601 -284.495677) (xy 210.782669 -284.549084)
			(xy 210.790789 -284.60426) (xy 210.791298 -284.632146) (xy 210.790789 -284.660032) (xy 210.789506 -284.668747)
			(xy 216.926722 -284.668747) (xy 216.926722 -284.614253) (xy 216.934477 -284.560315) (xy 216.949829 -284.508029)
			(xy 216.972465 -284.458459) (xy 217.001925 -284.412616) (xy 217.037609 -284.371431) (xy 217.07879 -284.335744)
			(xy 217.124631 -284.30628) (xy 217.174199 -284.28364) (xy 217.226483 -284.268284) (xy 217.280421 -284.260524)
			(xy 217.307668 -284.260036) (xy 217.336408 -284.260535) (xy 217.393235 -284.269167) (xy 217.448126 -284.286223)
			(xy 217.499837 -284.31132) (xy 217.547199 -284.343888) (xy 217.568526 -284.36316) (xy 217.575638 -284.369764)
			(xy 217.593164 -284.376876) (xy 217.682572 -284.376876) (xy 217.700098 -284.369764) (xy 217.70721 -284.36316)
			(xy 217.728553 -284.343908) (xy 217.775911 -284.311338) (xy 217.827618 -284.286242) (xy 217.882505 -284.269187)
			(xy 217.93933 -284.260559) (xy 217.968068 -284.260036) (xy 217.99819 -284.260631) (xy 218.057685 -284.270107)
			(xy 218.114953 -284.288812) (xy 218.16857 -284.316282) (xy 218.217206 -284.351836) (xy 218.238832 -284.372812)
			(xy 218.245944 -284.380178) (xy 218.26474 -284.387798) (xy 218.357196 -284.387798) (xy 218.375992 -284.380178)
			(xy 218.383104 -284.372812) (xy 218.404706 -284.351807) (xy 218.453341 -284.316241) (xy 218.506963 -284.288766)
			(xy 218.564238 -284.270063) (xy 218.623742 -284.2606) (xy 218.653868 -284.260036) (xy 218.681238 -284.260512)
			(xy 218.735417 -284.268326) (xy 218.78792 -284.283812) (xy 218.837667 -284.306652) (xy 218.883634 -284.336375)
			(xy 218.904566 -284.354016) (xy 218.911678 -284.360112) (xy 218.928696 -284.366462) (xy 219.01404 -284.366462)
			(xy 219.031058 -284.360112) (xy 219.03817 -284.354016) (xy 219.059105 -284.33638) (xy 219.105076 -284.306667)
			(xy 219.154823 -284.28383) (xy 219.207324 -284.268339) (xy 219.261499 -284.26051) (xy 219.288868 -284.260036)
			(xy 219.316126 -284.260409) (xy 219.370086 -284.268163) (xy 219.422394 -284.283518) (xy 219.471984 -284.306161)
			(xy 219.517846 -284.335632) (xy 219.559048 -284.37133) (xy 219.594749 -284.412528) (xy 219.624223 -284.458388)
			(xy 219.646871 -284.507976) (xy 219.66223 -284.560283) (xy 219.669989 -284.614243) (xy 219.669989 -284.668746)
			(xy 220.945522 -284.668746) (xy 220.945522 -284.614254) (xy 220.953276 -284.560316) (xy 220.968628 -284.508031)
			(xy 220.991263 -284.458463) (xy 221.020722 -284.41262) (xy 221.056404 -284.371435) (xy 221.097584 -284.335748)
			(xy 221.143424 -284.306284) (xy 221.19299 -284.283643) (xy 221.245273 -284.268286) (xy 221.29921 -284.260525)
			(xy 221.326456 -284.260036) (xy 221.355195 -284.260543) (xy 221.412023 -284.269172) (xy 221.466913 -284.286227)
			(xy 221.518624 -284.311322) (xy 221.565987 -284.343889) (xy 221.587314 -284.36316) (xy 221.594426 -284.369764)
			(xy 221.611952 -284.376876) (xy 221.70136 -284.376876) (xy 221.718886 -284.369764) (xy 221.725998 -284.36316)
			(xy 221.747325 -284.34389) (xy 221.794688 -284.311325) (xy 221.846399 -284.286234) (xy 221.90129 -284.269184)
			(xy 221.958117 -284.260562) (xy 222.015595 -284.260562) (xy 222.072422 -284.269184) (xy 222.127313 -284.286234)
			(xy 222.179024 -284.311325) (xy 222.226387 -284.34389) (xy 222.247714 -284.36316) (xy 222.254826 -284.369764)
			(xy 222.272352 -284.376876) (xy 222.36176 -284.376876) (xy 222.379286 -284.369764) (xy 222.386398 -284.36316)
			(xy 222.407705 -284.343866) (xy 222.455072 -284.311302) (xy 222.506789 -284.286214) (xy 222.561684 -284.269169)
			(xy 222.618516 -284.260553) (xy 222.647256 -284.260036) (xy 222.677378 -284.260638) (xy 222.736873 -284.270112)
			(xy 222.79414 -284.288816) (xy 222.847758 -284.316285) (xy 222.896394 -284.351836) (xy 222.91802 -284.372812)
			(xy 222.925132 -284.380178) (xy 222.943928 -284.387798) (xy 223.036384 -284.387798) (xy 223.05518 -284.380178)
			(xy 223.062292 -284.372812) (xy 223.083899 -284.351813) (xy 223.132533 -284.316246) (xy 223.186153 -284.28877)
			(xy 223.243428 -284.270066) (xy 223.30293 -284.260601) (xy 223.333056 -284.260036) (xy 223.360314 -284.260408)
			(xy 223.414276 -284.268161) (xy 223.466585 -284.283515) (xy 223.516177 -284.306157) (xy 223.562041 -284.335628)
			(xy 223.603243 -284.371325) (xy 223.638946 -284.412524) (xy 223.668422 -284.458385) (xy 223.69107 -284.507973)
			(xy 223.70643 -284.560281) (xy 223.714189 -284.614242) (xy 223.714189 -284.668758) (xy 223.70643 -284.722719)
			(xy 223.69107 -284.775027) (xy 223.668422 -284.824615) (xy 223.638946 -284.870476) (xy 223.603243 -284.911675)
			(xy 223.562041 -284.947372) (xy 223.516177 -284.976843) (xy 223.466585 -284.999485) (xy 223.414276 -285.014839)
			(xy 223.360314 -285.022592) (xy 223.333056 -285.023052) (xy 223.302934 -285.022445) (xy 223.243439 -285.012973)
			(xy 223.186172 -284.99427) (xy 223.132554 -284.966802) (xy 223.083918 -284.931251) (xy 223.062292 -284.910276)
			(xy 223.05518 -284.90291) (xy 223.036384 -284.89529) (xy 222.943928 -284.89529) (xy 222.925132 -284.90291)
			(xy 222.91802 -284.910276) (xy 222.896406 -284.931268) (xy 222.847774 -284.966835) (xy 222.794155 -284.994314)
			(xy 222.736883 -285.013019) (xy 222.677381 -285.022486) (xy 222.647256 -285.023052) (xy 222.618517 -285.022541)
			(xy 222.561689 -285.013913) (xy 222.506799 -284.996859) (xy 222.455088 -284.971765) (xy 222.407725 -284.939199)
			(xy 222.386398 -284.919928) (xy 222.379286 -284.913324) (xy 222.36176 -284.906212) (xy 222.272352 -284.906212)
			(xy 222.254826 -284.913324) (xy 222.247714 -284.919928) (xy 222.226387 -284.939198) (xy 222.179024 -284.971763)
			(xy 222.127313 -284.996854) (xy 222.072422 -285.013904) (xy 222.015595 -285.022526) (xy 221.958117 -285.022526)
			(xy 221.90129 -285.013904) (xy 221.846399 -284.996854) (xy 221.794688 -284.971763) (xy 221.747325 -284.939198)
			(xy 221.725998 -284.919928) (xy 221.718886 -284.913324) (xy 221.70136 -284.906212) (xy 221.611952 -284.906212)
			(xy 221.594426 -284.913324) (xy 221.587314 -284.919928) (xy 221.566 -284.939214) (xy 221.518635 -284.971779)
			(xy 221.46692 -284.99687) (xy 221.412026 -285.013916) (xy 221.355196 -285.022534) (xy 221.326456 -285.023052)
			(xy 221.29921 -285.022475) (xy 221.245273 -285.014714) (xy 221.19299 -284.999357) (xy 221.143424 -284.976716)
			(xy 221.097584 -284.947252) (xy 221.056404 -284.911565) (xy 221.020722 -284.87038) (xy 220.991263 -284.824537)
			(xy 220.968628 -284.774969) (xy 220.953276 -284.722684) (xy 220.945522 -284.668746) (xy 219.669989 -284.668746)
			(xy 219.669989 -284.668757) (xy 219.66223 -284.722717) (xy 219.646871 -284.775024) (xy 219.624223 -284.824612)
			(xy 219.594749 -284.870472) (xy 219.559048 -284.91167) (xy 219.517846 -284.947368) (xy 219.471984 -284.976839)
			(xy 219.422394 -284.999482) (xy 219.370086 -285.014837) (xy 219.316126 -285.022591) (xy 219.288868 -285.023052)
			(xy 219.261497 -285.022616) (xy 219.207316 -285.014793) (xy 219.154812 -284.999297) (xy 219.105065 -284.976449)
			(xy 219.0591 -284.946717) (xy 219.03817 -284.929072) (xy 219.031058 -284.922976) (xy 219.01404 -284.916626)
			(xy 218.928696 -284.916626) (xy 218.911678 -284.922976) (xy 218.904566 -284.929072) (xy 218.883616 -284.946689)
			(xy 218.837649 -284.976405) (xy 218.787906 -284.999246) (xy 218.735409 -285.014742) (xy 218.681236 -285.022575)
			(xy 218.653868 -285.023052) (xy 218.623744 -285.022501) (xy 218.564247 -285.013015) (xy 218.506978 -284.994299)
			(xy 218.453362 -284.966819) (xy 218.404728 -284.931257) (xy 218.383104 -284.910276) (xy 218.375992 -284.90291)
			(xy 218.357196 -284.89529) (xy 218.26474 -284.89529) (xy 218.245944 -284.90291) (xy 218.238832 -284.910276)
			(xy 218.217212 -284.931262) (xy 218.168583 -284.96683) (xy 218.114965 -284.99431) (xy 218.057693 -285.013017)
			(xy 217.998193 -285.022485) (xy 217.968068 -285.023052) (xy 217.939329 -285.022534) (xy 217.882502 -285.013908)
			(xy 217.827612 -284.996856) (xy 217.7759 -284.971763) (xy 217.728537 -284.939198) (xy 217.70721 -284.919928)
			(xy 217.700098 -284.913324) (xy 217.682572 -284.906212) (xy 217.593164 -284.906212) (xy 217.575638 -284.913324)
			(xy 217.568526 -284.919928) (xy 217.547207 -284.939208) (xy 217.499843 -284.971774) (xy 217.44813 -284.996866)
			(xy 217.393237 -285.013914) (xy 217.336408 -285.022533) (xy 217.307668 -285.023052) (xy 217.280421 -285.022476)
			(xy 217.226483 -285.014716) (xy 217.174199 -284.99936) (xy 217.124631 -284.97672) (xy 217.07879 -284.947256)
			(xy 217.037609 -284.911569) (xy 217.001925 -284.870384) (xy 216.972465 -284.824541) (xy 216.949829 -284.774971)
			(xy 216.934477 -284.722685) (xy 216.926722 -284.668747) (xy 210.789506 -284.668747) (xy 210.782669 -284.715208)
			(xy 210.766601 -284.768615) (xy 210.742929 -284.819112) (xy 210.712156 -284.865625) (xy 210.674939 -284.907162)
			(xy 210.632071 -284.942837) (xy 210.584465 -284.971891) (xy 210.533136 -284.993703) (xy 210.479179 -285.007809)
			(xy 210.423742 -285.013909) (xy 210.368008 -285.011872) (xy 210.313165 -285.001742) (xy 210.260381 -284.983735)
			(xy 210.210781 -284.958234) (xy 210.165423 -284.925783) (xy 210.125274 -284.887074) (xy 210.091188 -284.842931)
			(xy 210.063892 -284.794296) (xy 210.043969 -284.742205) (xy 210.031843 -284.687768) (xy 210.027772 -284.632146)
			(xy 198.824812 -284.632146) (xy 198.808485 -284.663254) (xy 198.77892 -284.702598) (xy 198.743427 -284.73669)
			(xy 198.702924 -284.764646) (xy 198.658462 -284.785744) (xy 198.611191 -284.799436) (xy 198.562336 -284.805368)
			(xy 198.513161 -284.803387) (xy 198.464942 -284.793543) (xy 198.418926 -284.776091) (xy 198.376305 -284.751484)
			(xy 198.338184 -284.720359) (xy 198.305549 -284.683522) (xy 198.279246 -284.641926) (xy 198.259955 -284.59665)
			(xy 198.248178 -284.548866) (xy 198.244218 -284.499812) (xy 197.90537 -284.499812) (xy 197.904875 -284.524419)
			(xy 197.89698 -284.572996) (xy 197.881396 -284.619677) (xy 197.858525 -284.663254) (xy 197.82896 -284.702598)
			(xy 197.793467 -284.73669) (xy 197.752964 -284.764646) (xy 197.708502 -284.785744) (xy 197.661231 -284.799436)
			(xy 197.612376 -284.805368) (xy 197.563201 -284.803387) (xy 197.514982 -284.793543) (xy 197.468966 -284.776091)
			(xy 197.426345 -284.751484) (xy 197.388224 -284.720359) (xy 197.355589 -284.683522) (xy 197.329286 -284.641926)
			(xy 197.309995 -284.59665) (xy 197.298218 -284.548866) (xy 197.294258 -284.499812) (xy 196.977 -284.499812)
			(xy 196.976496 -284.52552) (xy 196.968453 -284.576302) (xy 196.952565 -284.625201) (xy 196.929222 -284.671013)
			(xy 196.899001 -284.712609) (xy 196.862645 -284.748965) (xy 196.821049 -284.779186) (xy 196.775237 -284.802529)
			(xy 196.726338 -284.818417) (xy 196.675556 -284.82646) (xy 196.62414 -284.82646) (xy 196.573358 -284.818417)
			(xy 196.524459 -284.802529) (xy 196.478647 -284.779186) (xy 196.437051 -284.748965) (xy 196.400695 -284.712609)
			(xy 196.370474 -284.671013) (xy 196.347131 -284.625201) (xy 196.331243 -284.576302) (xy 196.3232 -284.52552)
			(xy 196.026536 -284.52552) (xy 196.018493 -284.576302) (xy 196.002605 -284.625201) (xy 195.979262 -284.671013)
			(xy 195.949041 -284.712609) (xy 195.912685 -284.748965) (xy 195.871089 -284.779186) (xy 195.825277 -284.802529)
			(xy 195.776378 -284.818417) (xy 195.725596 -284.82646) (xy 195.67418 -284.82646) (xy 195.623398 -284.818417)
			(xy 195.574499 -284.802529) (xy 195.528687 -284.779186) (xy 195.487091 -284.748965) (xy 195.450735 -284.712609)
			(xy 195.420514 -284.671013) (xy 195.397171 -284.625201) (xy 195.381283 -284.576302) (xy 195.37324 -284.52552)
			(xy 195.054562 -284.52552) (xy 195.046846 -284.572996) (xy 195.031262 -284.619677) (xy 195.008391 -284.663254)
			(xy 194.978826 -284.702598) (xy 194.943333 -284.73669) (xy 194.90283 -284.764646) (xy 194.858368 -284.785744)
			(xy 194.811097 -284.799436) (xy 194.762242 -284.805368) (xy 194.713067 -284.803387) (xy 194.664848 -284.793543)
			(xy 194.618832 -284.776091) (xy 194.576211 -284.751484) (xy 194.53809 -284.720359) (xy 194.505455 -284.683522)
			(xy 194.479152 -284.641926) (xy 194.459861 -284.59665) (xy 194.448084 -284.548866) (xy 194.444124 -284.499812)
			(xy 194.12712 -284.499812) (xy 194.126616 -284.52552) (xy 194.118573 -284.576302) (xy 194.102685 -284.625201)
			(xy 194.079342 -284.671013) (xy 194.049121 -284.712609) (xy 194.012765 -284.748965) (xy 193.971169 -284.779186)
			(xy 193.925357 -284.802529) (xy 193.876458 -284.818417) (xy 193.825676 -284.82646) (xy 193.77426 -284.82646)
			(xy 193.723478 -284.818417) (xy 193.674579 -284.802529) (xy 193.628767 -284.779186) (xy 193.587171 -284.748965)
			(xy 193.550815 -284.712609) (xy 193.520594 -284.671013) (xy 193.497251 -284.625201) (xy 193.481363 -284.576302)
			(xy 193.47332 -284.52552) (xy 193.176656 -284.52552) (xy 193.168613 -284.576302) (xy 193.152725 -284.625201)
			(xy 193.129382 -284.671013) (xy 193.099161 -284.712609) (xy 193.062805 -284.748965) (xy 193.021209 -284.779186)
			(xy 192.975397 -284.802529) (xy 192.926498 -284.818417) (xy 192.875716 -284.82646) (xy 192.8243 -284.82646)
			(xy 192.773518 -284.818417) (xy 192.724619 -284.802529) (xy 192.678807 -284.779186) (xy 192.637211 -284.748965)
			(xy 192.600855 -284.712609) (xy 192.570634 -284.671013) (xy 192.547291 -284.625201) (xy 192.531403 -284.576302)
			(xy 192.52336 -284.52552) (xy 192.204682 -284.52552) (xy 192.196966 -284.572996) (xy 192.181382 -284.619677)
			(xy 192.158511 -284.663254) (xy 192.128946 -284.702598) (xy 192.093453 -284.73669) (xy 192.05295 -284.764646)
			(xy 192.008488 -284.785744) (xy 191.961217 -284.799436) (xy 191.912362 -284.805368) (xy 191.863187 -284.803387)
			(xy 191.814968 -284.793543) (xy 191.768952 -284.776091) (xy 191.726331 -284.751484) (xy 191.68821 -284.720359)
			(xy 191.655575 -284.683522) (xy 191.629272 -284.641926) (xy 191.609981 -284.59665) (xy 191.598204 -284.548866)
			(xy 191.594244 -284.499812) (xy 191.255142 -284.499812) (xy 191.254647 -284.524419) (xy 191.246752 -284.572996)
			(xy 191.231168 -284.619677) (xy 191.208297 -284.663254) (xy 191.178732 -284.702598) (xy 191.143239 -284.73669)
			(xy 191.102736 -284.764646) (xy 191.058274 -284.785744) (xy 191.011003 -284.799436) (xy 190.962148 -284.805368)
			(xy 190.912973 -284.803387) (xy 190.864754 -284.793543) (xy 190.818738 -284.776091) (xy 190.776117 -284.751484)
			(xy 190.737996 -284.720359) (xy 190.705361 -284.683522) (xy 190.679058 -284.641926) (xy 190.659767 -284.59665)
			(xy 190.64799 -284.548866) (xy 190.64403 -284.499812) (xy 190.305182 -284.499812) (xy 190.304687 -284.524419)
			(xy 190.296792 -284.572996) (xy 190.281208 -284.619677) (xy 190.258337 -284.663254) (xy 190.228772 -284.702598)
			(xy 190.193279 -284.73669) (xy 190.152776 -284.764646) (xy 190.108314 -284.785744) (xy 190.061043 -284.799436)
			(xy 190.012188 -284.805368) (xy 189.963013 -284.803387) (xy 189.914794 -284.793543) (xy 189.868778 -284.776091)
			(xy 189.826157 -284.751484) (xy 189.788036 -284.720359) (xy 189.755401 -284.683522) (xy 189.729098 -284.641926)
			(xy 189.709807 -284.59665) (xy 189.69803 -284.548866) (xy 189.69407 -284.499812) (xy 164.790882 -284.499812)
			(xy 164.790882 -284.573218) (xy 164.791349 -284.582851) (xy 164.798528 -284.600735) (xy 164.804852 -284.608016)
			(xy 164.820092 -284.624018) (xy 164.82695 -284.631384) (xy 164.850318 -284.641798) (xy 164.854636 -284.643068)
			(xy 164.86505 -284.64637) (xy 164.869622 -284.647132) (xy 164.895692 -284.651209) (xy 164.946176 -284.666555)
			(xy 164.993582 -284.689723) (xy 165.036708 -284.720124) (xy 165.07446 -284.756987) (xy 165.105879 -284.799377)
			(xy 165.130169 -284.846218) (xy 165.146713 -284.896322) (xy 165.155092 -284.948417) (xy 165.155092 -284.974792)
			(xy 165.469074 -284.974792) (xy 165.473034 -284.925738) (xy 165.484811 -284.877954) (xy 165.504102 -284.832678)
			(xy 165.530405 -284.791082) (xy 165.56304 -284.754245) (xy 165.601161 -284.72312) (xy 165.643782 -284.698513)
			(xy 165.689798 -284.681061) (xy 165.738017 -284.671217) (xy 165.787192 -284.669236) (xy 165.836047 -284.675168)
			(xy 165.883318 -284.68886) (xy 165.92778 -284.709958) (xy 165.968283 -284.737914) (xy 166.003776 -284.772006)
			(xy 166.033341 -284.81135) (xy 166.056212 -284.854927) (xy 166.071796 -284.901608) (xy 166.079691 -284.950185)
			(xy 166.080186 -284.974792) (xy 166.419288 -284.974792) (xy 166.423248 -284.925738) (xy 166.435025 -284.877954)
			(xy 166.454316 -284.832678) (xy 166.480619 -284.791082) (xy 166.513254 -284.754245) (xy 166.551375 -284.72312)
			(xy 166.593996 -284.698513) (xy 166.640012 -284.681061) (xy 166.688231 -284.671217) (xy 166.737406 -284.669236)
			(xy 166.786261 -284.675168) (xy 166.833532 -284.68886) (xy 166.877994 -284.709958) (xy 166.918497 -284.737914)
			(xy 166.95399 -284.772006) (xy 166.983555 -284.81135) (xy 167.006426 -284.854927) (xy 167.02201 -284.901608)
			(xy 167.029905 -284.950185) (xy 167.0304 -284.974792) (xy 167.369248 -284.974792) (xy 167.373208 -284.925738)
			(xy 167.384985 -284.877954) (xy 167.404276 -284.832678) (xy 167.430579 -284.791082) (xy 167.463214 -284.754245)
			(xy 167.501335 -284.72312) (xy 167.543956 -284.698513) (xy 167.589972 -284.681061) (xy 167.638191 -284.671217)
			(xy 167.687366 -284.669236) (xy 167.736221 -284.675168) (xy 167.783492 -284.68886) (xy 167.827954 -284.709958)
			(xy 167.868457 -284.737914) (xy 167.90395 -284.772006) (xy 167.933515 -284.81135) (xy 167.956386 -284.854927)
			(xy 167.97197 -284.901608) (xy 167.979865 -284.950185) (xy 167.98036 -284.974792) (xy 168.319208 -284.974792)
			(xy 168.323168 -284.925738) (xy 168.334945 -284.877954) (xy 168.354236 -284.832678) (xy 168.380539 -284.791082)
			(xy 168.413174 -284.754245) (xy 168.451295 -284.72312) (xy 168.493916 -284.698513) (xy 168.539932 -284.681061)
			(xy 168.588151 -284.671217) (xy 168.637326 -284.669236) (xy 168.686181 -284.675168) (xy 168.733452 -284.68886)
			(xy 168.777914 -284.709958) (xy 168.818417 -284.737914) (xy 168.85391 -284.772006) (xy 168.883475 -284.81135)
			(xy 168.906346 -284.854927) (xy 168.92193 -284.901608) (xy 168.929825 -284.950185) (xy 168.93032 -284.974792)
			(xy 169.269168 -284.974792) (xy 169.273128 -284.925738) (xy 169.284905 -284.877954) (xy 169.304196 -284.832678)
			(xy 169.330499 -284.791082) (xy 169.363134 -284.754245) (xy 169.401255 -284.72312) (xy 169.443876 -284.698513)
			(xy 169.489892 -284.681061) (xy 169.538111 -284.671217) (xy 169.587286 -284.669236) (xy 169.636141 -284.675168)
			(xy 169.683412 -284.68886) (xy 169.727874 -284.709958) (xy 169.768377 -284.737914) (xy 169.80387 -284.772006)
			(xy 169.833435 -284.81135) (xy 169.856306 -284.854927) (xy 169.87189 -284.901608) (xy 169.879785 -284.950185)
			(xy 169.88028 -284.974792) (xy 170.219128 -284.974792) (xy 170.223088 -284.925738) (xy 170.234865 -284.877954)
			(xy 170.254156 -284.832678) (xy 170.280459 -284.791082) (xy 170.313094 -284.754245) (xy 170.351215 -284.72312)
			(xy 170.393836 -284.698513) (xy 170.439852 -284.681061) (xy 170.488071 -284.671217) (xy 170.537246 -284.669236)
			(xy 170.586101 -284.675168) (xy 170.633372 -284.68886) (xy 170.677834 -284.709958) (xy 170.718337 -284.737914)
			(xy 170.75383 -284.772006) (xy 170.783395 -284.81135) (xy 170.806266 -284.854927) (xy 170.82185 -284.901608)
			(xy 170.829745 -284.950185) (xy 170.83024 -284.974792) (xy 171.169088 -284.974792) (xy 171.173048 -284.925738)
			(xy 171.184825 -284.877954) (xy 171.204116 -284.832678) (xy 171.230419 -284.791082) (xy 171.263054 -284.754245)
			(xy 171.301175 -284.72312) (xy 171.343796 -284.698513) (xy 171.389812 -284.681061) (xy 171.438031 -284.671217)
			(xy 171.487206 -284.669236) (xy 171.536061 -284.675168) (xy 171.583332 -284.68886) (xy 171.627794 -284.709958)
			(xy 171.668297 -284.737914) (xy 171.70379 -284.772006) (xy 171.733355 -284.81135) (xy 171.756226 -284.854927)
			(xy 171.77181 -284.901608) (xy 171.779705 -284.950185) (xy 171.7802 -284.974792) (xy 172.119048 -284.974792)
			(xy 172.123008 -284.925738) (xy 172.134785 -284.877954) (xy 172.154076 -284.832678) (xy 172.180379 -284.791082)
			(xy 172.213014 -284.754245) (xy 172.251135 -284.72312) (xy 172.293756 -284.698513) (xy 172.339772 -284.681061)
			(xy 172.387991 -284.671217) (xy 172.437166 -284.669236) (xy 172.486021 -284.675168) (xy 172.533292 -284.68886)
			(xy 172.577754 -284.709958) (xy 172.618257 -284.737914) (xy 172.65375 -284.772006) (xy 172.683315 -284.81135)
			(xy 172.706186 -284.854927) (xy 172.72177 -284.901608) (xy 172.729665 -284.950185) (xy 172.73016 -284.974792)
			(xy 173.069262 -284.974792) (xy 173.073222 -284.925738) (xy 173.084999 -284.877954) (xy 173.10429 -284.832678)
			(xy 173.130593 -284.791082) (xy 173.163228 -284.754245) (xy 173.201349 -284.72312) (xy 173.24397 -284.698513)
			(xy 173.289986 -284.681061) (xy 173.338205 -284.671217) (xy 173.38738 -284.669236) (xy 173.436235 -284.675168)
			(xy 173.483506 -284.68886) (xy 173.527968 -284.709958) (xy 173.568471 -284.737914) (xy 173.603964 -284.772006)
			(xy 173.633529 -284.81135) (xy 173.6564 -284.854927) (xy 173.671984 -284.901608) (xy 173.679879 -284.950185)
			(xy 173.680374 -284.974792) (xy 174.019222 -284.974792) (xy 174.023182 -284.925738) (xy 174.034959 -284.877954)
			(xy 174.05425 -284.832678) (xy 174.080553 -284.791082) (xy 174.113188 -284.754245) (xy 174.151309 -284.72312)
			(xy 174.19393 -284.698513) (xy 174.239946 -284.681061) (xy 174.288165 -284.671217) (xy 174.33734 -284.669236)
			(xy 174.386195 -284.675168) (xy 174.433466 -284.68886) (xy 174.477928 -284.709958) (xy 174.518431 -284.737914)
			(xy 174.553924 -284.772006) (xy 174.583489 -284.81135) (xy 174.60636 -284.854927) (xy 174.621944 -284.901608)
			(xy 174.629839 -284.950185) (xy 174.630334 -284.974792) (xy 175.919142 -284.974792) (xy 175.923102 -284.925738)
			(xy 175.934879 -284.877954) (xy 175.95417 -284.832678) (xy 175.980473 -284.791082) (xy 176.013108 -284.754245)
			(xy 176.051229 -284.72312) (xy 176.09385 -284.698513) (xy 176.139866 -284.681061) (xy 176.188085 -284.671217)
			(xy 176.23726 -284.669236) (xy 176.286115 -284.675168) (xy 176.333386 -284.68886) (xy 176.377848 -284.709958)
			(xy 176.418351 -284.737914) (xy 176.453844 -284.772006) (xy 176.483409 -284.81135) (xy 176.50628 -284.854927)
			(xy 176.521864 -284.901608) (xy 176.529759 -284.950185) (xy 176.530254 -284.974792) (xy 176.869102 -284.974792)
			(xy 176.873062 -284.925738) (xy 176.884839 -284.877954) (xy 176.90413 -284.832678) (xy 176.930433 -284.791082)
			(xy 176.963068 -284.754245) (xy 177.001189 -284.72312) (xy 177.04381 -284.698513) (xy 177.089826 -284.681061)
			(xy 177.138045 -284.671217) (xy 177.18722 -284.669236) (xy 177.236075 -284.675168) (xy 177.283346 -284.68886)
			(xy 177.327808 -284.709958) (xy 177.368311 -284.737914) (xy 177.403804 -284.772006) (xy 177.433369 -284.81135)
			(xy 177.45624 -284.854927) (xy 177.471824 -284.901608) (xy 177.479719 -284.950185) (xy 177.480214 -284.974792)
			(xy 177.819062 -284.974792) (xy 177.823022 -284.925738) (xy 177.834799 -284.877954) (xy 177.85409 -284.832678)
			(xy 177.880393 -284.791082) (xy 177.913028 -284.754245) (xy 177.951149 -284.72312) (xy 177.99377 -284.698513)
			(xy 178.039786 -284.681061) (xy 178.088005 -284.671217) (xy 178.13718 -284.669236) (xy 178.186035 -284.675168)
			(xy 178.233306 -284.68886) (xy 178.277768 -284.709958) (xy 178.318271 -284.737914) (xy 178.353764 -284.772006)
			(xy 178.383329 -284.81135) (xy 178.4062 -284.854927) (xy 178.421784 -284.901608) (xy 178.429679 -284.950185)
			(xy 178.430174 -284.974792) (xy 178.769276 -284.974792) (xy 178.773236 -284.925738) (xy 178.785013 -284.877954)
			(xy 178.804304 -284.832678) (xy 178.830607 -284.791082) (xy 178.863242 -284.754245) (xy 178.901363 -284.72312)
			(xy 178.943984 -284.698513) (xy 178.99 -284.681061) (xy 179.038219 -284.671217) (xy 179.087394 -284.669236)
			(xy 179.136249 -284.675168) (xy 179.18352 -284.68886) (xy 179.227982 -284.709958) (xy 179.268485 -284.737914)
			(xy 179.303978 -284.772006) (xy 179.333543 -284.81135) (xy 179.356414 -284.854927) (xy 179.371998 -284.901608)
			(xy 179.379893 -284.950185) (xy 179.380388 -284.974792) (xy 179.719236 -284.974792) (xy 179.723196 -284.925738)
			(xy 179.734973 -284.877954) (xy 179.754264 -284.832678) (xy 179.780567 -284.791082) (xy 179.813202 -284.754245)
			(xy 179.851323 -284.72312) (xy 179.893944 -284.698513) (xy 179.93996 -284.681061) (xy 179.988179 -284.671217)
			(xy 180.037354 -284.669236) (xy 180.086209 -284.675168) (xy 180.13348 -284.68886) (xy 180.177942 -284.709958)
			(xy 180.218445 -284.737914) (xy 180.253938 -284.772006) (xy 180.283503 -284.81135) (xy 180.306374 -284.854927)
			(xy 180.321958 -284.901608) (xy 180.329853 -284.950185) (xy 180.330348 -284.974792) (xy 180.669196 -284.974792)
			(xy 180.673156 -284.925738) (xy 180.684933 -284.877954) (xy 180.704224 -284.832678) (xy 180.730527 -284.791082)
			(xy 180.763162 -284.754245) (xy 180.801283 -284.72312) (xy 180.843904 -284.698513) (xy 180.88992 -284.681061)
			(xy 180.938139 -284.671217) (xy 180.987314 -284.669236) (xy 181.036169 -284.675168) (xy 181.08344 -284.68886)
			(xy 181.127902 -284.709958) (xy 181.168405 -284.737914) (xy 181.203898 -284.772006) (xy 181.233463 -284.81135)
			(xy 181.256334 -284.854927) (xy 181.271918 -284.901608) (xy 181.279813 -284.950185) (xy 181.280308 -284.974792)
			(xy 181.619156 -284.974792) (xy 181.623116 -284.925738) (xy 181.634893 -284.877954) (xy 181.654184 -284.832678)
			(xy 181.680487 -284.791082) (xy 181.713122 -284.754245) (xy 181.751243 -284.72312) (xy 181.793864 -284.698513)
			(xy 181.83988 -284.681061) (xy 181.888099 -284.671217) (xy 181.937274 -284.669236) (xy 181.986129 -284.675168)
			(xy 182.0334 -284.68886) (xy 182.077862 -284.709958) (xy 182.118365 -284.737914) (xy 182.153858 -284.772006)
			(xy 182.183423 -284.81135) (xy 182.206294 -284.854927) (xy 182.221878 -284.901608) (xy 182.229773 -284.950185)
			(xy 182.230268 -284.974792) (xy 182.569116 -284.974792) (xy 182.573076 -284.925738) (xy 182.584853 -284.877954)
			(xy 182.604144 -284.832678) (xy 182.630447 -284.791082) (xy 182.663082 -284.754245) (xy 182.701203 -284.72312)
			(xy 182.743824 -284.698513) (xy 182.78984 -284.681061) (xy 182.838059 -284.671217) (xy 182.887234 -284.669236)
			(xy 182.936089 -284.675168) (xy 182.98336 -284.68886) (xy 183.027822 -284.709958) (xy 183.068325 -284.737914)
			(xy 183.103818 -284.772006) (xy 183.133383 -284.81135) (xy 183.156254 -284.854927) (xy 183.171838 -284.901608)
			(xy 183.179733 -284.950185) (xy 183.180228 -284.974792) (xy 183.519076 -284.974792) (xy 183.523036 -284.925738)
			(xy 183.534813 -284.877954) (xy 183.554104 -284.832678) (xy 183.580407 -284.791082) (xy 183.613042 -284.754245)
			(xy 183.651163 -284.72312) (xy 183.693784 -284.698513) (xy 183.7398 -284.681061) (xy 183.788019 -284.671217)
			(xy 183.837194 -284.669236) (xy 183.886049 -284.675168) (xy 183.93332 -284.68886) (xy 183.977782 -284.709958)
			(xy 184.018285 -284.737914) (xy 184.053778 -284.772006) (xy 184.083343 -284.81135) (xy 184.106214 -284.854927)
			(xy 184.121798 -284.901608) (xy 184.129693 -284.950185) (xy 184.130188 -284.974792) (xy 184.469036 -284.974792)
			(xy 184.472996 -284.925738) (xy 184.484773 -284.877954) (xy 184.504064 -284.832678) (xy 184.530367 -284.791082)
			(xy 184.563002 -284.754245) (xy 184.601123 -284.72312) (xy 184.643744 -284.698513) (xy 184.68976 -284.681061)
			(xy 184.737979 -284.671217) (xy 184.787154 -284.669236) (xy 184.836009 -284.675168) (xy 184.88328 -284.68886)
			(xy 184.927742 -284.709958) (xy 184.968245 -284.737914) (xy 185.003738 -284.772006) (xy 185.033303 -284.81135)
			(xy 185.056174 -284.854927) (xy 185.071758 -284.901608) (xy 185.079653 -284.950185) (xy 185.080148 -284.974792)
			(xy 185.41925 -284.974792) (xy 185.42321 -284.925738) (xy 185.434987 -284.877954) (xy 185.454278 -284.832678)
			(xy 185.480581 -284.791082) (xy 185.513216 -284.754245) (xy 185.551337 -284.72312) (xy 185.593958 -284.698513)
			(xy 185.639974 -284.681061) (xy 185.688193 -284.671217) (xy 185.737368 -284.669236) (xy 185.786223 -284.675168)
			(xy 185.833494 -284.68886) (xy 185.877956 -284.709958) (xy 185.918459 -284.737914) (xy 185.953952 -284.772006)
			(xy 185.983517 -284.81135) (xy 186.006388 -284.854927) (xy 186.021972 -284.901608) (xy 186.029867 -284.950185)
			(xy 186.030362 -284.974792) (xy 186.36921 -284.974792) (xy 186.37317 -284.925738) (xy 186.384947 -284.877954)
			(xy 186.404238 -284.832678) (xy 186.430541 -284.791082) (xy 186.463176 -284.754245) (xy 186.501297 -284.72312)
			(xy 186.543918 -284.698513) (xy 186.589934 -284.681061) (xy 186.638153 -284.671217) (xy 186.687328 -284.669236)
			(xy 186.736183 -284.675168) (xy 186.783454 -284.68886) (xy 186.827916 -284.709958) (xy 186.868419 -284.737914)
			(xy 186.903912 -284.772006) (xy 186.933477 -284.81135) (xy 186.956348 -284.854927) (xy 186.971932 -284.901608)
			(xy 186.979827 -284.950185) (xy 186.980322 -284.974792) (xy 186.979827 -284.999399) (xy 186.971932 -285.047976)
			(xy 186.956348 -285.094657) (xy 186.933477 -285.138234) (xy 186.903912 -285.177578) (xy 186.868419 -285.21167)
			(xy 186.827916 -285.239626) (xy 186.783454 -285.260724) (xy 186.736183 -285.274416) (xy 186.687328 -285.280348)
			(xy 186.638153 -285.278367) (xy 186.589934 -285.268523) (xy 186.543918 -285.251071) (xy 186.501297 -285.226464)
			(xy 186.463176 -285.195339) (xy 186.430541 -285.158502) (xy 186.404238 -285.116906) (xy 186.384947 -285.07163)
			(xy 186.37317 -285.023846) (xy 186.36921 -284.974792) (xy 186.030362 -284.974792) (xy 186.029867 -284.999399)
			(xy 186.021972 -285.047976) (xy 186.006388 -285.094657) (xy 185.983517 -285.138234) (xy 185.953952 -285.177578)
			(xy 185.918459 -285.21167) (xy 185.877956 -285.239626) (xy 185.833494 -285.260724) (xy 185.786223 -285.274416)
			(xy 185.737368 -285.280348) (xy 185.688193 -285.278367) (xy 185.639974 -285.268523) (xy 185.593958 -285.251071)
			(xy 185.551337 -285.226464) (xy 185.513216 -285.195339) (xy 185.480581 -285.158502) (xy 185.454278 -285.116906)
			(xy 185.434987 -285.07163) (xy 185.42321 -285.023846) (xy 185.41925 -284.974792) (xy 185.080148 -284.974792)
			(xy 185.079653 -284.999399) (xy 185.071758 -285.047976) (xy 185.056174 -285.094657) (xy 185.033303 -285.138234)
			(xy 185.003738 -285.177578) (xy 184.968245 -285.21167) (xy 184.927742 -285.239626) (xy 184.88328 -285.260724)
			(xy 184.836009 -285.274416) (xy 184.787154 -285.280348) (xy 184.737979 -285.278367) (xy 184.68976 -285.268523)
			(xy 184.643744 -285.251071) (xy 184.601123 -285.226464) (xy 184.563002 -285.195339) (xy 184.530367 -285.158502)
			(xy 184.504064 -285.116906) (xy 184.484773 -285.07163) (xy 184.472996 -285.023846) (xy 184.469036 -284.974792)
			(xy 184.130188 -284.974792) (xy 184.129693 -284.999399) (xy 184.121798 -285.047976) (xy 184.106214 -285.094657)
			(xy 184.083343 -285.138234) (xy 184.053778 -285.177578) (xy 184.018285 -285.21167) (xy 183.977782 -285.239626)
			(xy 183.93332 -285.260724) (xy 183.886049 -285.274416) (xy 183.837194 -285.280348) (xy 183.788019 -285.278367)
			(xy 183.7398 -285.268523) (xy 183.693784 -285.251071) (xy 183.651163 -285.226464) (xy 183.613042 -285.195339)
			(xy 183.580407 -285.158502) (xy 183.554104 -285.116906) (xy 183.534813 -285.07163) (xy 183.523036 -285.023846)
			(xy 183.519076 -284.974792) (xy 183.180228 -284.974792) (xy 183.179733 -284.999399) (xy 183.171838 -285.047976)
			(xy 183.156254 -285.094657) (xy 183.133383 -285.138234) (xy 183.103818 -285.177578) (xy 183.068325 -285.21167)
			(xy 183.027822 -285.239626) (xy 182.98336 -285.260724) (xy 182.936089 -285.274416) (xy 182.887234 -285.280348)
			(xy 182.838059 -285.278367) (xy 182.78984 -285.268523) (xy 182.743824 -285.251071) (xy 182.701203 -285.226464)
			(xy 182.663082 -285.195339) (xy 182.630447 -285.158502) (xy 182.604144 -285.116906) (xy 182.584853 -285.07163)
			(xy 182.573076 -285.023846) (xy 182.569116 -284.974792) (xy 182.230268 -284.974792) (xy 182.229773 -284.999399)
			(xy 182.221878 -285.047976) (xy 182.206294 -285.094657) (xy 182.183423 -285.138234) (xy 182.153858 -285.177578)
			(xy 182.118365 -285.21167) (xy 182.077862 -285.239626) (xy 182.0334 -285.260724) (xy 181.986129 -285.274416)
			(xy 181.937274 -285.280348) (xy 181.888099 -285.278367) (xy 181.83988 -285.268523) (xy 181.793864 -285.251071)
			(xy 181.751243 -285.226464) (xy 181.713122 -285.195339) (xy 181.680487 -285.158502) (xy 181.654184 -285.116906)
			(xy 181.634893 -285.07163) (xy 181.623116 -285.023846) (xy 181.619156 -284.974792) (xy 181.280308 -284.974792)
			(xy 181.279813 -284.999399) (xy 181.271918 -285.047976) (xy 181.256334 -285.094657) (xy 181.233463 -285.138234)
			(xy 181.203898 -285.177578) (xy 181.168405 -285.21167) (xy 181.127902 -285.239626) (xy 181.08344 -285.260724)
			(xy 181.036169 -285.274416) (xy 180.987314 -285.280348) (xy 180.938139 -285.278367) (xy 180.88992 -285.268523)
			(xy 180.843904 -285.251071) (xy 180.801283 -285.226464) (xy 180.763162 -285.195339) (xy 180.730527 -285.158502)
			(xy 180.704224 -285.116906) (xy 180.684933 -285.07163) (xy 180.673156 -285.023846) (xy 180.669196 -284.974792)
			(xy 180.330348 -284.974792) (xy 180.329853 -284.999399) (xy 180.321958 -285.047976) (xy 180.306374 -285.094657)
			(xy 180.283503 -285.138234) (xy 180.253938 -285.177578) (xy 180.218445 -285.21167) (xy 180.177942 -285.239626)
			(xy 180.13348 -285.260724) (xy 180.086209 -285.274416) (xy 180.037354 -285.280348) (xy 179.988179 -285.278367)
			(xy 179.93996 -285.268523) (xy 179.893944 -285.251071) (xy 179.851323 -285.226464) (xy 179.813202 -285.195339)
			(xy 179.780567 -285.158502) (xy 179.754264 -285.116906) (xy 179.734973 -285.07163) (xy 179.723196 -285.023846)
			(xy 179.719236 -284.974792) (xy 179.380388 -284.974792) (xy 179.379893 -284.999399) (xy 179.371998 -285.047976)
			(xy 179.356414 -285.094657) (xy 179.333543 -285.138234) (xy 179.303978 -285.177578) (xy 179.268485 -285.21167)
			(xy 179.227982 -285.239626) (xy 179.18352 -285.260724) (xy 179.136249 -285.274416) (xy 179.087394 -285.280348)
			(xy 179.038219 -285.278367) (xy 178.99 -285.268523) (xy 178.943984 -285.251071) (xy 178.901363 -285.226464)
			(xy 178.863242 -285.195339) (xy 178.830607 -285.158502) (xy 178.804304 -285.116906) (xy 178.785013 -285.07163)
			(xy 178.773236 -285.023846) (xy 178.769276 -284.974792) (xy 178.430174 -284.974792) (xy 178.429679 -284.999399)
			(xy 178.421784 -285.047976) (xy 178.4062 -285.094657) (xy 178.383329 -285.138234) (xy 178.353764 -285.177578)
			(xy 178.318271 -285.21167) (xy 178.277768 -285.239626) (xy 178.233306 -285.260724) (xy 178.186035 -285.274416)
			(xy 178.13718 -285.280348) (xy 178.088005 -285.278367) (xy 178.039786 -285.268523) (xy 177.99377 -285.251071)
			(xy 177.951149 -285.226464) (xy 177.913028 -285.195339) (xy 177.880393 -285.158502) (xy 177.85409 -285.116906)
			(xy 177.834799 -285.07163) (xy 177.823022 -285.023846) (xy 177.819062 -284.974792) (xy 177.480214 -284.974792)
			(xy 177.479719 -284.999399) (xy 177.471824 -285.047976) (xy 177.45624 -285.094657) (xy 177.433369 -285.138234)
			(xy 177.403804 -285.177578) (xy 177.368311 -285.21167) (xy 177.327808 -285.239626) (xy 177.283346 -285.260724)
			(xy 177.236075 -285.274416) (xy 177.18722 -285.280348) (xy 177.138045 -285.278367) (xy 177.089826 -285.268523)
			(xy 177.04381 -285.251071) (xy 177.001189 -285.226464) (xy 176.963068 -285.195339) (xy 176.930433 -285.158502)
			(xy 176.90413 -285.116906) (xy 176.884839 -285.07163) (xy 176.873062 -285.023846) (xy 176.869102 -284.974792)
			(xy 176.530254 -284.974792) (xy 176.529759 -284.999399) (xy 176.521864 -285.047976) (xy 176.50628 -285.094657)
			(xy 176.483409 -285.138234) (xy 176.453844 -285.177578) (xy 176.418351 -285.21167) (xy 176.377848 -285.239626)
			(xy 176.333386 -285.260724) (xy 176.286115 -285.274416) (xy 176.23726 -285.280348) (xy 176.188085 -285.278367)
			(xy 176.139866 -285.268523) (xy 176.09385 -285.251071) (xy 176.051229 -285.226464) (xy 176.013108 -285.195339)
			(xy 175.980473 -285.158502) (xy 175.95417 -285.116906) (xy 175.934879 -285.07163) (xy 175.923102 -285.023846)
			(xy 175.919142 -284.974792) (xy 174.630334 -284.974792) (xy 174.629839 -284.999399) (xy 174.621944 -285.047976)
			(xy 174.60636 -285.094657) (xy 174.583489 -285.138234) (xy 174.553924 -285.177578) (xy 174.518431 -285.21167)
			(xy 174.477928 -285.239626) (xy 174.433466 -285.260724) (xy 174.386195 -285.274416) (xy 174.33734 -285.280348)
			(xy 174.288165 -285.278367) (xy 174.239946 -285.268523) (xy 174.19393 -285.251071) (xy 174.151309 -285.226464)
			(xy 174.113188 -285.195339) (xy 174.080553 -285.158502) (xy 174.05425 -285.116906) (xy 174.034959 -285.07163)
			(xy 174.023182 -285.023846) (xy 174.019222 -284.974792) (xy 173.680374 -284.974792) (xy 173.679879 -284.999399)
			(xy 173.671984 -285.047976) (xy 173.6564 -285.094657) (xy 173.633529 -285.138234) (xy 173.603964 -285.177578)
			(xy 173.568471 -285.21167) (xy 173.527968 -285.239626) (xy 173.483506 -285.260724) (xy 173.436235 -285.274416)
			(xy 173.38738 -285.280348) (xy 173.338205 -285.278367) (xy 173.289986 -285.268523) (xy 173.24397 -285.251071)
			(xy 173.201349 -285.226464) (xy 173.163228 -285.195339) (xy 173.130593 -285.158502) (xy 173.10429 -285.116906)
			(xy 173.084999 -285.07163) (xy 173.073222 -285.023846) (xy 173.069262 -284.974792) (xy 172.73016 -284.974792)
			(xy 172.729665 -284.999399) (xy 172.72177 -285.047976) (xy 172.706186 -285.094657) (xy 172.683315 -285.138234)
			(xy 172.65375 -285.177578) (xy 172.618257 -285.21167) (xy 172.577754 -285.239626) (xy 172.533292 -285.260724)
			(xy 172.486021 -285.274416) (xy 172.437166 -285.280348) (xy 172.387991 -285.278367) (xy 172.339772 -285.268523)
			(xy 172.293756 -285.251071) (xy 172.251135 -285.226464) (xy 172.213014 -285.195339) (xy 172.180379 -285.158502)
			(xy 172.154076 -285.116906) (xy 172.134785 -285.07163) (xy 172.123008 -285.023846) (xy 172.119048 -284.974792)
			(xy 171.7802 -284.974792) (xy 171.779705 -284.999399) (xy 171.77181 -285.047976) (xy 171.756226 -285.094657)
			(xy 171.733355 -285.138234) (xy 171.70379 -285.177578) (xy 171.668297 -285.21167) (xy 171.627794 -285.239626)
			(xy 171.583332 -285.260724) (xy 171.536061 -285.274416) (xy 171.487206 -285.280348) (xy 171.438031 -285.278367)
			(xy 171.389812 -285.268523) (xy 171.343796 -285.251071) (xy 171.301175 -285.226464) (xy 171.263054 -285.195339)
			(xy 171.230419 -285.158502) (xy 171.204116 -285.116906) (xy 171.184825 -285.07163) (xy 171.173048 -285.023846)
			(xy 171.169088 -284.974792) (xy 170.83024 -284.974792) (xy 170.829745 -284.999399) (xy 170.82185 -285.047976)
			(xy 170.806266 -285.094657) (xy 170.783395 -285.138234) (xy 170.75383 -285.177578) (xy 170.718337 -285.21167)
			(xy 170.677834 -285.239626) (xy 170.633372 -285.260724) (xy 170.586101 -285.274416) (xy 170.537246 -285.280348)
			(xy 170.488071 -285.278367) (xy 170.439852 -285.268523) (xy 170.393836 -285.251071) (xy 170.351215 -285.226464)
			(xy 170.313094 -285.195339) (xy 170.280459 -285.158502) (xy 170.254156 -285.116906) (xy 170.234865 -285.07163)
			(xy 170.223088 -285.023846) (xy 170.219128 -284.974792) (xy 169.88028 -284.974792) (xy 169.879785 -284.999399)
			(xy 169.87189 -285.047976) (xy 169.856306 -285.094657) (xy 169.833435 -285.138234) (xy 169.80387 -285.177578)
			(xy 169.768377 -285.21167) (xy 169.727874 -285.239626) (xy 169.683412 -285.260724) (xy 169.636141 -285.274416)
			(xy 169.587286 -285.280348) (xy 169.538111 -285.278367) (xy 169.489892 -285.268523) (xy 169.443876 -285.251071)
			(xy 169.401255 -285.226464) (xy 169.363134 -285.195339) (xy 169.330499 -285.158502) (xy 169.304196 -285.116906)
			(xy 169.284905 -285.07163) (xy 169.273128 -285.023846) (xy 169.269168 -284.974792) (xy 168.93032 -284.974792)
			(xy 168.929825 -284.999399) (xy 168.92193 -285.047976) (xy 168.906346 -285.094657) (xy 168.883475 -285.138234)
			(xy 168.85391 -285.177578) (xy 168.818417 -285.21167) (xy 168.777914 -285.239626) (xy 168.733452 -285.260724)
			(xy 168.686181 -285.274416) (xy 168.637326 -285.280348) (xy 168.588151 -285.278367) (xy 168.539932 -285.268523)
			(xy 168.493916 -285.251071) (xy 168.451295 -285.226464) (xy 168.413174 -285.195339) (xy 168.380539 -285.158502)
			(xy 168.354236 -285.116906) (xy 168.334945 -285.07163) (xy 168.323168 -285.023846) (xy 168.319208 -284.974792)
			(xy 167.98036 -284.974792) (xy 167.979865 -284.999399) (xy 167.97197 -285.047976) (xy 167.956386 -285.094657)
			(xy 167.933515 -285.138234) (xy 167.90395 -285.177578) (xy 167.868457 -285.21167) (xy 167.827954 -285.239626)
			(xy 167.783492 -285.260724) (xy 167.736221 -285.274416) (xy 167.687366 -285.280348) (xy 167.638191 -285.278367)
			(xy 167.589972 -285.268523) (xy 167.543956 -285.251071) (xy 167.501335 -285.226464) (xy 167.463214 -285.195339)
			(xy 167.430579 -285.158502) (xy 167.404276 -285.116906) (xy 167.384985 -285.07163) (xy 167.373208 -285.023846)
			(xy 167.369248 -284.974792) (xy 167.0304 -284.974792) (xy 167.029905 -284.999399) (xy 167.02201 -285.047976)
			(xy 167.006426 -285.094657) (xy 166.983555 -285.138234) (xy 166.95399 -285.177578) (xy 166.918497 -285.21167)
			(xy 166.877994 -285.239626) (xy 166.833532 -285.260724) (xy 166.786261 -285.274416) (xy 166.737406 -285.280348)
			(xy 166.688231 -285.278367) (xy 166.640012 -285.268523) (xy 166.593996 -285.251071) (xy 166.551375 -285.226464)
			(xy 166.513254 -285.195339) (xy 166.480619 -285.158502) (xy 166.454316 -285.116906) (xy 166.435025 -285.07163)
			(xy 166.423248 -285.023846) (xy 166.419288 -284.974792) (xy 166.080186 -284.974792) (xy 166.079691 -284.999399)
			(xy 166.071796 -285.047976) (xy 166.056212 -285.094657) (xy 166.033341 -285.138234) (xy 166.003776 -285.177578)
			(xy 165.968283 -285.21167) (xy 165.92778 -285.239626) (xy 165.883318 -285.260724) (xy 165.836047 -285.274416)
			(xy 165.787192 -285.280348) (xy 165.738017 -285.278367) (xy 165.689798 -285.268523) (xy 165.643782 -285.251071)
			(xy 165.601161 -285.226464) (xy 165.56304 -285.195339) (xy 165.530405 -285.158502) (xy 165.504102 -285.116906)
			(xy 165.484811 -285.07163) (xy 165.473034 -285.023846) (xy 165.469074 -284.974792) (xy 165.155092 -284.974792)
			(xy 165.155092 -285.001181) (xy 165.146714 -285.053276) (xy 165.13017 -285.10338) (xy 165.10588 -285.150221)
			(xy 165.074461 -285.192611) (xy 165.03671 -285.229475) (xy 164.993584 -285.259876) (xy 164.946178 -285.283044)
			(xy 164.895694 -285.29839) (xy 164.869622 -285.302452) (xy 164.86505 -285.303214) (xy 164.854636 -285.306516)
			(xy 164.850318 -285.307786) (xy 164.826696 -285.318708) (xy 164.819838 -285.32582) (xy 164.804852 -285.341568)
			(xy 164.800261 -285.346671) (xy 164.793808 -285.358782) (xy 164.792152 -285.365444) (xy 164.790882 -285.376366)
			(xy 164.790882 -285.449772) (xy 189.69407 -285.449772) (xy 189.69803 -285.400718) (xy 189.709807 -285.352934)
			(xy 189.729098 -285.307658) (xy 189.755401 -285.266062) (xy 189.788036 -285.229225) (xy 189.826157 -285.1981)
			(xy 189.868778 -285.173493) (xy 189.914794 -285.156041) (xy 189.963013 -285.146197) (xy 190.012188 -285.144216)
			(xy 190.061043 -285.150148) (xy 190.108314 -285.16384) (xy 190.152776 -285.184938) (xy 190.193279 -285.212894)
			(xy 190.228772 -285.246986) (xy 190.258337 -285.28633) (xy 190.281208 -285.329907) (xy 190.296792 -285.376588)
			(xy 190.304687 -285.425165) (xy 190.305182 -285.449772) (xy 190.304687 -285.474379) (xy 190.304508 -285.47548)
			(xy 190.623186 -285.47548) (xy 190.623186 -285.424064) (xy 190.631229 -285.373282) (xy 190.647117 -285.324383)
			(xy 190.67046 -285.278571) (xy 190.700681 -285.236975) (xy 190.737037 -285.200619) (xy 190.778633 -285.170398)
			(xy 190.824445 -285.147055) (xy 190.873344 -285.131167) (xy 190.924126 -285.123124) (xy 190.975542 -285.123124)
			(xy 191.026324 -285.131167) (xy 191.075223 -285.147055) (xy 191.121035 -285.170398) (xy 191.162631 -285.200619)
			(xy 191.198987 -285.236975) (xy 191.229208 -285.278571) (xy 191.252551 -285.324383) (xy 191.268439 -285.373282)
			(xy 191.276482 -285.424064) (xy 191.276986 -285.449772) (xy 191.276482 -285.47548) (xy 191.5734 -285.47548)
			(xy 191.5734 -285.424064) (xy 191.581443 -285.373282) (xy 191.597331 -285.324383) (xy 191.620674 -285.278571)
			(xy 191.650895 -285.236975) (xy 191.687251 -285.200619) (xy 191.728847 -285.170398) (xy 191.774659 -285.147055)
			(xy 191.823558 -285.131167) (xy 191.87434 -285.123124) (xy 191.925756 -285.123124) (xy 191.976538 -285.131167)
			(xy 192.025437 -285.147055) (xy 192.071249 -285.170398) (xy 192.112845 -285.200619) (xy 192.149201 -285.236975)
			(xy 192.179422 -285.278571) (xy 192.202765 -285.324383) (xy 192.218653 -285.373282) (xy 192.226696 -285.424064)
			(xy 192.2272 -285.449772) (xy 192.544204 -285.449772) (xy 192.548164 -285.400718) (xy 192.559941 -285.352934)
			(xy 192.579232 -285.307658) (xy 192.605535 -285.266062) (xy 192.63817 -285.229225) (xy 192.676291 -285.1981)
			(xy 192.718912 -285.173493) (xy 192.764928 -285.156041) (xy 192.813147 -285.146197) (xy 192.862322 -285.144216)
			(xy 192.911177 -285.150148) (xy 192.958448 -285.16384) (xy 193.00291 -285.184938) (xy 193.043413 -285.212894)
			(xy 193.078906 -285.246986) (xy 193.108471 -285.28633) (xy 193.131342 -285.329907) (xy 193.146926 -285.376588)
			(xy 193.154821 -285.425165) (xy 193.155316 -285.449772) (xy 193.494164 -285.449772) (xy 193.498124 -285.400718)
			(xy 193.509901 -285.352934) (xy 193.529192 -285.307658) (xy 193.555495 -285.266062) (xy 193.58813 -285.229225)
			(xy 193.626251 -285.1981) (xy 193.668872 -285.173493) (xy 193.714888 -285.156041) (xy 193.763107 -285.146197)
			(xy 193.812282 -285.144216) (xy 193.861137 -285.150148) (xy 193.908408 -285.16384) (xy 193.95287 -285.184938)
			(xy 193.993373 -285.212894) (xy 194.028866 -285.246986) (xy 194.058431 -285.28633) (xy 194.081302 -285.329907)
			(xy 194.096886 -285.376588) (xy 194.104781 -285.425165) (xy 194.105276 -285.449772) (xy 194.444124 -285.449772)
			(xy 194.448084 -285.400718) (xy 194.459861 -285.352934) (xy 194.479152 -285.307658) (xy 194.505455 -285.266062)
			(xy 194.53809 -285.229225) (xy 194.576211 -285.1981) (xy 194.618832 -285.173493) (xy 194.664848 -285.156041)
			(xy 194.713067 -285.146197) (xy 194.762242 -285.144216) (xy 194.811097 -285.150148) (xy 194.858368 -285.16384)
			(xy 194.90283 -285.184938) (xy 194.943333 -285.212894) (xy 194.978826 -285.246986) (xy 195.008391 -285.28633)
			(xy 195.031262 -285.329907) (xy 195.046846 -285.376588) (xy 195.054741 -285.425165) (xy 195.055236 -285.449772)
			(xy 195.394084 -285.449772) (xy 195.398044 -285.400718) (xy 195.409821 -285.352934) (xy 195.429112 -285.307658)
			(xy 195.455415 -285.266062) (xy 195.48805 -285.229225) (xy 195.526171 -285.1981) (xy 195.568792 -285.173493)
			(xy 195.614808 -285.156041) (xy 195.663027 -285.146197) (xy 195.712202 -285.144216) (xy 195.761057 -285.150148)
			(xy 195.808328 -285.16384) (xy 195.85279 -285.184938) (xy 195.893293 -285.212894) (xy 195.928786 -285.246986)
			(xy 195.958351 -285.28633) (xy 195.981222 -285.329907) (xy 195.996806 -285.376588) (xy 196.004701 -285.425165)
			(xy 196.005196 -285.449772) (xy 196.344044 -285.449772) (xy 196.348004 -285.400718) (xy 196.359781 -285.352934)
			(xy 196.379072 -285.307658) (xy 196.405375 -285.266062) (xy 196.43801 -285.229225) (xy 196.476131 -285.1981)
			(xy 196.518752 -285.173493) (xy 196.564768 -285.156041) (xy 196.612987 -285.146197) (xy 196.662162 -285.144216)
			(xy 196.711017 -285.150148) (xy 196.758288 -285.16384) (xy 196.80275 -285.184938) (xy 196.843253 -285.212894)
			(xy 196.878746 -285.246986) (xy 196.908311 -285.28633) (xy 196.931182 -285.329907) (xy 196.946766 -285.376588)
			(xy 196.954661 -285.425165) (xy 196.955156 -285.449772) (xy 196.954661 -285.474379) (xy 196.954482 -285.47548)
			(xy 197.273414 -285.47548) (xy 197.273414 -285.424064) (xy 197.281457 -285.373282) (xy 197.297345 -285.324383)
			(xy 197.320688 -285.278571) (xy 197.350909 -285.236975) (xy 197.387265 -285.200619) (xy 197.428861 -285.170398)
			(xy 197.474673 -285.147055) (xy 197.523572 -285.131167) (xy 197.574354 -285.123124) (xy 197.62577 -285.123124)
			(xy 197.676552 -285.131167) (xy 197.725451 -285.147055) (xy 197.771263 -285.170398) (xy 197.812859 -285.200619)
			(xy 197.849215 -285.236975) (xy 197.879436 -285.278571) (xy 197.902779 -285.324383) (xy 197.918667 -285.373282)
			(xy 197.92671 -285.424064) (xy 197.927214 -285.449772) (xy 197.92671 -285.47548) (xy 198.223374 -285.47548)
			(xy 198.223374 -285.424064) (xy 198.231417 -285.373282) (xy 198.247305 -285.324383) (xy 198.270648 -285.278571)
			(xy 198.300869 -285.236975) (xy 198.337225 -285.200619) (xy 198.378821 -285.170398) (xy 198.424633 -285.147055)
			(xy 198.473532 -285.131167) (xy 198.524314 -285.123124) (xy 198.57573 -285.123124) (xy 198.626512 -285.131167)
			(xy 198.675411 -285.147055) (xy 198.721223 -285.170398) (xy 198.762819 -285.200619) (xy 198.799175 -285.236975)
			(xy 198.829396 -285.278571) (xy 198.852739 -285.324383) (xy 198.868627 -285.373282) (xy 198.87667 -285.424064)
			(xy 198.877174 -285.449772) (xy 198.877169 -285.450026) (xy 199.194432 -285.450026) (xy 199.198392 -285.400972)
			(xy 199.210169 -285.353188) (xy 199.22946 -285.307912) (xy 199.255763 -285.266316) (xy 199.288398 -285.229479)
			(xy 199.326519 -285.198354) (xy 199.36914 -285.173747) (xy 199.415156 -285.156295) (xy 199.463375 -285.146451)
			(xy 199.51255 -285.14447) (xy 199.561405 -285.150402) (xy 199.608676 -285.164094) (xy 199.653138 -285.185192)
			(xy 199.693641 -285.213148) (xy 199.729134 -285.24724) (xy 199.758699 -285.286584) (xy 199.78157 -285.330161)
			(xy 199.797154 -285.376842) (xy 199.805049 -285.425419) (xy 199.805544 -285.450026) (xy 199.805077 -285.473258)
			(xy 224.751517 -285.473258) (xy 224.751517 -285.418742) (xy 224.759276 -285.364782) (xy 224.774636 -285.312475)
			(xy 224.797284 -285.262887) (xy 224.826759 -285.217027) (xy 224.862462 -285.175829) (xy 224.903664 -285.140132)
			(xy 224.949527 -285.110662) (xy 224.999118 -285.08802) (xy 225.051427 -285.072666) (xy 225.105388 -285.064914)
			(xy 225.132646 -285.064454) (xy 225.161385 -285.064962) (xy 225.218213 -285.07359) (xy 225.273103 -285.090645)
			(xy 225.324815 -285.115739) (xy 225.372177 -285.148307) (xy 225.393504 -285.167578) (xy 225.400616 -285.174182)
			(xy 225.418142 -285.181294) (xy 225.50755 -285.181294) (xy 225.525076 -285.174182) (xy 225.532188 -285.167578)
			(xy 225.553515 -285.148308) (xy 225.600878 -285.115743) (xy 225.652589 -285.090652) (xy 225.70748 -285.073602)
			(xy 225.764307 -285.06498) (xy 225.821785 -285.06498) (xy 225.878612 -285.073602) (xy 225.933503 -285.090652)
			(xy 225.985214 -285.115743) (xy 226.032577 -285.148308) (xy 226.053904 -285.167578) (xy 226.061016 -285.174182)
			(xy 226.078542 -285.181294) (xy 226.16795 -285.181294) (xy 226.185476 -285.174182) (xy 226.192588 -285.167578)
			(xy 226.213902 -285.148292) (xy 226.261267 -285.115726) (xy 226.312982 -285.090636) (xy 226.367876 -285.073589)
			(xy 226.424706 -285.064972) (xy 226.453446 -285.064454) (xy 226.483568 -285.065058) (xy 226.543063 -285.074531)
			(xy 226.60033 -285.093234) (xy 226.653948 -285.120702) (xy 226.702584 -285.156254) (xy 226.72421 -285.17723)
			(xy 226.731322 -285.184596) (xy 226.750118 -285.192216) (xy 226.842574 -285.192216) (xy 226.86137 -285.184596)
			(xy 226.868482 -285.17723) (xy 226.890097 -285.156239) (xy 226.938728 -285.12067) (xy 226.992347 -285.093192)
			(xy 227.049619 -285.074487) (xy 227.109121 -285.06502) (xy 227.139246 -285.064454) (xy 227.166492 -285.065019)
			(xy 227.22043 -285.07278) (xy 227.272714 -285.088138) (xy 227.32228 -285.110779) (xy 227.36812 -285.140244)
			(xy 227.409301 -285.175932) (xy 227.444984 -285.217117) (xy 227.474443 -285.26296) (xy 227.497078 -285.31253)
			(xy 227.512429 -285.364815) (xy 227.520184 -285.418754) (xy 227.520184 -285.473246) (xy 227.512429 -285.527185)
			(xy 227.497078 -285.57947) (xy 227.474443 -285.62904) (xy 227.444984 -285.674883) (xy 227.409301 -285.716068)
			(xy 227.36812 -285.751756) (xy 227.32228 -285.781221) (xy 227.272714 -285.803862) (xy 227.22043 -285.81922)
			(xy 227.166492 -285.826981) (xy 227.139246 -285.82747) (xy 227.109124 -285.826865) (xy 227.04963 -285.817391)
			(xy 226.992362 -285.798688) (xy 226.938745 -285.77122) (xy 226.890108 -285.735669) (xy 226.868482 -285.714694)
			(xy 226.86137 -285.707328) (xy 226.842574 -285.699708) (xy 226.750118 -285.699708) (xy 226.731322 -285.707328)
			(xy 226.72421 -285.714694) (xy 226.702603 -285.735694) (xy 226.653969 -285.77126) (xy 226.600349 -285.798736)
			(xy 226.543074 -285.81744) (xy 226.483572 -285.826905) (xy 226.453446 -285.82747) (xy 226.424707 -285.82696)
			(xy 226.36788 -285.818332) (xy 226.312989 -285.801277) (xy 226.261278 -285.776183) (xy 226.213915 -285.743617)
			(xy 226.192588 -285.724346) (xy 226.185476 -285.717742) (xy 226.16795 -285.71063) (xy 226.078542 -285.71063)
			(xy 226.061016 -285.717742) (xy 226.053904 -285.724346) (xy 226.032577 -285.743616) (xy 225.985214 -285.776181)
			(xy 225.933503 -285.801272) (xy 225.878612 -285.818322) (xy 225.821785 -285.826944) (xy 225.764307 -285.826944)
			(xy 225.70748 -285.818322) (xy 225.652589 -285.801272) (xy 225.600878 -285.776181) (xy 225.553515 -285.743616)
			(xy 225.532188 -285.724346) (xy 225.525076 -285.717742) (xy 225.50755 -285.71063) (xy 225.418142 -285.71063)
			(xy 225.400616 -285.717742) (xy 225.393504 -285.724346) (xy 225.372197 -285.74364) (xy 225.32483 -285.776203)
			(xy 225.273113 -285.801292) (xy 225.218218 -285.818337) (xy 225.161386 -285.826953) (xy 225.132646 -285.82747)
			(xy 225.105388 -285.827086) (xy 225.051427 -285.819334) (xy 224.999118 -285.80398) (xy 224.949527 -285.781338)
			(xy 224.903664 -285.751868) (xy 224.862462 -285.716171) (xy 224.826759 -285.674973) (xy 224.797284 -285.629113)
			(xy 224.774636 -285.579525) (xy 224.759276 -285.527218) (xy 224.751517 -285.473258) (xy 199.805077 -285.473258)
			(xy 199.805049 -285.474633) (xy 199.797154 -285.52321) (xy 199.78157 -285.569891) (xy 199.758699 -285.613468)
			(xy 199.729134 -285.652812) (xy 199.693641 -285.686904) (xy 199.653138 -285.71486) (xy 199.608676 -285.735958)
			(xy 199.561405 -285.74965) (xy 199.51255 -285.755582) (xy 199.463375 -285.753601) (xy 199.415156 -285.743757)
			(xy 199.36914 -285.726305) (xy 199.326519 -285.701698) (xy 199.288398 -285.670573) (xy 199.255763 -285.633736)
			(xy 199.22946 -285.59214) (xy 199.210169 -285.546864) (xy 199.198392 -285.49908) (xy 199.194432 -285.450026)
			(xy 198.877169 -285.450026) (xy 198.87667 -285.47548) (xy 198.868627 -285.526262) (xy 198.852739 -285.575161)
			(xy 198.829396 -285.620973) (xy 198.799175 -285.662569) (xy 198.762819 -285.698925) (xy 198.721223 -285.729146)
			(xy 198.675411 -285.752489) (xy 198.626512 -285.768377) (xy 198.57573 -285.77642) (xy 198.524314 -285.77642)
			(xy 198.473532 -285.768377) (xy 198.424633 -285.752489) (xy 198.378821 -285.729146) (xy 198.337225 -285.698925)
			(xy 198.300869 -285.662569) (xy 198.270648 -285.620973) (xy 198.247305 -285.575161) (xy 198.231417 -285.526262)
			(xy 198.223374 -285.47548) (xy 197.92671 -285.47548) (xy 197.918667 -285.526262) (xy 197.902779 -285.575161)
			(xy 197.879436 -285.620973) (xy 197.849215 -285.662569) (xy 197.812859 -285.698925) (xy 197.771263 -285.729146)
			(xy 197.725451 -285.752489) (xy 197.676552 -285.768377) (xy 197.62577 -285.77642) (xy 197.574354 -285.77642)
			(xy 197.523572 -285.768377) (xy 197.474673 -285.752489) (xy 197.428861 -285.729146) (xy 197.387265 -285.698925)
			(xy 197.350909 -285.662569) (xy 197.320688 -285.620973) (xy 197.297345 -285.575161) (xy 197.281457 -285.526262)
			(xy 197.273414 -285.47548) (xy 196.954482 -285.47548) (xy 196.946766 -285.522956) (xy 196.931182 -285.569637)
			(xy 196.908311 -285.613214) (xy 196.878746 -285.652558) (xy 196.843253 -285.68665) (xy 196.80275 -285.714606)
			(xy 196.758288 -285.735704) (xy 196.711017 -285.749396) (xy 196.662162 -285.755328) (xy 196.612987 -285.753347)
			(xy 196.564768 -285.743503) (xy 196.518752 -285.726051) (xy 196.476131 -285.701444) (xy 196.43801 -285.670319)
			(xy 196.405375 -285.633482) (xy 196.379072 -285.591886) (xy 196.359781 -285.54661) (xy 196.348004 -285.498826)
			(xy 196.344044 -285.449772) (xy 196.005196 -285.449772) (xy 196.004701 -285.474379) (xy 195.996806 -285.522956)
			(xy 195.981222 -285.569637) (xy 195.958351 -285.613214) (xy 195.928786 -285.652558) (xy 195.893293 -285.68665)
			(xy 195.85279 -285.714606) (xy 195.808328 -285.735704) (xy 195.761057 -285.749396) (xy 195.712202 -285.755328)
			(xy 195.663027 -285.753347) (xy 195.614808 -285.743503) (xy 195.568792 -285.726051) (xy 195.526171 -285.701444)
			(xy 195.48805 -285.670319) (xy 195.455415 -285.633482) (xy 195.429112 -285.591886) (xy 195.409821 -285.54661)
			(xy 195.398044 -285.498826) (xy 195.394084 -285.449772) (xy 195.055236 -285.449772) (xy 195.054741 -285.474379)
			(xy 195.046846 -285.522956) (xy 195.031262 -285.569637) (xy 195.008391 -285.613214) (xy 194.978826 -285.652558)
			(xy 194.943333 -285.68665) (xy 194.90283 -285.714606) (xy 194.858368 -285.735704) (xy 194.811097 -285.749396)
			(xy 194.762242 -285.755328) (xy 194.713067 -285.753347) (xy 194.664848 -285.743503) (xy 194.618832 -285.726051)
			(xy 194.576211 -285.701444) (xy 194.53809 -285.670319) (xy 194.505455 -285.633482) (xy 194.479152 -285.591886)
			(xy 194.459861 -285.54661) (xy 194.448084 -285.498826) (xy 194.444124 -285.449772) (xy 194.105276 -285.449772)
			(xy 194.104781 -285.474379) (xy 194.096886 -285.522956) (xy 194.081302 -285.569637) (xy 194.058431 -285.613214)
			(xy 194.028866 -285.652558) (xy 193.993373 -285.68665) (xy 193.95287 -285.714606) (xy 193.908408 -285.735704)
			(xy 193.861137 -285.749396) (xy 193.812282 -285.755328) (xy 193.763107 -285.753347) (xy 193.714888 -285.743503)
			(xy 193.668872 -285.726051) (xy 193.626251 -285.701444) (xy 193.58813 -285.670319) (xy 193.555495 -285.633482)
			(xy 193.529192 -285.591886) (xy 193.509901 -285.54661) (xy 193.498124 -285.498826) (xy 193.494164 -285.449772)
			(xy 193.155316 -285.449772) (xy 193.154821 -285.474379) (xy 193.146926 -285.522956) (xy 193.131342 -285.569637)
			(xy 193.108471 -285.613214) (xy 193.078906 -285.652558) (xy 193.043413 -285.68665) (xy 193.00291 -285.714606)
			(xy 192.958448 -285.735704) (xy 192.911177 -285.749396) (xy 192.862322 -285.755328) (xy 192.813147 -285.753347)
			(xy 192.764928 -285.743503) (xy 192.718912 -285.726051) (xy 192.676291 -285.701444) (xy 192.63817 -285.670319)
			(xy 192.605535 -285.633482) (xy 192.579232 -285.591886) (xy 192.559941 -285.54661) (xy 192.548164 -285.498826)
			(xy 192.544204 -285.449772) (xy 192.2272 -285.449772) (xy 192.226696 -285.47548) (xy 192.218653 -285.526262)
			(xy 192.202765 -285.575161) (xy 192.179422 -285.620973) (xy 192.149201 -285.662569) (xy 192.112845 -285.698925)
			(xy 192.071249 -285.729146) (xy 192.025437 -285.752489) (xy 191.976538 -285.768377) (xy 191.925756 -285.77642)
			(xy 191.87434 -285.77642) (xy 191.823558 -285.768377) (xy 191.774659 -285.752489) (xy 191.728847 -285.729146)
			(xy 191.687251 -285.698925) (xy 191.650895 -285.662569) (xy 191.620674 -285.620973) (xy 191.597331 -285.575161)
			(xy 191.581443 -285.526262) (xy 191.5734 -285.47548) (xy 191.276482 -285.47548) (xy 191.268439 -285.526262)
			(xy 191.252551 -285.575161) (xy 191.229208 -285.620973) (xy 191.198987 -285.662569) (xy 191.162631 -285.698925)
			(xy 191.121035 -285.729146) (xy 191.075223 -285.752489) (xy 191.026324 -285.768377) (xy 190.975542 -285.77642)
			(xy 190.924126 -285.77642) (xy 190.873344 -285.768377) (xy 190.824445 -285.752489) (xy 190.778633 -285.729146)
			(xy 190.737037 -285.698925) (xy 190.700681 -285.662569) (xy 190.67046 -285.620973) (xy 190.647117 -285.575161)
			(xy 190.631229 -285.526262) (xy 190.623186 -285.47548) (xy 190.304508 -285.47548) (xy 190.296792 -285.522956)
			(xy 190.281208 -285.569637) (xy 190.258337 -285.613214) (xy 190.228772 -285.652558) (xy 190.193279 -285.68665)
			(xy 190.152776 -285.714606) (xy 190.108314 -285.735704) (xy 190.061043 -285.749396) (xy 190.012188 -285.755328)
			(xy 189.963013 -285.753347) (xy 189.914794 -285.743503) (xy 189.868778 -285.726051) (xy 189.826157 -285.701444)
			(xy 189.788036 -285.670319) (xy 189.755401 -285.633482) (xy 189.729098 -285.591886) (xy 189.709807 -285.54661)
			(xy 189.69803 -285.498826) (xy 189.69407 -285.449772) (xy 164.790882 -285.449772) (xy 164.790882 -285.523178)
			(xy 164.791053 -285.529331) (xy 164.794011 -285.541275) (xy 164.796724 -285.5468) (xy 164.804852 -285.557976)
			(xy 164.819584 -285.57347) (xy 164.826188 -285.580582) (xy 164.849302 -285.591504) (xy 164.852858 -285.59252)
			(xy 164.86505 -285.59633) (xy 164.869622 -285.597092) (xy 164.895695 -285.601169) (xy 164.946185 -285.616517)
			(xy 164.993597 -285.639686) (xy 165.036729 -285.67009) (xy 165.074486 -285.706957) (xy 165.10591 -285.749351)
			(xy 165.130203 -285.796198) (xy 165.14675 -285.846307) (xy 165.155131 -285.898408) (xy 165.155131 -285.924752)
			(xy 165.469074 -285.924752) (xy 165.473034 -285.875698) (xy 165.484811 -285.827914) (xy 165.504102 -285.782638)
			(xy 165.530405 -285.741042) (xy 165.56304 -285.704205) (xy 165.601161 -285.67308) (xy 165.643782 -285.648473)
			(xy 165.689798 -285.631021) (xy 165.738017 -285.621177) (xy 165.787192 -285.619196) (xy 165.836047 -285.625128)
			(xy 165.883318 -285.63882) (xy 165.92778 -285.659918) (xy 165.968283 -285.687874) (xy 166.003776 -285.721966)
			(xy 166.033341 -285.76131) (xy 166.056212 -285.804887) (xy 166.071796 -285.851568) (xy 166.079691 -285.900145)
			(xy 166.080186 -285.924752) (xy 166.419288 -285.924752) (xy 166.423248 -285.875698) (xy 166.435025 -285.827914)
			(xy 166.454316 -285.782638) (xy 166.480619 -285.741042) (xy 166.513254 -285.704205) (xy 166.551375 -285.67308)
			(xy 166.593996 -285.648473) (xy 166.640012 -285.631021) (xy 166.688231 -285.621177) (xy 166.737406 -285.619196)
			(xy 166.786261 -285.625128) (xy 166.833532 -285.63882) (xy 166.877994 -285.659918) (xy 166.918497 -285.687874)
			(xy 166.95399 -285.721966) (xy 166.983555 -285.76131) (xy 167.006426 -285.804887) (xy 167.02201 -285.851568)
			(xy 167.029905 -285.900145) (xy 167.0304 -285.924752) (xy 167.369248 -285.924752) (xy 167.373208 -285.875698)
			(xy 167.384985 -285.827914) (xy 167.404276 -285.782638) (xy 167.430579 -285.741042) (xy 167.463214 -285.704205)
			(xy 167.501335 -285.67308) (xy 167.543956 -285.648473) (xy 167.589972 -285.631021) (xy 167.638191 -285.621177)
			(xy 167.687366 -285.619196) (xy 167.736221 -285.625128) (xy 167.783492 -285.63882) (xy 167.827954 -285.659918)
			(xy 167.868457 -285.687874) (xy 167.90395 -285.721966) (xy 167.933515 -285.76131) (xy 167.956386 -285.804887)
			(xy 167.97197 -285.851568) (xy 167.979865 -285.900145) (xy 167.98036 -285.924752) (xy 168.319208 -285.924752)
			(xy 168.323168 -285.875698) (xy 168.334945 -285.827914) (xy 168.354236 -285.782638) (xy 168.380539 -285.741042)
			(xy 168.413174 -285.704205) (xy 168.451295 -285.67308) (xy 168.493916 -285.648473) (xy 168.539932 -285.631021)
			(xy 168.588151 -285.621177) (xy 168.637326 -285.619196) (xy 168.686181 -285.625128) (xy 168.733452 -285.63882)
			(xy 168.777914 -285.659918) (xy 168.818417 -285.687874) (xy 168.85391 -285.721966) (xy 168.883475 -285.76131)
			(xy 168.906346 -285.804887) (xy 168.92193 -285.851568) (xy 168.929825 -285.900145) (xy 168.93032 -285.924752)
			(xy 169.269168 -285.924752) (xy 169.273128 -285.875698) (xy 169.284905 -285.827914) (xy 169.304196 -285.782638)
			(xy 169.330499 -285.741042) (xy 169.363134 -285.704205) (xy 169.401255 -285.67308) (xy 169.443876 -285.648473)
			(xy 169.489892 -285.631021) (xy 169.538111 -285.621177) (xy 169.587286 -285.619196) (xy 169.636141 -285.625128)
			(xy 169.683412 -285.63882) (xy 169.727874 -285.659918) (xy 169.768377 -285.687874) (xy 169.80387 -285.721966)
			(xy 169.833435 -285.76131) (xy 169.856306 -285.804887) (xy 169.87189 -285.851568) (xy 169.879785 -285.900145)
			(xy 169.88028 -285.924752) (xy 170.219128 -285.924752) (xy 170.223088 -285.875698) (xy 170.234865 -285.827914)
			(xy 170.254156 -285.782638) (xy 170.280459 -285.741042) (xy 170.313094 -285.704205) (xy 170.351215 -285.67308)
			(xy 170.393836 -285.648473) (xy 170.439852 -285.631021) (xy 170.488071 -285.621177) (xy 170.537246 -285.619196)
			(xy 170.586101 -285.625128) (xy 170.633372 -285.63882) (xy 170.677834 -285.659918) (xy 170.718337 -285.687874)
			(xy 170.75383 -285.721966) (xy 170.783395 -285.76131) (xy 170.806266 -285.804887) (xy 170.82185 -285.851568)
			(xy 170.829745 -285.900145) (xy 170.83024 -285.924752) (xy 171.169088 -285.924752) (xy 171.173048 -285.875698)
			(xy 171.184825 -285.827914) (xy 171.204116 -285.782638) (xy 171.230419 -285.741042) (xy 171.263054 -285.704205)
			(xy 171.301175 -285.67308) (xy 171.343796 -285.648473) (xy 171.389812 -285.631021) (xy 171.438031 -285.621177)
			(xy 171.487206 -285.619196) (xy 171.536061 -285.625128) (xy 171.583332 -285.63882) (xy 171.627794 -285.659918)
			(xy 171.668297 -285.687874) (xy 171.70379 -285.721966) (xy 171.733355 -285.76131) (xy 171.756226 -285.804887)
			(xy 171.77181 -285.851568) (xy 171.779705 -285.900145) (xy 171.7802 -285.924752) (xy 172.119048 -285.924752)
			(xy 172.123008 -285.875698) (xy 172.134785 -285.827914) (xy 172.154076 -285.782638) (xy 172.180379 -285.741042)
			(xy 172.213014 -285.704205) (xy 172.251135 -285.67308) (xy 172.293756 -285.648473) (xy 172.339772 -285.631021)
			(xy 172.387991 -285.621177) (xy 172.437166 -285.619196) (xy 172.486021 -285.625128) (xy 172.533292 -285.63882)
			(xy 172.577754 -285.659918) (xy 172.618257 -285.687874) (xy 172.65375 -285.721966) (xy 172.683315 -285.76131)
			(xy 172.706186 -285.804887) (xy 172.72177 -285.851568) (xy 172.729665 -285.900145) (xy 172.73016 -285.924752)
			(xy 173.069262 -285.924752) (xy 173.073222 -285.875698) (xy 173.084999 -285.827914) (xy 173.10429 -285.782638)
			(xy 173.130593 -285.741042) (xy 173.163228 -285.704205) (xy 173.201349 -285.67308) (xy 173.24397 -285.648473)
			(xy 173.289986 -285.631021) (xy 173.338205 -285.621177) (xy 173.38738 -285.619196) (xy 173.436235 -285.625128)
			(xy 173.483506 -285.63882) (xy 173.527968 -285.659918) (xy 173.568471 -285.687874) (xy 173.603964 -285.721966)
			(xy 173.633529 -285.76131) (xy 173.6564 -285.804887) (xy 173.671984 -285.851568) (xy 173.679879 -285.900145)
			(xy 173.680374 -285.924752) (xy 174.019222 -285.924752) (xy 174.023182 -285.875698) (xy 174.034959 -285.827914)
			(xy 174.05425 -285.782638) (xy 174.080553 -285.741042) (xy 174.113188 -285.704205) (xy 174.151309 -285.67308)
			(xy 174.19393 -285.648473) (xy 174.239946 -285.631021) (xy 174.288165 -285.621177) (xy 174.33734 -285.619196)
			(xy 174.386195 -285.625128) (xy 174.433466 -285.63882) (xy 174.477928 -285.659918) (xy 174.518431 -285.687874)
			(xy 174.553924 -285.721966) (xy 174.583489 -285.76131) (xy 174.60636 -285.804887) (xy 174.621944 -285.851568)
			(xy 174.629839 -285.900145) (xy 174.630334 -285.924752) (xy 175.919142 -285.924752) (xy 175.923102 -285.875698)
			(xy 175.934879 -285.827914) (xy 175.95417 -285.782638) (xy 175.980473 -285.741042) (xy 176.013108 -285.704205)
			(xy 176.051229 -285.67308) (xy 176.09385 -285.648473) (xy 176.139866 -285.631021) (xy 176.188085 -285.621177)
			(xy 176.23726 -285.619196) (xy 176.286115 -285.625128) (xy 176.333386 -285.63882) (xy 176.377848 -285.659918)
			(xy 176.418351 -285.687874) (xy 176.453844 -285.721966) (xy 176.483409 -285.76131) (xy 176.50628 -285.804887)
			(xy 176.521864 -285.851568) (xy 176.529759 -285.900145) (xy 176.530254 -285.924752) (xy 176.869102 -285.924752)
			(xy 176.873062 -285.875698) (xy 176.884839 -285.827914) (xy 176.90413 -285.782638) (xy 176.930433 -285.741042)
			(xy 176.963068 -285.704205) (xy 177.001189 -285.67308) (xy 177.04381 -285.648473) (xy 177.089826 -285.631021)
			(xy 177.138045 -285.621177) (xy 177.18722 -285.619196) (xy 177.236075 -285.625128) (xy 177.283346 -285.63882)
			(xy 177.327808 -285.659918) (xy 177.368311 -285.687874) (xy 177.403804 -285.721966) (xy 177.433369 -285.76131)
			(xy 177.45624 -285.804887) (xy 177.471824 -285.851568) (xy 177.479719 -285.900145) (xy 177.480214 -285.924752)
			(xy 177.819062 -285.924752) (xy 177.823022 -285.875698) (xy 177.834799 -285.827914) (xy 177.85409 -285.782638)
			(xy 177.880393 -285.741042) (xy 177.913028 -285.704205) (xy 177.951149 -285.67308) (xy 177.99377 -285.648473)
			(xy 178.039786 -285.631021) (xy 178.088005 -285.621177) (xy 178.13718 -285.619196) (xy 178.186035 -285.625128)
			(xy 178.233306 -285.63882) (xy 178.277768 -285.659918) (xy 178.318271 -285.687874) (xy 178.353764 -285.721966)
			(xy 178.383329 -285.76131) (xy 178.4062 -285.804887) (xy 178.421784 -285.851568) (xy 178.429679 -285.900145)
			(xy 178.430174 -285.924752) (xy 178.769276 -285.924752) (xy 178.773236 -285.875698) (xy 178.785013 -285.827914)
			(xy 178.804304 -285.782638) (xy 178.830607 -285.741042) (xy 178.863242 -285.704205) (xy 178.901363 -285.67308)
			(xy 178.943984 -285.648473) (xy 178.99 -285.631021) (xy 179.038219 -285.621177) (xy 179.087394 -285.619196)
			(xy 179.136249 -285.625128) (xy 179.18352 -285.63882) (xy 179.227982 -285.659918) (xy 179.268485 -285.687874)
			(xy 179.303978 -285.721966) (xy 179.333543 -285.76131) (xy 179.356414 -285.804887) (xy 179.371998 -285.851568)
			(xy 179.379893 -285.900145) (xy 179.380388 -285.924752) (xy 179.719236 -285.924752) (xy 179.723196 -285.875698)
			(xy 179.734973 -285.827914) (xy 179.754264 -285.782638) (xy 179.780567 -285.741042) (xy 179.813202 -285.704205)
			(xy 179.851323 -285.67308) (xy 179.893944 -285.648473) (xy 179.93996 -285.631021) (xy 179.988179 -285.621177)
			(xy 180.037354 -285.619196) (xy 180.086209 -285.625128) (xy 180.13348 -285.63882) (xy 180.177942 -285.659918)
			(xy 180.218445 -285.687874) (xy 180.253938 -285.721966) (xy 180.283503 -285.76131) (xy 180.306374 -285.804887)
			(xy 180.321958 -285.851568) (xy 180.329853 -285.900145) (xy 180.330348 -285.924752) (xy 180.669196 -285.924752)
			(xy 180.673156 -285.875698) (xy 180.684933 -285.827914) (xy 180.704224 -285.782638) (xy 180.730527 -285.741042)
			(xy 180.763162 -285.704205) (xy 180.801283 -285.67308) (xy 180.843904 -285.648473) (xy 180.88992 -285.631021)
			(xy 180.938139 -285.621177) (xy 180.987314 -285.619196) (xy 181.036169 -285.625128) (xy 181.08344 -285.63882)
			(xy 181.127902 -285.659918) (xy 181.168405 -285.687874) (xy 181.203898 -285.721966) (xy 181.233463 -285.76131)
			(xy 181.256334 -285.804887) (xy 181.271918 -285.851568) (xy 181.279813 -285.900145) (xy 181.280308 -285.924752)
			(xy 181.619156 -285.924752) (xy 181.623116 -285.875698) (xy 181.634893 -285.827914) (xy 181.654184 -285.782638)
			(xy 181.680487 -285.741042) (xy 181.713122 -285.704205) (xy 181.751243 -285.67308) (xy 181.793864 -285.648473)
			(xy 181.83988 -285.631021) (xy 181.888099 -285.621177) (xy 181.937274 -285.619196) (xy 181.986129 -285.625128)
			(xy 182.0334 -285.63882) (xy 182.077862 -285.659918) (xy 182.118365 -285.687874) (xy 182.153858 -285.721966)
			(xy 182.183423 -285.76131) (xy 182.206294 -285.804887) (xy 182.221878 -285.851568) (xy 182.229773 -285.900145)
			(xy 182.230268 -285.924752) (xy 182.569116 -285.924752) (xy 182.573076 -285.875698) (xy 182.584853 -285.827914)
			(xy 182.604144 -285.782638) (xy 182.630447 -285.741042) (xy 182.663082 -285.704205) (xy 182.701203 -285.67308)
			(xy 182.743824 -285.648473) (xy 182.78984 -285.631021) (xy 182.838059 -285.621177) (xy 182.887234 -285.619196)
			(xy 182.936089 -285.625128) (xy 182.98336 -285.63882) (xy 183.027822 -285.659918) (xy 183.068325 -285.687874)
			(xy 183.103818 -285.721966) (xy 183.133383 -285.76131) (xy 183.156254 -285.804887) (xy 183.171838 -285.851568)
			(xy 183.179733 -285.900145) (xy 183.180228 -285.924752) (xy 183.519076 -285.924752) (xy 183.523036 -285.875698)
			(xy 183.534813 -285.827914) (xy 183.554104 -285.782638) (xy 183.580407 -285.741042) (xy 183.613042 -285.704205)
			(xy 183.651163 -285.67308) (xy 183.693784 -285.648473) (xy 183.7398 -285.631021) (xy 183.788019 -285.621177)
			(xy 183.837194 -285.619196) (xy 183.886049 -285.625128) (xy 183.93332 -285.63882) (xy 183.977782 -285.659918)
			(xy 184.018285 -285.687874) (xy 184.053778 -285.721966) (xy 184.083343 -285.76131) (xy 184.106214 -285.804887)
			(xy 184.121798 -285.851568) (xy 184.129693 -285.900145) (xy 184.130188 -285.924752) (xy 184.469036 -285.924752)
			(xy 184.472996 -285.875698) (xy 184.484773 -285.827914) (xy 184.504064 -285.782638) (xy 184.530367 -285.741042)
			(xy 184.563002 -285.704205) (xy 184.601123 -285.67308) (xy 184.643744 -285.648473) (xy 184.68976 -285.631021)
			(xy 184.737979 -285.621177) (xy 184.787154 -285.619196) (xy 184.836009 -285.625128) (xy 184.88328 -285.63882)
			(xy 184.927742 -285.659918) (xy 184.968245 -285.687874) (xy 185.003738 -285.721966) (xy 185.033303 -285.76131)
			(xy 185.056174 -285.804887) (xy 185.071758 -285.851568) (xy 185.079653 -285.900145) (xy 185.080148 -285.924752)
			(xy 185.41925 -285.924752) (xy 185.42321 -285.875698) (xy 185.434987 -285.827914) (xy 185.454278 -285.782638)
			(xy 185.480581 -285.741042) (xy 185.513216 -285.704205) (xy 185.551337 -285.67308) (xy 185.593958 -285.648473)
			(xy 185.639974 -285.631021) (xy 185.688193 -285.621177) (xy 185.737368 -285.619196) (xy 185.786223 -285.625128)
			(xy 185.833494 -285.63882) (xy 185.877956 -285.659918) (xy 185.918459 -285.687874) (xy 185.953952 -285.721966)
			(xy 185.983517 -285.76131) (xy 186.006388 -285.804887) (xy 186.021972 -285.851568) (xy 186.029867 -285.900145)
			(xy 186.030362 -285.924752) (xy 186.36921 -285.924752) (xy 186.37317 -285.875698) (xy 186.384947 -285.827914)
			(xy 186.404238 -285.782638) (xy 186.430541 -285.741042) (xy 186.463176 -285.704205) (xy 186.501297 -285.67308)
			(xy 186.543918 -285.648473) (xy 186.589934 -285.631021) (xy 186.638153 -285.621177) (xy 186.687328 -285.619196)
			(xy 186.736183 -285.625128) (xy 186.783454 -285.63882) (xy 186.827916 -285.659918) (xy 186.868419 -285.687874)
			(xy 186.903912 -285.721966) (xy 186.933477 -285.76131) (xy 186.956348 -285.804887) (xy 186.971932 -285.851568)
			(xy 186.979827 -285.900145) (xy 186.980322 -285.924752) (xy 186.979827 -285.949359) (xy 186.971932 -285.997936)
			(xy 186.956348 -286.044617) (xy 186.933477 -286.088194) (xy 186.903912 -286.127538) (xy 186.868419 -286.16163)
			(xy 186.827916 -286.189586) (xy 186.783454 -286.210684) (xy 186.736183 -286.224376) (xy 186.687328 -286.230308)
			(xy 186.638153 -286.228327) (xy 186.589934 -286.218483) (xy 186.543918 -286.201031) (xy 186.501297 -286.176424)
			(xy 186.463176 -286.145299) (xy 186.430541 -286.108462) (xy 186.404238 -286.066866) (xy 186.384947 -286.02159)
			(xy 186.37317 -285.973806) (xy 186.36921 -285.924752) (xy 186.030362 -285.924752) (xy 186.029867 -285.949359)
			(xy 186.021972 -285.997936) (xy 186.006388 -286.044617) (xy 185.983517 -286.088194) (xy 185.953952 -286.127538)
			(xy 185.918459 -286.16163) (xy 185.877956 -286.189586) (xy 185.833494 -286.210684) (xy 185.786223 -286.224376)
			(xy 185.737368 -286.230308) (xy 185.688193 -286.228327) (xy 185.639974 -286.218483) (xy 185.593958 -286.201031)
			(xy 185.551337 -286.176424) (xy 185.513216 -286.145299) (xy 185.480581 -286.108462) (xy 185.454278 -286.066866)
			(xy 185.434987 -286.02159) (xy 185.42321 -285.973806) (xy 185.41925 -285.924752) (xy 185.080148 -285.924752)
			(xy 185.079653 -285.949359) (xy 185.071758 -285.997936) (xy 185.056174 -286.044617) (xy 185.033303 -286.088194)
			(xy 185.003738 -286.127538) (xy 184.968245 -286.16163) (xy 184.927742 -286.189586) (xy 184.88328 -286.210684)
			(xy 184.836009 -286.224376) (xy 184.787154 -286.230308) (xy 184.737979 -286.228327) (xy 184.68976 -286.218483)
			(xy 184.643744 -286.201031) (xy 184.601123 -286.176424) (xy 184.563002 -286.145299) (xy 184.530367 -286.108462)
			(xy 184.504064 -286.066866) (xy 184.484773 -286.02159) (xy 184.472996 -285.973806) (xy 184.469036 -285.924752)
			(xy 184.130188 -285.924752) (xy 184.129693 -285.949359) (xy 184.121798 -285.997936) (xy 184.106214 -286.044617)
			(xy 184.083343 -286.088194) (xy 184.053778 -286.127538) (xy 184.018285 -286.16163) (xy 183.977782 -286.189586)
			(xy 183.93332 -286.210684) (xy 183.886049 -286.224376) (xy 183.837194 -286.230308) (xy 183.788019 -286.228327)
			(xy 183.7398 -286.218483) (xy 183.693784 -286.201031) (xy 183.651163 -286.176424) (xy 183.613042 -286.145299)
			(xy 183.580407 -286.108462) (xy 183.554104 -286.066866) (xy 183.534813 -286.02159) (xy 183.523036 -285.973806)
			(xy 183.519076 -285.924752) (xy 183.180228 -285.924752) (xy 183.179733 -285.949359) (xy 183.171838 -285.997936)
			(xy 183.156254 -286.044617) (xy 183.133383 -286.088194) (xy 183.103818 -286.127538) (xy 183.068325 -286.16163)
			(xy 183.027822 -286.189586) (xy 182.98336 -286.210684) (xy 182.936089 -286.224376) (xy 182.887234 -286.230308)
			(xy 182.838059 -286.228327) (xy 182.78984 -286.218483) (xy 182.743824 -286.201031) (xy 182.701203 -286.176424)
			(xy 182.663082 -286.145299) (xy 182.630447 -286.108462) (xy 182.604144 -286.066866) (xy 182.584853 -286.02159)
			(xy 182.573076 -285.973806) (xy 182.569116 -285.924752) (xy 182.230268 -285.924752) (xy 182.229773 -285.949359)
			(xy 182.221878 -285.997936) (xy 182.206294 -286.044617) (xy 182.183423 -286.088194) (xy 182.153858 -286.127538)
			(xy 182.118365 -286.16163) (xy 182.077862 -286.189586) (xy 182.0334 -286.210684) (xy 181.986129 -286.224376)
			(xy 181.937274 -286.230308) (xy 181.888099 -286.228327) (xy 181.83988 -286.218483) (xy 181.793864 -286.201031)
			(xy 181.751243 -286.176424) (xy 181.713122 -286.145299) (xy 181.680487 -286.108462) (xy 181.654184 -286.066866)
			(xy 181.634893 -286.02159) (xy 181.623116 -285.973806) (xy 181.619156 -285.924752) (xy 181.280308 -285.924752)
			(xy 181.279813 -285.949359) (xy 181.271918 -285.997936) (xy 181.256334 -286.044617) (xy 181.233463 -286.088194)
			(xy 181.203898 -286.127538) (xy 181.168405 -286.16163) (xy 181.127902 -286.189586) (xy 181.08344 -286.210684)
			(xy 181.036169 -286.224376) (xy 180.987314 -286.230308) (xy 180.938139 -286.228327) (xy 180.88992 -286.218483)
			(xy 180.843904 -286.201031) (xy 180.801283 -286.176424) (xy 180.763162 -286.145299) (xy 180.730527 -286.108462)
			(xy 180.704224 -286.066866) (xy 180.684933 -286.02159) (xy 180.673156 -285.973806) (xy 180.669196 -285.924752)
			(xy 180.330348 -285.924752) (xy 180.329853 -285.949359) (xy 180.321958 -285.997936) (xy 180.306374 -286.044617)
			(xy 180.283503 -286.088194) (xy 180.253938 -286.127538) (xy 180.218445 -286.16163) (xy 180.177942 -286.189586)
			(xy 180.13348 -286.210684) (xy 180.086209 -286.224376) (xy 180.037354 -286.230308) (xy 179.988179 -286.228327)
			(xy 179.93996 -286.218483) (xy 179.893944 -286.201031) (xy 179.851323 -286.176424) (xy 179.813202 -286.145299)
			(xy 179.780567 -286.108462) (xy 179.754264 -286.066866) (xy 179.734973 -286.02159) (xy 179.723196 -285.973806)
			(xy 179.719236 -285.924752) (xy 179.380388 -285.924752) (xy 179.379893 -285.949359) (xy 179.371998 -285.997936)
			(xy 179.356414 -286.044617) (xy 179.333543 -286.088194) (xy 179.303978 -286.127538) (xy 179.268485 -286.16163)
			(xy 179.227982 -286.189586) (xy 179.18352 -286.210684) (xy 179.136249 -286.224376) (xy 179.087394 -286.230308)
			(xy 179.038219 -286.228327) (xy 178.99 -286.218483) (xy 178.943984 -286.201031) (xy 178.901363 -286.176424)
			(xy 178.863242 -286.145299) (xy 178.830607 -286.108462) (xy 178.804304 -286.066866) (xy 178.785013 -286.02159)
			(xy 178.773236 -285.973806) (xy 178.769276 -285.924752) (xy 178.430174 -285.924752) (xy 178.429679 -285.949359)
			(xy 178.421784 -285.997936) (xy 178.4062 -286.044617) (xy 178.383329 -286.088194) (xy 178.353764 -286.127538)
			(xy 178.318271 -286.16163) (xy 178.277768 -286.189586) (xy 178.233306 -286.210684) (xy 178.186035 -286.224376)
			(xy 178.13718 -286.230308) (xy 178.088005 -286.228327) (xy 178.039786 -286.218483) (xy 177.99377 -286.201031)
			(xy 177.951149 -286.176424) (xy 177.913028 -286.145299) (xy 177.880393 -286.108462) (xy 177.85409 -286.066866)
			(xy 177.834799 -286.02159) (xy 177.823022 -285.973806) (xy 177.819062 -285.924752) (xy 177.480214 -285.924752)
			(xy 177.479719 -285.949359) (xy 177.471824 -285.997936) (xy 177.45624 -286.044617) (xy 177.433369 -286.088194)
			(xy 177.403804 -286.127538) (xy 177.368311 -286.16163) (xy 177.327808 -286.189586) (xy 177.283346 -286.210684)
			(xy 177.236075 -286.224376) (xy 177.18722 -286.230308) (xy 177.138045 -286.228327) (xy 177.089826 -286.218483)
			(xy 177.04381 -286.201031) (xy 177.001189 -286.176424) (xy 176.963068 -286.145299) (xy 176.930433 -286.108462)
			(xy 176.90413 -286.066866) (xy 176.884839 -286.02159) (xy 176.873062 -285.973806) (xy 176.869102 -285.924752)
			(xy 176.530254 -285.924752) (xy 176.529759 -285.949359) (xy 176.521864 -285.997936) (xy 176.50628 -286.044617)
			(xy 176.483409 -286.088194) (xy 176.453844 -286.127538) (xy 176.418351 -286.16163) (xy 176.377848 -286.189586)
			(xy 176.333386 -286.210684) (xy 176.286115 -286.224376) (xy 176.23726 -286.230308) (xy 176.188085 -286.228327)
			(xy 176.139866 -286.218483) (xy 176.09385 -286.201031) (xy 176.051229 -286.176424) (xy 176.013108 -286.145299)
			(xy 175.980473 -286.108462) (xy 175.95417 -286.066866) (xy 175.934879 -286.02159) (xy 175.923102 -285.973806)
			(xy 175.919142 -285.924752) (xy 174.630334 -285.924752) (xy 174.629839 -285.949359) (xy 174.621944 -285.997936)
			(xy 174.60636 -286.044617) (xy 174.583489 -286.088194) (xy 174.553924 -286.127538) (xy 174.518431 -286.16163)
			(xy 174.477928 -286.189586) (xy 174.433466 -286.210684) (xy 174.386195 -286.224376) (xy 174.33734 -286.230308)
			(xy 174.288165 -286.228327) (xy 174.239946 -286.218483) (xy 174.19393 -286.201031) (xy 174.151309 -286.176424)
			(xy 174.113188 -286.145299) (xy 174.080553 -286.108462) (xy 174.05425 -286.066866) (xy 174.034959 -286.02159)
			(xy 174.023182 -285.973806) (xy 174.019222 -285.924752) (xy 173.680374 -285.924752) (xy 173.679879 -285.949359)
			(xy 173.671984 -285.997936) (xy 173.6564 -286.044617) (xy 173.633529 -286.088194) (xy 173.603964 -286.127538)
			(xy 173.568471 -286.16163) (xy 173.527968 -286.189586) (xy 173.483506 -286.210684) (xy 173.436235 -286.224376)
			(xy 173.38738 -286.230308) (xy 173.338205 -286.228327) (xy 173.289986 -286.218483) (xy 173.24397 -286.201031)
			(xy 173.201349 -286.176424) (xy 173.163228 -286.145299) (xy 173.130593 -286.108462) (xy 173.10429 -286.066866)
			(xy 173.084999 -286.02159) (xy 173.073222 -285.973806) (xy 173.069262 -285.924752) (xy 172.73016 -285.924752)
			(xy 172.729665 -285.949359) (xy 172.72177 -285.997936) (xy 172.706186 -286.044617) (xy 172.683315 -286.088194)
			(xy 172.65375 -286.127538) (xy 172.618257 -286.16163) (xy 172.577754 -286.189586) (xy 172.533292 -286.210684)
			(xy 172.486021 -286.224376) (xy 172.437166 -286.230308) (xy 172.387991 -286.228327) (xy 172.339772 -286.218483)
			(xy 172.293756 -286.201031) (xy 172.251135 -286.176424) (xy 172.213014 -286.145299) (xy 172.180379 -286.108462)
			(xy 172.154076 -286.066866) (xy 172.134785 -286.02159) (xy 172.123008 -285.973806) (xy 172.119048 -285.924752)
			(xy 171.7802 -285.924752) (xy 171.779705 -285.949359) (xy 171.77181 -285.997936) (xy 171.756226 -286.044617)
			(xy 171.733355 -286.088194) (xy 171.70379 -286.127538) (xy 171.668297 -286.16163) (xy 171.627794 -286.189586)
			(xy 171.583332 -286.210684) (xy 171.536061 -286.224376) (xy 171.487206 -286.230308) (xy 171.438031 -286.228327)
			(xy 171.389812 -286.218483) (xy 171.343796 -286.201031) (xy 171.301175 -286.176424) (xy 171.263054 -286.145299)
			(xy 171.230419 -286.108462) (xy 171.204116 -286.066866) (xy 171.184825 -286.02159) (xy 171.173048 -285.973806)
			(xy 171.169088 -285.924752) (xy 170.83024 -285.924752) (xy 170.829745 -285.949359) (xy 170.82185 -285.997936)
			(xy 170.806266 -286.044617) (xy 170.783395 -286.088194) (xy 170.75383 -286.127538) (xy 170.718337 -286.16163)
			(xy 170.677834 -286.189586) (xy 170.633372 -286.210684) (xy 170.586101 -286.224376) (xy 170.537246 -286.230308)
			(xy 170.488071 -286.228327) (xy 170.439852 -286.218483) (xy 170.393836 -286.201031) (xy 170.351215 -286.176424)
			(xy 170.313094 -286.145299) (xy 170.280459 -286.108462) (xy 170.254156 -286.066866) (xy 170.234865 -286.02159)
			(xy 170.223088 -285.973806) (xy 170.219128 -285.924752) (xy 169.88028 -285.924752) (xy 169.879785 -285.949359)
			(xy 169.87189 -285.997936) (xy 169.856306 -286.044617) (xy 169.833435 -286.088194) (xy 169.80387 -286.127538)
			(xy 169.768377 -286.16163) (xy 169.727874 -286.189586) (xy 169.683412 -286.210684) (xy 169.636141 -286.224376)
			(xy 169.587286 -286.230308) (xy 169.538111 -286.228327) (xy 169.489892 -286.218483) (xy 169.443876 -286.201031)
			(xy 169.401255 -286.176424) (xy 169.363134 -286.145299) (xy 169.330499 -286.108462) (xy 169.304196 -286.066866)
			(xy 169.284905 -286.02159) (xy 169.273128 -285.973806) (xy 169.269168 -285.924752) (xy 168.93032 -285.924752)
			(xy 168.929825 -285.949359) (xy 168.92193 -285.997936) (xy 168.906346 -286.044617) (xy 168.883475 -286.088194)
			(xy 168.85391 -286.127538) (xy 168.818417 -286.16163) (xy 168.777914 -286.189586) (xy 168.733452 -286.210684)
			(xy 168.686181 -286.224376) (xy 168.637326 -286.230308) (xy 168.588151 -286.228327) (xy 168.539932 -286.218483)
			(xy 168.493916 -286.201031) (xy 168.451295 -286.176424) (xy 168.413174 -286.145299) (xy 168.380539 -286.108462)
			(xy 168.354236 -286.066866) (xy 168.334945 -286.02159) (xy 168.323168 -285.973806) (xy 168.319208 -285.924752)
			(xy 167.98036 -285.924752) (xy 167.979865 -285.949359) (xy 167.97197 -285.997936) (xy 167.956386 -286.044617)
			(xy 167.933515 -286.088194) (xy 167.90395 -286.127538) (xy 167.868457 -286.16163) (xy 167.827954 -286.189586)
			(xy 167.783492 -286.210684) (xy 167.736221 -286.224376) (xy 167.687366 -286.230308) (xy 167.638191 -286.228327)
			(xy 167.589972 -286.218483) (xy 167.543956 -286.201031) (xy 167.501335 -286.176424) (xy 167.463214 -286.145299)
			(xy 167.430579 -286.108462) (xy 167.404276 -286.066866) (xy 167.384985 -286.02159) (xy 167.373208 -285.973806)
			(xy 167.369248 -285.924752) (xy 167.0304 -285.924752) (xy 167.029905 -285.949359) (xy 167.02201 -285.997936)
			(xy 167.006426 -286.044617) (xy 166.983555 -286.088194) (xy 166.95399 -286.127538) (xy 166.918497 -286.16163)
			(xy 166.877994 -286.189586) (xy 166.833532 -286.210684) (xy 166.786261 -286.224376) (xy 166.737406 -286.230308)
			(xy 166.688231 -286.228327) (xy 166.640012 -286.218483) (xy 166.593996 -286.201031) (xy 166.551375 -286.176424)
			(xy 166.513254 -286.145299) (xy 166.480619 -286.108462) (xy 166.454316 -286.066866) (xy 166.435025 -286.02159)
			(xy 166.423248 -285.973806) (xy 166.419288 -285.924752) (xy 166.080186 -285.924752) (xy 166.079691 -285.949359)
			(xy 166.071796 -285.997936) (xy 166.056212 -286.044617) (xy 166.033341 -286.088194) (xy 166.003776 -286.127538)
			(xy 165.968283 -286.16163) (xy 165.92778 -286.189586) (xy 165.883318 -286.210684) (xy 165.836047 -286.224376)
			(xy 165.787192 -286.230308) (xy 165.738017 -286.228327) (xy 165.689798 -286.218483) (xy 165.643782 -286.201031)
			(xy 165.601161 -286.176424) (xy 165.56304 -286.145299) (xy 165.530405 -286.108462) (xy 165.504102 -286.066866)
			(xy 165.484811 -286.02159) (xy 165.473034 -285.973806) (xy 165.469074 -285.924752) (xy 165.155131 -285.924752)
			(xy 165.155132 -285.951179) (xy 165.146753 -286.00328) (xy 165.130209 -286.05339) (xy 165.105917 -286.100238)
			(xy 165.074495 -286.142633) (xy 165.036739 -286.179502) (xy 164.993609 -286.209907) (xy 164.946197 -286.233079)
			(xy 164.895708 -286.248428) (xy 164.869622 -286.252412) (xy 164.86505 -286.253174) (xy 164.852858 -286.256984)
			(xy 164.849556 -286.258) (xy 164.826188 -286.268922) (xy 164.819584 -286.276034) (xy 164.804852 -286.291528)
			(xy 164.796724 -286.302704) (xy 164.79403 -286.308235) (xy 164.791079 -286.320176) (xy 164.790882 -286.326326)
			(xy 164.790882 -286.399732) (xy 189.69407 -286.399732) (xy 189.69803 -286.350678) (xy 189.709807 -286.302894)
			(xy 189.729098 -286.257618) (xy 189.755401 -286.216022) (xy 189.788036 -286.179185) (xy 189.826157 -286.14806)
			(xy 189.868778 -286.123453) (xy 189.914794 -286.106001) (xy 189.963013 -286.096157) (xy 190.012188 -286.094176)
			(xy 190.061043 -286.100108) (xy 190.108314 -286.1138) (xy 190.152776 -286.134898) (xy 190.193279 -286.162854)
			(xy 190.228772 -286.196946) (xy 190.258337 -286.23629) (xy 190.281208 -286.279867) (xy 190.296792 -286.326548)
			(xy 190.304687 -286.375125) (xy 190.305182 -286.399732) (xy 190.644284 -286.399732) (xy 190.648244 -286.350678)
			(xy 190.660021 -286.302894) (xy 190.679312 -286.257618) (xy 190.705615 -286.216022) (xy 190.73825 -286.179185)
			(xy 190.776371 -286.14806) (xy 190.818992 -286.123453) (xy 190.865008 -286.106001) (xy 190.913227 -286.096157)
			(xy 190.962402 -286.094176) (xy 191.011257 -286.100108) (xy 191.058528 -286.1138) (xy 191.10299 -286.134898)
			(xy 191.143493 -286.162854) (xy 191.178986 -286.196946) (xy 191.208551 -286.23629) (xy 191.231422 -286.279867)
			(xy 191.247006 -286.326548) (xy 191.254901 -286.375125) (xy 191.255396 -286.399732) (xy 191.594244 -286.399732)
			(xy 191.598204 -286.350678) (xy 191.609981 -286.302894) (xy 191.629272 -286.257618) (xy 191.655575 -286.216022)
			(xy 191.68821 -286.179185) (xy 191.726331 -286.14806) (xy 191.768952 -286.123453) (xy 191.814968 -286.106001)
			(xy 191.863187 -286.096157) (xy 191.912362 -286.094176) (xy 191.961217 -286.100108) (xy 192.008488 -286.1138)
			(xy 192.05295 -286.134898) (xy 192.093453 -286.162854) (xy 192.128946 -286.196946) (xy 192.158511 -286.23629)
			(xy 192.181382 -286.279867) (xy 192.196966 -286.326548) (xy 192.204861 -286.375125) (xy 192.205356 -286.399732)
			(xy 192.204861 -286.424339) (xy 192.204641 -286.425694) (xy 192.52336 -286.425694) (xy 192.52336 -286.374278)
			(xy 192.531403 -286.323496) (xy 192.547291 -286.274597) (xy 192.570634 -286.228785) (xy 192.600855 -286.187189)
			(xy 192.637211 -286.150833) (xy 192.678807 -286.120612) (xy 192.724619 -286.097269) (xy 192.773518 -286.081381)
			(xy 192.8243 -286.073338) (xy 192.875716 -286.073338) (xy 192.926498 -286.081381) (xy 192.975397 -286.097269)
			(xy 193.021209 -286.120612) (xy 193.062805 -286.150833) (xy 193.099161 -286.187189) (xy 193.129382 -286.228785)
			(xy 193.152725 -286.274597) (xy 193.168613 -286.323496) (xy 193.176656 -286.374278) (xy 193.17716 -286.399986)
			(xy 193.176656 -286.425694) (xy 193.47332 -286.425694) (xy 193.47332 -286.374278) (xy 193.481363 -286.323496)
			(xy 193.497251 -286.274597) (xy 193.520594 -286.228785) (xy 193.550815 -286.187189) (xy 193.587171 -286.150833)
			(xy 193.628767 -286.120612) (xy 193.674579 -286.097269) (xy 193.723478 -286.081381) (xy 193.77426 -286.073338)
			(xy 193.825676 -286.073338) (xy 193.876458 -286.081381) (xy 193.925357 -286.097269) (xy 193.971169 -286.120612)
			(xy 194.012765 -286.150833) (xy 194.049121 -286.187189) (xy 194.079342 -286.228785) (xy 194.102685 -286.274597)
			(xy 194.118573 -286.323496) (xy 194.126616 -286.374278) (xy 194.127115 -286.399732) (xy 194.444124 -286.399732)
			(xy 194.448084 -286.350678) (xy 194.459861 -286.302894) (xy 194.479152 -286.257618) (xy 194.505455 -286.216022)
			(xy 194.53809 -286.179185) (xy 194.576211 -286.14806) (xy 194.618832 -286.123453) (xy 194.664848 -286.106001)
			(xy 194.713067 -286.096157) (xy 194.762242 -286.094176) (xy 194.811097 -286.100108) (xy 194.858368 -286.1138)
			(xy 194.90283 -286.134898) (xy 194.943333 -286.162854) (xy 194.978826 -286.196946) (xy 195.008391 -286.23629)
			(xy 195.031262 -286.279867) (xy 195.046846 -286.326548) (xy 195.054741 -286.375125) (xy 195.055236 -286.399732)
			(xy 195.054741 -286.424339) (xy 195.054562 -286.42544) (xy 195.37324 -286.42544) (xy 195.37324 -286.374024)
			(xy 195.381283 -286.323242) (xy 195.397171 -286.274343) (xy 195.420514 -286.228531) (xy 195.450735 -286.186935)
			(xy 195.487091 -286.150579) (xy 195.528687 -286.120358) (xy 195.574499 -286.097015) (xy 195.623398 -286.081127)
			(xy 195.67418 -286.073084) (xy 195.725596 -286.073084) (xy 195.776378 -286.081127) (xy 195.825277 -286.097015)
			(xy 195.871089 -286.120358) (xy 195.912685 -286.150579) (xy 195.949041 -286.186935) (xy 195.979262 -286.228531)
			(xy 196.002605 -286.274343) (xy 196.018493 -286.323242) (xy 196.026536 -286.374024) (xy 196.02704 -286.399732)
			(xy 196.026536 -286.42544) (xy 196.3232 -286.42544) (xy 196.3232 -286.374024) (xy 196.331243 -286.323242)
			(xy 196.347131 -286.274343) (xy 196.370474 -286.228531) (xy 196.400695 -286.186935) (xy 196.437051 -286.150579)
			(xy 196.478647 -286.120358) (xy 196.524459 -286.097015) (xy 196.573358 -286.081127) (xy 196.62414 -286.073084)
			(xy 196.675556 -286.073084) (xy 196.726338 -286.081127) (xy 196.775237 -286.097015) (xy 196.821049 -286.120358)
			(xy 196.862645 -286.150579) (xy 196.899001 -286.186935) (xy 196.929222 -286.228531) (xy 196.952565 -286.274343)
			(xy 196.968453 -286.323242) (xy 196.976496 -286.374024) (xy 196.977 -286.399732) (xy 197.294258 -286.399732)
			(xy 197.298218 -286.350678) (xy 197.309995 -286.302894) (xy 197.329286 -286.257618) (xy 197.355589 -286.216022)
			(xy 197.388224 -286.179185) (xy 197.426345 -286.14806) (xy 197.468966 -286.123453) (xy 197.514982 -286.106001)
			(xy 197.563201 -286.096157) (xy 197.612376 -286.094176) (xy 197.661231 -286.100108) (xy 197.708502 -286.1138)
			(xy 197.752964 -286.134898) (xy 197.793467 -286.162854) (xy 197.82896 -286.196946) (xy 197.858525 -286.23629)
			(xy 197.881396 -286.279867) (xy 197.89698 -286.326548) (xy 197.904875 -286.375125) (xy 197.90537 -286.399732)
			(xy 198.244218 -286.399732) (xy 198.248178 -286.350678) (xy 198.259955 -286.302894) (xy 198.279246 -286.257618)
			(xy 198.305549 -286.216022) (xy 198.338184 -286.179185) (xy 198.376305 -286.14806) (xy 198.418926 -286.123453)
			(xy 198.464942 -286.106001) (xy 198.513161 -286.096157) (xy 198.562336 -286.094176) (xy 198.611191 -286.100108)
			(xy 198.658462 -286.1138) (xy 198.702924 -286.134898) (xy 198.743427 -286.162854) (xy 198.77892 -286.196946)
			(xy 198.808485 -286.23629) (xy 198.831356 -286.279867) (xy 198.84694 -286.326548) (xy 198.854835 -286.375125)
			(xy 198.85533 -286.399732) (xy 198.854835 -286.424339) (xy 198.84694 -286.472916) (xy 198.831356 -286.519597)
			(xy 198.81708 -286.546798) (xy 207.650586 -286.546798) (xy 207.654657 -286.491176) (xy 207.666783 -286.436739)
			(xy 207.686706 -286.384648) (xy 207.714002 -286.336013) (xy 207.748088 -286.29187) (xy 207.788237 -286.253161)
			(xy 207.833595 -286.22071) (xy 207.883195 -286.195209) (xy 207.935979 -286.177202) (xy 207.990822 -286.167072)
			(xy 208.046556 -286.165035) (xy 208.101993 -286.171135) (xy 208.15595 -286.185241) (xy 208.207279 -286.207053)
			(xy 208.254885 -286.236107) (xy 208.297753 -286.271782) (xy 208.33497 -286.313319) (xy 208.365743 -286.359832)
			(xy 208.389415 -286.410329) (xy 208.405483 -286.463736) (xy 208.413603 -286.518912) (xy 208.414112 -286.546798)
			(xy 208.413603 -286.574684) (xy 208.405483 -286.62986) (xy 208.389415 -286.683267) (xy 208.365743 -286.733764)
			(xy 208.33497 -286.780277) (xy 208.297753 -286.821814) (xy 208.254885 -286.857489) (xy 208.207279 -286.886543)
			(xy 208.15595 -286.908355) (xy 208.101993 -286.922461) (xy 208.046556 -286.928561) (xy 207.990822 -286.926524)
			(xy 207.935979 -286.916394) (xy 207.883195 -286.898387) (xy 207.833595 -286.872886) (xy 207.788237 -286.840435)
			(xy 207.748088 -286.801726) (xy 207.714002 -286.757583) (xy 207.686706 -286.708948) (xy 207.666783 -286.656857)
			(xy 207.654657 -286.60242) (xy 207.650586 -286.546798) (xy 198.81708 -286.546798) (xy 198.808485 -286.563174)
			(xy 198.77892 -286.602518) (xy 198.743427 -286.63661) (xy 198.702924 -286.664566) (xy 198.658462 -286.685664)
			(xy 198.611191 -286.699356) (xy 198.562336 -286.705288) (xy 198.513161 -286.703307) (xy 198.464942 -286.693463)
			(xy 198.418926 -286.676011) (xy 198.376305 -286.651404) (xy 198.338184 -286.620279) (xy 198.305549 -286.583442)
			(xy 198.279246 -286.541846) (xy 198.259955 -286.49657) (xy 198.248178 -286.448786) (xy 198.244218 -286.399732)
			(xy 197.90537 -286.399732) (xy 197.904875 -286.424339) (xy 197.89698 -286.472916) (xy 197.881396 -286.519597)
			(xy 197.858525 -286.563174) (xy 197.82896 -286.602518) (xy 197.793467 -286.63661) (xy 197.752964 -286.664566)
			(xy 197.708502 -286.685664) (xy 197.661231 -286.699356) (xy 197.612376 -286.705288) (xy 197.563201 -286.703307)
			(xy 197.514982 -286.693463) (xy 197.468966 -286.676011) (xy 197.426345 -286.651404) (xy 197.388224 -286.620279)
			(xy 197.355589 -286.583442) (xy 197.329286 -286.541846) (xy 197.309995 -286.49657) (xy 197.298218 -286.448786)
			(xy 197.294258 -286.399732) (xy 196.977 -286.399732) (xy 196.976496 -286.42544) (xy 196.968453 -286.476222)
			(xy 196.952565 -286.525121) (xy 196.929222 -286.570933) (xy 196.899001 -286.612529) (xy 196.862645 -286.648885)
			(xy 196.821049 -286.679106) (xy 196.775237 -286.702449) (xy 196.726338 -286.718337) (xy 196.675556 -286.72638)
			(xy 196.62414 -286.72638) (xy 196.573358 -286.718337) (xy 196.524459 -286.702449) (xy 196.478647 -286.679106)
			(xy 196.437051 -286.648885) (xy 196.400695 -286.612529) (xy 196.370474 -286.570933) (xy 196.347131 -286.525121)
			(xy 196.331243 -286.476222) (xy 196.3232 -286.42544) (xy 196.026536 -286.42544) (xy 196.018493 -286.476222)
			(xy 196.002605 -286.525121) (xy 195.979262 -286.570933) (xy 195.949041 -286.612529) (xy 195.912685 -286.648885)
			(xy 195.871089 -286.679106) (xy 195.825277 -286.702449) (xy 195.776378 -286.718337) (xy 195.725596 -286.72638)
			(xy 195.67418 -286.72638) (xy 195.623398 -286.718337) (xy 195.574499 -286.702449) (xy 195.528687 -286.679106)
			(xy 195.487091 -286.648885) (xy 195.450735 -286.612529) (xy 195.420514 -286.570933) (xy 195.397171 -286.525121)
			(xy 195.381283 -286.476222) (xy 195.37324 -286.42544) (xy 195.054562 -286.42544) (xy 195.046846 -286.472916)
			(xy 195.031262 -286.519597) (xy 195.008391 -286.563174) (xy 194.978826 -286.602518) (xy 194.943333 -286.63661)
			(xy 194.90283 -286.664566) (xy 194.858368 -286.685664) (xy 194.811097 -286.699356) (xy 194.762242 -286.705288)
			(xy 194.713067 -286.703307) (xy 194.664848 -286.693463) (xy 194.618832 -286.676011) (xy 194.576211 -286.651404)
			(xy 194.53809 -286.620279) (xy 194.505455 -286.583442) (xy 194.479152 -286.541846) (xy 194.459861 -286.49657)
			(xy 194.448084 -286.448786) (xy 194.444124 -286.399732) (xy 194.127115 -286.399732) (xy 194.12712 -286.399986)
			(xy 194.126616 -286.425694) (xy 194.118573 -286.476476) (xy 194.102685 -286.525375) (xy 194.079342 -286.571187)
			(xy 194.049121 -286.612783) (xy 194.012765 -286.649139) (xy 193.971169 -286.67936) (xy 193.925357 -286.702703)
			(xy 193.876458 -286.718591) (xy 193.825676 -286.726634) (xy 193.77426 -286.726634) (xy 193.723478 -286.718591)
			(xy 193.674579 -286.702703) (xy 193.628767 -286.67936) (xy 193.587171 -286.649139) (xy 193.550815 -286.612783)
			(xy 193.520594 -286.571187) (xy 193.497251 -286.525375) (xy 193.481363 -286.476476) (xy 193.47332 -286.425694)
			(xy 193.176656 -286.425694) (xy 193.168613 -286.476476) (xy 193.152725 -286.525375) (xy 193.129382 -286.571187)
			(xy 193.099161 -286.612783) (xy 193.062805 -286.649139) (xy 193.021209 -286.67936) (xy 192.975397 -286.702703)
			(xy 192.926498 -286.718591) (xy 192.875716 -286.726634) (xy 192.8243 -286.726634) (xy 192.773518 -286.718591)
			(xy 192.724619 -286.702703) (xy 192.678807 -286.67936) (xy 192.637211 -286.649139) (xy 192.600855 -286.612783)
			(xy 192.570634 -286.571187) (xy 192.547291 -286.525375) (xy 192.531403 -286.476476) (xy 192.52336 -286.425694)
			(xy 192.204641 -286.425694) (xy 192.196966 -286.472916) (xy 192.181382 -286.519597) (xy 192.158511 -286.563174)
			(xy 192.128946 -286.602518) (xy 192.093453 -286.63661) (xy 192.05295 -286.664566) (xy 192.008488 -286.685664)
			(xy 191.961217 -286.699356) (xy 191.912362 -286.705288) (xy 191.863187 -286.703307) (xy 191.814968 -286.693463)
			(xy 191.768952 -286.676011) (xy 191.726331 -286.651404) (xy 191.68821 -286.620279) (xy 191.655575 -286.583442)
			(xy 191.629272 -286.541846) (xy 191.609981 -286.49657) (xy 191.598204 -286.448786) (xy 191.594244 -286.399732)
			(xy 191.255396 -286.399732) (xy 191.254901 -286.424339) (xy 191.247006 -286.472916) (xy 191.231422 -286.519597)
			(xy 191.208551 -286.563174) (xy 191.178986 -286.602518) (xy 191.143493 -286.63661) (xy 191.10299 -286.664566)
			(xy 191.058528 -286.685664) (xy 191.011257 -286.699356) (xy 190.962402 -286.705288) (xy 190.913227 -286.703307)
			(xy 190.865008 -286.693463) (xy 190.818992 -286.676011) (xy 190.776371 -286.651404) (xy 190.73825 -286.620279)
			(xy 190.705615 -286.583442) (xy 190.679312 -286.541846) (xy 190.660021 -286.49657) (xy 190.648244 -286.448786)
			(xy 190.644284 -286.399732) (xy 190.305182 -286.399732) (xy 190.304687 -286.424339) (xy 190.296792 -286.472916)
			(xy 190.281208 -286.519597) (xy 190.258337 -286.563174) (xy 190.228772 -286.602518) (xy 190.193279 -286.63661)
			(xy 190.152776 -286.664566) (xy 190.108314 -286.685664) (xy 190.061043 -286.699356) (xy 190.012188 -286.705288)
			(xy 189.963013 -286.703307) (xy 189.914794 -286.693463) (xy 189.868778 -286.676011) (xy 189.826157 -286.651404)
			(xy 189.788036 -286.620279) (xy 189.755401 -286.583442) (xy 189.729098 -286.541846) (xy 189.709807 -286.49657)
			(xy 189.69803 -286.448786) (xy 189.69407 -286.399732) (xy 164.790882 -286.399732) (xy 164.790882 -286.473392)
			(xy 164.791055 -286.479544) (xy 164.794016 -286.491487) (xy 164.796724 -286.497014) (xy 164.804852 -286.50819)
			(xy 164.819584 -286.523684) (xy 164.826188 -286.530796) (xy 164.849302 -286.541718) (xy 164.852858 -286.542734)
			(xy 164.86505 -286.546544) (xy 164.869622 -286.547306) (xy 164.895694 -286.551383) (xy 164.946182 -286.56673)
			(xy 164.993592 -286.589899) (xy 165.036722 -286.620302) (xy 165.074477 -286.657168) (xy 165.105899 -286.69956)
			(xy 165.130191 -286.746405) (xy 165.146737 -286.796512) (xy 165.155117 -286.848611) (xy 165.155117 -286.874966)
			(xy 165.469074 -286.874966) (xy 165.473034 -286.825912) (xy 165.484811 -286.778128) (xy 165.504102 -286.732852)
			(xy 165.530405 -286.691256) (xy 165.56304 -286.654419) (xy 165.601161 -286.623294) (xy 165.643782 -286.598687)
			(xy 165.689798 -286.581235) (xy 165.738017 -286.571391) (xy 165.787192 -286.56941) (xy 165.836047 -286.575342)
			(xy 165.883318 -286.589034) (xy 165.92778 -286.610132) (xy 165.968283 -286.638088) (xy 166.003776 -286.67218)
			(xy 166.033341 -286.711524) (xy 166.056212 -286.755101) (xy 166.071796 -286.801782) (xy 166.079691 -286.850359)
			(xy 166.080186 -286.874966) (xy 166.419288 -286.874966) (xy 166.423248 -286.825912) (xy 166.435025 -286.778128)
			(xy 166.454316 -286.732852) (xy 166.480619 -286.691256) (xy 166.513254 -286.654419) (xy 166.551375 -286.623294)
			(xy 166.593996 -286.598687) (xy 166.640012 -286.581235) (xy 166.688231 -286.571391) (xy 166.737406 -286.56941)
			(xy 166.786261 -286.575342) (xy 166.833532 -286.589034) (xy 166.877994 -286.610132) (xy 166.918497 -286.638088)
			(xy 166.95399 -286.67218) (xy 166.983555 -286.711524) (xy 167.006426 -286.755101) (xy 167.02201 -286.801782)
			(xy 167.029905 -286.850359) (xy 167.0304 -286.874966) (xy 167.369248 -286.874966) (xy 167.373208 -286.825912)
			(xy 167.384985 -286.778128) (xy 167.404276 -286.732852) (xy 167.430579 -286.691256) (xy 167.463214 -286.654419)
			(xy 167.501335 -286.623294) (xy 167.543956 -286.598687) (xy 167.589972 -286.581235) (xy 167.638191 -286.571391)
			(xy 167.687366 -286.56941) (xy 167.736221 -286.575342) (xy 167.783492 -286.589034) (xy 167.827954 -286.610132)
			(xy 167.868457 -286.638088) (xy 167.90395 -286.67218) (xy 167.933515 -286.711524) (xy 167.956386 -286.755101)
			(xy 167.97197 -286.801782) (xy 167.979865 -286.850359) (xy 167.98036 -286.874966) (xy 168.319208 -286.874966)
			(xy 168.323168 -286.825912) (xy 168.334945 -286.778128) (xy 168.354236 -286.732852) (xy 168.380539 -286.691256)
			(xy 168.413174 -286.654419) (xy 168.451295 -286.623294) (xy 168.493916 -286.598687) (xy 168.539932 -286.581235)
			(xy 168.588151 -286.571391) (xy 168.637326 -286.56941) (xy 168.686181 -286.575342) (xy 168.733452 -286.589034)
			(xy 168.777914 -286.610132) (xy 168.818417 -286.638088) (xy 168.85391 -286.67218) (xy 168.883475 -286.711524)
			(xy 168.906346 -286.755101) (xy 168.92193 -286.801782) (xy 168.929825 -286.850359) (xy 168.93032 -286.874966)
			(xy 169.269168 -286.874966) (xy 169.273128 -286.825912) (xy 169.284905 -286.778128) (xy 169.304196 -286.732852)
			(xy 169.330499 -286.691256) (xy 169.363134 -286.654419) (xy 169.401255 -286.623294) (xy 169.443876 -286.598687)
			(xy 169.489892 -286.581235) (xy 169.538111 -286.571391) (xy 169.587286 -286.56941) (xy 169.636141 -286.575342)
			(xy 169.683412 -286.589034) (xy 169.727874 -286.610132) (xy 169.768377 -286.638088) (xy 169.80387 -286.67218)
			(xy 169.833435 -286.711524) (xy 169.856306 -286.755101) (xy 169.87189 -286.801782) (xy 169.879785 -286.850359)
			(xy 169.88028 -286.874966) (xy 170.219128 -286.874966) (xy 170.223088 -286.825912) (xy 170.234865 -286.778128)
			(xy 170.254156 -286.732852) (xy 170.280459 -286.691256) (xy 170.313094 -286.654419) (xy 170.351215 -286.623294)
			(xy 170.393836 -286.598687) (xy 170.439852 -286.581235) (xy 170.488071 -286.571391) (xy 170.537246 -286.56941)
			(xy 170.586101 -286.575342) (xy 170.633372 -286.589034) (xy 170.677834 -286.610132) (xy 170.718337 -286.638088)
			(xy 170.75383 -286.67218) (xy 170.783395 -286.711524) (xy 170.806266 -286.755101) (xy 170.82185 -286.801782)
			(xy 170.829745 -286.850359) (xy 170.83024 -286.874966) (xy 171.169088 -286.874966) (xy 171.173048 -286.825912)
			(xy 171.184825 -286.778128) (xy 171.204116 -286.732852) (xy 171.230419 -286.691256) (xy 171.263054 -286.654419)
			(xy 171.301175 -286.623294) (xy 171.343796 -286.598687) (xy 171.389812 -286.581235) (xy 171.438031 -286.571391)
			(xy 171.487206 -286.56941) (xy 171.536061 -286.575342) (xy 171.583332 -286.589034) (xy 171.627794 -286.610132)
			(xy 171.668297 -286.638088) (xy 171.70379 -286.67218) (xy 171.733355 -286.711524) (xy 171.756226 -286.755101)
			(xy 171.77181 -286.801782) (xy 171.779705 -286.850359) (xy 171.7802 -286.874966) (xy 172.119048 -286.874966)
			(xy 172.123008 -286.825912) (xy 172.134785 -286.778128) (xy 172.154076 -286.732852) (xy 172.180379 -286.691256)
			(xy 172.213014 -286.654419) (xy 172.251135 -286.623294) (xy 172.293756 -286.598687) (xy 172.339772 -286.581235)
			(xy 172.387991 -286.571391) (xy 172.437166 -286.56941) (xy 172.486021 -286.575342) (xy 172.533292 -286.589034)
			(xy 172.577754 -286.610132) (xy 172.618257 -286.638088) (xy 172.65375 -286.67218) (xy 172.683315 -286.711524)
			(xy 172.706186 -286.755101) (xy 172.72177 -286.801782) (xy 172.729665 -286.850359) (xy 172.73016 -286.874966)
			(xy 173.069262 -286.874966) (xy 173.073222 -286.825912) (xy 173.084999 -286.778128) (xy 173.10429 -286.732852)
			(xy 173.130593 -286.691256) (xy 173.163228 -286.654419) (xy 173.201349 -286.623294) (xy 173.24397 -286.598687)
			(xy 173.289986 -286.581235) (xy 173.338205 -286.571391) (xy 173.38738 -286.56941) (xy 173.436235 -286.575342)
			(xy 173.483506 -286.589034) (xy 173.527968 -286.610132) (xy 173.568471 -286.638088) (xy 173.603964 -286.67218)
			(xy 173.633529 -286.711524) (xy 173.6564 -286.755101) (xy 173.671984 -286.801782) (xy 173.679879 -286.850359)
			(xy 173.680374 -286.874966) (xy 174.019222 -286.874966) (xy 174.023182 -286.825912) (xy 174.034959 -286.778128)
			(xy 174.05425 -286.732852) (xy 174.080553 -286.691256) (xy 174.113188 -286.654419) (xy 174.151309 -286.623294)
			(xy 174.19393 -286.598687) (xy 174.239946 -286.581235) (xy 174.288165 -286.571391) (xy 174.33734 -286.56941)
			(xy 174.386195 -286.575342) (xy 174.433466 -286.589034) (xy 174.477928 -286.610132) (xy 174.518431 -286.638088)
			(xy 174.553924 -286.67218) (xy 174.583489 -286.711524) (xy 174.60636 -286.755101) (xy 174.621944 -286.801782)
			(xy 174.629839 -286.850359) (xy 174.630334 -286.874966) (xy 175.919142 -286.874966) (xy 175.923102 -286.825912)
			(xy 175.934879 -286.778128) (xy 175.95417 -286.732852) (xy 175.980473 -286.691256) (xy 176.013108 -286.654419)
			(xy 176.051229 -286.623294) (xy 176.09385 -286.598687) (xy 176.139866 -286.581235) (xy 176.188085 -286.571391)
			(xy 176.23726 -286.56941) (xy 176.286115 -286.575342) (xy 176.333386 -286.589034) (xy 176.377848 -286.610132)
			(xy 176.418351 -286.638088) (xy 176.453844 -286.67218) (xy 176.483409 -286.711524) (xy 176.50628 -286.755101)
			(xy 176.521864 -286.801782) (xy 176.529759 -286.850359) (xy 176.530254 -286.874966) (xy 176.869102 -286.874966)
			(xy 176.873062 -286.825912) (xy 176.884839 -286.778128) (xy 176.90413 -286.732852) (xy 176.930433 -286.691256)
			(xy 176.963068 -286.654419) (xy 177.001189 -286.623294) (xy 177.04381 -286.598687) (xy 177.089826 -286.581235)
			(xy 177.138045 -286.571391) (xy 177.18722 -286.56941) (xy 177.236075 -286.575342) (xy 177.283346 -286.589034)
			(xy 177.327808 -286.610132) (xy 177.368311 -286.638088) (xy 177.403804 -286.67218) (xy 177.433369 -286.711524)
			(xy 177.45624 -286.755101) (xy 177.471824 -286.801782) (xy 177.479719 -286.850359) (xy 177.480214 -286.874966)
			(xy 177.819062 -286.874966) (xy 177.823022 -286.825912) (xy 177.834799 -286.778128) (xy 177.85409 -286.732852)
			(xy 177.880393 -286.691256) (xy 177.913028 -286.654419) (xy 177.951149 -286.623294) (xy 177.99377 -286.598687)
			(xy 178.039786 -286.581235) (xy 178.088005 -286.571391) (xy 178.13718 -286.56941) (xy 178.186035 -286.575342)
			(xy 178.233306 -286.589034) (xy 178.277768 -286.610132) (xy 178.318271 -286.638088) (xy 178.353764 -286.67218)
			(xy 178.383329 -286.711524) (xy 178.4062 -286.755101) (xy 178.421784 -286.801782) (xy 178.429679 -286.850359)
			(xy 178.430174 -286.874966) (xy 178.769276 -286.874966) (xy 178.773236 -286.825912) (xy 178.785013 -286.778128)
			(xy 178.804304 -286.732852) (xy 178.830607 -286.691256) (xy 178.863242 -286.654419) (xy 178.901363 -286.623294)
			(xy 178.943984 -286.598687) (xy 178.99 -286.581235) (xy 179.038219 -286.571391) (xy 179.087394 -286.56941)
			(xy 179.136249 -286.575342) (xy 179.18352 -286.589034) (xy 179.227982 -286.610132) (xy 179.268485 -286.638088)
			(xy 179.303978 -286.67218) (xy 179.333543 -286.711524) (xy 179.356414 -286.755101) (xy 179.371998 -286.801782)
			(xy 179.379893 -286.850359) (xy 179.380388 -286.874966) (xy 179.719236 -286.874966) (xy 179.723196 -286.825912)
			(xy 179.734973 -286.778128) (xy 179.754264 -286.732852) (xy 179.780567 -286.691256) (xy 179.813202 -286.654419)
			(xy 179.851323 -286.623294) (xy 179.893944 -286.598687) (xy 179.93996 -286.581235) (xy 179.988179 -286.571391)
			(xy 180.037354 -286.56941) (xy 180.086209 -286.575342) (xy 180.13348 -286.589034) (xy 180.177942 -286.610132)
			(xy 180.218445 -286.638088) (xy 180.253938 -286.67218) (xy 180.283503 -286.711524) (xy 180.306374 -286.755101)
			(xy 180.321958 -286.801782) (xy 180.329853 -286.850359) (xy 180.330348 -286.874966) (xy 180.669196 -286.874966)
			(xy 180.673156 -286.825912) (xy 180.684933 -286.778128) (xy 180.704224 -286.732852) (xy 180.730527 -286.691256)
			(xy 180.763162 -286.654419) (xy 180.801283 -286.623294) (xy 180.843904 -286.598687) (xy 180.88992 -286.581235)
			(xy 180.938139 -286.571391) (xy 180.987314 -286.56941) (xy 181.036169 -286.575342) (xy 181.08344 -286.589034)
			(xy 181.127902 -286.610132) (xy 181.168405 -286.638088) (xy 181.203898 -286.67218) (xy 181.233463 -286.711524)
			(xy 181.256334 -286.755101) (xy 181.271918 -286.801782) (xy 181.279813 -286.850359) (xy 181.280308 -286.874966)
			(xy 181.619156 -286.874966) (xy 181.623116 -286.825912) (xy 181.634893 -286.778128) (xy 181.654184 -286.732852)
			(xy 181.680487 -286.691256) (xy 181.713122 -286.654419) (xy 181.751243 -286.623294) (xy 181.793864 -286.598687)
			(xy 181.83988 -286.581235) (xy 181.888099 -286.571391) (xy 181.937274 -286.56941) (xy 181.986129 -286.575342)
			(xy 182.0334 -286.589034) (xy 182.077862 -286.610132) (xy 182.118365 -286.638088) (xy 182.153858 -286.67218)
			(xy 182.183423 -286.711524) (xy 182.206294 -286.755101) (xy 182.221878 -286.801782) (xy 182.229773 -286.850359)
			(xy 182.230268 -286.874966) (xy 182.569116 -286.874966) (xy 182.573076 -286.825912) (xy 182.584853 -286.778128)
			(xy 182.604144 -286.732852) (xy 182.630447 -286.691256) (xy 182.663082 -286.654419) (xy 182.701203 -286.623294)
			(xy 182.743824 -286.598687) (xy 182.78984 -286.581235) (xy 182.838059 -286.571391) (xy 182.887234 -286.56941)
			(xy 182.936089 -286.575342) (xy 182.98336 -286.589034) (xy 183.027822 -286.610132) (xy 183.068325 -286.638088)
			(xy 183.103818 -286.67218) (xy 183.133383 -286.711524) (xy 183.156254 -286.755101) (xy 183.171838 -286.801782)
			(xy 183.179733 -286.850359) (xy 183.180228 -286.874966) (xy 183.519076 -286.874966) (xy 183.523036 -286.825912)
			(xy 183.534813 -286.778128) (xy 183.554104 -286.732852) (xy 183.580407 -286.691256) (xy 183.613042 -286.654419)
			(xy 183.651163 -286.623294) (xy 183.693784 -286.598687) (xy 183.7398 -286.581235) (xy 183.788019 -286.571391)
			(xy 183.837194 -286.56941) (xy 183.886049 -286.575342) (xy 183.93332 -286.589034) (xy 183.977782 -286.610132)
			(xy 184.018285 -286.638088) (xy 184.053778 -286.67218) (xy 184.083343 -286.711524) (xy 184.106214 -286.755101)
			(xy 184.121798 -286.801782) (xy 184.129693 -286.850359) (xy 184.130188 -286.874966) (xy 184.469036 -286.874966)
			(xy 184.472996 -286.825912) (xy 184.484773 -286.778128) (xy 184.504064 -286.732852) (xy 184.530367 -286.691256)
			(xy 184.563002 -286.654419) (xy 184.601123 -286.623294) (xy 184.643744 -286.598687) (xy 184.68976 -286.581235)
			(xy 184.737979 -286.571391) (xy 184.787154 -286.56941) (xy 184.836009 -286.575342) (xy 184.88328 -286.589034)
			(xy 184.927742 -286.610132) (xy 184.968245 -286.638088) (xy 185.003738 -286.67218) (xy 185.033303 -286.711524)
			(xy 185.056174 -286.755101) (xy 185.071758 -286.801782) (xy 185.079653 -286.850359) (xy 185.080148 -286.874966)
			(xy 185.41925 -286.874966) (xy 185.42321 -286.825912) (xy 185.434987 -286.778128) (xy 185.454278 -286.732852)
			(xy 185.480581 -286.691256) (xy 185.513216 -286.654419) (xy 185.551337 -286.623294) (xy 185.593958 -286.598687)
			(xy 185.639974 -286.581235) (xy 185.688193 -286.571391) (xy 185.737368 -286.56941) (xy 185.786223 -286.575342)
			(xy 185.833494 -286.589034) (xy 185.877956 -286.610132) (xy 185.918459 -286.638088) (xy 185.953952 -286.67218)
			(xy 185.983517 -286.711524) (xy 186.006388 -286.755101) (xy 186.021972 -286.801782) (xy 186.029867 -286.850359)
			(xy 186.030362 -286.874966) (xy 186.36921 -286.874966) (xy 186.37317 -286.825912) (xy 186.384947 -286.778128)
			(xy 186.404238 -286.732852) (xy 186.430541 -286.691256) (xy 186.463176 -286.654419) (xy 186.501297 -286.623294)
			(xy 186.543918 -286.598687) (xy 186.589934 -286.581235) (xy 186.638153 -286.571391) (xy 186.687328 -286.56941)
			(xy 186.736183 -286.575342) (xy 186.783454 -286.589034) (xy 186.827916 -286.610132) (xy 186.868419 -286.638088)
			(xy 186.903912 -286.67218) (xy 186.933477 -286.711524) (xy 186.956348 -286.755101) (xy 186.971932 -286.801782)
			(xy 186.979827 -286.850359) (xy 186.980322 -286.874966) (xy 186.979827 -286.899573) (xy 186.971932 -286.94815)
			(xy 186.956348 -286.994831) (xy 186.933477 -287.038408) (xy 186.903912 -287.077752) (xy 186.868419 -287.111844)
			(xy 186.827916 -287.1398) (xy 186.783454 -287.160898) (xy 186.736183 -287.17459) (xy 186.687328 -287.180522)
			(xy 186.638153 -287.178541) (xy 186.589934 -287.168697) (xy 186.543918 -287.151245) (xy 186.501297 -287.126638)
			(xy 186.463176 -287.095513) (xy 186.430541 -287.058676) (xy 186.404238 -287.01708) (xy 186.384947 -286.971804)
			(xy 186.37317 -286.92402) (xy 186.36921 -286.874966) (xy 186.030362 -286.874966) (xy 186.029867 -286.899573)
			(xy 186.021972 -286.94815) (xy 186.006388 -286.994831) (xy 185.983517 -287.038408) (xy 185.953952 -287.077752)
			(xy 185.918459 -287.111844) (xy 185.877956 -287.1398) (xy 185.833494 -287.160898) (xy 185.786223 -287.17459)
			(xy 185.737368 -287.180522) (xy 185.688193 -287.178541) (xy 185.639974 -287.168697) (xy 185.593958 -287.151245)
			(xy 185.551337 -287.126638) (xy 185.513216 -287.095513) (xy 185.480581 -287.058676) (xy 185.454278 -287.01708)
			(xy 185.434987 -286.971804) (xy 185.42321 -286.92402) (xy 185.41925 -286.874966) (xy 185.080148 -286.874966)
			(xy 185.079653 -286.899573) (xy 185.071758 -286.94815) (xy 185.056174 -286.994831) (xy 185.033303 -287.038408)
			(xy 185.003738 -287.077752) (xy 184.968245 -287.111844) (xy 184.927742 -287.1398) (xy 184.88328 -287.160898)
			(xy 184.836009 -287.17459) (xy 184.787154 -287.180522) (xy 184.737979 -287.178541) (xy 184.68976 -287.168697)
			(xy 184.643744 -287.151245) (xy 184.601123 -287.126638) (xy 184.563002 -287.095513) (xy 184.530367 -287.058676)
			(xy 184.504064 -287.01708) (xy 184.484773 -286.971804) (xy 184.472996 -286.92402) (xy 184.469036 -286.874966)
			(xy 184.130188 -286.874966) (xy 184.129693 -286.899573) (xy 184.121798 -286.94815) (xy 184.106214 -286.994831)
			(xy 184.083343 -287.038408) (xy 184.053778 -287.077752) (xy 184.018285 -287.111844) (xy 183.977782 -287.1398)
			(xy 183.93332 -287.160898) (xy 183.886049 -287.17459) (xy 183.837194 -287.180522) (xy 183.788019 -287.178541)
			(xy 183.7398 -287.168697) (xy 183.693784 -287.151245) (xy 183.651163 -287.126638) (xy 183.613042 -287.095513)
			(xy 183.580407 -287.058676) (xy 183.554104 -287.01708) (xy 183.534813 -286.971804) (xy 183.523036 -286.92402)
			(xy 183.519076 -286.874966) (xy 183.180228 -286.874966) (xy 183.179733 -286.899573) (xy 183.171838 -286.94815)
			(xy 183.156254 -286.994831) (xy 183.133383 -287.038408) (xy 183.103818 -287.077752) (xy 183.068325 -287.111844)
			(xy 183.027822 -287.1398) (xy 182.98336 -287.160898) (xy 182.936089 -287.17459) (xy 182.887234 -287.180522)
			(xy 182.838059 -287.178541) (xy 182.78984 -287.168697) (xy 182.743824 -287.151245) (xy 182.701203 -287.126638)
			(xy 182.663082 -287.095513) (xy 182.630447 -287.058676) (xy 182.604144 -287.01708) (xy 182.584853 -286.971804)
			(xy 182.573076 -286.92402) (xy 182.569116 -286.874966) (xy 182.230268 -286.874966) (xy 182.229773 -286.899573)
			(xy 182.221878 -286.94815) (xy 182.206294 -286.994831) (xy 182.183423 -287.038408) (xy 182.153858 -287.077752)
			(xy 182.118365 -287.111844) (xy 182.077862 -287.1398) (xy 182.0334 -287.160898) (xy 181.986129 -287.17459)
			(xy 181.937274 -287.180522) (xy 181.888099 -287.178541) (xy 181.83988 -287.168697) (xy 181.793864 -287.151245)
			(xy 181.751243 -287.126638) (xy 181.713122 -287.095513) (xy 181.680487 -287.058676) (xy 181.654184 -287.01708)
			(xy 181.634893 -286.971804) (xy 181.623116 -286.92402) (xy 181.619156 -286.874966) (xy 181.280308 -286.874966)
			(xy 181.279813 -286.899573) (xy 181.271918 -286.94815) (xy 181.256334 -286.994831) (xy 181.233463 -287.038408)
			(xy 181.203898 -287.077752) (xy 181.168405 -287.111844) (xy 181.127902 -287.1398) (xy 181.08344 -287.160898)
			(xy 181.036169 -287.17459) (xy 180.987314 -287.180522) (xy 180.938139 -287.178541) (xy 180.88992 -287.168697)
			(xy 180.843904 -287.151245) (xy 180.801283 -287.126638) (xy 180.763162 -287.095513) (xy 180.730527 -287.058676)
			(xy 180.704224 -287.01708) (xy 180.684933 -286.971804) (xy 180.673156 -286.92402) (xy 180.669196 -286.874966)
			(xy 180.330348 -286.874966) (xy 180.329853 -286.899573) (xy 180.321958 -286.94815) (xy 180.306374 -286.994831)
			(xy 180.283503 -287.038408) (xy 180.253938 -287.077752) (xy 180.218445 -287.111844) (xy 180.177942 -287.1398)
			(xy 180.13348 -287.160898) (xy 180.086209 -287.17459) (xy 180.037354 -287.180522) (xy 179.988179 -287.178541)
			(xy 179.93996 -287.168697) (xy 179.893944 -287.151245) (xy 179.851323 -287.126638) (xy 179.813202 -287.095513)
			(xy 179.780567 -287.058676) (xy 179.754264 -287.01708) (xy 179.734973 -286.971804) (xy 179.723196 -286.92402)
			(xy 179.719236 -286.874966) (xy 179.380388 -286.874966) (xy 179.379893 -286.899573) (xy 179.371998 -286.94815)
			(xy 179.356414 -286.994831) (xy 179.333543 -287.038408) (xy 179.303978 -287.077752) (xy 179.268485 -287.111844)
			(xy 179.227982 -287.1398) (xy 179.18352 -287.160898) (xy 179.136249 -287.17459) (xy 179.087394 -287.180522)
			(xy 179.038219 -287.178541) (xy 178.99 -287.168697) (xy 178.943984 -287.151245) (xy 178.901363 -287.126638)
			(xy 178.863242 -287.095513) (xy 178.830607 -287.058676) (xy 178.804304 -287.01708) (xy 178.785013 -286.971804)
			(xy 178.773236 -286.92402) (xy 178.769276 -286.874966) (xy 178.430174 -286.874966) (xy 178.429679 -286.899573)
			(xy 178.421784 -286.94815) (xy 178.4062 -286.994831) (xy 178.383329 -287.038408) (xy 178.353764 -287.077752)
			(xy 178.318271 -287.111844) (xy 178.277768 -287.1398) (xy 178.233306 -287.160898) (xy 178.186035 -287.17459)
			(xy 178.13718 -287.180522) (xy 178.088005 -287.178541) (xy 178.039786 -287.168697) (xy 177.99377 -287.151245)
			(xy 177.951149 -287.126638) (xy 177.913028 -287.095513) (xy 177.880393 -287.058676) (xy 177.85409 -287.01708)
			(xy 177.834799 -286.971804) (xy 177.823022 -286.92402) (xy 177.819062 -286.874966) (xy 177.480214 -286.874966)
			(xy 177.479719 -286.899573) (xy 177.471824 -286.94815) (xy 177.45624 -286.994831) (xy 177.433369 -287.038408)
			(xy 177.403804 -287.077752) (xy 177.368311 -287.111844) (xy 177.327808 -287.1398) (xy 177.283346 -287.160898)
			(xy 177.236075 -287.17459) (xy 177.18722 -287.180522) (xy 177.138045 -287.178541) (xy 177.089826 -287.168697)
			(xy 177.04381 -287.151245) (xy 177.001189 -287.126638) (xy 176.963068 -287.095513) (xy 176.930433 -287.058676)
			(xy 176.90413 -287.01708) (xy 176.884839 -286.971804) (xy 176.873062 -286.92402) (xy 176.869102 -286.874966)
			(xy 176.530254 -286.874966) (xy 176.529759 -286.899573) (xy 176.521864 -286.94815) (xy 176.50628 -286.994831)
			(xy 176.483409 -287.038408) (xy 176.453844 -287.077752) (xy 176.418351 -287.111844) (xy 176.377848 -287.1398)
			(xy 176.333386 -287.160898) (xy 176.286115 -287.17459) (xy 176.23726 -287.180522) (xy 176.188085 -287.178541)
			(xy 176.139866 -287.168697) (xy 176.09385 -287.151245) (xy 176.051229 -287.126638) (xy 176.013108 -287.095513)
			(xy 175.980473 -287.058676) (xy 175.95417 -287.01708) (xy 175.934879 -286.971804) (xy 175.923102 -286.92402)
			(xy 175.919142 -286.874966) (xy 174.630334 -286.874966) (xy 174.629839 -286.899573) (xy 174.621944 -286.94815)
			(xy 174.60636 -286.994831) (xy 174.583489 -287.038408) (xy 174.553924 -287.077752) (xy 174.518431 -287.111844)
			(xy 174.477928 -287.1398) (xy 174.433466 -287.160898) (xy 174.386195 -287.17459) (xy 174.33734 -287.180522)
			(xy 174.288165 -287.178541) (xy 174.239946 -287.168697) (xy 174.19393 -287.151245) (xy 174.151309 -287.126638)
			(xy 174.113188 -287.095513) (xy 174.080553 -287.058676) (xy 174.05425 -287.01708) (xy 174.034959 -286.971804)
			(xy 174.023182 -286.92402) (xy 174.019222 -286.874966) (xy 173.680374 -286.874966) (xy 173.679879 -286.899573)
			(xy 173.671984 -286.94815) (xy 173.6564 -286.994831) (xy 173.633529 -287.038408) (xy 173.603964 -287.077752)
			(xy 173.568471 -287.111844) (xy 173.527968 -287.1398) (xy 173.483506 -287.160898) (xy 173.436235 -287.17459)
			(xy 173.38738 -287.180522) (xy 173.338205 -287.178541) (xy 173.289986 -287.168697) (xy 173.24397 -287.151245)
			(xy 173.201349 -287.126638) (xy 173.163228 -287.095513) (xy 173.130593 -287.058676) (xy 173.10429 -287.01708)
			(xy 173.084999 -286.971804) (xy 173.073222 -286.92402) (xy 173.069262 -286.874966) (xy 172.73016 -286.874966)
			(xy 172.729665 -286.899573) (xy 172.72177 -286.94815) (xy 172.706186 -286.994831) (xy 172.683315 -287.038408)
			(xy 172.65375 -287.077752) (xy 172.618257 -287.111844) (xy 172.577754 -287.1398) (xy 172.533292 -287.160898)
			(xy 172.486021 -287.17459) (xy 172.437166 -287.180522) (xy 172.387991 -287.178541) (xy 172.339772 -287.168697)
			(xy 172.293756 -287.151245) (xy 172.251135 -287.126638) (xy 172.213014 -287.095513) (xy 172.180379 -287.058676)
			(xy 172.154076 -287.01708) (xy 172.134785 -286.971804) (xy 172.123008 -286.92402) (xy 172.119048 -286.874966)
			(xy 171.7802 -286.874966) (xy 171.779705 -286.899573) (xy 171.77181 -286.94815) (xy 171.756226 -286.994831)
			(xy 171.733355 -287.038408) (xy 171.70379 -287.077752) (xy 171.668297 -287.111844) (xy 171.627794 -287.1398)
			(xy 171.583332 -287.160898) (xy 171.536061 -287.17459) (xy 171.487206 -287.180522) (xy 171.438031 -287.178541)
			(xy 171.389812 -287.168697) (xy 171.343796 -287.151245) (xy 171.301175 -287.126638) (xy 171.263054 -287.095513)
			(xy 171.230419 -287.058676) (xy 171.204116 -287.01708) (xy 171.184825 -286.971804) (xy 171.173048 -286.92402)
			(xy 171.169088 -286.874966) (xy 170.83024 -286.874966) (xy 170.829745 -286.899573) (xy 170.82185 -286.94815)
			(xy 170.806266 -286.994831) (xy 170.783395 -287.038408) (xy 170.75383 -287.077752) (xy 170.718337 -287.111844)
			(xy 170.677834 -287.1398) (xy 170.633372 -287.160898) (xy 170.586101 -287.17459) (xy 170.537246 -287.180522)
			(xy 170.488071 -287.178541) (xy 170.439852 -287.168697) (xy 170.393836 -287.151245) (xy 170.351215 -287.126638)
			(xy 170.313094 -287.095513) (xy 170.280459 -287.058676) (xy 170.254156 -287.01708) (xy 170.234865 -286.971804)
			(xy 170.223088 -286.92402) (xy 170.219128 -286.874966) (xy 169.88028 -286.874966) (xy 169.879785 -286.899573)
			(xy 169.87189 -286.94815) (xy 169.856306 -286.994831) (xy 169.833435 -287.038408) (xy 169.80387 -287.077752)
			(xy 169.768377 -287.111844) (xy 169.727874 -287.1398) (xy 169.683412 -287.160898) (xy 169.636141 -287.17459)
			(xy 169.587286 -287.180522) (xy 169.538111 -287.178541) (xy 169.489892 -287.168697) (xy 169.443876 -287.151245)
			(xy 169.401255 -287.126638) (xy 169.363134 -287.095513) (xy 169.330499 -287.058676) (xy 169.304196 -287.01708)
			(xy 169.284905 -286.971804) (xy 169.273128 -286.92402) (xy 169.269168 -286.874966) (xy 168.93032 -286.874966)
			(xy 168.929825 -286.899573) (xy 168.92193 -286.94815) (xy 168.906346 -286.994831) (xy 168.883475 -287.038408)
			(xy 168.85391 -287.077752) (xy 168.818417 -287.111844) (xy 168.777914 -287.1398) (xy 168.733452 -287.160898)
			(xy 168.686181 -287.17459) (xy 168.637326 -287.180522) (xy 168.588151 -287.178541) (xy 168.539932 -287.168697)
			(xy 168.493916 -287.151245) (xy 168.451295 -287.126638) (xy 168.413174 -287.095513) (xy 168.380539 -287.058676)
			(xy 168.354236 -287.01708) (xy 168.334945 -286.971804) (xy 168.323168 -286.92402) (xy 168.319208 -286.874966)
			(xy 167.98036 -286.874966) (xy 167.979865 -286.899573) (xy 167.97197 -286.94815) (xy 167.956386 -286.994831)
			(xy 167.933515 -287.038408) (xy 167.90395 -287.077752) (xy 167.868457 -287.111844) (xy 167.827954 -287.1398)
			(xy 167.783492 -287.160898) (xy 167.736221 -287.17459) (xy 167.687366 -287.180522) (xy 167.638191 -287.178541)
			(xy 167.589972 -287.168697) (xy 167.543956 -287.151245) (xy 167.501335 -287.126638) (xy 167.463214 -287.095513)
			(xy 167.430579 -287.058676) (xy 167.404276 -287.01708) (xy 167.384985 -286.971804) (xy 167.373208 -286.92402)
			(xy 167.369248 -286.874966) (xy 167.0304 -286.874966) (xy 167.029905 -286.899573) (xy 167.02201 -286.94815)
			(xy 167.006426 -286.994831) (xy 166.983555 -287.038408) (xy 166.95399 -287.077752) (xy 166.918497 -287.111844)
			(xy 166.877994 -287.1398) (xy 166.833532 -287.160898) (xy 166.786261 -287.17459) (xy 166.737406 -287.180522)
			(xy 166.688231 -287.178541) (xy 166.640012 -287.168697) (xy 166.593996 -287.151245) (xy 166.551375 -287.126638)
			(xy 166.513254 -287.095513) (xy 166.480619 -287.058676) (xy 166.454316 -287.01708) (xy 166.435025 -286.971804)
			(xy 166.423248 -286.92402) (xy 166.419288 -286.874966) (xy 166.080186 -286.874966) (xy 166.079691 -286.899573)
			(xy 166.071796 -286.94815) (xy 166.056212 -286.994831) (xy 166.033341 -287.038408) (xy 166.003776 -287.077752)
			(xy 165.968283 -287.111844) (xy 165.92778 -287.1398) (xy 165.883318 -287.160898) (xy 165.836047 -287.17459)
			(xy 165.787192 -287.180522) (xy 165.738017 -287.178541) (xy 165.689798 -287.168697) (xy 165.643782 -287.151245)
			(xy 165.601161 -287.126638) (xy 165.56304 -287.095513) (xy 165.530405 -287.058676) (xy 165.504102 -287.01708)
			(xy 165.484811 -286.971804) (xy 165.473034 -286.92402) (xy 165.469074 -286.874966) (xy 165.155117 -286.874966)
			(xy 165.155118 -286.90138) (xy 165.146739 -286.953479) (xy 165.130195 -287.003587) (xy 165.105904 -287.050432)
			(xy 165.074483 -287.092825) (xy 165.036729 -287.129692) (xy 164.9936 -287.160096) (xy 164.94619 -287.183266)
			(xy 164.895703 -287.198615) (xy 164.869622 -287.202626) (xy 164.86505 -287.203388) (xy 164.852858 -287.207198)
			(xy 164.849556 -287.208214) (xy 164.826188 -287.219136) (xy 164.819584 -287.226248) (xy 164.804852 -287.241742)
			(xy 164.796724 -287.252918) (xy 164.794031 -287.25845) (xy 164.791084 -287.270391) (xy 164.790882 -287.27654)
			(xy 164.790882 -287.349946) (xy 189.69407 -287.349946) (xy 189.69803 -287.300892) (xy 189.709807 -287.253108)
			(xy 189.729098 -287.207832) (xy 189.755401 -287.166236) (xy 189.788036 -287.129399) (xy 189.826157 -287.098274)
			(xy 189.868778 -287.073667) (xy 189.914794 -287.056215) (xy 189.963013 -287.046371) (xy 190.012188 -287.04439)
			(xy 190.061043 -287.050322) (xy 190.108314 -287.064014) (xy 190.152776 -287.085112) (xy 190.193279 -287.113068)
			(xy 190.228772 -287.14716) (xy 190.258337 -287.186504) (xy 190.281208 -287.230081) (xy 190.296792 -287.276762)
			(xy 190.304687 -287.325339) (xy 190.305182 -287.349946) (xy 190.304687 -287.374553) (xy 190.304508 -287.375654)
			(xy 190.623186 -287.375654) (xy 190.623186 -287.324238) (xy 190.631229 -287.273456) (xy 190.647117 -287.224557)
			(xy 190.67046 -287.178745) (xy 190.700681 -287.137149) (xy 190.737037 -287.100793) (xy 190.778633 -287.070572)
			(xy 190.824445 -287.047229) (xy 190.873344 -287.031341) (xy 190.924126 -287.023298) (xy 190.975542 -287.023298)
			(xy 191.026324 -287.031341) (xy 191.075223 -287.047229) (xy 191.121035 -287.070572) (xy 191.162631 -287.100793)
			(xy 191.198987 -287.137149) (xy 191.229208 -287.178745) (xy 191.252551 -287.224557) (xy 191.268439 -287.273456)
			(xy 191.276482 -287.324238) (xy 191.276986 -287.349946) (xy 191.276482 -287.375654) (xy 191.5734 -287.375654)
			(xy 191.5734 -287.324238) (xy 191.581443 -287.273456) (xy 191.597331 -287.224557) (xy 191.620674 -287.178745)
			(xy 191.650895 -287.137149) (xy 191.687251 -287.100793) (xy 191.728847 -287.070572) (xy 191.774659 -287.047229)
			(xy 191.823558 -287.031341) (xy 191.87434 -287.023298) (xy 191.925756 -287.023298) (xy 191.976538 -287.031341)
			(xy 192.025437 -287.047229) (xy 192.071249 -287.070572) (xy 192.112845 -287.100793) (xy 192.149201 -287.137149)
			(xy 192.179422 -287.178745) (xy 192.202765 -287.224557) (xy 192.218653 -287.273456) (xy 192.226696 -287.324238)
			(xy 192.2272 -287.349946) (xy 192.544204 -287.349946) (xy 192.548164 -287.300892) (xy 192.559941 -287.253108)
			(xy 192.579232 -287.207832) (xy 192.605535 -287.166236) (xy 192.63817 -287.129399) (xy 192.676291 -287.098274)
			(xy 192.718912 -287.073667) (xy 192.764928 -287.056215) (xy 192.813147 -287.046371) (xy 192.862322 -287.04439)
			(xy 192.911177 -287.050322) (xy 192.958448 -287.064014) (xy 193.00291 -287.085112) (xy 193.043413 -287.113068)
			(xy 193.078906 -287.14716) (xy 193.108471 -287.186504) (xy 193.131342 -287.230081) (xy 193.146926 -287.276762)
			(xy 193.154821 -287.325339) (xy 193.155316 -287.349946) (xy 193.494164 -287.349946) (xy 193.498124 -287.300892)
			(xy 193.509901 -287.253108) (xy 193.529192 -287.207832) (xy 193.555495 -287.166236) (xy 193.58813 -287.129399)
			(xy 193.626251 -287.098274) (xy 193.668872 -287.073667) (xy 193.714888 -287.056215) (xy 193.763107 -287.046371)
			(xy 193.812282 -287.04439) (xy 193.861137 -287.050322) (xy 193.908408 -287.064014) (xy 193.95287 -287.085112)
			(xy 193.993373 -287.113068) (xy 194.028866 -287.14716) (xy 194.058431 -287.186504) (xy 194.081302 -287.230081)
			(xy 194.096886 -287.276762) (xy 194.104781 -287.325339) (xy 194.105276 -287.349946) (xy 194.444124 -287.349946)
			(xy 194.448084 -287.300892) (xy 194.459861 -287.253108) (xy 194.479152 -287.207832) (xy 194.505455 -287.166236)
			(xy 194.53809 -287.129399) (xy 194.576211 -287.098274) (xy 194.618832 -287.073667) (xy 194.664848 -287.056215)
			(xy 194.713067 -287.046371) (xy 194.762242 -287.04439) (xy 194.811097 -287.050322) (xy 194.858368 -287.064014)
			(xy 194.90283 -287.085112) (xy 194.943333 -287.113068) (xy 194.978826 -287.14716) (xy 195.008391 -287.186504)
			(xy 195.031262 -287.230081) (xy 195.046846 -287.276762) (xy 195.054741 -287.325339) (xy 195.055236 -287.349946)
			(xy 195.39383 -287.349946) (xy 195.39779 -287.300892) (xy 195.409567 -287.253108) (xy 195.428858 -287.207832)
			(xy 195.455161 -287.166236) (xy 195.487796 -287.129399) (xy 195.525917 -287.098274) (xy 195.568538 -287.073667)
			(xy 195.614554 -287.056215) (xy 195.662773 -287.046371) (xy 195.711948 -287.04439) (xy 195.760803 -287.050322)
			(xy 195.808074 -287.064014) (xy 195.852536 -287.085112) (xy 195.893039 -287.113068) (xy 195.928532 -287.14716)
			(xy 195.958097 -287.186504) (xy 195.980968 -287.230081) (xy 195.996552 -287.276762) (xy 196.004447 -287.325339)
			(xy 196.004942 -287.349946) (xy 196.344044 -287.349946) (xy 196.348004 -287.300892) (xy 196.359781 -287.253108)
			(xy 196.379072 -287.207832) (xy 196.405375 -287.166236) (xy 196.43801 -287.129399) (xy 196.476131 -287.098274)
			(xy 196.518752 -287.073667) (xy 196.564768 -287.056215) (xy 196.612987 -287.046371) (xy 196.662162 -287.04439)
			(xy 196.711017 -287.050322) (xy 196.758288 -287.064014) (xy 196.80275 -287.085112) (xy 196.843253 -287.113068)
			(xy 196.878746 -287.14716) (xy 196.908311 -287.186504) (xy 196.931182 -287.230081) (xy 196.946766 -287.276762)
			(xy 196.954661 -287.325339) (xy 196.955156 -287.349946) (xy 196.954661 -287.374553) (xy 196.954482 -287.375654)
			(xy 197.273414 -287.375654) (xy 197.273414 -287.324238) (xy 197.281457 -287.273456) (xy 197.297345 -287.224557)
			(xy 197.320688 -287.178745) (xy 197.350909 -287.137149) (xy 197.387265 -287.100793) (xy 197.428861 -287.070572)
			(xy 197.474673 -287.047229) (xy 197.523572 -287.031341) (xy 197.574354 -287.023298) (xy 197.62577 -287.023298)
			(xy 197.676552 -287.031341) (xy 197.725451 -287.047229) (xy 197.771263 -287.070572) (xy 197.812859 -287.100793)
			(xy 197.849215 -287.137149) (xy 197.879436 -287.178745) (xy 197.902779 -287.224557) (xy 197.918667 -287.273456)
			(xy 197.92671 -287.324238) (xy 197.927214 -287.349946) (xy 197.92671 -287.375654) (xy 198.223374 -287.375654)
			(xy 198.223374 -287.324238) (xy 198.231417 -287.273456) (xy 198.247305 -287.224557) (xy 198.270648 -287.178745)
			(xy 198.300869 -287.137149) (xy 198.337225 -287.100793) (xy 198.378821 -287.070572) (xy 198.424633 -287.047229)
			(xy 198.473532 -287.031341) (xy 198.524314 -287.023298) (xy 198.57573 -287.023298) (xy 198.626512 -287.031341)
			(xy 198.675411 -287.047229) (xy 198.721223 -287.070572) (xy 198.762819 -287.100793) (xy 198.799175 -287.137149)
			(xy 198.829396 -287.178745) (xy 198.852739 -287.224557) (xy 198.868627 -287.273456) (xy 198.87667 -287.324238)
			(xy 198.877174 -287.349946) (xy 198.877169 -287.3502) (xy 199.194432 -287.3502) (xy 199.198392 -287.301146)
			(xy 199.210169 -287.253362) (xy 199.22946 -287.208086) (xy 199.255763 -287.16649) (xy 199.288398 -287.129653)
			(xy 199.326519 -287.098528) (xy 199.36914 -287.073921) (xy 199.415156 -287.056469) (xy 199.463375 -287.046625)
			(xy 199.51255 -287.044644) (xy 199.561405 -287.050576) (xy 199.608676 -287.064268) (xy 199.626724 -287.072832)
			(xy 208.407506 -287.072832) (xy 208.411577 -287.01721) (xy 208.423703 -286.962773) (xy 208.443626 -286.910682)
			(xy 208.470922 -286.862047) (xy 208.505008 -286.817904) (xy 208.545157 -286.779195) (xy 208.590515 -286.746744)
			(xy 208.640115 -286.721243) (xy 208.692899 -286.703236) (xy 208.747742 -286.693106) (xy 208.803476 -286.691069)
			(xy 208.858913 -286.697169) (xy 208.91287 -286.711275) (xy 208.964199 -286.733087) (xy 209.011805 -286.762141)
			(xy 209.054673 -286.797816) (xy 209.09189 -286.839353) (xy 209.122663 -286.885866) (xy 209.146335 -286.936363)
			(xy 209.162403 -286.98977) (xy 209.170523 -287.044946) (xy 209.171032 -287.072832) (xy 209.170523 -287.100718)
			(xy 209.165839 -287.132547) (xy 216.952122 -287.132547) (xy 216.952122 -287.078053) (xy 216.959877 -287.024115)
			(xy 216.975229 -286.971829) (xy 216.997865 -286.922259) (xy 217.027325 -286.876416) (xy 217.063009 -286.835231)
			(xy 217.10419 -286.799544) (xy 217.150031 -286.77008) (xy 217.199599 -286.74744) (xy 217.251883 -286.732084)
			(xy 217.305821 -286.724324) (xy 217.333068 -286.723836) (xy 217.361808 -286.724335) (xy 217.418635 -286.732967)
			(xy 217.473526 -286.750023) (xy 217.525237 -286.77512) (xy 217.572599 -286.807688) (xy 217.593926 -286.82696)
			(xy 217.601038 -286.833564) (xy 217.618564 -286.840676) (xy 217.707972 -286.840676) (xy 217.725498 -286.833564)
			(xy 217.73261 -286.82696) (xy 217.753953 -286.807708) (xy 217.801311 -286.775138) (xy 217.853018 -286.750042)
			(xy 217.907905 -286.732987) (xy 217.96473 -286.724359) (xy 217.993468 -286.723836) (xy 218.02359 -286.724431)
			(xy 218.083085 -286.733907) (xy 218.140353 -286.752612) (xy 218.19397 -286.780082) (xy 218.242606 -286.815636)
			(xy 218.264232 -286.836612) (xy 218.271344 -286.843978) (xy 218.29014 -286.851598) (xy 218.382596 -286.851598)
			(xy 218.401392 -286.843978) (xy 218.408504 -286.836612) (xy 218.430106 -286.815607) (xy 218.478741 -286.780041)
			(xy 218.532363 -286.752566) (xy 218.589638 -286.733863) (xy 218.649142 -286.7244) (xy 218.679268 -286.723836)
			(xy 218.706638 -286.724312) (xy 218.760817 -286.732126) (xy 218.81332 -286.747612) (xy 218.863067 -286.770452)
			(xy 218.909034 -286.800175) (xy 218.929966 -286.817816) (xy 218.937078 -286.823912) (xy 218.954096 -286.830262)
			(xy 219.03944 -286.830262) (xy 219.056458 -286.823912) (xy 219.06357 -286.817816) (xy 219.084505 -286.80018)
			(xy 219.130476 -286.770467) (xy 219.180223 -286.74763) (xy 219.232724 -286.732139) (xy 219.286899 -286.72431)
			(xy 219.314268 -286.723836) (xy 219.341526 -286.724209) (xy 219.395486 -286.731963) (xy 219.447794 -286.747318)
			(xy 219.497384 -286.769961) (xy 219.543246 -286.799432) (xy 219.584448 -286.83513) (xy 219.620149 -286.876328)
			(xy 219.649623 -286.922188) (xy 219.672271 -286.971776) (xy 219.68763 -287.024083) (xy 219.695389 -287.078043)
			(xy 219.695389 -287.132546) (xy 220.945522 -287.132546) (xy 220.945522 -287.078054) (xy 220.953276 -287.024116)
			(xy 220.968628 -286.971831) (xy 220.991263 -286.922263) (xy 221.020722 -286.87642) (xy 221.056404 -286.835235)
			(xy 221.097584 -286.799548) (xy 221.143424 -286.770084) (xy 221.19299 -286.747443) (xy 221.245273 -286.732086)
			(xy 221.29921 -286.724325) (xy 221.326456 -286.723836) (xy 221.355195 -286.724343) (xy 221.412023 -286.732972)
			(xy 221.466913 -286.750027) (xy 221.518624 -286.775122) (xy 221.565987 -286.807689) (xy 221.587314 -286.82696)
			(xy 221.594426 -286.833564) (xy 221.611952 -286.840676) (xy 221.70136 -286.840676) (xy 221.718886 -286.833564)
			(xy 221.725998 -286.82696) (xy 221.747325 -286.80769) (xy 221.794688 -286.775125) (xy 221.846399 -286.750034)
			(xy 221.90129 -286.732984) (xy 221.958117 -286.724362) (xy 222.015595 -286.724362) (xy 222.072422 -286.732984)
			(xy 222.127313 -286.750034) (xy 222.179024 -286.775125) (xy 222.226387 -286.80769) (xy 222.247714 -286.82696)
			(xy 222.254826 -286.833564) (xy 222.272352 -286.840676) (xy 222.36176 -286.840676) (xy 222.379286 -286.833564)
			(xy 222.386398 -286.82696) (xy 222.407705 -286.807666) (xy 222.455072 -286.775102) (xy 222.506789 -286.750014)
			(xy 222.561684 -286.732969) (xy 222.618516 -286.724353) (xy 222.647256 -286.723836) (xy 222.677378 -286.724438)
			(xy 222.736873 -286.733912) (xy 222.79414 -286.752616) (xy 222.847758 -286.780085) (xy 222.896394 -286.815636)
			(xy 222.91802 -286.836612) (xy 222.925132 -286.843978) (xy 222.943928 -286.851598) (xy 223.036384 -286.851598)
			(xy 223.05518 -286.843978) (xy 223.062292 -286.836612) (xy 223.083899 -286.815613) (xy 223.132533 -286.780046)
			(xy 223.186153 -286.75257) (xy 223.243428 -286.733866) (xy 223.30293 -286.724401) (xy 223.333056 -286.723836)
			(xy 223.360314 -286.724208) (xy 223.414276 -286.731961) (xy 223.466585 -286.747315) (xy 223.516177 -286.769957)
			(xy 223.562041 -286.799428) (xy 223.603243 -286.835125) (xy 223.638946 -286.876324) (xy 223.668422 -286.922185)
			(xy 223.69107 -286.971773) (xy 223.70643 -287.024081) (xy 223.714189 -287.078042) (xy 223.714189 -287.132558)
			(xy 223.70643 -287.186519) (xy 223.69107 -287.238827) (xy 223.668422 -287.288415) (xy 223.638946 -287.334276)
			(xy 223.603243 -287.375475) (xy 223.562041 -287.411172) (xy 223.516177 -287.440643) (xy 223.466585 -287.463285)
			(xy 223.414276 -287.478639) (xy 223.360314 -287.486392) (xy 223.333056 -287.486852) (xy 223.302934 -287.486245)
			(xy 223.243439 -287.476773) (xy 223.186172 -287.45807) (xy 223.132554 -287.430602) (xy 223.083918 -287.395051)
			(xy 223.062292 -287.374076) (xy 223.05518 -287.36671) (xy 223.036384 -287.35909) (xy 222.943928 -287.35909)
			(xy 222.925132 -287.36671) (xy 222.91802 -287.374076) (xy 222.896406 -287.395068) (xy 222.847774 -287.430635)
			(xy 222.794155 -287.458114) (xy 222.736883 -287.476819) (xy 222.677381 -287.486286) (xy 222.647256 -287.486852)
			(xy 222.618517 -287.486341) (xy 222.561689 -287.477713) (xy 222.506799 -287.460659) (xy 222.455088 -287.435565)
			(xy 222.407725 -287.402999) (xy 222.386398 -287.383728) (xy 222.379286 -287.377124) (xy 222.36176 -287.370012)
			(xy 222.272352 -287.370012) (xy 222.254826 -287.377124) (xy 222.247714 -287.383728) (xy 222.226387 -287.402998)
			(xy 222.179024 -287.435563) (xy 222.127313 -287.460654) (xy 222.072422 -287.477704) (xy 222.015595 -287.486326)
			(xy 221.958117 -287.486326) (xy 221.90129 -287.477704) (xy 221.846399 -287.460654) (xy 221.794688 -287.435563)
			(xy 221.747325 -287.402998) (xy 221.725998 -287.383728) (xy 221.718886 -287.377124) (xy 221.70136 -287.370012)
			(xy 221.611952 -287.370012) (xy 221.594426 -287.377124) (xy 221.587314 -287.383728) (xy 221.566 -287.403014)
			(xy 221.518635 -287.435579) (xy 221.46692 -287.46067) (xy 221.412026 -287.477716) (xy 221.355196 -287.486334)
			(xy 221.326456 -287.486852) (xy 221.29921 -287.486275) (xy 221.245273 -287.478514) (xy 221.19299 -287.463157)
			(xy 221.143424 -287.440516) (xy 221.097584 -287.411052) (xy 221.056404 -287.375365) (xy 221.020722 -287.33418)
			(xy 220.991263 -287.288337) (xy 220.968628 -287.238769) (xy 220.953276 -287.186484) (xy 220.945522 -287.132546)
			(xy 219.695389 -287.132546) (xy 219.695389 -287.132557) (xy 219.68763 -287.186517) (xy 219.672271 -287.238824)
			(xy 219.649623 -287.288412) (xy 219.620149 -287.334272) (xy 219.584448 -287.37547) (xy 219.543246 -287.411168)
			(xy 219.497384 -287.440639) (xy 219.447794 -287.463282) (xy 219.395486 -287.478637) (xy 219.341526 -287.486391)
			(xy 219.314268 -287.486852) (xy 219.286897 -287.486416) (xy 219.232716 -287.478593) (xy 219.180212 -287.463097)
			(xy 219.130465 -287.440249) (xy 219.0845 -287.410517) (xy 219.06357 -287.392872) (xy 219.056458 -287.386776)
			(xy 219.03944 -287.380426) (xy 218.954096 -287.380426) (xy 218.937078 -287.386776) (xy 218.929966 -287.392872)
			(xy 218.909016 -287.410489) (xy 218.863049 -287.440205) (xy 218.813306 -287.463046) (xy 218.760809 -287.478542)
			(xy 218.706636 -287.486375) (xy 218.679268 -287.486852) (xy 218.649144 -287.486301) (xy 218.589647 -287.476815)
			(xy 218.532378 -287.458099) (xy 218.478762 -287.430619) (xy 218.430128 -287.395057) (xy 218.408504 -287.374076)
			(xy 218.401392 -287.36671) (xy 218.382596 -287.35909) (xy 218.29014 -287.35909) (xy 218.271344 -287.36671)
			(xy 218.264232 -287.374076) (xy 218.242612 -287.395062) (xy 218.193983 -287.43063) (xy 218.140365 -287.45811)
			(xy 218.083093 -287.476817) (xy 218.023593 -287.486285) (xy 217.993468 -287.486852) (xy 217.964729 -287.486334)
			(xy 217.907902 -287.477708) (xy 217.853012 -287.460656) (xy 217.8013 -287.435563) (xy 217.753937 -287.402998)
			(xy 217.73261 -287.383728) (xy 217.725498 -287.377124) (xy 217.707972 -287.370012) (xy 217.618564 -287.370012)
			(xy 217.601038 -287.377124) (xy 217.593926 -287.383728) (xy 217.572607 -287.403008) (xy 217.525243 -287.435574)
			(xy 217.47353 -287.460666) (xy 217.418637 -287.477714) (xy 217.361808 -287.486333) (xy 217.333068 -287.486852)
			(xy 217.305821 -287.486276) (xy 217.251883 -287.478516) (xy 217.199599 -287.46316) (xy 217.150031 -287.44052)
			(xy 217.10419 -287.411056) (xy 217.063009 -287.375369) (xy 217.027325 -287.334184) (xy 216.997865 -287.288341)
			(xy 216.975229 -287.238771) (xy 216.959877 -287.186485) (xy 216.952122 -287.132547) (xy 209.165839 -287.132547)
			(xy 209.162403 -287.155894) (xy 209.146335 -287.209301) (xy 209.122663 -287.259798) (xy 209.09189 -287.306311)
			(xy 209.054673 -287.347848) (xy 209.011805 -287.383523) (xy 208.964199 -287.412577) (xy 208.91287 -287.434389)
			(xy 208.858913 -287.448495) (xy 208.803476 -287.454595) (xy 208.747742 -287.452558) (xy 208.692899 -287.442428)
			(xy 208.640115 -287.424421) (xy 208.590515 -287.39892) (xy 208.545157 -287.366469) (xy 208.505008 -287.32776)
			(xy 208.470922 -287.283617) (xy 208.443626 -287.234982) (xy 208.423703 -287.182891) (xy 208.411577 -287.128454)
			(xy 208.407506 -287.072832) (xy 199.626724 -287.072832) (xy 199.653138 -287.085366) (xy 199.693641 -287.113322)
			(xy 199.729134 -287.147414) (xy 199.758699 -287.186758) (xy 199.78157 -287.230335) (xy 199.797154 -287.277016)
			(xy 199.805049 -287.325593) (xy 199.805544 -287.3502) (xy 199.805049 -287.374807) (xy 199.797154 -287.423384)
			(xy 199.78157 -287.470065) (xy 199.758699 -287.513642) (xy 199.729134 -287.552986) (xy 199.693641 -287.587078)
			(xy 199.653138 -287.615034) (xy 199.608676 -287.636132) (xy 199.561405 -287.649824) (xy 199.51255 -287.655756)
			(xy 199.463375 -287.653775) (xy 199.415156 -287.643931) (xy 199.36914 -287.626479) (xy 199.326519 -287.601872)
			(xy 199.288398 -287.570747) (xy 199.255763 -287.53391) (xy 199.22946 -287.492314) (xy 199.210169 -287.447038)
			(xy 199.198392 -287.399254) (xy 199.194432 -287.3502) (xy 198.877169 -287.3502) (xy 198.87667 -287.375654)
			(xy 198.868627 -287.426436) (xy 198.852739 -287.475335) (xy 198.829396 -287.521147) (xy 198.799175 -287.562743)
			(xy 198.762819 -287.599099) (xy 198.721223 -287.62932) (xy 198.675411 -287.652663) (xy 198.626512 -287.668551)
			(xy 198.57573 -287.676594) (xy 198.524314 -287.676594) (xy 198.473532 -287.668551) (xy 198.424633 -287.652663)
			(xy 198.378821 -287.62932) (xy 198.337225 -287.599099) (xy 198.300869 -287.562743) (xy 198.270648 -287.521147)
			(xy 198.247305 -287.475335) (xy 198.231417 -287.426436) (xy 198.223374 -287.375654) (xy 197.92671 -287.375654)
			(xy 197.918667 -287.426436) (xy 197.902779 -287.475335) (xy 197.879436 -287.521147) (xy 197.849215 -287.562743)
			(xy 197.812859 -287.599099) (xy 197.771263 -287.62932) (xy 197.725451 -287.652663) (xy 197.676552 -287.668551)
			(xy 197.62577 -287.676594) (xy 197.574354 -287.676594) (xy 197.523572 -287.668551) (xy 197.474673 -287.652663)
			(xy 197.428861 -287.62932) (xy 197.387265 -287.599099) (xy 197.350909 -287.562743) (xy 197.320688 -287.521147)
			(xy 197.297345 -287.475335) (xy 197.281457 -287.426436) (xy 197.273414 -287.375654) (xy 196.954482 -287.375654)
			(xy 196.946766 -287.42313) (xy 196.931182 -287.469811) (xy 196.908311 -287.513388) (xy 196.878746 -287.552732)
			(xy 196.843253 -287.586824) (xy 196.80275 -287.61478) (xy 196.758288 -287.635878) (xy 196.711017 -287.64957)
			(xy 196.662162 -287.655502) (xy 196.612987 -287.653521) (xy 196.564768 -287.643677) (xy 196.518752 -287.626225)
			(xy 196.476131 -287.601618) (xy 196.43801 -287.570493) (xy 196.405375 -287.533656) (xy 196.379072 -287.49206)
			(xy 196.359781 -287.446784) (xy 196.348004 -287.399) (xy 196.344044 -287.349946) (xy 196.004942 -287.349946)
			(xy 196.004447 -287.374553) (xy 195.996552 -287.42313) (xy 195.980968 -287.469811) (xy 195.958097 -287.513388)
			(xy 195.928532 -287.552732) (xy 195.893039 -287.586824) (xy 195.852536 -287.61478) (xy 195.808074 -287.635878)
			(xy 195.760803 -287.64957) (xy 195.711948 -287.655502) (xy 195.662773 -287.653521) (xy 195.614554 -287.643677)
			(xy 195.568538 -287.626225) (xy 195.525917 -287.601618) (xy 195.487796 -287.570493) (xy 195.455161 -287.533656)
			(xy 195.428858 -287.49206) (xy 195.409567 -287.446784) (xy 195.39779 -287.399) (xy 195.39383 -287.349946)
			(xy 195.055236 -287.349946) (xy 195.054741 -287.374553) (xy 195.046846 -287.42313) (xy 195.031262 -287.469811)
			(xy 195.008391 -287.513388) (xy 194.978826 -287.552732) (xy 194.943333 -287.586824) (xy 194.90283 -287.61478)
			(xy 194.858368 -287.635878) (xy 194.811097 -287.64957) (xy 194.762242 -287.655502) (xy 194.713067 -287.653521)
			(xy 194.664848 -287.643677) (xy 194.618832 -287.626225) (xy 194.576211 -287.601618) (xy 194.53809 -287.570493)
			(xy 194.505455 -287.533656) (xy 194.479152 -287.49206) (xy 194.459861 -287.446784) (xy 194.448084 -287.399)
			(xy 194.444124 -287.349946) (xy 194.105276 -287.349946) (xy 194.104781 -287.374553) (xy 194.096886 -287.42313)
			(xy 194.081302 -287.469811) (xy 194.058431 -287.513388) (xy 194.028866 -287.552732) (xy 193.993373 -287.586824)
			(xy 193.95287 -287.61478) (xy 193.908408 -287.635878) (xy 193.861137 -287.64957) (xy 193.812282 -287.655502)
			(xy 193.763107 -287.653521) (xy 193.714888 -287.643677) (xy 193.668872 -287.626225) (xy 193.626251 -287.601618)
			(xy 193.58813 -287.570493) (xy 193.555495 -287.533656) (xy 193.529192 -287.49206) (xy 193.509901 -287.446784)
			(xy 193.498124 -287.399) (xy 193.494164 -287.349946) (xy 193.155316 -287.349946) (xy 193.154821 -287.374553)
			(xy 193.146926 -287.42313) (xy 193.131342 -287.469811) (xy 193.108471 -287.513388) (xy 193.078906 -287.552732)
			(xy 193.043413 -287.586824) (xy 193.00291 -287.61478) (xy 192.958448 -287.635878) (xy 192.911177 -287.64957)
			(xy 192.862322 -287.655502) (xy 192.813147 -287.653521) (xy 192.764928 -287.643677) (xy 192.718912 -287.626225)
			(xy 192.676291 -287.601618) (xy 192.63817 -287.570493) (xy 192.605535 -287.533656) (xy 192.579232 -287.49206)
			(xy 192.559941 -287.446784) (xy 192.548164 -287.399) (xy 192.544204 -287.349946) (xy 192.2272 -287.349946)
			(xy 192.226696 -287.375654) (xy 192.218653 -287.426436) (xy 192.202765 -287.475335) (xy 192.179422 -287.521147)
			(xy 192.149201 -287.562743) (xy 192.112845 -287.599099) (xy 192.071249 -287.62932) (xy 192.025437 -287.652663)
			(xy 191.976538 -287.668551) (xy 191.925756 -287.676594) (xy 191.87434 -287.676594) (xy 191.823558 -287.668551)
			(xy 191.774659 -287.652663) (xy 191.728847 -287.62932) (xy 191.687251 -287.599099) (xy 191.650895 -287.562743)
			(xy 191.620674 -287.521147) (xy 191.597331 -287.475335) (xy 191.581443 -287.426436) (xy 191.5734 -287.375654)
			(xy 191.276482 -287.375654) (xy 191.268439 -287.426436) (xy 191.252551 -287.475335) (xy 191.229208 -287.521147)
			(xy 191.198987 -287.562743) (xy 191.162631 -287.599099) (xy 191.121035 -287.62932) (xy 191.075223 -287.652663)
			(xy 191.026324 -287.668551) (xy 190.975542 -287.676594) (xy 190.924126 -287.676594) (xy 190.873344 -287.668551)
			(xy 190.824445 -287.652663) (xy 190.778633 -287.62932) (xy 190.737037 -287.599099) (xy 190.700681 -287.562743)
			(xy 190.67046 -287.521147) (xy 190.647117 -287.475335) (xy 190.631229 -287.426436) (xy 190.623186 -287.375654)
			(xy 190.304508 -287.375654) (xy 190.296792 -287.42313) (xy 190.281208 -287.469811) (xy 190.258337 -287.513388)
			(xy 190.228772 -287.552732) (xy 190.193279 -287.586824) (xy 190.152776 -287.61478) (xy 190.108314 -287.635878)
			(xy 190.061043 -287.64957) (xy 190.012188 -287.655502) (xy 189.963013 -287.653521) (xy 189.914794 -287.643677)
			(xy 189.868778 -287.626225) (xy 189.826157 -287.601618) (xy 189.788036 -287.570493) (xy 189.755401 -287.533656)
			(xy 189.729098 -287.49206) (xy 189.709807 -287.446784) (xy 189.69803 -287.399) (xy 189.69407 -287.349946)
			(xy 164.790882 -287.349946) (xy 164.790882 -287.423352) (xy 164.791355 -287.432982) (xy 164.798543 -287.450858)
			(xy 164.804852 -287.45815) (xy 164.820092 -287.474152) (xy 164.82695 -287.481518) (xy 164.850318 -287.491932)
			(xy 164.854636 -287.493202) (xy 164.86505 -287.496504) (xy 164.869622 -287.497266) (xy 164.89569 -287.501343)
			(xy 164.946168 -287.516688) (xy 164.993569 -287.539854) (xy 165.03669 -287.570253) (xy 165.074437 -287.607113)
			(xy 165.105853 -287.649499) (xy 165.13014 -287.696335) (xy 165.146681 -287.746434) (xy 165.155058 -287.798524)
			(xy 165.155058 -287.824926) (xy 165.469074 -287.824926) (xy 165.473034 -287.775872) (xy 165.484811 -287.728088)
			(xy 165.504102 -287.682812) (xy 165.530405 -287.641216) (xy 165.56304 -287.604379) (xy 165.601161 -287.573254)
			(xy 165.643782 -287.548647) (xy 165.689798 -287.531195) (xy 165.738017 -287.521351) (xy 165.787192 -287.51937)
			(xy 165.836047 -287.525302) (xy 165.883318 -287.538994) (xy 165.92778 -287.560092) (xy 165.968283 -287.588048)
			(xy 166.003776 -287.62214) (xy 166.033341 -287.661484) (xy 166.056212 -287.705061) (xy 166.071796 -287.751742)
			(xy 166.079691 -287.800319) (xy 166.080186 -287.824926) (xy 166.419288 -287.824926) (xy 166.423248 -287.775872)
			(xy 166.435025 -287.728088) (xy 166.454316 -287.682812) (xy 166.480619 -287.641216) (xy 166.513254 -287.604379)
			(xy 166.551375 -287.573254) (xy 166.593996 -287.548647) (xy 166.640012 -287.531195) (xy 166.688231 -287.521351)
			(xy 166.737406 -287.51937) (xy 166.786261 -287.525302) (xy 166.833532 -287.538994) (xy 166.877994 -287.560092)
			(xy 166.918497 -287.588048) (xy 166.95399 -287.62214) (xy 166.983555 -287.661484) (xy 167.006426 -287.705061)
			(xy 167.02201 -287.751742) (xy 167.029905 -287.800319) (xy 167.0304 -287.824926) (xy 167.369248 -287.824926)
			(xy 167.373208 -287.775872) (xy 167.384985 -287.728088) (xy 167.404276 -287.682812) (xy 167.430579 -287.641216)
			(xy 167.463214 -287.604379) (xy 167.501335 -287.573254) (xy 167.543956 -287.548647) (xy 167.589972 -287.531195)
			(xy 167.638191 -287.521351) (xy 167.687366 -287.51937) (xy 167.736221 -287.525302) (xy 167.783492 -287.538994)
			(xy 167.827954 -287.560092) (xy 167.868457 -287.588048) (xy 167.90395 -287.62214) (xy 167.933515 -287.661484)
			(xy 167.956386 -287.705061) (xy 167.97197 -287.751742) (xy 167.979865 -287.800319) (xy 167.98036 -287.824926)
			(xy 168.319208 -287.824926) (xy 168.323168 -287.775872) (xy 168.334945 -287.728088) (xy 168.354236 -287.682812)
			(xy 168.380539 -287.641216) (xy 168.413174 -287.604379) (xy 168.451295 -287.573254) (xy 168.493916 -287.548647)
			(xy 168.539932 -287.531195) (xy 168.588151 -287.521351) (xy 168.637326 -287.51937) (xy 168.686181 -287.525302)
			(xy 168.733452 -287.538994) (xy 168.777914 -287.560092) (xy 168.818417 -287.588048) (xy 168.85391 -287.62214)
			(xy 168.883475 -287.661484) (xy 168.906346 -287.705061) (xy 168.92193 -287.751742) (xy 168.929825 -287.800319)
			(xy 168.93032 -287.824926) (xy 169.269168 -287.824926) (xy 169.273128 -287.775872) (xy 169.284905 -287.728088)
			(xy 169.304196 -287.682812) (xy 169.330499 -287.641216) (xy 169.363134 -287.604379) (xy 169.401255 -287.573254)
			(xy 169.443876 -287.548647) (xy 169.489892 -287.531195) (xy 169.538111 -287.521351) (xy 169.587286 -287.51937)
			(xy 169.636141 -287.525302) (xy 169.683412 -287.538994) (xy 169.727874 -287.560092) (xy 169.768377 -287.588048)
			(xy 169.80387 -287.62214) (xy 169.833435 -287.661484) (xy 169.856306 -287.705061) (xy 169.87189 -287.751742)
			(xy 169.879785 -287.800319) (xy 169.88028 -287.824926) (xy 170.219128 -287.824926) (xy 170.223088 -287.775872)
			(xy 170.234865 -287.728088) (xy 170.254156 -287.682812) (xy 170.280459 -287.641216) (xy 170.313094 -287.604379)
			(xy 170.351215 -287.573254) (xy 170.393836 -287.548647) (xy 170.439852 -287.531195) (xy 170.488071 -287.521351)
			(xy 170.537246 -287.51937) (xy 170.586101 -287.525302) (xy 170.633372 -287.538994) (xy 170.677834 -287.560092)
			(xy 170.718337 -287.588048) (xy 170.75383 -287.62214) (xy 170.783395 -287.661484) (xy 170.806266 -287.705061)
			(xy 170.82185 -287.751742) (xy 170.829745 -287.800319) (xy 170.83024 -287.824926) (xy 171.169088 -287.824926)
			(xy 171.173048 -287.775872) (xy 171.184825 -287.728088) (xy 171.204116 -287.682812) (xy 171.230419 -287.641216)
			(xy 171.263054 -287.604379) (xy 171.301175 -287.573254) (xy 171.343796 -287.548647) (xy 171.389812 -287.531195)
			(xy 171.438031 -287.521351) (xy 171.487206 -287.51937) (xy 171.536061 -287.525302) (xy 171.583332 -287.538994)
			(xy 171.627794 -287.560092) (xy 171.668297 -287.588048) (xy 171.70379 -287.62214) (xy 171.733355 -287.661484)
			(xy 171.756226 -287.705061) (xy 171.77181 -287.751742) (xy 171.779705 -287.800319) (xy 171.7802 -287.824926)
			(xy 172.119048 -287.824926) (xy 172.123008 -287.775872) (xy 172.134785 -287.728088) (xy 172.154076 -287.682812)
			(xy 172.180379 -287.641216) (xy 172.213014 -287.604379) (xy 172.251135 -287.573254) (xy 172.293756 -287.548647)
			(xy 172.339772 -287.531195) (xy 172.387991 -287.521351) (xy 172.437166 -287.51937) (xy 172.486021 -287.525302)
			(xy 172.533292 -287.538994) (xy 172.577754 -287.560092) (xy 172.618257 -287.588048) (xy 172.65375 -287.62214)
			(xy 172.683315 -287.661484) (xy 172.706186 -287.705061) (xy 172.72177 -287.751742) (xy 172.729665 -287.800319)
			(xy 172.73016 -287.824926) (xy 173.069262 -287.824926) (xy 173.073222 -287.775872) (xy 173.084999 -287.728088)
			(xy 173.10429 -287.682812) (xy 173.130593 -287.641216) (xy 173.163228 -287.604379) (xy 173.201349 -287.573254)
			(xy 173.24397 -287.548647) (xy 173.289986 -287.531195) (xy 173.338205 -287.521351) (xy 173.38738 -287.51937)
			(xy 173.436235 -287.525302) (xy 173.483506 -287.538994) (xy 173.527968 -287.560092) (xy 173.568471 -287.588048)
			(xy 173.603964 -287.62214) (xy 173.633529 -287.661484) (xy 173.653722 -287.699958) (xy 174.044114 -287.699958)
			(xy 174.048074 -287.650904) (xy 174.059851 -287.60312) (xy 174.079142 -287.557844) (xy 174.105445 -287.516248)
			(xy 174.13808 -287.479411) (xy 174.176201 -287.448286) (xy 174.218822 -287.423679) (xy 174.264838 -287.406227)
			(xy 174.313057 -287.396383) (xy 174.362232 -287.394402) (xy 174.411087 -287.400334) (xy 174.458358 -287.414026)
			(xy 174.50282 -287.435124) (xy 174.543323 -287.46308) (xy 174.578816 -287.497172) (xy 174.608381 -287.536516)
			(xy 174.631252 -287.580093) (xy 174.646836 -287.626774) (xy 174.654731 -287.675351) (xy 174.655226 -287.699958)
			(xy 174.654731 -287.724565) (xy 174.646836 -287.773142) (xy 174.631252 -287.819823) (xy 174.608381 -287.8634)
			(xy 174.580986 -287.899856) (xy 175.919142 -287.899856) (xy 175.923102 -287.850802) (xy 175.934879 -287.803018)
			(xy 175.95417 -287.757742) (xy 175.980473 -287.716146) (xy 176.013108 -287.679309) (xy 176.051229 -287.648184)
			(xy 176.09385 -287.623577) (xy 176.139866 -287.606125) (xy 176.188085 -287.596281) (xy 176.23726 -287.5943)
			(xy 176.286115 -287.600232) (xy 176.333386 -287.613924) (xy 176.377848 -287.635022) (xy 176.418351 -287.662978)
			(xy 176.453844 -287.69707) (xy 176.483409 -287.736414) (xy 176.50628 -287.779991) (xy 176.521281 -287.824926)
			(xy 176.869102 -287.824926) (xy 176.873062 -287.775872) (xy 176.884839 -287.728088) (xy 176.90413 -287.682812)
			(xy 176.930433 -287.641216) (xy 176.963068 -287.604379) (xy 177.001189 -287.573254) (xy 177.04381 -287.548647)
			(xy 177.089826 -287.531195) (xy 177.138045 -287.521351) (xy 177.18722 -287.51937) (xy 177.236075 -287.525302)
			(xy 177.283346 -287.538994) (xy 177.327808 -287.560092) (xy 177.368311 -287.588048) (xy 177.403804 -287.62214)
			(xy 177.433369 -287.661484) (xy 177.45624 -287.705061) (xy 177.471824 -287.751742) (xy 177.479719 -287.800319)
			(xy 177.480214 -287.824926) (xy 177.819062 -287.824926) (xy 177.823022 -287.775872) (xy 177.834799 -287.728088)
			(xy 177.85409 -287.682812) (xy 177.880393 -287.641216) (xy 177.913028 -287.604379) (xy 177.951149 -287.573254)
			(xy 177.99377 -287.548647) (xy 178.039786 -287.531195) (xy 178.088005 -287.521351) (xy 178.13718 -287.51937)
			(xy 178.186035 -287.525302) (xy 178.233306 -287.538994) (xy 178.277768 -287.560092) (xy 178.318271 -287.588048)
			(xy 178.353764 -287.62214) (xy 178.383329 -287.661484) (xy 178.4062 -287.705061) (xy 178.421784 -287.751742)
			(xy 178.429679 -287.800319) (xy 178.430174 -287.824926) (xy 178.769276 -287.824926) (xy 178.773236 -287.775872)
			(xy 178.785013 -287.728088) (xy 178.804304 -287.682812) (xy 178.830607 -287.641216) (xy 178.863242 -287.604379)
			(xy 178.901363 -287.573254) (xy 178.943984 -287.548647) (xy 178.99 -287.531195) (xy 179.038219 -287.521351)
			(xy 179.087394 -287.51937) (xy 179.136249 -287.525302) (xy 179.18352 -287.538994) (xy 179.227982 -287.560092)
			(xy 179.268485 -287.588048) (xy 179.303978 -287.62214) (xy 179.333543 -287.661484) (xy 179.356414 -287.705061)
			(xy 179.371998 -287.751742) (xy 179.379893 -287.800319) (xy 179.380388 -287.824926) (xy 179.719236 -287.824926)
			(xy 179.723196 -287.775872) (xy 179.734973 -287.728088) (xy 179.754264 -287.682812) (xy 179.780567 -287.641216)
			(xy 179.813202 -287.604379) (xy 179.851323 -287.573254) (xy 179.893944 -287.548647) (xy 179.93996 -287.531195)
			(xy 179.988179 -287.521351) (xy 180.037354 -287.51937) (xy 180.086209 -287.525302) (xy 180.13348 -287.538994)
			(xy 180.177942 -287.560092) (xy 180.218445 -287.588048) (xy 180.253938 -287.62214) (xy 180.283503 -287.661484)
			(xy 180.306374 -287.705061) (xy 180.321958 -287.751742) (xy 180.329853 -287.800319) (xy 180.330348 -287.824926)
			(xy 180.669196 -287.824926) (xy 180.673156 -287.775872) (xy 180.684933 -287.728088) (xy 180.704224 -287.682812)
			(xy 180.730527 -287.641216) (xy 180.763162 -287.604379) (xy 180.801283 -287.573254) (xy 180.843904 -287.548647)
			(xy 180.88992 -287.531195) (xy 180.938139 -287.521351) (xy 180.987314 -287.51937) (xy 181.036169 -287.525302)
			(xy 181.08344 -287.538994) (xy 181.127902 -287.560092) (xy 181.168405 -287.588048) (xy 181.203898 -287.62214)
			(xy 181.233463 -287.661484) (xy 181.256334 -287.705061) (xy 181.271918 -287.751742) (xy 181.279813 -287.800319)
			(xy 181.280308 -287.824926) (xy 181.619156 -287.824926) (xy 181.623116 -287.775872) (xy 181.634893 -287.728088)
			(xy 181.654184 -287.682812) (xy 181.680487 -287.641216) (xy 181.713122 -287.604379) (xy 181.751243 -287.573254)
			(xy 181.793864 -287.548647) (xy 181.83988 -287.531195) (xy 181.888099 -287.521351) (xy 181.937274 -287.51937)
			(xy 181.986129 -287.525302) (xy 182.0334 -287.538994) (xy 182.077862 -287.560092) (xy 182.118365 -287.588048)
			(xy 182.153858 -287.62214) (xy 182.183423 -287.661484) (xy 182.206294 -287.705061) (xy 182.221878 -287.751742)
			(xy 182.229773 -287.800319) (xy 182.230268 -287.824926) (xy 182.569116 -287.824926) (xy 182.573076 -287.775872)
			(xy 182.584853 -287.728088) (xy 182.604144 -287.682812) (xy 182.630447 -287.641216) (xy 182.663082 -287.604379)
			(xy 182.701203 -287.573254) (xy 182.743824 -287.548647) (xy 182.78984 -287.531195) (xy 182.838059 -287.521351)
			(xy 182.887234 -287.51937) (xy 182.936089 -287.525302) (xy 182.98336 -287.538994) (xy 183.027822 -287.560092)
			(xy 183.068325 -287.588048) (xy 183.103818 -287.62214) (xy 183.133383 -287.661484) (xy 183.156254 -287.705061)
			(xy 183.171838 -287.751742) (xy 183.179733 -287.800319) (xy 183.180228 -287.824926) (xy 183.519076 -287.824926)
			(xy 183.523036 -287.775872) (xy 183.534813 -287.728088) (xy 183.554104 -287.682812) (xy 183.580407 -287.641216)
			(xy 183.613042 -287.604379) (xy 183.651163 -287.573254) (xy 183.693784 -287.548647) (xy 183.7398 -287.531195)
			(xy 183.788019 -287.521351) (xy 183.837194 -287.51937) (xy 183.886049 -287.525302) (xy 183.93332 -287.538994)
			(xy 183.977782 -287.560092) (xy 184.018285 -287.588048) (xy 184.053778 -287.62214) (xy 184.083343 -287.661484)
			(xy 184.106214 -287.705061) (xy 184.121798 -287.751742) (xy 184.129693 -287.800319) (xy 184.130188 -287.824926)
			(xy 184.469036 -287.824926) (xy 184.472996 -287.775872) (xy 184.484773 -287.728088) (xy 184.504064 -287.682812)
			(xy 184.530367 -287.641216) (xy 184.563002 -287.604379) (xy 184.601123 -287.573254) (xy 184.643744 -287.548647)
			(xy 184.68976 -287.531195) (xy 184.737979 -287.521351) (xy 184.787154 -287.51937) (xy 184.836009 -287.525302)
			(xy 184.88328 -287.538994) (xy 184.927742 -287.560092) (xy 184.968245 -287.588048) (xy 185.003738 -287.62214)
			(xy 185.033303 -287.661484) (xy 185.056174 -287.705061) (xy 185.071758 -287.751742) (xy 185.079653 -287.800319)
			(xy 185.080148 -287.824926) (xy 186.36921 -287.824926) (xy 186.37317 -287.775872) (xy 186.384947 -287.728088)
			(xy 186.404238 -287.682812) (xy 186.430541 -287.641216) (xy 186.463176 -287.604379) (xy 186.501297 -287.573254)
			(xy 186.543918 -287.548647) (xy 186.589934 -287.531195) (xy 186.638153 -287.521351) (xy 186.687328 -287.51937)
			(xy 186.736183 -287.525302) (xy 186.783454 -287.538994) (xy 186.827916 -287.560092) (xy 186.868419 -287.588048)
			(xy 186.903912 -287.62214) (xy 186.933477 -287.661484) (xy 186.956348 -287.705061) (xy 186.971932 -287.751742)
			(xy 186.979827 -287.800319) (xy 186.980322 -287.824926) (xy 186.979827 -287.849533) (xy 186.971932 -287.89811)
			(xy 186.956348 -287.944791) (xy 186.933477 -287.988368) (xy 186.903912 -288.027712) (xy 186.868419 -288.061804)
			(xy 186.827916 -288.08976) (xy 186.783454 -288.110858) (xy 186.736183 -288.12455) (xy 186.687328 -288.130482)
			(xy 186.638153 -288.128501) (xy 186.589934 -288.118657) (xy 186.543918 -288.101205) (xy 186.501297 -288.076598)
			(xy 186.463176 -288.045473) (xy 186.430541 -288.008636) (xy 186.404238 -287.96704) (xy 186.384947 -287.921764)
			(xy 186.37317 -287.87398) (xy 186.36921 -287.824926) (xy 185.080148 -287.824926) (xy 185.079653 -287.849533)
			(xy 185.071758 -287.89811) (xy 185.056174 -287.944791) (xy 185.033303 -287.988368) (xy 185.003738 -288.027712)
			(xy 184.968245 -288.061804) (xy 184.927742 -288.08976) (xy 184.88328 -288.110858) (xy 184.836009 -288.12455)
			(xy 184.787154 -288.130482) (xy 184.737979 -288.128501) (xy 184.68976 -288.118657) (xy 184.643744 -288.101205)
			(xy 184.601123 -288.076598) (xy 184.563002 -288.045473) (xy 184.530367 -288.008636) (xy 184.504064 -287.96704)
			(xy 184.484773 -287.921764) (xy 184.472996 -287.87398) (xy 184.469036 -287.824926) (xy 184.130188 -287.824926)
			(xy 184.129693 -287.849533) (xy 184.121798 -287.89811) (xy 184.106214 -287.944791) (xy 184.083343 -287.988368)
			(xy 184.053778 -288.027712) (xy 184.018285 -288.061804) (xy 183.977782 -288.08976) (xy 183.93332 -288.110858)
			(xy 183.886049 -288.12455) (xy 183.837194 -288.130482) (xy 183.788019 -288.128501) (xy 183.7398 -288.118657)
			(xy 183.693784 -288.101205) (xy 183.651163 -288.076598) (xy 183.613042 -288.045473) (xy 183.580407 -288.008636)
			(xy 183.554104 -287.96704) (xy 183.534813 -287.921764) (xy 183.523036 -287.87398) (xy 183.519076 -287.824926)
			(xy 183.180228 -287.824926) (xy 183.179733 -287.849533) (xy 183.171838 -287.89811) (xy 183.156254 -287.944791)
			(xy 183.133383 -287.988368) (xy 183.103818 -288.027712) (xy 183.068325 -288.061804) (xy 183.027822 -288.08976)
			(xy 182.98336 -288.110858) (xy 182.936089 -288.12455) (xy 182.887234 -288.130482) (xy 182.838059 -288.128501)
			(xy 182.78984 -288.118657) (xy 182.743824 -288.101205) (xy 182.701203 -288.076598) (xy 182.663082 -288.045473)
			(xy 182.630447 -288.008636) (xy 182.604144 -287.96704) (xy 182.584853 -287.921764) (xy 182.573076 -287.87398)
			(xy 182.569116 -287.824926) (xy 182.230268 -287.824926) (xy 182.229773 -287.849533) (xy 182.221878 -287.89811)
			(xy 182.206294 -287.944791) (xy 182.183423 -287.988368) (xy 182.153858 -288.027712) (xy 182.118365 -288.061804)
			(xy 182.077862 -288.08976) (xy 182.0334 -288.110858) (xy 181.986129 -288.12455) (xy 181.937274 -288.130482)
			(xy 181.888099 -288.128501) (xy 181.83988 -288.118657) (xy 181.793864 -288.101205) (xy 181.751243 -288.076598)
			(xy 181.713122 -288.045473) (xy 181.680487 -288.008636) (xy 181.654184 -287.96704) (xy 181.634893 -287.921764)
			(xy 181.623116 -287.87398) (xy 181.619156 -287.824926) (xy 181.280308 -287.824926) (xy 181.279813 -287.849533)
			(xy 181.271918 -287.89811) (xy 181.256334 -287.944791) (xy 181.233463 -287.988368) (xy 181.203898 -288.027712)
			(xy 181.168405 -288.061804) (xy 181.127902 -288.08976) (xy 181.08344 -288.110858) (xy 181.036169 -288.12455)
			(xy 180.987314 -288.130482) (xy 180.938139 -288.128501) (xy 180.88992 -288.118657) (xy 180.843904 -288.101205)
			(xy 180.801283 -288.076598) (xy 180.763162 -288.045473) (xy 180.730527 -288.008636) (xy 180.704224 -287.96704)
			(xy 180.684933 -287.921764) (xy 180.673156 -287.87398) (xy 180.669196 -287.824926) (xy 180.330348 -287.824926)
			(xy 180.329853 -287.849533) (xy 180.321958 -287.89811) (xy 180.306374 -287.944791) (xy 180.283503 -287.988368)
			(xy 180.253938 -288.027712) (xy 180.218445 -288.061804) (xy 180.177942 -288.08976) (xy 180.13348 -288.110858)
			(xy 180.086209 -288.12455) (xy 180.037354 -288.130482) (xy 179.988179 -288.128501) (xy 179.93996 -288.118657)
			(xy 179.893944 -288.101205) (xy 179.851323 -288.076598) (xy 179.813202 -288.045473) (xy 179.780567 -288.008636)
			(xy 179.754264 -287.96704) (xy 179.734973 -287.921764) (xy 179.723196 -287.87398) (xy 179.719236 -287.824926)
			(xy 179.380388 -287.824926) (xy 179.379893 -287.849533) (xy 179.371998 -287.89811) (xy 179.356414 -287.944791)
			(xy 179.333543 -287.988368) (xy 179.303978 -288.027712) (xy 179.268485 -288.061804) (xy 179.227982 -288.08976)
			(xy 179.18352 -288.110858) (xy 179.136249 -288.12455) (xy 179.087394 -288.130482) (xy 179.038219 -288.128501)
			(xy 178.99 -288.118657) (xy 178.943984 -288.101205) (xy 178.901363 -288.076598) (xy 178.863242 -288.045473)
			(xy 178.830607 -288.008636) (xy 178.804304 -287.96704) (xy 178.785013 -287.921764) (xy 178.773236 -287.87398)
			(xy 178.769276 -287.824926) (xy 178.430174 -287.824926) (xy 178.429679 -287.849533) (xy 178.421784 -287.89811)
			(xy 178.4062 -287.944791) (xy 178.383329 -287.988368) (xy 178.353764 -288.027712) (xy 178.318271 -288.061804)
			(xy 178.277768 -288.08976) (xy 178.233306 -288.110858) (xy 178.186035 -288.12455) (xy 178.13718 -288.130482)
			(xy 178.088005 -288.128501) (xy 178.039786 -288.118657) (xy 177.99377 -288.101205) (xy 177.951149 -288.076598)
			(xy 177.913028 -288.045473) (xy 177.880393 -288.008636) (xy 177.85409 -287.96704) (xy 177.834799 -287.921764)
			(xy 177.823022 -287.87398) (xy 177.819062 -287.824926) (xy 177.480214 -287.824926) (xy 177.479719 -287.849533)
			(xy 177.471824 -287.89811) (xy 177.45624 -287.944791) (xy 177.433369 -287.988368) (xy 177.403804 -288.027712)
			(xy 177.368311 -288.061804) (xy 177.327808 -288.08976) (xy 177.283346 -288.110858) (xy 177.236075 -288.12455)
			(xy 177.18722 -288.130482) (xy 177.138045 -288.128501) (xy 177.089826 -288.118657) (xy 177.04381 -288.101205)
			(xy 177.001189 -288.076598) (xy 176.963068 -288.045473) (xy 176.930433 -288.008636) (xy 176.90413 -287.96704)
			(xy 176.884839 -287.921764) (xy 176.873062 -287.87398) (xy 176.869102 -287.824926) (xy 176.521281 -287.824926)
			(xy 176.521864 -287.826672) (xy 176.529759 -287.875249) (xy 176.530254 -287.899856) (xy 176.529759 -287.924463)
			(xy 176.521864 -287.97304) (xy 176.50628 -288.019721) (xy 176.483409 -288.063298) (xy 176.453844 -288.102642)
			(xy 176.418351 -288.136734) (xy 176.377848 -288.16469) (xy 176.333386 -288.185788) (xy 176.286115 -288.19948)
			(xy 176.23726 -288.205412) (xy 176.188085 -288.203431) (xy 176.139866 -288.193587) (xy 176.09385 -288.176135)
			(xy 176.051229 -288.151528) (xy 176.013108 -288.120403) (xy 175.980473 -288.083566) (xy 175.95417 -288.04197)
			(xy 175.934879 -287.996694) (xy 175.923102 -287.94891) (xy 175.919142 -287.899856) (xy 174.580986 -287.899856)
			(xy 174.578816 -287.902744) (xy 174.543323 -287.936836) (xy 174.50282 -287.964792) (xy 174.458358 -287.98589)
			(xy 174.411087 -287.999582) (xy 174.362232 -288.005514) (xy 174.313057 -288.003533) (xy 174.264838 -287.993689)
			(xy 174.218822 -287.976237) (xy 174.176201 -287.95163) (xy 174.13808 -287.920505) (xy 174.105445 -287.883668)
			(xy 174.079142 -287.842072) (xy 174.059851 -287.796796) (xy 174.048074 -287.749012) (xy 174.044114 -287.699958)
			(xy 173.653722 -287.699958) (xy 173.6564 -287.705061) (xy 173.671984 -287.751742) (xy 173.679879 -287.800319)
			(xy 173.680374 -287.824926) (xy 173.679879 -287.849533) (xy 173.671984 -287.89811) (xy 173.6564 -287.944791)
			(xy 173.633529 -287.988368) (xy 173.603964 -288.027712) (xy 173.568471 -288.061804) (xy 173.527968 -288.08976)
			(xy 173.483506 -288.110858) (xy 173.436235 -288.12455) (xy 173.38738 -288.130482) (xy 173.338205 -288.128501)
			(xy 173.289986 -288.118657) (xy 173.24397 -288.101205) (xy 173.201349 -288.076598) (xy 173.163228 -288.045473)
			(xy 173.130593 -288.008636) (xy 173.10429 -287.96704) (xy 173.084999 -287.921764) (xy 173.073222 -287.87398)
			(xy 173.069262 -287.824926) (xy 172.73016 -287.824926) (xy 172.729665 -287.849533) (xy 172.72177 -287.89811)
			(xy 172.706186 -287.944791) (xy 172.683315 -287.988368) (xy 172.65375 -288.027712) (xy 172.618257 -288.061804)
			(xy 172.577754 -288.08976) (xy 172.533292 -288.110858) (xy 172.486021 -288.12455) (xy 172.437166 -288.130482)
			(xy 172.387991 -288.128501) (xy 172.339772 -288.118657) (xy 172.293756 -288.101205) (xy 172.251135 -288.076598)
			(xy 172.213014 -288.045473) (xy 172.180379 -288.008636) (xy 172.154076 -287.96704) (xy 172.134785 -287.921764)
			(xy 172.123008 -287.87398) (xy 172.119048 -287.824926) (xy 171.7802 -287.824926) (xy 171.779705 -287.849533)
			(xy 171.77181 -287.89811) (xy 171.756226 -287.944791) (xy 171.733355 -287.988368) (xy 171.70379 -288.027712)
			(xy 171.668297 -288.061804) (xy 171.627794 -288.08976) (xy 171.583332 -288.110858) (xy 171.536061 -288.12455)
			(xy 171.487206 -288.130482) (xy 171.438031 -288.128501) (xy 171.389812 -288.118657) (xy 171.343796 -288.101205)
			(xy 171.301175 -288.076598) (xy 171.263054 -288.045473) (xy 171.230419 -288.008636) (xy 171.204116 -287.96704)
			(xy 171.184825 -287.921764) (xy 171.173048 -287.87398) (xy 171.169088 -287.824926) (xy 170.83024 -287.824926)
			(xy 170.829745 -287.849533) (xy 170.82185 -287.89811) (xy 170.806266 -287.944791) (xy 170.783395 -287.988368)
			(xy 170.75383 -288.027712) (xy 170.718337 -288.061804) (xy 170.677834 -288.08976) (xy 170.633372 -288.110858)
			(xy 170.586101 -288.12455) (xy 170.537246 -288.130482) (xy 170.488071 -288.128501) (xy 170.439852 -288.118657)
			(xy 170.393836 -288.101205) (xy 170.351215 -288.076598) (xy 170.313094 -288.045473) (xy 170.280459 -288.008636)
			(xy 170.254156 -287.96704) (xy 170.234865 -287.921764) (xy 170.223088 -287.87398) (xy 170.219128 -287.824926)
			(xy 169.88028 -287.824926) (xy 169.879785 -287.849533) (xy 169.87189 -287.89811) (xy 169.856306 -287.944791)
			(xy 169.833435 -287.988368) (xy 169.80387 -288.027712) (xy 169.768377 -288.061804) (xy 169.727874 -288.08976)
			(xy 169.683412 -288.110858) (xy 169.636141 -288.12455) (xy 169.587286 -288.130482) (xy 169.538111 -288.128501)
			(xy 169.489892 -288.118657) (xy 169.443876 -288.101205) (xy 169.401255 -288.076598) (xy 169.363134 -288.045473)
			(xy 169.330499 -288.008636) (xy 169.304196 -287.96704) (xy 169.284905 -287.921764) (xy 169.273128 -287.87398)
			(xy 169.269168 -287.824926) (xy 168.93032 -287.824926) (xy 168.929825 -287.849533) (xy 168.92193 -287.89811)
			(xy 168.906346 -287.944791) (xy 168.883475 -287.988368) (xy 168.85391 -288.027712) (xy 168.818417 -288.061804)
			(xy 168.777914 -288.08976) (xy 168.733452 -288.110858) (xy 168.686181 -288.12455) (xy 168.637326 -288.130482)
			(xy 168.588151 -288.128501) (xy 168.539932 -288.118657) (xy 168.493916 -288.101205) (xy 168.451295 -288.076598)
			(xy 168.413174 -288.045473) (xy 168.380539 -288.008636) (xy 168.354236 -287.96704) (xy 168.334945 -287.921764)
			(xy 168.323168 -287.87398) (xy 168.319208 -287.824926) (xy 167.98036 -287.824926) (xy 167.979865 -287.849533)
			(xy 167.97197 -287.89811) (xy 167.956386 -287.944791) (xy 167.933515 -287.988368) (xy 167.90395 -288.027712)
			(xy 167.868457 -288.061804) (xy 167.827954 -288.08976) (xy 167.783492 -288.110858) (xy 167.736221 -288.12455)
			(xy 167.687366 -288.130482) (xy 167.638191 -288.128501) (xy 167.589972 -288.118657) (xy 167.543956 -288.101205)
			(xy 167.501335 -288.076598) (xy 167.463214 -288.045473) (xy 167.430579 -288.008636) (xy 167.404276 -287.96704)
			(xy 167.384985 -287.921764) (xy 167.373208 -287.87398) (xy 167.369248 -287.824926) (xy 167.0304 -287.824926)
			(xy 167.029905 -287.849533) (xy 167.02201 -287.89811) (xy 167.006426 -287.944791) (xy 166.983555 -287.988368)
			(xy 166.95399 -288.027712) (xy 166.918497 -288.061804) (xy 166.877994 -288.08976) (xy 166.833532 -288.110858)
			(xy 166.786261 -288.12455) (xy 166.737406 -288.130482) (xy 166.688231 -288.128501) (xy 166.640012 -288.118657)
			(xy 166.593996 -288.101205) (xy 166.551375 -288.076598) (xy 166.513254 -288.045473) (xy 166.480619 -288.008636)
			(xy 166.454316 -287.96704) (xy 166.435025 -287.921764) (xy 166.423248 -287.87398) (xy 166.419288 -287.824926)
			(xy 166.080186 -287.824926) (xy 166.079691 -287.849533) (xy 166.071796 -287.89811) (xy 166.056212 -287.944791)
			(xy 166.033341 -287.988368) (xy 166.003776 -288.027712) (xy 165.968283 -288.061804) (xy 165.92778 -288.08976)
			(xy 165.883318 -288.110858) (xy 165.836047 -288.12455) (xy 165.787192 -288.130482) (xy 165.738017 -288.128501)
			(xy 165.689798 -288.118657) (xy 165.643782 -288.101205) (xy 165.601161 -288.076598) (xy 165.56304 -288.045473)
			(xy 165.530405 -288.008636) (xy 165.504102 -287.96704) (xy 165.484811 -287.921764) (xy 165.473034 -287.87398)
			(xy 165.469074 -287.824926) (xy 165.155058 -287.824926) (xy 165.155058 -287.851283) (xy 165.14668 -287.903373)
			(xy 165.130137 -287.953471) (xy 165.105849 -288.000307) (xy 165.074433 -288.042693) (xy 165.036685 -288.079552)
			(xy 164.993563 -288.109949) (xy 164.946161 -288.133114) (xy 164.895683 -288.148458) (xy 164.869622 -288.152586)
			(xy 164.86505 -288.153348) (xy 164.854636 -288.15665) (xy 164.850318 -288.15792) (xy 164.826696 -288.168842)
			(xy 164.819838 -288.175954) (xy 164.804852 -288.191702) (xy 164.800264 -288.196807) (xy 164.793819 -288.20892)
			(xy 164.792152 -288.215578) (xy 164.790882 -288.2265) (xy 164.790882 -288.299906) (xy 189.69407 -288.299906)
			(xy 189.69803 -288.250852) (xy 189.709807 -288.203068) (xy 189.729098 -288.157792) (xy 189.755401 -288.116196)
			(xy 189.788036 -288.079359) (xy 189.826157 -288.048234) (xy 189.868778 -288.023627) (xy 189.914794 -288.006175)
			(xy 189.963013 -287.996331) (xy 190.012188 -287.99435) (xy 190.061043 -288.000282) (xy 190.108314 -288.013974)
			(xy 190.152776 -288.035072) (xy 190.193279 -288.063028) (xy 190.228772 -288.09712) (xy 190.258337 -288.136464)
			(xy 190.281208 -288.180041) (xy 190.296792 -288.226722) (xy 190.304687 -288.275299) (xy 190.305182 -288.299906)
			(xy 190.644284 -288.299906) (xy 190.648244 -288.250852) (xy 190.660021 -288.203068) (xy 190.679312 -288.157792)
			(xy 190.705615 -288.116196) (xy 190.73825 -288.079359) (xy 190.776371 -288.048234) (xy 190.818992 -288.023627)
			(xy 190.865008 -288.006175) (xy 190.913227 -287.996331) (xy 190.962402 -287.99435) (xy 191.011257 -288.000282)
			(xy 191.058528 -288.013974) (xy 191.10299 -288.035072) (xy 191.143493 -288.063028) (xy 191.178986 -288.09712)
			(xy 191.208551 -288.136464) (xy 191.231422 -288.180041) (xy 191.247006 -288.226722) (xy 191.254901 -288.275299)
			(xy 191.255396 -288.299906) (xy 191.594244 -288.299906) (xy 191.598204 -288.250852) (xy 191.609981 -288.203068)
			(xy 191.629272 -288.157792) (xy 191.655575 -288.116196) (xy 191.68821 -288.079359) (xy 191.726331 -288.048234)
			(xy 191.768952 -288.023627) (xy 191.814968 -288.006175) (xy 191.863187 -287.996331) (xy 191.912362 -287.99435)
			(xy 191.961217 -288.000282) (xy 192.008488 -288.013974) (xy 192.05295 -288.035072) (xy 192.093453 -288.063028)
			(xy 192.128946 -288.09712) (xy 192.158511 -288.136464) (xy 192.181382 -288.180041) (xy 192.196966 -288.226722)
			(xy 192.204861 -288.275299) (xy 192.205356 -288.299906) (xy 192.204861 -288.324513) (xy 192.204682 -288.325614)
			(xy 192.52336 -288.325614) (xy 192.52336 -288.274198) (xy 192.531403 -288.223416) (xy 192.547291 -288.174517)
			(xy 192.570634 -288.128705) (xy 192.600855 -288.087109) (xy 192.637211 -288.050753) (xy 192.678807 -288.020532)
			(xy 192.724619 -287.997189) (xy 192.773518 -287.981301) (xy 192.8243 -287.973258) (xy 192.875716 -287.973258)
			(xy 192.926498 -287.981301) (xy 192.975397 -287.997189) (xy 193.021209 -288.020532) (xy 193.062805 -288.050753)
			(xy 193.099161 -288.087109) (xy 193.129382 -288.128705) (xy 193.152725 -288.174517) (xy 193.168613 -288.223416)
			(xy 193.176656 -288.274198) (xy 193.17716 -288.299906) (xy 193.176656 -288.325614) (xy 193.47332 -288.325614)
			(xy 193.47332 -288.274198) (xy 193.481363 -288.223416) (xy 193.497251 -288.174517) (xy 193.520594 -288.128705)
			(xy 193.550815 -288.087109) (xy 193.587171 -288.050753) (xy 193.628767 -288.020532) (xy 193.674579 -287.997189)
			(xy 193.723478 -287.981301) (xy 193.77426 -287.973258) (xy 193.825676 -287.973258) (xy 193.876458 -287.981301)
			(xy 193.925357 -287.997189) (xy 193.971169 -288.020532) (xy 194.012765 -288.050753) (xy 194.049121 -288.087109)
			(xy 194.079342 -288.128705) (xy 194.102685 -288.174517) (xy 194.118573 -288.223416) (xy 194.126616 -288.274198)
			(xy 194.12712 -288.299906) (xy 194.444124 -288.299906) (xy 194.448084 -288.250852) (xy 194.459861 -288.203068)
			(xy 194.479152 -288.157792) (xy 194.505455 -288.116196) (xy 194.53809 -288.079359) (xy 194.576211 -288.048234)
			(xy 194.618832 -288.023627) (xy 194.664848 -288.006175) (xy 194.713067 -287.996331) (xy 194.762242 -287.99435)
			(xy 194.811097 -288.000282) (xy 194.858368 -288.013974) (xy 194.90283 -288.035072) (xy 194.943333 -288.063028)
			(xy 194.978826 -288.09712) (xy 195.008391 -288.136464) (xy 195.031262 -288.180041) (xy 195.046846 -288.226722)
			(xy 195.054741 -288.275299) (xy 195.055236 -288.299906) (xy 195.054741 -288.324513) (xy 195.054562 -288.325614)
			(xy 195.37324 -288.325614) (xy 195.37324 -288.274198) (xy 195.381283 -288.223416) (xy 195.397171 -288.174517)
			(xy 195.420514 -288.128705) (xy 195.450735 -288.087109) (xy 195.487091 -288.050753) (xy 195.528687 -288.020532)
			(xy 195.574499 -287.997189) (xy 195.623398 -287.981301) (xy 195.67418 -287.973258) (xy 195.725596 -287.973258)
			(xy 195.776378 -287.981301) (xy 195.825277 -287.997189) (xy 195.871089 -288.020532) (xy 195.912685 -288.050753)
			(xy 195.949041 -288.087109) (xy 195.979262 -288.128705) (xy 196.002605 -288.174517) (xy 196.018493 -288.223416)
			(xy 196.026536 -288.274198) (xy 196.02704 -288.299906) (xy 196.026536 -288.325614) (xy 196.3232 -288.325614)
			(xy 196.3232 -288.274198) (xy 196.331243 -288.223416) (xy 196.347131 -288.174517) (xy 196.370474 -288.128705)
			(xy 196.400695 -288.087109) (xy 196.437051 -288.050753) (xy 196.478647 -288.020532) (xy 196.524459 -287.997189)
			(xy 196.573358 -287.981301) (xy 196.62414 -287.973258) (xy 196.675556 -287.973258) (xy 196.726338 -287.981301)
			(xy 196.775237 -287.997189) (xy 196.821049 -288.020532) (xy 196.862645 -288.050753) (xy 196.899001 -288.087109)
			(xy 196.929222 -288.128705) (xy 196.952565 -288.174517) (xy 196.968453 -288.223416) (xy 196.976496 -288.274198)
			(xy 196.977 -288.299906) (xy 197.294258 -288.299906) (xy 197.298218 -288.250852) (xy 197.309995 -288.203068)
			(xy 197.329286 -288.157792) (xy 197.355589 -288.116196) (xy 197.388224 -288.079359) (xy 197.426345 -288.048234)
			(xy 197.468966 -288.023627) (xy 197.514982 -288.006175) (xy 197.563201 -287.996331) (xy 197.612376 -287.99435)
			(xy 197.661231 -288.000282) (xy 197.708502 -288.013974) (xy 197.752964 -288.035072) (xy 197.793467 -288.063028)
			(xy 197.82896 -288.09712) (xy 197.858525 -288.136464) (xy 197.881396 -288.180041) (xy 197.89698 -288.226722)
			(xy 197.904875 -288.275299) (xy 197.90537 -288.299906) (xy 198.244218 -288.299906) (xy 198.248178 -288.250852)
			(xy 198.259955 -288.203068) (xy 198.279246 -288.157792) (xy 198.305549 -288.116196) (xy 198.338184 -288.079359)
			(xy 198.376305 -288.048234) (xy 198.418926 -288.023627) (xy 198.464942 -288.006175) (xy 198.513161 -287.996331)
			(xy 198.562336 -287.99435) (xy 198.611191 -288.000282) (xy 198.658462 -288.013974) (xy 198.702924 -288.035072)
			(xy 198.743427 -288.063028) (xy 198.77892 -288.09712) (xy 198.808485 -288.136464) (xy 198.831356 -288.180041)
			(xy 198.84694 -288.226722) (xy 198.850472 -288.248452) (xy 203.696044 -288.248452) (xy 203.696044 -288.193948)
			(xy 203.7038 -288.139999) (xy 203.719155 -288.087702) (xy 203.741795 -288.038123) (xy 203.77126 -287.992271)
			(xy 203.806951 -287.951078) (xy 203.84814 -287.915383) (xy 203.89399 -287.885913) (xy 203.943567 -287.863268)
			(xy 203.995862 -287.847908) (xy 204.04981 -287.840146) (xy 204.077062 -287.839658) (xy 204.103177 -287.840144)
			(xy 204.154919 -287.847276) (xy 204.205204 -287.861399) (xy 204.253093 -287.882248) (xy 204.297691 -287.909434)
			(xy 204.338165 -287.942449) (xy 204.373757 -287.980675) (xy 204.403803 -288.023399) (xy 204.416152 -288.046414)
			(xy 204.422756 -288.059368) (xy 204.446886 -288.0741) (xy 204.566266 -288.0741) (xy 204.590396 -288.059368)
			(xy 204.597 -288.046414) (xy 204.609391 -288.023419) (xy 204.639416 -287.980676) (xy 204.674993 -287.942432)
			(xy 204.715458 -287.909401) (xy 204.760052 -287.882202) (xy 204.807941 -287.861344) (xy 204.858228 -287.847218)
			(xy 204.909973 -287.840087) (xy 204.93609 -287.839658) (xy 204.961212 -287.840047) (xy 205.011024 -287.846613)
			(xy 205.059543 -287.859658) (xy 205.105932 -287.878956) (xy 205.12786 -287.89122) (xy 205.139036 -287.897824)
			(xy 205.164436 -287.898586) (xy 205.264004 -287.84804) (xy 205.278482 -287.827212) (xy 205.279752 -287.814004)
			(xy 205.283201 -287.786244) (xy 205.297162 -287.732078) (xy 205.31888 -287.680529) (xy 205.347889 -287.632702)
			(xy 205.383569 -287.589622) (xy 205.425154 -287.552211) (xy 205.471755 -287.52127) (xy 205.522373 -287.497462)
			(xy 205.575923 -287.481298) (xy 205.63126 -287.473123) (xy 205.659228 -287.472628) (xy 205.686481 -287.473044)
			(xy 205.74043 -287.480804) (xy 205.792727 -287.496163) (xy 205.842305 -287.518808) (xy 205.888156 -287.548278)
			(xy 205.929347 -287.583973) (xy 205.965039 -287.625166) (xy 205.994505 -287.67102) (xy 206.017147 -287.7206)
			(xy 206.032502 -287.772897) (xy 206.040258 -287.826847) (xy 206.040258 -287.881353) (xy 206.032502 -287.935303)
			(xy 206.017147 -287.9876) (xy 205.994505 -288.03718) (xy 205.965039 -288.083034) (xy 205.929347 -288.124227)
			(xy 205.888156 -288.159922) (xy 205.842305 -288.189392) (xy 205.792727 -288.212037) (xy 205.74043 -288.227396)
			(xy 205.686481 -288.235156) (xy 205.659228 -288.235644) (xy 205.634107 -288.235246) (xy 205.584295 -288.228684)
			(xy 205.535775 -288.215641) (xy 205.489386 -288.196345) (xy 205.467458 -288.184082) (xy 205.456282 -288.177478)
			(xy 205.430882 -288.176716) (xy 205.331314 -288.227262) (xy 205.316836 -288.24809) (xy 205.316801 -288.248453)
			(xy 206.587044 -288.248453) (xy 206.587044 -288.193947) (xy 206.594801 -288.139995) (xy 206.610157 -288.087697)
			(xy 206.632799 -288.038116) (xy 206.662267 -287.992262) (xy 206.697961 -287.951068) (xy 206.739154 -287.915373)
			(xy 206.785007 -287.885904) (xy 206.834587 -287.86326) (xy 206.886885 -287.847903) (xy 206.940837 -287.840145)
			(xy 206.96809 -287.839658) (xy 206.982048 -287.839771) (xy 207.009889 -287.841808) (xy 207.023716 -287.843722)
			(xy 207.034384 -287.845246) (xy 207.054196 -287.839912) (xy 207.128872 -287.781492) (xy 207.138778 -287.763458)
			(xy 207.139794 -287.75279) (xy 207.143 -287.724799) (xy 207.156498 -287.670104) (xy 207.177896 -287.617989)
			(xy 207.206728 -287.569589) (xy 207.242367 -287.525958) (xy 207.284037 -287.488045) (xy 207.330832 -287.456676)
			(xy 207.381733 -287.432532) (xy 207.435632 -287.416139) (xy 207.491356 -287.407854) (xy 207.519524 -287.40735)
			(xy 207.546385 -287.407833) (xy 207.599576 -287.415373) (xy 207.651183 -287.4303) (xy 207.700186 -287.452318)
			(xy 207.745615 -287.480993) (xy 207.786573 -287.515758) (xy 207.822249 -287.555924) (xy 207.851937 -287.600698)
			(xy 207.875051 -287.649194) (xy 207.891134 -287.700453) (xy 207.895952 -287.726882) (xy 207.89773 -287.738058)
			(xy 207.909922 -287.756092) (xy 207.942568 -287.77625) (xy 226.333058 -287.77625) (xy 226.333058 -287.72175)
			(xy 226.340813 -287.667803) (xy 226.356167 -287.61551) (xy 226.378805 -287.565933) (xy 226.408269 -287.520083)
			(xy 226.443957 -287.478892) (xy 226.485143 -287.443199) (xy 226.530989 -287.413729) (xy 226.580563 -287.391084)
			(xy 226.632855 -287.375724) (xy 226.6868 -287.367961) (xy 226.71405 -287.367472) (xy 226.744172 -287.368068)
			(xy 226.803668 -287.377542) (xy 226.860936 -287.396247) (xy 226.914553 -287.423717) (xy 226.963188 -287.459271)
			(xy 226.984814 -287.480248) (xy 226.991926 -287.487614) (xy 227.010722 -287.495234) (xy 227.103178 -287.495234)
			(xy 227.121974 -287.487614) (xy 227.129086 -287.480248) (xy 227.150702 -287.459258) (xy 227.199332 -287.423689)
			(xy 227.252951 -287.39621) (xy 227.310223 -287.377504) (xy 227.369725 -287.368037) (xy 227.39985 -287.367472)
			(xy 227.427104 -287.367972) (xy 227.481057 -287.375723) (xy 227.533358 -287.391074) (xy 227.582942 -287.413712)
			(xy 227.628799 -287.443177) (xy 227.669996 -287.478869) (xy 227.705693 -287.520061) (xy 227.735164 -287.565914)
			(xy 227.757809 -287.615495) (xy 227.773167 -287.667794) (xy 227.780925 -287.721746) (xy 227.780925 -287.776254)
			(xy 227.773167 -287.830206) (xy 227.757809 -287.882505) (xy 227.735164 -287.932086) (xy 227.705693 -287.977939)
			(xy 227.669996 -288.019131) (xy 227.628799 -288.054823) (xy 227.582942 -288.084288) (xy 227.533358 -288.106926)
			(xy 227.481057 -288.122277) (xy 227.427104 -288.130028) (xy 227.39985 -288.130488) (xy 227.369727 -288.129903)
			(xy 227.31023 -288.120428) (xy 227.252962 -288.101722) (xy 227.199345 -288.074248) (xy 227.150711 -288.038691)
			(xy 227.129086 -288.017712) (xy 227.121974 -288.010346) (xy 227.103178 -288.002726) (xy 227.010722 -288.002726)
			(xy 226.991926 -288.010346) (xy 226.984814 -288.017712) (xy 226.963208 -288.038713) (xy 226.914574 -288.074278)
			(xy 226.860953 -288.101754) (xy 226.803678 -288.120457) (xy 226.744176 -288.129923) (xy 226.71405 -288.130488)
			(xy 226.6868 -288.130039) (xy 226.632855 -288.122276) (xy 226.580563 -288.106916) (xy 226.530989 -288.084271)
			(xy 226.485143 -288.054801) (xy 226.443957 -288.019108) (xy 226.408269 -287.977917) (xy 226.378805 -287.932067)
			(xy 226.356167 -287.88249) (xy 226.340813 -287.830197) (xy 226.333058 -287.77625) (xy 207.942568 -287.77625)
			(xy 207.99425 -287.808162) (xy 208.01584 -287.810702) (xy 208.026508 -287.8074) (xy 208.054198 -287.799338)
			(xy 208.111211 -287.790659) (xy 208.140046 -287.790128) (xy 208.167298 -287.790545) (xy 208.221246 -287.798308)
			(xy 208.27354 -287.813668) (xy 208.323116 -287.836314) (xy 208.368965 -287.865784) (xy 208.410153 -287.901479)
			(xy 208.445843 -287.942672) (xy 208.475308 -287.988525) (xy 208.497948 -288.038103) (xy 208.513302 -288.0904)
			(xy 208.521058 -288.144348) (xy 208.521058 -288.198852) (xy 208.513302 -288.252801) (xy 208.497948 -288.305097)
			(xy 208.475308 -288.354675) (xy 208.445843 -288.400528) (xy 208.410153 -288.441721) (xy 208.368965 -288.477416)
			(xy 208.323116 -288.506886) (xy 208.27354 -288.529532) (xy 208.221246 -288.544892) (xy 208.167298 -288.552655)
			(xy 208.140046 -288.553144) (xy 208.113184 -288.552693) (xy 208.059992 -288.545149) (xy 208.008383 -288.530218)
			(xy 207.95938 -288.508196) (xy 207.913951 -288.479517) (xy 207.872993 -288.444749) (xy 207.837318 -288.404579)
			(xy 207.80763 -288.359803) (xy 207.784517 -288.311304) (xy 207.768436 -288.260043) (xy 207.763618 -288.233612)
			(xy 207.76184 -288.222436) (xy 207.749648 -288.204402) (xy 207.66532 -288.152332) (xy 207.64373 -288.149792)
			(xy 207.633062 -288.153094) (xy 207.605373 -288.161162) (xy 207.548359 -288.169838) (xy 207.519524 -288.170366)
			(xy 207.505566 -288.170251) (xy 207.477725 -288.168215) (xy 207.463898 -288.166302) (xy 207.45323 -288.164778)
			(xy 207.433418 -288.170112) (xy 207.358742 -288.228532) (xy 207.348836 -288.246566) (xy 207.34782 -288.257234)
			(xy 207.34462 -288.285225) (xy 207.33112 -288.33992) (xy 207.30972 -288.392034) (xy 207.280886 -288.440432)
			(xy 207.245246 -288.484063) (xy 207.203575 -288.521975) (xy 207.156781 -288.553345) (xy 207.10588 -288.577489)
			(xy 207.051982 -288.593883) (xy 206.996258 -288.602169) (xy 206.96809 -288.602674) (xy 206.940837 -288.602255)
			(xy 206.886885 -288.594497) (xy 206.834587 -288.57914) (xy 206.785007 -288.556496) (xy 206.739154 -288.527027)
			(xy 206.697961 -288.491332) (xy 206.662267 -288.450138) (xy 206.632799 -288.404284) (xy 206.610157 -288.354703)
			(xy 206.594801 -288.302405) (xy 206.587044 -288.248453) (xy 205.316801 -288.248453) (xy 205.315566 -288.261298)
			(xy 205.312101 -288.289055) (xy 205.298141 -288.34322) (xy 205.276424 -288.394768) (xy 205.247416 -288.442594)
			(xy 205.211738 -288.485674) (xy 205.170155 -288.523085) (xy 205.123556 -288.554026) (xy 205.072941 -288.577835)
			(xy 205.019392 -288.594001) (xy 204.964058 -288.602178) (xy 204.93609 -288.602674) (xy 204.909972 -288.602264)
			(xy 204.858225 -288.595124) (xy 204.807936 -288.580992) (xy 204.760045 -288.560133) (xy 204.715447 -288.532936)
			(xy 204.674975 -288.499911) (xy 204.639386 -288.461673) (xy 204.609346 -288.418938) (xy 204.597 -288.395918)
			(xy 204.590396 -288.382964) (xy 204.566266 -288.368232) (xy 204.446886 -288.368232) (xy 204.422756 -288.382964)
			(xy 204.416152 -288.395918) (xy 204.40381 -288.418941) (xy 204.373777 -288.461683) (xy 204.338192 -288.499926)
			(xy 204.29772 -288.532954) (xy 204.25312 -288.560149) (xy 204.205224 -288.581002) (xy 204.154931 -288.595123)
			(xy 204.103181 -288.602248) (xy 204.077062 -288.602674) (xy 204.04981 -288.602254) (xy 203.995862 -288.594492)
			(xy 203.943567 -288.579132) (xy 203.89399 -288.556487) (xy 203.84814 -288.527017) (xy 203.806951 -288.491322)
			(xy 203.77126 -288.450129) (xy 203.741795 -288.404277) (xy 203.719155 -288.354698) (xy 203.7038 -288.302401)
			(xy 203.696044 -288.248452) (xy 198.850472 -288.248452) (xy 198.854835 -288.275299) (xy 198.85533 -288.299906)
			(xy 198.854835 -288.324513) (xy 198.84694 -288.37309) (xy 198.831356 -288.419771) (xy 198.808485 -288.463348)
			(xy 198.77892 -288.502692) (xy 198.743427 -288.536784) (xy 198.702924 -288.56474) (xy 198.658462 -288.585838)
			(xy 198.611191 -288.59953) (xy 198.562336 -288.605462) (xy 198.513161 -288.603481) (xy 198.464942 -288.593637)
			(xy 198.418926 -288.576185) (xy 198.376305 -288.551578) (xy 198.338184 -288.520453) (xy 198.305549 -288.483616)
			(xy 198.279246 -288.44202) (xy 198.259955 -288.396744) (xy 198.248178 -288.34896) (xy 198.244218 -288.299906)
			(xy 197.90537 -288.299906) (xy 197.904875 -288.324513) (xy 197.89698 -288.37309) (xy 197.881396 -288.419771)
			(xy 197.858525 -288.463348) (xy 197.82896 -288.502692) (xy 197.793467 -288.536784) (xy 197.752964 -288.56474)
			(xy 197.708502 -288.585838) (xy 197.661231 -288.59953) (xy 197.612376 -288.605462) (xy 197.563201 -288.603481)
			(xy 197.514982 -288.593637) (xy 197.468966 -288.576185) (xy 197.426345 -288.551578) (xy 197.388224 -288.520453)
			(xy 197.355589 -288.483616) (xy 197.329286 -288.44202) (xy 197.309995 -288.396744) (xy 197.298218 -288.34896)
			(xy 197.294258 -288.299906) (xy 196.977 -288.299906) (xy 196.976496 -288.325614) (xy 196.968453 -288.376396)
			(xy 196.952565 -288.425295) (xy 196.929222 -288.471107) (xy 196.899001 -288.512703) (xy 196.862645 -288.549059)
			(xy 196.821049 -288.57928) (xy 196.775237 -288.602623) (xy 196.726338 -288.618511) (xy 196.675556 -288.626554)
			(xy 196.62414 -288.626554) (xy 196.573358 -288.618511) (xy 196.524459 -288.602623) (xy 196.478647 -288.57928)
			(xy 196.437051 -288.549059) (xy 196.400695 -288.512703) (xy 196.370474 -288.471107) (xy 196.347131 -288.425295)
			(xy 196.331243 -288.376396) (xy 196.3232 -288.325614) (xy 196.026536 -288.325614) (xy 196.018493 -288.376396)
			(xy 196.002605 -288.425295) (xy 195.979262 -288.471107) (xy 195.949041 -288.512703) (xy 195.912685 -288.549059)
			(xy 195.871089 -288.57928) (xy 195.825277 -288.602623) (xy 195.776378 -288.618511) (xy 195.725596 -288.626554)
			(xy 195.67418 -288.626554) (xy 195.623398 -288.618511) (xy 195.574499 -288.602623) (xy 195.528687 -288.57928)
			(xy 195.487091 -288.549059) (xy 195.450735 -288.512703) (xy 195.420514 -288.471107) (xy 195.397171 -288.425295)
			(xy 195.381283 -288.376396) (xy 195.37324 -288.325614) (xy 195.054562 -288.325614) (xy 195.046846 -288.37309)
			(xy 195.031262 -288.419771) (xy 195.008391 -288.463348) (xy 194.978826 -288.502692) (xy 194.943333 -288.536784)
			(xy 194.90283 -288.56474) (xy 194.858368 -288.585838) (xy 194.811097 -288.59953) (xy 194.762242 -288.605462)
			(xy 194.713067 -288.603481) (xy 194.664848 -288.593637) (xy 194.618832 -288.576185) (xy 194.576211 -288.551578)
			(xy 194.53809 -288.520453) (xy 194.505455 -288.483616) (xy 194.479152 -288.44202) (xy 194.459861 -288.396744)
			(xy 194.448084 -288.34896) (xy 194.444124 -288.299906) (xy 194.12712 -288.299906) (xy 194.126616 -288.325614)
			(xy 194.118573 -288.376396) (xy 194.102685 -288.425295) (xy 194.079342 -288.471107) (xy 194.049121 -288.512703)
			(xy 194.012765 -288.549059) (xy 193.971169 -288.57928) (xy 193.925357 -288.602623) (xy 193.876458 -288.618511)
			(xy 193.825676 -288.626554) (xy 193.77426 -288.626554) (xy 193.723478 -288.618511) (xy 193.674579 -288.602623)
			(xy 193.628767 -288.57928) (xy 193.587171 -288.549059) (xy 193.550815 -288.512703) (xy 193.520594 -288.471107)
			(xy 193.497251 -288.425295) (xy 193.481363 -288.376396) (xy 193.47332 -288.325614) (xy 193.176656 -288.325614)
			(xy 193.168613 -288.376396) (xy 193.152725 -288.425295) (xy 193.129382 -288.471107) (xy 193.099161 -288.512703)
			(xy 193.062805 -288.549059) (xy 193.021209 -288.57928) (xy 192.975397 -288.602623) (xy 192.926498 -288.618511)
			(xy 192.875716 -288.626554) (xy 192.8243 -288.626554) (xy 192.773518 -288.618511) (xy 192.724619 -288.602623)
			(xy 192.678807 -288.57928) (xy 192.637211 -288.549059) (xy 192.600855 -288.512703) (xy 192.570634 -288.471107)
			(xy 192.547291 -288.425295) (xy 192.531403 -288.376396) (xy 192.52336 -288.325614) (xy 192.204682 -288.325614)
			(xy 192.196966 -288.37309) (xy 192.181382 -288.419771) (xy 192.158511 -288.463348) (xy 192.128946 -288.502692)
			(xy 192.093453 -288.536784) (xy 192.05295 -288.56474) (xy 192.008488 -288.585838) (xy 191.961217 -288.59953)
			(xy 191.912362 -288.605462) (xy 191.863187 -288.603481) (xy 191.814968 -288.593637) (xy 191.768952 -288.576185)
			(xy 191.726331 -288.551578) (xy 191.68821 -288.520453) (xy 191.655575 -288.483616) (xy 191.629272 -288.44202)
			(xy 191.609981 -288.396744) (xy 191.598204 -288.34896) (xy 191.594244 -288.299906) (xy 191.255396 -288.299906)
			(xy 191.254901 -288.324513) (xy 191.247006 -288.37309) (xy 191.231422 -288.419771) (xy 191.208551 -288.463348)
			(xy 191.178986 -288.502692) (xy 191.143493 -288.536784) (xy 191.10299 -288.56474) (xy 191.058528 -288.585838)
			(xy 191.011257 -288.59953) (xy 190.962402 -288.605462) (xy 190.913227 -288.603481) (xy 190.865008 -288.593637)
			(xy 190.818992 -288.576185) (xy 190.776371 -288.551578) (xy 190.73825 -288.520453) (xy 190.705615 -288.483616)
			(xy 190.679312 -288.44202) (xy 190.660021 -288.396744) (xy 190.648244 -288.34896) (xy 190.644284 -288.299906)
			(xy 190.305182 -288.299906) (xy 190.304687 -288.324513) (xy 190.296792 -288.37309) (xy 190.281208 -288.419771)
			(xy 190.258337 -288.463348) (xy 190.228772 -288.502692) (xy 190.193279 -288.536784) (xy 190.152776 -288.56474)
			(xy 190.108314 -288.585838) (xy 190.061043 -288.59953) (xy 190.012188 -288.605462) (xy 189.963013 -288.603481)
			(xy 189.914794 -288.593637) (xy 189.868778 -288.576185) (xy 189.826157 -288.551578) (xy 189.788036 -288.520453)
			(xy 189.755401 -288.483616) (xy 189.729098 -288.44202) (xy 189.709807 -288.396744) (xy 189.69803 -288.34896)
			(xy 189.69407 -288.299906) (xy 164.790882 -288.299906) (xy 164.790882 -288.373312) (xy 164.791057 -288.379464)
			(xy 164.794022 -288.391404) (xy 164.796724 -288.396934) (xy 164.804852 -288.40811) (xy 164.819584 -288.423604)
			(xy 164.826188 -288.430716) (xy 164.849302 -288.441638) (xy 164.852858 -288.442654) (xy 164.86505 -288.446464)
			(xy 164.869622 -288.447226) (xy 164.895693 -288.451303) (xy 164.946177 -288.46665) (xy 164.993584 -288.489817)
			(xy 165.036711 -288.520219) (xy 165.074464 -288.557083) (xy 165.105884 -288.599473) (xy 165.130174 -288.646315)
			(xy 165.146719 -288.69642) (xy 165.155097 -288.748515) (xy 165.155097 -288.774886) (xy 165.469074 -288.774886)
			(xy 165.473034 -288.725832) (xy 165.484811 -288.678048) (xy 165.504102 -288.632772) (xy 165.530405 -288.591176)
			(xy 165.56304 -288.554339) (xy 165.601161 -288.523214) (xy 165.643782 -288.498607) (xy 165.689798 -288.481155)
			(xy 165.738017 -288.471311) (xy 165.787192 -288.46933) (xy 165.836047 -288.475262) (xy 165.883318 -288.488954)
			(xy 165.92778 -288.510052) (xy 165.968283 -288.538008) (xy 166.003776 -288.5721) (xy 166.033341 -288.611444)
			(xy 166.056212 -288.655021) (xy 166.071796 -288.701702) (xy 166.079691 -288.750279) (xy 166.080186 -288.774886)
			(xy 184.469036 -288.774886) (xy 184.472996 -288.725832) (xy 184.484773 -288.678048) (xy 184.504064 -288.632772)
			(xy 184.530367 -288.591176) (xy 184.563002 -288.554339) (xy 184.601123 -288.523214) (xy 184.643744 -288.498607)
			(xy 184.68976 -288.481155) (xy 184.737979 -288.471311) (xy 184.787154 -288.46933) (xy 184.836009 -288.475262)
			(xy 184.88328 -288.488954) (xy 184.927742 -288.510052) (xy 184.968245 -288.538008) (xy 185.003738 -288.5721)
			(xy 185.033303 -288.611444) (xy 185.056174 -288.655021) (xy 185.071758 -288.701702) (xy 185.079653 -288.750279)
			(xy 185.080148 -288.774886) (xy 185.41925 -288.774886) (xy 185.42321 -288.725832) (xy 185.434987 -288.678048)
			(xy 185.454278 -288.632772) (xy 185.480581 -288.591176) (xy 185.513216 -288.554339) (xy 185.551337 -288.523214)
			(xy 185.593958 -288.498607) (xy 185.639974 -288.481155) (xy 185.688193 -288.471311) (xy 185.737368 -288.46933)
			(xy 185.786223 -288.475262) (xy 185.833494 -288.488954) (xy 185.877956 -288.510052) (xy 185.918459 -288.538008)
			(xy 185.953952 -288.5721) (xy 185.983517 -288.611444) (xy 186.006388 -288.655021) (xy 186.021972 -288.701702)
			(xy 186.029867 -288.750279) (xy 186.030362 -288.774886) (xy 186.36921 -288.774886) (xy 186.37317 -288.725832)
			(xy 186.384947 -288.678048) (xy 186.404238 -288.632772) (xy 186.430541 -288.591176) (xy 186.463176 -288.554339)
			(xy 186.501297 -288.523214) (xy 186.543918 -288.498607) (xy 186.589934 -288.481155) (xy 186.638153 -288.471311)
			(xy 186.687328 -288.46933) (xy 186.736183 -288.475262) (xy 186.783454 -288.488954) (xy 186.827916 -288.510052)
			(xy 186.868419 -288.538008) (xy 186.903912 -288.5721) (xy 186.933477 -288.611444) (xy 186.956348 -288.655021)
			(xy 186.971932 -288.701702) (xy 186.979827 -288.750279) (xy 186.980322 -288.774886) (xy 187.31917 -288.774886)
			(xy 187.32313 -288.725832) (xy 187.334907 -288.678048) (xy 187.354198 -288.632772) (xy 187.380501 -288.591176)
			(xy 187.413136 -288.554339) (xy 187.451257 -288.523214) (xy 187.493878 -288.498607) (xy 187.539894 -288.481155)
			(xy 187.588113 -288.471311) (xy 187.637288 -288.46933) (xy 187.686143 -288.475262) (xy 187.733414 -288.488954)
			(xy 187.777876 -288.510052) (xy 187.818379 -288.538008) (xy 187.853872 -288.5721) (xy 187.883437 -288.611444)
			(xy 187.906308 -288.655021) (xy 187.921892 -288.701702) (xy 187.929787 -288.750279) (xy 187.930282 -288.774886)
			(xy 188.26913 -288.774886) (xy 188.27309 -288.725832) (xy 188.284867 -288.678048) (xy 188.304158 -288.632772)
			(xy 188.330461 -288.591176) (xy 188.363096 -288.554339) (xy 188.401217 -288.523214) (xy 188.443838 -288.498607)
			(xy 188.489854 -288.481155) (xy 188.538073 -288.471311) (xy 188.587248 -288.46933) (xy 188.636103 -288.475262)
			(xy 188.683374 -288.488954) (xy 188.727836 -288.510052) (xy 188.768339 -288.538008) (xy 188.803832 -288.5721)
			(xy 188.833397 -288.611444) (xy 188.856268 -288.655021) (xy 188.871852 -288.701702) (xy 188.879747 -288.750279)
			(xy 188.880242 -288.774886) (xy 188.879747 -288.799493) (xy 188.871852 -288.84807) (xy 188.856268 -288.894751)
			(xy 188.833397 -288.938328) (xy 188.803832 -288.977672) (xy 188.768339 -289.011764) (xy 188.727836 -289.03972)
			(xy 188.683374 -289.060818) (xy 188.636103 -289.07451) (xy 188.587248 -289.080442) (xy 188.538073 -289.078461)
			(xy 188.489854 -289.068617) (xy 188.443838 -289.051165) (xy 188.401217 -289.026558) (xy 188.363096 -288.995433)
			(xy 188.330461 -288.958596) (xy 188.304158 -288.917) (xy 188.284867 -288.871724) (xy 188.27309 -288.82394)
			(xy 188.26913 -288.774886) (xy 187.930282 -288.774886) (xy 187.929787 -288.799493) (xy 187.921892 -288.84807)
			(xy 187.906308 -288.894751) (xy 187.883437 -288.938328) (xy 187.853872 -288.977672) (xy 187.818379 -289.011764)
			(xy 187.777876 -289.03972) (xy 187.733414 -289.060818) (xy 187.686143 -289.07451) (xy 187.637288 -289.080442)
			(xy 187.588113 -289.078461) (xy 187.539894 -289.068617) (xy 187.493878 -289.051165) (xy 187.451257 -289.026558)
			(xy 187.413136 -288.995433) (xy 187.380501 -288.958596) (xy 187.354198 -288.917) (xy 187.334907 -288.871724)
			(xy 187.32313 -288.82394) (xy 187.31917 -288.774886) (xy 186.980322 -288.774886) (xy 186.979827 -288.799493)
			(xy 186.971932 -288.84807) (xy 186.956348 -288.894751) (xy 186.933477 -288.938328) (xy 186.903912 -288.977672)
			(xy 186.868419 -289.011764) (xy 186.827916 -289.03972) (xy 186.783454 -289.060818) (xy 186.736183 -289.07451)
			(xy 186.687328 -289.080442) (xy 186.638153 -289.078461) (xy 186.589934 -289.068617) (xy 186.543918 -289.051165)
			(xy 186.501297 -289.026558) (xy 186.463176 -288.995433) (xy 186.430541 -288.958596) (xy 186.404238 -288.917)
			(xy 186.384947 -288.871724) (xy 186.37317 -288.82394) (xy 186.36921 -288.774886) (xy 186.030362 -288.774886)
			(xy 186.029867 -288.799493) (xy 186.021972 -288.84807) (xy 186.006388 -288.894751) (xy 185.983517 -288.938328)
			(xy 185.953952 -288.977672) (xy 185.918459 -289.011764) (xy 185.877956 -289.03972) (xy 185.833494 -289.060818)
			(xy 185.786223 -289.07451) (xy 185.737368 -289.080442) (xy 185.688193 -289.078461) (xy 185.639974 -289.068617)
			(xy 185.593958 -289.051165) (xy 185.551337 -289.026558) (xy 185.513216 -288.995433) (xy 185.480581 -288.958596)
			(xy 185.454278 -288.917) (xy 185.434987 -288.871724) (xy 185.42321 -288.82394) (xy 185.41925 -288.774886)
			(xy 185.080148 -288.774886) (xy 185.079653 -288.799493) (xy 185.071758 -288.84807) (xy 185.056174 -288.894751)
			(xy 185.033303 -288.938328) (xy 185.003738 -288.977672) (xy 184.968245 -289.011764) (xy 184.927742 -289.03972)
			(xy 184.88328 -289.060818) (xy 184.836009 -289.07451) (xy 184.787154 -289.080442) (xy 184.737979 -289.078461)
			(xy 184.68976 -289.068617) (xy 184.643744 -289.051165) (xy 184.601123 -289.026558) (xy 184.563002 -288.995433)
			(xy 184.530367 -288.958596) (xy 184.504064 -288.917) (xy 184.484773 -288.871724) (xy 184.472996 -288.82394)
			(xy 184.469036 -288.774886) (xy 166.080186 -288.774886) (xy 166.079691 -288.799493) (xy 166.071796 -288.84807)
			(xy 166.056212 -288.894751) (xy 166.033341 -288.938328) (xy 166.003776 -288.977672) (xy 165.968283 -289.011764)
			(xy 165.92778 -289.03972) (xy 165.883318 -289.060818) (xy 165.836047 -289.07451) (xy 165.787192 -289.080442)
			(xy 165.738017 -289.078461) (xy 165.689798 -289.068617) (xy 165.643782 -289.051165) (xy 165.601161 -289.026558)
			(xy 165.56304 -288.995433) (xy 165.530405 -288.958596) (xy 165.504102 -288.917) (xy 165.484811 -288.871724)
			(xy 165.473034 -288.82394) (xy 165.469074 -288.774886) (xy 165.155097 -288.774886) (xy 165.155098 -288.801281)
			(xy 165.14672 -288.853377) (xy 165.130176 -288.903481) (xy 165.105886 -288.950324) (xy 165.074466 -288.992715)
			(xy 165.036714 -289.029579) (xy 164.993588 -289.059981) (xy 164.946181 -289.083149) (xy 164.895696 -289.098496)
			(xy 164.869622 -289.102546) (xy 164.86505 -289.103308) (xy 164.854636 -289.10661) (xy 164.850318 -289.10788)
			(xy 164.826696 -289.118802) (xy 164.819838 -289.125914) (xy 164.804852 -289.141662) (xy 164.80026 -289.146765)
			(xy 164.793806 -289.158876) (xy 164.792152 -289.165538) (xy 164.790882 -289.17646) (xy 164.790882 -289.323272)
			(xy 164.791341 -289.332908) (xy 164.798508 -289.350803) (xy 164.804852 -289.35807) (xy 164.820092 -289.374072)
			(xy 164.82695 -289.381438) (xy 164.850318 -289.391852) (xy 164.854636 -289.393122) (xy 164.86505 -289.396424)
			(xy 164.869622 -289.397186) (xy 164.895688 -289.401263) (xy 164.946163 -289.416608) (xy 164.993561 -289.439773)
			(xy 165.036679 -289.47017) (xy 165.074424 -289.507028) (xy 165.105838 -289.549412) (xy 165.130123 -289.596246)
			(xy 165.146663 -289.646342) (xy 165.155039 -289.698428) (xy 165.155038 -289.724846) (xy 165.469074 -289.724846)
			(xy 165.473034 -289.675792) (xy 165.484811 -289.628008) (xy 165.504102 -289.582732) (xy 165.530405 -289.541136)
			(xy 165.56304 -289.504299) (xy 165.601161 -289.473174) (xy 165.643782 -289.448567) (xy 165.689798 -289.431115)
			(xy 165.738017 -289.421271) (xy 165.787192 -289.41929) (xy 165.836047 -289.425222) (xy 165.883318 -289.438914)
			(xy 165.92778 -289.460012) (xy 165.968283 -289.487968) (xy 166.003776 -289.52206) (xy 166.033341 -289.561404)
			(xy 166.056212 -289.604981) (xy 166.071796 -289.651662) (xy 166.079691 -289.700239) (xy 166.080186 -289.724846)
			(xy 166.419288 -289.724846) (xy 166.423248 -289.675792) (xy 166.435025 -289.628008) (xy 166.454316 -289.582732)
			(xy 166.480619 -289.541136) (xy 166.513254 -289.504299) (xy 166.551375 -289.473174) (xy 166.593996 -289.448567)
			(xy 166.640012 -289.431115) (xy 166.688231 -289.421271) (xy 166.737406 -289.41929) (xy 166.786261 -289.425222)
			(xy 166.833532 -289.438914) (xy 166.877994 -289.460012) (xy 166.918497 -289.487968) (xy 166.95399 -289.52206)
			(xy 166.983555 -289.561404) (xy 167.006426 -289.604981) (xy 167.02201 -289.651662) (xy 167.029905 -289.700239)
			(xy 167.0304 -289.724846) (xy 167.369248 -289.724846) (xy 167.373208 -289.675792) (xy 167.384985 -289.628008)
			(xy 167.404276 -289.582732) (xy 167.430579 -289.541136) (xy 167.463214 -289.504299) (xy 167.501335 -289.473174)
			(xy 167.543956 -289.448567) (xy 167.589972 -289.431115) (xy 167.638191 -289.421271) (xy 167.687366 -289.41929)
			(xy 167.736221 -289.425222) (xy 167.783492 -289.438914) (xy 167.827954 -289.460012) (xy 167.868457 -289.487968)
			(xy 167.90395 -289.52206) (xy 167.933515 -289.561404) (xy 167.956386 -289.604981) (xy 167.97197 -289.651662)
			(xy 167.979865 -289.700239) (xy 167.98036 -289.724846) (xy 168.319208 -289.724846) (xy 168.323168 -289.675792)
			(xy 168.334945 -289.628008) (xy 168.354236 -289.582732) (xy 168.380539 -289.541136) (xy 168.413174 -289.504299)
			(xy 168.451295 -289.473174) (xy 168.493916 -289.448567) (xy 168.539932 -289.431115) (xy 168.588151 -289.421271)
			(xy 168.637326 -289.41929) (xy 168.686181 -289.425222) (xy 168.733452 -289.438914) (xy 168.777914 -289.460012)
			(xy 168.818417 -289.487968) (xy 168.85391 -289.52206) (xy 168.883475 -289.561404) (xy 168.906346 -289.604981)
			(xy 168.92193 -289.651662) (xy 168.929825 -289.700239) (xy 168.93032 -289.724846) (xy 169.269168 -289.724846)
			(xy 169.273128 -289.675792) (xy 169.284905 -289.628008) (xy 169.304196 -289.582732) (xy 169.330499 -289.541136)
			(xy 169.363134 -289.504299) (xy 169.401255 -289.473174) (xy 169.443876 -289.448567) (xy 169.489892 -289.431115)
			(xy 169.538111 -289.421271) (xy 169.587286 -289.41929) (xy 169.636141 -289.425222) (xy 169.683412 -289.438914)
			(xy 169.727874 -289.460012) (xy 169.768377 -289.487968) (xy 169.80387 -289.52206) (xy 169.833435 -289.561404)
			(xy 169.856306 -289.604981) (xy 169.87189 -289.651662) (xy 169.879785 -289.700239) (xy 169.88028 -289.724846)
			(xy 170.219128 -289.724846) (xy 170.223088 -289.675792) (xy 170.234865 -289.628008) (xy 170.254156 -289.582732)
			(xy 170.280459 -289.541136) (xy 170.313094 -289.504299) (xy 170.351215 -289.473174) (xy 170.393836 -289.448567)
			(xy 170.439852 -289.431115) (xy 170.488071 -289.421271) (xy 170.537246 -289.41929) (xy 170.586101 -289.425222)
			(xy 170.633372 -289.438914) (xy 170.677834 -289.460012) (xy 170.718337 -289.487968) (xy 170.75383 -289.52206)
			(xy 170.783395 -289.561404) (xy 170.806266 -289.604981) (xy 170.82185 -289.651662) (xy 170.829745 -289.700239)
			(xy 170.83024 -289.724846) (xy 171.169088 -289.724846) (xy 171.173048 -289.675792) (xy 171.184825 -289.628008)
			(xy 171.204116 -289.582732) (xy 171.230419 -289.541136) (xy 171.263054 -289.504299) (xy 171.301175 -289.473174)
			(xy 171.343796 -289.448567) (xy 171.389812 -289.431115) (xy 171.438031 -289.421271) (xy 171.487206 -289.41929)
			(xy 171.536061 -289.425222) (xy 171.583332 -289.438914) (xy 171.627794 -289.460012) (xy 171.668297 -289.487968)
			(xy 171.70379 -289.52206) (xy 171.733355 -289.561404) (xy 171.756226 -289.604981) (xy 171.77181 -289.651662)
			(xy 171.779705 -289.700239) (xy 171.7802 -289.724846) (xy 172.119048 -289.724846) (xy 172.123008 -289.675792)
			(xy 172.134785 -289.628008) (xy 172.154076 -289.582732) (xy 172.180379 -289.541136) (xy 172.213014 -289.504299)
			(xy 172.251135 -289.473174) (xy 172.293756 -289.448567) (xy 172.339772 -289.431115) (xy 172.387991 -289.421271)
			(xy 172.437166 -289.41929) (xy 172.486021 -289.425222) (xy 172.533292 -289.438914) (xy 172.577754 -289.460012)
			(xy 172.618257 -289.487968) (xy 172.65375 -289.52206) (xy 172.683315 -289.561404) (xy 172.706186 -289.604981)
			(xy 172.72177 -289.651662) (xy 172.729665 -289.700239) (xy 172.73016 -289.724846) (xy 173.069262 -289.724846)
			(xy 173.073222 -289.675792) (xy 173.084999 -289.628008) (xy 173.10429 -289.582732) (xy 173.130593 -289.541136)
			(xy 173.163228 -289.504299) (xy 173.201349 -289.473174) (xy 173.24397 -289.448567) (xy 173.289986 -289.431115)
			(xy 173.338205 -289.421271) (xy 173.38738 -289.41929) (xy 173.436235 -289.425222) (xy 173.483506 -289.438914)
			(xy 173.527968 -289.460012) (xy 173.568471 -289.487968) (xy 173.603964 -289.52206) (xy 173.633529 -289.561404)
			(xy 173.6564 -289.604981) (xy 173.671984 -289.651662) (xy 173.679879 -289.700239) (xy 173.680374 -289.724846)
			(xy 174.019222 -289.724846) (xy 174.023182 -289.675792) (xy 174.034959 -289.628008) (xy 174.05425 -289.582732)
			(xy 174.080553 -289.541136) (xy 174.113188 -289.504299) (xy 174.151309 -289.473174) (xy 174.19393 -289.448567)
			(xy 174.239946 -289.431115) (xy 174.288165 -289.421271) (xy 174.33734 -289.41929) (xy 174.386195 -289.425222)
			(xy 174.433466 -289.438914) (xy 174.477928 -289.460012) (xy 174.518431 -289.487968) (xy 174.553924 -289.52206)
			(xy 174.583489 -289.561404) (xy 174.60636 -289.604981) (xy 174.621944 -289.651662) (xy 174.629839 -289.700239)
			(xy 174.630334 -289.724846) (xy 175.919142 -289.724846) (xy 175.923102 -289.675792) (xy 175.934879 -289.628008)
			(xy 175.95417 -289.582732) (xy 175.980473 -289.541136) (xy 176.013108 -289.504299) (xy 176.051229 -289.473174)
			(xy 176.09385 -289.448567) (xy 176.139866 -289.431115) (xy 176.188085 -289.421271) (xy 176.23726 -289.41929)
			(xy 176.286115 -289.425222) (xy 176.333386 -289.438914) (xy 176.377848 -289.460012) (xy 176.418351 -289.487968)
			(xy 176.453844 -289.52206) (xy 176.483409 -289.561404) (xy 176.50628 -289.604981) (xy 176.521864 -289.651662)
			(xy 176.529759 -289.700239) (xy 176.530254 -289.724846) (xy 176.869102 -289.724846) (xy 176.873062 -289.675792)
			(xy 176.884839 -289.628008) (xy 176.90413 -289.582732) (xy 176.930433 -289.541136) (xy 176.963068 -289.504299)
			(xy 177.001189 -289.473174) (xy 177.04381 -289.448567) (xy 177.089826 -289.431115) (xy 177.138045 -289.421271)
			(xy 177.18722 -289.41929) (xy 177.236075 -289.425222) (xy 177.283346 -289.438914) (xy 177.327808 -289.460012)
			(xy 177.368311 -289.487968) (xy 177.403804 -289.52206) (xy 177.433369 -289.561404) (xy 177.45624 -289.604981)
			(xy 177.471824 -289.651662) (xy 177.479719 -289.700239) (xy 177.480214 -289.724846) (xy 177.819062 -289.724846)
			(xy 177.823022 -289.675792) (xy 177.834799 -289.628008) (xy 177.85409 -289.582732) (xy 177.880393 -289.541136)
			(xy 177.913028 -289.504299) (xy 177.951149 -289.473174) (xy 177.99377 -289.448567) (xy 178.039786 -289.431115)
			(xy 178.088005 -289.421271) (xy 178.13718 -289.41929) (xy 178.186035 -289.425222) (xy 178.233306 -289.438914)
			(xy 178.277768 -289.460012) (xy 178.318271 -289.487968) (xy 178.353764 -289.52206) (xy 178.383329 -289.561404)
			(xy 178.4062 -289.604981) (xy 178.421784 -289.651662) (xy 178.429679 -289.700239) (xy 178.430174 -289.724846)
			(xy 178.769276 -289.724846) (xy 178.773236 -289.675792) (xy 178.785013 -289.628008) (xy 178.804304 -289.582732)
			(xy 178.830607 -289.541136) (xy 178.863242 -289.504299) (xy 178.901363 -289.473174) (xy 178.943984 -289.448567)
			(xy 178.99 -289.431115) (xy 179.038219 -289.421271) (xy 179.087394 -289.41929) (xy 179.136249 -289.425222)
			(xy 179.18352 -289.438914) (xy 179.227982 -289.460012) (xy 179.268485 -289.487968) (xy 179.303978 -289.52206)
			(xy 179.333543 -289.561404) (xy 179.356414 -289.604981) (xy 179.371998 -289.651662) (xy 179.379893 -289.700239)
			(xy 179.380388 -289.724846) (xy 179.719236 -289.724846) (xy 179.723196 -289.675792) (xy 179.734973 -289.628008)
			(xy 179.754264 -289.582732) (xy 179.780567 -289.541136) (xy 179.813202 -289.504299) (xy 179.851323 -289.473174)
			(xy 179.893944 -289.448567) (xy 179.93996 -289.431115) (xy 179.988179 -289.421271) (xy 180.037354 -289.41929)
			(xy 180.086209 -289.425222) (xy 180.13348 -289.438914) (xy 180.177942 -289.460012) (xy 180.218445 -289.487968)
			(xy 180.253938 -289.52206) (xy 180.283503 -289.561404) (xy 180.306374 -289.604981) (xy 180.321958 -289.651662)
			(xy 180.329853 -289.700239) (xy 180.330348 -289.724846) (xy 180.669196 -289.724846) (xy 180.673156 -289.675792)
			(xy 180.684933 -289.628008) (xy 180.704224 -289.582732) (xy 180.730527 -289.541136) (xy 180.763162 -289.504299)
			(xy 180.801283 -289.473174) (xy 180.843904 -289.448567) (xy 180.88992 -289.431115) (xy 180.938139 -289.421271)
			(xy 180.987314 -289.41929) (xy 181.036169 -289.425222) (xy 181.08344 -289.438914) (xy 181.127902 -289.460012)
			(xy 181.168405 -289.487968) (xy 181.203898 -289.52206) (xy 181.233463 -289.561404) (xy 181.256334 -289.604981)
			(xy 181.271918 -289.651662) (xy 181.279813 -289.700239) (xy 181.280308 -289.724846) (xy 181.619156 -289.724846)
			(xy 181.623116 -289.675792) (xy 181.634893 -289.628008) (xy 181.654184 -289.582732) (xy 181.680487 -289.541136)
			(xy 181.713122 -289.504299) (xy 181.751243 -289.473174) (xy 181.793864 -289.448567) (xy 181.83988 -289.431115)
			(xy 181.888099 -289.421271) (xy 181.937274 -289.41929) (xy 181.986129 -289.425222) (xy 182.0334 -289.438914)
			(xy 182.077862 -289.460012) (xy 182.118365 -289.487968) (xy 182.153858 -289.52206) (xy 182.183423 -289.561404)
			(xy 182.206294 -289.604981) (xy 182.221878 -289.651662) (xy 182.229773 -289.700239) (xy 182.230268 -289.724846)
			(xy 182.569116 -289.724846) (xy 182.573076 -289.675792) (xy 182.584853 -289.628008) (xy 182.604144 -289.582732)
			(xy 182.630447 -289.541136) (xy 182.663082 -289.504299) (xy 182.701203 -289.473174) (xy 182.743824 -289.448567)
			(xy 182.78984 -289.431115) (xy 182.838059 -289.421271) (xy 182.887234 -289.41929) (xy 182.936089 -289.425222)
			(xy 182.98336 -289.438914) (xy 183.027822 -289.460012) (xy 183.068325 -289.487968) (xy 183.103818 -289.52206)
			(xy 183.133383 -289.561404) (xy 183.156254 -289.604981) (xy 183.171838 -289.651662) (xy 183.179733 -289.700239)
			(xy 183.180228 -289.724846) (xy 183.519076 -289.724846) (xy 183.523036 -289.675792) (xy 183.534813 -289.628008)
			(xy 183.554104 -289.582732) (xy 183.580407 -289.541136) (xy 183.613042 -289.504299) (xy 183.651163 -289.473174)
			(xy 183.693784 -289.448567) (xy 183.7398 -289.431115) (xy 183.788019 -289.421271) (xy 183.837194 -289.41929)
			(xy 183.886049 -289.425222) (xy 183.93332 -289.438914) (xy 183.977782 -289.460012) (xy 184.018285 -289.487968)
			(xy 184.053778 -289.52206) (xy 184.083343 -289.561404) (xy 184.106214 -289.604981) (xy 184.121798 -289.651662)
			(xy 184.129693 -289.700239) (xy 184.130188 -289.724846) (xy 184.469036 -289.724846) (xy 184.472996 -289.675792)
			(xy 184.484773 -289.628008) (xy 184.504064 -289.582732) (xy 184.530367 -289.541136) (xy 184.563002 -289.504299)
			(xy 184.601123 -289.473174) (xy 184.643744 -289.448567) (xy 184.68976 -289.431115) (xy 184.737979 -289.421271)
			(xy 184.787154 -289.41929) (xy 184.836009 -289.425222) (xy 184.88328 -289.438914) (xy 184.927742 -289.460012)
			(xy 184.968245 -289.487968) (xy 185.003738 -289.52206) (xy 185.033303 -289.561404) (xy 185.056174 -289.604981)
			(xy 185.071758 -289.651662) (xy 185.079653 -289.700239) (xy 185.080148 -289.724846) (xy 185.41925 -289.724846)
			(xy 185.42321 -289.675792) (xy 185.434987 -289.628008) (xy 185.454278 -289.582732) (xy 185.480581 -289.541136)
			(xy 185.513216 -289.504299) (xy 185.551337 -289.473174) (xy 185.593958 -289.448567) (xy 185.639974 -289.431115)
			(xy 185.688193 -289.421271) (xy 185.737368 -289.41929) (xy 185.786223 -289.425222) (xy 185.833494 -289.438914)
			(xy 185.877956 -289.460012) (xy 185.918459 -289.487968) (xy 185.953952 -289.52206) (xy 185.983517 -289.561404)
			(xy 186.006388 -289.604981) (xy 186.021972 -289.651662) (xy 186.029867 -289.700239) (xy 186.030362 -289.724846)
			(xy 186.36921 -289.724846) (xy 186.37317 -289.675792) (xy 186.384947 -289.628008) (xy 186.404238 -289.582732)
			(xy 186.430541 -289.541136) (xy 186.463176 -289.504299) (xy 186.501297 -289.473174) (xy 186.543918 -289.448567)
			(xy 186.589934 -289.431115) (xy 186.638153 -289.421271) (xy 186.687328 -289.41929) (xy 186.736183 -289.425222)
			(xy 186.783454 -289.438914) (xy 186.827916 -289.460012) (xy 186.868419 -289.487968) (xy 186.903912 -289.52206)
			(xy 186.933477 -289.561404) (xy 186.956348 -289.604981) (xy 186.971932 -289.651662) (xy 186.979827 -289.700239)
			(xy 186.980322 -289.724846) (xy 187.31917 -289.724846) (xy 187.32313 -289.675792) (xy 187.334907 -289.628008)
			(xy 187.354198 -289.582732) (xy 187.380501 -289.541136) (xy 187.413136 -289.504299) (xy 187.451257 -289.473174)
			(xy 187.493878 -289.448567) (xy 187.539894 -289.431115) (xy 187.588113 -289.421271) (xy 187.637288 -289.41929)
			(xy 187.686143 -289.425222) (xy 187.733414 -289.438914) (xy 187.777876 -289.460012) (xy 187.818379 -289.487968)
			(xy 187.853872 -289.52206) (xy 187.883437 -289.561404) (xy 187.906308 -289.604981) (xy 187.921892 -289.651662)
			(xy 187.929787 -289.700239) (xy 187.930282 -289.724846) (xy 188.26913 -289.724846) (xy 188.27309 -289.675792)
			(xy 188.284867 -289.628008) (xy 188.304158 -289.582732) (xy 188.330461 -289.541136) (xy 188.363096 -289.504299)
			(xy 188.401217 -289.473174) (xy 188.443838 -289.448567) (xy 188.489854 -289.431115) (xy 188.538073 -289.421271)
			(xy 188.587248 -289.41929) (xy 188.636103 -289.425222) (xy 188.683374 -289.438914) (xy 188.727836 -289.460012)
			(xy 188.768339 -289.487968) (xy 188.803832 -289.52206) (xy 188.833397 -289.561404) (xy 188.856268 -289.604981)
			(xy 188.871852 -289.651662) (xy 188.879747 -289.700239) (xy 188.880074 -289.716508) (xy 189.219227 -289.716508)
			(xy 189.224595 -289.667167) (xy 189.237875 -289.619344) (xy 189.258716 -289.574299) (xy 189.28657 -289.53322)
			(xy 189.320702 -289.497187) (xy 189.360214 -289.467151) (xy 189.404065 -289.443903) (xy 189.451099 -289.428054)
			(xy 189.500078 -289.420024) (xy 189.524894 -289.419538) (xy 189.539077 -289.419715) (xy 189.567317 -289.422387)
			(xy 189.581282 -289.424872) (xy 189.593728 -289.427158) (xy 189.61735 -289.419792) (xy 189.69482 -289.342322)
			(xy 189.702186 -289.3187) (xy 189.6999 -289.306254) (xy 189.697421 -289.292289) (xy 189.694751 -289.264049)
			(xy 189.694566 -289.249866) (xy 189.695088 -289.224611) (xy 189.703401 -289.174789) (xy 189.719802 -289.127015)
			(xy 189.743843 -289.082592) (xy 189.774867 -289.042732) (xy 189.812029 -289.008522) (xy 189.854315 -288.980896)
			(xy 189.900571 -288.960606) (xy 189.949536 -288.948206) (xy 189.999874 -288.944035) (xy 190.050212 -288.948206)
			(xy 190.099177 -288.960606) (xy 190.145433 -288.980896) (xy 190.187719 -289.008522) (xy 190.224881 -289.042732)
			(xy 190.255905 -289.082592) (xy 190.279946 -289.127015) (xy 190.296347 -289.174789) (xy 190.30466 -289.224611)
			(xy 190.305182 -289.249866) (xy 190.305001 -289.264049) (xy 190.302332 -289.292289) (xy 190.299848 -289.306254)
			(xy 190.297562 -289.3187) (xy 190.304928 -289.342576) (xy 190.382144 -289.419792) (xy 190.406274 -289.427158)
			(xy 190.418466 -289.424872) (xy 190.432494 -289.422381) (xy 190.460862 -289.419713) (xy 190.475108 -289.419538)
			(xy 190.499927 -289.419986) (xy 190.548912 -289.428018) (xy 190.595952 -289.443868) (xy 190.639808 -289.46712)
			(xy 190.679325 -289.49716) (xy 190.713461 -289.533197) (xy 190.741318 -289.574282) (xy 190.762162 -289.619332)
			(xy 190.775442 -289.667161) (xy 190.780811 -289.716509) (xy 190.780359 -289.724846) (xy 192.069224 -289.724846)
			(xy 192.073184 -289.675792) (xy 192.084961 -289.628008) (xy 192.104252 -289.582732) (xy 192.130555 -289.541136)
			(xy 192.16319 -289.504299) (xy 192.201311 -289.473174) (xy 192.243932 -289.448567) (xy 192.289948 -289.431115)
			(xy 192.338167 -289.421271) (xy 192.387342 -289.41929) (xy 192.436197 -289.425222) (xy 192.483468 -289.438914)
			(xy 192.52793 -289.460012) (xy 192.568433 -289.487968) (xy 192.603926 -289.52206) (xy 192.633491 -289.561404)
			(xy 192.656362 -289.604981) (xy 192.671946 -289.651662) (xy 192.679841 -289.700239) (xy 192.680336 -289.724846)
			(xy 193.019184 -289.724846) (xy 193.023144 -289.675792) (xy 193.034921 -289.628008) (xy 193.054212 -289.582732)
			(xy 193.080515 -289.541136) (xy 193.11315 -289.504299) (xy 193.151271 -289.473174) (xy 193.193892 -289.448567)
			(xy 193.239908 -289.431115) (xy 193.288127 -289.421271) (xy 193.337302 -289.41929) (xy 193.386157 -289.425222)
			(xy 193.433428 -289.438914) (xy 193.47789 -289.460012) (xy 193.518393 -289.487968) (xy 193.553886 -289.52206)
			(xy 193.583451 -289.561404) (xy 193.606322 -289.604981) (xy 193.621906 -289.651662) (xy 193.629801 -289.700239)
			(xy 193.630296 -289.724846) (xy 193.969144 -289.724846) (xy 193.973104 -289.675792) (xy 193.984881 -289.628008)
			(xy 194.004172 -289.582732) (xy 194.030475 -289.541136) (xy 194.06311 -289.504299) (xy 194.101231 -289.473174)
			(xy 194.143852 -289.448567) (xy 194.189868 -289.431115) (xy 194.238087 -289.421271) (xy 194.287262 -289.41929)
			(xy 194.336117 -289.425222) (xy 194.383388 -289.438914) (xy 194.42785 -289.460012) (xy 194.468353 -289.487968)
			(xy 194.503846 -289.52206) (xy 194.533411 -289.561404) (xy 194.556282 -289.604981) (xy 194.571866 -289.651662)
			(xy 194.579761 -289.700239) (xy 194.580088 -289.716499) (xy 194.919228 -289.716499) (xy 194.924597 -289.667157)
			(xy 194.937878 -289.619334) (xy 194.958721 -289.57429) (xy 194.986577 -289.533211) (xy 195.020711 -289.497179)
			(xy 195.060225 -289.467144) (xy 195.104077 -289.443897) (xy 195.151112 -289.428051) (xy 195.200092 -289.420023)
			(xy 195.224908 -289.419538) (xy 195.239091 -289.419713) (xy 195.267331 -289.422386) (xy 195.281296 -289.424872)
			(xy 195.293742 -289.427158) (xy 195.317364 -289.419792) (xy 195.394834 -289.342322) (xy 195.4022 -289.3187)
			(xy 195.399914 -289.306254) (xy 195.397435 -289.292288) (xy 195.394765 -289.264049) (xy 195.39458 -289.249866)
			(xy 195.395102 -289.224611) (xy 195.403415 -289.174789) (xy 195.419816 -289.127015) (xy 195.443857 -289.082592)
			(xy 195.474881 -289.042732) (xy 195.512043 -289.008522) (xy 195.554329 -288.980896) (xy 195.600585 -288.960606)
			(xy 195.64955 -288.948206) (xy 195.699888 -288.944035) (xy 195.750226 -288.948206) (xy 195.799191 -288.960606)
			(xy 195.845447 -288.980896) (xy 195.887733 -289.008522) (xy 195.924895 -289.042732) (xy 195.955919 -289.082592)
			(xy 195.957233 -289.08502) (xy 201.887834 -289.08502) (xy 201.891905 -289.029398) (xy 201.904031 -288.974961)
			(xy 201.923954 -288.92287) (xy 201.95125 -288.874235) (xy 201.985336 -288.830092) (xy 202.025485 -288.791383)
			(xy 202.070843 -288.758932) (xy 202.120443 -288.733431) (xy 202.173227 -288.715424) (xy 202.22807 -288.705294)
			(xy 202.283804 -288.703257) (xy 202.339241 -288.709357) (xy 202.393198 -288.723463) (xy 202.444527 -288.745275)
			(xy 202.492133 -288.774329) (xy 202.535001 -288.810004) (xy 202.553604 -288.830766) (xy 209.253072 -288.830766)
			(xy 209.257143 -288.775144) (xy 209.269269 -288.720707) (xy 209.289192 -288.668616) (xy 209.316488 -288.619981)
			(xy 209.350574 -288.575838) (xy 209.390723 -288.537129) (xy 209.436081 -288.504678) (xy 209.485681 -288.479177)
			(xy 209.538465 -288.46117) (xy 209.593308 -288.45104) (xy 209.649042 -288.449003) (xy 209.704479 -288.455103)
			(xy 209.758436 -288.469209) (xy 209.809765 -288.491021) (xy 209.857371 -288.520075) (xy 209.900239 -288.55575)
			(xy 209.937456 -288.597287) (xy 209.968229 -288.6438) (xy 209.984942 -288.679453) (xy 227.781559 -288.679453)
			(xy 227.781559 -288.624947) (xy 227.789317 -288.570995) (xy 227.804673 -288.518697) (xy 227.827316 -288.469117)
			(xy 227.856785 -288.423264) (xy 227.89248 -288.382071) (xy 227.933673 -288.346378) (xy 227.979527 -288.31691)
			(xy 228.029108 -288.294269) (xy 228.081407 -288.278914) (xy 228.135359 -288.271159) (xy 228.162612 -288.270696)
			(xy 228.189216 -288.271137) (xy 228.24191 -288.278521) (xy 228.293065 -288.293156) (xy 228.34169 -288.31476)
			(xy 228.38684 -288.342913) (xy 228.427639 -288.377068) (xy 228.463295 -288.416562) (xy 228.478588 -288.438336)
			(xy 228.486079 -288.448296) (xy 228.508053 -288.460003) (xy 228.520498 -288.460688) (xy 228.604826 -288.460688)
			(xy 228.617276 -288.460012) (xy 228.639254 -288.448307) (xy 228.646736 -288.438336) (xy 228.662058 -288.416586)
			(xy 228.69772 -288.377106) (xy 228.738519 -288.342962) (xy 228.783664 -288.314814) (xy 228.832281 -288.293208)
			(xy 228.883427 -288.278563) (xy 228.936111 -288.271163) (xy 228.962712 -288.270696) (xy 228.991375 -288.271229)
			(xy 229.048055 -288.279806) (xy 229.102814 -288.296764) (xy 229.154421 -288.321724) (xy 229.178358 -288.337498)
			(xy 229.186994 -288.34334) (xy 229.206298 -288.347404) (xy 229.296722 -288.330894) (xy 229.313232 -288.320226)
			(xy 229.319074 -288.311844) (xy 229.334965 -288.289939) (xy 229.371937 -288.25042) (xy 229.392734 -288.233104)
			(xy 229.40264 -288.22523) (xy 229.412292 -288.203386) (xy 229.406958 -288.096452) (xy 229.39502 -288.075624)
			(xy 229.384606 -288.068766) (xy 229.362139 -288.053604) (xy 229.321344 -288.017916) (xy 229.286012 -287.976814)
			(xy 229.256852 -287.931124) (xy 229.234454 -287.881767) (xy 229.219267 -287.829737) (xy 229.211598 -287.776081)
			(xy 229.211124 -287.74898) (xy 229.21161 -287.721729) (xy 229.219366 -287.667781) (xy 229.234721 -287.615486)
			(xy 229.257363 -287.565909) (xy 229.286829 -287.520059) (xy 229.32252 -287.478868) (xy 229.363711 -287.443177)
			(xy 229.409561 -287.413711) (xy 229.459138 -287.391069) (xy 229.511433 -287.375714) (xy 229.565381 -287.367958)
			(xy 229.619883 -287.367958) (xy 229.673831 -287.375714) (xy 229.726126 -287.391069) (xy 229.775703 -287.413711)
			(xy 229.821553 -287.443177) (xy 229.862744 -287.478868) (xy 229.898435 -287.520059) (xy 229.927901 -287.565909)
			(xy 229.950543 -287.615486) (xy 229.965898 -287.667781) (xy 229.973654 -287.721729) (xy 229.97414 -287.74898)
			(xy 229.97358 -287.777382) (xy 229.965173 -287.83356) (xy 229.948526 -287.887869) (xy 229.924009 -287.939109)
			(xy 229.892163 -287.986146) (xy 229.853694 -288.02794) (xy 229.8319 -288.04616) (xy 229.821994 -288.054034)
			(xy 229.812342 -288.075878) (xy 229.817676 -288.182812) (xy 229.829614 -288.20364) (xy 229.840028 -288.210498)
			(xy 229.862464 -288.225705) (xy 229.903262 -288.261383) (xy 229.938599 -288.302476) (xy 229.967763 -288.348158)
			(xy 229.990167 -288.397509) (xy 230.005359 -288.449534) (xy 230.013033 -288.503185) (xy 230.01351 -288.530284)
			(xy 230.01303 -288.557536) (xy 230.005275 -288.611487) (xy 229.989921 -288.663784) (xy 229.967281 -288.713364)
			(xy 229.937815 -288.759217) (xy 229.902123 -288.80041) (xy 229.860931 -288.836104) (xy 229.81508 -288.865572)
			(xy 229.765501 -288.888215) (xy 229.713204 -288.903571) (xy 229.659254 -288.911329) (xy 229.632002 -288.911792)
			(xy 229.603339 -288.911254) (xy 229.546659 -288.902679) (xy 229.4919 -288.885722) (xy 229.440293 -288.860764)
			(xy 229.416356 -288.84499) (xy 229.40772 -288.839148) (xy 229.388416 -288.835084) (xy 229.297992 -288.851594)
			(xy 229.281482 -288.862262) (xy 229.27564 -288.870644) (xy 229.260267 -288.89188) (xy 229.224637 -288.930334)
			(xy 229.18408 -288.963553) (xy 229.139359 -288.99091) (xy 229.091317 -289.011892) (xy 229.040855 -289.026103)
			(xy 228.988924 -289.033277) (xy 228.962712 -289.033712) (xy 228.936109 -289.033249) (xy 228.883416 -289.025869)
			(xy 228.832261 -289.011237) (xy 228.783636 -288.989636) (xy 228.738486 -288.961487) (xy 228.697686 -288.927336)
			(xy 228.66203 -288.887845) (xy 228.646736 -288.866072) (xy 228.639232 -288.856124) (xy 228.617268 -288.84441)
			(xy 228.604826 -288.84372) (xy 228.520498 -288.84372) (xy 228.508041 -288.844348) (xy 228.486064 -288.856087)
			(xy 228.478588 -288.866072) (xy 228.463316 -288.887859) (xy 228.427646 -288.927338) (xy 228.386838 -288.961479)
			(xy 228.341684 -288.989622) (xy 228.293059 -289.011222) (xy 228.241906 -289.025859) (xy 228.189215 -289.03325)
			(xy 228.162612 -289.033712) (xy 228.135359 -289.033241) (xy 228.081407 -289.025486) (xy 228.029108 -289.010131)
			(xy 227.979527 -288.98749) (xy 227.933673 -288.958022) (xy 227.89248 -288.922329) (xy 227.856785 -288.881136)
			(xy 227.827316 -288.835283) (xy 227.804673 -288.785703) (xy 227.789317 -288.733405) (xy 227.781559 -288.679453)
			(xy 209.984942 -288.679453) (xy 209.991901 -288.694297) (xy 210.007969 -288.747704) (xy 210.016089 -288.80288)
			(xy 210.016598 -288.830766) (xy 210.016089 -288.858652) (xy 210.007969 -288.913828) (xy 209.991901 -288.967235)
			(xy 209.968229 -289.017732) (xy 209.937456 -289.064245) (xy 209.900239 -289.105782) (xy 209.857371 -289.141457)
			(xy 209.809765 -289.170511) (xy 209.758436 -289.192323) (xy 209.704479 -289.206429) (xy 209.649042 -289.212529)
			(xy 209.593308 -289.210492) (xy 209.538465 -289.200362) (xy 209.485681 -289.182355) (xy 209.436081 -289.156854)
			(xy 209.390723 -289.124403) (xy 209.350574 -289.085694) (xy 209.316488 -289.041551) (xy 209.289192 -288.992916)
			(xy 209.269269 -288.940825) (xy 209.257143 -288.886388) (xy 209.253072 -288.830766) (xy 202.553604 -288.830766)
			(xy 202.572218 -288.851541) (xy 202.602991 -288.898054) (xy 202.626663 -288.948551) (xy 202.642731 -289.001958)
			(xy 202.650851 -289.057134) (xy 202.65136 -289.08502) (xy 202.650851 -289.112906) (xy 202.642731 -289.168082)
			(xy 202.626663 -289.221489) (xy 202.602991 -289.271986) (xy 202.572218 -289.318499) (xy 202.535001 -289.360036)
			(xy 202.492133 -289.395711) (xy 202.454715 -289.418547) (xy 218.298322 -289.418547) (xy 218.298322 -289.364053)
			(xy 218.306077 -289.310115) (xy 218.321429 -289.257829) (xy 218.344065 -289.208259) (xy 218.373525 -289.162416)
			(xy 218.409209 -289.121231) (xy 218.45039 -289.085544) (xy 218.496231 -289.05608) (xy 218.545799 -289.03344)
			(xy 218.598083 -289.018084) (xy 218.652021 -289.010324) (xy 218.679268 -289.009836) (xy 218.706638 -289.010312)
			(xy 218.760817 -289.018126) (xy 218.81332 -289.033612) (xy 218.863067 -289.056452) (xy 218.909034 -289.086175)
			(xy 218.929966 -289.103816) (xy 218.937078 -289.109912) (xy 218.954096 -289.116262) (xy 219.03944 -289.116262)
			(xy 219.056458 -289.109912) (xy 219.06357 -289.103816) (xy 219.084505 -289.08618) (xy 219.130476 -289.056467)
			(xy 219.180223 -289.03363) (xy 219.232724 -289.018139) (xy 219.286899 -289.01031) (xy 219.314268 -289.009836)
			(xy 219.341526 -289.010209) (xy 219.395486 -289.017963) (xy 219.447794 -289.033318) (xy 219.497384 -289.055961)
			(xy 219.543246 -289.085432) (xy 219.584448 -289.12113) (xy 219.620149 -289.162328) (xy 219.649623 -289.208188)
			(xy 219.672271 -289.257776) (xy 219.68763 -289.310083) (xy 219.695389 -289.364043) (xy 219.695389 -289.418546)
			(xy 220.259722 -289.418546) (xy 220.259722 -289.364054) (xy 220.267476 -289.310116) (xy 220.282828 -289.257831)
			(xy 220.305463 -289.208263) (xy 220.334922 -289.16242) (xy 220.370604 -289.121235) (xy 220.411784 -289.085548)
			(xy 220.457624 -289.056084) (xy 220.50719 -289.033443) (xy 220.559473 -289.018086) (xy 220.61341 -289.010325)
			(xy 220.640656 -289.009836) (xy 220.670778 -289.010438) (xy 220.730273 -289.019912) (xy 220.78754 -289.038616)
			(xy 220.841158 -289.066085) (xy 220.889794 -289.101636) (xy 220.91142 -289.122612) (xy 220.918532 -289.129978)
			(xy 220.937328 -289.137598) (xy 221.029784 -289.137598) (xy 221.04858 -289.129978) (xy 221.055692 -289.122612)
			(xy 221.077299 -289.101613) (xy 221.125933 -289.066046) (xy 221.179553 -289.03857) (xy 221.236828 -289.019866)
			(xy 221.29633 -289.010401) (xy 221.326456 -289.009836) (xy 221.353714 -289.010208) (xy 221.407676 -289.017961)
			(xy 221.459985 -289.033315) (xy 221.509577 -289.055957) (xy 221.555441 -289.085428) (xy 221.596643 -289.121125)
			(xy 221.632346 -289.162324) (xy 221.661822 -289.208185) (xy 221.68447 -289.257773) (xy 221.69983 -289.310081)
			(xy 221.707589 -289.364042) (xy 221.707589 -289.418558) (xy 221.69983 -289.472519) (xy 221.68447 -289.524827)
			(xy 221.661822 -289.574415) (xy 221.632346 -289.620276) (xy 221.596643 -289.661475) (xy 221.555441 -289.697172)
			(xy 221.509577 -289.726643) (xy 221.459985 -289.749285) (xy 221.407676 -289.764639) (xy 221.353714 -289.772392)
			(xy 221.326456 -289.772852) (xy 221.296334 -289.772245) (xy 221.236839 -289.762773) (xy 221.179572 -289.74407)
			(xy 221.125954 -289.716602) (xy 221.077318 -289.681051) (xy 221.055692 -289.660076) (xy 221.04858 -289.65271)
			(xy 221.029784 -289.64509) (xy 220.937328 -289.64509) (xy 220.918532 -289.65271) (xy 220.91142 -289.660076)
			(xy 220.889806 -289.681068) (xy 220.841174 -289.716635) (xy 220.787555 -289.744114) (xy 220.730283 -289.762819)
			(xy 220.670781 -289.772286) (xy 220.640656 -289.772852) (xy 220.61341 -289.772275) (xy 220.559473 -289.764514)
			(xy 220.50719 -289.749157) (xy 220.457624 -289.726516) (xy 220.411784 -289.697052) (xy 220.370604 -289.661365)
			(xy 220.334922 -289.62018) (xy 220.305463 -289.574337) (xy 220.282828 -289.524769) (xy 220.267476 -289.472484)
			(xy 220.259722 -289.418546) (xy 219.695389 -289.418546) (xy 219.695389 -289.418557) (xy 219.68763 -289.472517)
			(xy 219.672271 -289.524824) (xy 219.649623 -289.574412) (xy 219.620149 -289.620272) (xy 219.584448 -289.66147)
			(xy 219.543246 -289.697168) (xy 219.497384 -289.726639) (xy 219.447794 -289.749282) (xy 219.395486 -289.764637)
			(xy 219.341526 -289.772391) (xy 219.314268 -289.772852) (xy 219.286897 -289.772416) (xy 219.232716 -289.764593)
			(xy 219.180212 -289.749097) (xy 219.130465 -289.726249) (xy 219.0845 -289.696517) (xy 219.06357 -289.678872)
			(xy 219.056458 -289.672776) (xy 219.03944 -289.666426) (xy 218.954096 -289.666426) (xy 218.937078 -289.672776)
			(xy 218.929966 -289.678872) (xy 218.909016 -289.696489) (xy 218.863049 -289.726205) (xy 218.813306 -289.749046)
			(xy 218.760809 -289.764542) (xy 218.706636 -289.772375) (xy 218.679268 -289.772852) (xy 218.652021 -289.772276)
			(xy 218.598083 -289.764516) (xy 218.545799 -289.74916) (xy 218.496231 -289.72652) (xy 218.45039 -289.697056)
			(xy 218.409209 -289.661369) (xy 218.373525 -289.620184) (xy 218.344065 -289.574341) (xy 218.321429 -289.524771)
			(xy 218.306077 -289.472485) (xy 218.298322 -289.418547) (xy 202.454715 -289.418547) (xy 202.444527 -289.424765)
			(xy 202.393198 -289.446577) (xy 202.339241 -289.460683) (xy 202.283804 -289.466783) (xy 202.22807 -289.464746)
			(xy 202.173227 -289.454616) (xy 202.120443 -289.436609) (xy 202.070843 -289.411108) (xy 202.025485 -289.378657)
			(xy 201.985336 -289.339948) (xy 201.95125 -289.295805) (xy 201.923954 -289.24717) (xy 201.904031 -289.195079)
			(xy 201.891905 -289.140642) (xy 201.887834 -289.08502) (xy 195.957233 -289.08502) (xy 195.97996 -289.127015)
			(xy 195.996361 -289.174789) (xy 196.004674 -289.224611) (xy 196.005196 -289.249866) (xy 196.005015 -289.264049)
			(xy 196.002346 -289.292289) (xy 195.999862 -289.306254) (xy 195.997576 -289.3187) (xy 196.004942 -289.342322)
			(xy 196.082412 -289.419792) (xy 196.106034 -289.427158) (xy 196.11848 -289.424872) (xy 196.132445 -289.422388)
			(xy 196.160685 -289.419721) (xy 196.174868 -289.419538) (xy 196.199691 -289.419943) (xy 196.248685 -289.42797)
			(xy 196.295734 -289.443817) (xy 196.3396 -289.467067) (xy 196.379126 -289.497107) (xy 196.413272 -289.533147)
			(xy 196.441138 -289.574235) (xy 196.461989 -289.619291) (xy 196.475276 -289.667126) (xy 196.48065 -289.716481)
			(xy 196.480197 -289.724846) (xy 196.819278 -289.724846) (xy 196.823238 -289.675792) (xy 196.835015 -289.628008)
			(xy 196.854306 -289.582732) (xy 196.880609 -289.541136) (xy 196.913244 -289.504299) (xy 196.951365 -289.473174)
			(xy 196.993986 -289.448567) (xy 197.040002 -289.431115) (xy 197.088221 -289.421271) (xy 197.137396 -289.41929)
			(xy 197.186251 -289.425222) (xy 197.233522 -289.438914) (xy 197.277984 -289.460012) (xy 197.318487 -289.487968)
			(xy 197.35398 -289.52206) (xy 197.383545 -289.561404) (xy 197.406416 -289.604981) (xy 197.422 -289.651662)
			(xy 197.429895 -289.700239) (xy 197.43039 -289.724846) (xy 197.769238 -289.724846) (xy 197.773198 -289.675792)
			(xy 197.784975 -289.628008) (xy 197.804266 -289.582732) (xy 197.830569 -289.541136) (xy 197.863204 -289.504299)
			(xy 197.901325 -289.473174) (xy 197.943946 -289.448567) (xy 197.989962 -289.431115) (xy 198.038181 -289.421271)
			(xy 198.087356 -289.41929) (xy 198.136211 -289.425222) (xy 198.183482 -289.438914) (xy 198.227944 -289.460012)
			(xy 198.268447 -289.487968) (xy 198.30394 -289.52206) (xy 198.333505 -289.561404) (xy 198.356376 -289.604981)
			(xy 198.37196 -289.651662) (xy 198.379855 -289.700239) (xy 198.38035 -289.724846) (xy 198.719198 -289.724846)
			(xy 198.723158 -289.675792) (xy 198.734935 -289.628008) (xy 198.754226 -289.582732) (xy 198.780529 -289.541136)
			(xy 198.813164 -289.504299) (xy 198.851285 -289.473174) (xy 198.893906 -289.448567) (xy 198.939922 -289.431115)
			(xy 198.988141 -289.421271) (xy 199.037316 -289.41929) (xy 199.086171 -289.425222) (xy 199.133442 -289.438914)
			(xy 199.177904 -289.460012) (xy 199.218407 -289.487968) (xy 199.2539 -289.52206) (xy 199.283465 -289.561404)
			(xy 199.306336 -289.604981) (xy 199.32192 -289.651662) (xy 199.329815 -289.700239) (xy 199.33031 -289.724846)
			(xy 199.329815 -289.749453) (xy 199.32192 -289.79803) (xy 199.306336 -289.844711) (xy 199.283465 -289.888288)
			(xy 199.2539 -289.927632) (xy 199.218407 -289.961724) (xy 199.177904 -289.98968) (xy 199.133442 -290.010778)
			(xy 199.086171 -290.02447) (xy 199.037316 -290.030402) (xy 198.988141 -290.028421) (xy 198.939922 -290.018577)
			(xy 198.893906 -290.001125) (xy 198.851285 -289.976518) (xy 198.813164 -289.945393) (xy 198.780529 -289.908556)
			(xy 198.754226 -289.86696) (xy 198.734935 -289.821684) (xy 198.723158 -289.7739) (xy 198.719198 -289.724846)
			(xy 198.38035 -289.724846) (xy 198.379855 -289.749453) (xy 198.37196 -289.79803) (xy 198.356376 -289.844711)
			(xy 198.333505 -289.888288) (xy 198.30394 -289.927632) (xy 198.268447 -289.961724) (xy 198.227944 -289.98968)
			(xy 198.183482 -290.010778) (xy 198.136211 -290.02447) (xy 198.087356 -290.030402) (xy 198.038181 -290.028421)
			(xy 197.989962 -290.018577) (xy 197.943946 -290.001125) (xy 197.901325 -289.976518) (xy 197.863204 -289.945393)
			(xy 197.830569 -289.908556) (xy 197.804266 -289.86696) (xy 197.784975 -289.821684) (xy 197.773198 -289.7739)
			(xy 197.769238 -289.724846) (xy 197.43039 -289.724846) (xy 197.429895 -289.749453) (xy 197.422 -289.79803)
			(xy 197.406416 -289.844711) (xy 197.383545 -289.888288) (xy 197.35398 -289.927632) (xy 197.318487 -289.961724)
			(xy 197.277984 -289.98968) (xy 197.233522 -290.010778) (xy 197.186251 -290.02447) (xy 197.137396 -290.030402)
			(xy 197.088221 -290.028421) (xy 197.040002 -290.018577) (xy 196.993986 -290.001125) (xy 196.951365 -289.976518)
			(xy 196.913244 -289.945393) (xy 196.880609 -289.908556) (xy 196.854306 -289.86696) (xy 196.835015 -289.821684)
			(xy 196.823238 -289.7739) (xy 196.819278 -289.724846) (xy 196.480197 -289.724846) (xy 196.477968 -289.766055)
			(xy 196.467301 -289.814542) (xy 196.448931 -289.860664) (xy 196.423341 -289.903207) (xy 196.391205 -289.94105)
			(xy 196.353371 -289.973195) (xy 196.310834 -289.998796) (xy 196.264716 -290.017178) (xy 196.216232 -290.027857)
			(xy 196.166659 -290.030552) (xy 196.117303 -290.025191) (xy 196.069464 -290.011916) (xy 196.024403 -289.991076)
			(xy 195.983308 -289.963221) (xy 195.94726 -289.929084) (xy 195.917209 -289.889565) (xy 195.893948 -289.845706)
			(xy 195.878089 -289.79866) (xy 195.87005 -289.749669) (xy 195.86956 -289.724846) (xy 195.869744 -289.710663)
			(xy 195.872411 -289.682423) (xy 195.874894 -289.668458) (xy 195.87718 -289.656012) (xy 195.869814 -289.63239)
			(xy 195.792344 -289.55492) (xy 195.768722 -289.547554) (xy 195.756276 -289.54984) (xy 195.74231 -289.552315)
			(xy 195.71407 -289.554988) (xy 195.699888 -289.555174) (xy 195.685705 -289.555) (xy 195.657465 -289.552326)
			(xy 195.6435 -289.54984) (xy 195.631054 -289.547554) (xy 195.607432 -289.55492) (xy 195.529962 -289.63239)
			(xy 195.522596 -289.656012) (xy 195.524882 -289.668458) (xy 195.527362 -289.682423) (xy 195.530032 -289.710663)
			(xy 195.530216 -289.724846) (xy 195.529673 -289.749662) (xy 195.521636 -289.79864) (xy 195.505781 -289.845673)
			(xy 195.482527 -289.889521) (xy 195.452485 -289.929029) (xy 195.416447 -289.963157) (xy 195.375363 -289.991005)
			(xy 195.330315 -290.01184) (xy 195.282489 -290.025113) (xy 195.233147 -290.030474) (xy 195.183587 -290.027781)
			(xy 195.135116 -290.017107) (xy 195.08901 -289.998731) (xy 195.046484 -289.973139) (xy 195.008658 -289.941004)
			(xy 194.97653 -289.903172) (xy 194.950945 -289.860642) (xy 194.932577 -289.814533) (xy 194.921911 -289.766059)
			(xy 194.919228 -289.716499) (xy 194.580088 -289.716499) (xy 194.580256 -289.724846) (xy 194.579761 -289.749453)
			(xy 194.571866 -289.79803) (xy 194.556282 -289.844711) (xy 194.533411 -289.888288) (xy 194.503846 -289.927632)
			(xy 194.468353 -289.961724) (xy 194.42785 -289.98968) (xy 194.383388 -290.010778) (xy 194.336117 -290.02447)
			(xy 194.287262 -290.030402) (xy 194.238087 -290.028421) (xy 194.189868 -290.018577) (xy 194.143852 -290.001125)
			(xy 194.101231 -289.976518) (xy 194.06311 -289.945393) (xy 194.030475 -289.908556) (xy 194.004172 -289.86696)
			(xy 193.984881 -289.821684) (xy 193.973104 -289.7739) (xy 193.969144 -289.724846) (xy 193.630296 -289.724846)
			(xy 193.629801 -289.749453) (xy 193.621906 -289.79803) (xy 193.606322 -289.844711) (xy 193.583451 -289.888288)
			(xy 193.553886 -289.927632) (xy 193.518393 -289.961724) (xy 193.47789 -289.98968) (xy 193.433428 -290.010778)
			(xy 193.386157 -290.02447) (xy 193.337302 -290.030402) (xy 193.288127 -290.028421) (xy 193.239908 -290.018577)
			(xy 193.193892 -290.001125) (xy 193.151271 -289.976518) (xy 193.11315 -289.945393) (xy 193.080515 -289.908556)
			(xy 193.054212 -289.86696) (xy 193.034921 -289.821684) (xy 193.023144 -289.7739) (xy 193.019184 -289.724846)
			(xy 192.680336 -289.724846) (xy 192.679841 -289.749453) (xy 192.671946 -289.79803) (xy 192.656362 -289.844711)
			(xy 192.633491 -289.888288) (xy 192.603926 -289.927632) (xy 192.568433 -289.961724) (xy 192.52793 -289.98968)
			(xy 192.483468 -290.010778) (xy 192.436197 -290.02447) (xy 192.387342 -290.030402) (xy 192.338167 -290.028421)
			(xy 192.289948 -290.018577) (xy 192.243932 -290.001125) (xy 192.201311 -289.976518) (xy 192.16319 -289.945393)
			(xy 192.130555 -289.908556) (xy 192.104252 -289.86696) (xy 192.084961 -289.821684) (xy 192.073184 -289.7739)
			(xy 192.069224 -289.724846) (xy 190.780359 -289.724846) (xy 190.778125 -289.766075) (xy 190.767456 -289.814553)
			(xy 190.749085 -289.860667) (xy 190.723496 -289.903202) (xy 190.691363 -289.941036) (xy 190.653532 -289.973174)
			(xy 190.611001 -289.998768) (xy 190.564889 -290.017145) (xy 190.516412 -290.02782) (xy 190.466847 -290.030512)
			(xy 190.417499 -290.025149) (xy 190.369668 -290.011875) (xy 190.324615 -289.991037) (xy 190.283527 -289.963185)
			(xy 190.247485 -289.929053) (xy 190.21744 -289.88954) (xy 190.194183 -289.845687) (xy 190.178327 -289.798649)
			(xy 190.17029 -289.749665) (xy 190.1698 -289.724846) (xy 190.169983 -289.710663) (xy 190.172651 -289.682423)
			(xy 190.175134 -289.668458) (xy 190.17742 -289.656012) (xy 190.170054 -289.632136) (xy 190.092838 -289.55492)
			(xy 190.068708 -289.547554) (xy 190.056516 -289.54984) (xy 190.042486 -289.55232) (xy 190.01412 -289.554995)
			(xy 189.999874 -289.555174) (xy 189.985691 -289.555002) (xy 189.957451 -289.552327) (xy 189.943486 -289.54984)
			(xy 189.93104 -289.547554) (xy 189.907418 -289.55492) (xy 189.829948 -289.63239) (xy 189.822582 -289.656012)
			(xy 189.824868 -289.668458) (xy 189.827348 -289.682423) (xy 189.830018 -289.710663) (xy 189.830202 -289.724846)
			(xy 189.829673 -289.749662) (xy 189.821636 -289.79864) (xy 189.805782 -289.845672) (xy 189.782528 -289.88952)
			(xy 189.752486 -289.929028) (xy 189.716449 -289.963156) (xy 189.675366 -289.991004) (xy 189.630318 -290.011839)
			(xy 189.582493 -290.025112) (xy 189.533151 -290.030474) (xy 189.483592 -290.027782) (xy 189.435121 -290.017108)
			(xy 189.389015 -289.998734) (xy 189.346489 -289.973142) (xy 189.308663 -289.941008) (xy 189.276534 -289.903179)
			(xy 189.250948 -289.860649) (xy 189.23258 -289.814541) (xy 189.221913 -289.766068) (xy 189.219227 -289.716508)
			(xy 188.880074 -289.716508) (xy 188.880242 -289.724846) (xy 188.879747 -289.749453) (xy 188.871852 -289.79803)
			(xy 188.856268 -289.844711) (xy 188.833397 -289.888288) (xy 188.803832 -289.927632) (xy 188.768339 -289.961724)
			(xy 188.727836 -289.98968) (xy 188.683374 -290.010778) (xy 188.636103 -290.02447) (xy 188.587248 -290.030402)
			(xy 188.538073 -290.028421) (xy 188.489854 -290.018577) (xy 188.443838 -290.001125) (xy 188.401217 -289.976518)
			(xy 188.363096 -289.945393) (xy 188.330461 -289.908556) (xy 188.304158 -289.86696) (xy 188.284867 -289.821684)
			(xy 188.27309 -289.7739) (xy 188.26913 -289.724846) (xy 187.930282 -289.724846) (xy 187.929787 -289.749453)
			(xy 187.921892 -289.79803) (xy 187.906308 -289.844711) (xy 187.883437 -289.888288) (xy 187.853872 -289.927632)
			(xy 187.818379 -289.961724) (xy 187.777876 -289.98968) (xy 187.733414 -290.010778) (xy 187.686143 -290.02447)
			(xy 187.637288 -290.030402) (xy 187.588113 -290.028421) (xy 187.539894 -290.018577) (xy 187.493878 -290.001125)
			(xy 187.451257 -289.976518) (xy 187.413136 -289.945393) (xy 187.380501 -289.908556) (xy 187.354198 -289.86696)
			(xy 187.334907 -289.821684) (xy 187.32313 -289.7739) (xy 187.31917 -289.724846) (xy 186.980322 -289.724846)
			(xy 186.979827 -289.749453) (xy 186.971932 -289.79803) (xy 186.956348 -289.844711) (xy 186.933477 -289.888288)
			(xy 186.903912 -289.927632) (xy 186.868419 -289.961724) (xy 186.827916 -289.98968) (xy 186.783454 -290.010778)
			(xy 186.736183 -290.02447) (xy 186.687328 -290.030402) (xy 186.638153 -290.028421) (xy 186.589934 -290.018577)
			(xy 186.543918 -290.001125) (xy 186.501297 -289.976518) (xy 186.463176 -289.945393) (xy 186.430541 -289.908556)
			(xy 186.404238 -289.86696) (xy 186.384947 -289.821684) (xy 186.37317 -289.7739) (xy 186.36921 -289.724846)
			(xy 186.030362 -289.724846) (xy 186.029867 -289.749453) (xy 186.021972 -289.79803) (xy 186.006388 -289.844711)
			(xy 185.983517 -289.888288) (xy 185.953952 -289.927632) (xy 185.918459 -289.961724) (xy 185.877956 -289.98968)
			(xy 185.833494 -290.010778) (xy 185.786223 -290.02447) (xy 185.737368 -290.030402) (xy 185.688193 -290.028421)
			(xy 185.639974 -290.018577) (xy 185.593958 -290.001125) (xy 185.551337 -289.976518) (xy 185.513216 -289.945393)
			(xy 185.480581 -289.908556) (xy 185.454278 -289.86696) (xy 185.434987 -289.821684) (xy 185.42321 -289.7739)
			(xy 185.41925 -289.724846) (xy 185.080148 -289.724846) (xy 185.079653 -289.749453) (xy 185.071758 -289.79803)
			(xy 185.056174 -289.844711) (xy 185.033303 -289.888288) (xy 185.003738 -289.927632) (xy 184.968245 -289.961724)
			(xy 184.927742 -289.98968) (xy 184.88328 -290.010778) (xy 184.836009 -290.02447) (xy 184.787154 -290.030402)
			(xy 184.737979 -290.028421) (xy 184.68976 -290.018577) (xy 184.643744 -290.001125) (xy 184.601123 -289.976518)
			(xy 184.563002 -289.945393) (xy 184.530367 -289.908556) (xy 184.504064 -289.86696) (xy 184.484773 -289.821684)
			(xy 184.472996 -289.7739) (xy 184.469036 -289.724846) (xy 184.130188 -289.724846) (xy 184.129693 -289.749453)
			(xy 184.121798 -289.79803) (xy 184.106214 -289.844711) (xy 184.083343 -289.888288) (xy 184.053778 -289.927632)
			(xy 184.018285 -289.961724) (xy 183.977782 -289.98968) (xy 183.93332 -290.010778) (xy 183.886049 -290.02447)
			(xy 183.837194 -290.030402) (xy 183.788019 -290.028421) (xy 183.7398 -290.018577) (xy 183.693784 -290.001125)
			(xy 183.651163 -289.976518) (xy 183.613042 -289.945393) (xy 183.580407 -289.908556) (xy 183.554104 -289.86696)
			(xy 183.534813 -289.821684) (xy 183.523036 -289.7739) (xy 183.519076 -289.724846) (xy 183.180228 -289.724846)
			(xy 183.179733 -289.749453) (xy 183.171838 -289.79803) (xy 183.156254 -289.844711) (xy 183.133383 -289.888288)
			(xy 183.103818 -289.927632) (xy 183.068325 -289.961724) (xy 183.027822 -289.98968) (xy 182.98336 -290.010778)
			(xy 182.936089 -290.02447) (xy 182.887234 -290.030402) (xy 182.838059 -290.028421) (xy 182.78984 -290.018577)
			(xy 182.743824 -290.001125) (xy 182.701203 -289.976518) (xy 182.663082 -289.945393) (xy 182.630447 -289.908556)
			(xy 182.604144 -289.86696) (xy 182.584853 -289.821684) (xy 182.573076 -289.7739) (xy 182.569116 -289.724846)
			(xy 182.230268 -289.724846) (xy 182.229773 -289.749453) (xy 182.221878 -289.79803) (xy 182.206294 -289.844711)
			(xy 182.183423 -289.888288) (xy 182.153858 -289.927632) (xy 182.118365 -289.961724) (xy 182.077862 -289.98968)
			(xy 182.0334 -290.010778) (xy 181.986129 -290.02447) (xy 181.937274 -290.030402) (xy 181.888099 -290.028421)
			(xy 181.83988 -290.018577) (xy 181.793864 -290.001125) (xy 181.751243 -289.976518) (xy 181.713122 -289.945393)
			(xy 181.680487 -289.908556) (xy 181.654184 -289.86696) (xy 181.634893 -289.821684) (xy 181.623116 -289.7739)
			(xy 181.619156 -289.724846) (xy 181.280308 -289.724846) (xy 181.279813 -289.749453) (xy 181.271918 -289.79803)
			(xy 181.256334 -289.844711) (xy 181.233463 -289.888288) (xy 181.203898 -289.927632) (xy 181.168405 -289.961724)
			(xy 181.127902 -289.98968) (xy 181.08344 -290.010778) (xy 181.036169 -290.02447) (xy 180.987314 -290.030402)
			(xy 180.938139 -290.028421) (xy 180.88992 -290.018577) (xy 180.843904 -290.001125) (xy 180.801283 -289.976518)
			(xy 180.763162 -289.945393) (xy 180.730527 -289.908556) (xy 180.704224 -289.86696) (xy 180.684933 -289.821684)
			(xy 180.673156 -289.7739) (xy 180.669196 -289.724846) (xy 180.330348 -289.724846) (xy 180.329853 -289.749453)
			(xy 180.321958 -289.79803) (xy 180.306374 -289.844711) (xy 180.283503 -289.888288) (xy 180.253938 -289.927632)
			(xy 180.218445 -289.961724) (xy 180.177942 -289.98968) (xy 180.13348 -290.010778) (xy 180.086209 -290.02447)
			(xy 180.037354 -290.030402) (xy 179.988179 -290.028421) (xy 179.93996 -290.018577) (xy 179.893944 -290.001125)
			(xy 179.851323 -289.976518) (xy 179.813202 -289.945393) (xy 179.780567 -289.908556) (xy 179.754264 -289.86696)
			(xy 179.734973 -289.821684) (xy 179.723196 -289.7739) (xy 179.719236 -289.724846) (xy 179.380388 -289.724846)
			(xy 179.379893 -289.749453) (xy 179.371998 -289.79803) (xy 179.356414 -289.844711) (xy 179.333543 -289.888288)
			(xy 179.303978 -289.927632) (xy 179.268485 -289.961724) (xy 179.227982 -289.98968) (xy 179.18352 -290.010778)
			(xy 179.136249 -290.02447) (xy 179.087394 -290.030402) (xy 179.038219 -290.028421) (xy 178.99 -290.018577)
			(xy 178.943984 -290.001125) (xy 178.901363 -289.976518) (xy 178.863242 -289.945393) (xy 178.830607 -289.908556)
			(xy 178.804304 -289.86696) (xy 178.785013 -289.821684) (xy 178.773236 -289.7739) (xy 178.769276 -289.724846)
			(xy 178.430174 -289.724846) (xy 178.429679 -289.749453) (xy 178.421784 -289.79803) (xy 178.4062 -289.844711)
			(xy 178.383329 -289.888288) (xy 178.353764 -289.927632) (xy 178.318271 -289.961724) (xy 178.277768 -289.98968)
			(xy 178.233306 -290.010778) (xy 178.186035 -290.02447) (xy 178.13718 -290.030402) (xy 178.088005 -290.028421)
			(xy 178.039786 -290.018577) (xy 177.99377 -290.001125) (xy 177.951149 -289.976518) (xy 177.913028 -289.945393)
			(xy 177.880393 -289.908556) (xy 177.85409 -289.86696) (xy 177.834799 -289.821684) (xy 177.823022 -289.7739)
			(xy 177.819062 -289.724846) (xy 177.480214 -289.724846) (xy 177.479719 -289.749453) (xy 177.471824 -289.79803)
			(xy 177.45624 -289.844711) (xy 177.433369 -289.888288) (xy 177.403804 -289.927632) (xy 177.368311 -289.961724)
			(xy 177.327808 -289.98968) (xy 177.283346 -290.010778) (xy 177.236075 -290.02447) (xy 177.18722 -290.030402)
			(xy 177.138045 -290.028421) (xy 177.089826 -290.018577) (xy 177.04381 -290.001125) (xy 177.001189 -289.976518)
			(xy 176.963068 -289.945393) (xy 176.930433 -289.908556) (xy 176.90413 -289.86696) (xy 176.884839 -289.821684)
			(xy 176.873062 -289.7739) (xy 176.869102 -289.724846) (xy 176.530254 -289.724846) (xy 176.529759 -289.749453)
			(xy 176.521864 -289.79803) (xy 176.50628 -289.844711) (xy 176.483409 -289.888288) (xy 176.453844 -289.927632)
			(xy 176.418351 -289.961724) (xy 176.377848 -289.98968) (xy 176.333386 -290.010778) (xy 176.286115 -290.02447)
			(xy 176.23726 -290.030402) (xy 176.188085 -290.028421) (xy 176.139866 -290.018577) (xy 176.09385 -290.001125)
			(xy 176.051229 -289.976518) (xy 176.013108 -289.945393) (xy 175.980473 -289.908556) (xy 175.95417 -289.86696)
			(xy 175.934879 -289.821684) (xy 175.923102 -289.7739) (xy 175.919142 -289.724846) (xy 174.630334 -289.724846)
			(xy 174.629839 -289.749453) (xy 174.621944 -289.79803) (xy 174.60636 -289.844711) (xy 174.583489 -289.888288)
			(xy 174.553924 -289.927632) (xy 174.518431 -289.961724) (xy 174.477928 -289.98968) (xy 174.433466 -290.010778)
			(xy 174.386195 -290.02447) (xy 174.33734 -290.030402) (xy 174.288165 -290.028421) (xy 174.239946 -290.018577)
			(xy 174.19393 -290.001125) (xy 174.151309 -289.976518) (xy 174.113188 -289.945393) (xy 174.080553 -289.908556)
			(xy 174.05425 -289.86696) (xy 174.034959 -289.821684) (xy 174.023182 -289.7739) (xy 174.019222 -289.724846)
			(xy 173.680374 -289.724846) (xy 173.679879 -289.749453) (xy 173.671984 -289.79803) (xy 173.6564 -289.844711)
			(xy 173.633529 -289.888288) (xy 173.603964 -289.927632) (xy 173.568471 -289.961724) (xy 173.527968 -289.98968)
			(xy 173.483506 -290.010778) (xy 173.436235 -290.02447) (xy 173.38738 -290.030402) (xy 173.338205 -290.028421)
			(xy 173.289986 -290.018577) (xy 173.24397 -290.001125) (xy 173.201349 -289.976518) (xy 173.163228 -289.945393)
			(xy 173.130593 -289.908556) (xy 173.10429 -289.86696) (xy 173.084999 -289.821684) (xy 173.073222 -289.7739)
			(xy 173.069262 -289.724846) (xy 172.73016 -289.724846) (xy 172.729665 -289.749453) (xy 172.72177 -289.79803)
			(xy 172.706186 -289.844711) (xy 172.683315 -289.888288) (xy 172.65375 -289.927632) (xy 172.618257 -289.961724)
			(xy 172.577754 -289.98968) (xy 172.533292 -290.010778) (xy 172.486021 -290.02447) (xy 172.437166 -290.030402)
			(xy 172.387991 -290.028421) (xy 172.339772 -290.018577) (xy 172.293756 -290.001125) (xy 172.251135 -289.976518)
			(xy 172.213014 -289.945393) (xy 172.180379 -289.908556) (xy 172.154076 -289.86696) (xy 172.134785 -289.821684)
			(xy 172.123008 -289.7739) (xy 172.119048 -289.724846) (xy 171.7802 -289.724846) (xy 171.779705 -289.749453)
			(xy 171.77181 -289.79803) (xy 171.756226 -289.844711) (xy 171.733355 -289.888288) (xy 171.70379 -289.927632)
			(xy 171.668297 -289.961724) (xy 171.627794 -289.98968) (xy 171.583332 -290.010778) (xy 171.536061 -290.02447)
			(xy 171.487206 -290.030402) (xy 171.438031 -290.028421) (xy 171.389812 -290.018577) (xy 171.343796 -290.001125)
			(xy 171.301175 -289.976518) (xy 171.263054 -289.945393) (xy 171.230419 -289.908556) (xy 171.204116 -289.86696)
			(xy 171.184825 -289.821684) (xy 171.173048 -289.7739) (xy 171.169088 -289.724846) (xy 170.83024 -289.724846)
			(xy 170.829745 -289.749453) (xy 170.82185 -289.79803) (xy 170.806266 -289.844711) (xy 170.783395 -289.888288)
			(xy 170.75383 -289.927632) (xy 170.718337 -289.961724) (xy 170.677834 -289.98968) (xy 170.633372 -290.010778)
			(xy 170.586101 -290.02447) (xy 170.537246 -290.030402) (xy 170.488071 -290.028421) (xy 170.439852 -290.018577)
			(xy 170.393836 -290.001125) (xy 170.351215 -289.976518) (xy 170.313094 -289.945393) (xy 170.280459 -289.908556)
			(xy 170.254156 -289.86696) (xy 170.234865 -289.821684) (xy 170.223088 -289.7739) (xy 170.219128 -289.724846)
			(xy 169.88028 -289.724846) (xy 169.879785 -289.749453) (xy 169.87189 -289.79803) (xy 169.856306 -289.844711)
			(xy 169.833435 -289.888288) (xy 169.80387 -289.927632) (xy 169.768377 -289.961724) (xy 169.727874 -289.98968)
			(xy 169.683412 -290.010778) (xy 169.636141 -290.02447) (xy 169.587286 -290.030402) (xy 169.538111 -290.028421)
			(xy 169.489892 -290.018577) (xy 169.443876 -290.001125) (xy 169.401255 -289.976518) (xy 169.363134 -289.945393)
			(xy 169.330499 -289.908556) (xy 169.304196 -289.86696) (xy 169.284905 -289.821684) (xy 169.273128 -289.7739)
			(xy 169.269168 -289.724846) (xy 168.93032 -289.724846) (xy 168.929825 -289.749453) (xy 168.92193 -289.79803)
			(xy 168.906346 -289.844711) (xy 168.883475 -289.888288) (xy 168.85391 -289.927632) (xy 168.818417 -289.961724)
			(xy 168.777914 -289.98968) (xy 168.733452 -290.010778) (xy 168.686181 -290.02447) (xy 168.637326 -290.030402)
			(xy 168.588151 -290.028421) (xy 168.539932 -290.018577) (xy 168.493916 -290.001125) (xy 168.451295 -289.976518)
			(xy 168.413174 -289.945393) (xy 168.380539 -289.908556) (xy 168.354236 -289.86696) (xy 168.334945 -289.821684)
			(xy 168.323168 -289.7739) (xy 168.319208 -289.724846) (xy 167.98036 -289.724846) (xy 167.979865 -289.749453)
			(xy 167.97197 -289.79803) (xy 167.956386 -289.844711) (xy 167.933515 -289.888288) (xy 167.90395 -289.927632)
			(xy 167.868457 -289.961724) (xy 167.827954 -289.98968) (xy 167.783492 -290.010778) (xy 167.736221 -290.02447)
			(xy 167.687366 -290.030402) (xy 167.638191 -290.028421) (xy 167.589972 -290.018577) (xy 167.543956 -290.001125)
			(xy 167.501335 -289.976518) (xy 167.463214 -289.945393) (xy 167.430579 -289.908556) (xy 167.404276 -289.86696)
			(xy 167.384985 -289.821684) (xy 167.373208 -289.7739) (xy 167.369248 -289.724846) (xy 167.0304 -289.724846)
			(xy 167.029905 -289.749453) (xy 167.02201 -289.79803) (xy 167.006426 -289.844711) (xy 166.983555 -289.888288)
			(xy 166.95399 -289.927632) (xy 166.918497 -289.961724) (xy 166.877994 -289.98968) (xy 166.833532 -290.010778)
			(xy 166.786261 -290.02447) (xy 166.737406 -290.030402) (xy 166.688231 -290.028421) (xy 166.640012 -290.018577)
			(xy 166.593996 -290.001125) (xy 166.551375 -289.976518) (xy 166.513254 -289.945393) (xy 166.480619 -289.908556)
			(xy 166.454316 -289.86696) (xy 166.435025 -289.821684) (xy 166.423248 -289.7739) (xy 166.419288 -289.724846)
			(xy 166.080186 -289.724846) (xy 166.079691 -289.749453) (xy 166.071796 -289.79803) (xy 166.056212 -289.844711)
			(xy 166.033341 -289.888288) (xy 166.003776 -289.927632) (xy 165.968283 -289.961724) (xy 165.92778 -289.98968)
			(xy 165.883318 -290.010778) (xy 165.836047 -290.02447) (xy 165.787192 -290.030402) (xy 165.738017 -290.028421)
			(xy 165.689798 -290.018577) (xy 165.643782 -290.001125) (xy 165.601161 -289.976518) (xy 165.56304 -289.945393)
			(xy 165.530405 -289.908556) (xy 165.504102 -289.86696) (xy 165.484811 -289.821684) (xy 165.473034 -289.7739)
			(xy 165.469074 -289.724846) (xy 165.155038 -289.724846) (xy 165.155038 -289.751184) (xy 165.14666 -289.803271)
			(xy 165.130118 -289.853366) (xy 165.105831 -289.900199) (xy 165.074416 -289.942582) (xy 165.03667 -289.979438)
			(xy 164.99355 -290.009834) (xy 164.946151 -290.032997) (xy 164.895676 -290.04834) (xy 164.869622 -290.052506)
			(xy 164.86505 -290.053268) (xy 164.854636 -290.05657) (xy 164.850318 -290.05784) (xy 164.826696 -290.068762)
			(xy 164.819838 -290.075874) (xy 164.804852 -290.091622) (xy 164.800266 -290.096728) (xy 164.793826 -290.108842)
			(xy 164.792152 -290.115498) (xy 164.790882 -290.12642) (xy 164.790882 -290.273232) (xy 164.791047 -290.279386)
			(xy 164.793996 -290.291335) (xy 164.796724 -290.296854) (xy 164.804852 -290.30803) (xy 164.819584 -290.323524)
			(xy 164.826188 -290.330636) (xy 164.849302 -290.341558) (xy 164.852858 -290.342574) (xy 164.86505 -290.346384)
			(xy 164.869622 -290.347146) (xy 164.895691 -290.351223) (xy 164.946172 -290.366569) (xy 164.993577 -290.389736)
			(xy 165.036701 -290.420136) (xy 165.074451 -290.456998) (xy 165.105868 -290.499386) (xy 165.130157 -290.546225)
			(xy 165.1467 -290.596327) (xy 165.155078 -290.64842) (xy 165.155078 -290.674806) (xy 165.469074 -290.674806)
			(xy 165.473034 -290.625752) (xy 165.484811 -290.577968) (xy 165.504102 -290.532692) (xy 165.530405 -290.491096)
			(xy 165.56304 -290.454259) (xy 165.601161 -290.423134) (xy 165.643782 -290.398527) (xy 165.689798 -290.381075)
			(xy 165.738017 -290.371231) (xy 165.787192 -290.36925) (xy 165.836047 -290.375182) (xy 165.883318 -290.388874)
			(xy 165.92778 -290.409972) (xy 165.968283 -290.437928) (xy 166.003776 -290.47202) (xy 166.033341 -290.511364)
			(xy 166.056212 -290.554941) (xy 166.071796 -290.601622) (xy 166.079691 -290.650199) (xy 166.080186 -290.674806)
			(xy 166.419288 -290.674806) (xy 166.423248 -290.625752) (xy 166.435025 -290.577968) (xy 166.454316 -290.532692)
			(xy 166.480619 -290.491096) (xy 166.513254 -290.454259) (xy 166.551375 -290.423134) (xy 166.593996 -290.398527)
			(xy 166.640012 -290.381075) (xy 166.688231 -290.371231) (xy 166.737406 -290.36925) (xy 166.786261 -290.375182)
			(xy 166.833532 -290.388874) (xy 166.877994 -290.409972) (xy 166.918497 -290.437928) (xy 166.95399 -290.47202)
			(xy 166.983555 -290.511364) (xy 167.006426 -290.554941) (xy 167.02201 -290.601622) (xy 167.029905 -290.650199)
			(xy 167.0304 -290.674806) (xy 167.369248 -290.674806) (xy 167.373208 -290.625752) (xy 167.384985 -290.577968)
			(xy 167.404276 -290.532692) (xy 167.430579 -290.491096) (xy 167.463214 -290.454259) (xy 167.501335 -290.423134)
			(xy 167.543956 -290.398527) (xy 167.589972 -290.381075) (xy 167.638191 -290.371231) (xy 167.687366 -290.36925)
			(xy 167.736221 -290.375182) (xy 167.783492 -290.388874) (xy 167.827954 -290.409972) (xy 167.868457 -290.437928)
			(xy 167.90395 -290.47202) (xy 167.933515 -290.511364) (xy 167.956386 -290.554941) (xy 167.97197 -290.601622)
			(xy 167.979865 -290.650199) (xy 167.98036 -290.674806) (xy 168.319208 -290.674806) (xy 168.323168 -290.625752)
			(xy 168.334945 -290.577968) (xy 168.354236 -290.532692) (xy 168.380539 -290.491096) (xy 168.413174 -290.454259)
			(xy 168.451295 -290.423134) (xy 168.493916 -290.398527) (xy 168.539932 -290.381075) (xy 168.588151 -290.371231)
			(xy 168.637326 -290.36925) (xy 168.686181 -290.375182) (xy 168.733452 -290.388874) (xy 168.777914 -290.409972)
			(xy 168.818417 -290.437928) (xy 168.85391 -290.47202) (xy 168.883475 -290.511364) (xy 168.906346 -290.554941)
			(xy 168.92193 -290.601622) (xy 168.929825 -290.650199) (xy 168.93032 -290.674806) (xy 169.269168 -290.674806)
			(xy 169.273128 -290.625752) (xy 169.284905 -290.577968) (xy 169.304196 -290.532692) (xy 169.330499 -290.491096)
			(xy 169.363134 -290.454259) (xy 169.401255 -290.423134) (xy 169.443876 -290.398527) (xy 169.489892 -290.381075)
			(xy 169.538111 -290.371231) (xy 169.587286 -290.36925) (xy 169.636141 -290.375182) (xy 169.683412 -290.388874)
			(xy 169.727874 -290.409972) (xy 169.768377 -290.437928) (xy 169.80387 -290.47202) (xy 169.833435 -290.511364)
			(xy 169.856306 -290.554941) (xy 169.87189 -290.601622) (xy 169.879785 -290.650199) (xy 169.88028 -290.674806)
			(xy 170.219128 -290.674806) (xy 170.223088 -290.625752) (xy 170.234865 -290.577968) (xy 170.254156 -290.532692)
			(xy 170.280459 -290.491096) (xy 170.313094 -290.454259) (xy 170.351215 -290.423134) (xy 170.393836 -290.398527)
			(xy 170.439852 -290.381075) (xy 170.488071 -290.371231) (xy 170.537246 -290.36925) (xy 170.586101 -290.375182)
			(xy 170.633372 -290.388874) (xy 170.677834 -290.409972) (xy 170.718337 -290.437928) (xy 170.75383 -290.47202)
			(xy 170.783395 -290.511364) (xy 170.806266 -290.554941) (xy 170.82185 -290.601622) (xy 170.829745 -290.650199)
			(xy 170.83024 -290.674806) (xy 171.169088 -290.674806) (xy 171.173048 -290.625752) (xy 171.184825 -290.577968)
			(xy 171.204116 -290.532692) (xy 171.230419 -290.491096) (xy 171.263054 -290.454259) (xy 171.301175 -290.423134)
			(xy 171.343796 -290.398527) (xy 171.389812 -290.381075) (xy 171.438031 -290.371231) (xy 171.487206 -290.36925)
			(xy 171.536061 -290.375182) (xy 171.583332 -290.388874) (xy 171.627794 -290.409972) (xy 171.668297 -290.437928)
			(xy 171.70379 -290.47202) (xy 171.733355 -290.511364) (xy 171.756226 -290.554941) (xy 171.77181 -290.601622)
			(xy 171.779705 -290.650199) (xy 171.7802 -290.674806) (xy 172.119048 -290.674806) (xy 172.123008 -290.625752)
			(xy 172.134785 -290.577968) (xy 172.154076 -290.532692) (xy 172.180379 -290.491096) (xy 172.213014 -290.454259)
			(xy 172.251135 -290.423134) (xy 172.293756 -290.398527) (xy 172.339772 -290.381075) (xy 172.387991 -290.371231)
			(xy 172.437166 -290.36925) (xy 172.486021 -290.375182) (xy 172.533292 -290.388874) (xy 172.577754 -290.409972)
			(xy 172.618257 -290.437928) (xy 172.65375 -290.47202) (xy 172.683315 -290.511364) (xy 172.706186 -290.554941)
			(xy 172.72177 -290.601622) (xy 172.729665 -290.650199) (xy 172.73016 -290.674806) (xy 173.069262 -290.674806)
			(xy 173.073222 -290.625752) (xy 173.084999 -290.577968) (xy 173.10429 -290.532692) (xy 173.130593 -290.491096)
			(xy 173.163228 -290.454259) (xy 173.201349 -290.423134) (xy 173.24397 -290.398527) (xy 173.289986 -290.381075)
			(xy 173.338205 -290.371231) (xy 173.38738 -290.36925) (xy 173.436235 -290.375182) (xy 173.483506 -290.388874)
			(xy 173.527968 -290.409972) (xy 173.568471 -290.437928) (xy 173.603964 -290.47202) (xy 173.633529 -290.511364)
			(xy 173.6564 -290.554941) (xy 173.671984 -290.601622) (xy 173.679879 -290.650199) (xy 173.680374 -290.674806)
			(xy 174.019222 -290.674806) (xy 174.023182 -290.625752) (xy 174.034959 -290.577968) (xy 174.05425 -290.532692)
			(xy 174.080553 -290.491096) (xy 174.113188 -290.454259) (xy 174.151309 -290.423134) (xy 174.19393 -290.398527)
			(xy 174.239946 -290.381075) (xy 174.288165 -290.371231) (xy 174.33734 -290.36925) (xy 174.386195 -290.375182)
			(xy 174.433466 -290.388874) (xy 174.477928 -290.409972) (xy 174.518431 -290.437928) (xy 174.553924 -290.47202)
			(xy 174.583489 -290.511364) (xy 174.60636 -290.554941) (xy 174.621944 -290.601622) (xy 174.629839 -290.650199)
			(xy 174.630334 -290.674806) (xy 175.919142 -290.674806) (xy 175.923102 -290.625752) (xy 175.934879 -290.577968)
			(xy 175.95417 -290.532692) (xy 175.980473 -290.491096) (xy 176.013108 -290.454259) (xy 176.051229 -290.423134)
			(xy 176.09385 -290.398527) (xy 176.139866 -290.381075) (xy 176.188085 -290.371231) (xy 176.23726 -290.36925)
			(xy 176.286115 -290.375182) (xy 176.333386 -290.388874) (xy 176.377848 -290.409972) (xy 176.418351 -290.437928)
			(xy 176.453844 -290.47202) (xy 176.483409 -290.511364) (xy 176.50628 -290.554941) (xy 176.521864 -290.601622)
			(xy 176.529759 -290.650199) (xy 176.530254 -290.674806) (xy 176.869102 -290.674806) (xy 176.873062 -290.625752)
			(xy 176.884839 -290.577968) (xy 176.90413 -290.532692) (xy 176.930433 -290.491096) (xy 176.963068 -290.454259)
			(xy 177.001189 -290.423134) (xy 177.04381 -290.398527) (xy 177.089826 -290.381075) (xy 177.138045 -290.371231)
			(xy 177.18722 -290.36925) (xy 177.236075 -290.375182) (xy 177.283346 -290.388874) (xy 177.327808 -290.409972)
			(xy 177.368311 -290.437928) (xy 177.403804 -290.47202) (xy 177.433369 -290.511364) (xy 177.45624 -290.554941)
			(xy 177.471824 -290.601622) (xy 177.479719 -290.650199) (xy 177.480214 -290.674806) (xy 177.819062 -290.674806)
			(xy 177.823022 -290.625752) (xy 177.834799 -290.577968) (xy 177.85409 -290.532692) (xy 177.880393 -290.491096)
			(xy 177.913028 -290.454259) (xy 177.951149 -290.423134) (xy 177.99377 -290.398527) (xy 178.039786 -290.381075)
			(xy 178.088005 -290.371231) (xy 178.13718 -290.36925) (xy 178.186035 -290.375182) (xy 178.233306 -290.388874)
			(xy 178.277768 -290.409972) (xy 178.318271 -290.437928) (xy 178.353764 -290.47202) (xy 178.383329 -290.511364)
			(xy 178.4062 -290.554941) (xy 178.421784 -290.601622) (xy 178.429679 -290.650199) (xy 178.430174 -290.674806)
			(xy 178.769276 -290.674806) (xy 178.773236 -290.625752) (xy 178.785013 -290.577968) (xy 178.804304 -290.532692)
			(xy 178.830607 -290.491096) (xy 178.863242 -290.454259) (xy 178.901363 -290.423134) (xy 178.943984 -290.398527)
			(xy 178.99 -290.381075) (xy 179.038219 -290.371231) (xy 179.087394 -290.36925) (xy 179.136249 -290.375182)
			(xy 179.18352 -290.388874) (xy 179.227982 -290.409972) (xy 179.268485 -290.437928) (xy 179.303978 -290.47202)
			(xy 179.333543 -290.511364) (xy 179.356414 -290.554941) (xy 179.371998 -290.601622) (xy 179.379893 -290.650199)
			(xy 179.380388 -290.674806) (xy 179.719236 -290.674806) (xy 179.723196 -290.625752) (xy 179.734973 -290.577968)
			(xy 179.754264 -290.532692) (xy 179.780567 -290.491096) (xy 179.813202 -290.454259) (xy 179.851323 -290.423134)
			(xy 179.893944 -290.398527) (xy 179.93996 -290.381075) (xy 179.988179 -290.371231) (xy 180.037354 -290.36925)
			(xy 180.086209 -290.375182) (xy 180.13348 -290.388874) (xy 180.177942 -290.409972) (xy 180.218445 -290.437928)
			(xy 180.253938 -290.47202) (xy 180.283503 -290.511364) (xy 180.306374 -290.554941) (xy 180.321958 -290.601622)
			(xy 180.329853 -290.650199) (xy 180.330348 -290.674806) (xy 180.669196 -290.674806) (xy 180.673156 -290.625752)
			(xy 180.684933 -290.577968) (xy 180.704224 -290.532692) (xy 180.730527 -290.491096) (xy 180.763162 -290.454259)
			(xy 180.801283 -290.423134) (xy 180.843904 -290.398527) (xy 180.88992 -290.381075) (xy 180.938139 -290.371231)
			(xy 180.987314 -290.36925) (xy 181.036169 -290.375182) (xy 181.08344 -290.388874) (xy 181.127902 -290.409972)
			(xy 181.168405 -290.437928) (xy 181.203898 -290.47202) (xy 181.233463 -290.511364) (xy 181.256334 -290.554941)
			(xy 181.271918 -290.601622) (xy 181.279813 -290.650199) (xy 181.280308 -290.674806) (xy 181.619156 -290.674806)
			(xy 181.623116 -290.625752) (xy 181.634893 -290.577968) (xy 181.654184 -290.532692) (xy 181.680487 -290.491096)
			(xy 181.713122 -290.454259) (xy 181.751243 -290.423134) (xy 181.793864 -290.398527) (xy 181.83988 -290.381075)
			(xy 181.888099 -290.371231) (xy 181.937274 -290.36925) (xy 181.986129 -290.375182) (xy 182.0334 -290.388874)
			(xy 182.077862 -290.409972) (xy 182.118365 -290.437928) (xy 182.153858 -290.47202) (xy 182.183423 -290.511364)
			(xy 182.206294 -290.554941) (xy 182.221878 -290.601622) (xy 182.229773 -290.650199) (xy 182.230268 -290.674806)
			(xy 182.569116 -290.674806) (xy 182.573076 -290.625752) (xy 182.584853 -290.577968) (xy 182.604144 -290.532692)
			(xy 182.630447 -290.491096) (xy 182.663082 -290.454259) (xy 182.701203 -290.423134) (xy 182.743824 -290.398527)
			(xy 182.78984 -290.381075) (xy 182.838059 -290.371231) (xy 182.887234 -290.36925) (xy 182.936089 -290.375182)
			(xy 182.98336 -290.388874) (xy 183.027822 -290.409972) (xy 183.068325 -290.437928) (xy 183.103818 -290.47202)
			(xy 183.133383 -290.511364) (xy 183.156254 -290.554941) (xy 183.171838 -290.601622) (xy 183.179733 -290.650199)
			(xy 183.180228 -290.674806) (xy 183.519076 -290.674806) (xy 183.523036 -290.625752) (xy 183.534813 -290.577968)
			(xy 183.554104 -290.532692) (xy 183.580407 -290.491096) (xy 183.613042 -290.454259) (xy 183.651163 -290.423134)
			(xy 183.693784 -290.398527) (xy 183.7398 -290.381075) (xy 183.788019 -290.371231) (xy 183.837194 -290.36925)
			(xy 183.886049 -290.375182) (xy 183.93332 -290.388874) (xy 183.977782 -290.409972) (xy 184.018285 -290.437928)
			(xy 184.053778 -290.47202) (xy 184.083343 -290.511364) (xy 184.106214 -290.554941) (xy 184.121798 -290.601622)
			(xy 184.129693 -290.650199) (xy 184.130188 -290.674806) (xy 184.469036 -290.674806) (xy 184.472996 -290.625752)
			(xy 184.484773 -290.577968) (xy 184.504064 -290.532692) (xy 184.530367 -290.491096) (xy 184.563002 -290.454259)
			(xy 184.601123 -290.423134) (xy 184.643744 -290.398527) (xy 184.68976 -290.381075) (xy 184.737979 -290.371231)
			(xy 184.787154 -290.36925) (xy 184.836009 -290.375182) (xy 184.88328 -290.388874) (xy 184.927742 -290.409972)
			(xy 184.968245 -290.437928) (xy 185.003738 -290.47202) (xy 185.033303 -290.511364) (xy 185.056174 -290.554941)
			(xy 185.071758 -290.601622) (xy 185.079653 -290.650199) (xy 185.080148 -290.674806) (xy 185.41925 -290.674806)
			(xy 185.42321 -290.625752) (xy 185.434987 -290.577968) (xy 185.454278 -290.532692) (xy 185.480581 -290.491096)
			(xy 185.513216 -290.454259) (xy 185.551337 -290.423134) (xy 185.593958 -290.398527) (xy 185.639974 -290.381075)
			(xy 185.688193 -290.371231) (xy 185.737368 -290.36925) (xy 185.786223 -290.375182) (xy 185.833494 -290.388874)
			(xy 185.877956 -290.409972) (xy 185.918459 -290.437928) (xy 185.953952 -290.47202) (xy 185.983517 -290.511364)
			(xy 186.006388 -290.554941) (xy 186.021972 -290.601622) (xy 186.029867 -290.650199) (xy 186.030362 -290.674806)
			(xy 186.36921 -290.674806) (xy 186.37317 -290.625752) (xy 186.384947 -290.577968) (xy 186.404238 -290.532692)
			(xy 186.430541 -290.491096) (xy 186.463176 -290.454259) (xy 186.501297 -290.423134) (xy 186.543918 -290.398527)
			(xy 186.589934 -290.381075) (xy 186.638153 -290.371231) (xy 186.687328 -290.36925) (xy 186.736183 -290.375182)
			(xy 186.783454 -290.388874) (xy 186.827916 -290.409972) (xy 186.868419 -290.437928) (xy 186.903912 -290.47202)
			(xy 186.933477 -290.511364) (xy 186.956348 -290.554941) (xy 186.971932 -290.601622) (xy 186.979827 -290.650199)
			(xy 186.980322 -290.674806) (xy 187.31917 -290.674806) (xy 187.32313 -290.625752) (xy 187.334907 -290.577968)
			(xy 187.354198 -290.532692) (xy 187.380501 -290.491096) (xy 187.413136 -290.454259) (xy 187.451257 -290.423134)
			(xy 187.493878 -290.398527) (xy 187.539894 -290.381075) (xy 187.588113 -290.371231) (xy 187.637288 -290.36925)
			(xy 187.686143 -290.375182) (xy 187.733414 -290.388874) (xy 187.777876 -290.409972) (xy 187.818379 -290.437928)
			(xy 187.853872 -290.47202) (xy 187.883437 -290.511364) (xy 187.906308 -290.554941) (xy 187.921892 -290.601622)
			(xy 187.929787 -290.650199) (xy 187.930282 -290.674806) (xy 188.26913 -290.674806) (xy 188.27309 -290.625752)
			(xy 188.284867 -290.577968) (xy 188.304158 -290.532692) (xy 188.330461 -290.491096) (xy 188.363096 -290.454259)
			(xy 188.401217 -290.423134) (xy 188.443838 -290.398527) (xy 188.489854 -290.381075) (xy 188.538073 -290.371231)
			(xy 188.587248 -290.36925) (xy 188.636103 -290.375182) (xy 188.683374 -290.388874) (xy 188.727836 -290.409972)
			(xy 188.768339 -290.437928) (xy 188.803832 -290.47202) (xy 188.833397 -290.511364) (xy 188.856268 -290.554941)
			(xy 188.871852 -290.601622) (xy 188.879747 -290.650199) (xy 188.880242 -290.674806) (xy 189.21909 -290.674806)
			(xy 189.22305 -290.625752) (xy 189.234827 -290.577968) (xy 189.254118 -290.532692) (xy 189.280421 -290.491096)
			(xy 189.313056 -290.454259) (xy 189.351177 -290.423134) (xy 189.393798 -290.398527) (xy 189.439814 -290.381075)
			(xy 189.488033 -290.371231) (xy 189.537208 -290.36925) (xy 189.586063 -290.375182) (xy 189.633334 -290.388874)
			(xy 189.677796 -290.409972) (xy 189.718299 -290.437928) (xy 189.753792 -290.47202) (xy 189.783357 -290.511364)
			(xy 189.806228 -290.554941) (xy 189.821812 -290.601622) (xy 189.829707 -290.650199) (xy 189.830202 -290.674806)
			(xy 190.16905 -290.674806) (xy 190.17301 -290.625752) (xy 190.184787 -290.577968) (xy 190.204078 -290.532692)
			(xy 190.230381 -290.491096) (xy 190.263016 -290.454259) (xy 190.301137 -290.423134) (xy 190.343758 -290.398527)
			(xy 190.389774 -290.381075) (xy 190.437993 -290.371231) (xy 190.487168 -290.36925) (xy 190.536023 -290.375182)
			(xy 190.583294 -290.388874) (xy 190.627756 -290.409972) (xy 190.668259 -290.437928) (xy 190.703752 -290.47202)
			(xy 190.733317 -290.511364) (xy 190.756188 -290.554941) (xy 190.771772 -290.601622) (xy 190.779667 -290.650199)
			(xy 190.780162 -290.674806) (xy 191.119264 -290.674806) (xy 191.123224 -290.625752) (xy 191.135001 -290.577968)
			(xy 191.154292 -290.532692) (xy 191.180595 -290.491096) (xy 191.21323 -290.454259) (xy 191.251351 -290.423134)
			(xy 191.293972 -290.398527) (xy 191.339988 -290.381075) (xy 191.388207 -290.371231) (xy 191.437382 -290.36925)
			(xy 191.486237 -290.375182) (xy 191.533508 -290.388874) (xy 191.57797 -290.409972) (xy 191.618473 -290.437928)
			(xy 191.653966 -290.47202) (xy 191.683531 -290.511364) (xy 191.706402 -290.554941) (xy 191.721986 -290.601622)
			(xy 191.729881 -290.650199) (xy 191.730376 -290.674806) (xy 192.069224 -290.674806) (xy 192.073184 -290.625752)
			(xy 192.084961 -290.577968) (xy 192.104252 -290.532692) (xy 192.130555 -290.491096) (xy 192.16319 -290.454259)
			(xy 192.201311 -290.423134) (xy 192.243932 -290.398527) (xy 192.289948 -290.381075) (xy 192.338167 -290.371231)
			(xy 192.387342 -290.36925) (xy 192.436197 -290.375182) (xy 192.483468 -290.388874) (xy 192.52793 -290.409972)
			(xy 192.568433 -290.437928) (xy 192.603926 -290.47202) (xy 192.633491 -290.511364) (xy 192.656362 -290.554941)
			(xy 192.671946 -290.601622) (xy 192.679841 -290.650199) (xy 192.680336 -290.674806) (xy 193.019184 -290.674806)
			(xy 193.023144 -290.625752) (xy 193.034921 -290.577968) (xy 193.054212 -290.532692) (xy 193.080515 -290.491096)
			(xy 193.11315 -290.454259) (xy 193.151271 -290.423134) (xy 193.193892 -290.398527) (xy 193.239908 -290.381075)
			(xy 193.288127 -290.371231) (xy 193.337302 -290.36925) (xy 193.386157 -290.375182) (xy 193.433428 -290.388874)
			(xy 193.47789 -290.409972) (xy 193.518393 -290.437928) (xy 193.553886 -290.47202) (xy 193.583451 -290.511364)
			(xy 193.606322 -290.554941) (xy 193.621906 -290.601622) (xy 193.629801 -290.650199) (xy 193.630296 -290.674806)
			(xy 193.969144 -290.674806) (xy 193.973104 -290.625752) (xy 193.984881 -290.577968) (xy 194.004172 -290.532692)
			(xy 194.030475 -290.491096) (xy 194.06311 -290.454259) (xy 194.101231 -290.423134) (xy 194.143852 -290.398527)
			(xy 194.189868 -290.381075) (xy 194.238087 -290.371231) (xy 194.287262 -290.36925) (xy 194.336117 -290.375182)
			(xy 194.383388 -290.388874) (xy 194.42785 -290.409972) (xy 194.468353 -290.437928) (xy 194.503846 -290.47202)
			(xy 194.533411 -290.511364) (xy 194.556282 -290.554941) (xy 194.571866 -290.601622) (xy 194.579761 -290.650199)
			(xy 194.580256 -290.674806) (xy 194.919104 -290.674806) (xy 194.923064 -290.625752) (xy 194.934841 -290.577968)
			(xy 194.954132 -290.532692) (xy 194.980435 -290.491096) (xy 195.01307 -290.454259) (xy 195.051191 -290.423134)
			(xy 195.093812 -290.398527) (xy 195.139828 -290.381075) (xy 195.188047 -290.371231) (xy 195.237222 -290.36925)
			(xy 195.286077 -290.375182) (xy 195.333348 -290.388874) (xy 195.37781 -290.409972) (xy 195.418313 -290.437928)
			(xy 195.453806 -290.47202) (xy 195.483371 -290.511364) (xy 195.506242 -290.554941) (xy 195.521826 -290.601622)
			(xy 195.529721 -290.650199) (xy 195.530216 -290.674806) (xy 195.869064 -290.674806) (xy 195.873024 -290.625752)
			(xy 195.884801 -290.577968) (xy 195.904092 -290.532692) (xy 195.930395 -290.491096) (xy 195.96303 -290.454259)
			(xy 196.001151 -290.423134) (xy 196.043772 -290.398527) (xy 196.089788 -290.381075) (xy 196.138007 -290.371231)
			(xy 196.187182 -290.36925) (xy 196.236037 -290.375182) (xy 196.283308 -290.388874) (xy 196.32777 -290.409972)
			(xy 196.368273 -290.437928) (xy 196.403766 -290.47202) (xy 196.433331 -290.511364) (xy 196.456202 -290.554941)
			(xy 196.471786 -290.601622) (xy 196.479681 -290.650199) (xy 196.480176 -290.674806) (xy 196.819278 -290.674806)
			(xy 196.823238 -290.625752) (xy 196.835015 -290.577968) (xy 196.854306 -290.532692) (xy 196.880609 -290.491096)
			(xy 196.913244 -290.454259) (xy 196.951365 -290.423134) (xy 196.993986 -290.398527) (xy 197.040002 -290.381075)
			(xy 197.088221 -290.371231) (xy 197.137396 -290.36925) (xy 197.186251 -290.375182) (xy 197.233522 -290.388874)
			(xy 197.277984 -290.409972) (xy 197.318487 -290.437928) (xy 197.35398 -290.47202) (xy 197.383545 -290.511364)
			(xy 197.406416 -290.554941) (xy 197.422 -290.601622) (xy 197.429895 -290.650199) (xy 197.43039 -290.674806)
			(xy 197.769238 -290.674806) (xy 197.773198 -290.625752) (xy 197.784975 -290.577968) (xy 197.804266 -290.532692)
			(xy 197.830569 -290.491096) (xy 197.863204 -290.454259) (xy 197.901325 -290.423134) (xy 197.943946 -290.398527)
			(xy 197.989962 -290.381075) (xy 198.038181 -290.371231) (xy 198.087356 -290.36925) (xy 198.136211 -290.375182)
			(xy 198.183482 -290.388874) (xy 198.227944 -290.409972) (xy 198.268447 -290.437928) (xy 198.30394 -290.47202)
			(xy 198.333505 -290.511364) (xy 198.356376 -290.554941) (xy 198.37196 -290.601622) (xy 198.379855 -290.650199)
			(xy 198.38035 -290.674806) (xy 198.719198 -290.674806) (xy 198.723158 -290.625752) (xy 198.734935 -290.577968)
			(xy 198.754226 -290.532692) (xy 198.780529 -290.491096) (xy 198.813164 -290.454259) (xy 198.851285 -290.423134)
			(xy 198.893906 -290.398527) (xy 198.939922 -290.381075) (xy 198.988141 -290.371231) (xy 199.037316 -290.36925)
			(xy 199.086171 -290.375182) (xy 199.133442 -290.388874) (xy 199.177904 -290.409972) (xy 199.19176 -290.419536)
			(xy 201.25385 -290.419536) (xy 201.257921 -290.363914) (xy 201.270047 -290.309477) (xy 201.28997 -290.257386)
			(xy 201.317266 -290.208751) (xy 201.351352 -290.164608) (xy 201.391501 -290.125899) (xy 201.436859 -290.093448)
			(xy 201.486459 -290.067947) (xy 201.539243 -290.04994) (xy 201.594086 -290.03981) (xy 201.64982 -290.037773)
			(xy 201.705257 -290.043873) (xy 201.759214 -290.057979) (xy 201.810543 -290.079791) (xy 201.858149 -290.108845)
			(xy 201.901017 -290.14452) (xy 201.938234 -290.186057) (xy 201.969007 -290.23257) (xy 201.971161 -290.237164)
			(xy 205.26451 -290.237164) (xy 205.268581 -290.181542) (xy 205.280707 -290.127105) (xy 205.30063 -290.075014)
			(xy 205.327926 -290.026379) (xy 205.362012 -289.982236) (xy 205.402161 -289.943527) (xy 205.447519 -289.911076)
			(xy 205.497119 -289.885575) (xy 205.549903 -289.867568) (xy 205.604746 -289.857438) (xy 205.66048 -289.855401)
			(xy 205.715917 -289.861501) (xy 205.769874 -289.875607) (xy 205.821203 -289.897419) (xy 205.868809 -289.926473)
			(xy 205.911677 -289.962148) (xy 205.948894 -290.003685) (xy 205.979667 -290.050198) (xy 206.003339 -290.100695)
			(xy 206.019407 -290.154102) (xy 206.027527 -290.209278) (xy 206.028036 -290.237164) (xy 206.027527 -290.26505)
			(xy 206.019407 -290.320226) (xy 206.003339 -290.373633) (xy 205.979667 -290.42413) (xy 205.948894 -290.470643)
			(xy 205.911677 -290.51218) (xy 205.868809 -290.547855) (xy 205.821203 -290.576909) (xy 205.769874 -290.598721)
			(xy 205.715917 -290.612827) (xy 205.66048 -290.618927) (xy 205.604746 -290.61689) (xy 205.549903 -290.60676)
			(xy 205.497119 -290.588753) (xy 205.447519 -290.563252) (xy 205.402161 -290.530801) (xy 205.362012 -290.492092)
			(xy 205.327926 -290.447949) (xy 205.30063 -290.399314) (xy 205.280707 -290.347223) (xy 205.268581 -290.292786)
			(xy 205.26451 -290.237164) (xy 201.971161 -290.237164) (xy 201.992679 -290.283067) (xy 202.008747 -290.336474)
			(xy 202.016867 -290.39165) (xy 202.017376 -290.419536) (xy 202.016867 -290.447422) (xy 202.008747 -290.502598)
			(xy 201.992679 -290.556005) (xy 201.969007 -290.606502) (xy 201.938234 -290.653015) (xy 201.901017 -290.694552)
			(xy 201.858149 -290.730227) (xy 201.810543 -290.759281) (xy 201.759214 -290.781093) (xy 201.705257 -290.795199)
			(xy 201.64982 -290.801299) (xy 201.594086 -290.799262) (xy 201.539243 -290.789132) (xy 201.486459 -290.771125)
			(xy 201.436859 -290.745624) (xy 201.391501 -290.713173) (xy 201.351352 -290.674464) (xy 201.317266 -290.630321)
			(xy 201.28997 -290.581686) (xy 201.270047 -290.529595) (xy 201.257921 -290.475158) (xy 201.25385 -290.419536)
			(xy 199.19176 -290.419536) (xy 199.218407 -290.437928) (xy 199.2539 -290.47202) (xy 199.283465 -290.511364)
			(xy 199.306336 -290.554941) (xy 199.32192 -290.601622) (xy 199.329815 -290.650199) (xy 199.33031 -290.674806)
			(xy 199.329815 -290.699413) (xy 199.32192 -290.74799) (xy 199.306336 -290.794671) (xy 199.283465 -290.838248)
			(xy 199.2539 -290.877592) (xy 199.218407 -290.911684) (xy 199.177904 -290.93964) (xy 199.133442 -290.960738)
			(xy 199.086171 -290.97443) (xy 199.037316 -290.980362) (xy 198.988141 -290.978381) (xy 198.939922 -290.968537)
			(xy 198.893906 -290.951085) (xy 198.851285 -290.926478) (xy 198.813164 -290.895353) (xy 198.780529 -290.858516)
			(xy 198.754226 -290.81692) (xy 198.734935 -290.771644) (xy 198.723158 -290.72386) (xy 198.719198 -290.674806)
			(xy 198.38035 -290.674806) (xy 198.379855 -290.699413) (xy 198.37196 -290.74799) (xy 198.356376 -290.794671)
			(xy 198.333505 -290.838248) (xy 198.30394 -290.877592) (xy 198.268447 -290.911684) (xy 198.227944 -290.93964)
			(xy 198.183482 -290.960738) (xy 198.136211 -290.97443) (xy 198.087356 -290.980362) (xy 198.038181 -290.978381)
			(xy 197.989962 -290.968537) (xy 197.943946 -290.951085) (xy 197.901325 -290.926478) (xy 197.863204 -290.895353)
			(xy 197.830569 -290.858516) (xy 197.804266 -290.81692) (xy 197.784975 -290.771644) (xy 197.773198 -290.72386)
			(xy 197.769238 -290.674806) (xy 197.43039 -290.674806) (xy 197.429895 -290.699413) (xy 197.422 -290.74799)
			(xy 197.406416 -290.794671) (xy 197.383545 -290.838248) (xy 197.35398 -290.877592) (xy 197.318487 -290.911684)
			(xy 197.277984 -290.93964) (xy 197.233522 -290.960738) (xy 197.186251 -290.97443) (xy 197.137396 -290.980362)
			(xy 197.088221 -290.978381) (xy 197.040002 -290.968537) (xy 196.993986 -290.951085) (xy 196.951365 -290.926478)
			(xy 196.913244 -290.895353) (xy 196.880609 -290.858516) (xy 196.854306 -290.81692) (xy 196.835015 -290.771644)
			(xy 196.823238 -290.72386) (xy 196.819278 -290.674806) (xy 196.480176 -290.674806) (xy 196.479681 -290.699413)
			(xy 196.471786 -290.74799) (xy 196.456202 -290.794671) (xy 196.433331 -290.838248) (xy 196.403766 -290.877592)
			(xy 196.368273 -290.911684) (xy 196.32777 -290.93964) (xy 196.283308 -290.960738) (xy 196.236037 -290.97443)
			(xy 196.187182 -290.980362) (xy 196.138007 -290.978381) (xy 196.089788 -290.968537) (xy 196.043772 -290.951085)
			(xy 196.001151 -290.926478) (xy 195.96303 -290.895353) (xy 195.930395 -290.858516) (xy 195.904092 -290.81692)
			(xy 195.884801 -290.771644) (xy 195.873024 -290.72386) (xy 195.869064 -290.674806) (xy 195.530216 -290.674806)
			(xy 195.529721 -290.699413) (xy 195.521826 -290.74799) (xy 195.506242 -290.794671) (xy 195.483371 -290.838248)
			(xy 195.453806 -290.877592) (xy 195.418313 -290.911684) (xy 195.37781 -290.93964) (xy 195.333348 -290.960738)
			(xy 195.286077 -290.97443) (xy 195.237222 -290.980362) (xy 195.188047 -290.978381) (xy 195.139828 -290.968537)
			(xy 195.093812 -290.951085) (xy 195.051191 -290.926478) (xy 195.01307 -290.895353) (xy 194.980435 -290.858516)
			(xy 194.954132 -290.81692) (xy 194.934841 -290.771644) (xy 194.923064 -290.72386) (xy 194.919104 -290.674806)
			(xy 194.580256 -290.674806) (xy 194.579761 -290.699413) (xy 194.571866 -290.74799) (xy 194.556282 -290.794671)
			(xy 194.533411 -290.838248) (xy 194.503846 -290.877592) (xy 194.468353 -290.911684) (xy 194.42785 -290.93964)
			(xy 194.383388 -290.960738) (xy 194.336117 -290.97443) (xy 194.287262 -290.980362) (xy 194.238087 -290.978381)
			(xy 194.189868 -290.968537) (xy 194.143852 -290.951085) (xy 194.101231 -290.926478) (xy 194.06311 -290.895353)
			(xy 194.030475 -290.858516) (xy 194.004172 -290.81692) (xy 193.984881 -290.771644) (xy 193.973104 -290.72386)
			(xy 193.969144 -290.674806) (xy 193.630296 -290.674806) (xy 193.629801 -290.699413) (xy 193.621906 -290.74799)
			(xy 193.606322 -290.794671) (xy 193.583451 -290.838248) (xy 193.553886 -290.877592) (xy 193.518393 -290.911684)
			(xy 193.47789 -290.93964) (xy 193.433428 -290.960738) (xy 193.386157 -290.97443) (xy 193.337302 -290.980362)
			(xy 193.288127 -290.978381) (xy 193.239908 -290.968537) (xy 193.193892 -290.951085) (xy 193.151271 -290.926478)
			(xy 193.11315 -290.895353) (xy 193.080515 -290.858516) (xy 193.054212 -290.81692) (xy 193.034921 -290.771644)
			(xy 193.023144 -290.72386) (xy 193.019184 -290.674806) (xy 192.680336 -290.674806) (xy 192.679841 -290.699413)
			(xy 192.671946 -290.74799) (xy 192.656362 -290.794671) (xy 192.633491 -290.838248) (xy 192.603926 -290.877592)
			(xy 192.568433 -290.911684) (xy 192.52793 -290.93964) (xy 192.483468 -290.960738) (xy 192.436197 -290.97443)
			(xy 192.387342 -290.980362) (xy 192.338167 -290.978381) (xy 192.289948 -290.968537) (xy 192.243932 -290.951085)
			(xy 192.201311 -290.926478) (xy 192.16319 -290.895353) (xy 192.130555 -290.858516) (xy 192.104252 -290.81692)
			(xy 192.084961 -290.771644) (xy 192.073184 -290.72386) (xy 192.069224 -290.674806) (xy 191.730376 -290.674806)
			(xy 191.729881 -290.699413) (xy 191.721986 -290.74799) (xy 191.706402 -290.794671) (xy 191.683531 -290.838248)
			(xy 191.653966 -290.877592) (xy 191.618473 -290.911684) (xy 191.57797 -290.93964) (xy 191.533508 -290.960738)
			(xy 191.486237 -290.97443) (xy 191.437382 -290.980362) (xy 191.388207 -290.978381) (xy 191.339988 -290.968537)
			(xy 191.293972 -290.951085) (xy 191.251351 -290.926478) (xy 191.21323 -290.895353) (xy 191.180595 -290.858516)
			(xy 191.154292 -290.81692) (xy 191.135001 -290.771644) (xy 191.123224 -290.72386) (xy 191.119264 -290.674806)
			(xy 190.780162 -290.674806) (xy 190.779667 -290.699413) (xy 190.771772 -290.74799) (xy 190.756188 -290.794671)
			(xy 190.733317 -290.838248) (xy 190.703752 -290.877592) (xy 190.668259 -290.911684) (xy 190.627756 -290.93964)
			(xy 190.583294 -290.960738) (xy 190.536023 -290.97443) (xy 190.487168 -290.980362) (xy 190.437993 -290.978381)
			(xy 190.389774 -290.968537) (xy 190.343758 -290.951085) (xy 190.301137 -290.926478) (xy 190.263016 -290.895353)
			(xy 190.230381 -290.858516) (xy 190.204078 -290.81692) (xy 190.184787 -290.771644) (xy 190.17301 -290.72386)
			(xy 190.16905 -290.674806) (xy 189.830202 -290.674806) (xy 189.829707 -290.699413) (xy 189.821812 -290.74799)
			(xy 189.806228 -290.794671) (xy 189.783357 -290.838248) (xy 189.753792 -290.877592) (xy 189.718299 -290.911684)
			(xy 189.677796 -290.93964) (xy 189.633334 -290.960738) (xy 189.586063 -290.97443) (xy 189.537208 -290.980362)
			(xy 189.488033 -290.978381) (xy 189.439814 -290.968537) (xy 189.393798 -290.951085) (xy 189.351177 -290.926478)
			(xy 189.313056 -290.895353) (xy 189.280421 -290.858516) (xy 189.254118 -290.81692) (xy 189.234827 -290.771644)
			(xy 189.22305 -290.72386) (xy 189.21909 -290.674806) (xy 188.880242 -290.674806) (xy 188.879747 -290.699413)
			(xy 188.871852 -290.74799) (xy 188.856268 -290.794671) (xy 188.833397 -290.838248) (xy 188.803832 -290.877592)
			(xy 188.768339 -290.911684) (xy 188.727836 -290.93964) (xy 188.683374 -290.960738) (xy 188.636103 -290.97443)
			(xy 188.587248 -290.980362) (xy 188.538073 -290.978381) (xy 188.489854 -290.968537) (xy 188.443838 -290.951085)
			(xy 188.401217 -290.926478) (xy 188.363096 -290.895353) (xy 188.330461 -290.858516) (xy 188.304158 -290.81692)
			(xy 188.284867 -290.771644) (xy 188.27309 -290.72386) (xy 188.26913 -290.674806) (xy 187.930282 -290.674806)
			(xy 187.929787 -290.699413) (xy 187.921892 -290.74799) (xy 187.906308 -290.794671) (xy 187.883437 -290.838248)
			(xy 187.853872 -290.877592) (xy 187.818379 -290.911684) (xy 187.777876 -290.93964) (xy 187.733414 -290.960738)
			(xy 187.686143 -290.97443) (xy 187.637288 -290.980362) (xy 187.588113 -290.978381) (xy 187.539894 -290.968537)
			(xy 187.493878 -290.951085) (xy 187.451257 -290.926478) (xy 187.413136 -290.895353) (xy 187.380501 -290.858516)
			(xy 187.354198 -290.81692) (xy 187.334907 -290.771644) (xy 187.32313 -290.72386) (xy 187.31917 -290.674806)
			(xy 186.980322 -290.674806) (xy 186.979827 -290.699413) (xy 186.971932 -290.74799) (xy 186.956348 -290.794671)
			(xy 186.933477 -290.838248) (xy 186.903912 -290.877592) (xy 186.868419 -290.911684) (xy 186.827916 -290.93964)
			(xy 186.783454 -290.960738) (xy 186.736183 -290.97443) (xy 186.687328 -290.980362) (xy 186.638153 -290.978381)
			(xy 186.589934 -290.968537) (xy 186.543918 -290.951085) (xy 186.501297 -290.926478) (xy 186.463176 -290.895353)
			(xy 186.430541 -290.858516) (xy 186.404238 -290.81692) (xy 186.384947 -290.771644) (xy 186.37317 -290.72386)
			(xy 186.36921 -290.674806) (xy 186.030362 -290.674806) (xy 186.029867 -290.699413) (xy 186.021972 -290.74799)
			(xy 186.006388 -290.794671) (xy 185.983517 -290.838248) (xy 185.953952 -290.877592) (xy 185.918459 -290.911684)
			(xy 185.877956 -290.93964) (xy 185.833494 -290.960738) (xy 185.786223 -290.97443) (xy 185.737368 -290.980362)
			(xy 185.688193 -290.978381) (xy 185.639974 -290.968537) (xy 185.593958 -290.951085) (xy 185.551337 -290.926478)
			(xy 185.513216 -290.895353) (xy 185.480581 -290.858516) (xy 185.454278 -290.81692) (xy 185.434987 -290.771644)
			(xy 185.42321 -290.72386) (xy 185.41925 -290.674806) (xy 185.080148 -290.674806) (xy 185.079653 -290.699413)
			(xy 185.071758 -290.74799) (xy 185.056174 -290.794671) (xy 185.033303 -290.838248) (xy 185.003738 -290.877592)
			(xy 184.968245 -290.911684) (xy 184.927742 -290.93964) (xy 184.88328 -290.960738) (xy 184.836009 -290.97443)
			(xy 184.787154 -290.980362) (xy 184.737979 -290.978381) (xy 184.68976 -290.968537) (xy 184.643744 -290.951085)
			(xy 184.601123 -290.926478) (xy 184.563002 -290.895353) (xy 184.530367 -290.858516) (xy 184.504064 -290.81692)
			(xy 184.484773 -290.771644) (xy 184.472996 -290.72386) (xy 184.469036 -290.674806) (xy 184.130188 -290.674806)
			(xy 184.129693 -290.699413) (xy 184.121798 -290.74799) (xy 184.106214 -290.794671) (xy 184.083343 -290.838248)
			(xy 184.053778 -290.877592) (xy 184.018285 -290.911684) (xy 183.977782 -290.93964) (xy 183.93332 -290.960738)
			(xy 183.886049 -290.97443) (xy 183.837194 -290.980362) (xy 183.788019 -290.978381) (xy 183.7398 -290.968537)
			(xy 183.693784 -290.951085) (xy 183.651163 -290.926478) (xy 183.613042 -290.895353) (xy 183.580407 -290.858516)
			(xy 183.554104 -290.81692) (xy 183.534813 -290.771644) (xy 183.523036 -290.72386) (xy 183.519076 -290.674806)
			(xy 183.180228 -290.674806) (xy 183.179733 -290.699413) (xy 183.171838 -290.74799) (xy 183.156254 -290.794671)
			(xy 183.133383 -290.838248) (xy 183.103818 -290.877592) (xy 183.068325 -290.911684) (xy 183.027822 -290.93964)
			(xy 182.98336 -290.960738) (xy 182.936089 -290.97443) (xy 182.887234 -290.980362) (xy 182.838059 -290.978381)
			(xy 182.78984 -290.968537) (xy 182.743824 -290.951085) (xy 182.701203 -290.926478) (xy 182.663082 -290.895353)
			(xy 182.630447 -290.858516) (xy 182.604144 -290.81692) (xy 182.584853 -290.771644) (xy 182.573076 -290.72386)
			(xy 182.569116 -290.674806) (xy 182.230268 -290.674806) (xy 182.229773 -290.699413) (xy 182.221878 -290.74799)
			(xy 182.206294 -290.794671) (xy 182.183423 -290.838248) (xy 182.153858 -290.877592) (xy 182.118365 -290.911684)
			(xy 182.077862 -290.93964) (xy 182.0334 -290.960738) (xy 181.986129 -290.97443) (xy 181.937274 -290.980362)
			(xy 181.888099 -290.978381) (xy 181.83988 -290.968537) (xy 181.793864 -290.951085) (xy 181.751243 -290.926478)
			(xy 181.713122 -290.895353) (xy 181.680487 -290.858516) (xy 181.654184 -290.81692) (xy 181.634893 -290.771644)
			(xy 181.623116 -290.72386) (xy 181.619156 -290.674806) (xy 181.280308 -290.674806) (xy 181.279813 -290.699413)
			(xy 181.271918 -290.74799) (xy 181.256334 -290.794671) (xy 181.233463 -290.838248) (xy 181.203898 -290.877592)
			(xy 181.168405 -290.911684) (xy 181.127902 -290.93964) (xy 181.08344 -290.960738) (xy 181.036169 -290.97443)
			(xy 180.987314 -290.980362) (xy 180.938139 -290.978381) (xy 180.88992 -290.968537) (xy 180.843904 -290.951085)
			(xy 180.801283 -290.926478) (xy 180.763162 -290.895353) (xy 180.730527 -290.858516) (xy 180.704224 -290.81692)
			(xy 180.684933 -290.771644) (xy 180.673156 -290.72386) (xy 180.669196 -290.674806) (xy 180.330348 -290.674806)
			(xy 180.329853 -290.699413) (xy 180.321958 -290.74799) (xy 180.306374 -290.794671) (xy 180.283503 -290.838248)
			(xy 180.253938 -290.877592) (xy 180.218445 -290.911684) (xy 180.177942 -290.93964) (xy 180.13348 -290.960738)
			(xy 180.086209 -290.97443) (xy 180.037354 -290.980362) (xy 179.988179 -290.978381) (xy 179.93996 -290.968537)
			(xy 179.893944 -290.951085) (xy 179.851323 -290.926478) (xy 179.813202 -290.895353) (xy 179.780567 -290.858516)
			(xy 179.754264 -290.81692) (xy 179.734973 -290.771644) (xy 179.723196 -290.72386) (xy 179.719236 -290.674806)
			(xy 179.380388 -290.674806) (xy 179.379893 -290.699413) (xy 179.371998 -290.74799) (xy 179.356414 -290.794671)
			(xy 179.333543 -290.838248) (xy 179.303978 -290.877592) (xy 179.268485 -290.911684) (xy 179.227982 -290.93964)
			(xy 179.18352 -290.960738) (xy 179.136249 -290.97443) (xy 179.087394 -290.980362) (xy 179.038219 -290.978381)
			(xy 178.99 -290.968537) (xy 178.943984 -290.951085) (xy 178.901363 -290.926478) (xy 178.863242 -290.895353)
			(xy 178.830607 -290.858516) (xy 178.804304 -290.81692) (xy 178.785013 -290.771644) (xy 178.773236 -290.72386)
			(xy 178.769276 -290.674806) (xy 178.430174 -290.674806) (xy 178.429679 -290.699413) (xy 178.421784 -290.74799)
			(xy 178.4062 -290.794671) (xy 178.383329 -290.838248) (xy 178.353764 -290.877592) (xy 178.318271 -290.911684)
			(xy 178.277768 -290.93964) (xy 178.233306 -290.960738) (xy 178.186035 -290.97443) (xy 178.13718 -290.980362)
			(xy 178.088005 -290.978381) (xy 178.039786 -290.968537) (xy 177.99377 -290.951085) (xy 177.951149 -290.926478)
			(xy 177.913028 -290.895353) (xy 177.880393 -290.858516) (xy 177.85409 -290.81692) (xy 177.834799 -290.771644)
			(xy 177.823022 -290.72386) (xy 177.819062 -290.674806) (xy 177.480214 -290.674806) (xy 177.479719 -290.699413)
			(xy 177.471824 -290.74799) (xy 177.45624 -290.794671) (xy 177.433369 -290.838248) (xy 177.403804 -290.877592)
			(xy 177.368311 -290.911684) (xy 177.327808 -290.93964) (xy 177.283346 -290.960738) (xy 177.236075 -290.97443)
			(xy 177.18722 -290.980362) (xy 177.138045 -290.978381) (xy 177.089826 -290.968537) (xy 177.04381 -290.951085)
			(xy 177.001189 -290.926478) (xy 176.963068 -290.895353) (xy 176.930433 -290.858516) (xy 176.90413 -290.81692)
			(xy 176.884839 -290.771644) (xy 176.873062 -290.72386) (xy 176.869102 -290.674806) (xy 176.530254 -290.674806)
			(xy 176.529759 -290.699413) (xy 176.521864 -290.74799) (xy 176.50628 -290.794671) (xy 176.483409 -290.838248)
			(xy 176.453844 -290.877592) (xy 176.418351 -290.911684) (xy 176.377848 -290.93964) (xy 176.333386 -290.960738)
			(xy 176.286115 -290.97443) (xy 176.23726 -290.980362) (xy 176.188085 -290.978381) (xy 176.139866 -290.968537)
			(xy 176.09385 -290.951085) (xy 176.051229 -290.926478) (xy 176.013108 -290.895353) (xy 175.980473 -290.858516)
			(xy 175.95417 -290.81692) (xy 175.934879 -290.771644) (xy 175.923102 -290.72386) (xy 175.919142 -290.674806)
			(xy 174.630334 -290.674806) (xy 174.629839 -290.699413) (xy 174.621944 -290.74799) (xy 174.60636 -290.794671)
			(xy 174.583489 -290.838248) (xy 174.553924 -290.877592) (xy 174.518431 -290.911684) (xy 174.477928 -290.93964)
			(xy 174.433466 -290.960738) (xy 174.386195 -290.97443) (xy 174.33734 -290.980362) (xy 174.288165 -290.978381)
			(xy 174.239946 -290.968537) (xy 174.19393 -290.951085) (xy 174.151309 -290.926478) (xy 174.113188 -290.895353)
			(xy 174.080553 -290.858516) (xy 174.05425 -290.81692) (xy 174.034959 -290.771644) (xy 174.023182 -290.72386)
			(xy 174.019222 -290.674806) (xy 173.680374 -290.674806) (xy 173.679879 -290.699413) (xy 173.671984 -290.74799)
			(xy 173.6564 -290.794671) (xy 173.633529 -290.838248) (xy 173.603964 -290.877592) (xy 173.568471 -290.911684)
			(xy 173.527968 -290.93964) (xy 173.483506 -290.960738) (xy 173.436235 -290.97443) (xy 173.38738 -290.980362)
			(xy 173.338205 -290.978381) (xy 173.289986 -290.968537) (xy 173.24397 -290.951085) (xy 173.201349 -290.926478)
			(xy 173.163228 -290.895353) (xy 173.130593 -290.858516) (xy 173.10429 -290.81692) (xy 173.084999 -290.771644)
			(xy 173.073222 -290.72386) (xy 173.069262 -290.674806) (xy 172.73016 -290.674806) (xy 172.729665 -290.699413)
			(xy 172.72177 -290.74799) (xy 172.706186 -290.794671) (xy 172.683315 -290.838248) (xy 172.65375 -290.877592)
			(xy 172.618257 -290.911684) (xy 172.577754 -290.93964) (xy 172.533292 -290.960738) (xy 172.486021 -290.97443)
			(xy 172.437166 -290.980362) (xy 172.387991 -290.978381) (xy 172.339772 -290.968537) (xy 172.293756 -290.951085)
			(xy 172.251135 -290.926478) (xy 172.213014 -290.895353) (xy 172.180379 -290.858516) (xy 172.154076 -290.81692)
			(xy 172.134785 -290.771644) (xy 172.123008 -290.72386) (xy 172.119048 -290.674806) (xy 171.7802 -290.674806)
			(xy 171.779705 -290.699413) (xy 171.77181 -290.74799) (xy 171.756226 -290.794671) (xy 171.733355 -290.838248)
			(xy 171.70379 -290.877592) (xy 171.668297 -290.911684) (xy 171.627794 -290.93964) (xy 171.583332 -290.960738)
			(xy 171.536061 -290.97443) (xy 171.487206 -290.980362) (xy 171.438031 -290.978381) (xy 171.389812 -290.968537)
			(xy 171.343796 -290.951085) (xy 171.301175 -290.926478) (xy 171.263054 -290.895353) (xy 171.230419 -290.858516)
			(xy 171.204116 -290.81692) (xy 171.184825 -290.771644) (xy 171.173048 -290.72386) (xy 171.169088 -290.674806)
			(xy 170.83024 -290.674806) (xy 170.829745 -290.699413) (xy 170.82185 -290.74799) (xy 170.806266 -290.794671)
			(xy 170.783395 -290.838248) (xy 170.75383 -290.877592) (xy 170.718337 -290.911684) (xy 170.677834 -290.93964)
			(xy 170.633372 -290.960738) (xy 170.586101 -290.97443) (xy 170.537246 -290.980362) (xy 170.488071 -290.978381)
			(xy 170.439852 -290.968537) (xy 170.393836 -290.951085) (xy 170.351215 -290.926478) (xy 170.313094 -290.895353)
			(xy 170.280459 -290.858516) (xy 170.254156 -290.81692) (xy 170.234865 -290.771644) (xy 170.223088 -290.72386)
			(xy 170.219128 -290.674806) (xy 169.88028 -290.674806) (xy 169.879785 -290.699413) (xy 169.87189 -290.74799)
			(xy 169.856306 -290.794671) (xy 169.833435 -290.838248) (xy 169.80387 -290.877592) (xy 169.768377 -290.911684)
			(xy 169.727874 -290.93964) (xy 169.683412 -290.960738) (xy 169.636141 -290.97443) (xy 169.587286 -290.980362)
			(xy 169.538111 -290.978381) (xy 169.489892 -290.968537) (xy 169.443876 -290.951085) (xy 169.401255 -290.926478)
			(xy 169.363134 -290.895353) (xy 169.330499 -290.858516) (xy 169.304196 -290.81692) (xy 169.284905 -290.771644)
			(xy 169.273128 -290.72386) (xy 169.269168 -290.674806) (xy 168.93032 -290.674806) (xy 168.929825 -290.699413)
			(xy 168.92193 -290.74799) (xy 168.906346 -290.794671) (xy 168.883475 -290.838248) (xy 168.85391 -290.877592)
			(xy 168.818417 -290.911684) (xy 168.777914 -290.93964) (xy 168.733452 -290.960738) (xy 168.686181 -290.97443)
			(xy 168.637326 -290.980362) (xy 168.588151 -290.978381) (xy 168.539932 -290.968537) (xy 168.493916 -290.951085)
			(xy 168.451295 -290.926478) (xy 168.413174 -290.895353) (xy 168.380539 -290.858516) (xy 168.354236 -290.81692)
			(xy 168.334945 -290.771644) (xy 168.323168 -290.72386) (xy 168.319208 -290.674806) (xy 167.98036 -290.674806)
			(xy 167.979865 -290.699413) (xy 167.97197 -290.74799) (xy 167.956386 -290.794671) (xy 167.933515 -290.838248)
			(xy 167.90395 -290.877592) (xy 167.868457 -290.911684) (xy 167.827954 -290.93964) (xy 167.783492 -290.960738)
			(xy 167.736221 -290.97443) (xy 167.687366 -290.980362) (xy 167.638191 -290.978381) (xy 167.589972 -290.968537)
			(xy 167.543956 -290.951085) (xy 167.501335 -290.926478) (xy 167.463214 -290.895353) (xy 167.430579 -290.858516)
			(xy 167.404276 -290.81692) (xy 167.384985 -290.771644) (xy 167.373208 -290.72386) (xy 167.369248 -290.674806)
			(xy 167.0304 -290.674806) (xy 167.029905 -290.699413) (xy 167.02201 -290.74799) (xy 167.006426 -290.794671)
			(xy 166.983555 -290.838248) (xy 166.95399 -290.877592) (xy 166.918497 -290.911684) (xy 166.877994 -290.93964)
			(xy 166.833532 -290.960738) (xy 166.786261 -290.97443) (xy 166.737406 -290.980362) (xy 166.688231 -290.978381)
			(xy 166.640012 -290.968537) (xy 166.593996 -290.951085) (xy 166.551375 -290.926478) (xy 166.513254 -290.895353)
			(xy 166.480619 -290.858516) (xy 166.454316 -290.81692) (xy 166.435025 -290.771644) (xy 166.423248 -290.72386)
			(xy 166.419288 -290.674806) (xy 166.080186 -290.674806) (xy 166.079691 -290.699413) (xy 166.071796 -290.74799)
			(xy 166.056212 -290.794671) (xy 166.033341 -290.838248) (xy 166.003776 -290.877592) (xy 165.968283 -290.911684)
			(xy 165.92778 -290.93964) (xy 165.883318 -290.960738) (xy 165.836047 -290.97443) (xy 165.787192 -290.980362)
			(xy 165.738017 -290.978381) (xy 165.689798 -290.968537) (xy 165.643782 -290.951085) (xy 165.601161 -290.926478)
			(xy 165.56304 -290.895353) (xy 165.530405 -290.858516) (xy 165.504102 -290.81692) (xy 165.484811 -290.771644)
			(xy 165.473034 -290.72386) (xy 165.469074 -290.674806) (xy 165.155078 -290.674806) (xy 165.155078 -290.701182)
			(xy 165.1467 -290.753275) (xy 165.130156 -290.803376) (xy 165.105868 -290.850215) (xy 165.074449 -290.892604)
			(xy 165.036699 -290.929465) (xy 164.993575 -290.959865) (xy 164.946171 -290.983032) (xy 164.89569 -290.998377)
			(xy 164.869622 -291.002466) (xy 164.86505 -291.003228) (xy 164.854636 -291.00653) (xy 164.850318 -291.0078)
			(xy 164.826696 -291.018722) (xy 164.819838 -291.025834) (xy 164.804852 -291.041582) (xy 164.800262 -291.046686)
			(xy 164.793812 -291.058798) (xy 164.792152 -291.065458) (xy 164.790882 -291.07638) (xy 164.790882 -291.223192)
			(xy 164.791344 -291.232827) (xy 164.793693 -291.238686) (xy 202.096622 -291.238686) (xy 202.100693 -291.183064)
			(xy 202.112819 -291.128627) (xy 202.132742 -291.076536) (xy 202.160038 -291.027901) (xy 202.194124 -290.983758)
			(xy 202.234273 -290.945049) (xy 202.279631 -290.912598) (xy 202.329231 -290.887097) (xy 202.382015 -290.86909)
			(xy 202.436858 -290.85896) (xy 202.492592 -290.856923) (xy 202.548029 -290.863023) (xy 202.601986 -290.877129)
			(xy 202.653315 -290.898941) (xy 202.655301 -290.900153) (xy 227.087881 -290.900153) (xy 227.087881 -290.845647)
			(xy 227.095639 -290.791697) (xy 227.110996 -290.739399) (xy 227.133639 -290.68982) (xy 227.163109 -290.643968)
			(xy 227.198804 -290.602777) (xy 227.239999 -290.567086) (xy 227.285853 -290.537621) (xy 227.335435 -290.514982)
			(xy 227.387734 -290.499631) (xy 227.441685 -290.491879) (xy 227.468938 -290.491418) (xy 227.496307 -290.491916)
			(xy 227.550485 -290.499725) (xy 227.602988 -290.515207) (xy 227.652735 -290.538042) (xy 227.698703 -290.56776)
			(xy 227.719636 -290.585398) (xy 227.726748 -290.591494) (xy 227.743766 -290.597844) (xy 227.82911 -290.597844)
			(xy 227.846128 -290.591494) (xy 227.85324 -290.585398) (xy 227.874184 -290.567773) (xy 227.920153 -290.538059)
			(xy 227.969898 -290.515221) (xy 228.022396 -290.499726) (xy 228.07657 -290.491894) (xy 228.103938 -290.491418)
			(xy 228.131189 -290.491854) (xy 228.185137 -290.499616) (xy 228.23743 -290.514975) (xy 228.287006 -290.53762)
			(xy 228.332855 -290.56709) (xy 228.374043 -290.602783) (xy 228.409733 -290.643976) (xy 228.439198 -290.689827)
			(xy 228.461838 -290.739405) (xy 228.477192 -290.791701) (xy 228.484948 -290.845649) (xy 228.484948 -290.900151)
			(xy 228.484948 -290.900153) (xy 228.827781 -290.900153) (xy 228.827781 -290.845647) (xy 228.835539 -290.791697)
			(xy 228.850896 -290.739399) (xy 228.873539 -290.68982) (xy 228.903009 -290.643968) (xy 228.938704 -290.602777)
			(xy 228.979899 -290.567086) (xy 229.025753 -290.537621) (xy 229.075335 -290.514982) (xy 229.127634 -290.499631)
			(xy 229.181585 -290.491879) (xy 229.208838 -290.491418) (xy 229.236207 -290.491916) (xy 229.290385 -290.499725)
			(xy 229.342888 -290.515207) (xy 229.392635 -290.538042) (xy 229.438603 -290.56776) (xy 229.459536 -290.585398)
			(xy 229.466648 -290.591494) (xy 229.483666 -290.597844) (xy 229.56901 -290.597844) (xy 229.586028 -290.591494)
			(xy 229.59314 -290.585398) (xy 229.614084 -290.567773) (xy 229.660053 -290.538059) (xy 229.709798 -290.515221)
			(xy 229.762296 -290.499726) (xy 229.81647 -290.491894) (xy 229.843838 -290.491418) (xy 229.871089 -290.491854)
			(xy 229.925037 -290.499616) (xy 229.97733 -290.514975) (xy 230.026906 -290.53762) (xy 230.072755 -290.56709)
			(xy 230.113943 -290.602783) (xy 230.149633 -290.643976) (xy 230.179098 -290.689827) (xy 230.201738 -290.739405)
			(xy 230.217092 -290.791701) (xy 230.224848 -290.845649) (xy 230.224848 -290.900151) (xy 230.217092 -290.954099)
			(xy 230.201738 -291.006395) (xy 230.179098 -291.055973) (xy 230.149633 -291.101824) (xy 230.113943 -291.143017)
			(xy 230.072755 -291.17871) (xy 230.026906 -291.20818) (xy 229.97733 -291.230825) (xy 229.925037 -291.246184)
			(xy 229.871089 -291.253946) (xy 229.843838 -291.254434) (xy 229.816468 -291.253962) (xy 229.762288 -291.246148)
			(xy 229.709785 -291.230661) (xy 229.660038 -291.20782) (xy 229.614071 -291.178096) (xy 229.59314 -291.160454)
			(xy 229.586028 -291.154358) (xy 229.56901 -291.148008) (xy 229.483666 -291.148008) (xy 229.466648 -291.154358)
			(xy 229.459536 -291.160454) (xy 229.438595 -291.178083) (xy 229.392626 -291.207798) (xy 229.34288 -291.230636)
			(xy 229.290381 -291.24613) (xy 229.236207 -291.253959) (xy 229.208838 -291.254434) (xy 229.181585 -291.253921)
			(xy 229.127634 -291.246169) (xy 229.075335 -291.230818) (xy 229.025753 -291.208179) (xy 228.979899 -291.178714)
			(xy 228.938704 -291.143023) (xy 228.903009 -291.101832) (xy 228.873539 -291.05598) (xy 228.850896 -291.006401)
			(xy 228.835539 -290.954103) (xy 228.827781 -290.900153) (xy 228.484948 -290.900153) (xy 228.477192 -290.954099)
			(xy 228.461838 -291.006395) (xy 228.439198 -291.055973) (xy 228.409733 -291.101824) (xy 228.374043 -291.143017)
			(xy 228.332855 -291.17871) (xy 228.287006 -291.20818) (xy 228.23743 -291.230825) (xy 228.185137 -291.246184)
			(xy 228.131189 -291.253946) (xy 228.103938 -291.254434) (xy 228.076568 -291.253962) (xy 228.022388 -291.246148)
			(xy 227.969885 -291.230661) (xy 227.920138 -291.20782) (xy 227.874171 -291.178096) (xy 227.85324 -291.160454)
			(xy 227.846128 -291.154358) (xy 227.82911 -291.148008) (xy 227.743766 -291.148008) (xy 227.726748 -291.154358)
			(xy 227.719636 -291.160454) (xy 227.698695 -291.178083) (xy 227.652726 -291.207798) (xy 227.60298 -291.230636)
			(xy 227.550481 -291.24613) (xy 227.496307 -291.253959) (xy 227.468938 -291.254434) (xy 227.441685 -291.253921)
			(xy 227.387734 -291.246169) (xy 227.335435 -291.230818) (xy 227.285853 -291.208179) (xy 227.239999 -291.178714)
			(xy 227.198804 -291.143023) (xy 227.163109 -291.101832) (xy 227.133639 -291.05598) (xy 227.110996 -291.006401)
			(xy 227.095639 -290.954103) (xy 227.087881 -290.900153) (xy 202.655301 -290.900153) (xy 202.700921 -290.927995)
			(xy 202.743789 -290.96367) (xy 202.781006 -291.005207) (xy 202.811779 -291.05172) (xy 202.835451 -291.102217)
			(xy 202.851519 -291.155624) (xy 202.859639 -291.2108) (xy 202.860148 -291.238686) (xy 202.859639 -291.266572)
			(xy 202.851519 -291.321748) (xy 202.835451 -291.375155) (xy 202.811779 -291.425652) (xy 202.781006 -291.472165)
			(xy 202.743789 -291.513702) (xy 202.700921 -291.549377) (xy 202.653315 -291.578431) (xy 202.621384 -291.592)
			(xy 204.54188 -291.592) (xy 204.545951 -291.536378) (xy 204.558077 -291.481941) (xy 204.578 -291.42985)
			(xy 204.605296 -291.381215) (xy 204.639382 -291.337072) (xy 204.679531 -291.298363) (xy 204.724889 -291.265912)
			(xy 204.774489 -291.240411) (xy 204.827273 -291.222404) (xy 204.882116 -291.212274) (xy 204.93785 -291.210237)
			(xy 204.993287 -291.216337) (xy 205.047244 -291.230443) (xy 205.098573 -291.252255) (xy 205.146179 -291.281309)
			(xy 205.189047 -291.316984) (xy 205.226264 -291.358521) (xy 205.257037 -291.405034) (xy 205.280709 -291.455531)
			(xy 205.296777 -291.508938) (xy 205.304897 -291.564114) (xy 205.305406 -291.592) (xy 205.304897 -291.619886)
			(xy 205.296777 -291.675062) (xy 205.280709 -291.728469) (xy 205.257037 -291.778966) (xy 205.226264 -291.825479)
			(xy 205.189047 -291.867016) (xy 205.146179 -291.902691) (xy 205.098573 -291.931745) (xy 205.047244 -291.953557)
			(xy 204.993287 -291.967663) (xy 204.93785 -291.973763) (xy 204.882116 -291.971726) (xy 204.827273 -291.961596)
			(xy 204.774489 -291.943589) (xy 204.724889 -291.918088) (xy 204.679531 -291.885637) (xy 204.639382 -291.846928)
			(xy 204.605296 -291.802785) (xy 204.578 -291.75415) (xy 204.558077 -291.702059) (xy 204.545951 -291.647622)
			(xy 204.54188 -291.592) (xy 202.621384 -291.592) (xy 202.601986 -291.600243) (xy 202.548029 -291.614349)
			(xy 202.492592 -291.620449) (xy 202.436858 -291.618412) (xy 202.382015 -291.608282) (xy 202.329231 -291.590275)
			(xy 202.279631 -291.564774) (xy 202.234273 -291.532323) (xy 202.194124 -291.493614) (xy 202.160038 -291.449471)
			(xy 202.132742 -291.400836) (xy 202.112819 -291.348745) (xy 202.100693 -291.294308) (xy 202.096622 -291.238686)
			(xy 164.793693 -291.238686) (xy 164.798517 -291.250717) (xy 164.804852 -291.25799) (xy 164.820092 -291.273992)
			(xy 164.82695 -291.281358) (xy 164.850318 -291.291772) (xy 164.854636 -291.293042) (xy 164.86505 -291.296344)
			(xy 164.869622 -291.297106) (xy 164.895694 -291.301183) (xy 164.946182 -291.31653) (xy 164.993592 -291.339699)
			(xy 165.036722 -291.370102) (xy 165.074477 -291.406968) (xy 165.105899 -291.44936) (xy 165.130191 -291.496205)
			(xy 165.146737 -291.546312) (xy 165.155117 -291.598411) (xy 165.155117 -291.624766) (xy 165.469074 -291.624766)
			(xy 165.473034 -291.575712) (xy 165.484811 -291.527928) (xy 165.504102 -291.482652) (xy 165.530405 -291.441056)
			(xy 165.56304 -291.404219) (xy 165.601161 -291.373094) (xy 165.643782 -291.348487) (xy 165.689798 -291.331035)
			(xy 165.738017 -291.321191) (xy 165.787192 -291.31921) (xy 165.836047 -291.325142) (xy 165.883318 -291.338834)
			(xy 165.92778 -291.359932) (xy 165.968283 -291.387888) (xy 166.003776 -291.42198) (xy 166.033341 -291.461324)
			(xy 166.056212 -291.504901) (xy 166.071796 -291.551582) (xy 166.079691 -291.600159) (xy 166.080186 -291.624766)
			(xy 166.419288 -291.624766) (xy 166.423248 -291.575712) (xy 166.435025 -291.527928) (xy 166.454316 -291.482652)
			(xy 166.480619 -291.441056) (xy 166.513254 -291.404219) (xy 166.551375 -291.373094) (xy 166.593996 -291.348487)
			(xy 166.640012 -291.331035) (xy 166.688231 -291.321191) (xy 166.737406 -291.31921) (xy 166.786261 -291.325142)
			(xy 166.833532 -291.338834) (xy 166.877994 -291.359932) (xy 166.918497 -291.387888) (xy 166.95399 -291.42198)
			(xy 166.983555 -291.461324) (xy 167.006426 -291.504901) (xy 167.02201 -291.551582) (xy 167.029905 -291.600159)
			(xy 167.0304 -291.624766) (xy 167.369248 -291.624766) (xy 167.373208 -291.575712) (xy 167.384985 -291.527928)
			(xy 167.404276 -291.482652) (xy 167.430579 -291.441056) (xy 167.463214 -291.404219) (xy 167.501335 -291.373094)
			(xy 167.543956 -291.348487) (xy 167.589972 -291.331035) (xy 167.638191 -291.321191) (xy 167.687366 -291.31921)
			(xy 167.736221 -291.325142) (xy 167.783492 -291.338834) (xy 167.827954 -291.359932) (xy 167.868457 -291.387888)
			(xy 167.90395 -291.42198) (xy 167.933515 -291.461324) (xy 167.956386 -291.504901) (xy 167.97197 -291.551582)
			(xy 167.979865 -291.600159) (xy 167.98036 -291.624766) (xy 168.319208 -291.624766) (xy 168.323168 -291.575712)
			(xy 168.334945 -291.527928) (xy 168.354236 -291.482652) (xy 168.380539 -291.441056) (xy 168.413174 -291.404219)
			(xy 168.451295 -291.373094) (xy 168.493916 -291.348487) (xy 168.539932 -291.331035) (xy 168.588151 -291.321191)
			(xy 168.637326 -291.31921) (xy 168.686181 -291.325142) (xy 168.733452 -291.338834) (xy 168.777914 -291.359932)
			(xy 168.818417 -291.387888) (xy 168.85391 -291.42198) (xy 168.883475 -291.461324) (xy 168.906346 -291.504901)
			(xy 168.92193 -291.551582) (xy 168.929825 -291.600159) (xy 168.93032 -291.624766) (xy 169.269168 -291.624766)
			(xy 169.273128 -291.575712) (xy 169.284905 -291.527928) (xy 169.304196 -291.482652) (xy 169.330499 -291.441056)
			(xy 169.363134 -291.404219) (xy 169.401255 -291.373094) (xy 169.443876 -291.348487) (xy 169.489892 -291.331035)
			(xy 169.538111 -291.321191) (xy 169.587286 -291.31921) (xy 169.636141 -291.325142) (xy 169.683412 -291.338834)
			(xy 169.727874 -291.359932) (xy 169.768377 -291.387888) (xy 169.80387 -291.42198) (xy 169.833435 -291.461324)
			(xy 169.856306 -291.504901) (xy 169.87189 -291.551582) (xy 169.879785 -291.600159) (xy 169.88028 -291.624766)
			(xy 170.219128 -291.624766) (xy 170.223088 -291.575712) (xy 170.234865 -291.527928) (xy 170.254156 -291.482652)
			(xy 170.280459 -291.441056) (xy 170.313094 -291.404219) (xy 170.351215 -291.373094) (xy 170.393836 -291.348487)
			(xy 170.439852 -291.331035) (xy 170.488071 -291.321191) (xy 170.537246 -291.31921) (xy 170.586101 -291.325142)
			(xy 170.633372 -291.338834) (xy 170.677834 -291.359932) (xy 170.718337 -291.387888) (xy 170.75383 -291.42198)
			(xy 170.783395 -291.461324) (xy 170.806266 -291.504901) (xy 170.82185 -291.551582) (xy 170.829745 -291.600159)
			(xy 170.83024 -291.624766) (xy 171.169088 -291.624766) (xy 171.173048 -291.575712) (xy 171.184825 -291.527928)
			(xy 171.204116 -291.482652) (xy 171.230419 -291.441056) (xy 171.263054 -291.404219) (xy 171.301175 -291.373094)
			(xy 171.343796 -291.348487) (xy 171.389812 -291.331035) (xy 171.438031 -291.321191) (xy 171.487206 -291.31921)
			(xy 171.536061 -291.325142) (xy 171.583332 -291.338834) (xy 171.627794 -291.359932) (xy 171.668297 -291.387888)
			(xy 171.70379 -291.42198) (xy 171.733355 -291.461324) (xy 171.756226 -291.504901) (xy 171.77181 -291.551582)
			(xy 171.779705 -291.600159) (xy 171.7802 -291.624766) (xy 172.119048 -291.624766) (xy 172.123008 -291.575712)
			(xy 172.134785 -291.527928) (xy 172.154076 -291.482652) (xy 172.180379 -291.441056) (xy 172.213014 -291.404219)
			(xy 172.251135 -291.373094) (xy 172.293756 -291.348487) (xy 172.339772 -291.331035) (xy 172.387991 -291.321191)
			(xy 172.437166 -291.31921) (xy 172.486021 -291.325142) (xy 172.533292 -291.338834) (xy 172.577754 -291.359932)
			(xy 172.618257 -291.387888) (xy 172.65375 -291.42198) (xy 172.683315 -291.461324) (xy 172.706186 -291.504901)
			(xy 172.72177 -291.551582) (xy 172.729665 -291.600159) (xy 172.73016 -291.624766) (xy 173.069262 -291.624766)
			(xy 173.073222 -291.575712) (xy 173.084999 -291.527928) (xy 173.10429 -291.482652) (xy 173.130593 -291.441056)
			(xy 173.163228 -291.404219) (xy 173.201349 -291.373094) (xy 173.24397 -291.348487) (xy 173.289986 -291.331035)
			(xy 173.338205 -291.321191) (xy 173.38738 -291.31921) (xy 173.436235 -291.325142) (xy 173.483506 -291.338834)
			(xy 173.527968 -291.359932) (xy 173.568471 -291.387888) (xy 173.603964 -291.42198) (xy 173.633529 -291.461324)
			(xy 173.6564 -291.504901) (xy 173.671984 -291.551582) (xy 173.679879 -291.600159) (xy 173.680374 -291.624766)
			(xy 174.019222 -291.624766) (xy 174.023182 -291.575712) (xy 174.034959 -291.527928) (xy 174.05425 -291.482652)
			(xy 174.080553 -291.441056) (xy 174.113188 -291.404219) (xy 174.151309 -291.373094) (xy 174.19393 -291.348487)
			(xy 174.239946 -291.331035) (xy 174.288165 -291.321191) (xy 174.33734 -291.31921) (xy 174.386195 -291.325142)
			(xy 174.433466 -291.338834) (xy 174.477928 -291.359932) (xy 174.518431 -291.387888) (xy 174.553924 -291.42198)
			(xy 174.583489 -291.461324) (xy 174.60636 -291.504901) (xy 174.621944 -291.551582) (xy 174.629839 -291.600159)
			(xy 174.630334 -291.624766) (xy 175.919142 -291.624766) (xy 175.923102 -291.575712) (xy 175.934879 -291.527928)
			(xy 175.95417 -291.482652) (xy 175.980473 -291.441056) (xy 176.013108 -291.404219) (xy 176.051229 -291.373094)
			(xy 176.09385 -291.348487) (xy 176.139866 -291.331035) (xy 176.188085 -291.321191) (xy 176.23726 -291.31921)
			(xy 176.286115 -291.325142) (xy 176.333386 -291.338834) (xy 176.377848 -291.359932) (xy 176.418351 -291.387888)
			(xy 176.453844 -291.42198) (xy 176.483409 -291.461324) (xy 176.50628 -291.504901) (xy 176.521864 -291.551582)
			(xy 176.529759 -291.600159) (xy 176.530254 -291.624766) (xy 176.869102 -291.624766) (xy 176.873062 -291.575712)
			(xy 176.884839 -291.527928) (xy 176.90413 -291.482652) (xy 176.930433 -291.441056) (xy 176.963068 -291.404219)
			(xy 177.001189 -291.373094) (xy 177.04381 -291.348487) (xy 177.089826 -291.331035) (xy 177.138045 -291.321191)
			(xy 177.18722 -291.31921) (xy 177.236075 -291.325142) (xy 177.283346 -291.338834) (xy 177.327808 -291.359932)
			(xy 177.368311 -291.387888) (xy 177.403804 -291.42198) (xy 177.433369 -291.461324) (xy 177.45624 -291.504901)
			(xy 177.471824 -291.551582) (xy 177.479719 -291.600159) (xy 177.480214 -291.624766) (xy 177.819062 -291.624766)
			(xy 177.823022 -291.575712) (xy 177.834799 -291.527928) (xy 177.85409 -291.482652) (xy 177.880393 -291.441056)
			(xy 177.913028 -291.404219) (xy 177.951149 -291.373094) (xy 177.99377 -291.348487) (xy 178.039786 -291.331035)
			(xy 178.088005 -291.321191) (xy 178.13718 -291.31921) (xy 178.186035 -291.325142) (xy 178.233306 -291.338834)
			(xy 178.277768 -291.359932) (xy 178.318271 -291.387888) (xy 178.353764 -291.42198) (xy 178.383329 -291.461324)
			(xy 178.4062 -291.504901) (xy 178.421784 -291.551582) (xy 178.429679 -291.600159) (xy 178.430174 -291.624766)
			(xy 178.769276 -291.624766) (xy 178.773236 -291.575712) (xy 178.785013 -291.527928) (xy 178.804304 -291.482652)
			(xy 178.830607 -291.441056) (xy 178.863242 -291.404219) (xy 178.901363 -291.373094) (xy 178.943984 -291.348487)
			(xy 178.99 -291.331035) (xy 179.038219 -291.321191) (xy 179.087394 -291.31921) (xy 179.136249 -291.325142)
			(xy 179.18352 -291.338834) (xy 179.227982 -291.359932) (xy 179.268485 -291.387888) (xy 179.303978 -291.42198)
			(xy 179.333543 -291.461324) (xy 179.356414 -291.504901) (xy 179.371998 -291.551582) (xy 179.379893 -291.600159)
			(xy 179.380388 -291.624766) (xy 179.719236 -291.624766) (xy 179.723196 -291.575712) (xy 179.734973 -291.527928)
			(xy 179.754264 -291.482652) (xy 179.780567 -291.441056) (xy 179.813202 -291.404219) (xy 179.851323 -291.373094)
			(xy 179.893944 -291.348487) (xy 179.93996 -291.331035) (xy 179.988179 -291.321191) (xy 180.037354 -291.31921)
			(xy 180.086209 -291.325142) (xy 180.13348 -291.338834) (xy 180.177942 -291.359932) (xy 180.218445 -291.387888)
			(xy 180.253938 -291.42198) (xy 180.283503 -291.461324) (xy 180.306374 -291.504901) (xy 180.321958 -291.551582)
			(xy 180.329853 -291.600159) (xy 180.330348 -291.624766) (xy 180.669196 -291.624766) (xy 180.673156 -291.575712)
			(xy 180.684933 -291.527928) (xy 180.704224 -291.482652) (xy 180.730527 -291.441056) (xy 180.763162 -291.404219)
			(xy 180.801283 -291.373094) (xy 180.843904 -291.348487) (xy 180.88992 -291.331035) (xy 180.938139 -291.321191)
			(xy 180.987314 -291.31921) (xy 181.036169 -291.325142) (xy 181.08344 -291.338834) (xy 181.127902 -291.359932)
			(xy 181.168405 -291.387888) (xy 181.203898 -291.42198) (xy 181.233463 -291.461324) (xy 181.256334 -291.504901)
			(xy 181.271918 -291.551582) (xy 181.279813 -291.600159) (xy 181.280308 -291.624766) (xy 181.619156 -291.624766)
			(xy 181.623116 -291.575712) (xy 181.634893 -291.527928) (xy 181.654184 -291.482652) (xy 181.680487 -291.441056)
			(xy 181.713122 -291.404219) (xy 181.751243 -291.373094) (xy 181.793864 -291.348487) (xy 181.83988 -291.331035)
			(xy 181.888099 -291.321191) (xy 181.937274 -291.31921) (xy 181.986129 -291.325142) (xy 182.0334 -291.338834)
			(xy 182.077862 -291.359932) (xy 182.118365 -291.387888) (xy 182.153858 -291.42198) (xy 182.183423 -291.461324)
			(xy 182.206294 -291.504901) (xy 182.221878 -291.551582) (xy 182.229773 -291.600159) (xy 182.230268 -291.624766)
			(xy 182.569116 -291.624766) (xy 182.573076 -291.575712) (xy 182.584853 -291.527928) (xy 182.604144 -291.482652)
			(xy 182.630447 -291.441056) (xy 182.663082 -291.404219) (xy 182.701203 -291.373094) (xy 182.743824 -291.348487)
			(xy 182.78984 -291.331035) (xy 182.838059 -291.321191) (xy 182.887234 -291.31921) (xy 182.936089 -291.325142)
			(xy 182.98336 -291.338834) (xy 183.027822 -291.359932) (xy 183.068325 -291.387888) (xy 183.103818 -291.42198)
			(xy 183.133383 -291.461324) (xy 183.156254 -291.504901) (xy 183.171838 -291.551582) (xy 183.179733 -291.600159)
			(xy 183.180228 -291.624766) (xy 183.519076 -291.624766) (xy 183.523036 -291.575712) (xy 183.534813 -291.527928)
			(xy 183.554104 -291.482652) (xy 183.580407 -291.441056) (xy 183.613042 -291.404219) (xy 183.651163 -291.373094)
			(xy 183.693784 -291.348487) (xy 183.7398 -291.331035) (xy 183.788019 -291.321191) (xy 183.837194 -291.31921)
			(xy 183.886049 -291.325142) (xy 183.93332 -291.338834) (xy 183.977782 -291.359932) (xy 184.018285 -291.387888)
			(xy 184.053778 -291.42198) (xy 184.083343 -291.461324) (xy 184.106214 -291.504901) (xy 184.121798 -291.551582)
			(xy 184.129693 -291.600159) (xy 184.130188 -291.624766) (xy 184.469036 -291.624766) (xy 184.472996 -291.575712)
			(xy 184.484773 -291.527928) (xy 184.504064 -291.482652) (xy 184.530367 -291.441056) (xy 184.563002 -291.404219)
			(xy 184.601123 -291.373094) (xy 184.643744 -291.348487) (xy 184.68976 -291.331035) (xy 184.737979 -291.321191)
			(xy 184.787154 -291.31921) (xy 184.836009 -291.325142) (xy 184.88328 -291.338834) (xy 184.927742 -291.359932)
			(xy 184.968245 -291.387888) (xy 185.003738 -291.42198) (xy 185.033303 -291.461324) (xy 185.056174 -291.504901)
			(xy 185.071758 -291.551582) (xy 185.079653 -291.600159) (xy 185.080148 -291.624766) (xy 185.41925 -291.624766)
			(xy 185.42321 -291.575712) (xy 185.434987 -291.527928) (xy 185.454278 -291.482652) (xy 185.480581 -291.441056)
			(xy 185.513216 -291.404219) (xy 185.551337 -291.373094) (xy 185.593958 -291.348487) (xy 185.639974 -291.331035)
			(xy 185.688193 -291.321191) (xy 185.737368 -291.31921) (xy 185.786223 -291.325142) (xy 185.833494 -291.338834)
			(xy 185.877956 -291.359932) (xy 185.918459 -291.387888) (xy 185.953952 -291.42198) (xy 185.983517 -291.461324)
			(xy 186.006388 -291.504901) (xy 186.021972 -291.551582) (xy 186.029867 -291.600159) (xy 186.030362 -291.624766)
			(xy 186.36921 -291.624766) (xy 186.37317 -291.575712) (xy 186.384947 -291.527928) (xy 186.404238 -291.482652)
			(xy 186.430541 -291.441056) (xy 186.463176 -291.404219) (xy 186.501297 -291.373094) (xy 186.543918 -291.348487)
			(xy 186.589934 -291.331035) (xy 186.638153 -291.321191) (xy 186.687328 -291.31921) (xy 186.736183 -291.325142)
			(xy 186.783454 -291.338834) (xy 186.827916 -291.359932) (xy 186.868419 -291.387888) (xy 186.903912 -291.42198)
			(xy 186.933477 -291.461324) (xy 186.956348 -291.504901) (xy 186.971932 -291.551582) (xy 186.979827 -291.600159)
			(xy 186.980322 -291.624766) (xy 187.31917 -291.624766) (xy 187.32313 -291.575712) (xy 187.334907 -291.527928)
			(xy 187.354198 -291.482652) (xy 187.380501 -291.441056) (xy 187.413136 -291.404219) (xy 187.451257 -291.373094)
			(xy 187.493878 -291.348487) (xy 187.539894 -291.331035) (xy 187.588113 -291.321191) (xy 187.637288 -291.31921)
			(xy 187.686143 -291.325142) (xy 187.733414 -291.338834) (xy 187.777876 -291.359932) (xy 187.818379 -291.387888)
			(xy 187.853872 -291.42198) (xy 187.883437 -291.461324) (xy 187.906308 -291.504901) (xy 187.921892 -291.551582)
			(xy 187.929787 -291.600159) (xy 187.930282 -291.624766) (xy 188.26913 -291.624766) (xy 188.27309 -291.575712)
			(xy 188.284867 -291.527928) (xy 188.304158 -291.482652) (xy 188.330461 -291.441056) (xy 188.363096 -291.404219)
			(xy 188.401217 -291.373094) (xy 188.443838 -291.348487) (xy 188.489854 -291.331035) (xy 188.538073 -291.321191)
			(xy 188.587248 -291.31921) (xy 188.636103 -291.325142) (xy 188.683374 -291.338834) (xy 188.727836 -291.359932)
			(xy 188.768339 -291.387888) (xy 188.803832 -291.42198) (xy 188.833397 -291.461324) (xy 188.856268 -291.504901)
			(xy 188.871852 -291.551582) (xy 188.879747 -291.600159) (xy 188.880242 -291.624766) (xy 189.21909 -291.624766)
			(xy 189.22305 -291.575712) (xy 189.234827 -291.527928) (xy 189.254118 -291.482652) (xy 189.280421 -291.441056)
			(xy 189.313056 -291.404219) (xy 189.351177 -291.373094) (xy 189.393798 -291.348487) (xy 189.439814 -291.331035)
			(xy 189.488033 -291.321191) (xy 189.537208 -291.31921) (xy 189.586063 -291.325142) (xy 189.633334 -291.338834)
			(xy 189.677796 -291.359932) (xy 189.718299 -291.387888) (xy 189.753792 -291.42198) (xy 189.783357 -291.461324)
			(xy 189.806228 -291.504901) (xy 189.821812 -291.551582) (xy 189.829707 -291.600159) (xy 189.830202 -291.624766)
			(xy 190.169304 -291.624766) (xy 190.173264 -291.575712) (xy 190.185041 -291.527928) (xy 190.204332 -291.482652)
			(xy 190.230635 -291.441056) (xy 190.26327 -291.404219) (xy 190.301391 -291.373094) (xy 190.344012 -291.348487)
			(xy 190.390028 -291.331035) (xy 190.438247 -291.321191) (xy 190.487422 -291.31921) (xy 190.536277 -291.325142)
			(xy 190.583548 -291.338834) (xy 190.62801 -291.359932) (xy 190.668513 -291.387888) (xy 190.704006 -291.42198)
			(xy 190.733571 -291.461324) (xy 190.756442 -291.504901) (xy 190.772026 -291.551582) (xy 190.779921 -291.600159)
			(xy 190.780416 -291.624766) (xy 192.069224 -291.624766) (xy 192.073184 -291.575712) (xy 192.084961 -291.527928)
			(xy 192.104252 -291.482652) (xy 192.130555 -291.441056) (xy 192.16319 -291.404219) (xy 192.201311 -291.373094)
			(xy 192.243932 -291.348487) (xy 192.289948 -291.331035) (xy 192.338167 -291.321191) (xy 192.387342 -291.31921)
			(xy 192.436197 -291.325142) (xy 192.483468 -291.338834) (xy 192.52793 -291.359932) (xy 192.568433 -291.387888)
			(xy 192.603926 -291.42198) (xy 192.633491 -291.461324) (xy 192.656362 -291.504901) (xy 192.671946 -291.551582)
			(xy 192.679841 -291.600159) (xy 192.680336 -291.624766) (xy 193.019184 -291.624766) (xy 193.023144 -291.575712)
			(xy 193.034921 -291.527928) (xy 193.054212 -291.482652) (xy 193.080515 -291.441056) (xy 193.11315 -291.404219)
			(xy 193.151271 -291.373094) (xy 193.193892 -291.348487) (xy 193.239908 -291.331035) (xy 193.288127 -291.321191)
			(xy 193.337302 -291.31921) (xy 193.386157 -291.325142) (xy 193.433428 -291.338834) (xy 193.47789 -291.359932)
			(xy 193.518393 -291.387888) (xy 193.553886 -291.42198) (xy 193.583451 -291.461324) (xy 193.606322 -291.504901)
			(xy 193.621906 -291.551582) (xy 193.629801 -291.600159) (xy 193.630296 -291.624766) (xy 193.969144 -291.624766)
			(xy 193.973104 -291.575712) (xy 193.984881 -291.527928) (xy 194.004172 -291.482652) (xy 194.030475 -291.441056)
			(xy 194.06311 -291.404219) (xy 194.101231 -291.373094) (xy 194.143852 -291.348487) (xy 194.189868 -291.331035)
			(xy 194.238087 -291.321191) (xy 194.287262 -291.31921) (xy 194.336117 -291.325142) (xy 194.383388 -291.338834)
			(xy 194.42785 -291.359932) (xy 194.468353 -291.387888) (xy 194.503846 -291.42198) (xy 194.533411 -291.461324)
			(xy 194.556282 -291.504901) (xy 194.571866 -291.551582) (xy 194.579761 -291.600159) (xy 194.580256 -291.624766)
			(xy 194.919104 -291.624766) (xy 194.923064 -291.575712) (xy 194.934841 -291.527928) (xy 194.954132 -291.482652)
			(xy 194.980435 -291.441056) (xy 195.01307 -291.404219) (xy 195.051191 -291.373094) (xy 195.093812 -291.348487)
			(xy 195.139828 -291.331035) (xy 195.188047 -291.321191) (xy 195.237222 -291.31921) (xy 195.286077 -291.325142)
			(xy 195.333348 -291.338834) (xy 195.37781 -291.359932) (xy 195.418313 -291.387888) (xy 195.453806 -291.42198)
			(xy 195.483371 -291.461324) (xy 195.506242 -291.504901) (xy 195.521826 -291.551582) (xy 195.529721 -291.600159)
			(xy 195.530216 -291.624766) (xy 195.869064 -291.624766) (xy 195.873024 -291.575712) (xy 195.884801 -291.527928)
			(xy 195.904092 -291.482652) (xy 195.930395 -291.441056) (xy 195.96303 -291.404219) (xy 196.001151 -291.373094)
			(xy 196.043772 -291.348487) (xy 196.089788 -291.331035) (xy 196.138007 -291.321191) (xy 196.187182 -291.31921)
			(xy 196.236037 -291.325142) (xy 196.283308 -291.338834) (xy 196.32777 -291.359932) (xy 196.368273 -291.387888)
			(xy 196.403766 -291.42198) (xy 196.433331 -291.461324) (xy 196.456202 -291.504901) (xy 196.471786 -291.551582)
			(xy 196.479681 -291.600159) (xy 196.480176 -291.624766) (xy 196.819278 -291.624766) (xy 196.823238 -291.575712)
			(xy 196.835015 -291.527928) (xy 196.854306 -291.482652) (xy 196.880609 -291.441056) (xy 196.913244 -291.404219)
			(xy 196.951365 -291.373094) (xy 196.993986 -291.348487) (xy 197.040002 -291.331035) (xy 197.088221 -291.321191)
			(xy 197.137396 -291.31921) (xy 197.186251 -291.325142) (xy 197.233522 -291.338834) (xy 197.277984 -291.359932)
			(xy 197.318487 -291.387888) (xy 197.35398 -291.42198) (xy 197.383545 -291.461324) (xy 197.406416 -291.504901)
			(xy 197.422 -291.551582) (xy 197.429895 -291.600159) (xy 197.43039 -291.624766) (xy 197.769238 -291.624766)
			(xy 197.773198 -291.575712) (xy 197.784975 -291.527928) (xy 197.804266 -291.482652) (xy 197.830569 -291.441056)
			(xy 197.863204 -291.404219) (xy 197.901325 -291.373094) (xy 197.943946 -291.348487) (xy 197.989962 -291.331035)
			(xy 198.038181 -291.321191) (xy 198.087356 -291.31921) (xy 198.136211 -291.325142) (xy 198.183482 -291.338834)
			(xy 198.227944 -291.359932) (xy 198.268447 -291.387888) (xy 198.30394 -291.42198) (xy 198.333505 -291.461324)
			(xy 198.356376 -291.504901) (xy 198.37196 -291.551582) (xy 198.379855 -291.600159) (xy 198.38035 -291.624766)
			(xy 198.719198 -291.624766) (xy 198.723158 -291.575712) (xy 198.734935 -291.527928) (xy 198.754226 -291.482652)
			(xy 198.780529 -291.441056) (xy 198.813164 -291.404219) (xy 198.851285 -291.373094) (xy 198.893906 -291.348487)
			(xy 198.939922 -291.331035) (xy 198.988141 -291.321191) (xy 199.037316 -291.31921) (xy 199.086171 -291.325142)
			(xy 199.133442 -291.338834) (xy 199.177904 -291.359932) (xy 199.218407 -291.387888) (xy 199.2539 -291.42198)
			(xy 199.283465 -291.461324) (xy 199.306336 -291.504901) (xy 199.32192 -291.551582) (xy 199.329815 -291.600159)
			(xy 199.33031 -291.624766) (xy 199.329815 -291.649373) (xy 199.32192 -291.69795) (xy 199.306336 -291.744631)
			(xy 199.283465 -291.788208) (xy 199.2539 -291.827552) (xy 199.218407 -291.861644) (xy 199.177904 -291.8896)
			(xy 199.133442 -291.910698) (xy 199.086171 -291.92439) (xy 199.037316 -291.930322) (xy 198.988141 -291.928341)
			(xy 198.939922 -291.918497) (xy 198.893906 -291.901045) (xy 198.851285 -291.876438) (xy 198.813164 -291.845313)
			(xy 198.780529 -291.808476) (xy 198.754226 -291.76688) (xy 198.734935 -291.721604) (xy 198.723158 -291.67382)
			(xy 198.719198 -291.624766) (xy 198.38035 -291.624766) (xy 198.379855 -291.649373) (xy 198.37196 -291.69795)
			(xy 198.356376 -291.744631) (xy 198.333505 -291.788208) (xy 198.30394 -291.827552) (xy 198.268447 -291.861644)
			(xy 198.227944 -291.8896) (xy 198.183482 -291.910698) (xy 198.136211 -291.92439) (xy 198.087356 -291.930322)
			(xy 198.038181 -291.928341) (xy 197.989962 -291.918497) (xy 197.943946 -291.901045) (xy 197.901325 -291.876438)
			(xy 197.863204 -291.845313) (xy 197.830569 -291.808476) (xy 197.804266 -291.76688) (xy 197.784975 -291.721604)
			(xy 197.773198 -291.67382) (xy 197.769238 -291.624766) (xy 197.43039 -291.624766) (xy 197.429895 -291.649373)
			(xy 197.422 -291.69795) (xy 197.406416 -291.744631) (xy 197.383545 -291.788208) (xy 197.35398 -291.827552)
			(xy 197.318487 -291.861644) (xy 197.277984 -291.8896) (xy 197.233522 -291.910698) (xy 197.186251 -291.92439)
			(xy 197.137396 -291.930322) (xy 197.088221 -291.928341) (xy 197.040002 -291.918497) (xy 196.993986 -291.901045)
			(xy 196.951365 -291.876438) (xy 196.913244 -291.845313) (xy 196.880609 -291.808476) (xy 196.854306 -291.76688)
			(xy 196.835015 -291.721604) (xy 196.823238 -291.67382) (xy 196.819278 -291.624766) (xy 196.480176 -291.624766)
			(xy 196.479681 -291.649373) (xy 196.471786 -291.69795) (xy 196.456202 -291.744631) (xy 196.433331 -291.788208)
			(xy 196.403766 -291.827552) (xy 196.368273 -291.861644) (xy 196.32777 -291.8896) (xy 196.283308 -291.910698)
			(xy 196.236037 -291.92439) (xy 196.187182 -291.930322) (xy 196.138007 -291.928341) (xy 196.089788 -291.918497)
			(xy 196.043772 -291.901045) (xy 196.001151 -291.876438) (xy 195.96303 -291.845313) (xy 195.930395 -291.808476)
			(xy 195.904092 -291.76688) (xy 195.884801 -291.721604) (xy 195.873024 -291.67382) (xy 195.869064 -291.624766)
			(xy 195.530216 -291.624766) (xy 195.529721 -291.649373) (xy 195.521826 -291.69795) (xy 195.506242 -291.744631)
			(xy 195.483371 -291.788208) (xy 195.453806 -291.827552) (xy 195.418313 -291.861644) (xy 195.37781 -291.8896)
			(xy 195.333348 -291.910698) (xy 195.286077 -291.92439) (xy 195.237222 -291.930322) (xy 195.188047 -291.928341)
			(xy 195.139828 -291.918497) (xy 195.093812 -291.901045) (xy 195.051191 -291.876438) (xy 195.01307 -291.845313)
			(xy 194.980435 -291.808476) (xy 194.954132 -291.76688) (xy 194.934841 -291.721604) (xy 194.923064 -291.67382)
			(xy 194.919104 -291.624766) (xy 194.580256 -291.624766) (xy 194.579761 -291.649373) (xy 194.571866 -291.69795)
			(xy 194.556282 -291.744631) (xy 194.533411 -291.788208) (xy 194.503846 -291.827552) (xy 194.468353 -291.861644)
			(xy 194.42785 -291.8896) (xy 194.383388 -291.910698) (xy 194.336117 -291.92439) (xy 194.287262 -291.930322)
			(xy 194.238087 -291.928341) (xy 194.189868 -291.918497) (xy 194.143852 -291.901045) (xy 194.101231 -291.876438)
			(xy 194.06311 -291.845313) (xy 194.030475 -291.808476) (xy 194.004172 -291.76688) (xy 193.984881 -291.721604)
			(xy 193.973104 -291.67382) (xy 193.969144 -291.624766) (xy 193.630296 -291.624766) (xy 193.629801 -291.649373)
			(xy 193.621906 -291.69795) (xy 193.606322 -291.744631) (xy 193.583451 -291.788208) (xy 193.553886 -291.827552)
			(xy 193.518393 -291.861644) (xy 193.47789 -291.8896) (xy 193.433428 -291.910698) (xy 193.386157 -291.92439)
			(xy 193.337302 -291.930322) (xy 193.288127 -291.928341) (xy 193.239908 -291.918497) (xy 193.193892 -291.901045)
			(xy 193.151271 -291.876438) (xy 193.11315 -291.845313) (xy 193.080515 -291.808476) (xy 193.054212 -291.76688)
			(xy 193.034921 -291.721604) (xy 193.023144 -291.67382) (xy 193.019184 -291.624766) (xy 192.680336 -291.624766)
			(xy 192.679841 -291.649373) (xy 192.671946 -291.69795) (xy 192.656362 -291.744631) (xy 192.633491 -291.788208)
			(xy 192.603926 -291.827552) (xy 192.568433 -291.861644) (xy 192.52793 -291.8896) (xy 192.483468 -291.910698)
			(xy 192.436197 -291.92439) (xy 192.387342 -291.930322) (xy 192.338167 -291.928341) (xy 192.289948 -291.918497)
			(xy 192.243932 -291.901045) (xy 192.201311 -291.876438) (xy 192.16319 -291.845313) (xy 192.130555 -291.808476)
			(xy 192.104252 -291.76688) (xy 192.084961 -291.721604) (xy 192.073184 -291.67382) (xy 192.069224 -291.624766)
			(xy 190.780416 -291.624766) (xy 190.779921 -291.649373) (xy 190.772026 -291.69795) (xy 190.756442 -291.744631)
			(xy 190.733571 -291.788208) (xy 190.704006 -291.827552) (xy 190.668513 -291.861644) (xy 190.62801 -291.8896)
			(xy 190.583548 -291.910698) (xy 190.536277 -291.92439) (xy 190.487422 -291.930322) (xy 190.438247 -291.928341)
			(xy 190.390028 -291.918497) (xy 190.344012 -291.901045) (xy 190.301391 -291.876438) (xy 190.26327 -291.845313)
			(xy 190.230635 -291.808476) (xy 190.204332 -291.76688) (xy 190.185041 -291.721604) (xy 190.173264 -291.67382)
			(xy 190.169304 -291.624766) (xy 189.830202 -291.624766) (xy 189.829707 -291.649373) (xy 189.821812 -291.69795)
			(xy 189.806228 -291.744631) (xy 189.783357 -291.788208) (xy 189.753792 -291.827552) (xy 189.718299 -291.861644)
			(xy 189.677796 -291.8896) (xy 189.633334 -291.910698) (xy 189.586063 -291.92439) (xy 189.537208 -291.930322)
			(xy 189.488033 -291.928341) (xy 189.439814 -291.918497) (xy 189.393798 -291.901045) (xy 189.351177 -291.876438)
			(xy 189.313056 -291.845313) (xy 189.280421 -291.808476) (xy 189.254118 -291.76688) (xy 189.234827 -291.721604)
			(xy 189.22305 -291.67382) (xy 189.21909 -291.624766) (xy 188.880242 -291.624766) (xy 188.879747 -291.649373)
			(xy 188.871852 -291.69795) (xy 188.856268 -291.744631) (xy 188.833397 -291.788208) (xy 188.803832 -291.827552)
			(xy 188.768339 -291.861644) (xy 188.727836 -291.8896) (xy 188.683374 -291.910698) (xy 188.636103 -291.92439)
			(xy 188.587248 -291.930322) (xy 188.538073 -291.928341) (xy 188.489854 -291.918497) (xy 188.443838 -291.901045)
			(xy 188.401217 -291.876438) (xy 188.363096 -291.845313) (xy 188.330461 -291.808476) (xy 188.304158 -291.76688)
			(xy 188.284867 -291.721604) (xy 188.27309 -291.67382) (xy 188.26913 -291.624766) (xy 187.930282 -291.624766)
			(xy 187.929787 -291.649373) (xy 187.921892 -291.69795) (xy 187.906308 -291.744631) (xy 187.883437 -291.788208)
			(xy 187.853872 -291.827552) (xy 187.818379 -291.861644) (xy 187.777876 -291.8896) (xy 187.733414 -291.910698)
			(xy 187.686143 -291.92439) (xy 187.637288 -291.930322) (xy 187.588113 -291.928341) (xy 187.539894 -291.918497)
			(xy 187.493878 -291.901045) (xy 187.451257 -291.876438) (xy 187.413136 -291.845313) (xy 187.380501 -291.808476)
			(xy 187.354198 -291.76688) (xy 187.334907 -291.721604) (xy 187.32313 -291.67382) (xy 187.31917 -291.624766)
			(xy 186.980322 -291.624766) (xy 186.979827 -291.649373) (xy 186.971932 -291.69795) (xy 186.956348 -291.744631)
			(xy 186.933477 -291.788208) (xy 186.903912 -291.827552) (xy 186.868419 -291.861644) (xy 186.827916 -291.8896)
			(xy 186.783454 -291.910698) (xy 186.736183 -291.92439) (xy 186.687328 -291.930322) (xy 186.638153 -291.928341)
			(xy 186.589934 -291.918497) (xy 186.543918 -291.901045) (xy 186.501297 -291.876438) (xy 186.463176 -291.845313)
			(xy 186.430541 -291.808476) (xy 186.404238 -291.76688) (xy 186.384947 -291.721604) (xy 186.37317 -291.67382)
			(xy 186.36921 -291.624766) (xy 186.030362 -291.624766) (xy 186.029867 -291.649373) (xy 186.021972 -291.69795)
			(xy 186.006388 -291.744631) (xy 185.983517 -291.788208) (xy 185.953952 -291.827552) (xy 185.918459 -291.861644)
			(xy 185.877956 -291.8896) (xy 185.833494 -291.910698) (xy 185.786223 -291.92439) (xy 185.737368 -291.930322)
			(xy 185.688193 -291.928341) (xy 185.639974 -291.918497) (xy 185.593958 -291.901045) (xy 185.551337 -291.876438)
			(xy 185.513216 -291.845313) (xy 185.480581 -291.808476) (xy 185.454278 -291.76688) (xy 185.434987 -291.721604)
			(xy 185.42321 -291.67382) (xy 185.41925 -291.624766) (xy 185.080148 -291.624766) (xy 185.079653 -291.649373)
			(xy 185.071758 -291.69795) (xy 185.056174 -291.744631) (xy 185.033303 -291.788208) (xy 185.003738 -291.827552)
			(xy 184.968245 -291.861644) (xy 184.927742 -291.8896) (xy 184.88328 -291.910698) (xy 184.836009 -291.92439)
			(xy 184.787154 -291.930322) (xy 184.737979 -291.928341) (xy 184.68976 -291.918497) (xy 184.643744 -291.901045)
			(xy 184.601123 -291.876438) (xy 184.563002 -291.845313) (xy 184.530367 -291.808476) (xy 184.504064 -291.76688)
			(xy 184.484773 -291.721604) (xy 184.472996 -291.67382) (xy 184.469036 -291.624766) (xy 184.130188 -291.624766)
			(xy 184.129693 -291.649373) (xy 184.121798 -291.69795) (xy 184.106214 -291.744631) (xy 184.083343 -291.788208)
			(xy 184.053778 -291.827552) (xy 184.018285 -291.861644) (xy 183.977782 -291.8896) (xy 183.93332 -291.910698)
			(xy 183.886049 -291.92439) (xy 183.837194 -291.930322) (xy 183.788019 -291.928341) (xy 183.7398 -291.918497)
			(xy 183.693784 -291.901045) (xy 183.651163 -291.876438) (xy 183.613042 -291.845313) (xy 183.580407 -291.808476)
			(xy 183.554104 -291.76688) (xy 183.534813 -291.721604) (xy 183.523036 -291.67382) (xy 183.519076 -291.624766)
			(xy 183.180228 -291.624766) (xy 183.179733 -291.649373) (xy 183.171838 -291.69795) (xy 183.156254 -291.744631)
			(xy 183.133383 -291.788208) (xy 183.103818 -291.827552) (xy 183.068325 -291.861644) (xy 183.027822 -291.8896)
			(xy 182.98336 -291.910698) (xy 182.936089 -291.92439) (xy 182.887234 -291.930322) (xy 182.838059 -291.928341)
			(xy 182.78984 -291.918497) (xy 182.743824 -291.901045) (xy 182.701203 -291.876438) (xy 182.663082 -291.845313)
			(xy 182.630447 -291.808476) (xy 182.604144 -291.76688) (xy 182.584853 -291.721604) (xy 182.573076 -291.67382)
			(xy 182.569116 -291.624766) (xy 182.230268 -291.624766) (xy 182.229773 -291.649373) (xy 182.221878 -291.69795)
			(xy 182.206294 -291.744631) (xy 182.183423 -291.788208) (xy 182.153858 -291.827552) (xy 182.118365 -291.861644)
			(xy 182.077862 -291.8896) (xy 182.0334 -291.910698) (xy 181.986129 -291.92439) (xy 181.937274 -291.930322)
			(xy 181.888099 -291.928341) (xy 181.83988 -291.918497) (xy 181.793864 -291.901045) (xy 181.751243 -291.876438)
			(xy 181.713122 -291.845313) (xy 181.680487 -291.808476) (xy 181.654184 -291.76688) (xy 181.634893 -291.721604)
			(xy 181.623116 -291.67382) (xy 181.619156 -291.624766) (xy 181.280308 -291.624766) (xy 181.279813 -291.649373)
			(xy 181.271918 -291.69795) (xy 181.256334 -291.744631) (xy 181.233463 -291.788208) (xy 181.203898 -291.827552)
			(xy 181.168405 -291.861644) (xy 181.127902 -291.8896) (xy 181.08344 -291.910698) (xy 181.036169 -291.92439)
			(xy 180.987314 -291.930322) (xy 180.938139 -291.928341) (xy 180.88992 -291.918497) (xy 180.843904 -291.901045)
			(xy 180.801283 -291.876438) (xy 180.763162 -291.845313) (xy 180.730527 -291.808476) (xy 180.704224 -291.76688)
			(xy 180.684933 -291.721604) (xy 180.673156 -291.67382) (xy 180.669196 -291.624766) (xy 180.330348 -291.624766)
			(xy 180.329853 -291.649373) (xy 180.321958 -291.69795) (xy 180.306374 -291.744631) (xy 180.283503 -291.788208)
			(xy 180.253938 -291.827552) (xy 180.218445 -291.861644) (xy 180.177942 -291.8896) (xy 180.13348 -291.910698)
			(xy 180.086209 -291.92439) (xy 180.037354 -291.930322) (xy 179.988179 -291.928341) (xy 179.93996 -291.918497)
			(xy 179.893944 -291.901045) (xy 179.851323 -291.876438) (xy 179.813202 -291.845313) (xy 179.780567 -291.808476)
			(xy 179.754264 -291.76688) (xy 179.734973 -291.721604) (xy 179.723196 -291.67382) (xy 179.719236 -291.624766)
			(xy 179.380388 -291.624766) (xy 179.379893 -291.649373) (xy 179.371998 -291.69795) (xy 179.356414 -291.744631)
			(xy 179.333543 -291.788208) (xy 179.303978 -291.827552) (xy 179.268485 -291.861644) (xy 179.227982 -291.8896)
			(xy 179.18352 -291.910698) (xy 179.136249 -291.92439) (xy 179.087394 -291.930322) (xy 179.038219 -291.928341)
			(xy 178.99 -291.918497) (xy 178.943984 -291.901045) (xy 178.901363 -291.876438) (xy 178.863242 -291.845313)
			(xy 178.830607 -291.808476) (xy 178.804304 -291.76688) (xy 178.785013 -291.721604) (xy 178.773236 -291.67382)
			(xy 178.769276 -291.624766) (xy 178.430174 -291.624766) (xy 178.429679 -291.649373) (xy 178.421784 -291.69795)
			(xy 178.4062 -291.744631) (xy 178.383329 -291.788208) (xy 178.353764 -291.827552) (xy 178.318271 -291.861644)
			(xy 178.277768 -291.8896) (xy 178.233306 -291.910698) (xy 178.186035 -291.92439) (xy 178.13718 -291.930322)
			(xy 178.088005 -291.928341) (xy 178.039786 -291.918497) (xy 177.99377 -291.901045) (xy 177.951149 -291.876438)
			(xy 177.913028 -291.845313) (xy 177.880393 -291.808476) (xy 177.85409 -291.76688) (xy 177.834799 -291.721604)
			(xy 177.823022 -291.67382) (xy 177.819062 -291.624766) (xy 177.480214 -291.624766) (xy 177.479719 -291.649373)
			(xy 177.471824 -291.69795) (xy 177.45624 -291.744631) (xy 177.433369 -291.788208) (xy 177.403804 -291.827552)
			(xy 177.368311 -291.861644) (xy 177.327808 -291.8896) (xy 177.283346 -291.910698) (xy 177.236075 -291.92439)
			(xy 177.18722 -291.930322) (xy 177.138045 -291.928341) (xy 177.089826 -291.918497) (xy 177.04381 -291.901045)
			(xy 177.001189 -291.876438) (xy 176.963068 -291.845313) (xy 176.930433 -291.808476) (xy 176.90413 -291.76688)
			(xy 176.884839 -291.721604) (xy 176.873062 -291.67382) (xy 176.869102 -291.624766) (xy 176.530254 -291.624766)
			(xy 176.529759 -291.649373) (xy 176.521864 -291.69795) (xy 176.50628 -291.744631) (xy 176.483409 -291.788208)
			(xy 176.453844 -291.827552) (xy 176.418351 -291.861644) (xy 176.377848 -291.8896) (xy 176.333386 -291.910698)
			(xy 176.286115 -291.92439) (xy 176.23726 -291.930322) (xy 176.188085 -291.928341) (xy 176.139866 -291.918497)
			(xy 176.09385 -291.901045) (xy 176.051229 -291.876438) (xy 176.013108 -291.845313) (xy 175.980473 -291.808476)
			(xy 175.95417 -291.76688) (xy 175.934879 -291.721604) (xy 175.923102 -291.67382) (xy 175.919142 -291.624766)
			(xy 174.630334 -291.624766) (xy 174.629839 -291.649373) (xy 174.621944 -291.69795) (xy 174.60636 -291.744631)
			(xy 174.583489 -291.788208) (xy 174.553924 -291.827552) (xy 174.518431 -291.861644) (xy 174.477928 -291.8896)
			(xy 174.433466 -291.910698) (xy 174.386195 -291.92439) (xy 174.33734 -291.930322) (xy 174.288165 -291.928341)
			(xy 174.239946 -291.918497) (xy 174.19393 -291.901045) (xy 174.151309 -291.876438) (xy 174.113188 -291.845313)
			(xy 174.080553 -291.808476) (xy 174.05425 -291.76688) (xy 174.034959 -291.721604) (xy 174.023182 -291.67382)
			(xy 174.019222 -291.624766) (xy 173.680374 -291.624766) (xy 173.679879 -291.649373) (xy 173.671984 -291.69795)
			(xy 173.6564 -291.744631) (xy 173.633529 -291.788208) (xy 173.603964 -291.827552) (xy 173.568471 -291.861644)
			(xy 173.527968 -291.8896) (xy 173.483506 -291.910698) (xy 173.436235 -291.92439) (xy 173.38738 -291.930322)
			(xy 173.338205 -291.928341) (xy 173.289986 -291.918497) (xy 173.24397 -291.901045) (xy 173.201349 -291.876438)
			(xy 173.163228 -291.845313) (xy 173.130593 -291.808476) (xy 173.10429 -291.76688) (xy 173.084999 -291.721604)
			(xy 173.073222 -291.67382) (xy 173.069262 -291.624766) (xy 172.73016 -291.624766) (xy 172.729665 -291.649373)
			(xy 172.72177 -291.69795) (xy 172.706186 -291.744631) (xy 172.683315 -291.788208) (xy 172.65375 -291.827552)
			(xy 172.618257 -291.861644) (xy 172.577754 -291.8896) (xy 172.533292 -291.910698) (xy 172.486021 -291.92439)
			(xy 172.437166 -291.930322) (xy 172.387991 -291.928341) (xy 172.339772 -291.918497) (xy 172.293756 -291.901045)
			(xy 172.251135 -291.876438) (xy 172.213014 -291.845313) (xy 172.180379 -291.808476) (xy 172.154076 -291.76688)
			(xy 172.134785 -291.721604) (xy 172.123008 -291.67382) (xy 172.119048 -291.624766) (xy 171.7802 -291.624766)
			(xy 171.779705 -291.649373) (xy 171.77181 -291.69795) (xy 171.756226 -291.744631) (xy 171.733355 -291.788208)
			(xy 171.70379 -291.827552) (xy 171.668297 -291.861644) (xy 171.627794 -291.8896) (xy 171.583332 -291.910698)
			(xy 171.536061 -291.92439) (xy 171.487206 -291.930322) (xy 171.438031 -291.928341) (xy 171.389812 -291.918497)
			(xy 171.343796 -291.901045) (xy 171.301175 -291.876438) (xy 171.263054 -291.845313) (xy 171.230419 -291.808476)
			(xy 171.204116 -291.76688) (xy 171.184825 -291.721604) (xy 171.173048 -291.67382) (xy 171.169088 -291.624766)
			(xy 170.83024 -291.624766) (xy 170.829745 -291.649373) (xy 170.82185 -291.69795) (xy 170.806266 -291.744631)
			(xy 170.783395 -291.788208) (xy 170.75383 -291.827552) (xy 170.718337 -291.861644) (xy 170.677834 -291.8896)
			(xy 170.633372 -291.910698) (xy 170.586101 -291.92439) (xy 170.537246 -291.930322) (xy 170.488071 -291.928341)
			(xy 170.439852 -291.918497) (xy 170.393836 -291.901045) (xy 170.351215 -291.876438) (xy 170.313094 -291.845313)
			(xy 170.280459 -291.808476) (xy 170.254156 -291.76688) (xy 170.234865 -291.721604) (xy 170.223088 -291.67382)
			(xy 170.219128 -291.624766) (xy 169.88028 -291.624766) (xy 169.879785 -291.649373) (xy 169.87189 -291.69795)
			(xy 169.856306 -291.744631) (xy 169.833435 -291.788208) (xy 169.80387 -291.827552) (xy 169.768377 -291.861644)
			(xy 169.727874 -291.8896) (xy 169.683412 -291.910698) (xy 169.636141 -291.92439) (xy 169.587286 -291.930322)
			(xy 169.538111 -291.928341) (xy 169.489892 -291.918497) (xy 169.443876 -291.901045) (xy 169.401255 -291.876438)
			(xy 169.363134 -291.845313) (xy 169.330499 -291.808476) (xy 169.304196 -291.76688) (xy 169.284905 -291.721604)
			(xy 169.273128 -291.67382) (xy 169.269168 -291.624766) (xy 168.93032 -291.624766) (xy 168.929825 -291.649373)
			(xy 168.92193 -291.69795) (xy 168.906346 -291.744631) (xy 168.883475 -291.788208) (xy 168.85391 -291.827552)
			(xy 168.818417 -291.861644) (xy 168.777914 -291.8896) (xy 168.733452 -291.910698) (xy 168.686181 -291.92439)
			(xy 168.637326 -291.930322) (xy 168.588151 -291.928341) (xy 168.539932 -291.918497) (xy 168.493916 -291.901045)
			(xy 168.451295 -291.876438) (xy 168.413174 -291.845313) (xy 168.380539 -291.808476) (xy 168.354236 -291.76688)
			(xy 168.334945 -291.721604) (xy 168.323168 -291.67382) (xy 168.319208 -291.624766) (xy 167.98036 -291.624766)
			(xy 167.979865 -291.649373) (xy 167.97197 -291.69795) (xy 167.956386 -291.744631) (xy 167.933515 -291.788208)
			(xy 167.90395 -291.827552) (xy 167.868457 -291.861644) (xy 167.827954 -291.8896) (xy 167.783492 -291.910698)
			(xy 167.736221 -291.92439) (xy 167.687366 -291.930322) (xy 167.638191 -291.928341) (xy 167.589972 -291.918497)
			(xy 167.543956 -291.901045) (xy 167.501335 -291.876438) (xy 167.463214 -291.845313) (xy 167.430579 -291.808476)
			(xy 167.404276 -291.76688) (xy 167.384985 -291.721604) (xy 167.373208 -291.67382) (xy 167.369248 -291.624766)
			(xy 167.0304 -291.624766) (xy 167.029905 -291.649373) (xy 167.02201 -291.69795) (xy 167.006426 -291.744631)
			(xy 166.983555 -291.788208) (xy 166.95399 -291.827552) (xy 166.918497 -291.861644) (xy 166.877994 -291.8896)
			(xy 166.833532 -291.910698) (xy 166.786261 -291.92439) (xy 166.737406 -291.930322) (xy 166.688231 -291.928341)
			(xy 166.640012 -291.918497) (xy 166.593996 -291.901045) (xy 166.551375 -291.876438) (xy 166.513254 -291.845313)
			(xy 166.480619 -291.808476) (xy 166.454316 -291.76688) (xy 166.435025 -291.721604) (xy 166.423248 -291.67382)
			(xy 166.419288 -291.624766) (xy 166.080186 -291.624766) (xy 166.079691 -291.649373) (xy 166.071796 -291.69795)
			(xy 166.056212 -291.744631) (xy 166.033341 -291.788208) (xy 166.003776 -291.827552) (xy 165.968283 -291.861644)
			(xy 165.92778 -291.8896) (xy 165.883318 -291.910698) (xy 165.836047 -291.92439) (xy 165.787192 -291.930322)
			(xy 165.738017 -291.928341) (xy 165.689798 -291.918497) (xy 165.643782 -291.901045) (xy 165.601161 -291.876438)
			(xy 165.56304 -291.845313) (xy 165.530405 -291.808476) (xy 165.504102 -291.76688) (xy 165.484811 -291.721604)
			(xy 165.473034 -291.67382) (xy 165.469074 -291.624766) (xy 165.155117 -291.624766) (xy 165.155118 -291.65118)
			(xy 165.146739 -291.703279) (xy 165.130195 -291.753387) (xy 165.105904 -291.800232) (xy 165.074483 -291.842625)
			(xy 165.036729 -291.879492) (xy 164.9936 -291.909896) (xy 164.94619 -291.933066) (xy 164.895703 -291.948415)
			(xy 164.869622 -291.952426) (xy 164.86505 -291.953188) (xy 164.852858 -291.956998) (xy 164.849556 -291.958014)
			(xy 164.826188 -291.968936) (xy 164.819584 -291.976048) (xy 164.804852 -291.991542) (xy 164.796724 -292.002718)
			(xy 164.794031 -292.00825) (xy 164.791084 -292.020191) (xy 164.790882 -292.02634) (xy 164.790882 -292.122098)
			(xy 209.357468 -292.122098) (xy 209.357886 -292.095493) (xy 209.365269 -292.042797) (xy 209.379907 -291.991639)
			(xy 209.401514 -291.943013) (xy 209.429671 -291.897863) (xy 209.463831 -291.857065) (xy 209.503331 -291.821413)
			(xy 209.525108 -291.806122) (xy 209.536541 -291.797728) (xy 209.554741 -291.775997) (xy 209.56626 -291.750097)
			(xy 209.570205 -291.722027) (xy 209.566274 -291.693955) (xy 209.55477 -291.668049) (xy 209.536581 -291.646309)
			(xy 209.525108 -291.637974) (xy 209.50331 -291.622718) (xy 209.463833 -291.587044) (xy 209.429693 -291.546233)
			(xy 209.401551 -291.501076) (xy 209.379953 -291.452449) (xy 209.365318 -291.401294) (xy 209.357929 -291.348602)
			(xy 209.357468 -291.321998) (xy 209.357954 -291.294747) (xy 209.36571 -291.240799) (xy 209.381065 -291.188504)
			(xy 209.403707 -291.138927) (xy 209.433173 -291.093077) (xy 209.468864 -291.051886) (xy 209.510055 -291.016195)
			(xy 209.555905 -290.986729) (xy 209.605482 -290.964087) (xy 209.657777 -290.948732) (xy 209.711725 -290.940976)
			(xy 209.766227 -290.940976) (xy 209.820175 -290.948732) (xy 209.87247 -290.964087) (xy 209.922047 -290.986729)
			(xy 209.967897 -291.016195) (xy 210.009088 -291.051886) (xy 210.044779 -291.093077) (xy 210.074245 -291.138927)
			(xy 210.096887 -291.188504) (xy 210.112242 -291.240799) (xy 210.119998 -291.294747) (xy 210.120484 -291.321998)
			(xy 210.120041 -291.348602) (xy 210.112659 -291.401296) (xy 210.098024 -291.452452) (xy 210.076421 -291.501077)
			(xy 210.048268 -291.546227) (xy 210.014113 -291.587026) (xy 209.974619 -291.622681) (xy 209.952844 -291.637974)
			(xy 209.950643 -291.639553) (xy 218.343175 -291.639553) (xy 218.343175 -291.585047) (xy 218.350933 -291.531097)
			(xy 218.366289 -291.4788) (xy 218.388932 -291.429221) (xy 218.418401 -291.383369) (xy 218.454096 -291.342177)
			(xy 218.495289 -291.306486) (xy 218.541143 -291.27702) (xy 218.590724 -291.25438) (xy 218.643022 -291.239027)
			(xy 218.696973 -291.231274) (xy 218.724226 -291.230812) (xy 218.751597 -291.23126) (xy 218.805777 -291.239082)
			(xy 218.85828 -291.254575) (xy 218.908027 -291.277421) (xy 218.953993 -291.307149) (xy 218.974924 -291.324792)
			(xy 218.982036 -291.330888) (xy 218.999054 -291.337238) (xy 219.084398 -291.337238) (xy 219.101416 -291.330888)
			(xy 219.108528 -291.324792) (xy 219.129475 -291.307172) (xy 219.175444 -291.277458) (xy 219.225188 -291.254618)
			(xy 219.277685 -291.239122) (xy 219.331858 -291.231289) (xy 219.359226 -291.230812) (xy 219.386477 -291.23126)
			(xy 219.440425 -291.23902) (xy 219.49272 -291.254378) (xy 219.542296 -291.277022) (xy 219.588146 -291.30649)
			(xy 219.629335 -291.342183) (xy 219.665026 -291.383375) (xy 219.694491 -291.429227) (xy 219.717131 -291.478805)
			(xy 219.732486 -291.5311) (xy 219.740242 -291.585049) (xy 219.740242 -291.639549) (xy 220.096598 -291.639549)
			(xy 220.096598 -291.585051) (xy 220.104354 -291.531107) (xy 220.119708 -291.478816) (xy 220.142347 -291.429242)
			(xy 220.17181 -291.383395) (xy 220.207499 -291.342207) (xy 220.248685 -291.306518) (xy 220.294532 -291.277052)
			(xy 220.344105 -291.254412) (xy 220.396395 -291.239057) (xy 220.450339 -291.231299) (xy 220.477588 -291.230812)
			(xy 220.504958 -291.231282) (xy 220.559137 -291.239099) (xy 220.61164 -291.254587) (xy 220.661387 -291.277427)
			(xy 220.707354 -291.307151) (xy 220.728286 -291.324792) (xy 220.735398 -291.330888) (xy 220.752416 -291.337238)
			(xy 220.83776 -291.337238) (xy 220.854778 -291.330888) (xy 220.86189 -291.324792) (xy 220.882814 -291.307143)
			(xy 220.928789 -291.277433) (xy 220.978539 -291.254599) (xy 221.031041 -291.23911) (xy 221.085218 -291.231285)
			(xy 221.112588 -291.230812) (xy 221.139843 -291.231234) (xy 221.193798 -291.23899) (xy 221.2461 -291.254346)
			(xy 221.295684 -291.276989) (xy 221.341541 -291.306458) (xy 221.382738 -291.342154) (xy 221.418435 -291.383349)
			(xy 221.447905 -291.429205) (xy 221.47055 -291.478789) (xy 221.485907 -291.53109) (xy 221.493665 -291.585045)
			(xy 221.493665 -291.639555) (xy 221.485907 -291.69351) (xy 221.47055 -291.745811) (xy 221.447905 -291.795395)
			(xy 221.418435 -291.841251) (xy 221.382738 -291.882446) (xy 221.341541 -291.918142) (xy 221.295684 -291.947611)
			(xy 221.2461 -291.970254) (xy 221.193798 -291.98561) (xy 221.139843 -291.993366) (xy 221.112588 -291.993828)
			(xy 221.085217 -291.993387) (xy 221.031036 -291.985565) (xy 220.978532 -291.970072) (xy 220.928785 -291.947224)
			(xy 220.88282 -291.917493) (xy 220.86189 -291.899848) (xy 220.854778 -291.893752) (xy 220.83776 -291.887402)
			(xy 220.752416 -291.887402) (xy 220.735398 -291.893752) (xy 220.728286 -291.899848) (xy 220.707326 -291.917452)
			(xy 220.661361 -291.947171) (xy 220.611621 -291.970015) (xy 220.559126 -291.985514) (xy 220.504955 -291.99335)
			(xy 220.477588 -291.993828) (xy 220.450339 -291.993301) (xy 220.396395 -291.985543) (xy 220.344105 -291.970188)
			(xy 220.294532 -291.947548) (xy 220.248685 -291.918082) (xy 220.207499 -291.882393) (xy 220.17181 -291.841205)
			(xy 220.142347 -291.795358) (xy 220.119708 -291.745784) (xy 220.104354 -291.693493) (xy 220.096598 -291.639549)
			(xy 219.740242 -291.639549) (xy 219.740242 -291.639551) (xy 219.732486 -291.6935) (xy 219.717131 -291.745795)
			(xy 219.694491 -291.795373) (xy 219.665026 -291.841225) (xy 219.629335 -291.882417) (xy 219.588146 -291.91811)
			(xy 219.542296 -291.947578) (xy 219.49272 -291.970222) (xy 219.440425 -291.98558) (xy 219.386477 -291.99334)
			(xy 219.359226 -291.993828) (xy 219.331855 -291.993364) (xy 219.277676 -291.985549) (xy 219.225172 -291.97006)
			(xy 219.175425 -291.947217) (xy 219.129459 -291.917491) (xy 219.108528 -291.899848) (xy 219.101416 -291.893752)
			(xy 219.084398 -291.887402) (xy 218.999054 -291.887402) (xy 218.982036 -291.893752) (xy 218.974924 -291.899848)
			(xy 218.953987 -291.917481) (xy 218.908016 -291.947196) (xy 218.85827 -291.970034) (xy 218.80577 -291.985526)
			(xy 218.751595 -291.993354) (xy 218.724226 -291.993828) (xy 218.696973 -291.993326) (xy 218.643022 -291.985573)
			(xy 218.590724 -291.97022) (xy 218.541143 -291.94758) (xy 218.495289 -291.918114) (xy 218.454096 -291.882423)
			(xy 218.418401 -291.841231) (xy 218.388932 -291.795379) (xy 218.366289 -291.7458) (xy 218.350933 -291.693503)
			(xy 218.343175 -291.639553) (xy 209.950643 -291.639553) (xy 209.941313 -291.646246) (xy 209.9231 -291.668001)
			(xy 209.911581 -291.693929) (xy 209.907644 -291.722027) (xy 209.911595 -291.750123) (xy 209.923129 -291.776045)
			(xy 209.941353 -291.79779) (xy 209.952844 -291.806122) (xy 209.97463 -291.821396) (xy 210.014109 -291.857065)
			(xy 210.048252 -291.897872) (xy 210.076396 -291.943026) (xy 210.097996 -291.991651) (xy 210.112633 -292.042804)
			(xy 210.120023 -292.095495) (xy 210.120484 -292.122098) (xy 210.119998 -292.149349) (xy 210.112242 -292.203297)
			(xy 210.096887 -292.255592) (xy 210.074245 -292.305169) (xy 210.044779 -292.351019) (xy 210.009088 -292.39221)
			(xy 209.967897 -292.427901) (xy 209.922047 -292.457367) (xy 209.87247 -292.480009) (xy 209.820175 -292.495364)
			(xy 209.766227 -292.50312) (xy 209.711725 -292.50312) (xy 209.657777 -292.495364) (xy 209.605482 -292.480009)
			(xy 209.555905 -292.457367) (xy 209.510055 -292.427901) (xy 209.468864 -292.39221) (xy 209.433173 -292.351019)
			(xy 209.403707 -292.305169) (xy 209.381065 -292.255592) (xy 209.36571 -292.203297) (xy 209.357954 -292.149349)
			(xy 209.357468 -292.122098) (xy 164.790882 -292.122098) (xy 164.790882 -292.173152) (xy 164.79105 -292.179305)
			(xy 164.794003 -292.191253) (xy 164.796724 -292.196774) (xy 164.804852 -292.20795) (xy 164.819584 -292.223444)
			(xy 164.826188 -292.230556) (xy 164.849302 -292.241478) (xy 164.852858 -292.242494) (xy 164.86505 -292.246304)
			(xy 164.869622 -292.247066) (xy 164.89569 -292.251143) (xy 164.946168 -292.266488) (xy 164.993569 -292.289654)
			(xy 165.03669 -292.320053) (xy 165.074437 -292.356913) (xy 165.105853 -292.399299) (xy 165.13014 -292.446135)
			(xy 165.146681 -292.496234) (xy 165.155058 -292.548324) (xy 165.155058 -292.574726) (xy 165.469074 -292.574726)
			(xy 165.473034 -292.525672) (xy 165.484811 -292.477888) (xy 165.504102 -292.432612) (xy 165.530405 -292.391016)
			(xy 165.56304 -292.354179) (xy 165.601161 -292.323054) (xy 165.643782 -292.298447) (xy 165.689798 -292.280995)
			(xy 165.738017 -292.271151) (xy 165.787192 -292.26917) (xy 165.836047 -292.275102) (xy 165.883318 -292.288794)
			(xy 165.92778 -292.309892) (xy 165.968283 -292.337848) (xy 166.003776 -292.37194) (xy 166.033341 -292.411284)
			(xy 166.056212 -292.454861) (xy 166.071796 -292.501542) (xy 166.079691 -292.550119) (xy 166.080186 -292.574726)
			(xy 166.080181 -292.57498) (xy 166.419288 -292.57498) (xy 166.423248 -292.525926) (xy 166.435025 -292.478142)
			(xy 166.454316 -292.432866) (xy 166.480619 -292.39127) (xy 166.513254 -292.354433) (xy 166.551375 -292.323308)
			(xy 166.593996 -292.298701) (xy 166.640012 -292.281249) (xy 166.688231 -292.271405) (xy 166.737406 -292.269424)
			(xy 166.786261 -292.275356) (xy 166.833532 -292.289048) (xy 166.877994 -292.310146) (xy 166.918497 -292.338102)
			(xy 166.95399 -292.372194) (xy 166.983555 -292.411538) (xy 167.006426 -292.455115) (xy 167.02201 -292.501796)
			(xy 167.029905 -292.550373) (xy 167.0304 -292.57498) (xy 167.369248 -292.57498) (xy 167.373208 -292.525926)
			(xy 167.384985 -292.478142) (xy 167.404276 -292.432866) (xy 167.430579 -292.39127) (xy 167.463214 -292.354433)
			(xy 167.501335 -292.323308) (xy 167.543956 -292.298701) (xy 167.589972 -292.281249) (xy 167.638191 -292.271405)
			(xy 167.687366 -292.269424) (xy 167.736221 -292.275356) (xy 167.783492 -292.289048) (xy 167.827954 -292.310146)
			(xy 167.868457 -292.338102) (xy 167.90395 -292.372194) (xy 167.933515 -292.411538) (xy 167.956386 -292.455115)
			(xy 167.97197 -292.501796) (xy 167.979865 -292.550373) (xy 167.98036 -292.57498) (xy 168.319208 -292.57498)
			(xy 168.323168 -292.525926) (xy 168.334945 -292.478142) (xy 168.354236 -292.432866) (xy 168.380539 -292.39127)
			(xy 168.413174 -292.354433) (xy 168.451295 -292.323308) (xy 168.493916 -292.298701) (xy 168.539932 -292.281249)
			(xy 168.588151 -292.271405) (xy 168.637326 -292.269424) (xy 168.686181 -292.275356) (xy 168.733452 -292.289048)
			(xy 168.777914 -292.310146) (xy 168.818417 -292.338102) (xy 168.85391 -292.372194) (xy 168.883475 -292.411538)
			(xy 168.906346 -292.455115) (xy 168.92193 -292.501796) (xy 168.929825 -292.550373) (xy 168.93032 -292.57498)
			(xy 169.269168 -292.57498) (xy 169.273128 -292.525926) (xy 169.284905 -292.478142) (xy 169.304196 -292.432866)
			(xy 169.330499 -292.39127) (xy 169.363134 -292.354433) (xy 169.401255 -292.323308) (xy 169.443876 -292.298701)
			(xy 169.489892 -292.281249) (xy 169.538111 -292.271405) (xy 169.587286 -292.269424) (xy 169.636141 -292.275356)
			(xy 169.683412 -292.289048) (xy 169.727874 -292.310146) (xy 169.768377 -292.338102) (xy 169.80387 -292.372194)
			(xy 169.833435 -292.411538) (xy 169.856306 -292.455115) (xy 169.87189 -292.501796) (xy 169.879785 -292.550373)
			(xy 169.88028 -292.57498) (xy 170.219128 -292.57498) (xy 170.223088 -292.525926) (xy 170.234865 -292.478142)
			(xy 170.254156 -292.432866) (xy 170.280459 -292.39127) (xy 170.313094 -292.354433) (xy 170.351215 -292.323308)
			(xy 170.393836 -292.298701) (xy 170.439852 -292.281249) (xy 170.488071 -292.271405) (xy 170.537246 -292.269424)
			(xy 170.586101 -292.275356) (xy 170.633372 -292.289048) (xy 170.677834 -292.310146) (xy 170.718337 -292.338102)
			(xy 170.75383 -292.372194) (xy 170.783395 -292.411538) (xy 170.806266 -292.455115) (xy 170.82185 -292.501796)
			(xy 170.829745 -292.550373) (xy 170.83024 -292.57498) (xy 171.169088 -292.57498) (xy 171.173048 -292.525926)
			(xy 171.184825 -292.478142) (xy 171.204116 -292.432866) (xy 171.230419 -292.39127) (xy 171.263054 -292.354433)
			(xy 171.301175 -292.323308) (xy 171.343796 -292.298701) (xy 171.389812 -292.281249) (xy 171.438031 -292.271405)
			(xy 171.487206 -292.269424) (xy 171.536061 -292.275356) (xy 171.583332 -292.289048) (xy 171.627794 -292.310146)
			(xy 171.668297 -292.338102) (xy 171.70379 -292.372194) (xy 171.733355 -292.411538) (xy 171.756226 -292.455115)
			(xy 171.77181 -292.501796) (xy 171.779705 -292.550373) (xy 171.7802 -292.57498) (xy 172.119302 -292.57498)
			(xy 172.123262 -292.525926) (xy 172.135039 -292.478142) (xy 172.15433 -292.432866) (xy 172.180633 -292.39127)
			(xy 172.213268 -292.354433) (xy 172.251389 -292.323308) (xy 172.29401 -292.298701) (xy 172.340026 -292.281249)
			(xy 172.388245 -292.271405) (xy 172.43742 -292.269424) (xy 172.486275 -292.275356) (xy 172.533546 -292.289048)
			(xy 172.578008 -292.310146) (xy 172.618511 -292.338102) (xy 172.654004 -292.372194) (xy 172.683569 -292.411538)
			(xy 172.70644 -292.455115) (xy 172.722024 -292.501796) (xy 172.729919 -292.550373) (xy 172.730414 -292.57498)
			(xy 173.069262 -292.57498) (xy 173.073222 -292.525926) (xy 173.084999 -292.478142) (xy 173.10429 -292.432866)
			(xy 173.130593 -292.39127) (xy 173.163228 -292.354433) (xy 173.201349 -292.323308) (xy 173.24397 -292.298701)
			(xy 173.289986 -292.281249) (xy 173.338205 -292.271405) (xy 173.38738 -292.269424) (xy 173.436235 -292.275356)
			(xy 173.483506 -292.289048) (xy 173.527968 -292.310146) (xy 173.568471 -292.338102) (xy 173.603964 -292.372194)
			(xy 173.633529 -292.411538) (xy 173.6564 -292.455115) (xy 173.671984 -292.501796) (xy 173.679879 -292.550373)
			(xy 173.680374 -292.57498) (xy 174.019222 -292.57498) (xy 174.023182 -292.525926) (xy 174.034959 -292.478142)
			(xy 174.05425 -292.432866) (xy 174.080553 -292.39127) (xy 174.113188 -292.354433) (xy 174.151309 -292.323308)
			(xy 174.19393 -292.298701) (xy 174.239946 -292.281249) (xy 174.288165 -292.271405) (xy 174.33734 -292.269424)
			(xy 174.386195 -292.275356) (xy 174.433466 -292.289048) (xy 174.477928 -292.310146) (xy 174.518431 -292.338102)
			(xy 174.553924 -292.372194) (xy 174.583489 -292.411538) (xy 174.60636 -292.455115) (xy 174.621944 -292.501796)
			(xy 174.629839 -292.550373) (xy 174.630329 -292.574726) (xy 175.919142 -292.574726) (xy 175.923102 -292.525672)
			(xy 175.934879 -292.477888) (xy 175.95417 -292.432612) (xy 175.980473 -292.391016) (xy 176.013108 -292.354179)
			(xy 176.051229 -292.323054) (xy 176.09385 -292.298447) (xy 176.139866 -292.280995) (xy 176.188085 -292.271151)
			(xy 176.23726 -292.26917) (xy 176.286115 -292.275102) (xy 176.333386 -292.288794) (xy 176.377848 -292.309892)
			(xy 176.418351 -292.337848) (xy 176.453844 -292.37194) (xy 176.483409 -292.411284) (xy 176.50628 -292.454861)
			(xy 176.521864 -292.501542) (xy 176.529759 -292.550119) (xy 176.530254 -292.574726) (xy 176.869102 -292.574726)
			(xy 176.873062 -292.525672) (xy 176.884839 -292.477888) (xy 176.90413 -292.432612) (xy 176.930433 -292.391016)
			(xy 176.963068 -292.354179) (xy 177.001189 -292.323054) (xy 177.04381 -292.298447) (xy 177.089826 -292.280995)
			(xy 177.138045 -292.271151) (xy 177.18722 -292.26917) (xy 177.236075 -292.275102) (xy 177.283346 -292.288794)
			(xy 177.327808 -292.309892) (xy 177.368311 -292.337848) (xy 177.403804 -292.37194) (xy 177.433369 -292.411284)
			(xy 177.45624 -292.454861) (xy 177.471824 -292.501542) (xy 177.479719 -292.550119) (xy 177.480214 -292.574726)
			(xy 177.819062 -292.574726) (xy 177.823022 -292.525672) (xy 177.834799 -292.477888) (xy 177.85409 -292.432612)
			(xy 177.880393 -292.391016) (xy 177.913028 -292.354179) (xy 177.951149 -292.323054) (xy 177.99377 -292.298447)
			(xy 178.039786 -292.280995) (xy 178.088005 -292.271151) (xy 178.13718 -292.26917) (xy 178.186035 -292.275102)
			(xy 178.233306 -292.288794) (xy 178.277768 -292.309892) (xy 178.318271 -292.337848) (xy 178.353764 -292.37194)
			(xy 178.383329 -292.411284) (xy 178.4062 -292.454861) (xy 178.421784 -292.501542) (xy 178.429679 -292.550119)
			(xy 178.430174 -292.574726) (xy 178.769276 -292.574726) (xy 178.773236 -292.525672) (xy 178.785013 -292.477888)
			(xy 178.804304 -292.432612) (xy 178.830607 -292.391016) (xy 178.863242 -292.354179) (xy 178.901363 -292.323054)
			(xy 178.943984 -292.298447) (xy 178.99 -292.280995) (xy 179.038219 -292.271151) (xy 179.087394 -292.26917)
			(xy 179.136249 -292.275102) (xy 179.18352 -292.288794) (xy 179.227982 -292.309892) (xy 179.268485 -292.337848)
			(xy 179.303978 -292.37194) (xy 179.333543 -292.411284) (xy 179.356414 -292.454861) (xy 179.371998 -292.501542)
			(xy 179.379893 -292.550119) (xy 179.380388 -292.574726) (xy 179.719236 -292.574726) (xy 179.723196 -292.525672)
			(xy 179.734973 -292.477888) (xy 179.754264 -292.432612) (xy 179.780567 -292.391016) (xy 179.813202 -292.354179)
			(xy 179.851323 -292.323054) (xy 179.893944 -292.298447) (xy 179.93996 -292.280995) (xy 179.988179 -292.271151)
			(xy 180.037354 -292.26917) (xy 180.086209 -292.275102) (xy 180.13348 -292.288794) (xy 180.177942 -292.309892)
			(xy 180.218445 -292.337848) (xy 180.253938 -292.37194) (xy 180.283503 -292.411284) (xy 180.306374 -292.454861)
			(xy 180.321958 -292.501542) (xy 180.329853 -292.550119) (xy 180.330348 -292.574726) (xy 180.669196 -292.574726)
			(xy 180.673156 -292.525672) (xy 180.684933 -292.477888) (xy 180.704224 -292.432612) (xy 180.730527 -292.391016)
			(xy 180.763162 -292.354179) (xy 180.801283 -292.323054) (xy 180.843904 -292.298447) (xy 180.88992 -292.280995)
			(xy 180.938139 -292.271151) (xy 180.987314 -292.26917) (xy 181.036169 -292.275102) (xy 181.08344 -292.288794)
			(xy 181.127902 -292.309892) (xy 181.168405 -292.337848) (xy 181.203898 -292.37194) (xy 181.233463 -292.411284)
			(xy 181.256334 -292.454861) (xy 181.271918 -292.501542) (xy 181.279813 -292.550119) (xy 181.280308 -292.574726)
			(xy 181.619156 -292.574726) (xy 181.623116 -292.525672) (xy 181.634893 -292.477888) (xy 181.654184 -292.432612)
			(xy 181.680487 -292.391016) (xy 181.713122 -292.354179) (xy 181.751243 -292.323054) (xy 181.793864 -292.298447)
			(xy 181.83988 -292.280995) (xy 181.888099 -292.271151) (xy 181.937274 -292.26917) (xy 181.986129 -292.275102)
			(xy 182.0334 -292.288794) (xy 182.077862 -292.309892) (xy 182.118365 -292.337848) (xy 182.153858 -292.37194)
			(xy 182.183423 -292.411284) (xy 182.206294 -292.454861) (xy 182.221878 -292.501542) (xy 182.229773 -292.550119)
			(xy 182.230268 -292.574726) (xy 182.569116 -292.574726) (xy 182.573076 -292.525672) (xy 182.584853 -292.477888)
			(xy 182.604144 -292.432612) (xy 182.630447 -292.391016) (xy 182.663082 -292.354179) (xy 182.701203 -292.323054)
			(xy 182.743824 -292.298447) (xy 182.78984 -292.280995) (xy 182.838059 -292.271151) (xy 182.887234 -292.26917)
			(xy 182.936089 -292.275102) (xy 182.98336 -292.288794) (xy 183.027822 -292.309892) (xy 183.068325 -292.337848)
			(xy 183.103818 -292.37194) (xy 183.133383 -292.411284) (xy 183.156254 -292.454861) (xy 183.171838 -292.501542)
			(xy 183.179733 -292.550119) (xy 183.180228 -292.574726) (xy 183.519076 -292.574726) (xy 183.523036 -292.525672)
			(xy 183.534813 -292.477888) (xy 183.554104 -292.432612) (xy 183.580407 -292.391016) (xy 183.613042 -292.354179)
			(xy 183.651163 -292.323054) (xy 183.693784 -292.298447) (xy 183.7398 -292.280995) (xy 183.788019 -292.271151)
			(xy 183.837194 -292.26917) (xy 183.886049 -292.275102) (xy 183.93332 -292.288794) (xy 183.977782 -292.309892)
			(xy 184.018285 -292.337848) (xy 184.053778 -292.37194) (xy 184.083343 -292.411284) (xy 184.106214 -292.454861)
			(xy 184.121798 -292.501542) (xy 184.129693 -292.550119) (xy 184.130188 -292.574726) (xy 184.469036 -292.574726)
			(xy 184.472996 -292.525672) (xy 184.484773 -292.477888) (xy 184.504064 -292.432612) (xy 184.530367 -292.391016)
			(xy 184.563002 -292.354179) (xy 184.601123 -292.323054) (xy 184.643744 -292.298447) (xy 184.68976 -292.280995)
			(xy 184.737979 -292.271151) (xy 184.787154 -292.26917) (xy 184.836009 -292.275102) (xy 184.88328 -292.288794)
			(xy 184.927742 -292.309892) (xy 184.968245 -292.337848) (xy 185.003738 -292.37194) (xy 185.033303 -292.411284)
			(xy 185.056174 -292.454861) (xy 185.071758 -292.501542) (xy 185.079653 -292.550119) (xy 185.080148 -292.574726)
			(xy 185.41925 -292.574726) (xy 185.42321 -292.525672) (xy 185.434987 -292.477888) (xy 185.454278 -292.432612)
			(xy 185.480581 -292.391016) (xy 185.513216 -292.354179) (xy 185.551337 -292.323054) (xy 185.593958 -292.298447)
			(xy 185.639974 -292.280995) (xy 185.688193 -292.271151) (xy 185.737368 -292.26917) (xy 185.786223 -292.275102)
			(xy 185.833494 -292.288794) (xy 185.877956 -292.309892) (xy 185.918459 -292.337848) (xy 185.953952 -292.37194)
			(xy 185.983517 -292.411284) (xy 186.006388 -292.454861) (xy 186.021972 -292.501542) (xy 186.029867 -292.550119)
			(xy 186.030362 -292.574726) (xy 186.030357 -292.57498) (xy 186.36921 -292.57498) (xy 186.37317 -292.525926)
			(xy 186.384947 -292.478142) (xy 186.404238 -292.432866) (xy 186.430541 -292.39127) (xy 186.463176 -292.354433)
			(xy 186.501297 -292.323308) (xy 186.543918 -292.298701) (xy 186.589934 -292.281249) (xy 186.638153 -292.271405)
			(xy 186.687328 -292.269424) (xy 186.736183 -292.275356) (xy 186.783454 -292.289048) (xy 186.827916 -292.310146)
			(xy 186.868419 -292.338102) (xy 186.903912 -292.372194) (xy 186.933477 -292.411538) (xy 186.956348 -292.455115)
			(xy 186.971932 -292.501796) (xy 186.979827 -292.550373) (xy 186.980317 -292.574726) (xy 187.31917 -292.574726)
			(xy 187.32313 -292.525672) (xy 187.334907 -292.477888) (xy 187.354198 -292.432612) (xy 187.380501 -292.391016)
			(xy 187.413136 -292.354179) (xy 187.451257 -292.323054) (xy 187.493878 -292.298447) (xy 187.539894 -292.280995)
			(xy 187.588113 -292.271151) (xy 187.637288 -292.26917) (xy 187.686143 -292.275102) (xy 187.733414 -292.288794)
			(xy 187.777876 -292.309892) (xy 187.818379 -292.337848) (xy 187.853872 -292.37194) (xy 187.883437 -292.411284)
			(xy 187.906308 -292.454861) (xy 187.921892 -292.501542) (xy 187.929787 -292.550119) (xy 187.930282 -292.574726)
			(xy 188.26913 -292.574726) (xy 188.27309 -292.525672) (xy 188.284867 -292.477888) (xy 188.304158 -292.432612)
			(xy 188.330461 -292.391016) (xy 188.363096 -292.354179) (xy 188.401217 -292.323054) (xy 188.443838 -292.298447)
			(xy 188.489854 -292.280995) (xy 188.538073 -292.271151) (xy 188.587248 -292.26917) (xy 188.636103 -292.275102)
			(xy 188.683374 -292.288794) (xy 188.727836 -292.309892) (xy 188.768339 -292.337848) (xy 188.803832 -292.37194)
			(xy 188.833397 -292.411284) (xy 188.856268 -292.454861) (xy 188.871852 -292.501542) (xy 188.879747 -292.550119)
			(xy 188.880242 -292.574726) (xy 189.21909 -292.574726) (xy 189.22305 -292.525672) (xy 189.234827 -292.477888)
			(xy 189.254118 -292.432612) (xy 189.280421 -292.391016) (xy 189.313056 -292.354179) (xy 189.351177 -292.323054)
			(xy 189.393798 -292.298447) (xy 189.439814 -292.280995) (xy 189.488033 -292.271151) (xy 189.537208 -292.26917)
			(xy 189.586063 -292.275102) (xy 189.633334 -292.288794) (xy 189.677796 -292.309892) (xy 189.718299 -292.337848)
			(xy 189.753792 -292.37194) (xy 189.783357 -292.411284) (xy 189.806228 -292.454861) (xy 189.821812 -292.501542)
			(xy 189.829707 -292.550119) (xy 189.830202 -292.574726) (xy 190.16905 -292.574726) (xy 190.17301 -292.525672)
			(xy 190.184787 -292.477888) (xy 190.204078 -292.432612) (xy 190.230381 -292.391016) (xy 190.263016 -292.354179)
			(xy 190.301137 -292.323054) (xy 190.343758 -292.298447) (xy 190.389774 -292.280995) (xy 190.437993 -292.271151)
			(xy 190.487168 -292.26917) (xy 190.536023 -292.275102) (xy 190.583294 -292.288794) (xy 190.627756 -292.309892)
			(xy 190.668259 -292.337848) (xy 190.703752 -292.37194) (xy 190.733317 -292.411284) (xy 190.756188 -292.454861)
			(xy 190.771772 -292.501542) (xy 190.779667 -292.550119) (xy 190.780162 -292.574726) (xy 191.119264 -292.574726)
			(xy 191.123224 -292.525672) (xy 191.135001 -292.477888) (xy 191.154292 -292.432612) (xy 191.180595 -292.391016)
			(xy 191.21323 -292.354179) (xy 191.251351 -292.323054) (xy 191.293972 -292.298447) (xy 191.339988 -292.280995)
			(xy 191.388207 -292.271151) (xy 191.437382 -292.26917) (xy 191.486237 -292.275102) (xy 191.533508 -292.288794)
			(xy 191.57797 -292.309892) (xy 191.618473 -292.337848) (xy 191.653966 -292.37194) (xy 191.683531 -292.411284)
			(xy 191.706402 -292.454861) (xy 191.721986 -292.501542) (xy 191.729881 -292.550119) (xy 191.730376 -292.574726)
			(xy 192.069224 -292.574726) (xy 192.073184 -292.525672) (xy 192.084961 -292.477888) (xy 192.104252 -292.432612)
			(xy 192.130555 -292.391016) (xy 192.16319 -292.354179) (xy 192.201311 -292.323054) (xy 192.243932 -292.298447)
			(xy 192.289948 -292.280995) (xy 192.338167 -292.271151) (xy 192.387342 -292.26917) (xy 192.436197 -292.275102)
			(xy 192.483468 -292.288794) (xy 192.52793 -292.309892) (xy 192.568433 -292.337848) (xy 192.603926 -292.37194)
			(xy 192.633491 -292.411284) (xy 192.656362 -292.454861) (xy 192.671946 -292.501542) (xy 192.679841 -292.550119)
			(xy 192.680336 -292.574726) (xy 193.019184 -292.574726) (xy 193.023144 -292.525672) (xy 193.034921 -292.477888)
			(xy 193.054212 -292.432612) (xy 193.080515 -292.391016) (xy 193.11315 -292.354179) (xy 193.151271 -292.323054)
			(xy 193.193892 -292.298447) (xy 193.239908 -292.280995) (xy 193.288127 -292.271151) (xy 193.337302 -292.26917)
			(xy 193.386157 -292.275102) (xy 193.433428 -292.288794) (xy 193.47789 -292.309892) (xy 193.518393 -292.337848)
			(xy 193.553886 -292.37194) (xy 193.583451 -292.411284) (xy 193.606322 -292.454861) (xy 193.621906 -292.501542)
			(xy 193.629801 -292.550119) (xy 193.630296 -292.574726) (xy 193.969144 -292.574726) (xy 193.973104 -292.525672)
			(xy 193.984881 -292.477888) (xy 194.004172 -292.432612) (xy 194.030475 -292.391016) (xy 194.06311 -292.354179)
			(xy 194.101231 -292.323054) (xy 194.143852 -292.298447) (xy 194.189868 -292.280995) (xy 194.238087 -292.271151)
			(xy 194.287262 -292.26917) (xy 194.336117 -292.275102) (xy 194.383388 -292.288794) (xy 194.42785 -292.309892)
			(xy 194.468353 -292.337848) (xy 194.503846 -292.37194) (xy 194.533411 -292.411284) (xy 194.556282 -292.454861)
			(xy 194.571866 -292.501542) (xy 194.579761 -292.550119) (xy 194.580256 -292.574726) (xy 194.919104 -292.574726)
			(xy 194.923064 -292.525672) (xy 194.934841 -292.477888) (xy 194.954132 -292.432612) (xy 194.980435 -292.391016)
			(xy 195.01307 -292.354179) (xy 195.051191 -292.323054) (xy 195.093812 -292.298447) (xy 195.139828 -292.280995)
			(xy 195.188047 -292.271151) (xy 195.237222 -292.26917) (xy 195.286077 -292.275102) (xy 195.333348 -292.288794)
			(xy 195.37781 -292.309892) (xy 195.418313 -292.337848) (xy 195.453806 -292.37194) (xy 195.483371 -292.411284)
			(xy 195.506242 -292.454861) (xy 195.521826 -292.501542) (xy 195.529721 -292.550119) (xy 195.530216 -292.574726)
			(xy 195.869064 -292.574726) (xy 195.873024 -292.525672) (xy 195.884801 -292.477888) (xy 195.904092 -292.432612)
			(xy 195.930395 -292.391016) (xy 195.96303 -292.354179) (xy 196.001151 -292.323054) (xy 196.043772 -292.298447)
			(xy 196.089788 -292.280995) (xy 196.138007 -292.271151) (xy 196.187182 -292.26917) (xy 196.236037 -292.275102)
			(xy 196.283308 -292.288794) (xy 196.32777 -292.309892) (xy 196.368273 -292.337848) (xy 196.403766 -292.37194)
			(xy 196.433331 -292.411284) (xy 196.456202 -292.454861) (xy 196.471786 -292.501542) (xy 196.479681 -292.550119)
			(xy 196.480176 -292.574726) (xy 196.819278 -292.574726) (xy 196.823238 -292.525672) (xy 196.835015 -292.477888)
			(xy 196.854306 -292.432612) (xy 196.880609 -292.391016) (xy 196.913244 -292.354179) (xy 196.951365 -292.323054)
			(xy 196.993986 -292.298447) (xy 197.040002 -292.280995) (xy 197.088221 -292.271151) (xy 197.137396 -292.26917)
			(xy 197.186251 -292.275102) (xy 197.233522 -292.288794) (xy 197.277984 -292.309892) (xy 197.318487 -292.337848)
			(xy 197.35398 -292.37194) (xy 197.383545 -292.411284) (xy 197.406416 -292.454861) (xy 197.422 -292.501542)
			(xy 197.429895 -292.550119) (xy 197.43039 -292.574726) (xy 197.430385 -292.57498) (xy 197.769238 -292.57498)
			(xy 197.773198 -292.525926) (xy 197.784975 -292.478142) (xy 197.804266 -292.432866) (xy 197.830569 -292.39127)
			(xy 197.863204 -292.354433) (xy 197.901325 -292.323308) (xy 197.943946 -292.298701) (xy 197.989962 -292.281249)
			(xy 198.038181 -292.271405) (xy 198.087356 -292.269424) (xy 198.136211 -292.275356) (xy 198.183482 -292.289048)
			(xy 198.227944 -292.310146) (xy 198.268447 -292.338102) (xy 198.30394 -292.372194) (xy 198.333505 -292.411538)
			(xy 198.356376 -292.455115) (xy 198.37196 -292.501796) (xy 198.379855 -292.550373) (xy 198.38035 -292.57498)
			(xy 198.719198 -292.57498) (xy 198.723158 -292.525926) (xy 198.734935 -292.478142) (xy 198.754226 -292.432866)
			(xy 198.780529 -292.39127) (xy 198.813164 -292.354433) (xy 198.851285 -292.323308) (xy 198.893906 -292.298701)
			(xy 198.939922 -292.281249) (xy 198.988141 -292.271405) (xy 199.037316 -292.269424) (xy 199.086171 -292.275356)
			(xy 199.133442 -292.289048) (xy 199.177904 -292.310146) (xy 199.218407 -292.338102) (xy 199.2539 -292.372194)
			(xy 199.283465 -292.411538) (xy 199.306336 -292.455115) (xy 199.32192 -292.501796) (xy 199.329815 -292.550373)
			(xy 199.33031 -292.57498) (xy 199.329815 -292.599587) (xy 199.32192 -292.648164) (xy 199.306336 -292.694845)
			(xy 199.283465 -292.738422) (xy 199.2539 -292.777766) (xy 199.218407 -292.811858) (xy 199.177904 -292.839814)
			(xy 199.133442 -292.860912) (xy 199.086171 -292.874604) (xy 199.037316 -292.880536) (xy 198.988141 -292.878555)
			(xy 198.939922 -292.868711) (xy 198.893906 -292.851259) (xy 198.851285 -292.826652) (xy 198.813164 -292.795527)
			(xy 198.780529 -292.75869) (xy 198.754226 -292.717094) (xy 198.734935 -292.671818) (xy 198.723158 -292.624034)
			(xy 198.719198 -292.57498) (xy 198.38035 -292.57498) (xy 198.379855 -292.599587) (xy 198.37196 -292.648164)
			(xy 198.356376 -292.694845) (xy 198.333505 -292.738422) (xy 198.30394 -292.777766) (xy 198.268447 -292.811858)
			(xy 198.227944 -292.839814) (xy 198.183482 -292.860912) (xy 198.136211 -292.874604) (xy 198.087356 -292.880536)
			(xy 198.038181 -292.878555) (xy 197.989962 -292.868711) (xy 197.943946 -292.851259) (xy 197.901325 -292.826652)
			(xy 197.863204 -292.795527) (xy 197.830569 -292.75869) (xy 197.804266 -292.717094) (xy 197.784975 -292.671818)
			(xy 197.773198 -292.624034) (xy 197.769238 -292.57498) (xy 197.430385 -292.57498) (xy 197.429895 -292.599333)
			(xy 197.422 -292.64791) (xy 197.406416 -292.694591) (xy 197.383545 -292.738168) (xy 197.35398 -292.777512)
			(xy 197.318487 -292.811604) (xy 197.277984 -292.83956) (xy 197.233522 -292.860658) (xy 197.186251 -292.87435)
			(xy 197.137396 -292.880282) (xy 197.088221 -292.878301) (xy 197.040002 -292.868457) (xy 196.993986 -292.851005)
			(xy 196.951365 -292.826398) (xy 196.913244 -292.795273) (xy 196.880609 -292.758436) (xy 196.854306 -292.71684)
			(xy 196.835015 -292.671564) (xy 196.823238 -292.62378) (xy 196.819278 -292.574726) (xy 196.480176 -292.574726)
			(xy 196.479681 -292.599333) (xy 196.471786 -292.64791) (xy 196.456202 -292.694591) (xy 196.433331 -292.738168)
			(xy 196.403766 -292.777512) (xy 196.368273 -292.811604) (xy 196.32777 -292.83956) (xy 196.283308 -292.860658)
			(xy 196.236037 -292.87435) (xy 196.187182 -292.880282) (xy 196.138007 -292.878301) (xy 196.089788 -292.868457)
			(xy 196.043772 -292.851005) (xy 196.001151 -292.826398) (xy 195.96303 -292.795273) (xy 195.930395 -292.758436)
			(xy 195.904092 -292.71684) (xy 195.884801 -292.671564) (xy 195.873024 -292.62378) (xy 195.869064 -292.574726)
			(xy 195.530216 -292.574726) (xy 195.529721 -292.599333) (xy 195.521826 -292.64791) (xy 195.506242 -292.694591)
			(xy 195.483371 -292.738168) (xy 195.453806 -292.777512) (xy 195.418313 -292.811604) (xy 195.37781 -292.83956)
			(xy 195.333348 -292.860658) (xy 195.286077 -292.87435) (xy 195.237222 -292.880282) (xy 195.188047 -292.878301)
			(xy 195.139828 -292.868457) (xy 195.093812 -292.851005) (xy 195.051191 -292.826398) (xy 195.01307 -292.795273)
			(xy 194.980435 -292.758436) (xy 194.954132 -292.71684) (xy 194.934841 -292.671564) (xy 194.923064 -292.62378)
			(xy 194.919104 -292.574726) (xy 194.580256 -292.574726) (xy 194.579761 -292.599333) (xy 194.571866 -292.64791)
			(xy 194.556282 -292.694591) (xy 194.533411 -292.738168) (xy 194.503846 -292.777512) (xy 194.468353 -292.811604)
			(xy 194.42785 -292.83956) (xy 194.383388 -292.860658) (xy 194.336117 -292.87435) (xy 194.287262 -292.880282)
			(xy 194.238087 -292.878301) (xy 194.189868 -292.868457) (xy 194.143852 -292.851005) (xy 194.101231 -292.826398)
			(xy 194.06311 -292.795273) (xy 194.030475 -292.758436) (xy 194.004172 -292.71684) (xy 193.984881 -292.671564)
			(xy 193.973104 -292.62378) (xy 193.969144 -292.574726) (xy 193.630296 -292.574726) (xy 193.629801 -292.599333)
			(xy 193.621906 -292.64791) (xy 193.606322 -292.694591) (xy 193.583451 -292.738168) (xy 193.553886 -292.777512)
			(xy 193.518393 -292.811604) (xy 193.47789 -292.83956) (xy 193.433428 -292.860658) (xy 193.386157 -292.87435)
			(xy 193.337302 -292.880282) (xy 193.288127 -292.878301) (xy 193.239908 -292.868457) (xy 193.193892 -292.851005)
			(xy 193.151271 -292.826398) (xy 193.11315 -292.795273) (xy 193.080515 -292.758436) (xy 193.054212 -292.71684)
			(xy 193.034921 -292.671564) (xy 193.023144 -292.62378) (xy 193.019184 -292.574726) (xy 192.680336 -292.574726)
			(xy 192.679841 -292.599333) (xy 192.671946 -292.64791) (xy 192.656362 -292.694591) (xy 192.633491 -292.738168)
			(xy 192.603926 -292.777512) (xy 192.568433 -292.811604) (xy 192.52793 -292.83956) (xy 192.483468 -292.860658)
			(xy 192.436197 -292.87435) (xy 192.387342 -292.880282) (xy 192.338167 -292.878301) (xy 192.289948 -292.868457)
			(xy 192.243932 -292.851005) (xy 192.201311 -292.826398) (xy 192.16319 -292.795273) (xy 192.130555 -292.758436)
			(xy 192.104252 -292.71684) (xy 192.084961 -292.671564) (xy 192.073184 -292.62378) (xy 192.069224 -292.574726)
			(xy 191.730376 -292.574726) (xy 191.729881 -292.599333) (xy 191.721986 -292.64791) (xy 191.706402 -292.694591)
			(xy 191.683531 -292.738168) (xy 191.653966 -292.777512) (xy 191.618473 -292.811604) (xy 191.57797 -292.83956)
			(xy 191.533508 -292.860658) (xy 191.486237 -292.87435) (xy 191.437382 -292.880282) (xy 191.388207 -292.878301)
			(xy 191.339988 -292.868457) (xy 191.293972 -292.851005) (xy 191.251351 -292.826398) (xy 191.21323 -292.795273)
			(xy 191.180595 -292.758436) (xy 191.154292 -292.71684) (xy 191.135001 -292.671564) (xy 191.123224 -292.62378)
			(xy 191.119264 -292.574726) (xy 190.780162 -292.574726) (xy 190.779667 -292.599333) (xy 190.771772 -292.64791)
			(xy 190.756188 -292.694591) (xy 190.733317 -292.738168) (xy 190.703752 -292.777512) (xy 190.668259 -292.811604)
			(xy 190.627756 -292.83956) (xy 190.583294 -292.860658) (xy 190.536023 -292.87435) (xy 190.487168 -292.880282)
			(xy 190.437993 -292.878301) (xy 190.389774 -292.868457) (xy 190.343758 -292.851005) (xy 190.301137 -292.826398)
			(xy 190.263016 -292.795273) (xy 190.230381 -292.758436) (xy 190.204078 -292.71684) (xy 190.184787 -292.671564)
			(xy 190.17301 -292.62378) (xy 190.16905 -292.574726) (xy 189.830202 -292.574726) (xy 189.829707 -292.599333)
			(xy 189.821812 -292.64791) (xy 189.806228 -292.694591) (xy 189.783357 -292.738168) (xy 189.753792 -292.777512)
			(xy 189.718299 -292.811604) (xy 189.677796 -292.83956) (xy 189.633334 -292.860658) (xy 189.586063 -292.87435)
			(xy 189.537208 -292.880282) (xy 189.488033 -292.878301) (xy 189.439814 -292.868457) (xy 189.393798 -292.851005)
			(xy 189.351177 -292.826398) (xy 189.313056 -292.795273) (xy 189.280421 -292.758436) (xy 189.254118 -292.71684)
			(xy 189.234827 -292.671564) (xy 189.22305 -292.62378) (xy 189.21909 -292.574726) (xy 188.880242 -292.574726)
			(xy 188.879747 -292.599333) (xy 188.871852 -292.64791) (xy 188.856268 -292.694591) (xy 188.833397 -292.738168)
			(xy 188.803832 -292.777512) (xy 188.768339 -292.811604) (xy 188.727836 -292.83956) (xy 188.683374 -292.860658)
			(xy 188.636103 -292.87435) (xy 188.587248 -292.880282) (xy 188.538073 -292.878301) (xy 188.489854 -292.868457)
			(xy 188.443838 -292.851005) (xy 188.401217 -292.826398) (xy 188.363096 -292.795273) (xy 188.330461 -292.758436)
			(xy 188.304158 -292.71684) (xy 188.284867 -292.671564) (xy 188.27309 -292.62378) (xy 188.26913 -292.574726)
			(xy 187.930282 -292.574726) (xy 187.929787 -292.599333) (xy 187.921892 -292.64791) (xy 187.906308 -292.694591)
			(xy 187.883437 -292.738168) (xy 187.853872 -292.777512) (xy 187.818379 -292.811604) (xy 187.777876 -292.83956)
			(xy 187.733414 -292.860658) (xy 187.686143 -292.87435) (xy 187.637288 -292.880282) (xy 187.588113 -292.878301)
			(xy 187.539894 -292.868457) (xy 187.493878 -292.851005) (xy 187.451257 -292.826398) (xy 187.413136 -292.795273)
			(xy 187.380501 -292.758436) (xy 187.354198 -292.71684) (xy 187.334907 -292.671564) (xy 187.32313 -292.62378)
			(xy 187.31917 -292.574726) (xy 186.980317 -292.574726) (xy 186.980322 -292.57498) (xy 186.979827 -292.599587)
			(xy 186.971932 -292.648164) (xy 186.956348 -292.694845) (xy 186.933477 -292.738422) (xy 186.903912 -292.777766)
			(xy 186.868419 -292.811858) (xy 186.827916 -292.839814) (xy 186.783454 -292.860912) (xy 186.736183 -292.874604)
			(xy 186.687328 -292.880536) (xy 186.638153 -292.878555) (xy 186.589934 -292.868711) (xy 186.543918 -292.851259)
			(xy 186.501297 -292.826652) (xy 186.463176 -292.795527) (xy 186.430541 -292.75869) (xy 186.404238 -292.717094)
			(xy 186.384947 -292.671818) (xy 186.37317 -292.624034) (xy 186.36921 -292.57498) (xy 186.030357 -292.57498)
			(xy 186.029867 -292.599333) (xy 186.021972 -292.64791) (xy 186.006388 -292.694591) (xy 185.983517 -292.738168)
			(xy 185.953952 -292.777512) (xy 185.918459 -292.811604) (xy 185.877956 -292.83956) (xy 185.833494 -292.860658)
			(xy 185.786223 -292.87435) (xy 185.737368 -292.880282) (xy 185.688193 -292.878301) (xy 185.639974 -292.868457)
			(xy 185.593958 -292.851005) (xy 185.551337 -292.826398) (xy 185.513216 -292.795273) (xy 185.480581 -292.758436)
			(xy 185.454278 -292.71684) (xy 185.434987 -292.671564) (xy 185.42321 -292.62378) (xy 185.41925 -292.574726)
			(xy 185.080148 -292.574726) (xy 185.079653 -292.599333) (xy 185.071758 -292.64791) (xy 185.056174 -292.694591)
			(xy 185.033303 -292.738168) (xy 185.003738 -292.777512) (xy 184.968245 -292.811604) (xy 184.927742 -292.83956)
			(xy 184.88328 -292.860658) (xy 184.836009 -292.87435) (xy 184.787154 -292.880282) (xy 184.737979 -292.878301)
			(xy 184.68976 -292.868457) (xy 184.643744 -292.851005) (xy 184.601123 -292.826398) (xy 184.563002 -292.795273)
			(xy 184.530367 -292.758436) (xy 184.504064 -292.71684) (xy 184.484773 -292.671564) (xy 184.472996 -292.62378)
			(xy 184.469036 -292.574726) (xy 184.130188 -292.574726) (xy 184.129693 -292.599333) (xy 184.121798 -292.64791)
			(xy 184.106214 -292.694591) (xy 184.083343 -292.738168) (xy 184.053778 -292.777512) (xy 184.018285 -292.811604)
			(xy 183.977782 -292.83956) (xy 183.93332 -292.860658) (xy 183.886049 -292.87435) (xy 183.837194 -292.880282)
			(xy 183.788019 -292.878301) (xy 183.7398 -292.868457) (xy 183.693784 -292.851005) (xy 183.651163 -292.826398)
			(xy 183.613042 -292.795273) (xy 183.580407 -292.758436) (xy 183.554104 -292.71684) (xy 183.534813 -292.671564)
			(xy 183.523036 -292.62378) (xy 183.519076 -292.574726) (xy 183.180228 -292.574726) (xy 183.179733 -292.599333)
			(xy 183.171838 -292.64791) (xy 183.156254 -292.694591) (xy 183.133383 -292.738168) (xy 183.103818 -292.777512)
			(xy 183.068325 -292.811604) (xy 183.027822 -292.83956) (xy 182.98336 -292.860658) (xy 182.936089 -292.87435)
			(xy 182.887234 -292.880282) (xy 182.838059 -292.878301) (xy 182.78984 -292.868457) (xy 182.743824 -292.851005)
			(xy 182.701203 -292.826398) (xy 182.663082 -292.795273) (xy 182.630447 -292.758436) (xy 182.604144 -292.71684)
			(xy 182.584853 -292.671564) (xy 182.573076 -292.62378) (xy 182.569116 -292.574726) (xy 182.230268 -292.574726)
			(xy 182.229773 -292.599333) (xy 182.221878 -292.64791) (xy 182.206294 -292.694591) (xy 182.183423 -292.738168)
			(xy 182.153858 -292.777512) (xy 182.118365 -292.811604) (xy 182.077862 -292.83956) (xy 182.0334 -292.860658)
			(xy 181.986129 -292.87435) (xy 181.937274 -292.880282) (xy 181.888099 -292.878301) (xy 181.83988 -292.868457)
			(xy 181.793864 -292.851005) (xy 181.751243 -292.826398) (xy 181.713122 -292.795273) (xy 181.680487 -292.758436)
			(xy 181.654184 -292.71684) (xy 181.634893 -292.671564) (xy 181.623116 -292.62378) (xy 181.619156 -292.574726)
			(xy 181.280308 -292.574726) (xy 181.279813 -292.599333) (xy 181.271918 -292.64791) (xy 181.256334 -292.694591)
			(xy 181.233463 -292.738168) (xy 181.203898 -292.777512) (xy 181.168405 -292.811604) (xy 181.127902 -292.83956)
			(xy 181.08344 -292.860658) (xy 181.036169 -292.87435) (xy 180.987314 -292.880282) (xy 180.938139 -292.878301)
			(xy 180.88992 -292.868457) (xy 180.843904 -292.851005) (xy 180.801283 -292.826398) (xy 180.763162 -292.795273)
			(xy 180.730527 -292.758436) (xy 180.704224 -292.71684) (xy 180.684933 -292.671564) (xy 180.673156 -292.62378)
			(xy 180.669196 -292.574726) (xy 180.330348 -292.574726) (xy 180.329853 -292.599333) (xy 180.321958 -292.64791)
			(xy 180.306374 -292.694591) (xy 180.283503 -292.738168) (xy 180.253938 -292.777512) (xy 180.218445 -292.811604)
			(xy 180.177942 -292.83956) (xy 180.13348 -292.860658) (xy 180.086209 -292.87435) (xy 180.037354 -292.880282)
			(xy 179.988179 -292.878301) (xy 179.93996 -292.868457) (xy 179.893944 -292.851005) (xy 179.851323 -292.826398)
			(xy 179.813202 -292.795273) (xy 179.780567 -292.758436) (xy 179.754264 -292.71684) (xy 179.734973 -292.671564)
			(xy 179.723196 -292.62378) (xy 179.719236 -292.574726) (xy 179.380388 -292.574726) (xy 179.379893 -292.599333)
			(xy 179.371998 -292.64791) (xy 179.356414 -292.694591) (xy 179.333543 -292.738168) (xy 179.303978 -292.777512)
			(xy 179.268485 -292.811604) (xy 179.227982 -292.83956) (xy 179.18352 -292.860658) (xy 179.136249 -292.87435)
			(xy 179.087394 -292.880282) (xy 179.038219 -292.878301) (xy 178.99 -292.868457) (xy 178.943984 -292.851005)
			(xy 178.901363 -292.826398) (xy 178.863242 -292.795273) (xy 178.830607 -292.758436) (xy 178.804304 -292.71684)
			(xy 178.785013 -292.671564) (xy 178.773236 -292.62378) (xy 178.769276 -292.574726) (xy 178.430174 -292.574726)
			(xy 178.429679 -292.599333) (xy 178.421784 -292.64791) (xy 178.4062 -292.694591) (xy 178.383329 -292.738168)
			(xy 178.353764 -292.777512) (xy 178.318271 -292.811604) (xy 178.277768 -292.83956) (xy 178.233306 -292.860658)
			(xy 178.186035 -292.87435) (xy 178.13718 -292.880282) (xy 178.088005 -292.878301) (xy 178.039786 -292.868457)
			(xy 177.99377 -292.851005) (xy 177.951149 -292.826398) (xy 177.913028 -292.795273) (xy 177.880393 -292.758436)
			(xy 177.85409 -292.71684) (xy 177.834799 -292.671564) (xy 177.823022 -292.62378) (xy 177.819062 -292.574726)
			(xy 177.480214 -292.574726) (xy 177.479719 -292.599333) (xy 177.471824 -292.64791) (xy 177.45624 -292.694591)
			(xy 177.433369 -292.738168) (xy 177.403804 -292.777512) (xy 177.368311 -292.811604) (xy 177.327808 -292.83956)
			(xy 177.283346 -292.860658) (xy 177.236075 -292.87435) (xy 177.18722 -292.880282) (xy 177.138045 -292.878301)
			(xy 177.089826 -292.868457) (xy 177.04381 -292.851005) (xy 177.001189 -292.826398) (xy 176.963068 -292.795273)
			(xy 176.930433 -292.758436) (xy 176.90413 -292.71684) (xy 176.884839 -292.671564) (xy 176.873062 -292.62378)
			(xy 176.869102 -292.574726) (xy 176.530254 -292.574726) (xy 176.529759 -292.599333) (xy 176.521864 -292.64791)
			(xy 176.50628 -292.694591) (xy 176.483409 -292.738168) (xy 176.453844 -292.777512) (xy 176.418351 -292.811604)
			(xy 176.377848 -292.83956) (xy 176.333386 -292.860658) (xy 176.286115 -292.87435) (xy 176.23726 -292.880282)
			(xy 176.188085 -292.878301) (xy 176.139866 -292.868457) (xy 176.09385 -292.851005) (xy 176.051229 -292.826398)
			(xy 176.013108 -292.795273) (xy 175.980473 -292.758436) (xy 175.95417 -292.71684) (xy 175.934879 -292.671564)
			(xy 175.923102 -292.62378) (xy 175.919142 -292.574726) (xy 174.630329 -292.574726) (xy 174.630334 -292.57498)
			(xy 174.629839 -292.599587) (xy 174.621944 -292.648164) (xy 174.60636 -292.694845) (xy 174.583489 -292.738422)
			(xy 174.553924 -292.777766) (xy 174.518431 -292.811858) (xy 174.477928 -292.839814) (xy 174.433466 -292.860912)
			(xy 174.386195 -292.874604) (xy 174.33734 -292.880536) (xy 174.288165 -292.878555) (xy 174.239946 -292.868711)
			(xy 174.19393 -292.851259) (xy 174.151309 -292.826652) (xy 174.113188 -292.795527) (xy 174.080553 -292.75869)
			(xy 174.05425 -292.717094) (xy 174.034959 -292.671818) (xy 174.023182 -292.624034) (xy 174.019222 -292.57498)
			(xy 173.680374 -292.57498) (xy 173.679879 -292.599587) (xy 173.671984 -292.648164) (xy 173.6564 -292.694845)
			(xy 173.633529 -292.738422) (xy 173.603964 -292.777766) (xy 173.568471 -292.811858) (xy 173.527968 -292.839814)
			(xy 173.483506 -292.860912) (xy 173.436235 -292.874604) (xy 173.38738 -292.880536) (xy 173.338205 -292.878555)
			(xy 173.289986 -292.868711) (xy 173.24397 -292.851259) (xy 173.201349 -292.826652) (xy 173.163228 -292.795527)
			(xy 173.130593 -292.75869) (xy 173.10429 -292.717094) (xy 173.084999 -292.671818) (xy 173.073222 -292.624034)
			(xy 173.069262 -292.57498) (xy 172.730414 -292.57498) (xy 172.729919 -292.599587) (xy 172.722024 -292.648164)
			(xy 172.70644 -292.694845) (xy 172.683569 -292.738422) (xy 172.654004 -292.777766) (xy 172.618511 -292.811858)
			(xy 172.578008 -292.839814) (xy 172.533546 -292.860912) (xy 172.486275 -292.874604) (xy 172.43742 -292.880536)
			(xy 172.388245 -292.878555) (xy 172.340026 -292.868711) (xy 172.29401 -292.851259) (xy 172.251389 -292.826652)
			(xy 172.213268 -292.795527) (xy 172.180633 -292.75869) (xy 172.15433 -292.717094) (xy 172.135039 -292.671818)
			(xy 172.123262 -292.624034) (xy 172.119302 -292.57498) (xy 171.7802 -292.57498) (xy 171.779705 -292.599587)
			(xy 171.77181 -292.648164) (xy 171.756226 -292.694845) (xy 171.733355 -292.738422) (xy 171.70379 -292.777766)
			(xy 171.668297 -292.811858) (xy 171.627794 -292.839814) (xy 171.583332 -292.860912) (xy 171.536061 -292.874604)
			(xy 171.487206 -292.880536) (xy 171.438031 -292.878555) (xy 171.389812 -292.868711) (xy 171.343796 -292.851259)
			(xy 171.301175 -292.826652) (xy 171.263054 -292.795527) (xy 171.230419 -292.75869) (xy 171.204116 -292.717094)
			(xy 171.184825 -292.671818) (xy 171.173048 -292.624034) (xy 171.169088 -292.57498) (xy 170.83024 -292.57498)
			(xy 170.829745 -292.599587) (xy 170.82185 -292.648164) (xy 170.806266 -292.694845) (xy 170.783395 -292.738422)
			(xy 170.75383 -292.777766) (xy 170.718337 -292.811858) (xy 170.677834 -292.839814) (xy 170.633372 -292.860912)
			(xy 170.586101 -292.874604) (xy 170.537246 -292.880536) (xy 170.488071 -292.878555) (xy 170.439852 -292.868711)
			(xy 170.393836 -292.851259) (xy 170.351215 -292.826652) (xy 170.313094 -292.795527) (xy 170.280459 -292.75869)
			(xy 170.254156 -292.717094) (xy 170.234865 -292.671818) (xy 170.223088 -292.624034) (xy 170.219128 -292.57498)
			(xy 169.88028 -292.57498) (xy 169.879785 -292.599587) (xy 169.87189 -292.648164) (xy 169.856306 -292.694845)
			(xy 169.833435 -292.738422) (xy 169.80387 -292.777766) (xy 169.768377 -292.811858) (xy 169.727874 -292.839814)
			(xy 169.683412 -292.860912) (xy 169.636141 -292.874604) (xy 169.587286 -292.880536) (xy 169.538111 -292.878555)
			(xy 169.489892 -292.868711) (xy 169.443876 -292.851259) (xy 169.401255 -292.826652) (xy 169.363134 -292.795527)
			(xy 169.330499 -292.75869) (xy 169.304196 -292.717094) (xy 169.284905 -292.671818) (xy 169.273128 -292.624034)
			(xy 169.269168 -292.57498) (xy 168.93032 -292.57498) (xy 168.929825 -292.599587) (xy 168.92193 -292.648164)
			(xy 168.906346 -292.694845) (xy 168.883475 -292.738422) (xy 168.85391 -292.777766) (xy 168.818417 -292.811858)
			(xy 168.777914 -292.839814) (xy 168.733452 -292.860912) (xy 168.686181 -292.874604) (xy 168.637326 -292.880536)
			(xy 168.588151 -292.878555) (xy 168.539932 -292.868711) (xy 168.493916 -292.851259) (xy 168.451295 -292.826652)
			(xy 168.413174 -292.795527) (xy 168.380539 -292.75869) (xy 168.354236 -292.717094) (xy 168.334945 -292.671818)
			(xy 168.323168 -292.624034) (xy 168.319208 -292.57498) (xy 167.98036 -292.57498) (xy 167.979865 -292.599587)
			(xy 167.97197 -292.648164) (xy 167.956386 -292.694845) (xy 167.933515 -292.738422) (xy 167.90395 -292.777766)
			(xy 167.868457 -292.811858) (xy 167.827954 -292.839814) (xy 167.783492 -292.860912) (xy 167.736221 -292.874604)
			(xy 167.687366 -292.880536) (xy 167.638191 -292.878555) (xy 167.589972 -292.868711) (xy 167.543956 -292.851259)
			(xy 167.501335 -292.826652) (xy 167.463214 -292.795527) (xy 167.430579 -292.75869) (xy 167.404276 -292.717094)
			(xy 167.384985 -292.671818) (xy 167.373208 -292.624034) (xy 167.369248 -292.57498) (xy 167.0304 -292.57498)
			(xy 167.029905 -292.599587) (xy 167.02201 -292.648164) (xy 167.006426 -292.694845) (xy 166.983555 -292.738422)
			(xy 166.95399 -292.777766) (xy 166.918497 -292.811858) (xy 166.877994 -292.839814) (xy 166.833532 -292.860912)
			(xy 166.786261 -292.874604) (xy 166.737406 -292.880536) (xy 166.688231 -292.878555) (xy 166.640012 -292.868711)
			(xy 166.593996 -292.851259) (xy 166.551375 -292.826652) (xy 166.513254 -292.795527) (xy 166.480619 -292.75869)
			(xy 166.454316 -292.717094) (xy 166.435025 -292.671818) (xy 166.423248 -292.624034) (xy 166.419288 -292.57498)
			(xy 166.080181 -292.57498) (xy 166.079691 -292.599333) (xy 166.071796 -292.64791) (xy 166.056212 -292.694591)
			(xy 166.033341 -292.738168) (xy 166.003776 -292.777512) (xy 165.968283 -292.811604) (xy 165.92778 -292.83956)
			(xy 165.883318 -292.860658) (xy 165.836047 -292.87435) (xy 165.787192 -292.880282) (xy 165.738017 -292.878301)
			(xy 165.689798 -292.868457) (xy 165.643782 -292.851005) (xy 165.601161 -292.826398) (xy 165.56304 -292.795273)
			(xy 165.530405 -292.758436) (xy 165.504102 -292.71684) (xy 165.484811 -292.671564) (xy 165.473034 -292.62378)
			(xy 165.469074 -292.574726) (xy 165.155058 -292.574726) (xy 165.155058 -292.601083) (xy 165.14668 -292.653173)
			(xy 165.130137 -292.703271) (xy 165.105849 -292.750107) (xy 165.074433 -292.792493) (xy 165.036685 -292.829352)
			(xy 164.993563 -292.859749) (xy 164.946161 -292.882914) (xy 164.895683 -292.898258) (xy 164.869622 -292.902386)
			(xy 164.86505 -292.903148) (xy 164.854636 -292.90645) (xy 164.850318 -292.90772) (xy 164.826696 -292.918642)
			(xy 164.819838 -292.925754) (xy 164.804852 -292.941502) (xy 164.800264 -292.946607) (xy 164.793819 -292.95872)
			(xy 164.792152 -292.965378) (xy 164.790882 -292.9763) (xy 164.790882 -293.123366) (xy 164.79134 -293.133003)
			(xy 164.798506 -293.150899) (xy 164.804852 -293.158164) (xy 164.820092 -293.174166) (xy 164.82695 -293.181532)
			(xy 164.850318 -293.191946) (xy 164.854636 -293.193216) (xy 164.86505 -293.196518) (xy 164.869622 -293.19728)
			(xy 164.895688 -293.201357) (xy 164.946164 -293.216702) (xy 164.993563 -293.239867) (xy 165.036683 -293.270265)
			(xy 165.074428 -293.307123) (xy 165.105842 -293.349508) (xy 165.130128 -293.396343) (xy 165.146668 -293.446439)
			(xy 165.155045 -293.498527) (xy 165.155044 -293.52494) (xy 165.469074 -293.52494) (xy 165.473034 -293.475886)
			(xy 165.484811 -293.428102) (xy 165.504102 -293.382826) (xy 165.530405 -293.34123) (xy 165.56304 -293.304393)
			(xy 165.601161 -293.273268) (xy 165.643782 -293.248661) (xy 165.689798 -293.231209) (xy 165.738017 -293.221365)
			(xy 165.787192 -293.219384) (xy 165.836047 -293.225316) (xy 165.883318 -293.239008) (xy 165.92778 -293.260106)
			(xy 165.968283 -293.288062) (xy 166.003776 -293.322154) (xy 166.033341 -293.361498) (xy 166.056212 -293.405075)
			(xy 166.071796 -293.451756) (xy 166.079691 -293.500333) (xy 166.080186 -293.52494) (xy 166.419288 -293.52494)
			(xy 166.423248 -293.475886) (xy 166.435025 -293.428102) (xy 166.454316 -293.382826) (xy 166.480619 -293.34123)
			(xy 166.513254 -293.304393) (xy 166.551375 -293.273268) (xy 166.593996 -293.248661) (xy 166.640012 -293.231209)
			(xy 166.688231 -293.221365) (xy 166.737406 -293.219384) (xy 166.786261 -293.225316) (xy 166.833532 -293.239008)
			(xy 166.877994 -293.260106) (xy 166.918497 -293.288062) (xy 166.95399 -293.322154) (xy 166.983555 -293.361498)
			(xy 167.006426 -293.405075) (xy 167.02201 -293.451756) (xy 167.029905 -293.500333) (xy 167.0304 -293.52494)
			(xy 167.369248 -293.52494) (xy 167.373208 -293.475886) (xy 167.384985 -293.428102) (xy 167.404276 -293.382826)
			(xy 167.430579 -293.34123) (xy 167.463214 -293.304393) (xy 167.501335 -293.273268) (xy 167.543956 -293.248661)
			(xy 167.589972 -293.231209) (xy 167.638191 -293.221365) (xy 167.687366 -293.219384) (xy 167.736221 -293.225316)
			(xy 167.783492 -293.239008) (xy 167.827954 -293.260106) (xy 167.868457 -293.288062) (xy 167.90395 -293.322154)
			(xy 167.933515 -293.361498) (xy 167.956386 -293.405075) (xy 167.97197 -293.451756) (xy 167.979865 -293.500333)
			(xy 167.98036 -293.52494) (xy 168.319208 -293.52494) (xy 168.323168 -293.475886) (xy 168.334945 -293.428102)
			(xy 168.354236 -293.382826) (xy 168.380539 -293.34123) (xy 168.413174 -293.304393) (xy 168.451295 -293.273268)
			(xy 168.493916 -293.248661) (xy 168.539932 -293.231209) (xy 168.588151 -293.221365) (xy 168.637326 -293.219384)
			(xy 168.686181 -293.225316) (xy 168.733452 -293.239008) (xy 168.777914 -293.260106) (xy 168.818417 -293.288062)
			(xy 168.85391 -293.322154) (xy 168.883475 -293.361498) (xy 168.906346 -293.405075) (xy 168.92193 -293.451756)
			(xy 168.929825 -293.500333) (xy 168.93032 -293.52494) (xy 169.269168 -293.52494) (xy 169.273128 -293.475886)
			(xy 169.284905 -293.428102) (xy 169.304196 -293.382826) (xy 169.330499 -293.34123) (xy 169.363134 -293.304393)
			(xy 169.401255 -293.273268) (xy 169.443876 -293.248661) (xy 169.489892 -293.231209) (xy 169.538111 -293.221365)
			(xy 169.587286 -293.219384) (xy 169.636141 -293.225316) (xy 169.683412 -293.239008) (xy 169.727874 -293.260106)
			(xy 169.768377 -293.288062) (xy 169.80387 -293.322154) (xy 169.833435 -293.361498) (xy 169.856306 -293.405075)
			(xy 169.87189 -293.451756) (xy 169.879785 -293.500333) (xy 169.88028 -293.52494) (xy 170.219128 -293.52494)
			(xy 170.223088 -293.475886) (xy 170.234865 -293.428102) (xy 170.254156 -293.382826) (xy 170.280459 -293.34123)
			(xy 170.313094 -293.304393) (xy 170.351215 -293.273268) (xy 170.393836 -293.248661) (xy 170.439852 -293.231209)
			(xy 170.488071 -293.221365) (xy 170.537246 -293.219384) (xy 170.586101 -293.225316) (xy 170.633372 -293.239008)
			(xy 170.677834 -293.260106) (xy 170.718337 -293.288062) (xy 170.75383 -293.322154) (xy 170.783395 -293.361498)
			(xy 170.806266 -293.405075) (xy 170.82185 -293.451756) (xy 170.829745 -293.500333) (xy 170.83024 -293.52494)
			(xy 171.169088 -293.52494) (xy 171.173048 -293.475886) (xy 171.184825 -293.428102) (xy 171.204116 -293.382826)
			(xy 171.230419 -293.34123) (xy 171.263054 -293.304393) (xy 171.301175 -293.273268) (xy 171.343796 -293.248661)
			(xy 171.389812 -293.231209) (xy 171.438031 -293.221365) (xy 171.487206 -293.219384) (xy 171.536061 -293.225316)
			(xy 171.583332 -293.239008) (xy 171.627794 -293.260106) (xy 171.668297 -293.288062) (xy 171.70379 -293.322154)
			(xy 171.733355 -293.361498) (xy 171.756226 -293.405075) (xy 171.77181 -293.451756) (xy 171.779705 -293.500333)
			(xy 171.7802 -293.52494) (xy 172.119048 -293.52494) (xy 172.123008 -293.475886) (xy 172.134785 -293.428102)
			(xy 172.154076 -293.382826) (xy 172.180379 -293.34123) (xy 172.213014 -293.304393) (xy 172.251135 -293.273268)
			(xy 172.293756 -293.248661) (xy 172.339772 -293.231209) (xy 172.387991 -293.221365) (xy 172.437166 -293.219384)
			(xy 172.486021 -293.225316) (xy 172.533292 -293.239008) (xy 172.577754 -293.260106) (xy 172.618257 -293.288062)
			(xy 172.65375 -293.322154) (xy 172.683315 -293.361498) (xy 172.706186 -293.405075) (xy 172.72177 -293.451756)
			(xy 172.729665 -293.500333) (xy 172.73016 -293.52494) (xy 173.069262 -293.52494) (xy 173.073222 -293.475886)
			(xy 173.084999 -293.428102) (xy 173.10429 -293.382826) (xy 173.130593 -293.34123) (xy 173.163228 -293.304393)
			(xy 173.201349 -293.273268) (xy 173.24397 -293.248661) (xy 173.289986 -293.231209) (xy 173.338205 -293.221365)
			(xy 173.38738 -293.219384) (xy 173.436235 -293.225316) (xy 173.483506 -293.239008) (xy 173.527968 -293.260106)
			(xy 173.568471 -293.288062) (xy 173.603964 -293.322154) (xy 173.633529 -293.361498) (xy 173.6564 -293.405075)
			(xy 173.671984 -293.451756) (xy 173.679879 -293.500333) (xy 173.680374 -293.52494) (xy 174.019222 -293.52494)
			(xy 174.023182 -293.475886) (xy 174.034959 -293.428102) (xy 174.05425 -293.382826) (xy 174.080553 -293.34123)
			(xy 174.113188 -293.304393) (xy 174.151309 -293.273268) (xy 174.19393 -293.248661) (xy 174.239946 -293.231209)
			(xy 174.288165 -293.221365) (xy 174.33734 -293.219384) (xy 174.386195 -293.225316) (xy 174.433466 -293.239008)
			(xy 174.477928 -293.260106) (xy 174.518431 -293.288062) (xy 174.553924 -293.322154) (xy 174.583489 -293.361498)
			(xy 174.60636 -293.405075) (xy 174.621944 -293.451756) (xy 174.629839 -293.500333) (xy 174.630334 -293.52494)
			(xy 175.919142 -293.52494) (xy 175.923102 -293.475886) (xy 175.934879 -293.428102) (xy 175.95417 -293.382826)
			(xy 175.980473 -293.34123) (xy 176.013108 -293.304393) (xy 176.051229 -293.273268) (xy 176.09385 -293.248661)
			(xy 176.139866 -293.231209) (xy 176.188085 -293.221365) (xy 176.23726 -293.219384) (xy 176.286115 -293.225316)
			(xy 176.333386 -293.239008) (xy 176.377848 -293.260106) (xy 176.418351 -293.288062) (xy 176.453844 -293.322154)
			(xy 176.483409 -293.361498) (xy 176.50628 -293.405075) (xy 176.521864 -293.451756) (xy 176.529759 -293.500333)
			(xy 176.530254 -293.52494) (xy 176.869102 -293.52494) (xy 176.873062 -293.475886) (xy 176.884839 -293.428102)
			(xy 176.90413 -293.382826) (xy 176.930433 -293.34123) (xy 176.963068 -293.304393) (xy 177.001189 -293.273268)
			(xy 177.04381 -293.248661) (xy 177.089826 -293.231209) (xy 177.138045 -293.221365) (xy 177.18722 -293.219384)
			(xy 177.236075 -293.225316) (xy 177.283346 -293.239008) (xy 177.327808 -293.260106) (xy 177.368311 -293.288062)
			(xy 177.403804 -293.322154) (xy 177.433369 -293.361498) (xy 177.45624 -293.405075) (xy 177.471824 -293.451756)
			(xy 177.479719 -293.500333) (xy 177.480214 -293.52494) (xy 177.819062 -293.52494) (xy 177.823022 -293.475886)
			(xy 177.834799 -293.428102) (xy 177.85409 -293.382826) (xy 177.880393 -293.34123) (xy 177.913028 -293.304393)
			(xy 177.951149 -293.273268) (xy 177.99377 -293.248661) (xy 178.039786 -293.231209) (xy 178.088005 -293.221365)
			(xy 178.13718 -293.219384) (xy 178.186035 -293.225316) (xy 178.233306 -293.239008) (xy 178.277768 -293.260106)
			(xy 178.318271 -293.288062) (xy 178.353764 -293.322154) (xy 178.383329 -293.361498) (xy 178.4062 -293.405075)
			(xy 178.421784 -293.451756) (xy 178.429679 -293.500333) (xy 178.430174 -293.52494) (xy 178.769276 -293.52494)
			(xy 178.773236 -293.475886) (xy 178.785013 -293.428102) (xy 178.804304 -293.382826) (xy 178.830607 -293.34123)
			(xy 178.863242 -293.304393) (xy 178.901363 -293.273268) (xy 178.943984 -293.248661) (xy 178.99 -293.231209)
			(xy 179.038219 -293.221365) (xy 179.087394 -293.219384) (xy 179.136249 -293.225316) (xy 179.18352 -293.239008)
			(xy 179.227982 -293.260106) (xy 179.268485 -293.288062) (xy 179.303978 -293.322154) (xy 179.333543 -293.361498)
			(xy 179.356414 -293.405075) (xy 179.371998 -293.451756) (xy 179.379893 -293.500333) (xy 179.380388 -293.52494)
			(xy 179.719236 -293.52494) (xy 179.723196 -293.475886) (xy 179.734973 -293.428102) (xy 179.754264 -293.382826)
			(xy 179.780567 -293.34123) (xy 179.813202 -293.304393) (xy 179.851323 -293.273268) (xy 179.893944 -293.248661)
			(xy 179.93996 -293.231209) (xy 179.988179 -293.221365) (xy 180.037354 -293.219384) (xy 180.086209 -293.225316)
			(xy 180.13348 -293.239008) (xy 180.177942 -293.260106) (xy 180.218445 -293.288062) (xy 180.253938 -293.322154)
			(xy 180.283503 -293.361498) (xy 180.306374 -293.405075) (xy 180.321958 -293.451756) (xy 180.329853 -293.500333)
			(xy 180.330348 -293.52494) (xy 180.669196 -293.52494) (xy 180.673156 -293.475886) (xy 180.684933 -293.428102)
			(xy 180.704224 -293.382826) (xy 180.730527 -293.34123) (xy 180.763162 -293.304393) (xy 180.801283 -293.273268)
			(xy 180.843904 -293.248661) (xy 180.88992 -293.231209) (xy 180.938139 -293.221365) (xy 180.987314 -293.219384)
			(xy 181.036169 -293.225316) (xy 181.08344 -293.239008) (xy 181.127902 -293.260106) (xy 181.168405 -293.288062)
			(xy 181.203898 -293.322154) (xy 181.233463 -293.361498) (xy 181.256334 -293.405075) (xy 181.271918 -293.451756)
			(xy 181.279813 -293.500333) (xy 181.280308 -293.52494) (xy 181.619156 -293.52494) (xy 181.623116 -293.475886)
			(xy 181.634893 -293.428102) (xy 181.654184 -293.382826) (xy 181.680487 -293.34123) (xy 181.713122 -293.304393)
			(xy 181.751243 -293.273268) (xy 181.793864 -293.248661) (xy 181.83988 -293.231209) (xy 181.888099 -293.221365)
			(xy 181.937274 -293.219384) (xy 181.986129 -293.225316) (xy 182.0334 -293.239008) (xy 182.077862 -293.260106)
			(xy 182.118365 -293.288062) (xy 182.153858 -293.322154) (xy 182.183423 -293.361498) (xy 182.206294 -293.405075)
			(xy 182.221878 -293.451756) (xy 182.229773 -293.500333) (xy 182.230268 -293.52494) (xy 182.569116 -293.52494)
			(xy 182.573076 -293.475886) (xy 182.584853 -293.428102) (xy 182.604144 -293.382826) (xy 182.630447 -293.34123)
			(xy 182.663082 -293.304393) (xy 182.701203 -293.273268) (xy 182.743824 -293.248661) (xy 182.78984 -293.231209)
			(xy 182.838059 -293.221365) (xy 182.887234 -293.219384) (xy 182.936089 -293.225316) (xy 182.98336 -293.239008)
			(xy 183.027822 -293.260106) (xy 183.068325 -293.288062) (xy 183.103818 -293.322154) (xy 183.133383 -293.361498)
			(xy 183.156254 -293.405075) (xy 183.171838 -293.451756) (xy 183.179733 -293.500333) (xy 183.180228 -293.52494)
			(xy 183.519076 -293.52494) (xy 183.523036 -293.475886) (xy 183.534813 -293.428102) (xy 183.554104 -293.382826)
			(xy 183.580407 -293.34123) (xy 183.613042 -293.304393) (xy 183.651163 -293.273268) (xy 183.693784 -293.248661)
			(xy 183.7398 -293.231209) (xy 183.788019 -293.221365) (xy 183.837194 -293.219384) (xy 183.886049 -293.225316)
			(xy 183.93332 -293.239008) (xy 183.977782 -293.260106) (xy 184.018285 -293.288062) (xy 184.053778 -293.322154)
			(xy 184.083343 -293.361498) (xy 184.106214 -293.405075) (xy 184.121798 -293.451756) (xy 184.129693 -293.500333)
			(xy 184.130188 -293.52494) (xy 184.469036 -293.52494) (xy 184.472996 -293.475886) (xy 184.484773 -293.428102)
			(xy 184.504064 -293.382826) (xy 184.530367 -293.34123) (xy 184.563002 -293.304393) (xy 184.601123 -293.273268)
			(xy 184.643744 -293.248661) (xy 184.68976 -293.231209) (xy 184.737979 -293.221365) (xy 184.787154 -293.219384)
			(xy 184.836009 -293.225316) (xy 184.88328 -293.239008) (xy 184.927742 -293.260106) (xy 184.968245 -293.288062)
			(xy 185.003738 -293.322154) (xy 185.033303 -293.361498) (xy 185.056174 -293.405075) (xy 185.071758 -293.451756)
			(xy 185.079653 -293.500333) (xy 185.080148 -293.52494) (xy 185.41925 -293.52494) (xy 185.42321 -293.475886)
			(xy 185.434987 -293.428102) (xy 185.454278 -293.382826) (xy 185.480581 -293.34123) (xy 185.513216 -293.304393)
			(xy 185.551337 -293.273268) (xy 185.593958 -293.248661) (xy 185.639974 -293.231209) (xy 185.688193 -293.221365)
			(xy 185.737368 -293.219384) (xy 185.786223 -293.225316) (xy 185.833494 -293.239008) (xy 185.877956 -293.260106)
			(xy 185.918459 -293.288062) (xy 185.953952 -293.322154) (xy 185.983517 -293.361498) (xy 186.006388 -293.405075)
			(xy 186.021972 -293.451756) (xy 186.029867 -293.500333) (xy 186.030362 -293.52494) (xy 187.31917 -293.52494)
			(xy 187.32313 -293.475886) (xy 187.334907 -293.428102) (xy 187.354198 -293.382826) (xy 187.380501 -293.34123)
			(xy 187.413136 -293.304393) (xy 187.451257 -293.273268) (xy 187.493878 -293.248661) (xy 187.539894 -293.231209)
			(xy 187.588113 -293.221365) (xy 187.637288 -293.219384) (xy 187.686143 -293.225316) (xy 187.733414 -293.239008)
			(xy 187.777876 -293.260106) (xy 187.818379 -293.288062) (xy 187.853872 -293.322154) (xy 187.883437 -293.361498)
			(xy 187.906308 -293.405075) (xy 187.921892 -293.451756) (xy 187.929787 -293.500333) (xy 187.930282 -293.52494)
			(xy 188.26913 -293.52494) (xy 188.27309 -293.475886) (xy 188.284867 -293.428102) (xy 188.304158 -293.382826)
			(xy 188.330461 -293.34123) (xy 188.363096 -293.304393) (xy 188.401217 -293.273268) (xy 188.443838 -293.248661)
			(xy 188.489854 -293.231209) (xy 188.538073 -293.221365) (xy 188.587248 -293.219384) (xy 188.636103 -293.225316)
			(xy 188.683374 -293.239008) (xy 188.727836 -293.260106) (xy 188.768339 -293.288062) (xy 188.803832 -293.322154)
			(xy 188.833397 -293.361498) (xy 188.856268 -293.405075) (xy 188.871852 -293.451756) (xy 188.879747 -293.500333)
			(xy 188.880242 -293.52494) (xy 189.21909 -293.52494) (xy 189.22305 -293.475886) (xy 189.234827 -293.428102)
			(xy 189.254118 -293.382826) (xy 189.280421 -293.34123) (xy 189.313056 -293.304393) (xy 189.351177 -293.273268)
			(xy 189.393798 -293.248661) (xy 189.439814 -293.231209) (xy 189.488033 -293.221365) (xy 189.537208 -293.219384)
			(xy 189.586063 -293.225316) (xy 189.633334 -293.239008) (xy 189.677796 -293.260106) (xy 189.718299 -293.288062)
			(xy 189.753792 -293.322154) (xy 189.783357 -293.361498) (xy 189.806228 -293.405075) (xy 189.821812 -293.451756)
			(xy 189.829707 -293.500333) (xy 189.830202 -293.52494) (xy 190.169304 -293.52494) (xy 190.173264 -293.475886)
			(xy 190.185041 -293.428102) (xy 190.204332 -293.382826) (xy 190.230635 -293.34123) (xy 190.26327 -293.304393)
			(xy 190.301391 -293.273268) (xy 190.344012 -293.248661) (xy 190.390028 -293.231209) (xy 190.438247 -293.221365)
			(xy 190.487422 -293.219384) (xy 190.536277 -293.225316) (xy 190.583548 -293.239008) (xy 190.62801 -293.260106)
			(xy 190.668513 -293.288062) (xy 190.704006 -293.322154) (xy 190.733571 -293.361498) (xy 190.756442 -293.405075)
			(xy 190.772026 -293.451756) (xy 190.779921 -293.500333) (xy 190.780416 -293.52494) (xy 191.119264 -293.52494)
			(xy 191.123224 -293.475886) (xy 191.135001 -293.428102) (xy 191.154292 -293.382826) (xy 191.180595 -293.34123)
			(xy 191.21323 -293.304393) (xy 191.251351 -293.273268) (xy 191.293972 -293.248661) (xy 191.339988 -293.231209)
			(xy 191.388207 -293.221365) (xy 191.437382 -293.219384) (xy 191.486237 -293.225316) (xy 191.533508 -293.239008)
			(xy 191.57797 -293.260106) (xy 191.618473 -293.288062) (xy 191.653966 -293.322154) (xy 191.683531 -293.361498)
			(xy 191.706402 -293.405075) (xy 191.721986 -293.451756) (xy 191.729881 -293.500333) (xy 191.730376 -293.52494)
			(xy 192.069224 -293.52494) (xy 192.073184 -293.475886) (xy 192.084961 -293.428102) (xy 192.104252 -293.382826)
			(xy 192.130555 -293.34123) (xy 192.16319 -293.304393) (xy 192.201311 -293.273268) (xy 192.243932 -293.248661)
			(xy 192.289948 -293.231209) (xy 192.338167 -293.221365) (xy 192.387342 -293.219384) (xy 192.436197 -293.225316)
			(xy 192.483468 -293.239008) (xy 192.52793 -293.260106) (xy 192.568433 -293.288062) (xy 192.603926 -293.322154)
			(xy 192.633491 -293.361498) (xy 192.656362 -293.405075) (xy 192.671946 -293.451756) (xy 192.679841 -293.500333)
			(xy 192.680336 -293.52494) (xy 193.019184 -293.52494) (xy 193.023144 -293.475886) (xy 193.034921 -293.428102)
			(xy 193.054212 -293.382826) (xy 193.080515 -293.34123) (xy 193.11315 -293.304393) (xy 193.151271 -293.273268)
			(xy 193.193892 -293.248661) (xy 193.239908 -293.231209) (xy 193.288127 -293.221365) (xy 193.337302 -293.219384)
			(xy 193.386157 -293.225316) (xy 193.433428 -293.239008) (xy 193.47789 -293.260106) (xy 193.518393 -293.288062)
			(xy 193.553886 -293.322154) (xy 193.583451 -293.361498) (xy 193.606322 -293.405075) (xy 193.621906 -293.451756)
			(xy 193.629801 -293.500333) (xy 193.630296 -293.52494) (xy 193.969144 -293.52494) (xy 193.973104 -293.475886)
			(xy 193.984881 -293.428102) (xy 194.004172 -293.382826) (xy 194.030475 -293.34123) (xy 194.06311 -293.304393)
			(xy 194.101231 -293.273268) (xy 194.143852 -293.248661) (xy 194.189868 -293.231209) (xy 194.238087 -293.221365)
			(xy 194.287262 -293.219384) (xy 194.336117 -293.225316) (xy 194.383388 -293.239008) (xy 194.42785 -293.260106)
			(xy 194.468353 -293.288062) (xy 194.503846 -293.322154) (xy 194.533411 -293.361498) (xy 194.556282 -293.405075)
			(xy 194.571866 -293.451756) (xy 194.579761 -293.500333) (xy 194.580256 -293.52494) (xy 194.919104 -293.52494)
			(xy 194.923064 -293.475886) (xy 194.934841 -293.428102) (xy 194.954132 -293.382826) (xy 194.980435 -293.34123)
			(xy 195.01307 -293.304393) (xy 195.051191 -293.273268) (xy 195.093812 -293.248661) (xy 195.139828 -293.231209)
			(xy 195.188047 -293.221365) (xy 195.237222 -293.219384) (xy 195.286077 -293.225316) (xy 195.333348 -293.239008)
			(xy 195.37781 -293.260106) (xy 195.418313 -293.288062) (xy 195.453806 -293.322154) (xy 195.483371 -293.361498)
			(xy 195.506242 -293.405075) (xy 195.521826 -293.451756) (xy 195.529721 -293.500333) (xy 195.530216 -293.52494)
			(xy 195.869064 -293.52494) (xy 195.873024 -293.475886) (xy 195.884801 -293.428102) (xy 195.904092 -293.382826)
			(xy 195.930395 -293.34123) (xy 195.96303 -293.304393) (xy 196.001151 -293.273268) (xy 196.043772 -293.248661)
			(xy 196.089788 -293.231209) (xy 196.138007 -293.221365) (xy 196.187182 -293.219384) (xy 196.236037 -293.225316)
			(xy 196.283308 -293.239008) (xy 196.32777 -293.260106) (xy 196.368273 -293.288062) (xy 196.403766 -293.322154)
			(xy 196.433331 -293.361498) (xy 196.456202 -293.405075) (xy 196.471786 -293.451756) (xy 196.479681 -293.500333)
			(xy 196.480176 -293.52494) (xy 196.819278 -293.52494) (xy 196.823238 -293.475886) (xy 196.835015 -293.428102)
			(xy 196.854306 -293.382826) (xy 196.880609 -293.34123) (xy 196.913244 -293.304393) (xy 196.951365 -293.273268)
			(xy 196.993986 -293.248661) (xy 197.040002 -293.231209) (xy 197.088221 -293.221365) (xy 197.137396 -293.219384)
			(xy 197.186251 -293.225316) (xy 197.233522 -293.239008) (xy 197.277984 -293.260106) (xy 197.318487 -293.288062)
			(xy 197.35398 -293.322154) (xy 197.383545 -293.361498) (xy 197.406416 -293.405075) (xy 197.422 -293.451756)
			(xy 197.429895 -293.500333) (xy 197.43039 -293.52494) (xy 197.769238 -293.52494) (xy 197.773198 -293.475886)
			(xy 197.784975 -293.428102) (xy 197.804266 -293.382826) (xy 197.830569 -293.34123) (xy 197.863204 -293.304393)
			(xy 197.901325 -293.273268) (xy 197.943946 -293.248661) (xy 197.989962 -293.231209) (xy 198.038181 -293.221365)
			(xy 198.087356 -293.219384) (xy 198.136211 -293.225316) (xy 198.183482 -293.239008) (xy 198.227944 -293.260106)
			(xy 198.268447 -293.288062) (xy 198.30394 -293.322154) (xy 198.333505 -293.361498) (xy 198.356376 -293.405075)
			(xy 198.37196 -293.451756) (xy 198.379855 -293.500333) (xy 198.38035 -293.52494) (xy 198.719198 -293.52494)
			(xy 198.723158 -293.475886) (xy 198.734935 -293.428102) (xy 198.754226 -293.382826) (xy 198.780529 -293.34123)
			(xy 198.813164 -293.304393) (xy 198.851285 -293.273268) (xy 198.893906 -293.248661) (xy 198.939922 -293.231209)
			(xy 198.988141 -293.221365) (xy 199.037316 -293.219384) (xy 199.086171 -293.225316) (xy 199.133442 -293.239008)
			(xy 199.177904 -293.260106) (xy 199.218407 -293.288062) (xy 199.2539 -293.322154) (xy 199.283465 -293.361498)
			(xy 199.306336 -293.405075) (xy 199.32192 -293.451756) (xy 199.329815 -293.500333) (xy 199.33031 -293.52494)
			(xy 199.329815 -293.549547) (xy 199.32192 -293.598124) (xy 199.306336 -293.644805) (xy 199.283465 -293.688382)
			(xy 199.2539 -293.727726) (xy 199.218407 -293.761818) (xy 199.177904 -293.789774) (xy 199.133442 -293.810872)
			(xy 199.086171 -293.824564) (xy 199.037316 -293.830496) (xy 198.988141 -293.828515) (xy 198.939922 -293.818671)
			(xy 198.893906 -293.801219) (xy 198.851285 -293.776612) (xy 198.813164 -293.745487) (xy 198.780529 -293.70865)
			(xy 198.754226 -293.667054) (xy 198.734935 -293.621778) (xy 198.723158 -293.573994) (xy 198.719198 -293.52494)
			(xy 198.38035 -293.52494) (xy 198.379855 -293.549547) (xy 198.37196 -293.598124) (xy 198.356376 -293.644805)
			(xy 198.333505 -293.688382) (xy 198.30394 -293.727726) (xy 198.268447 -293.761818) (xy 198.227944 -293.789774)
			(xy 198.183482 -293.810872) (xy 198.136211 -293.824564) (xy 198.087356 -293.830496) (xy 198.038181 -293.828515)
			(xy 197.989962 -293.818671) (xy 197.943946 -293.801219) (xy 197.901325 -293.776612) (xy 197.863204 -293.745487)
			(xy 197.830569 -293.70865) (xy 197.804266 -293.667054) (xy 197.784975 -293.621778) (xy 197.773198 -293.573994)
			(xy 197.769238 -293.52494) (xy 197.43039 -293.52494) (xy 197.429895 -293.549547) (xy 197.422 -293.598124)
			(xy 197.406416 -293.644805) (xy 197.383545 -293.688382) (xy 197.35398 -293.727726) (xy 197.318487 -293.761818)
			(xy 197.277984 -293.789774) (xy 197.233522 -293.810872) (xy 197.186251 -293.824564) (xy 197.137396 -293.830496)
			(xy 197.088221 -293.828515) (xy 197.040002 -293.818671) (xy 196.993986 -293.801219) (xy 196.951365 -293.776612)
			(xy 196.913244 -293.745487) (xy 196.880609 -293.70865) (xy 196.854306 -293.667054) (xy 196.835015 -293.621778)
			(xy 196.823238 -293.573994) (xy 196.819278 -293.52494) (xy 196.480176 -293.52494) (xy 196.479681 -293.549547)
			(xy 196.471786 -293.598124) (xy 196.456202 -293.644805) (xy 196.433331 -293.688382) (xy 196.403766 -293.727726)
			(xy 196.368273 -293.761818) (xy 196.32777 -293.789774) (xy 196.283308 -293.810872) (xy 196.236037 -293.824564)
			(xy 196.187182 -293.830496) (xy 196.138007 -293.828515) (xy 196.089788 -293.818671) (xy 196.043772 -293.801219)
			(xy 196.001151 -293.776612) (xy 195.96303 -293.745487) (xy 195.930395 -293.70865) (xy 195.904092 -293.667054)
			(xy 195.884801 -293.621778) (xy 195.873024 -293.573994) (xy 195.869064 -293.52494) (xy 195.530216 -293.52494)
			(xy 195.529721 -293.549547) (xy 195.521826 -293.598124) (xy 195.506242 -293.644805) (xy 195.483371 -293.688382)
			(xy 195.453806 -293.727726) (xy 195.418313 -293.761818) (xy 195.37781 -293.789774) (xy 195.333348 -293.810872)
			(xy 195.286077 -293.824564) (xy 195.237222 -293.830496) (xy 195.188047 -293.828515) (xy 195.139828 -293.818671)
			(xy 195.093812 -293.801219) (xy 195.051191 -293.776612) (xy 195.01307 -293.745487) (xy 194.980435 -293.70865)
			(xy 194.954132 -293.667054) (xy 194.934841 -293.621778) (xy 194.923064 -293.573994) (xy 194.919104 -293.52494)
			(xy 194.580256 -293.52494) (xy 194.579761 -293.549547) (xy 194.571866 -293.598124) (xy 194.556282 -293.644805)
			(xy 194.533411 -293.688382) (xy 194.503846 -293.727726) (xy 194.468353 -293.761818) (xy 194.42785 -293.789774)
			(xy 194.383388 -293.810872) (xy 194.336117 -293.824564) (xy 194.287262 -293.830496) (xy 194.238087 -293.828515)
			(xy 194.189868 -293.818671) (xy 194.143852 -293.801219) (xy 194.101231 -293.776612) (xy 194.06311 -293.745487)
			(xy 194.030475 -293.70865) (xy 194.004172 -293.667054) (xy 193.984881 -293.621778) (xy 193.973104 -293.573994)
			(xy 193.969144 -293.52494) (xy 193.630296 -293.52494) (xy 193.629801 -293.549547) (xy 193.621906 -293.598124)
			(xy 193.606322 -293.644805) (xy 193.583451 -293.688382) (xy 193.553886 -293.727726) (xy 193.518393 -293.761818)
			(xy 193.47789 -293.789774) (xy 193.433428 -293.810872) (xy 193.386157 -293.824564) (xy 193.337302 -293.830496)
			(xy 193.288127 -293.828515) (xy 193.239908 -293.818671) (xy 193.193892 -293.801219) (xy 193.151271 -293.776612)
			(xy 193.11315 -293.745487) (xy 193.080515 -293.70865) (xy 193.054212 -293.667054) (xy 193.034921 -293.621778)
			(xy 193.023144 -293.573994) (xy 193.019184 -293.52494) (xy 192.680336 -293.52494) (xy 192.679841 -293.549547)
			(xy 192.671946 -293.598124) (xy 192.656362 -293.644805) (xy 192.633491 -293.688382) (xy 192.603926 -293.727726)
			(xy 192.568433 -293.761818) (xy 192.52793 -293.789774) (xy 192.483468 -293.810872) (xy 192.436197 -293.824564)
			(xy 192.387342 -293.830496) (xy 192.338167 -293.828515) (xy 192.289948 -293.818671) (xy 192.243932 -293.801219)
			(xy 192.201311 -293.776612) (xy 192.16319 -293.745487) (xy 192.130555 -293.70865) (xy 192.104252 -293.667054)
			(xy 192.084961 -293.621778) (xy 192.073184 -293.573994) (xy 192.069224 -293.52494) (xy 191.730376 -293.52494)
			(xy 191.729881 -293.549547) (xy 191.721986 -293.598124) (xy 191.706402 -293.644805) (xy 191.683531 -293.688382)
			(xy 191.653966 -293.727726) (xy 191.618473 -293.761818) (xy 191.57797 -293.789774) (xy 191.533508 -293.810872)
			(xy 191.486237 -293.824564) (xy 191.437382 -293.830496) (xy 191.388207 -293.828515) (xy 191.339988 -293.818671)
			(xy 191.293972 -293.801219) (xy 191.251351 -293.776612) (xy 191.21323 -293.745487) (xy 191.180595 -293.70865)
			(xy 191.154292 -293.667054) (xy 191.135001 -293.621778) (xy 191.123224 -293.573994) (xy 191.119264 -293.52494)
			(xy 190.780416 -293.52494) (xy 190.779921 -293.549547) (xy 190.772026 -293.598124) (xy 190.756442 -293.644805)
			(xy 190.733571 -293.688382) (xy 190.704006 -293.727726) (xy 190.668513 -293.761818) (xy 190.62801 -293.789774)
			(xy 190.583548 -293.810872) (xy 190.536277 -293.824564) (xy 190.487422 -293.830496) (xy 190.438247 -293.828515)
			(xy 190.390028 -293.818671) (xy 190.344012 -293.801219) (xy 190.301391 -293.776612) (xy 190.26327 -293.745487)
			(xy 190.230635 -293.70865) (xy 190.204332 -293.667054) (xy 190.185041 -293.621778) (xy 190.173264 -293.573994)
			(xy 190.169304 -293.52494) (xy 189.830202 -293.52494) (xy 189.829707 -293.549547) (xy 189.821812 -293.598124)
			(xy 189.806228 -293.644805) (xy 189.783357 -293.688382) (xy 189.753792 -293.727726) (xy 189.718299 -293.761818)
			(xy 189.677796 -293.789774) (xy 189.633334 -293.810872) (xy 189.586063 -293.824564) (xy 189.537208 -293.830496)
			(xy 189.488033 -293.828515) (xy 189.439814 -293.818671) (xy 189.393798 -293.801219) (xy 189.351177 -293.776612)
			(xy 189.313056 -293.745487) (xy 189.280421 -293.70865) (xy 189.254118 -293.667054) (xy 189.234827 -293.621778)
			(xy 189.22305 -293.573994) (xy 189.21909 -293.52494) (xy 188.880242 -293.52494) (xy 188.879747 -293.549547)
			(xy 188.871852 -293.598124) (xy 188.856268 -293.644805) (xy 188.833397 -293.688382) (xy 188.803832 -293.727726)
			(xy 188.768339 -293.761818) (xy 188.727836 -293.789774) (xy 188.683374 -293.810872) (xy 188.636103 -293.824564)
			(xy 188.587248 -293.830496) (xy 188.538073 -293.828515) (xy 188.489854 -293.818671) (xy 188.443838 -293.801219)
			(xy 188.401217 -293.776612) (xy 188.363096 -293.745487) (xy 188.330461 -293.70865) (xy 188.304158 -293.667054)
			(xy 188.284867 -293.621778) (xy 188.27309 -293.573994) (xy 188.26913 -293.52494) (xy 187.930282 -293.52494)
			(xy 187.929787 -293.549547) (xy 187.921892 -293.598124) (xy 187.906308 -293.644805) (xy 187.883437 -293.688382)
			(xy 187.853872 -293.727726) (xy 187.818379 -293.761818) (xy 187.777876 -293.789774) (xy 187.733414 -293.810872)
			(xy 187.686143 -293.824564) (xy 187.637288 -293.830496) (xy 187.588113 -293.828515) (xy 187.539894 -293.818671)
			(xy 187.493878 -293.801219) (xy 187.451257 -293.776612) (xy 187.413136 -293.745487) (xy 187.380501 -293.70865)
			(xy 187.354198 -293.667054) (xy 187.334907 -293.621778) (xy 187.32313 -293.573994) (xy 187.31917 -293.52494)
			(xy 186.030362 -293.52494) (xy 186.029867 -293.549547) (xy 186.021972 -293.598124) (xy 186.006388 -293.644805)
			(xy 185.983517 -293.688382) (xy 185.953952 -293.727726) (xy 185.918459 -293.761818) (xy 185.877956 -293.789774)
			(xy 185.833494 -293.810872) (xy 185.786223 -293.824564) (xy 185.737368 -293.830496) (xy 185.688193 -293.828515)
			(xy 185.639974 -293.818671) (xy 185.593958 -293.801219) (xy 185.551337 -293.776612) (xy 185.513216 -293.745487)
			(xy 185.480581 -293.70865) (xy 185.454278 -293.667054) (xy 185.434987 -293.621778) (xy 185.42321 -293.573994)
			(xy 185.41925 -293.52494) (xy 185.080148 -293.52494) (xy 185.079653 -293.549547) (xy 185.071758 -293.598124)
			(xy 185.056174 -293.644805) (xy 185.033303 -293.688382) (xy 185.003738 -293.727726) (xy 184.968245 -293.761818)
			(xy 184.927742 -293.789774) (xy 184.88328 -293.810872) (xy 184.836009 -293.824564) (xy 184.787154 -293.830496)
			(xy 184.737979 -293.828515) (xy 184.68976 -293.818671) (xy 184.643744 -293.801219) (xy 184.601123 -293.776612)
			(xy 184.563002 -293.745487) (xy 184.530367 -293.70865) (xy 184.504064 -293.667054) (xy 184.484773 -293.621778)
			(xy 184.472996 -293.573994) (xy 184.469036 -293.52494) (xy 184.130188 -293.52494) (xy 184.129693 -293.549547)
			(xy 184.121798 -293.598124) (xy 184.106214 -293.644805) (xy 184.083343 -293.688382) (xy 184.053778 -293.727726)
			(xy 184.018285 -293.761818) (xy 183.977782 -293.789774) (xy 183.93332 -293.810872) (xy 183.886049 -293.824564)
			(xy 183.837194 -293.830496) (xy 183.788019 -293.828515) (xy 183.7398 -293.818671) (xy 183.693784 -293.801219)
			(xy 183.651163 -293.776612) (xy 183.613042 -293.745487) (xy 183.580407 -293.70865) (xy 183.554104 -293.667054)
			(xy 183.534813 -293.621778) (xy 183.523036 -293.573994) (xy 183.519076 -293.52494) (xy 183.180228 -293.52494)
			(xy 183.179733 -293.549547) (xy 183.171838 -293.598124) (xy 183.156254 -293.644805) (xy 183.133383 -293.688382)
			(xy 183.103818 -293.727726) (xy 183.068325 -293.761818) (xy 183.027822 -293.789774) (xy 182.98336 -293.810872)
			(xy 182.936089 -293.824564) (xy 182.887234 -293.830496) (xy 182.838059 -293.828515) (xy 182.78984 -293.818671)
			(xy 182.743824 -293.801219) (xy 182.701203 -293.776612) (xy 182.663082 -293.745487) (xy 182.630447 -293.70865)
			(xy 182.604144 -293.667054) (xy 182.584853 -293.621778) (xy 182.573076 -293.573994) (xy 182.569116 -293.52494)
			(xy 182.230268 -293.52494) (xy 182.229773 -293.549547) (xy 182.221878 -293.598124) (xy 182.206294 -293.644805)
			(xy 182.183423 -293.688382) (xy 182.153858 -293.727726) (xy 182.118365 -293.761818) (xy 182.077862 -293.789774)
			(xy 182.0334 -293.810872) (xy 181.986129 -293.824564) (xy 181.937274 -293.830496) (xy 181.888099 -293.828515)
			(xy 181.83988 -293.818671) (xy 181.793864 -293.801219) (xy 181.751243 -293.776612) (xy 181.713122 -293.745487)
			(xy 181.680487 -293.70865) (xy 181.654184 -293.667054) (xy 181.634893 -293.621778) (xy 181.623116 -293.573994)
			(xy 181.619156 -293.52494) (xy 181.280308 -293.52494) (xy 181.279813 -293.549547) (xy 181.271918 -293.598124)
			(xy 181.256334 -293.644805) (xy 181.233463 -293.688382) (xy 181.203898 -293.727726) (xy 181.168405 -293.761818)
			(xy 181.127902 -293.789774) (xy 181.08344 -293.810872) (xy 181.036169 -293.824564) (xy 180.987314 -293.830496)
			(xy 180.938139 -293.828515) (xy 180.88992 -293.818671) (xy 180.843904 -293.801219) (xy 180.801283 -293.776612)
			(xy 180.763162 -293.745487) (xy 180.730527 -293.70865) (xy 180.704224 -293.667054) (xy 180.684933 -293.621778)
			(xy 180.673156 -293.573994) (xy 180.669196 -293.52494) (xy 180.330348 -293.52494) (xy 180.329853 -293.549547)
			(xy 180.321958 -293.598124) (xy 180.306374 -293.644805) (xy 180.283503 -293.688382) (xy 180.253938 -293.727726)
			(xy 180.218445 -293.761818) (xy 180.177942 -293.789774) (xy 180.13348 -293.810872) (xy 180.086209 -293.824564)
			(xy 180.037354 -293.830496) (xy 179.988179 -293.828515) (xy 179.93996 -293.818671) (xy 179.893944 -293.801219)
			(xy 179.851323 -293.776612) (xy 179.813202 -293.745487) (xy 179.780567 -293.70865) (xy 179.754264 -293.667054)
			(xy 179.734973 -293.621778) (xy 179.723196 -293.573994) (xy 179.719236 -293.52494) (xy 179.380388 -293.52494)
			(xy 179.379893 -293.549547) (xy 179.371998 -293.598124) (xy 179.356414 -293.644805) (xy 179.333543 -293.688382)
			(xy 179.303978 -293.727726) (xy 179.268485 -293.761818) (xy 179.227982 -293.789774) (xy 179.18352 -293.810872)
			(xy 179.136249 -293.824564) (xy 179.087394 -293.830496) (xy 179.038219 -293.828515) (xy 178.99 -293.818671)
			(xy 178.943984 -293.801219) (xy 178.901363 -293.776612) (xy 178.863242 -293.745487) (xy 178.830607 -293.70865)
			(xy 178.804304 -293.667054) (xy 178.785013 -293.621778) (xy 178.773236 -293.573994) (xy 178.769276 -293.52494)
			(xy 178.430174 -293.52494) (xy 178.429679 -293.549547) (xy 178.421784 -293.598124) (xy 178.4062 -293.644805)
			(xy 178.383329 -293.688382) (xy 178.353764 -293.727726) (xy 178.318271 -293.761818) (xy 178.277768 -293.789774)
			(xy 178.233306 -293.810872) (xy 178.186035 -293.824564) (xy 178.13718 -293.830496) (xy 178.088005 -293.828515)
			(xy 178.039786 -293.818671) (xy 177.99377 -293.801219) (xy 177.951149 -293.776612) (xy 177.913028 -293.745487)
			(xy 177.880393 -293.70865) (xy 177.85409 -293.667054) (xy 177.834799 -293.621778) (xy 177.823022 -293.573994)
			(xy 177.819062 -293.52494) (xy 177.480214 -293.52494) (xy 177.479719 -293.549547) (xy 177.471824 -293.598124)
			(xy 177.45624 -293.644805) (xy 177.433369 -293.688382) (xy 177.403804 -293.727726) (xy 177.368311 -293.761818)
			(xy 177.327808 -293.789774) (xy 177.283346 -293.810872) (xy 177.236075 -293.824564) (xy 177.18722 -293.830496)
			(xy 177.138045 -293.828515) (xy 177.089826 -293.818671) (xy 177.04381 -293.801219) (xy 177.001189 -293.776612)
			(xy 176.963068 -293.745487) (xy 176.930433 -293.70865) (xy 176.90413 -293.667054) (xy 176.884839 -293.621778)
			(xy 176.873062 -293.573994) (xy 176.869102 -293.52494) (xy 176.530254 -293.52494) (xy 176.529759 -293.549547)
			(xy 176.521864 -293.598124) (xy 176.50628 -293.644805) (xy 176.483409 -293.688382) (xy 176.453844 -293.727726)
			(xy 176.418351 -293.761818) (xy 176.377848 -293.789774) (xy 176.333386 -293.810872) (xy 176.286115 -293.824564)
			(xy 176.23726 -293.830496) (xy 176.188085 -293.828515) (xy 176.139866 -293.818671) (xy 176.09385 -293.801219)
			(xy 176.051229 -293.776612) (xy 176.013108 -293.745487) (xy 175.980473 -293.70865) (xy 175.95417 -293.667054)
			(xy 175.934879 -293.621778) (xy 175.923102 -293.573994) (xy 175.919142 -293.52494) (xy 174.630334 -293.52494)
			(xy 174.629839 -293.549547) (xy 174.621944 -293.598124) (xy 174.60636 -293.644805) (xy 174.583489 -293.688382)
			(xy 174.553924 -293.727726) (xy 174.518431 -293.761818) (xy 174.477928 -293.789774) (xy 174.433466 -293.810872)
			(xy 174.386195 -293.824564) (xy 174.33734 -293.830496) (xy 174.288165 -293.828515) (xy 174.239946 -293.818671)
			(xy 174.19393 -293.801219) (xy 174.151309 -293.776612) (xy 174.113188 -293.745487) (xy 174.080553 -293.70865)
			(xy 174.05425 -293.667054) (xy 174.034959 -293.621778) (xy 174.023182 -293.573994) (xy 174.019222 -293.52494)
			(xy 173.680374 -293.52494) (xy 173.679879 -293.549547) (xy 173.671984 -293.598124) (xy 173.6564 -293.644805)
			(xy 173.633529 -293.688382) (xy 173.603964 -293.727726) (xy 173.568471 -293.761818) (xy 173.527968 -293.789774)
			(xy 173.483506 -293.810872) (xy 173.436235 -293.824564) (xy 173.38738 -293.830496) (xy 173.338205 -293.828515)
			(xy 173.289986 -293.818671) (xy 173.24397 -293.801219) (xy 173.201349 -293.776612) (xy 173.163228 -293.745487)
			(xy 173.130593 -293.70865) (xy 173.10429 -293.667054) (xy 173.084999 -293.621778) (xy 173.073222 -293.573994)
			(xy 173.069262 -293.52494) (xy 172.73016 -293.52494) (xy 172.729665 -293.549547) (xy 172.72177 -293.598124)
			(xy 172.706186 -293.644805) (xy 172.683315 -293.688382) (xy 172.65375 -293.727726) (xy 172.618257 -293.761818)
			(xy 172.577754 -293.789774) (xy 172.533292 -293.810872) (xy 172.486021 -293.824564) (xy 172.437166 -293.830496)
			(xy 172.387991 -293.828515) (xy 172.339772 -293.818671) (xy 172.293756 -293.801219) (xy 172.251135 -293.776612)
			(xy 172.213014 -293.745487) (xy 172.180379 -293.70865) (xy 172.154076 -293.667054) (xy 172.134785 -293.621778)
			(xy 172.123008 -293.573994) (xy 172.119048 -293.52494) (xy 171.7802 -293.52494) (xy 171.779705 -293.549547)
			(xy 171.77181 -293.598124) (xy 171.756226 -293.644805) (xy 171.733355 -293.688382) (xy 171.70379 -293.727726)
			(xy 171.668297 -293.761818) (xy 171.627794 -293.789774) (xy 171.583332 -293.810872) (xy 171.536061 -293.824564)
			(xy 171.487206 -293.830496) (xy 171.438031 -293.828515) (xy 171.389812 -293.818671) (xy 171.343796 -293.801219)
			(xy 171.301175 -293.776612) (xy 171.263054 -293.745487) (xy 171.230419 -293.70865) (xy 171.204116 -293.667054)
			(xy 171.184825 -293.621778) (xy 171.173048 -293.573994) (xy 171.169088 -293.52494) (xy 170.83024 -293.52494)
			(xy 170.829745 -293.549547) (xy 170.82185 -293.598124) (xy 170.806266 -293.644805) (xy 170.783395 -293.688382)
			(xy 170.75383 -293.727726) (xy 170.718337 -293.761818) (xy 170.677834 -293.789774) (xy 170.633372 -293.810872)
			(xy 170.586101 -293.824564) (xy 170.537246 -293.830496) (xy 170.488071 -293.828515) (xy 170.439852 -293.818671)
			(xy 170.393836 -293.801219) (xy 170.351215 -293.776612) (xy 170.313094 -293.745487) (xy 170.280459 -293.70865)
			(xy 170.254156 -293.667054) (xy 170.234865 -293.621778) (xy 170.223088 -293.573994) (xy 170.219128 -293.52494)
			(xy 169.88028 -293.52494) (xy 169.879785 -293.549547) (xy 169.87189 -293.598124) (xy 169.856306 -293.644805)
			(xy 169.833435 -293.688382) (xy 169.80387 -293.727726) (xy 169.768377 -293.761818) (xy 169.727874 -293.789774)
			(xy 169.683412 -293.810872) (xy 169.636141 -293.824564) (xy 169.587286 -293.830496) (xy 169.538111 -293.828515)
			(xy 169.489892 -293.818671) (xy 169.443876 -293.801219) (xy 169.401255 -293.776612) (xy 169.363134 -293.745487)
			(xy 169.330499 -293.70865) (xy 169.304196 -293.667054) (xy 169.284905 -293.621778) (xy 169.273128 -293.573994)
			(xy 169.269168 -293.52494) (xy 168.93032 -293.52494) (xy 168.929825 -293.549547) (xy 168.92193 -293.598124)
			(xy 168.906346 -293.644805) (xy 168.883475 -293.688382) (xy 168.85391 -293.727726) (xy 168.818417 -293.761818)
			(xy 168.777914 -293.789774) (xy 168.733452 -293.810872) (xy 168.686181 -293.824564) (xy 168.637326 -293.830496)
			(xy 168.588151 -293.828515) (xy 168.539932 -293.818671) (xy 168.493916 -293.801219) (xy 168.451295 -293.776612)
			(xy 168.413174 -293.745487) (xy 168.380539 -293.70865) (xy 168.354236 -293.667054) (xy 168.334945 -293.621778)
			(xy 168.323168 -293.573994) (xy 168.319208 -293.52494) (xy 167.98036 -293.52494) (xy 167.979865 -293.549547)
			(xy 167.97197 -293.598124) (xy 167.956386 -293.644805) (xy 167.933515 -293.688382) (xy 167.90395 -293.727726)
			(xy 167.868457 -293.761818) (xy 167.827954 -293.789774) (xy 167.783492 -293.810872) (xy 167.736221 -293.824564)
			(xy 167.687366 -293.830496) (xy 167.638191 -293.828515) (xy 167.589972 -293.818671) (xy 167.543956 -293.801219)
			(xy 167.501335 -293.776612) (xy 167.463214 -293.745487) (xy 167.430579 -293.70865) (xy 167.404276 -293.667054)
			(xy 167.384985 -293.621778) (xy 167.373208 -293.573994) (xy 167.369248 -293.52494) (xy 167.0304 -293.52494)
			(xy 167.029905 -293.549547) (xy 167.02201 -293.598124) (xy 167.006426 -293.644805) (xy 166.983555 -293.688382)
			(xy 166.95399 -293.727726) (xy 166.918497 -293.761818) (xy 166.877994 -293.789774) (xy 166.833532 -293.810872)
			(xy 166.786261 -293.824564) (xy 166.737406 -293.830496) (xy 166.688231 -293.828515) (xy 166.640012 -293.818671)
			(xy 166.593996 -293.801219) (xy 166.551375 -293.776612) (xy 166.513254 -293.745487) (xy 166.480619 -293.70865)
			(xy 166.454316 -293.667054) (xy 166.435025 -293.621778) (xy 166.423248 -293.573994) (xy 166.419288 -293.52494)
			(xy 166.080186 -293.52494) (xy 166.079691 -293.549547) (xy 166.071796 -293.598124) (xy 166.056212 -293.644805)
			(xy 166.033341 -293.688382) (xy 166.003776 -293.727726) (xy 165.968283 -293.761818) (xy 165.92778 -293.789774)
			(xy 165.883318 -293.810872) (xy 165.836047 -293.824564) (xy 165.787192 -293.830496) (xy 165.738017 -293.828515)
			(xy 165.689798 -293.818671) (xy 165.643782 -293.801219) (xy 165.601161 -293.776612) (xy 165.56304 -293.745487)
			(xy 165.530405 -293.70865) (xy 165.504102 -293.667054) (xy 165.484811 -293.621778) (xy 165.473034 -293.573994)
			(xy 165.469074 -293.52494) (xy 165.155044 -293.52494) (xy 165.155044 -293.551284) (xy 165.146666 -293.603371)
			(xy 165.130124 -293.653467) (xy 165.105837 -293.700301) (xy 165.074421 -293.742685) (xy 165.036674 -293.779542)
			(xy 164.993554 -293.809938) (xy 164.946154 -293.833102) (xy 164.895678 -293.848445) (xy 164.869622 -293.8526)
			(xy 164.86505 -293.853362) (xy 164.854636 -293.856664) (xy 164.850318 -293.857934) (xy 164.826696 -293.868856)
			(xy 164.819838 -293.875968) (xy 164.804852 -293.891716) (xy 164.800265 -293.896822) (xy 164.793824 -293.908935)
			(xy 164.792152 -293.915592) (xy 164.790882 -293.926514) (xy 164.790882 -294.073326) (xy 164.791047 -294.07948)
			(xy 164.793994 -294.09143) (xy 164.796724 -294.096948) (xy 164.804852 -294.108124) (xy 164.819584 -294.123618)
			(xy 164.826188 -294.13073) (xy 164.849302 -294.141652) (xy 164.852858 -294.142668) (xy 164.86505 -294.146478)
			(xy 164.869622 -294.14724) (xy 164.895692 -294.151317) (xy 164.946174 -294.166663) (xy 164.993579 -294.18983)
			(xy 165.036704 -294.220231) (xy 165.074454 -294.257093) (xy 165.105873 -294.299482) (xy 165.130162 -294.346322)
			(xy 165.146706 -294.396425) (xy 165.155084 -294.448518) (xy 165.155084 -294.4749) (xy 165.469074 -294.4749)
			(xy 165.473034 -294.425846) (xy 165.484811 -294.378062) (xy 165.504102 -294.332786) (xy 165.530405 -294.29119)
			(xy 165.56304 -294.254353) (xy 165.601161 -294.223228) (xy 165.643782 -294.198621) (xy 165.689798 -294.181169)
			(xy 165.738017 -294.171325) (xy 165.787192 -294.169344) (xy 165.836047 -294.175276) (xy 165.883318 -294.188968)
			(xy 165.92778 -294.210066) (xy 165.968283 -294.238022) (xy 166.003776 -294.272114) (xy 166.033341 -294.311458)
			(xy 166.056212 -294.355035) (xy 166.071796 -294.401716) (xy 166.079691 -294.450293) (xy 166.080186 -294.4749)
			(xy 166.419288 -294.4749) (xy 166.423248 -294.425846) (xy 166.435025 -294.378062) (xy 166.454316 -294.332786)
			(xy 166.480619 -294.29119) (xy 166.513254 -294.254353) (xy 166.551375 -294.223228) (xy 166.593996 -294.198621)
			(xy 166.640012 -294.181169) (xy 166.688231 -294.171325) (xy 166.737406 -294.169344) (xy 166.786261 -294.175276)
			(xy 166.833532 -294.188968) (xy 166.877994 -294.210066) (xy 166.918497 -294.238022) (xy 166.95399 -294.272114)
			(xy 166.983555 -294.311458) (xy 167.006426 -294.355035) (xy 167.02201 -294.401716) (xy 167.029905 -294.450293)
			(xy 167.0304 -294.4749) (xy 167.369248 -294.4749) (xy 167.373208 -294.425846) (xy 167.384985 -294.378062)
			(xy 167.404276 -294.332786) (xy 167.430579 -294.29119) (xy 167.463214 -294.254353) (xy 167.501335 -294.223228)
			(xy 167.543956 -294.198621) (xy 167.589972 -294.181169) (xy 167.638191 -294.171325) (xy 167.687366 -294.169344)
			(xy 167.736221 -294.175276) (xy 167.783492 -294.188968) (xy 167.827954 -294.210066) (xy 167.868457 -294.238022)
			(xy 167.90395 -294.272114) (xy 167.933515 -294.311458) (xy 167.956386 -294.355035) (xy 167.97197 -294.401716)
			(xy 167.979865 -294.450293) (xy 167.98036 -294.4749) (xy 168.319208 -294.4749) (xy 168.323168 -294.425846)
			(xy 168.334945 -294.378062) (xy 168.354236 -294.332786) (xy 168.380539 -294.29119) (xy 168.413174 -294.254353)
			(xy 168.451295 -294.223228) (xy 168.493916 -294.198621) (xy 168.539932 -294.181169) (xy 168.588151 -294.171325)
			(xy 168.637326 -294.169344) (xy 168.686181 -294.175276) (xy 168.733452 -294.188968) (xy 168.777914 -294.210066)
			(xy 168.818417 -294.238022) (xy 168.85391 -294.272114) (xy 168.883475 -294.311458) (xy 168.906346 -294.355035)
			(xy 168.92193 -294.401716) (xy 168.929825 -294.450293) (xy 168.93032 -294.4749) (xy 169.269168 -294.4749)
			(xy 169.273128 -294.425846) (xy 169.284905 -294.378062) (xy 169.304196 -294.332786) (xy 169.330499 -294.29119)
			(xy 169.363134 -294.254353) (xy 169.401255 -294.223228) (xy 169.443876 -294.198621) (xy 169.489892 -294.181169)
			(xy 169.538111 -294.171325) (xy 169.587286 -294.169344) (xy 169.636141 -294.175276) (xy 169.683412 -294.188968)
			(xy 169.727874 -294.210066) (xy 169.768377 -294.238022) (xy 169.80387 -294.272114) (xy 169.833435 -294.311458)
			(xy 169.856306 -294.355035) (xy 169.87189 -294.401716) (xy 169.879785 -294.450293) (xy 169.88028 -294.4749)
			(xy 170.219128 -294.4749) (xy 170.223088 -294.425846) (xy 170.234865 -294.378062) (xy 170.254156 -294.332786)
			(xy 170.280459 -294.29119) (xy 170.313094 -294.254353) (xy 170.351215 -294.223228) (xy 170.393836 -294.198621)
			(xy 170.439852 -294.181169) (xy 170.488071 -294.171325) (xy 170.537246 -294.169344) (xy 170.586101 -294.175276)
			(xy 170.633372 -294.188968) (xy 170.677834 -294.210066) (xy 170.718337 -294.238022) (xy 170.75383 -294.272114)
			(xy 170.783395 -294.311458) (xy 170.806266 -294.355035) (xy 170.82185 -294.401716) (xy 170.829745 -294.450293)
			(xy 170.83024 -294.4749) (xy 171.169088 -294.4749) (xy 171.173048 -294.425846) (xy 171.184825 -294.378062)
			(xy 171.204116 -294.332786) (xy 171.230419 -294.29119) (xy 171.263054 -294.254353) (xy 171.301175 -294.223228)
			(xy 171.343796 -294.198621) (xy 171.389812 -294.181169) (xy 171.438031 -294.171325) (xy 171.487206 -294.169344)
			(xy 171.536061 -294.175276) (xy 171.583332 -294.188968) (xy 171.627794 -294.210066) (xy 171.668297 -294.238022)
			(xy 171.70379 -294.272114) (xy 171.733355 -294.311458) (xy 171.756226 -294.355035) (xy 171.77181 -294.401716)
			(xy 171.779705 -294.450293) (xy 171.7802 -294.4749) (xy 172.119048 -294.4749) (xy 172.123008 -294.425846)
			(xy 172.134785 -294.378062) (xy 172.154076 -294.332786) (xy 172.180379 -294.29119) (xy 172.213014 -294.254353)
			(xy 172.251135 -294.223228) (xy 172.293756 -294.198621) (xy 172.339772 -294.181169) (xy 172.387991 -294.171325)
			(xy 172.437166 -294.169344) (xy 172.486021 -294.175276) (xy 172.533292 -294.188968) (xy 172.577754 -294.210066)
			(xy 172.618257 -294.238022) (xy 172.65375 -294.272114) (xy 172.683315 -294.311458) (xy 172.706186 -294.355035)
			(xy 172.72177 -294.401716) (xy 172.729665 -294.450293) (xy 172.73016 -294.4749) (xy 173.069262 -294.4749)
			(xy 173.073222 -294.425846) (xy 173.084999 -294.378062) (xy 173.10429 -294.332786) (xy 173.130593 -294.29119)
			(xy 173.163228 -294.254353) (xy 173.201349 -294.223228) (xy 173.24397 -294.198621) (xy 173.289986 -294.181169)
			(xy 173.338205 -294.171325) (xy 173.38738 -294.169344) (xy 173.436235 -294.175276) (xy 173.483506 -294.188968)
			(xy 173.527968 -294.210066) (xy 173.568471 -294.238022) (xy 173.603964 -294.272114) (xy 173.633529 -294.311458)
			(xy 173.6564 -294.355035) (xy 173.671984 -294.401716) (xy 173.679879 -294.450293) (xy 173.680374 -294.4749)
			(xy 174.019222 -294.4749) (xy 174.023182 -294.425846) (xy 174.034959 -294.378062) (xy 174.05425 -294.332786)
			(xy 174.080553 -294.29119) (xy 174.113188 -294.254353) (xy 174.151309 -294.223228) (xy 174.19393 -294.198621)
			(xy 174.239946 -294.181169) (xy 174.288165 -294.171325) (xy 174.33734 -294.169344) (xy 174.386195 -294.175276)
			(xy 174.433466 -294.188968) (xy 174.477928 -294.210066) (xy 174.518431 -294.238022) (xy 174.553924 -294.272114)
			(xy 174.583489 -294.311458) (xy 174.60636 -294.355035) (xy 174.621944 -294.401716) (xy 174.629839 -294.450293)
			(xy 174.630334 -294.4749) (xy 175.919142 -294.4749) (xy 175.923102 -294.425846) (xy 175.934879 -294.378062)
			(xy 175.95417 -294.332786) (xy 175.980473 -294.29119) (xy 176.013108 -294.254353) (xy 176.051229 -294.223228)
			(xy 176.09385 -294.198621) (xy 176.139866 -294.181169) (xy 176.188085 -294.171325) (xy 176.23726 -294.169344)
			(xy 176.286115 -294.175276) (xy 176.333386 -294.188968) (xy 176.377848 -294.210066) (xy 176.418351 -294.238022)
			(xy 176.453844 -294.272114) (xy 176.483409 -294.311458) (xy 176.50628 -294.355035) (xy 176.521864 -294.401716)
			(xy 176.529759 -294.450293) (xy 176.530254 -294.4749) (xy 176.869102 -294.4749) (xy 176.873062 -294.425846)
			(xy 176.884839 -294.378062) (xy 176.90413 -294.332786) (xy 176.930433 -294.29119) (xy 176.963068 -294.254353)
			(xy 177.001189 -294.223228) (xy 177.04381 -294.198621) (xy 177.089826 -294.181169) (xy 177.138045 -294.171325)
			(xy 177.18722 -294.169344) (xy 177.236075 -294.175276) (xy 177.283346 -294.188968) (xy 177.327808 -294.210066)
			(xy 177.368311 -294.238022) (xy 177.403804 -294.272114) (xy 177.433369 -294.311458) (xy 177.45624 -294.355035)
			(xy 177.471824 -294.401716) (xy 177.479719 -294.450293) (xy 177.480214 -294.4749) (xy 177.819062 -294.4749)
			(xy 177.823022 -294.425846) (xy 177.834799 -294.378062) (xy 177.85409 -294.332786) (xy 177.880393 -294.29119)
			(xy 177.913028 -294.254353) (xy 177.951149 -294.223228) (xy 177.99377 -294.198621) (xy 178.039786 -294.181169)
			(xy 178.088005 -294.171325) (xy 178.13718 -294.169344) (xy 178.186035 -294.175276) (xy 178.233306 -294.188968)
			(xy 178.277768 -294.210066) (xy 178.318271 -294.238022) (xy 178.353764 -294.272114) (xy 178.383329 -294.311458)
			(xy 178.4062 -294.355035) (xy 178.421784 -294.401716) (xy 178.429679 -294.450293) (xy 178.430174 -294.4749)
			(xy 178.769276 -294.4749) (xy 178.773236 -294.425846) (xy 178.785013 -294.378062) (xy 178.804304 -294.332786)
			(xy 178.830607 -294.29119) (xy 178.863242 -294.254353) (xy 178.901363 -294.223228) (xy 178.943984 -294.198621)
			(xy 178.99 -294.181169) (xy 179.038219 -294.171325) (xy 179.087394 -294.169344) (xy 179.136249 -294.175276)
			(xy 179.18352 -294.188968) (xy 179.227982 -294.210066) (xy 179.268485 -294.238022) (xy 179.303978 -294.272114)
			(xy 179.333543 -294.311458) (xy 179.356414 -294.355035) (xy 179.371998 -294.401716) (xy 179.379893 -294.450293)
			(xy 179.380388 -294.4749) (xy 179.719236 -294.4749) (xy 179.723196 -294.425846) (xy 179.734973 -294.378062)
			(xy 179.754264 -294.332786) (xy 179.780567 -294.29119) (xy 179.813202 -294.254353) (xy 179.851323 -294.223228)
			(xy 179.893944 -294.198621) (xy 179.93996 -294.181169) (xy 179.988179 -294.171325) (xy 180.037354 -294.169344)
			(xy 180.086209 -294.175276) (xy 180.13348 -294.188968) (xy 180.177942 -294.210066) (xy 180.218445 -294.238022)
			(xy 180.253938 -294.272114) (xy 180.283503 -294.311458) (xy 180.306374 -294.355035) (xy 180.321958 -294.401716)
			(xy 180.329853 -294.450293) (xy 180.330348 -294.4749) (xy 180.669196 -294.4749) (xy 180.673156 -294.425846)
			(xy 180.684933 -294.378062) (xy 180.704224 -294.332786) (xy 180.730527 -294.29119) (xy 180.763162 -294.254353)
			(xy 180.801283 -294.223228) (xy 180.843904 -294.198621) (xy 180.88992 -294.181169) (xy 180.938139 -294.171325)
			(xy 180.987314 -294.169344) (xy 181.036169 -294.175276) (xy 181.08344 -294.188968) (xy 181.127902 -294.210066)
			(xy 181.168405 -294.238022) (xy 181.203898 -294.272114) (xy 181.233463 -294.311458) (xy 181.256334 -294.355035)
			(xy 181.271918 -294.401716) (xy 181.279813 -294.450293) (xy 181.280308 -294.4749) (xy 181.619156 -294.4749)
			(xy 181.623116 -294.425846) (xy 181.634893 -294.378062) (xy 181.654184 -294.332786) (xy 181.680487 -294.29119)
			(xy 181.713122 -294.254353) (xy 181.751243 -294.223228) (xy 181.793864 -294.198621) (xy 181.83988 -294.181169)
			(xy 181.888099 -294.171325) (xy 181.937274 -294.169344) (xy 181.986129 -294.175276) (xy 182.0334 -294.188968)
			(xy 182.077862 -294.210066) (xy 182.118365 -294.238022) (xy 182.153858 -294.272114) (xy 182.183423 -294.311458)
			(xy 182.206294 -294.355035) (xy 182.221878 -294.401716) (xy 182.229773 -294.450293) (xy 182.230268 -294.4749)
			(xy 182.569116 -294.4749) (xy 182.573076 -294.425846) (xy 182.584853 -294.378062) (xy 182.604144 -294.332786)
			(xy 182.630447 -294.29119) (xy 182.663082 -294.254353) (xy 182.701203 -294.223228) (xy 182.743824 -294.198621)
			(xy 182.78984 -294.181169) (xy 182.838059 -294.171325) (xy 182.887234 -294.169344) (xy 182.936089 -294.175276)
			(xy 182.98336 -294.188968) (xy 183.027822 -294.210066) (xy 183.068325 -294.238022) (xy 183.103818 -294.272114)
			(xy 183.133383 -294.311458) (xy 183.156254 -294.355035) (xy 183.171838 -294.401716) (xy 183.179733 -294.450293)
			(xy 183.180228 -294.4749) (xy 183.519076 -294.4749) (xy 183.523036 -294.425846) (xy 183.534813 -294.378062)
			(xy 183.554104 -294.332786) (xy 183.580407 -294.29119) (xy 183.613042 -294.254353) (xy 183.651163 -294.223228)
			(xy 183.693784 -294.198621) (xy 183.7398 -294.181169) (xy 183.788019 -294.171325) (xy 183.837194 -294.169344)
			(xy 183.886049 -294.175276) (xy 183.93332 -294.188968) (xy 183.977782 -294.210066) (xy 184.018285 -294.238022)
			(xy 184.053778 -294.272114) (xy 184.083343 -294.311458) (xy 184.106214 -294.355035) (xy 184.121798 -294.401716)
			(xy 184.129693 -294.450293) (xy 184.130188 -294.4749) (xy 184.469036 -294.4749) (xy 184.472996 -294.425846)
			(xy 184.484773 -294.378062) (xy 184.504064 -294.332786) (xy 184.530367 -294.29119) (xy 184.563002 -294.254353)
			(xy 184.601123 -294.223228) (xy 184.643744 -294.198621) (xy 184.68976 -294.181169) (xy 184.737979 -294.171325)
			(xy 184.787154 -294.169344) (xy 184.836009 -294.175276) (xy 184.88328 -294.188968) (xy 184.927742 -294.210066)
			(xy 184.968245 -294.238022) (xy 185.003738 -294.272114) (xy 185.033303 -294.311458) (xy 185.056174 -294.355035)
			(xy 185.071758 -294.401716) (xy 185.079653 -294.450293) (xy 185.080148 -294.4749) (xy 185.41925 -294.4749)
			(xy 185.42321 -294.425846) (xy 185.434987 -294.378062) (xy 185.454278 -294.332786) (xy 185.480581 -294.29119)
			(xy 185.513216 -294.254353) (xy 185.551337 -294.223228) (xy 185.593958 -294.198621) (xy 185.639974 -294.181169)
			(xy 185.688193 -294.171325) (xy 185.737368 -294.169344) (xy 185.786223 -294.175276) (xy 185.833494 -294.188968)
			(xy 185.877956 -294.210066) (xy 185.918459 -294.238022) (xy 185.953952 -294.272114) (xy 185.983517 -294.311458)
			(xy 186.006388 -294.355035) (xy 186.021972 -294.401716) (xy 186.029867 -294.450293) (xy 186.030362 -294.4749)
			(xy 187.31917 -294.4749) (xy 187.32313 -294.425846) (xy 187.334907 -294.378062) (xy 187.354198 -294.332786)
			(xy 187.380501 -294.29119) (xy 187.413136 -294.254353) (xy 187.451257 -294.223228) (xy 187.493878 -294.198621)
			(xy 187.539894 -294.181169) (xy 187.588113 -294.171325) (xy 187.637288 -294.169344) (xy 187.686143 -294.175276)
			(xy 187.733414 -294.188968) (xy 187.777876 -294.210066) (xy 187.818379 -294.238022) (xy 187.853872 -294.272114)
			(xy 187.883437 -294.311458) (xy 187.906308 -294.355035) (xy 187.921892 -294.401716) (xy 187.929787 -294.450293)
			(xy 187.930282 -294.4749) (xy 188.26913 -294.4749) (xy 188.27309 -294.425846) (xy 188.284867 -294.378062)
			(xy 188.304158 -294.332786) (xy 188.330461 -294.29119) (xy 188.363096 -294.254353) (xy 188.401217 -294.223228)
			(xy 188.443838 -294.198621) (xy 188.489854 -294.181169) (xy 188.538073 -294.171325) (xy 188.587248 -294.169344)
			(xy 188.636103 -294.175276) (xy 188.683374 -294.188968) (xy 188.727836 -294.210066) (xy 188.768339 -294.238022)
			(xy 188.803832 -294.272114) (xy 188.833397 -294.311458) (xy 188.856268 -294.355035) (xy 188.871852 -294.401716)
			(xy 188.879747 -294.450293) (xy 188.880242 -294.4749) (xy 189.21909 -294.4749) (xy 189.22305 -294.425846)
			(xy 189.234827 -294.378062) (xy 189.254118 -294.332786) (xy 189.280421 -294.29119) (xy 189.313056 -294.254353)
			(xy 189.351177 -294.223228) (xy 189.393798 -294.198621) (xy 189.439814 -294.181169) (xy 189.488033 -294.171325)
			(xy 189.537208 -294.169344) (xy 189.586063 -294.175276) (xy 189.633334 -294.188968) (xy 189.677796 -294.210066)
			(xy 189.718299 -294.238022) (xy 189.753792 -294.272114) (xy 189.783357 -294.311458) (xy 189.806228 -294.355035)
			(xy 189.821812 -294.401716) (xy 189.829707 -294.450293) (xy 189.830202 -294.4749) (xy 190.16905 -294.4749)
			(xy 190.17301 -294.425846) (xy 190.184787 -294.378062) (xy 190.204078 -294.332786) (xy 190.230381 -294.29119)
			(xy 190.263016 -294.254353) (xy 190.301137 -294.223228) (xy 190.343758 -294.198621) (xy 190.389774 -294.181169)
			(xy 190.437993 -294.171325) (xy 190.487168 -294.169344) (xy 190.536023 -294.175276) (xy 190.583294 -294.188968)
			(xy 190.627756 -294.210066) (xy 190.668259 -294.238022) (xy 190.703752 -294.272114) (xy 190.733317 -294.311458)
			(xy 190.756188 -294.355035) (xy 190.771772 -294.401716) (xy 190.779667 -294.450293) (xy 190.780162 -294.4749)
			(xy 191.119264 -294.4749) (xy 191.123224 -294.425846) (xy 191.135001 -294.378062) (xy 191.154292 -294.332786)
			(xy 191.180595 -294.29119) (xy 191.21323 -294.254353) (xy 191.251351 -294.223228) (xy 191.293972 -294.198621)
			(xy 191.339988 -294.181169) (xy 191.388207 -294.171325) (xy 191.437382 -294.169344) (xy 191.486237 -294.175276)
			(xy 191.533508 -294.188968) (xy 191.57797 -294.210066) (xy 191.618473 -294.238022) (xy 191.653966 -294.272114)
			(xy 191.683531 -294.311458) (xy 191.706402 -294.355035) (xy 191.721986 -294.401716) (xy 191.729881 -294.450293)
			(xy 191.730376 -294.4749) (xy 192.069224 -294.4749) (xy 192.073184 -294.425846) (xy 192.084961 -294.378062)
			(xy 192.104252 -294.332786) (xy 192.130555 -294.29119) (xy 192.16319 -294.254353) (xy 192.201311 -294.223228)
			(xy 192.243932 -294.198621) (xy 192.289948 -294.181169) (xy 192.338167 -294.171325) (xy 192.387342 -294.169344)
			(xy 192.436197 -294.175276) (xy 192.483468 -294.188968) (xy 192.52793 -294.210066) (xy 192.568433 -294.238022)
			(xy 192.603926 -294.272114) (xy 192.633491 -294.311458) (xy 192.656362 -294.355035) (xy 192.671946 -294.401716)
			(xy 192.679841 -294.450293) (xy 192.680336 -294.4749) (xy 193.969144 -294.4749) (xy 193.973104 -294.425846)
			(xy 193.984881 -294.378062) (xy 194.004172 -294.332786) (xy 194.030475 -294.29119) (xy 194.06311 -294.254353)
			(xy 194.101231 -294.223228) (xy 194.143852 -294.198621) (xy 194.189868 -294.181169) (xy 194.238087 -294.171325)
			(xy 194.287262 -294.169344) (xy 194.336117 -294.175276) (xy 194.383388 -294.188968) (xy 194.42785 -294.210066)
			(xy 194.468353 -294.238022) (xy 194.503846 -294.272114) (xy 194.533411 -294.311458) (xy 194.556282 -294.355035)
			(xy 194.571866 -294.401716) (xy 194.579761 -294.450293) (xy 194.580256 -294.4749) (xy 194.919104 -294.4749)
			(xy 194.923064 -294.425846) (xy 194.934841 -294.378062) (xy 194.954132 -294.332786) (xy 194.980435 -294.29119)
			(xy 195.01307 -294.254353) (xy 195.051191 -294.223228) (xy 195.093812 -294.198621) (xy 195.139828 -294.181169)
			(xy 195.188047 -294.171325) (xy 195.237222 -294.169344) (xy 195.286077 -294.175276) (xy 195.333348 -294.188968)
			(xy 195.37781 -294.210066) (xy 195.418313 -294.238022) (xy 195.453806 -294.272114) (xy 195.483371 -294.311458)
			(xy 195.506242 -294.355035) (xy 195.521826 -294.401716) (xy 195.529721 -294.450293) (xy 195.530216 -294.4749)
			(xy 195.869064 -294.4749) (xy 195.873024 -294.425846) (xy 195.884801 -294.378062) (xy 195.904092 -294.332786)
			(xy 195.930395 -294.29119) (xy 195.96303 -294.254353) (xy 196.001151 -294.223228) (xy 196.043772 -294.198621)
			(xy 196.089788 -294.181169) (xy 196.138007 -294.171325) (xy 196.187182 -294.169344) (xy 196.236037 -294.175276)
			(xy 196.283308 -294.188968) (xy 196.32777 -294.210066) (xy 196.368273 -294.238022) (xy 196.403766 -294.272114)
			(xy 196.433331 -294.311458) (xy 196.456202 -294.355035) (xy 196.471786 -294.401716) (xy 196.479681 -294.450293)
			(xy 196.480176 -294.4749) (xy 196.819278 -294.4749) (xy 196.823238 -294.425846) (xy 196.835015 -294.378062)
			(xy 196.854306 -294.332786) (xy 196.880609 -294.29119) (xy 196.913244 -294.254353) (xy 196.951365 -294.223228)
			(xy 196.993986 -294.198621) (xy 197.040002 -294.181169) (xy 197.088221 -294.171325) (xy 197.137396 -294.169344)
			(xy 197.186251 -294.175276) (xy 197.233522 -294.188968) (xy 197.277984 -294.210066) (xy 197.318487 -294.238022)
			(xy 197.35398 -294.272114) (xy 197.383545 -294.311458) (xy 197.406416 -294.355035) (xy 197.422 -294.401716)
			(xy 197.429895 -294.450293) (xy 197.43039 -294.4749) (xy 197.769238 -294.4749) (xy 197.773198 -294.425846)
			(xy 197.784975 -294.378062) (xy 197.804266 -294.332786) (xy 197.830569 -294.29119) (xy 197.863204 -294.254353)
			(xy 197.901325 -294.223228) (xy 197.943946 -294.198621) (xy 197.989962 -294.181169) (xy 198.038181 -294.171325)
			(xy 198.087356 -294.169344) (xy 198.136211 -294.175276) (xy 198.183482 -294.188968) (xy 198.227944 -294.210066)
			(xy 198.268447 -294.238022) (xy 198.30394 -294.272114) (xy 198.333505 -294.311458) (xy 198.356376 -294.355035)
			(xy 198.37196 -294.401716) (xy 198.379855 -294.450293) (xy 198.38035 -294.4749) (xy 198.719198 -294.4749)
			(xy 198.723158 -294.425846) (xy 198.734935 -294.378062) (xy 198.754226 -294.332786) (xy 198.780529 -294.29119)
			(xy 198.813164 -294.254353) (xy 198.851285 -294.223228) (xy 198.893906 -294.198621) (xy 198.939922 -294.181169)
			(xy 198.988141 -294.171325) (xy 199.037316 -294.169344) (xy 199.086171 -294.175276) (xy 199.133442 -294.188968)
			(xy 199.177904 -294.210066) (xy 199.218407 -294.238022) (xy 199.2539 -294.272114) (xy 199.283465 -294.311458)
			(xy 199.306336 -294.355035) (xy 199.32192 -294.401716) (xy 199.329815 -294.450293) (xy 199.33031 -294.4749)
			(xy 199.329815 -294.499507) (xy 199.32192 -294.548084) (xy 199.306336 -294.594765) (xy 199.283465 -294.638342)
			(xy 199.2539 -294.677686) (xy 199.220324 -294.709937) (xy 205.263126 -294.709937) (xy 205.263128 -294.655425)
			(xy 205.270889 -294.601469) (xy 205.28625 -294.549166) (xy 205.308898 -294.499582) (xy 205.338373 -294.453725)
			(xy 205.374074 -294.412531) (xy 205.415274 -294.376837) (xy 205.461135 -294.347369) (xy 205.510723 -294.324729)
			(xy 205.563028 -294.309376) (xy 205.616986 -294.301624) (xy 205.644242 -294.301164) (xy 205.669642 -294.301926)
			(xy 205.684375 -294.302413) (xy 205.713104 -294.29587) (xy 205.738771 -294.281399) (xy 205.759238 -294.260201)
			(xy 205.772802 -294.234043) (xy 205.778333 -294.205102) (xy 205.775372 -294.175786) (xy 205.770226 -294.161972)
			(xy 205.761062 -294.13877) (xy 205.748173 -294.090579) (xy 205.741674 -294.041119) (xy 205.74127 -294.016176)
			(xy 205.741804 -293.988927) (xy 205.749563 -293.934983) (xy 205.764921 -293.882692) (xy 205.787563 -293.83312)
			(xy 205.817031 -293.787274) (xy 205.852722 -293.746089) (xy 205.893912 -293.710402) (xy 205.939761 -293.680941)
			(xy 205.989337 -293.658304) (xy 206.041629 -293.642953) (xy 206.095574 -293.635201) (xy 206.150073 -293.635204)
			(xy 206.204017 -293.642963) (xy 206.256307 -293.65832) (xy 206.30588 -293.680963) (xy 206.351725 -293.71043)
			(xy 206.392911 -293.746122) (xy 206.428597 -293.787312) (xy 206.458059 -293.833161) (xy 206.480696 -293.882736)
			(xy 206.496047 -293.935028) (xy 206.502598 -293.980616) (xy 207.380838 -293.980616) (xy 207.384909 -293.924994)
			(xy 207.397035 -293.870557) (xy 207.416958 -293.818466) (xy 207.444254 -293.769831) (xy 207.47834 -293.725688)
			(xy 207.518489 -293.686979) (xy 207.563847 -293.654528) (xy 207.613447 -293.629027) (xy 207.666231 -293.61102)
			(xy 207.721074 -293.60089) (xy 207.776808 -293.598853) (xy 207.832245 -293.604953) (xy 207.886202 -293.619059)
			(xy 207.937531 -293.640871) (xy 207.985137 -293.669925) (xy 208.028005 -293.7056) (xy 208.065222 -293.747137)
			(xy 208.095995 -293.79365) (xy 208.119667 -293.844147) (xy 208.135735 -293.897554) (xy 208.143855 -293.95273)
			(xy 208.144364 -293.980616) (xy 208.143855 -294.008502) (xy 208.135735 -294.063678) (xy 208.119667 -294.117085)
			(xy 208.095995 -294.167582) (xy 208.065222 -294.214095) (xy 208.028005 -294.255632) (xy 207.985137 -294.291307)
			(xy 207.937531 -294.320361) (xy 207.886202 -294.342173) (xy 207.832245 -294.356279) (xy 207.776808 -294.362379)
			(xy 207.721074 -294.360342) (xy 207.666231 -294.350212) (xy 207.613447 -294.332205) (xy 207.563847 -294.306704)
			(xy 207.518489 -294.274253) (xy 207.47834 -294.235544) (xy 207.444254 -294.191401) (xy 207.416958 -294.142766)
			(xy 207.397035 -294.090675) (xy 207.384909 -294.036238) (xy 207.380838 -293.980616) (xy 206.502598 -293.980616)
			(xy 206.503799 -293.988973) (xy 206.503796 -294.043472) (xy 206.496037 -294.097416) (xy 206.48068 -294.149706)
			(xy 206.458037 -294.199279) (xy 206.42857 -294.245125) (xy 206.392878 -294.28631) (xy 206.351689 -294.321997)
			(xy 206.30584 -294.351459) (xy 206.256264 -294.374095) (xy 206.203972 -294.389446) (xy 206.150027 -294.397199)
			(xy 206.122778 -294.397684) (xy 206.097378 -294.396922) (xy 206.082647 -294.396524) (xy 206.05393 -294.403057)
			(xy 206.028272 -294.417516) (xy 206.00781 -294.438698) (xy 205.994245 -294.464839) (xy 205.988707 -294.493764)
			(xy 205.989493 -294.50157) (xy 206.636618 -294.50157) (xy 206.640689 -294.445948) (xy 206.652815 -294.391511)
			(xy 206.672738 -294.33942) (xy 206.700034 -294.290785) (xy 206.73412 -294.246642) (xy 206.774269 -294.207933)
			(xy 206.819627 -294.175482) (xy 206.869227 -294.149981) (xy 206.922011 -294.131974) (xy 206.976854 -294.121844)
			(xy 207.032588 -294.119807) (xy 207.088025 -294.125907) (xy 207.141982 -294.140013) (xy 207.193311 -294.161825)
			(xy 207.240917 -294.190879) (xy 207.283785 -294.226554) (xy 207.321002 -294.268091) (xy 207.351775 -294.314604)
			(xy 207.375447 -294.365101) (xy 207.391515 -294.418508) (xy 207.399635 -294.473684) (xy 207.400144 -294.50157)
			(xy 207.399635 -294.529456) (xy 207.391515 -294.584632) (xy 207.375447 -294.638039) (xy 207.351775 -294.688536)
			(xy 207.321002 -294.735049) (xy 207.283785 -294.776586) (xy 207.240917 -294.812261) (xy 207.193311 -294.841315)
			(xy 207.141982 -294.863127) (xy 207.088025 -294.877233) (xy 207.032588 -294.883333) (xy 206.976854 -294.881296)
			(xy 206.922011 -294.871166) (xy 206.869227 -294.853159) (xy 206.819627 -294.827658) (xy 206.774269 -294.795207)
			(xy 206.73412 -294.756498) (xy 206.700034 -294.712355) (xy 206.672738 -294.66372) (xy 206.652815 -294.611629)
			(xy 206.640689 -294.557192) (xy 206.636618 -294.50157) (xy 205.989493 -294.50157) (xy 205.991656 -294.523067)
			(xy 205.996794 -294.536876) (xy 206.005943 -294.560083) (xy 206.018838 -294.608272) (xy 206.025342 -294.65773)
			(xy 206.02575 -294.682672) (xy 206.025275 -294.709928) (xy 206.017521 -294.763886) (xy 206.002166 -294.81619)
			(xy 205.979524 -294.865777) (xy 205.950055 -294.911637) (xy 205.914359 -294.952836) (xy 205.873163 -294.988535)
			(xy 205.827306 -295.018008) (xy 205.777721 -295.040655) (xy 205.725418 -295.056014) (xy 205.671461 -295.063773)
			(xy 205.616949 -295.063773) (xy 205.562992 -295.056016) (xy 205.510688 -295.040658) (xy 205.461102 -295.018013)
			(xy 205.415244 -294.988541) (xy 205.374047 -294.952843) (xy 205.338351 -294.911645) (xy 205.30888 -294.865786)
			(xy 205.286237 -294.816199) (xy 205.270881 -294.763895) (xy 205.263126 -294.709937) (xy 199.220324 -294.709937)
			(xy 199.218407 -294.711778) (xy 199.177904 -294.739734) (xy 199.133442 -294.760832) (xy 199.086171 -294.774524)
			(xy 199.037316 -294.780456) (xy 198.988141 -294.778475) (xy 198.939922 -294.768631) (xy 198.893906 -294.751179)
			(xy 198.851285 -294.726572) (xy 198.813164 -294.695447) (xy 198.780529 -294.65861) (xy 198.754226 -294.617014)
			(xy 198.734935 -294.571738) (xy 198.723158 -294.523954) (xy 198.719198 -294.4749) (xy 198.38035 -294.4749)
			(xy 198.379855 -294.499507) (xy 198.37196 -294.548084) (xy 198.356376 -294.594765) (xy 198.333505 -294.638342)
			(xy 198.30394 -294.677686) (xy 198.268447 -294.711778) (xy 198.227944 -294.739734) (xy 198.183482 -294.760832)
			(xy 198.136211 -294.774524) (xy 198.087356 -294.780456) (xy 198.038181 -294.778475) (xy 197.989962 -294.768631)
			(xy 197.943946 -294.751179) (xy 197.901325 -294.726572) (xy 197.863204 -294.695447) (xy 197.830569 -294.65861)
			(xy 197.804266 -294.617014) (xy 197.784975 -294.571738) (xy 197.773198 -294.523954) (xy 197.769238 -294.4749)
			(xy 197.43039 -294.4749) (xy 197.429895 -294.499507) (xy 197.422 -294.548084) (xy 197.406416 -294.594765)
			(xy 197.383545 -294.638342) (xy 197.35398 -294.677686) (xy 197.318487 -294.711778) (xy 197.277984 -294.739734)
			(xy 197.233522 -294.760832) (xy 197.186251 -294.774524) (xy 197.137396 -294.780456) (xy 197.088221 -294.778475)
			(xy 197.040002 -294.768631) (xy 196.993986 -294.751179) (xy 196.951365 -294.726572) (xy 196.913244 -294.695447)
			(xy 196.880609 -294.65861) (xy 196.854306 -294.617014) (xy 196.835015 -294.571738) (xy 196.823238 -294.523954)
			(xy 196.819278 -294.4749) (xy 196.480176 -294.4749) (xy 196.479681 -294.499507) (xy 196.471786 -294.548084)
			(xy 196.456202 -294.594765) (xy 196.433331 -294.638342) (xy 196.403766 -294.677686) (xy 196.368273 -294.711778)
			(xy 196.32777 -294.739734) (xy 196.283308 -294.760832) (xy 196.236037 -294.774524) (xy 196.187182 -294.780456)
			(xy 196.138007 -294.778475) (xy 196.089788 -294.768631) (xy 196.043772 -294.751179) (xy 196.001151 -294.726572)
			(xy 195.96303 -294.695447) (xy 195.930395 -294.65861) (xy 195.904092 -294.617014) (xy 195.884801 -294.571738)
			(xy 195.873024 -294.523954) (xy 195.869064 -294.4749) (xy 195.530216 -294.4749) (xy 195.529721 -294.499507)
			(xy 195.521826 -294.548084) (xy 195.506242 -294.594765) (xy 195.483371 -294.638342) (xy 195.453806 -294.677686)
			(xy 195.418313 -294.711778) (xy 195.37781 -294.739734) (xy 195.333348 -294.760832) (xy 195.286077 -294.774524)
			(xy 195.237222 -294.780456) (xy 195.188047 -294.778475) (xy 195.139828 -294.768631) (xy 195.093812 -294.751179)
			(xy 195.051191 -294.726572) (xy 195.01307 -294.695447) (xy 194.980435 -294.65861) (xy 194.954132 -294.617014)
			(xy 194.934841 -294.571738) (xy 194.923064 -294.523954) (xy 194.919104 -294.4749) (xy 194.580256 -294.4749)
			(xy 194.579761 -294.499507) (xy 194.571866 -294.548084) (xy 194.556282 -294.594765) (xy 194.533411 -294.638342)
			(xy 194.503846 -294.677686) (xy 194.468353 -294.711778) (xy 194.42785 -294.739734) (xy 194.383388 -294.760832)
			(xy 194.336117 -294.774524) (xy 194.287262 -294.780456) (xy 194.238087 -294.778475) (xy 194.189868 -294.768631)
			(xy 194.143852 -294.751179) (xy 194.101231 -294.726572) (xy 194.06311 -294.695447) (xy 194.030475 -294.65861)
			(xy 194.004172 -294.617014) (xy 193.984881 -294.571738) (xy 193.973104 -294.523954) (xy 193.969144 -294.4749)
			(xy 192.680336 -294.4749) (xy 192.679841 -294.499507) (xy 192.671946 -294.548084) (xy 192.656362 -294.594765)
			(xy 192.633491 -294.638342) (xy 192.603926 -294.677686) (xy 192.568433 -294.711778) (xy 192.52793 -294.739734)
			(xy 192.483468 -294.760832) (xy 192.436197 -294.774524) (xy 192.387342 -294.780456) (xy 192.338167 -294.778475)
			(xy 192.289948 -294.768631) (xy 192.243932 -294.751179) (xy 192.201311 -294.726572) (xy 192.16319 -294.695447)
			(xy 192.130555 -294.65861) (xy 192.104252 -294.617014) (xy 192.084961 -294.571738) (xy 192.073184 -294.523954)
			(xy 192.069224 -294.4749) (xy 191.730376 -294.4749) (xy 191.729881 -294.499507) (xy 191.721986 -294.548084)
			(xy 191.706402 -294.594765) (xy 191.683531 -294.638342) (xy 191.653966 -294.677686) (xy 191.618473 -294.711778)
			(xy 191.57797 -294.739734) (xy 191.533508 -294.760832) (xy 191.486237 -294.774524) (xy 191.437382 -294.780456)
			(xy 191.388207 -294.778475) (xy 191.339988 -294.768631) (xy 191.293972 -294.751179) (xy 191.251351 -294.726572)
			(xy 191.21323 -294.695447) (xy 191.180595 -294.65861) (xy 191.154292 -294.617014) (xy 191.135001 -294.571738)
			(xy 191.123224 -294.523954) (xy 191.119264 -294.4749) (xy 190.780162 -294.4749) (xy 190.779667 -294.499507)
			(xy 190.771772 -294.548084) (xy 190.756188 -294.594765) (xy 190.733317 -294.638342) (xy 190.703752 -294.677686)
			(xy 190.668259 -294.711778) (xy 190.627756 -294.739734) (xy 190.583294 -294.760832) (xy 190.536023 -294.774524)
			(xy 190.487168 -294.780456) (xy 190.437993 -294.778475) (xy 190.389774 -294.768631) (xy 190.343758 -294.751179)
			(xy 190.301137 -294.726572) (xy 190.263016 -294.695447) (xy 190.230381 -294.65861) (xy 190.204078 -294.617014)
			(xy 190.184787 -294.571738) (xy 190.17301 -294.523954) (xy 190.16905 -294.4749) (xy 189.830202 -294.4749)
			(xy 189.829707 -294.499507) (xy 189.821812 -294.548084) (xy 189.806228 -294.594765) (xy 189.783357 -294.638342)
			(xy 189.753792 -294.677686) (xy 189.718299 -294.711778) (xy 189.677796 -294.739734) (xy 189.633334 -294.760832)
			(xy 189.586063 -294.774524) (xy 189.537208 -294.780456) (xy 189.488033 -294.778475) (xy 189.439814 -294.768631)
			(xy 189.393798 -294.751179) (xy 189.351177 -294.726572) (xy 189.313056 -294.695447) (xy 189.280421 -294.65861)
			(xy 189.254118 -294.617014) (xy 189.234827 -294.571738) (xy 189.22305 -294.523954) (xy 189.21909 -294.4749)
			(xy 188.880242 -294.4749) (xy 188.879747 -294.499507) (xy 188.871852 -294.548084) (xy 188.856268 -294.594765)
			(xy 188.833397 -294.638342) (xy 188.803832 -294.677686) (xy 188.768339 -294.711778) (xy 188.727836 -294.739734)
			(xy 188.683374 -294.760832) (xy 188.636103 -294.774524) (xy 188.587248 -294.780456) (xy 188.538073 -294.778475)
			(xy 188.489854 -294.768631) (xy 188.443838 -294.751179) (xy 188.401217 -294.726572) (xy 188.363096 -294.695447)
			(xy 188.330461 -294.65861) (xy 188.304158 -294.617014) (xy 188.284867 -294.571738) (xy 188.27309 -294.523954)
			(xy 188.26913 -294.4749) (xy 187.930282 -294.4749) (xy 187.929787 -294.499507) (xy 187.921892 -294.548084)
			(xy 187.906308 -294.594765) (xy 187.883437 -294.638342) (xy 187.853872 -294.677686) (xy 187.818379 -294.711778)
			(xy 187.777876 -294.739734) (xy 187.733414 -294.760832) (xy 187.686143 -294.774524) (xy 187.637288 -294.780456)
			(xy 187.588113 -294.778475) (xy 187.539894 -294.768631) (xy 187.493878 -294.751179) (xy 187.451257 -294.726572)
			(xy 187.413136 -294.695447) (xy 187.380501 -294.65861) (xy 187.354198 -294.617014) (xy 187.334907 -294.571738)
			(xy 187.32313 -294.523954) (xy 187.31917 -294.4749) (xy 186.030362 -294.4749) (xy 186.029867 -294.499507)
			(xy 186.021972 -294.548084) (xy 186.006388 -294.594765) (xy 185.983517 -294.638342) (xy 185.953952 -294.677686)
			(xy 185.918459 -294.711778) (xy 185.877956 -294.739734) (xy 185.833494 -294.760832) (xy 185.786223 -294.774524)
			(xy 185.737368 -294.780456) (xy 185.688193 -294.778475) (xy 185.639974 -294.768631) (xy 185.593958 -294.751179)
			(xy 185.551337 -294.726572) (xy 185.513216 -294.695447) (xy 185.480581 -294.65861) (xy 185.454278 -294.617014)
			(xy 185.434987 -294.571738) (xy 185.42321 -294.523954) (xy 185.41925 -294.4749) (xy 185.080148 -294.4749)
			(xy 185.079653 -294.499507) (xy 185.071758 -294.548084) (xy 185.056174 -294.594765) (xy 185.033303 -294.638342)
			(xy 185.003738 -294.677686) (xy 184.968245 -294.711778) (xy 184.927742 -294.739734) (xy 184.88328 -294.760832)
			(xy 184.836009 -294.774524) (xy 184.787154 -294.780456) (xy 184.737979 -294.778475) (xy 184.68976 -294.768631)
			(xy 184.643744 -294.751179) (xy 184.601123 -294.726572) (xy 184.563002 -294.695447) (xy 184.530367 -294.65861)
			(xy 184.504064 -294.617014) (xy 184.484773 -294.571738) (xy 184.472996 -294.523954) (xy 184.469036 -294.4749)
			(xy 184.130188 -294.4749) (xy 184.129693 -294.499507) (xy 184.121798 -294.548084) (xy 184.106214 -294.594765)
			(xy 184.083343 -294.638342) (xy 184.053778 -294.677686) (xy 184.018285 -294.711778) (xy 183.977782 -294.739734)
			(xy 183.93332 -294.760832) (xy 183.886049 -294.774524) (xy 183.837194 -294.780456) (xy 183.788019 -294.778475)
			(xy 183.7398 -294.768631) (xy 183.693784 -294.751179) (xy 183.651163 -294.726572) (xy 183.613042 -294.695447)
			(xy 183.580407 -294.65861) (xy 183.554104 -294.617014) (xy 183.534813 -294.571738) (xy 183.523036 -294.523954)
			(xy 183.519076 -294.4749) (xy 183.180228 -294.4749) (xy 183.179733 -294.499507) (xy 183.171838 -294.548084)
			(xy 183.156254 -294.594765) (xy 183.133383 -294.638342) (xy 183.103818 -294.677686) (xy 183.068325 -294.711778)
			(xy 183.027822 -294.739734) (xy 182.98336 -294.760832) (xy 182.936089 -294.774524) (xy 182.887234 -294.780456)
			(xy 182.838059 -294.778475) (xy 182.78984 -294.768631) (xy 182.743824 -294.751179) (xy 182.701203 -294.726572)
			(xy 182.663082 -294.695447) (xy 182.630447 -294.65861) (xy 182.604144 -294.617014) (xy 182.584853 -294.571738)
			(xy 182.573076 -294.523954) (xy 182.569116 -294.4749) (xy 182.230268 -294.4749) (xy 182.229773 -294.499507)
			(xy 182.221878 -294.548084) (xy 182.206294 -294.594765) (xy 182.183423 -294.638342) (xy 182.153858 -294.677686)
			(xy 182.118365 -294.711778) (xy 182.077862 -294.739734) (xy 182.0334 -294.760832) (xy 181.986129 -294.774524)
			(xy 181.937274 -294.780456) (xy 181.888099 -294.778475) (xy 181.83988 -294.768631) (xy 181.793864 -294.751179)
			(xy 181.751243 -294.726572) (xy 181.713122 -294.695447) (xy 181.680487 -294.65861) (xy 181.654184 -294.617014)
			(xy 181.634893 -294.571738) (xy 181.623116 -294.523954) (xy 181.619156 -294.4749) (xy 181.280308 -294.4749)
			(xy 181.279813 -294.499507) (xy 181.271918 -294.548084) (xy 181.256334 -294.594765) (xy 181.233463 -294.638342)
			(xy 181.203898 -294.677686) (xy 181.168405 -294.711778) (xy 181.127902 -294.739734) (xy 181.08344 -294.760832)
			(xy 181.036169 -294.774524) (xy 180.987314 -294.780456) (xy 180.938139 -294.778475) (xy 180.88992 -294.768631)
			(xy 180.843904 -294.751179) (xy 180.801283 -294.726572) (xy 180.763162 -294.695447) (xy 180.730527 -294.65861)
			(xy 180.704224 -294.617014) (xy 180.684933 -294.571738) (xy 180.673156 -294.523954) (xy 180.669196 -294.4749)
			(xy 180.330348 -294.4749) (xy 180.329853 -294.499507) (xy 180.321958 -294.548084) (xy 180.306374 -294.594765)
			(xy 180.283503 -294.638342) (xy 180.253938 -294.677686) (xy 180.218445 -294.711778) (xy 180.177942 -294.739734)
			(xy 180.13348 -294.760832) (xy 180.086209 -294.774524) (xy 180.037354 -294.780456) (xy 179.988179 -294.778475)
			(xy 179.93996 -294.768631) (xy 179.893944 -294.751179) (xy 179.851323 -294.726572) (xy 179.813202 -294.695447)
			(xy 179.780567 -294.65861) (xy 179.754264 -294.617014) (xy 179.734973 -294.571738) (xy 179.723196 -294.523954)
			(xy 179.719236 -294.4749) (xy 179.380388 -294.4749) (xy 179.379893 -294.499507) (xy 179.371998 -294.548084)
			(xy 179.356414 -294.594765) (xy 179.333543 -294.638342) (xy 179.303978 -294.677686) (xy 179.268485 -294.711778)
			(xy 179.227982 -294.739734) (xy 179.18352 -294.760832) (xy 179.136249 -294.774524) (xy 179.087394 -294.780456)
			(xy 179.038219 -294.778475) (xy 178.99 -294.768631) (xy 178.943984 -294.751179) (xy 178.901363 -294.726572)
			(xy 178.863242 -294.695447) (xy 178.830607 -294.65861) (xy 178.804304 -294.617014) (xy 178.785013 -294.571738)
			(xy 178.773236 -294.523954) (xy 178.769276 -294.4749) (xy 178.430174 -294.4749) (xy 178.429679 -294.499507)
			(xy 178.421784 -294.548084) (xy 178.4062 -294.594765) (xy 178.383329 -294.638342) (xy 178.353764 -294.677686)
			(xy 178.318271 -294.711778) (xy 178.277768 -294.739734) (xy 178.233306 -294.760832) (xy 178.186035 -294.774524)
			(xy 178.13718 -294.780456) (xy 178.088005 -294.778475) (xy 178.039786 -294.768631) (xy 177.99377 -294.751179)
			(xy 177.951149 -294.726572) (xy 177.913028 -294.695447) (xy 177.880393 -294.65861) (xy 177.85409 -294.617014)
			(xy 177.834799 -294.571738) (xy 177.823022 -294.523954) (xy 177.819062 -294.4749) (xy 177.480214 -294.4749)
			(xy 177.479719 -294.499507) (xy 177.471824 -294.548084) (xy 177.45624 -294.594765) (xy 177.433369 -294.638342)
			(xy 177.403804 -294.677686) (xy 177.368311 -294.711778) (xy 177.327808 -294.739734) (xy 177.283346 -294.760832)
			(xy 177.236075 -294.774524) (xy 177.18722 -294.780456) (xy 177.138045 -294.778475) (xy 177.089826 -294.768631)
			(xy 177.04381 -294.751179) (xy 177.001189 -294.726572) (xy 176.963068 -294.695447) (xy 176.930433 -294.65861)
			(xy 176.90413 -294.617014) (xy 176.884839 -294.571738) (xy 176.873062 -294.523954) (xy 176.869102 -294.4749)
			(xy 176.530254 -294.4749) (xy 176.529759 -294.499507) (xy 176.521864 -294.548084) (xy 176.50628 -294.594765)
			(xy 176.483409 -294.638342) (xy 176.453844 -294.677686) (xy 176.418351 -294.711778) (xy 176.377848 -294.739734)
			(xy 176.333386 -294.760832) (xy 176.286115 -294.774524) (xy 176.23726 -294.780456) (xy 176.188085 -294.778475)
			(xy 176.139866 -294.768631) (xy 176.09385 -294.751179) (xy 176.051229 -294.726572) (xy 176.013108 -294.695447)
			(xy 175.980473 -294.65861) (xy 175.95417 -294.617014) (xy 175.934879 -294.571738) (xy 175.923102 -294.523954)
			(xy 175.919142 -294.4749) (xy 174.630334 -294.4749) (xy 174.629839 -294.499507) (xy 174.621944 -294.548084)
			(xy 174.60636 -294.594765) (xy 174.583489 -294.638342) (xy 174.553924 -294.677686) (xy 174.518431 -294.711778)
			(xy 174.477928 -294.739734) (xy 174.433466 -294.760832) (xy 174.386195 -294.774524) (xy 174.33734 -294.780456)
			(xy 174.288165 -294.778475) (xy 174.239946 -294.768631) (xy 174.19393 -294.751179) (xy 174.151309 -294.726572)
			(xy 174.113188 -294.695447) (xy 174.080553 -294.65861) (xy 174.05425 -294.617014) (xy 174.034959 -294.571738)
			(xy 174.023182 -294.523954) (xy 174.019222 -294.4749) (xy 173.680374 -294.4749) (xy 173.679879 -294.499507)
			(xy 173.671984 -294.548084) (xy 173.6564 -294.594765) (xy 173.633529 -294.638342) (xy 173.603964 -294.677686)
			(xy 173.568471 -294.711778) (xy 173.527968 -294.739734) (xy 173.483506 -294.760832) (xy 173.436235 -294.774524)
			(xy 173.38738 -294.780456) (xy 173.338205 -294.778475) (xy 173.289986 -294.768631) (xy 173.24397 -294.751179)
			(xy 173.201349 -294.726572) (xy 173.163228 -294.695447) (xy 173.130593 -294.65861) (xy 173.10429 -294.617014)
			(xy 173.084999 -294.571738) (xy 173.073222 -294.523954) (xy 173.069262 -294.4749) (xy 172.73016 -294.4749)
			(xy 172.729665 -294.499507) (xy 172.72177 -294.548084) (xy 172.706186 -294.594765) (xy 172.683315 -294.638342)
			(xy 172.65375 -294.677686) (xy 172.618257 -294.711778) (xy 172.577754 -294.739734) (xy 172.533292 -294.760832)
			(xy 172.486021 -294.774524) (xy 172.437166 -294.780456) (xy 172.387991 -294.778475) (xy 172.339772 -294.768631)
			(xy 172.293756 -294.751179) (xy 172.251135 -294.726572) (xy 172.213014 -294.695447) (xy 172.180379 -294.65861)
			(xy 172.154076 -294.617014) (xy 172.134785 -294.571738) (xy 172.123008 -294.523954) (xy 172.119048 -294.4749)
			(xy 171.7802 -294.4749) (xy 171.779705 -294.499507) (xy 171.77181 -294.548084) (xy 171.756226 -294.594765)
			(xy 171.733355 -294.638342) (xy 171.70379 -294.677686) (xy 171.668297 -294.711778) (xy 171.627794 -294.739734)
			(xy 171.583332 -294.760832) (xy 171.536061 -294.774524) (xy 171.487206 -294.780456) (xy 171.438031 -294.778475)
			(xy 171.389812 -294.768631) (xy 171.343796 -294.751179) (xy 171.301175 -294.726572) (xy 171.263054 -294.695447)
			(xy 171.230419 -294.65861) (xy 171.204116 -294.617014) (xy 171.184825 -294.571738) (xy 171.173048 -294.523954)
			(xy 171.169088 -294.4749) (xy 170.83024 -294.4749) (xy 170.829745 -294.499507) (xy 170.82185 -294.548084)
			(xy 170.806266 -294.594765) (xy 170.783395 -294.638342) (xy 170.75383 -294.677686) (xy 170.718337 -294.711778)
			(xy 170.677834 -294.739734) (xy 170.633372 -294.760832) (xy 170.586101 -294.774524) (xy 170.537246 -294.780456)
			(xy 170.488071 -294.778475) (xy 170.439852 -294.768631) (xy 170.393836 -294.751179) (xy 170.351215 -294.726572)
			(xy 170.313094 -294.695447) (xy 170.280459 -294.65861) (xy 170.254156 -294.617014) (xy 170.234865 -294.571738)
			(xy 170.223088 -294.523954) (xy 170.219128 -294.4749) (xy 169.88028 -294.4749) (xy 169.879785 -294.499507)
			(xy 169.87189 -294.548084) (xy 169.856306 -294.594765) (xy 169.833435 -294.638342) (xy 169.80387 -294.677686)
			(xy 169.768377 -294.711778) (xy 169.727874 -294.739734) (xy 169.683412 -294.760832) (xy 169.636141 -294.774524)
			(xy 169.587286 -294.780456) (xy 169.538111 -294.778475) (xy 169.489892 -294.768631) (xy 169.443876 -294.751179)
			(xy 169.401255 -294.726572) (xy 169.363134 -294.695447) (xy 169.330499 -294.65861) (xy 169.304196 -294.617014)
			(xy 169.284905 -294.571738) (xy 169.273128 -294.523954) (xy 169.269168 -294.4749) (xy 168.93032 -294.4749)
			(xy 168.929825 -294.499507) (xy 168.92193 -294.548084) (xy 168.906346 -294.594765) (xy 168.883475 -294.638342)
			(xy 168.85391 -294.677686) (xy 168.818417 -294.711778) (xy 168.777914 -294.739734) (xy 168.733452 -294.760832)
			(xy 168.686181 -294.774524) (xy 168.637326 -294.780456) (xy 168.588151 -294.778475) (xy 168.539932 -294.768631)
			(xy 168.493916 -294.751179) (xy 168.451295 -294.726572) (xy 168.413174 -294.695447) (xy 168.380539 -294.65861)
			(xy 168.354236 -294.617014) (xy 168.334945 -294.571738) (xy 168.323168 -294.523954) (xy 168.319208 -294.4749)
			(xy 167.98036 -294.4749) (xy 167.979865 -294.499507) (xy 167.97197 -294.548084) (xy 167.956386 -294.594765)
			(xy 167.933515 -294.638342) (xy 167.90395 -294.677686) (xy 167.868457 -294.711778) (xy 167.827954 -294.739734)
			(xy 167.783492 -294.760832) (xy 167.736221 -294.774524) (xy 167.687366 -294.780456) (xy 167.638191 -294.778475)
			(xy 167.589972 -294.768631) (xy 167.543956 -294.751179) (xy 167.501335 -294.726572) (xy 167.463214 -294.695447)
			(xy 167.430579 -294.65861) (xy 167.404276 -294.617014) (xy 167.384985 -294.571738) (xy 167.373208 -294.523954)
			(xy 167.369248 -294.4749) (xy 167.0304 -294.4749) (xy 167.029905 -294.499507) (xy 167.02201 -294.548084)
			(xy 167.006426 -294.594765) (xy 166.983555 -294.638342) (xy 166.95399 -294.677686) (xy 166.918497 -294.711778)
			(xy 166.877994 -294.739734) (xy 166.833532 -294.760832) (xy 166.786261 -294.774524) (xy 166.737406 -294.780456)
			(xy 166.688231 -294.778475) (xy 166.640012 -294.768631) (xy 166.593996 -294.751179) (xy 166.551375 -294.726572)
			(xy 166.513254 -294.695447) (xy 166.480619 -294.65861) (xy 166.454316 -294.617014) (xy 166.435025 -294.571738)
			(xy 166.423248 -294.523954) (xy 166.419288 -294.4749) (xy 166.080186 -294.4749) (xy 166.079691 -294.499507)
			(xy 166.071796 -294.548084) (xy 166.056212 -294.594765) (xy 166.033341 -294.638342) (xy 166.003776 -294.677686)
			(xy 165.968283 -294.711778) (xy 165.92778 -294.739734) (xy 165.883318 -294.760832) (xy 165.836047 -294.774524)
			(xy 165.787192 -294.780456) (xy 165.738017 -294.778475) (xy 165.689798 -294.768631) (xy 165.643782 -294.751179)
			(xy 165.601161 -294.726572) (xy 165.56304 -294.695447) (xy 165.530405 -294.65861) (xy 165.504102 -294.617014)
			(xy 165.484811 -294.571738) (xy 165.473034 -294.523954) (xy 165.469074 -294.4749) (xy 165.155084 -294.4749)
			(xy 165.155084 -294.501282) (xy 165.146706 -294.553375) (xy 165.130162 -294.603478) (xy 165.105873 -294.650318)
			(xy 165.074454 -294.692707) (xy 165.036704 -294.729569) (xy 164.993579 -294.75997) (xy 164.946174 -294.783137)
			(xy 164.895692 -294.798483) (xy 164.869622 -294.80256) (xy 164.86505 -294.803322) (xy 164.852858 -294.807132)
			(xy 164.849556 -294.808148) (xy 164.826188 -294.81907) (xy 164.819584 -294.826182) (xy 164.804852 -294.841676)
			(xy 164.796724 -294.852852) (xy 164.794024 -294.858382) (xy 164.791061 -294.870323) (xy 164.790882 -294.876474)
			(xy 164.790882 -295.355518) (xy 208.715862 -295.355518) (xy 208.719933 -295.299896) (xy 208.732059 -295.245459)
			(xy 208.751982 -295.193368) (xy 208.779278 -295.144733) (xy 208.813364 -295.10059) (xy 208.853513 -295.061881)
			(xy 208.898871 -295.02943) (xy 208.948471 -295.003929) (xy 209.001255 -294.985922) (xy 209.056098 -294.975792)
			(xy 209.111832 -294.973755) (xy 209.167269 -294.979855) (xy 209.221226 -294.993961) (xy 209.272555 -295.015773)
			(xy 209.320161 -295.044827) (xy 209.363029 -295.080502) (xy 209.400246 -295.122039) (xy 209.431019 -295.168552)
			(xy 209.454691 -295.219049) (xy 209.470759 -295.272456) (xy 209.478879 -295.327632) (xy 209.479388 -295.355518)
			(xy 209.478879 -295.383404) (xy 209.470759 -295.43858) (xy 209.454691 -295.491987) (xy 209.431019 -295.542484)
			(xy 209.400246 -295.588997) (xy 209.363029 -295.630534) (xy 209.320161 -295.666209) (xy 209.272555 -295.695263)
			(xy 209.221226 -295.717075) (xy 209.167269 -295.731181) (xy 209.111832 -295.737281) (xy 209.056098 -295.735244)
			(xy 209.001255 -295.725114) (xy 208.948471 -295.707107) (xy 208.898871 -295.681606) (xy 208.853513 -295.649155)
			(xy 208.813364 -295.610446) (xy 208.779278 -295.566303) (xy 208.751982 -295.517668) (xy 208.732059 -295.465577)
			(xy 208.719933 -295.41114) (xy 208.715862 -295.355518) (xy 164.790882 -295.355518) (xy 164.790882 -295.973246)
			(xy 164.791354 -295.982877) (xy 164.79854 -296.000754) (xy 164.804852 -296.008044) (xy 164.820092 -296.024046)
			(xy 164.82695 -296.031412) (xy 164.850318 -296.041826) (xy 164.854636 -296.043096) (xy 164.86505 -296.046398)
			(xy 164.869622 -296.04716) (xy 164.89569 -296.051237) (xy 164.946169 -296.066583) (xy 164.993571 -296.089749)
			(xy 165.036693 -296.120148) (xy 165.074441 -296.157008) (xy 165.105858 -296.199395) (xy 165.130145 -296.246232)
			(xy 165.146687 -296.296332) (xy 165.155064 -296.348423) (xy 165.155064 -296.37482) (xy 165.469074 -296.37482)
			(xy 165.473034 -296.325766) (xy 165.484811 -296.277982) (xy 165.504102 -296.232706) (xy 165.530405 -296.19111)
			(xy 165.56304 -296.154273) (xy 165.601161 -296.123148) (xy 165.643782 -296.098541) (xy 165.689798 -296.081089)
			(xy 165.738017 -296.071245) (xy 165.787192 -296.069264) (xy 165.836047 -296.075196) (xy 165.883318 -296.088888)
			(xy 165.92778 -296.109986) (xy 165.968283 -296.137942) (xy 166.003776 -296.172034) (xy 166.033341 -296.211378)
			(xy 166.056212 -296.254955) (xy 166.071796 -296.301636) (xy 166.079691 -296.350213) (xy 166.080186 -296.37482)
			(xy 166.419288 -296.37482) (xy 166.423248 -296.325766) (xy 166.435025 -296.277982) (xy 166.454316 -296.232706)
			(xy 166.480619 -296.19111) (xy 166.513254 -296.154273) (xy 166.551375 -296.123148) (xy 166.593996 -296.098541)
			(xy 166.640012 -296.081089) (xy 166.688231 -296.071245) (xy 166.737406 -296.069264) (xy 166.786261 -296.075196)
			(xy 166.833532 -296.088888) (xy 166.877994 -296.109986) (xy 166.918497 -296.137942) (xy 166.95399 -296.172034)
			(xy 166.983555 -296.211378) (xy 167.006426 -296.254955) (xy 167.02201 -296.301636) (xy 167.029905 -296.350213)
			(xy 167.0304 -296.37482) (xy 167.369248 -296.37482) (xy 167.373208 -296.325766) (xy 167.384985 -296.277982)
			(xy 167.404276 -296.232706) (xy 167.430579 -296.19111) (xy 167.463214 -296.154273) (xy 167.501335 -296.123148)
			(xy 167.543956 -296.098541) (xy 167.589972 -296.081089) (xy 167.638191 -296.071245) (xy 167.687366 -296.069264)
			(xy 167.736221 -296.075196) (xy 167.783492 -296.088888) (xy 167.827954 -296.109986) (xy 167.868457 -296.137942)
			(xy 167.90395 -296.172034) (xy 167.933515 -296.211378) (xy 167.956386 -296.254955) (xy 167.97197 -296.301636)
			(xy 167.979865 -296.350213) (xy 167.98036 -296.37482) (xy 168.319208 -296.37482) (xy 168.323168 -296.325766)
			(xy 168.334945 -296.277982) (xy 168.354236 -296.232706) (xy 168.380539 -296.19111) (xy 168.413174 -296.154273)
			(xy 168.451295 -296.123148) (xy 168.493916 -296.098541) (xy 168.539932 -296.081089) (xy 168.588151 -296.071245)
			(xy 168.637326 -296.069264) (xy 168.686181 -296.075196) (xy 168.733452 -296.088888) (xy 168.777914 -296.109986)
			(xy 168.818417 -296.137942) (xy 168.85391 -296.172034) (xy 168.883475 -296.211378) (xy 168.906346 -296.254955)
			(xy 168.92193 -296.301636) (xy 168.929825 -296.350213) (xy 168.93032 -296.37482) (xy 169.269168 -296.37482)
			(xy 169.273128 -296.325766) (xy 169.284905 -296.277982) (xy 169.304196 -296.232706) (xy 169.330499 -296.19111)
			(xy 169.363134 -296.154273) (xy 169.401255 -296.123148) (xy 169.443876 -296.098541) (xy 169.489892 -296.081089)
			(xy 169.538111 -296.071245) (xy 169.587286 -296.069264) (xy 169.636141 -296.075196) (xy 169.683412 -296.088888)
			(xy 169.727874 -296.109986) (xy 169.768377 -296.137942) (xy 169.80387 -296.172034) (xy 169.833435 -296.211378)
			(xy 169.856306 -296.254955) (xy 169.87189 -296.301636) (xy 169.879785 -296.350213) (xy 169.88028 -296.37482)
			(xy 170.219128 -296.37482) (xy 170.223088 -296.325766) (xy 170.234865 -296.277982) (xy 170.254156 -296.232706)
			(xy 170.280459 -296.19111) (xy 170.313094 -296.154273) (xy 170.351215 -296.123148) (xy 170.393836 -296.098541)
			(xy 170.439852 -296.081089) (xy 170.488071 -296.071245) (xy 170.537246 -296.069264) (xy 170.586101 -296.075196)
			(xy 170.633372 -296.088888) (xy 170.677834 -296.109986) (xy 170.718337 -296.137942) (xy 170.75383 -296.172034)
			(xy 170.783395 -296.211378) (xy 170.806266 -296.254955) (xy 170.82185 -296.301636) (xy 170.829745 -296.350213)
			(xy 170.83024 -296.37482) (xy 171.169088 -296.37482) (xy 171.173048 -296.325766) (xy 171.184825 -296.277982)
			(xy 171.204116 -296.232706) (xy 171.230419 -296.19111) (xy 171.263054 -296.154273) (xy 171.301175 -296.123148)
			(xy 171.343796 -296.098541) (xy 171.389812 -296.081089) (xy 171.438031 -296.071245) (xy 171.487206 -296.069264)
			(xy 171.536061 -296.075196) (xy 171.583332 -296.088888) (xy 171.627794 -296.109986) (xy 171.668297 -296.137942)
			(xy 171.70379 -296.172034) (xy 171.733355 -296.211378) (xy 171.756226 -296.254955) (xy 171.77181 -296.301636)
			(xy 171.779705 -296.350213) (xy 171.7802 -296.37482) (xy 172.119302 -296.37482) (xy 172.123262 -296.325766)
			(xy 172.135039 -296.277982) (xy 172.15433 -296.232706) (xy 172.180633 -296.19111) (xy 172.213268 -296.154273)
			(xy 172.251389 -296.123148) (xy 172.29401 -296.098541) (xy 172.340026 -296.081089) (xy 172.388245 -296.071245)
			(xy 172.43742 -296.069264) (xy 172.486275 -296.075196) (xy 172.533546 -296.088888) (xy 172.578008 -296.109986)
			(xy 172.618511 -296.137942) (xy 172.654004 -296.172034) (xy 172.683569 -296.211378) (xy 172.70644 -296.254955)
			(xy 172.722024 -296.301636) (xy 172.729919 -296.350213) (xy 172.730414 -296.37482) (xy 173.069262 -296.37482)
			(xy 173.073222 -296.325766) (xy 173.084999 -296.277982) (xy 173.10429 -296.232706) (xy 173.130593 -296.19111)
			(xy 173.163228 -296.154273) (xy 173.201349 -296.123148) (xy 173.24397 -296.098541) (xy 173.289986 -296.081089)
			(xy 173.338205 -296.071245) (xy 173.38738 -296.069264) (xy 173.436235 -296.075196) (xy 173.483506 -296.088888)
			(xy 173.527968 -296.109986) (xy 173.568471 -296.137942) (xy 173.603964 -296.172034) (xy 173.633529 -296.211378)
			(xy 173.6564 -296.254955) (xy 173.671984 -296.301636) (xy 173.679879 -296.350213) (xy 173.680374 -296.37482)
			(xy 174.019222 -296.37482) (xy 174.023182 -296.325766) (xy 174.034959 -296.277982) (xy 174.05425 -296.232706)
			(xy 174.080553 -296.19111) (xy 174.113188 -296.154273) (xy 174.151309 -296.123148) (xy 174.19393 -296.098541)
			(xy 174.239946 -296.081089) (xy 174.288165 -296.071245) (xy 174.33734 -296.069264) (xy 174.386195 -296.075196)
			(xy 174.433466 -296.088888) (xy 174.477928 -296.109986) (xy 174.518431 -296.137942) (xy 174.553924 -296.172034)
			(xy 174.583489 -296.211378) (xy 174.60636 -296.254955) (xy 174.621944 -296.301636) (xy 174.629839 -296.350213)
			(xy 174.630334 -296.37482) (xy 175.919142 -296.37482) (xy 175.923102 -296.325766) (xy 175.934879 -296.277982)
			(xy 175.95417 -296.232706) (xy 175.980473 -296.19111) (xy 176.013108 -296.154273) (xy 176.051229 -296.123148)
			(xy 176.09385 -296.098541) (xy 176.139866 -296.081089) (xy 176.188085 -296.071245) (xy 176.23726 -296.069264)
			(xy 176.286115 -296.075196) (xy 176.333386 -296.088888) (xy 176.377848 -296.109986) (xy 176.418351 -296.137942)
			(xy 176.453844 -296.172034) (xy 176.483409 -296.211378) (xy 176.50628 -296.254955) (xy 176.521864 -296.301636)
			(xy 176.529759 -296.350213) (xy 176.530254 -296.37482) (xy 176.869102 -296.37482) (xy 176.873062 -296.325766)
			(xy 176.884839 -296.277982) (xy 176.90413 -296.232706) (xy 176.930433 -296.19111) (xy 176.963068 -296.154273)
			(xy 177.001189 -296.123148) (xy 177.04381 -296.098541) (xy 177.089826 -296.081089) (xy 177.138045 -296.071245)
			(xy 177.18722 -296.069264) (xy 177.236075 -296.075196) (xy 177.283346 -296.088888) (xy 177.327808 -296.109986)
			(xy 177.368311 -296.137942) (xy 177.403804 -296.172034) (xy 177.433369 -296.211378) (xy 177.45624 -296.254955)
			(xy 177.471824 -296.301636) (xy 177.479719 -296.350213) (xy 177.480214 -296.37482) (xy 177.819062 -296.37482)
			(xy 177.823022 -296.325766) (xy 177.834799 -296.277982) (xy 177.85409 -296.232706) (xy 177.880393 -296.19111)
			(xy 177.913028 -296.154273) (xy 177.951149 -296.123148) (xy 177.99377 -296.098541) (xy 178.039786 -296.081089)
			(xy 178.088005 -296.071245) (xy 178.13718 -296.069264) (xy 178.186035 -296.075196) (xy 178.233306 -296.088888)
			(xy 178.277768 -296.109986) (xy 178.318271 -296.137942) (xy 178.353764 -296.172034) (xy 178.383329 -296.211378)
			(xy 178.4062 -296.254955) (xy 178.421784 -296.301636) (xy 178.429679 -296.350213) (xy 178.430174 -296.37482)
			(xy 178.769276 -296.37482) (xy 178.773236 -296.325766) (xy 178.785013 -296.277982) (xy 178.804304 -296.232706)
			(xy 178.830607 -296.19111) (xy 178.863242 -296.154273) (xy 178.901363 -296.123148) (xy 178.943984 -296.098541)
			(xy 178.99 -296.081089) (xy 179.038219 -296.071245) (xy 179.087394 -296.069264) (xy 179.136249 -296.075196)
			(xy 179.18352 -296.088888) (xy 179.227982 -296.109986) (xy 179.268485 -296.137942) (xy 179.303978 -296.172034)
			(xy 179.333543 -296.211378) (xy 179.356414 -296.254955) (xy 179.371998 -296.301636) (xy 179.379893 -296.350213)
			(xy 179.380388 -296.37482) (xy 179.719236 -296.37482) (xy 179.723196 -296.325766) (xy 179.734973 -296.277982)
			(xy 179.754264 -296.232706) (xy 179.780567 -296.19111) (xy 179.813202 -296.154273) (xy 179.851323 -296.123148)
			(xy 179.893944 -296.098541) (xy 179.93996 -296.081089) (xy 179.988179 -296.071245) (xy 180.037354 -296.069264)
			(xy 180.086209 -296.075196) (xy 180.13348 -296.088888) (xy 180.177942 -296.109986) (xy 180.218445 -296.137942)
			(xy 180.253938 -296.172034) (xy 180.283503 -296.211378) (xy 180.306374 -296.254955) (xy 180.321958 -296.301636)
			(xy 180.329853 -296.350213) (xy 180.330348 -296.37482) (xy 180.669196 -296.37482) (xy 180.673156 -296.325766)
			(xy 180.684933 -296.277982) (xy 180.704224 -296.232706) (xy 180.730527 -296.19111) (xy 180.763162 -296.154273)
			(xy 180.801283 -296.123148) (xy 180.843904 -296.098541) (xy 180.88992 -296.081089) (xy 180.938139 -296.071245)
			(xy 180.987314 -296.069264) (xy 181.036169 -296.075196) (xy 181.08344 -296.088888) (xy 181.127902 -296.109986)
			(xy 181.168405 -296.137942) (xy 181.203898 -296.172034) (xy 181.233463 -296.211378) (xy 181.256334 -296.254955)
			(xy 181.271918 -296.301636) (xy 181.279813 -296.350213) (xy 181.280308 -296.37482) (xy 181.619156 -296.37482)
			(xy 181.623116 -296.325766) (xy 181.634893 -296.277982) (xy 181.654184 -296.232706) (xy 181.680487 -296.19111)
			(xy 181.713122 -296.154273) (xy 181.751243 -296.123148) (xy 181.793864 -296.098541) (xy 181.83988 -296.081089)
			(xy 181.888099 -296.071245) (xy 181.937274 -296.069264) (xy 181.986129 -296.075196) (xy 182.0334 -296.088888)
			(xy 182.077862 -296.109986) (xy 182.118365 -296.137942) (xy 182.153858 -296.172034) (xy 182.183423 -296.211378)
			(xy 182.206294 -296.254955) (xy 182.221878 -296.301636) (xy 182.229773 -296.350213) (xy 182.230268 -296.37482)
			(xy 182.569116 -296.37482) (xy 182.573076 -296.325766) (xy 182.584853 -296.277982) (xy 182.604144 -296.232706)
			(xy 182.630447 -296.19111) (xy 182.663082 -296.154273) (xy 182.701203 -296.123148) (xy 182.743824 -296.098541)
			(xy 182.78984 -296.081089) (xy 182.838059 -296.071245) (xy 182.887234 -296.069264) (xy 182.936089 -296.075196)
			(xy 182.98336 -296.088888) (xy 183.027822 -296.109986) (xy 183.068325 -296.137942) (xy 183.103818 -296.172034)
			(xy 183.133383 -296.211378) (xy 183.156254 -296.254955) (xy 183.171838 -296.301636) (xy 183.179733 -296.350213)
			(xy 183.180228 -296.37482) (xy 183.519076 -296.37482) (xy 183.523036 -296.325766) (xy 183.534813 -296.277982)
			(xy 183.554104 -296.232706) (xy 183.580407 -296.19111) (xy 183.613042 -296.154273) (xy 183.651163 -296.123148)
			(xy 183.693784 -296.098541) (xy 183.7398 -296.081089) (xy 183.788019 -296.071245) (xy 183.837194 -296.069264)
			(xy 183.886049 -296.075196) (xy 183.93332 -296.088888) (xy 183.977782 -296.109986) (xy 184.018285 -296.137942)
			(xy 184.053778 -296.172034) (xy 184.083343 -296.211378) (xy 184.106214 -296.254955) (xy 184.121798 -296.301636)
			(xy 184.129693 -296.350213) (xy 184.130188 -296.37482) (xy 184.469036 -296.37482) (xy 184.472996 -296.325766)
			(xy 184.484773 -296.277982) (xy 184.504064 -296.232706) (xy 184.530367 -296.19111) (xy 184.563002 -296.154273)
			(xy 184.601123 -296.123148) (xy 184.643744 -296.098541) (xy 184.68976 -296.081089) (xy 184.737979 -296.071245)
			(xy 184.787154 -296.069264) (xy 184.836009 -296.075196) (xy 184.88328 -296.088888) (xy 184.927742 -296.109986)
			(xy 184.968245 -296.137942) (xy 185.003738 -296.172034) (xy 185.033303 -296.211378) (xy 185.056174 -296.254955)
			(xy 185.071758 -296.301636) (xy 185.079653 -296.350213) (xy 185.080148 -296.37482) (xy 185.41925 -296.37482)
			(xy 185.42321 -296.325766) (xy 185.434987 -296.277982) (xy 185.454278 -296.232706) (xy 185.480581 -296.19111)
			(xy 185.513216 -296.154273) (xy 185.551337 -296.123148) (xy 185.593958 -296.098541) (xy 185.639974 -296.081089)
			(xy 185.688193 -296.071245) (xy 185.737368 -296.069264) (xy 185.786223 -296.075196) (xy 185.833494 -296.088888)
			(xy 185.877956 -296.109986) (xy 185.918459 -296.137942) (xy 185.953952 -296.172034) (xy 185.983517 -296.211378)
			(xy 186.006388 -296.254955) (xy 186.021972 -296.301636) (xy 186.029867 -296.350213) (xy 186.030362 -296.37482)
			(xy 187.31917 -296.37482) (xy 187.32313 -296.325766) (xy 187.334907 -296.277982) (xy 187.354198 -296.232706)
			(xy 187.380501 -296.19111) (xy 187.413136 -296.154273) (xy 187.451257 -296.123148) (xy 187.493878 -296.098541)
			(xy 187.539894 -296.081089) (xy 187.588113 -296.071245) (xy 187.637288 -296.069264) (xy 187.686143 -296.075196)
			(xy 187.733414 -296.088888) (xy 187.777876 -296.109986) (xy 187.818379 -296.137942) (xy 187.853872 -296.172034)
			(xy 187.883437 -296.211378) (xy 187.906308 -296.254955) (xy 187.921892 -296.301636) (xy 187.929787 -296.350213)
			(xy 187.930282 -296.37482) (xy 188.26913 -296.37482) (xy 188.27309 -296.325766) (xy 188.284867 -296.277982)
			(xy 188.304158 -296.232706) (xy 188.330461 -296.19111) (xy 188.363096 -296.154273) (xy 188.401217 -296.123148)
			(xy 188.443838 -296.098541) (xy 188.489854 -296.081089) (xy 188.538073 -296.071245) (xy 188.587248 -296.069264)
			(xy 188.636103 -296.075196) (xy 188.683374 -296.088888) (xy 188.727836 -296.109986) (xy 188.768339 -296.137942)
			(xy 188.803832 -296.172034) (xy 188.833397 -296.211378) (xy 188.856268 -296.254955) (xy 188.871852 -296.301636)
			(xy 188.879747 -296.350213) (xy 188.880242 -296.37482) (xy 189.21909 -296.37482) (xy 189.22305 -296.325766)
			(xy 189.234827 -296.277982) (xy 189.254118 -296.232706) (xy 189.280421 -296.19111) (xy 189.313056 -296.154273)
			(xy 189.351177 -296.123148) (xy 189.393798 -296.098541) (xy 189.439814 -296.081089) (xy 189.488033 -296.071245)
			(xy 189.537208 -296.069264) (xy 189.586063 -296.075196) (xy 189.633334 -296.088888) (xy 189.677796 -296.109986)
			(xy 189.718299 -296.137942) (xy 189.753792 -296.172034) (xy 189.783357 -296.211378) (xy 189.806228 -296.254955)
			(xy 189.821812 -296.301636) (xy 189.829707 -296.350213) (xy 189.830202 -296.37482) (xy 190.16905 -296.37482)
			(xy 190.17301 -296.325766) (xy 190.184787 -296.277982) (xy 190.204078 -296.232706) (xy 190.230381 -296.19111)
			(xy 190.263016 -296.154273) (xy 190.301137 -296.123148) (xy 190.343758 -296.098541) (xy 190.389774 -296.081089)
			(xy 190.437993 -296.071245) (xy 190.487168 -296.069264) (xy 190.536023 -296.075196) (xy 190.583294 -296.088888)
			(xy 190.627756 -296.109986) (xy 190.668259 -296.137942) (xy 190.703752 -296.172034) (xy 190.733317 -296.211378)
			(xy 190.756188 -296.254955) (xy 190.771772 -296.301636) (xy 190.779667 -296.350213) (xy 190.780162 -296.37482)
			(xy 191.119264 -296.37482) (xy 191.123224 -296.325766) (xy 191.135001 -296.277982) (xy 191.154292 -296.232706)
			(xy 191.180595 -296.19111) (xy 191.21323 -296.154273) (xy 191.251351 -296.123148) (xy 191.293972 -296.098541)
			(xy 191.339988 -296.081089) (xy 191.388207 -296.071245) (xy 191.437382 -296.069264) (xy 191.486237 -296.075196)
			(xy 191.533508 -296.088888) (xy 191.57797 -296.109986) (xy 191.618473 -296.137942) (xy 191.653966 -296.172034)
			(xy 191.683531 -296.211378) (xy 191.706402 -296.254955) (xy 191.721986 -296.301636) (xy 191.729881 -296.350213)
			(xy 191.730376 -296.37482) (xy 192.069224 -296.37482) (xy 192.073184 -296.325766) (xy 192.084961 -296.277982)
			(xy 192.104252 -296.232706) (xy 192.130555 -296.19111) (xy 192.16319 -296.154273) (xy 192.201311 -296.123148)
			(xy 192.243932 -296.098541) (xy 192.289948 -296.081089) (xy 192.338167 -296.071245) (xy 192.387342 -296.069264)
			(xy 192.436197 -296.075196) (xy 192.483468 -296.088888) (xy 192.52793 -296.109986) (xy 192.568433 -296.137942)
			(xy 192.603926 -296.172034) (xy 192.633491 -296.211378) (xy 192.656362 -296.254955) (xy 192.671946 -296.301636)
			(xy 192.679841 -296.350213) (xy 192.680336 -296.37482) (xy 194.919104 -296.37482) (xy 194.923064 -296.325766)
			(xy 194.934841 -296.277982) (xy 194.954132 -296.232706) (xy 194.980435 -296.19111) (xy 195.01307 -296.154273)
			(xy 195.051191 -296.123148) (xy 195.093812 -296.098541) (xy 195.139828 -296.081089) (xy 195.188047 -296.071245)
			(xy 195.237222 -296.069264) (xy 195.286077 -296.075196) (xy 195.333348 -296.088888) (xy 195.37781 -296.109986)
			(xy 195.418313 -296.137942) (xy 195.453806 -296.172034) (xy 195.483371 -296.211378) (xy 195.506242 -296.254955)
			(xy 195.521826 -296.301636) (xy 195.529721 -296.350213) (xy 195.530216 -296.37482) (xy 195.869064 -296.37482)
			(xy 195.873024 -296.325766) (xy 195.884801 -296.277982) (xy 195.904092 -296.232706) (xy 195.930395 -296.19111)
			(xy 195.96303 -296.154273) (xy 196.001151 -296.123148) (xy 196.043772 -296.098541) (xy 196.089788 -296.081089)
			(xy 196.138007 -296.071245) (xy 196.187182 -296.069264) (xy 196.236037 -296.075196) (xy 196.283308 -296.088888)
			(xy 196.32777 -296.109986) (xy 196.368273 -296.137942) (xy 196.403766 -296.172034) (xy 196.433331 -296.211378)
			(xy 196.456202 -296.254955) (xy 196.471786 -296.301636) (xy 196.479681 -296.350213) (xy 196.480176 -296.37482)
			(xy 196.819278 -296.37482) (xy 196.823238 -296.325766) (xy 196.835015 -296.277982) (xy 196.854306 -296.232706)
			(xy 196.880609 -296.19111) (xy 196.913244 -296.154273) (xy 196.951365 -296.123148) (xy 196.993986 -296.098541)
			(xy 197.040002 -296.081089) (xy 197.088221 -296.071245) (xy 197.137396 -296.069264) (xy 197.186251 -296.075196)
			(xy 197.233522 -296.088888) (xy 197.277984 -296.109986) (xy 197.318487 -296.137942) (xy 197.35398 -296.172034)
			(xy 197.383545 -296.211378) (xy 197.406416 -296.254955) (xy 197.422 -296.301636) (xy 197.429895 -296.350213)
			(xy 197.43039 -296.37482) (xy 197.769238 -296.37482) (xy 197.773198 -296.325766) (xy 197.784975 -296.277982)
			(xy 197.804266 -296.232706) (xy 197.830569 -296.19111) (xy 197.863204 -296.154273) (xy 197.901325 -296.123148)
			(xy 197.943946 -296.098541) (xy 197.989962 -296.081089) (xy 198.038181 -296.071245) (xy 198.087356 -296.069264)
			(xy 198.136211 -296.075196) (xy 198.183482 -296.088888) (xy 198.227944 -296.109986) (xy 198.268447 -296.137942)
			(xy 198.30394 -296.172034) (xy 198.333505 -296.211378) (xy 198.356376 -296.254955) (xy 198.37196 -296.301636)
			(xy 198.379855 -296.350213) (xy 198.38035 -296.37482) (xy 198.719198 -296.37482) (xy 198.723158 -296.325766)
			(xy 198.734935 -296.277982) (xy 198.754226 -296.232706) (xy 198.780529 -296.19111) (xy 198.813164 -296.154273)
			(xy 198.851285 -296.123148) (xy 198.893906 -296.098541) (xy 198.939922 -296.081089) (xy 198.988141 -296.071245)
			(xy 199.037316 -296.069264) (xy 199.086171 -296.075196) (xy 199.133442 -296.088888) (xy 199.177904 -296.109986)
			(xy 199.218407 -296.137942) (xy 199.2539 -296.172034) (xy 199.283465 -296.211378) (xy 199.306336 -296.254955)
			(xy 199.32192 -296.301636) (xy 199.329815 -296.350213) (xy 199.33031 -296.37482) (xy 199.329815 -296.399427)
			(xy 199.32192 -296.448004) (xy 199.306336 -296.494685) (xy 199.283465 -296.538262) (xy 199.2539 -296.577606)
			(xy 199.218407 -296.611698) (xy 199.216416 -296.613072) (xy 205.362554 -296.613072) (xy 205.366625 -296.55745)
			(xy 205.378751 -296.503013) (xy 205.398674 -296.450922) (xy 205.42597 -296.402287) (xy 205.460056 -296.358144)
			(xy 205.500205 -296.319435) (xy 205.545563 -296.286984) (xy 205.595163 -296.261483) (xy 205.647947 -296.243476)
			(xy 205.70279 -296.233346) (xy 205.758524 -296.231309) (xy 205.813961 -296.237409) (xy 205.867918 -296.251515)
			(xy 205.919247 -296.273327) (xy 205.966853 -296.302381) (xy 206.009721 -296.338056) (xy 206.046938 -296.379593)
			(xy 206.077711 -296.426106) (xy 206.101383 -296.476603) (xy 206.117451 -296.53001) (xy 206.125571 -296.585186)
			(xy 206.12608 -296.613072) (xy 206.63738 -296.613072) (xy 206.641451 -296.55745) (xy 206.653577 -296.503013)
			(xy 206.6735 -296.450922) (xy 206.700796 -296.402287) (xy 206.734882 -296.358144) (xy 206.775031 -296.319435)
			(xy 206.820389 -296.286984) (xy 206.869989 -296.261483) (xy 206.922773 -296.243476) (xy 206.977616 -296.233346)
			(xy 207.03335 -296.231309) (xy 207.088787 -296.237409) (xy 207.142744 -296.251515) (xy 207.194073 -296.273327)
			(xy 207.241679 -296.302381) (xy 207.284547 -296.338056) (xy 207.321764 -296.379593) (xy 207.352537 -296.426106)
			(xy 207.376209 -296.476603) (xy 207.392277 -296.53001) (xy 207.400397 -296.585186) (xy 207.400906 -296.613072)
			(xy 207.400397 -296.640958) (xy 207.392277 -296.696134) (xy 207.376209 -296.749541) (xy 207.352537 -296.800038)
			(xy 207.321764 -296.846551) (xy 207.284547 -296.888088) (xy 207.241679 -296.923763) (xy 207.194073 -296.952817)
			(xy 207.142744 -296.974629) (xy 207.088787 -296.988735) (xy 207.03335 -296.994835) (xy 206.977616 -296.992798)
			(xy 206.922773 -296.982668) (xy 206.869989 -296.964661) (xy 206.820389 -296.93916) (xy 206.775031 -296.906709)
			(xy 206.734882 -296.868) (xy 206.700796 -296.823857) (xy 206.6735 -296.775222) (xy 206.653577 -296.723131)
			(xy 206.641451 -296.668694) (xy 206.63738 -296.613072) (xy 206.12608 -296.613072) (xy 206.125571 -296.640958)
			(xy 206.117451 -296.696134) (xy 206.101383 -296.749541) (xy 206.077711 -296.800038) (xy 206.046938 -296.846551)
			(xy 206.009721 -296.888088) (xy 205.966853 -296.923763) (xy 205.919247 -296.952817) (xy 205.867918 -296.974629)
			(xy 205.813961 -296.988735) (xy 205.758524 -296.994835) (xy 205.70279 -296.992798) (xy 205.647947 -296.982668)
			(xy 205.595163 -296.964661) (xy 205.545563 -296.93916) (xy 205.500205 -296.906709) (xy 205.460056 -296.868)
			(xy 205.42597 -296.823857) (xy 205.398674 -296.775222) (xy 205.378751 -296.723131) (xy 205.366625 -296.668694)
			(xy 205.362554 -296.613072) (xy 199.216416 -296.613072) (xy 199.177904 -296.639654) (xy 199.133442 -296.660752)
			(xy 199.086171 -296.674444) (xy 199.037316 -296.680376) (xy 198.988141 -296.678395) (xy 198.939922 -296.668551)
			(xy 198.893906 -296.651099) (xy 198.851285 -296.626492) (xy 198.813164 -296.595367) (xy 198.780529 -296.55853)
			(xy 198.754226 -296.516934) (xy 198.734935 -296.471658) (xy 198.723158 -296.423874) (xy 198.719198 -296.37482)
			(xy 198.38035 -296.37482) (xy 198.379855 -296.399427) (xy 198.37196 -296.448004) (xy 198.356376 -296.494685)
			(xy 198.333505 -296.538262) (xy 198.30394 -296.577606) (xy 198.268447 -296.611698) (xy 198.227944 -296.639654)
			(xy 198.183482 -296.660752) (xy 198.136211 -296.674444) (xy 198.087356 -296.680376) (xy 198.038181 -296.678395)
			(xy 197.989962 -296.668551) (xy 197.943946 -296.651099) (xy 197.901325 -296.626492) (xy 197.863204 -296.595367)
			(xy 197.830569 -296.55853) (xy 197.804266 -296.516934) (xy 197.784975 -296.471658) (xy 197.773198 -296.423874)
			(xy 197.769238 -296.37482) (xy 197.43039 -296.37482) (xy 197.429895 -296.399427) (xy 197.422 -296.448004)
			(xy 197.406416 -296.494685) (xy 197.383545 -296.538262) (xy 197.35398 -296.577606) (xy 197.318487 -296.611698)
			(xy 197.277984 -296.639654) (xy 197.233522 -296.660752) (xy 197.186251 -296.674444) (xy 197.137396 -296.680376)
			(xy 197.088221 -296.678395) (xy 197.040002 -296.668551) (xy 196.993986 -296.651099) (xy 196.951365 -296.626492)
			(xy 196.913244 -296.595367) (xy 196.880609 -296.55853) (xy 196.854306 -296.516934) (xy 196.835015 -296.471658)
			(xy 196.823238 -296.423874) (xy 196.819278 -296.37482) (xy 196.480176 -296.37482) (xy 196.479681 -296.399427)
			(xy 196.471786 -296.448004) (xy 196.456202 -296.494685) (xy 196.433331 -296.538262) (xy 196.403766 -296.577606)
			(xy 196.368273 -296.611698) (xy 196.32777 -296.639654) (xy 196.283308 -296.660752) (xy 196.236037 -296.674444)
			(xy 196.187182 -296.680376) (xy 196.138007 -296.678395) (xy 196.089788 -296.668551) (xy 196.043772 -296.651099)
			(xy 196.001151 -296.626492) (xy 195.96303 -296.595367) (xy 195.930395 -296.55853) (xy 195.904092 -296.516934)
			(xy 195.884801 -296.471658) (xy 195.873024 -296.423874) (xy 195.869064 -296.37482) (xy 195.530216 -296.37482)
			(xy 195.529721 -296.399427) (xy 195.521826 -296.448004) (xy 195.506242 -296.494685) (xy 195.483371 -296.538262)
			(xy 195.453806 -296.577606) (xy 195.418313 -296.611698) (xy 195.37781 -296.639654) (xy 195.333348 -296.660752)
			(xy 195.286077 -296.674444) (xy 195.237222 -296.680376) (xy 195.188047 -296.678395) (xy 195.139828 -296.668551)
			(xy 195.093812 -296.651099) (xy 195.051191 -296.626492) (xy 195.01307 -296.595367) (xy 194.980435 -296.55853)
			(xy 194.954132 -296.516934) (xy 194.934841 -296.471658) (xy 194.923064 -296.423874) (xy 194.919104 -296.37482)
			(xy 192.680336 -296.37482) (xy 192.679841 -296.399427) (xy 192.671946 -296.448004) (xy 192.656362 -296.494685)
			(xy 192.633491 -296.538262) (xy 192.603926 -296.577606) (xy 192.568433 -296.611698) (xy 192.52793 -296.639654)
			(xy 192.483468 -296.660752) (xy 192.436197 -296.674444) (xy 192.387342 -296.680376) (xy 192.338167 -296.678395)
			(xy 192.289948 -296.668551) (xy 192.243932 -296.651099) (xy 192.201311 -296.626492) (xy 192.16319 -296.595367)
			(xy 192.130555 -296.55853) (xy 192.104252 -296.516934) (xy 192.084961 -296.471658) (xy 192.073184 -296.423874)
			(xy 192.069224 -296.37482) (xy 191.730376 -296.37482) (xy 191.729881 -296.399427) (xy 191.721986 -296.448004)
			(xy 191.706402 -296.494685) (xy 191.683531 -296.538262) (xy 191.653966 -296.577606) (xy 191.618473 -296.611698)
			(xy 191.57797 -296.639654) (xy 191.533508 -296.660752) (xy 191.486237 -296.674444) (xy 191.437382 -296.680376)
			(xy 191.388207 -296.678395) (xy 191.339988 -296.668551) (xy 191.293972 -296.651099) (xy 191.251351 -296.626492)
			(xy 191.21323 -296.595367) (xy 191.180595 -296.55853) (xy 191.154292 -296.516934) (xy 191.135001 -296.471658)
			(xy 191.123224 -296.423874) (xy 191.119264 -296.37482) (xy 190.780162 -296.37482) (xy 190.779667 -296.399427)
			(xy 190.771772 -296.448004) (xy 190.756188 -296.494685) (xy 190.733317 -296.538262) (xy 190.703752 -296.577606)
			(xy 190.668259 -296.611698) (xy 190.627756 -296.639654) (xy 190.583294 -296.660752) (xy 190.536023 -296.674444)
			(xy 190.487168 -296.680376) (xy 190.437993 -296.678395) (xy 190.389774 -296.668551) (xy 190.343758 -296.651099)
			(xy 190.301137 -296.626492) (xy 190.263016 -296.595367) (xy 190.230381 -296.55853) (xy 190.204078 -296.516934)
			(xy 190.184787 -296.471658) (xy 190.17301 -296.423874) (xy 190.16905 -296.37482) (xy 189.830202 -296.37482)
			(xy 189.829707 -296.399427) (xy 189.821812 -296.448004) (xy 189.806228 -296.494685) (xy 189.783357 -296.538262)
			(xy 189.753792 -296.577606) (xy 189.718299 -296.611698) (xy 189.677796 -296.639654) (xy 189.633334 -296.660752)
			(xy 189.586063 -296.674444) (xy 189.537208 -296.680376) (xy 189.488033 -296.678395) (xy 189.439814 -296.668551)
			(xy 189.393798 -296.651099) (xy 189.351177 -296.626492) (xy 189.313056 -296.595367) (xy 189.280421 -296.55853)
			(xy 189.254118 -296.516934) (xy 189.234827 -296.471658) (xy 189.22305 -296.423874) (xy 189.21909 -296.37482)
			(xy 188.880242 -296.37482) (xy 188.879747 -296.399427) (xy 188.871852 -296.448004) (xy 188.856268 -296.494685)
			(xy 188.833397 -296.538262) (xy 188.803832 -296.577606) (xy 188.768339 -296.611698) (xy 188.727836 -296.639654)
			(xy 188.683374 -296.660752) (xy 188.636103 -296.674444) (xy 188.587248 -296.680376) (xy 188.538073 -296.678395)
			(xy 188.489854 -296.668551) (xy 188.443838 -296.651099) (xy 188.401217 -296.626492) (xy 188.363096 -296.595367)
			(xy 188.330461 -296.55853) (xy 188.304158 -296.516934) (xy 188.284867 -296.471658) (xy 188.27309 -296.423874)
			(xy 188.26913 -296.37482) (xy 187.930282 -296.37482) (xy 187.929787 -296.399427) (xy 187.921892 -296.448004)
			(xy 187.906308 -296.494685) (xy 187.883437 -296.538262) (xy 187.853872 -296.577606) (xy 187.818379 -296.611698)
			(xy 187.777876 -296.639654) (xy 187.733414 -296.660752) (xy 187.686143 -296.674444) (xy 187.637288 -296.680376)
			(xy 187.588113 -296.678395) (xy 187.539894 -296.668551) (xy 187.493878 -296.651099) (xy 187.451257 -296.626492)
			(xy 187.413136 -296.595367) (xy 187.380501 -296.55853) (xy 187.354198 -296.516934) (xy 187.334907 -296.471658)
			(xy 187.32313 -296.423874) (xy 187.31917 -296.37482) (xy 186.030362 -296.37482) (xy 186.029867 -296.399427)
			(xy 186.021972 -296.448004) (xy 186.006388 -296.494685) (xy 185.983517 -296.538262) (xy 185.953952 -296.577606)
			(xy 185.918459 -296.611698) (xy 185.877956 -296.639654) (xy 185.833494 -296.660752) (xy 185.786223 -296.674444)
			(xy 185.737368 -296.680376) (xy 185.688193 -296.678395) (xy 185.639974 -296.668551) (xy 185.593958 -296.651099)
			(xy 185.551337 -296.626492) (xy 185.513216 -296.595367) (xy 185.480581 -296.55853) (xy 185.454278 -296.516934)
			(xy 185.434987 -296.471658) (xy 185.42321 -296.423874) (xy 185.41925 -296.37482) (xy 185.080148 -296.37482)
			(xy 185.079653 -296.399427) (xy 185.071758 -296.448004) (xy 185.056174 -296.494685) (xy 185.033303 -296.538262)
			(xy 185.003738 -296.577606) (xy 184.968245 -296.611698) (xy 184.927742 -296.639654) (xy 184.88328 -296.660752)
			(xy 184.836009 -296.674444) (xy 184.787154 -296.680376) (xy 184.737979 -296.678395) (xy 184.68976 -296.668551)
			(xy 184.643744 -296.651099) (xy 184.601123 -296.626492) (xy 184.563002 -296.595367) (xy 184.530367 -296.55853)
			(xy 184.504064 -296.516934) (xy 184.484773 -296.471658) (xy 184.472996 -296.423874) (xy 184.469036 -296.37482)
			(xy 184.130188 -296.37482) (xy 184.129693 -296.399427) (xy 184.121798 -296.448004) (xy 184.106214 -296.494685)
			(xy 184.083343 -296.538262) (xy 184.053778 -296.577606) (xy 184.018285 -296.611698) (xy 183.977782 -296.639654)
			(xy 183.93332 -296.660752) (xy 183.886049 -296.674444) (xy 183.837194 -296.680376) (xy 183.788019 -296.678395)
			(xy 183.7398 -296.668551) (xy 183.693784 -296.651099) (xy 183.651163 -296.626492) (xy 183.613042 -296.595367)
			(xy 183.580407 -296.55853) (xy 183.554104 -296.516934) (xy 183.534813 -296.471658) (xy 183.523036 -296.423874)
			(xy 183.519076 -296.37482) (xy 183.180228 -296.37482) (xy 183.179733 -296.399427) (xy 183.171838 -296.448004)
			(xy 183.156254 -296.494685) (xy 183.133383 -296.538262) (xy 183.103818 -296.577606) (xy 183.068325 -296.611698)
			(xy 183.027822 -296.639654) (xy 182.98336 -296.660752) (xy 182.936089 -296.674444) (xy 182.887234 -296.680376)
			(xy 182.838059 -296.678395) (xy 182.78984 -296.668551) (xy 182.743824 -296.651099) (xy 182.701203 -296.626492)
			(xy 182.663082 -296.595367) (xy 182.630447 -296.55853) (xy 182.604144 -296.516934) (xy 182.584853 -296.471658)
			(xy 182.573076 -296.423874) (xy 182.569116 -296.37482) (xy 182.230268 -296.37482) (xy 182.229773 -296.399427)
			(xy 182.221878 -296.448004) (xy 182.206294 -296.494685) (xy 182.183423 -296.538262) (xy 182.153858 -296.577606)
			(xy 182.118365 -296.611698) (xy 182.077862 -296.639654) (xy 182.0334 -296.660752) (xy 181.986129 -296.674444)
			(xy 181.937274 -296.680376) (xy 181.888099 -296.678395) (xy 181.83988 -296.668551) (xy 181.793864 -296.651099)
			(xy 181.751243 -296.626492) (xy 181.713122 -296.595367) (xy 181.680487 -296.55853) (xy 181.654184 -296.516934)
			(xy 181.634893 -296.471658) (xy 181.623116 -296.423874) (xy 181.619156 -296.37482) (xy 181.280308 -296.37482)
			(xy 181.279813 -296.399427) (xy 181.271918 -296.448004) (xy 181.256334 -296.494685) (xy 181.233463 -296.538262)
			(xy 181.203898 -296.577606) (xy 181.168405 -296.611698) (xy 181.127902 -296.639654) (xy 181.08344 -296.660752)
			(xy 181.036169 -296.674444) (xy 180.987314 -296.680376) (xy 180.938139 -296.678395) (xy 180.88992 -296.668551)
			(xy 180.843904 -296.651099) (xy 180.801283 -296.626492) (xy 180.763162 -296.595367) (xy 180.730527 -296.55853)
			(xy 180.704224 -296.516934) (xy 180.684933 -296.471658) (xy 180.673156 -296.423874) (xy 180.669196 -296.37482)
			(xy 180.330348 -296.37482) (xy 180.329853 -296.399427) (xy 180.321958 -296.448004) (xy 180.306374 -296.494685)
			(xy 180.283503 -296.538262) (xy 180.253938 -296.577606) (xy 180.218445 -296.611698) (xy 180.177942 -296.639654)
			(xy 180.13348 -296.660752) (xy 180.086209 -296.674444) (xy 180.037354 -296.680376) (xy 179.988179 -296.678395)
			(xy 179.93996 -296.668551) (xy 179.893944 -296.651099) (xy 179.851323 -296.626492) (xy 179.813202 -296.595367)
			(xy 179.780567 -296.55853) (xy 179.754264 -296.516934) (xy 179.734973 -296.471658) (xy 179.723196 -296.423874)
			(xy 179.719236 -296.37482) (xy 179.380388 -296.37482) (xy 179.379893 -296.399427) (xy 179.371998 -296.448004)
			(xy 179.356414 -296.494685) (xy 179.333543 -296.538262) (xy 179.303978 -296.577606) (xy 179.268485 -296.611698)
			(xy 179.227982 -296.639654) (xy 179.18352 -296.660752) (xy 179.136249 -296.674444) (xy 179.087394 -296.680376)
			(xy 179.038219 -296.678395) (xy 178.99 -296.668551) (xy 178.943984 -296.651099) (xy 178.901363 -296.626492)
			(xy 178.863242 -296.595367) (xy 178.830607 -296.55853) (xy 178.804304 -296.516934) (xy 178.785013 -296.471658)
			(xy 178.773236 -296.423874) (xy 178.769276 -296.37482) (xy 178.430174 -296.37482) (xy 178.429679 -296.399427)
			(xy 178.421784 -296.448004) (xy 178.4062 -296.494685) (xy 178.383329 -296.538262) (xy 178.353764 -296.577606)
			(xy 178.318271 -296.611698) (xy 178.277768 -296.639654) (xy 178.233306 -296.660752) (xy 178.186035 -296.674444)
			(xy 178.13718 -296.680376) (xy 178.088005 -296.678395) (xy 178.039786 -296.668551) (xy 177.99377 -296.651099)
			(xy 177.951149 -296.626492) (xy 177.913028 -296.595367) (xy 177.880393 -296.55853) (xy 177.85409 -296.516934)
			(xy 177.834799 -296.471658) (xy 177.823022 -296.423874) (xy 177.819062 -296.37482) (xy 177.480214 -296.37482)
			(xy 177.479719 -296.399427) (xy 177.471824 -296.448004) (xy 177.45624 -296.494685) (xy 177.433369 -296.538262)
			(xy 177.403804 -296.577606) (xy 177.368311 -296.611698) (xy 177.327808 -296.639654) (xy 177.283346 -296.660752)
			(xy 177.236075 -296.674444) (xy 177.18722 -296.680376) (xy 177.138045 -296.678395) (xy 177.089826 -296.668551)
			(xy 177.04381 -296.651099) (xy 177.001189 -296.626492) (xy 176.963068 -296.595367) (xy 176.930433 -296.55853)
			(xy 176.90413 -296.516934) (xy 176.884839 -296.471658) (xy 176.873062 -296.423874) (xy 176.869102 -296.37482)
			(xy 176.530254 -296.37482) (xy 176.529759 -296.399427) (xy 176.521864 -296.448004) (xy 176.50628 -296.494685)
			(xy 176.483409 -296.538262) (xy 176.453844 -296.577606) (xy 176.418351 -296.611698) (xy 176.377848 -296.639654)
			(xy 176.333386 -296.660752) (xy 176.286115 -296.674444) (xy 176.23726 -296.680376) (xy 176.188085 -296.678395)
			(xy 176.139866 -296.668551) (xy 176.09385 -296.651099) (xy 176.051229 -296.626492) (xy 176.013108 -296.595367)
			(xy 175.980473 -296.55853) (xy 175.95417 -296.516934) (xy 175.934879 -296.471658) (xy 175.923102 -296.423874)
			(xy 175.919142 -296.37482) (xy 174.630334 -296.37482) (xy 174.629839 -296.399427) (xy 174.621944 -296.448004)
			(xy 174.60636 -296.494685) (xy 174.583489 -296.538262) (xy 174.553924 -296.577606) (xy 174.518431 -296.611698)
			(xy 174.477928 -296.639654) (xy 174.433466 -296.660752) (xy 174.386195 -296.674444) (xy 174.33734 -296.680376)
			(xy 174.288165 -296.678395) (xy 174.239946 -296.668551) (xy 174.19393 -296.651099) (xy 174.151309 -296.626492)
			(xy 174.113188 -296.595367) (xy 174.080553 -296.55853) (xy 174.05425 -296.516934) (xy 174.034959 -296.471658)
			(xy 174.023182 -296.423874) (xy 174.019222 -296.37482) (xy 173.680374 -296.37482) (xy 173.679879 -296.399427)
			(xy 173.671984 -296.448004) (xy 173.6564 -296.494685) (xy 173.633529 -296.538262) (xy 173.603964 -296.577606)
			(xy 173.568471 -296.611698) (xy 173.527968 -296.639654) (xy 173.483506 -296.660752) (xy 173.436235 -296.674444)
			(xy 173.38738 -296.680376) (xy 173.338205 -296.678395) (xy 173.289986 -296.668551) (xy 173.24397 -296.651099)
			(xy 173.201349 -296.626492) (xy 173.163228 -296.595367) (xy 173.130593 -296.55853) (xy 173.10429 -296.516934)
			(xy 173.084999 -296.471658) (xy 173.073222 -296.423874) (xy 173.069262 -296.37482) (xy 172.730414 -296.37482)
			(xy 172.729919 -296.399427) (xy 172.722024 -296.448004) (xy 172.70644 -296.494685) (xy 172.683569 -296.538262)
			(xy 172.654004 -296.577606) (xy 172.618511 -296.611698) (xy 172.578008 -296.639654) (xy 172.533546 -296.660752)
			(xy 172.486275 -296.674444) (xy 172.43742 -296.680376) (xy 172.388245 -296.678395) (xy 172.340026 -296.668551)
			(xy 172.29401 -296.651099) (xy 172.251389 -296.626492) (xy 172.213268 -296.595367) (xy 172.180633 -296.55853)
			(xy 172.15433 -296.516934) (xy 172.135039 -296.471658) (xy 172.123262 -296.423874) (xy 172.119302 -296.37482)
			(xy 171.7802 -296.37482) (xy 171.779705 -296.399427) (xy 171.77181 -296.448004) (xy 171.756226 -296.494685)
			(xy 171.733355 -296.538262) (xy 171.70379 -296.577606) (xy 171.668297 -296.611698) (xy 171.627794 -296.639654)
			(xy 171.583332 -296.660752) (xy 171.536061 -296.674444) (xy 171.487206 -296.680376) (xy 171.438031 -296.678395)
			(xy 171.389812 -296.668551) (xy 171.343796 -296.651099) (xy 171.301175 -296.626492) (xy 171.263054 -296.595367)
			(xy 171.230419 -296.55853) (xy 171.204116 -296.516934) (xy 171.184825 -296.471658) (xy 171.173048 -296.423874)
			(xy 171.169088 -296.37482) (xy 170.83024 -296.37482) (xy 170.829745 -296.399427) (xy 170.82185 -296.448004)
			(xy 170.806266 -296.494685) (xy 170.783395 -296.538262) (xy 170.75383 -296.577606) (xy 170.718337 -296.611698)
			(xy 170.677834 -296.639654) (xy 170.633372 -296.660752) (xy 170.586101 -296.674444) (xy 170.537246 -296.680376)
			(xy 170.488071 -296.678395) (xy 170.439852 -296.668551) (xy 170.393836 -296.651099) (xy 170.351215 -296.626492)
			(xy 170.313094 -296.595367) (xy 170.280459 -296.55853) (xy 170.254156 -296.516934) (xy 170.234865 -296.471658)
			(xy 170.223088 -296.423874) (xy 170.219128 -296.37482) (xy 169.88028 -296.37482) (xy 169.879785 -296.399427)
			(xy 169.87189 -296.448004) (xy 169.856306 -296.494685) (xy 169.833435 -296.538262) (xy 169.80387 -296.577606)
			(xy 169.768377 -296.611698) (xy 169.727874 -296.639654) (xy 169.683412 -296.660752) (xy 169.636141 -296.674444)
			(xy 169.587286 -296.680376) (xy 169.538111 -296.678395) (xy 169.489892 -296.668551) (xy 169.443876 -296.651099)
			(xy 169.401255 -296.626492) (xy 169.363134 -296.595367) (xy 169.330499 -296.55853) (xy 169.304196 -296.516934)
			(xy 169.284905 -296.471658) (xy 169.273128 -296.423874) (xy 169.269168 -296.37482) (xy 168.93032 -296.37482)
			(xy 168.929825 -296.399427) (xy 168.92193 -296.448004) (xy 168.906346 -296.494685) (xy 168.883475 -296.538262)
			(xy 168.85391 -296.577606) (xy 168.818417 -296.611698) (xy 168.777914 -296.639654) (xy 168.733452 -296.660752)
			(xy 168.686181 -296.674444) (xy 168.637326 -296.680376) (xy 168.588151 -296.678395) (xy 168.539932 -296.668551)
			(xy 168.493916 -296.651099) (xy 168.451295 -296.626492) (xy 168.413174 -296.595367) (xy 168.380539 -296.55853)
			(xy 168.354236 -296.516934) (xy 168.334945 -296.471658) (xy 168.323168 -296.423874) (xy 168.319208 -296.37482)
			(xy 167.98036 -296.37482) (xy 167.979865 -296.399427) (xy 167.97197 -296.448004) (xy 167.956386 -296.494685)
			(xy 167.933515 -296.538262) (xy 167.90395 -296.577606) (xy 167.868457 -296.611698) (xy 167.827954 -296.639654)
			(xy 167.783492 -296.660752) (xy 167.736221 -296.674444) (xy 167.687366 -296.680376) (xy 167.638191 -296.678395)
			(xy 167.589972 -296.668551) (xy 167.543956 -296.651099) (xy 167.501335 -296.626492) (xy 167.463214 -296.595367)
			(xy 167.430579 -296.55853) (xy 167.404276 -296.516934) (xy 167.384985 -296.471658) (xy 167.373208 -296.423874)
			(xy 167.369248 -296.37482) (xy 167.0304 -296.37482) (xy 167.029905 -296.399427) (xy 167.02201 -296.448004)
			(xy 167.006426 -296.494685) (xy 166.983555 -296.538262) (xy 166.95399 -296.577606) (xy 166.918497 -296.611698)
			(xy 166.877994 -296.639654) (xy 166.833532 -296.660752) (xy 166.786261 -296.674444) (xy 166.737406 -296.680376)
			(xy 166.688231 -296.678395) (xy 166.640012 -296.668551) (xy 166.593996 -296.651099) (xy 166.551375 -296.626492)
			(xy 166.513254 -296.595367) (xy 166.480619 -296.55853) (xy 166.454316 -296.516934) (xy 166.435025 -296.471658)
			(xy 166.423248 -296.423874) (xy 166.419288 -296.37482) (xy 166.080186 -296.37482) (xy 166.079691 -296.399427)
			(xy 166.071796 -296.448004) (xy 166.056212 -296.494685) (xy 166.033341 -296.538262) (xy 166.003776 -296.577606)
			(xy 165.968283 -296.611698) (xy 165.92778 -296.639654) (xy 165.883318 -296.660752) (xy 165.836047 -296.674444)
			(xy 165.787192 -296.680376) (xy 165.738017 -296.678395) (xy 165.689798 -296.668551) (xy 165.643782 -296.651099)
			(xy 165.601161 -296.626492) (xy 165.56304 -296.595367) (xy 165.530405 -296.55853) (xy 165.504102 -296.516934)
			(xy 165.484811 -296.471658) (xy 165.473034 -296.423874) (xy 165.469074 -296.37482) (xy 165.155064 -296.37482)
			(xy 165.155064 -296.401183) (xy 165.146686 -296.453273) (xy 165.130143 -296.503373) (xy 165.105855 -296.55021)
			(xy 165.074438 -296.592596) (xy 165.036689 -296.629456) (xy 164.993566 -296.659854) (xy 164.946164 -296.683019)
			(xy 164.895685 -296.698364) (xy 164.869622 -296.70248) (xy 164.86505 -296.703242) (xy 164.854636 -296.706544)
			(xy 164.850318 -296.707814) (xy 164.826696 -296.718736) (xy 164.819838 -296.725848) (xy 164.804852 -296.741596)
			(xy 164.800263 -296.746701) (xy 164.793817 -296.758813) (xy 164.792152 -296.765472) (xy 164.790882 -296.776394)
			(xy 164.790882 -296.923206) (xy 164.791347 -296.93284) (xy 164.798523 -296.950727) (xy 164.804852 -296.958004)
			(xy 164.820092 -296.974006) (xy 164.82695 -296.981372) (xy 164.850318 -296.991786) (xy 164.854636 -296.993056)
			(xy 164.86505 -296.996358) (xy 164.869622 -296.99712) (xy 164.895693 -297.001197) (xy 164.946179 -297.016544)
			(xy 164.993587 -297.039712) (xy 165.036714 -297.070114) (xy 165.074468 -297.106978) (xy 165.105888 -297.149369)
			(xy 165.130179 -297.196212) (xy 165.146724 -297.246317) (xy 165.155103 -297.298414) (xy 165.155103 -297.32478)
			(xy 165.469074 -297.32478) (xy 165.473034 -297.275726) (xy 165.484811 -297.227942) (xy 165.504102 -297.182666)
			(xy 165.530405 -297.14107) (xy 165.56304 -297.104233) (xy 165.601161 -297.073108) (xy 165.643782 -297.048501)
			(xy 165.689798 -297.031049) (xy 165.738017 -297.021205) (xy 165.787192 -297.019224) (xy 165.836047 -297.025156)
			(xy 165.883318 -297.038848) (xy 165.92778 -297.059946) (xy 165.968283 -297.087902) (xy 166.003776 -297.121994)
			(xy 166.033341 -297.161338) (xy 166.056212 -297.204915) (xy 166.071796 -297.251596) (xy 166.079691 -297.300173)
			(xy 166.080186 -297.32478) (xy 166.419288 -297.32478) (xy 166.423248 -297.275726) (xy 166.435025 -297.227942)
			(xy 166.454316 -297.182666) (xy 166.480619 -297.14107) (xy 166.513254 -297.104233) (xy 166.551375 -297.073108)
			(xy 166.593996 -297.048501) (xy 166.640012 -297.031049) (xy 166.688231 -297.021205) (xy 166.737406 -297.019224)
			(xy 166.786261 -297.025156) (xy 166.833532 -297.038848) (xy 166.877994 -297.059946) (xy 166.918497 -297.087902)
			(xy 166.95399 -297.121994) (xy 166.983555 -297.161338) (xy 167.006426 -297.204915) (xy 167.02201 -297.251596)
			(xy 167.029905 -297.300173) (xy 167.0304 -297.32478) (xy 167.369248 -297.32478) (xy 167.373208 -297.275726)
			(xy 167.384985 -297.227942) (xy 167.404276 -297.182666) (xy 167.430579 -297.14107) (xy 167.463214 -297.104233)
			(xy 167.501335 -297.073108) (xy 167.543956 -297.048501) (xy 167.589972 -297.031049) (xy 167.638191 -297.021205)
			(xy 167.687366 -297.019224) (xy 167.736221 -297.025156) (xy 167.783492 -297.038848) (xy 167.827954 -297.059946)
			(xy 167.868457 -297.087902) (xy 167.90395 -297.121994) (xy 167.933515 -297.161338) (xy 167.956386 -297.204915)
			(xy 167.97197 -297.251596) (xy 167.979865 -297.300173) (xy 167.98036 -297.32478) (xy 168.319208 -297.32478)
			(xy 168.323168 -297.275726) (xy 168.334945 -297.227942) (xy 168.354236 -297.182666) (xy 168.380539 -297.14107)
			(xy 168.413174 -297.104233) (xy 168.451295 -297.073108) (xy 168.493916 -297.048501) (xy 168.539932 -297.031049)
			(xy 168.588151 -297.021205) (xy 168.637326 -297.019224) (xy 168.686181 -297.025156) (xy 168.733452 -297.038848)
			(xy 168.777914 -297.059946) (xy 168.818417 -297.087902) (xy 168.85391 -297.121994) (xy 168.883475 -297.161338)
			(xy 168.906346 -297.204915) (xy 168.92193 -297.251596) (xy 168.929825 -297.300173) (xy 168.93032 -297.32478)
			(xy 169.269168 -297.32478) (xy 169.273128 -297.275726) (xy 169.284905 -297.227942) (xy 169.304196 -297.182666)
			(xy 169.330499 -297.14107) (xy 169.363134 -297.104233) (xy 169.401255 -297.073108) (xy 169.443876 -297.048501)
			(xy 169.489892 -297.031049) (xy 169.538111 -297.021205) (xy 169.587286 -297.019224) (xy 169.636141 -297.025156)
			(xy 169.683412 -297.038848) (xy 169.727874 -297.059946) (xy 169.768377 -297.087902) (xy 169.80387 -297.121994)
			(xy 169.833435 -297.161338) (xy 169.856306 -297.204915) (xy 169.87189 -297.251596) (xy 169.879785 -297.300173)
			(xy 169.88028 -297.32478) (xy 170.219128 -297.32478) (xy 170.223088 -297.275726) (xy 170.234865 -297.227942)
			(xy 170.254156 -297.182666) (xy 170.280459 -297.14107) (xy 170.313094 -297.104233) (xy 170.351215 -297.073108)
			(xy 170.393836 -297.048501) (xy 170.439852 -297.031049) (xy 170.488071 -297.021205) (xy 170.537246 -297.019224)
			(xy 170.586101 -297.025156) (xy 170.633372 -297.038848) (xy 170.677834 -297.059946) (xy 170.718337 -297.087902)
			(xy 170.75383 -297.121994) (xy 170.783395 -297.161338) (xy 170.806266 -297.204915) (xy 170.82185 -297.251596)
			(xy 170.829745 -297.300173) (xy 170.83024 -297.32478) (xy 171.169088 -297.32478) (xy 171.173048 -297.275726)
			(xy 171.184825 -297.227942) (xy 171.204116 -297.182666) (xy 171.230419 -297.14107) (xy 171.263054 -297.104233)
			(xy 171.301175 -297.073108) (xy 171.343796 -297.048501) (xy 171.389812 -297.031049) (xy 171.438031 -297.021205)
			(xy 171.487206 -297.019224) (xy 171.536061 -297.025156) (xy 171.583332 -297.038848) (xy 171.627794 -297.059946)
			(xy 171.668297 -297.087902) (xy 171.70379 -297.121994) (xy 171.733355 -297.161338) (xy 171.756226 -297.204915)
			(xy 171.77181 -297.251596) (xy 171.779705 -297.300173) (xy 171.7802 -297.32478) (xy 172.119048 -297.32478)
			(xy 172.123008 -297.275726) (xy 172.134785 -297.227942) (xy 172.154076 -297.182666) (xy 172.180379 -297.14107)
			(xy 172.213014 -297.104233) (xy 172.251135 -297.073108) (xy 172.293756 -297.048501) (xy 172.339772 -297.031049)
			(xy 172.387991 -297.021205) (xy 172.437166 -297.019224) (xy 172.486021 -297.025156) (xy 172.533292 -297.038848)
			(xy 172.577754 -297.059946) (xy 172.618257 -297.087902) (xy 172.65375 -297.121994) (xy 172.683315 -297.161338)
			(xy 172.706186 -297.204915) (xy 172.72177 -297.251596) (xy 172.729665 -297.300173) (xy 172.73016 -297.32478)
			(xy 173.069262 -297.32478) (xy 173.073222 -297.275726) (xy 173.084999 -297.227942) (xy 173.10429 -297.182666)
			(xy 173.130593 -297.14107) (xy 173.163228 -297.104233) (xy 173.201349 -297.073108) (xy 173.24397 -297.048501)
			(xy 173.289986 -297.031049) (xy 173.338205 -297.021205) (xy 173.38738 -297.019224) (xy 173.436235 -297.025156)
			(xy 173.483506 -297.038848) (xy 173.527968 -297.059946) (xy 173.568471 -297.087902) (xy 173.603964 -297.121994)
			(xy 173.633529 -297.161338) (xy 173.6564 -297.204915) (xy 173.671984 -297.251596) (xy 173.679879 -297.300173)
			(xy 173.680374 -297.32478) (xy 174.019222 -297.32478) (xy 174.023182 -297.275726) (xy 174.034959 -297.227942)
			(xy 174.05425 -297.182666) (xy 174.080553 -297.14107) (xy 174.113188 -297.104233) (xy 174.151309 -297.073108)
			(xy 174.19393 -297.048501) (xy 174.239946 -297.031049) (xy 174.288165 -297.021205) (xy 174.33734 -297.019224)
			(xy 174.386195 -297.025156) (xy 174.433466 -297.038848) (xy 174.477928 -297.059946) (xy 174.518431 -297.087902)
			(xy 174.553924 -297.121994) (xy 174.583489 -297.161338) (xy 174.60636 -297.204915) (xy 174.621944 -297.251596)
			(xy 174.629839 -297.300173) (xy 174.630334 -297.32478) (xy 175.919142 -297.32478) (xy 175.923102 -297.275726)
			(xy 175.934879 -297.227942) (xy 175.95417 -297.182666) (xy 175.980473 -297.14107) (xy 176.013108 -297.104233)
			(xy 176.051229 -297.073108) (xy 176.09385 -297.048501) (xy 176.139866 -297.031049) (xy 176.188085 -297.021205)
			(xy 176.23726 -297.019224) (xy 176.286115 -297.025156) (xy 176.333386 -297.038848) (xy 176.377848 -297.059946)
			(xy 176.418351 -297.087902) (xy 176.453844 -297.121994) (xy 176.483409 -297.161338) (xy 176.50628 -297.204915)
			(xy 176.521864 -297.251596) (xy 176.529759 -297.300173) (xy 176.530254 -297.32478) (xy 176.869102 -297.32478)
			(xy 176.873062 -297.275726) (xy 176.884839 -297.227942) (xy 176.90413 -297.182666) (xy 176.930433 -297.14107)
			(xy 176.963068 -297.104233) (xy 177.001189 -297.073108) (xy 177.04381 -297.048501) (xy 177.089826 -297.031049)
			(xy 177.138045 -297.021205) (xy 177.18722 -297.019224) (xy 177.236075 -297.025156) (xy 177.283346 -297.038848)
			(xy 177.327808 -297.059946) (xy 177.368311 -297.087902) (xy 177.403804 -297.121994) (xy 177.433369 -297.161338)
			(xy 177.45624 -297.204915) (xy 177.471824 -297.251596) (xy 177.479719 -297.300173) (xy 177.480214 -297.32478)
			(xy 177.819062 -297.32478) (xy 177.823022 -297.275726) (xy 177.834799 -297.227942) (xy 177.85409 -297.182666)
			(xy 177.880393 -297.14107) (xy 177.913028 -297.104233) (xy 177.951149 -297.073108) (xy 177.99377 -297.048501)
			(xy 178.039786 -297.031049) (xy 178.088005 -297.021205) (xy 178.13718 -297.019224) (xy 178.186035 -297.025156)
			(xy 178.233306 -297.038848) (xy 178.277768 -297.059946) (xy 178.318271 -297.087902) (xy 178.353764 -297.121994)
			(xy 178.383329 -297.161338) (xy 178.4062 -297.204915) (xy 178.421784 -297.251596) (xy 178.429679 -297.300173)
			(xy 178.430174 -297.32478) (xy 178.769276 -297.32478) (xy 178.773236 -297.275726) (xy 178.785013 -297.227942)
			(xy 178.804304 -297.182666) (xy 178.830607 -297.14107) (xy 178.863242 -297.104233) (xy 178.901363 -297.073108)
			(xy 178.943984 -297.048501) (xy 178.99 -297.031049) (xy 179.038219 -297.021205) (xy 179.087394 -297.019224)
			(xy 179.136249 -297.025156) (xy 179.18352 -297.038848) (xy 179.227982 -297.059946) (xy 179.268485 -297.087902)
			(xy 179.303978 -297.121994) (xy 179.333543 -297.161338) (xy 179.356414 -297.204915) (xy 179.371998 -297.251596)
			(xy 179.379893 -297.300173) (xy 179.380388 -297.32478) (xy 179.719236 -297.32478) (xy 179.723196 -297.275726)
			(xy 179.734973 -297.227942) (xy 179.754264 -297.182666) (xy 179.780567 -297.14107) (xy 179.813202 -297.104233)
			(xy 179.851323 -297.073108) (xy 179.893944 -297.048501) (xy 179.93996 -297.031049) (xy 179.988179 -297.021205)
			(xy 180.037354 -297.019224) (xy 180.086209 -297.025156) (xy 180.13348 -297.038848) (xy 180.177942 -297.059946)
			(xy 180.218445 -297.087902) (xy 180.253938 -297.121994) (xy 180.283503 -297.161338) (xy 180.306374 -297.204915)
			(xy 180.321958 -297.251596) (xy 180.329853 -297.300173) (xy 180.330348 -297.32478) (xy 180.669196 -297.32478)
			(xy 180.673156 -297.275726) (xy 180.684933 -297.227942) (xy 180.704224 -297.182666) (xy 180.730527 -297.14107)
			(xy 180.763162 -297.104233) (xy 180.801283 -297.073108) (xy 180.843904 -297.048501) (xy 180.88992 -297.031049)
			(xy 180.938139 -297.021205) (xy 180.987314 -297.019224) (xy 181.036169 -297.025156) (xy 181.08344 -297.038848)
			(xy 181.127902 -297.059946) (xy 181.168405 -297.087902) (xy 181.203898 -297.121994) (xy 181.233463 -297.161338)
			(xy 181.256334 -297.204915) (xy 181.271918 -297.251596) (xy 181.279813 -297.300173) (xy 181.280308 -297.32478)
			(xy 181.619156 -297.32478) (xy 181.623116 -297.275726) (xy 181.634893 -297.227942) (xy 181.654184 -297.182666)
			(xy 181.680487 -297.14107) (xy 181.713122 -297.104233) (xy 181.751243 -297.073108) (xy 181.793864 -297.048501)
			(xy 181.83988 -297.031049) (xy 181.888099 -297.021205) (xy 181.937274 -297.019224) (xy 181.986129 -297.025156)
			(xy 182.0334 -297.038848) (xy 182.077862 -297.059946) (xy 182.118365 -297.087902) (xy 182.153858 -297.121994)
			(xy 182.183423 -297.161338) (xy 182.206294 -297.204915) (xy 182.221878 -297.251596) (xy 182.229773 -297.300173)
			(xy 182.230268 -297.32478) (xy 182.569116 -297.32478) (xy 182.573076 -297.275726) (xy 182.584853 -297.227942)
			(xy 182.604144 -297.182666) (xy 182.630447 -297.14107) (xy 182.663082 -297.104233) (xy 182.701203 -297.073108)
			(xy 182.743824 -297.048501) (xy 182.78984 -297.031049) (xy 182.838059 -297.021205) (xy 182.887234 -297.019224)
			(xy 182.936089 -297.025156) (xy 182.98336 -297.038848) (xy 183.027822 -297.059946) (xy 183.068325 -297.087902)
			(xy 183.103818 -297.121994) (xy 183.133383 -297.161338) (xy 183.156254 -297.204915) (xy 183.171838 -297.251596)
			(xy 183.179733 -297.300173) (xy 183.180228 -297.32478) (xy 183.519076 -297.32478) (xy 183.523036 -297.275726)
			(xy 183.534813 -297.227942) (xy 183.554104 -297.182666) (xy 183.580407 -297.14107) (xy 183.613042 -297.104233)
			(xy 183.651163 -297.073108) (xy 183.693784 -297.048501) (xy 183.7398 -297.031049) (xy 183.788019 -297.021205)
			(xy 183.837194 -297.019224) (xy 183.886049 -297.025156) (xy 183.93332 -297.038848) (xy 183.977782 -297.059946)
			(xy 184.018285 -297.087902) (xy 184.053778 -297.121994) (xy 184.083343 -297.161338) (xy 184.106214 -297.204915)
			(xy 184.121798 -297.251596) (xy 184.129693 -297.300173) (xy 184.130188 -297.32478) (xy 184.469036 -297.32478)
			(xy 184.472996 -297.275726) (xy 184.484773 -297.227942) (xy 184.504064 -297.182666) (xy 184.530367 -297.14107)
			(xy 184.563002 -297.104233) (xy 184.601123 -297.073108) (xy 184.643744 -297.048501) (xy 184.68976 -297.031049)
			(xy 184.737979 -297.021205) (xy 184.787154 -297.019224) (xy 184.836009 -297.025156) (xy 184.88328 -297.038848)
			(xy 184.927742 -297.059946) (xy 184.968245 -297.087902) (xy 185.003738 -297.121994) (xy 185.033303 -297.161338)
			(xy 185.056174 -297.204915) (xy 185.071758 -297.251596) (xy 185.079653 -297.300173) (xy 185.080148 -297.32478)
			(xy 185.41925 -297.32478) (xy 185.42321 -297.275726) (xy 185.434987 -297.227942) (xy 185.454278 -297.182666)
			(xy 185.480581 -297.14107) (xy 185.513216 -297.104233) (xy 185.551337 -297.073108) (xy 185.593958 -297.048501)
			(xy 185.639974 -297.031049) (xy 185.688193 -297.021205) (xy 185.737368 -297.019224) (xy 185.786223 -297.025156)
			(xy 185.833494 -297.038848) (xy 185.877956 -297.059946) (xy 185.918459 -297.087902) (xy 185.953952 -297.121994)
			(xy 185.983517 -297.161338) (xy 186.006388 -297.204915) (xy 186.021972 -297.251596) (xy 186.029867 -297.300173)
			(xy 186.030362 -297.32478) (xy 187.31917 -297.32478) (xy 187.32313 -297.275726) (xy 187.334907 -297.227942)
			(xy 187.354198 -297.182666) (xy 187.380501 -297.14107) (xy 187.413136 -297.104233) (xy 187.451257 -297.073108)
			(xy 187.493878 -297.048501) (xy 187.539894 -297.031049) (xy 187.588113 -297.021205) (xy 187.637288 -297.019224)
			(xy 187.686143 -297.025156) (xy 187.733414 -297.038848) (xy 187.777876 -297.059946) (xy 187.818379 -297.087902)
			(xy 187.853872 -297.121994) (xy 187.883437 -297.161338) (xy 187.906308 -297.204915) (xy 187.921892 -297.251596)
			(xy 187.929787 -297.300173) (xy 187.930282 -297.32478) (xy 188.26913 -297.32478) (xy 188.27309 -297.275726)
			(xy 188.284867 -297.227942) (xy 188.304158 -297.182666) (xy 188.330461 -297.14107) (xy 188.363096 -297.104233)
			(xy 188.401217 -297.073108) (xy 188.443838 -297.048501) (xy 188.489854 -297.031049) (xy 188.538073 -297.021205)
			(xy 188.587248 -297.019224) (xy 188.636103 -297.025156) (xy 188.683374 -297.038848) (xy 188.727836 -297.059946)
			(xy 188.768339 -297.087902) (xy 188.803832 -297.121994) (xy 188.833397 -297.161338) (xy 188.856268 -297.204915)
			(xy 188.871852 -297.251596) (xy 188.879747 -297.300173) (xy 188.880242 -297.32478) (xy 189.21909 -297.32478)
			(xy 189.22305 -297.275726) (xy 189.234827 -297.227942) (xy 189.254118 -297.182666) (xy 189.280421 -297.14107)
			(xy 189.313056 -297.104233) (xy 189.351177 -297.073108) (xy 189.393798 -297.048501) (xy 189.439814 -297.031049)
			(xy 189.488033 -297.021205) (xy 189.537208 -297.019224) (xy 189.586063 -297.025156) (xy 189.633334 -297.038848)
			(xy 189.677796 -297.059946) (xy 189.718299 -297.087902) (xy 189.753792 -297.121994) (xy 189.783357 -297.161338)
			(xy 189.806228 -297.204915) (xy 189.821812 -297.251596) (xy 189.829707 -297.300173) (xy 189.830202 -297.32478)
			(xy 190.169304 -297.32478) (xy 190.173264 -297.275726) (xy 190.185041 -297.227942) (xy 190.204332 -297.182666)
			(xy 190.230635 -297.14107) (xy 190.26327 -297.104233) (xy 190.301391 -297.073108) (xy 190.344012 -297.048501)
			(xy 190.390028 -297.031049) (xy 190.438247 -297.021205) (xy 190.487422 -297.019224) (xy 190.536277 -297.025156)
			(xy 190.583548 -297.038848) (xy 190.62801 -297.059946) (xy 190.668513 -297.087902) (xy 190.704006 -297.121994)
			(xy 190.733571 -297.161338) (xy 190.756442 -297.204915) (xy 190.772026 -297.251596) (xy 190.779921 -297.300173)
			(xy 190.780416 -297.32478) (xy 191.119264 -297.32478) (xy 191.123224 -297.275726) (xy 191.135001 -297.227942)
			(xy 191.154292 -297.182666) (xy 191.180595 -297.14107) (xy 191.21323 -297.104233) (xy 191.251351 -297.073108)
			(xy 191.293972 -297.048501) (xy 191.339988 -297.031049) (xy 191.388207 -297.021205) (xy 191.437382 -297.019224)
			(xy 191.486237 -297.025156) (xy 191.533508 -297.038848) (xy 191.57797 -297.059946) (xy 191.618473 -297.087902)
			(xy 191.653966 -297.121994) (xy 191.683531 -297.161338) (xy 191.706402 -297.204915) (xy 191.721986 -297.251596)
			(xy 191.729881 -297.300173) (xy 191.730376 -297.32478) (xy 192.069224 -297.32478) (xy 192.073184 -297.275726)
			(xy 192.084961 -297.227942) (xy 192.104252 -297.182666) (xy 192.130555 -297.14107) (xy 192.16319 -297.104233)
			(xy 192.201311 -297.073108) (xy 192.243932 -297.048501) (xy 192.289948 -297.031049) (xy 192.338167 -297.021205)
			(xy 192.387342 -297.019224) (xy 192.436197 -297.025156) (xy 192.483468 -297.038848) (xy 192.52793 -297.059946)
			(xy 192.568433 -297.087902) (xy 192.603926 -297.121994) (xy 192.633491 -297.161338) (xy 192.656362 -297.204915)
			(xy 192.671946 -297.251596) (xy 192.679841 -297.300173) (xy 192.680336 -297.32478) (xy 193.019184 -297.32478)
			(xy 193.023144 -297.275726) (xy 193.034921 -297.227942) (xy 193.054212 -297.182666) (xy 193.080515 -297.14107)
			(xy 193.11315 -297.104233) (xy 193.151271 -297.073108) (xy 193.193892 -297.048501) (xy 193.239908 -297.031049)
			(xy 193.288127 -297.021205) (xy 193.337302 -297.019224) (xy 193.386157 -297.025156) (xy 193.433428 -297.038848)
			(xy 193.47789 -297.059946) (xy 193.518393 -297.087902) (xy 193.553886 -297.121994) (xy 193.583451 -297.161338)
			(xy 193.606322 -297.204915) (xy 193.621906 -297.251596) (xy 193.629801 -297.300173) (xy 193.630296 -297.32478)
			(xy 193.969144 -297.32478) (xy 193.973104 -297.275726) (xy 193.984881 -297.227942) (xy 194.004172 -297.182666)
			(xy 194.030475 -297.14107) (xy 194.06311 -297.104233) (xy 194.101231 -297.073108) (xy 194.143852 -297.048501)
			(xy 194.189868 -297.031049) (xy 194.238087 -297.021205) (xy 194.287262 -297.019224) (xy 194.336117 -297.025156)
			(xy 194.383388 -297.038848) (xy 194.42785 -297.059946) (xy 194.468353 -297.087902) (xy 194.503846 -297.121994)
			(xy 194.533411 -297.161338) (xy 194.556282 -297.204915) (xy 194.571866 -297.251596) (xy 194.579761 -297.300173)
			(xy 194.580256 -297.32478) (xy 194.919104 -297.32478) (xy 194.923064 -297.275726) (xy 194.934841 -297.227942)
			(xy 194.954132 -297.182666) (xy 194.980435 -297.14107) (xy 195.01307 -297.104233) (xy 195.051191 -297.073108)
			(xy 195.093812 -297.048501) (xy 195.139828 -297.031049) (xy 195.188047 -297.021205) (xy 195.237222 -297.019224)
			(xy 195.286077 -297.025156) (xy 195.333348 -297.038848) (xy 195.37781 -297.059946) (xy 195.418313 -297.087902)
			(xy 195.453806 -297.121994) (xy 195.483371 -297.161338) (xy 195.506242 -297.204915) (xy 195.521826 -297.251596)
			(xy 195.529721 -297.300173) (xy 195.530216 -297.32478) (xy 195.869064 -297.32478) (xy 195.873024 -297.275726)
			(xy 195.884801 -297.227942) (xy 195.904092 -297.182666) (xy 195.930395 -297.14107) (xy 195.96303 -297.104233)
			(xy 196.001151 -297.073108) (xy 196.043772 -297.048501) (xy 196.089788 -297.031049) (xy 196.138007 -297.021205)
			(xy 196.187182 -297.019224) (xy 196.236037 -297.025156) (xy 196.283308 -297.038848) (xy 196.32777 -297.059946)
			(xy 196.368273 -297.087902) (xy 196.403766 -297.121994) (xy 196.433331 -297.161338) (xy 196.456202 -297.204915)
			(xy 196.471786 -297.251596) (xy 196.479681 -297.300173) (xy 196.480176 -297.32478) (xy 196.819278 -297.32478)
			(xy 196.823238 -297.275726) (xy 196.835015 -297.227942) (xy 196.854306 -297.182666) (xy 196.880609 -297.14107)
			(xy 196.913244 -297.104233) (xy 196.951365 -297.073108) (xy 196.993986 -297.048501) (xy 197.040002 -297.031049)
			(xy 197.088221 -297.021205) (xy 197.137396 -297.019224) (xy 197.186251 -297.025156) (xy 197.233522 -297.038848)
			(xy 197.277984 -297.059946) (xy 197.318487 -297.087902) (xy 197.35398 -297.121994) (xy 197.383545 -297.161338)
			(xy 197.406416 -297.204915) (xy 197.422 -297.251596) (xy 197.429895 -297.300173) (xy 197.43039 -297.32478)
			(xy 197.769238 -297.32478) (xy 197.773198 -297.275726) (xy 197.784975 -297.227942) (xy 197.804266 -297.182666)
			(xy 197.830569 -297.14107) (xy 197.863204 -297.104233) (xy 197.901325 -297.073108) (xy 197.943946 -297.048501)
			(xy 197.989962 -297.031049) (xy 198.038181 -297.021205) (xy 198.087356 -297.019224) (xy 198.136211 -297.025156)
			(xy 198.183482 -297.038848) (xy 198.227944 -297.059946) (xy 198.268447 -297.087902) (xy 198.30394 -297.121994)
			(xy 198.333505 -297.161338) (xy 198.356376 -297.204915) (xy 198.37196 -297.251596) (xy 198.379855 -297.300173)
			(xy 198.38035 -297.32478) (xy 198.719198 -297.32478) (xy 198.723158 -297.275726) (xy 198.734935 -297.227942)
			(xy 198.754226 -297.182666) (xy 198.780529 -297.14107) (xy 198.813164 -297.104233) (xy 198.851285 -297.073108)
			(xy 198.893906 -297.048501) (xy 198.939922 -297.031049) (xy 198.988141 -297.021205) (xy 199.037316 -297.019224)
			(xy 199.086171 -297.025156) (xy 199.133442 -297.038848) (xy 199.177904 -297.059946) (xy 199.218407 -297.087902)
			(xy 199.2539 -297.121994) (xy 199.283465 -297.161338) (xy 199.306336 -297.204915) (xy 199.32192 -297.251596)
			(xy 199.329815 -297.300173) (xy 199.33031 -297.32478) (xy 199.329815 -297.349387) (xy 199.32192 -297.397964)
			(xy 199.306336 -297.444645) (xy 199.283465 -297.488222) (xy 199.2539 -297.527566) (xy 199.218407 -297.561658)
			(xy 199.177904 -297.589614) (xy 199.133442 -297.610712) (xy 199.086171 -297.624404) (xy 199.037316 -297.630336)
			(xy 198.988141 -297.628355) (xy 198.939922 -297.618511) (xy 198.893906 -297.601059) (xy 198.851285 -297.576452)
			(xy 198.813164 -297.545327) (xy 198.780529 -297.50849) (xy 198.754226 -297.466894) (xy 198.734935 -297.421618)
			(xy 198.723158 -297.373834) (xy 198.719198 -297.32478) (xy 198.38035 -297.32478) (xy 198.379855 -297.349387)
			(xy 198.37196 -297.397964) (xy 198.356376 -297.444645) (xy 198.333505 -297.488222) (xy 198.30394 -297.527566)
			(xy 198.268447 -297.561658) (xy 198.227944 -297.589614) (xy 198.183482 -297.610712) (xy 198.136211 -297.624404)
			(xy 198.087356 -297.630336) (xy 198.038181 -297.628355) (xy 197.989962 -297.618511) (xy 197.943946 -297.601059)
			(xy 197.901325 -297.576452) (xy 197.863204 -297.545327) (xy 197.830569 -297.50849) (xy 197.804266 -297.466894)
			(xy 197.784975 -297.421618) (xy 197.773198 -297.373834) (xy 197.769238 -297.32478) (xy 197.43039 -297.32478)
			(xy 197.429895 -297.349387) (xy 197.422 -297.397964) (xy 197.406416 -297.444645) (xy 197.383545 -297.488222)
			(xy 197.35398 -297.527566) (xy 197.318487 -297.561658) (xy 197.277984 -297.589614) (xy 197.233522 -297.610712)
			(xy 197.186251 -297.624404) (xy 197.137396 -297.630336) (xy 197.088221 -297.628355) (xy 197.040002 -297.618511)
			(xy 196.993986 -297.601059) (xy 196.951365 -297.576452) (xy 196.913244 -297.545327) (xy 196.880609 -297.50849)
			(xy 196.854306 -297.466894) (xy 196.835015 -297.421618) (xy 196.823238 -297.373834) (xy 196.819278 -297.32478)
			(xy 196.480176 -297.32478) (xy 196.479681 -297.349387) (xy 196.471786 -297.397964) (xy 196.456202 -297.444645)
			(xy 196.433331 -297.488222) (xy 196.403766 -297.527566) (xy 196.368273 -297.561658) (xy 196.32777 -297.589614)
			(xy 196.283308 -297.610712) (xy 196.236037 -297.624404) (xy 196.187182 -297.630336) (xy 196.138007 -297.628355)
			(xy 196.089788 -297.618511) (xy 196.043772 -297.601059) (xy 196.001151 -297.576452) (xy 195.96303 -297.545327)
			(xy 195.930395 -297.50849) (xy 195.904092 -297.466894) (xy 195.884801 -297.421618) (xy 195.873024 -297.373834)
			(xy 195.869064 -297.32478) (xy 195.530216 -297.32478) (xy 195.529721 -297.349387) (xy 195.521826 -297.397964)
			(xy 195.506242 -297.444645) (xy 195.483371 -297.488222) (xy 195.453806 -297.527566) (xy 195.418313 -297.561658)
			(xy 195.37781 -297.589614) (xy 195.333348 -297.610712) (xy 195.286077 -297.624404) (xy 195.237222 -297.630336)
			(xy 195.188047 -297.628355) (xy 195.139828 -297.618511) (xy 195.093812 -297.601059) (xy 195.051191 -297.576452)
			(xy 195.01307 -297.545327) (xy 194.980435 -297.50849) (xy 194.954132 -297.466894) (xy 194.934841 -297.421618)
			(xy 194.923064 -297.373834) (xy 194.919104 -297.32478) (xy 194.580256 -297.32478) (xy 194.579761 -297.349387)
			(xy 194.571866 -297.397964) (xy 194.556282 -297.444645) (xy 194.533411 -297.488222) (xy 194.503846 -297.527566)
			(xy 194.468353 -297.561658) (xy 194.42785 -297.589614) (xy 194.383388 -297.610712) (xy 194.336117 -297.624404)
			(xy 194.287262 -297.630336) (xy 194.238087 -297.628355) (xy 194.189868 -297.618511) (xy 194.143852 -297.601059)
			(xy 194.101231 -297.576452) (xy 194.06311 -297.545327) (xy 194.030475 -297.50849) (xy 194.004172 -297.466894)
			(xy 193.984881 -297.421618) (xy 193.973104 -297.373834) (xy 193.969144 -297.32478) (xy 193.630296 -297.32478)
			(xy 193.629801 -297.349387) (xy 193.621906 -297.397964) (xy 193.606322 -297.444645) (xy 193.583451 -297.488222)
			(xy 193.553886 -297.527566) (xy 193.518393 -297.561658) (xy 193.47789 -297.589614) (xy 193.433428 -297.610712)
			(xy 193.386157 -297.624404) (xy 193.337302 -297.630336) (xy 193.288127 -297.628355) (xy 193.239908 -297.618511)
			(xy 193.193892 -297.601059) (xy 193.151271 -297.576452) (xy 193.11315 -297.545327) (xy 193.080515 -297.50849)
			(xy 193.054212 -297.466894) (xy 193.034921 -297.421618) (xy 193.023144 -297.373834) (xy 193.019184 -297.32478)
			(xy 192.680336 -297.32478) (xy 192.679841 -297.349387) (xy 192.671946 -297.397964) (xy 192.656362 -297.444645)
			(xy 192.633491 -297.488222) (xy 192.603926 -297.527566) (xy 192.568433 -297.561658) (xy 192.52793 -297.589614)
			(xy 192.483468 -297.610712) (xy 192.436197 -297.624404) (xy 192.387342 -297.630336) (xy 192.338167 -297.628355)
			(xy 192.289948 -297.618511) (xy 192.243932 -297.601059) (xy 192.201311 -297.576452) (xy 192.16319 -297.545327)
			(xy 192.130555 -297.50849) (xy 192.104252 -297.466894) (xy 192.084961 -297.421618) (xy 192.073184 -297.373834)
			(xy 192.069224 -297.32478) (xy 191.730376 -297.32478) (xy 191.729881 -297.349387) (xy 191.721986 -297.397964)
			(xy 191.706402 -297.444645) (xy 191.683531 -297.488222) (xy 191.653966 -297.527566) (xy 191.618473 -297.561658)
			(xy 191.57797 -297.589614) (xy 191.533508 -297.610712) (xy 191.486237 -297.624404) (xy 191.437382 -297.630336)
			(xy 191.388207 -297.628355) (xy 191.339988 -297.618511) (xy 191.293972 -297.601059) (xy 191.251351 -297.576452)
			(xy 191.21323 -297.545327) (xy 191.180595 -297.50849) (xy 191.154292 -297.466894) (xy 191.135001 -297.421618)
			(xy 191.123224 -297.373834) (xy 191.119264 -297.32478) (xy 190.780416 -297.32478) (xy 190.779921 -297.349387)
			(xy 190.772026 -297.397964) (xy 190.756442 -297.444645) (xy 190.733571 -297.488222) (xy 190.704006 -297.527566)
			(xy 190.668513 -297.561658) (xy 190.62801 -297.589614) (xy 190.583548 -297.610712) (xy 190.536277 -297.624404)
			(xy 190.487422 -297.630336) (xy 190.438247 -297.628355) (xy 190.390028 -297.618511) (xy 190.344012 -297.601059)
			(xy 190.301391 -297.576452) (xy 190.26327 -297.545327) (xy 190.230635 -297.50849) (xy 190.204332 -297.466894)
			(xy 190.185041 -297.421618) (xy 190.173264 -297.373834) (xy 190.169304 -297.32478) (xy 189.830202 -297.32478)
			(xy 189.829707 -297.349387) (xy 189.821812 -297.397964) (xy 189.806228 -297.444645) (xy 189.783357 -297.488222)
			(xy 189.753792 -297.527566) (xy 189.718299 -297.561658) (xy 189.677796 -297.589614) (xy 189.633334 -297.610712)
			(xy 189.586063 -297.624404) (xy 189.537208 -297.630336) (xy 189.488033 -297.628355) (xy 189.439814 -297.618511)
			(xy 189.393798 -297.601059) (xy 189.351177 -297.576452) (xy 189.313056 -297.545327) (xy 189.280421 -297.50849)
			(xy 189.254118 -297.466894) (xy 189.234827 -297.421618) (xy 189.22305 -297.373834) (xy 189.21909 -297.32478)
			(xy 188.880242 -297.32478) (xy 188.879747 -297.349387) (xy 188.871852 -297.397964) (xy 188.856268 -297.444645)
			(xy 188.833397 -297.488222) (xy 188.803832 -297.527566) (xy 188.768339 -297.561658) (xy 188.727836 -297.589614)
			(xy 188.683374 -297.610712) (xy 188.636103 -297.624404) (xy 188.587248 -297.630336) (xy 188.538073 -297.628355)
			(xy 188.489854 -297.618511) (xy 188.443838 -297.601059) (xy 188.401217 -297.576452) (xy 188.363096 -297.545327)
			(xy 188.330461 -297.50849) (xy 188.304158 -297.466894) (xy 188.284867 -297.421618) (xy 188.27309 -297.373834)
			(xy 188.26913 -297.32478) (xy 187.930282 -297.32478) (xy 187.929787 -297.349387) (xy 187.921892 -297.397964)
			(xy 187.906308 -297.444645) (xy 187.883437 -297.488222) (xy 187.853872 -297.527566) (xy 187.818379 -297.561658)
			(xy 187.777876 -297.589614) (xy 187.733414 -297.610712) (xy 187.686143 -297.624404) (xy 187.637288 -297.630336)
			(xy 187.588113 -297.628355) (xy 187.539894 -297.618511) (xy 187.493878 -297.601059) (xy 187.451257 -297.576452)
			(xy 187.413136 -297.545327) (xy 187.380501 -297.50849) (xy 187.354198 -297.466894) (xy 187.334907 -297.421618)
			(xy 187.32313 -297.373834) (xy 187.31917 -297.32478) (xy 186.030362 -297.32478) (xy 186.029867 -297.349387)
			(xy 186.021972 -297.397964) (xy 186.006388 -297.444645) (xy 185.983517 -297.488222) (xy 185.953952 -297.527566)
			(xy 185.918459 -297.561658) (xy 185.877956 -297.589614) (xy 185.833494 -297.610712) (xy 185.786223 -297.624404)
			(xy 185.737368 -297.630336) (xy 185.688193 -297.628355) (xy 185.639974 -297.618511) (xy 185.593958 -297.601059)
			(xy 185.551337 -297.576452) (xy 185.513216 -297.545327) (xy 185.480581 -297.50849) (xy 185.454278 -297.466894)
			(xy 185.434987 -297.421618) (xy 185.42321 -297.373834) (xy 185.41925 -297.32478) (xy 185.080148 -297.32478)
			(xy 185.079653 -297.349387) (xy 185.071758 -297.397964) (xy 185.056174 -297.444645) (xy 185.033303 -297.488222)
			(xy 185.003738 -297.527566) (xy 184.968245 -297.561658) (xy 184.927742 -297.589614) (xy 184.88328 -297.610712)
			(xy 184.836009 -297.624404) (xy 184.787154 -297.630336) (xy 184.737979 -297.628355) (xy 184.68976 -297.618511)
			(xy 184.643744 -297.601059) (xy 184.601123 -297.576452) (xy 184.563002 -297.545327) (xy 184.530367 -297.50849)
			(xy 184.504064 -297.466894) (xy 184.484773 -297.421618) (xy 184.472996 -297.373834) (xy 184.469036 -297.32478)
			(xy 184.130188 -297.32478) (xy 184.129693 -297.349387) (xy 184.121798 -297.397964) (xy 184.106214 -297.444645)
			(xy 184.083343 -297.488222) (xy 184.053778 -297.527566) (xy 184.018285 -297.561658) (xy 183.977782 -297.589614)
			(xy 183.93332 -297.610712) (xy 183.886049 -297.624404) (xy 183.837194 -297.630336) (xy 183.788019 -297.628355)
			(xy 183.7398 -297.618511) (xy 183.693784 -297.601059) (xy 183.651163 -297.576452) (xy 183.613042 -297.545327)
			(xy 183.580407 -297.50849) (xy 183.554104 -297.466894) (xy 183.534813 -297.421618) (xy 183.523036 -297.373834)
			(xy 183.519076 -297.32478) (xy 183.180228 -297.32478) (xy 183.179733 -297.349387) (xy 183.171838 -297.397964)
			(xy 183.156254 -297.444645) (xy 183.133383 -297.488222) (xy 183.103818 -297.527566) (xy 183.068325 -297.561658)
			(xy 183.027822 -297.589614) (xy 182.98336 -297.610712) (xy 182.936089 -297.624404) (xy 182.887234 -297.630336)
			(xy 182.838059 -297.628355) (xy 182.78984 -297.618511) (xy 182.743824 -297.601059) (xy 182.701203 -297.576452)
			(xy 182.663082 -297.545327) (xy 182.630447 -297.50849) (xy 182.604144 -297.466894) (xy 182.584853 -297.421618)
			(xy 182.573076 -297.373834) (xy 182.569116 -297.32478) (xy 182.230268 -297.32478) (xy 182.229773 -297.349387)
			(xy 182.221878 -297.397964) (xy 182.206294 -297.444645) (xy 182.183423 -297.488222) (xy 182.153858 -297.527566)
			(xy 182.118365 -297.561658) (xy 182.077862 -297.589614) (xy 182.0334 -297.610712) (xy 181.986129 -297.624404)
			(xy 181.937274 -297.630336) (xy 181.888099 -297.628355) (xy 181.83988 -297.618511) (xy 181.793864 -297.601059)
			(xy 181.751243 -297.576452) (xy 181.713122 -297.545327) (xy 181.680487 -297.50849) (xy 181.654184 -297.466894)
			(xy 181.634893 -297.421618) (xy 181.623116 -297.373834) (xy 181.619156 -297.32478) (xy 181.280308 -297.32478)
			(xy 181.279813 -297.349387) (xy 181.271918 -297.397964) (xy 181.256334 -297.444645) (xy 181.233463 -297.488222)
			(xy 181.203898 -297.527566) (xy 181.168405 -297.561658) (xy 181.127902 -297.589614) (xy 181.08344 -297.610712)
			(xy 181.036169 -297.624404) (xy 180.987314 -297.630336) (xy 180.938139 -297.628355) (xy 180.88992 -297.618511)
			(xy 180.843904 -297.601059) (xy 180.801283 -297.576452) (xy 180.763162 -297.545327) (xy 180.730527 -297.50849)
			(xy 180.704224 -297.466894) (xy 180.684933 -297.421618) (xy 180.673156 -297.373834) (xy 180.669196 -297.32478)
			(xy 180.330348 -297.32478) (xy 180.329853 -297.349387) (xy 180.321958 -297.397964) (xy 180.306374 -297.444645)
			(xy 180.283503 -297.488222) (xy 180.253938 -297.527566) (xy 180.218445 -297.561658) (xy 180.177942 -297.589614)
			(xy 180.13348 -297.610712) (xy 180.086209 -297.624404) (xy 180.037354 -297.630336) (xy 179.988179 -297.628355)
			(xy 179.93996 -297.618511) (xy 179.893944 -297.601059) (xy 179.851323 -297.576452) (xy 179.813202 -297.545327)
			(xy 179.780567 -297.50849) (xy 179.754264 -297.466894) (xy 179.734973 -297.421618) (xy 179.723196 -297.373834)
			(xy 179.719236 -297.32478) (xy 179.380388 -297.32478) (xy 179.379893 -297.349387) (xy 179.371998 -297.397964)
			(xy 179.356414 -297.444645) (xy 179.333543 -297.488222) (xy 179.303978 -297.527566) (xy 179.268485 -297.561658)
			(xy 179.227982 -297.589614) (xy 179.18352 -297.610712) (xy 179.136249 -297.624404) (xy 179.087394 -297.630336)
			(xy 179.038219 -297.628355) (xy 178.99 -297.618511) (xy 178.943984 -297.601059) (xy 178.901363 -297.576452)
			(xy 178.863242 -297.545327) (xy 178.830607 -297.50849) (xy 178.804304 -297.466894) (xy 178.785013 -297.421618)
			(xy 178.773236 -297.373834) (xy 178.769276 -297.32478) (xy 178.430174 -297.32478) (xy 178.429679 -297.349387)
			(xy 178.421784 -297.397964) (xy 178.4062 -297.444645) (xy 178.383329 -297.488222) (xy 178.353764 -297.527566)
			(xy 178.318271 -297.561658) (xy 178.277768 -297.589614) (xy 178.233306 -297.610712) (xy 178.186035 -297.624404)
			(xy 178.13718 -297.630336) (xy 178.088005 -297.628355) (xy 178.039786 -297.618511) (xy 177.99377 -297.601059)
			(xy 177.951149 -297.576452) (xy 177.913028 -297.545327) (xy 177.880393 -297.50849) (xy 177.85409 -297.466894)
			(xy 177.834799 -297.421618) (xy 177.823022 -297.373834) (xy 177.819062 -297.32478) (xy 177.480214 -297.32478)
			(xy 177.479719 -297.349387) (xy 177.471824 -297.397964) (xy 177.45624 -297.444645) (xy 177.433369 -297.488222)
			(xy 177.403804 -297.527566) (xy 177.368311 -297.561658) (xy 177.327808 -297.589614) (xy 177.283346 -297.610712)
			(xy 177.236075 -297.624404) (xy 177.18722 -297.630336) (xy 177.138045 -297.628355) (xy 177.089826 -297.618511)
			(xy 177.04381 -297.601059) (xy 177.001189 -297.576452) (xy 176.963068 -297.545327) (xy 176.930433 -297.50849)
			(xy 176.90413 -297.466894) (xy 176.884839 -297.421618) (xy 176.873062 -297.373834) (xy 176.869102 -297.32478)
			(xy 176.530254 -297.32478) (xy 176.529759 -297.349387) (xy 176.521864 -297.397964) (xy 176.50628 -297.444645)
			(xy 176.483409 -297.488222) (xy 176.453844 -297.527566) (xy 176.418351 -297.561658) (xy 176.377848 -297.589614)
			(xy 176.333386 -297.610712) (xy 176.286115 -297.624404) (xy 176.23726 -297.630336) (xy 176.188085 -297.628355)
			(xy 176.139866 -297.618511) (xy 176.09385 -297.601059) (xy 176.051229 -297.576452) (xy 176.013108 -297.545327)
			(xy 175.980473 -297.50849) (xy 175.95417 -297.466894) (xy 175.934879 -297.421618) (xy 175.923102 -297.373834)
			(xy 175.919142 -297.32478) (xy 174.630334 -297.32478) (xy 174.629839 -297.349387) (xy 174.621944 -297.397964)
			(xy 174.60636 -297.444645) (xy 174.583489 -297.488222) (xy 174.553924 -297.527566) (xy 174.518431 -297.561658)
			(xy 174.477928 -297.589614) (xy 174.433466 -297.610712) (xy 174.386195 -297.624404) (xy 174.33734 -297.630336)
			(xy 174.288165 -297.628355) (xy 174.239946 -297.618511) (xy 174.19393 -297.601059) (xy 174.151309 -297.576452)
			(xy 174.113188 -297.545327) (xy 174.080553 -297.50849) (xy 174.05425 -297.466894) (xy 174.034959 -297.421618)
			(xy 174.023182 -297.373834) (xy 174.019222 -297.32478) (xy 173.680374 -297.32478) (xy 173.679879 -297.349387)
			(xy 173.671984 -297.397964) (xy 173.6564 -297.444645) (xy 173.633529 -297.488222) (xy 173.603964 -297.527566)
			(xy 173.568471 -297.561658) (xy 173.527968 -297.589614) (xy 173.483506 -297.610712) (xy 173.436235 -297.624404)
			(xy 173.38738 -297.630336) (xy 173.338205 -297.628355) (xy 173.289986 -297.618511) (xy 173.24397 -297.601059)
			(xy 173.201349 -297.576452) (xy 173.163228 -297.545327) (xy 173.130593 -297.50849) (xy 173.10429 -297.466894)
			(xy 173.084999 -297.421618) (xy 173.073222 -297.373834) (xy 173.069262 -297.32478) (xy 172.73016 -297.32478)
			(xy 172.729665 -297.349387) (xy 172.72177 -297.397964) (xy 172.706186 -297.444645) (xy 172.683315 -297.488222)
			(xy 172.65375 -297.527566) (xy 172.618257 -297.561658) (xy 172.577754 -297.589614) (xy 172.533292 -297.610712)
			(xy 172.486021 -297.624404) (xy 172.437166 -297.630336) (xy 172.387991 -297.628355) (xy 172.339772 -297.618511)
			(xy 172.293756 -297.601059) (xy 172.251135 -297.576452) (xy 172.213014 -297.545327) (xy 172.180379 -297.50849)
			(xy 172.154076 -297.466894) (xy 172.134785 -297.421618) (xy 172.123008 -297.373834) (xy 172.119048 -297.32478)
			(xy 171.7802 -297.32478) (xy 171.779705 -297.349387) (xy 171.77181 -297.397964) (xy 171.756226 -297.444645)
			(xy 171.733355 -297.488222) (xy 171.70379 -297.527566) (xy 171.668297 -297.561658) (xy 171.627794 -297.589614)
			(xy 171.583332 -297.610712) (xy 171.536061 -297.624404) (xy 171.487206 -297.630336) (xy 171.438031 -297.628355)
			(xy 171.389812 -297.618511) (xy 171.343796 -297.601059) (xy 171.301175 -297.576452) (xy 171.263054 -297.545327)
			(xy 171.230419 -297.50849) (xy 171.204116 -297.466894) (xy 171.184825 -297.421618) (xy 171.173048 -297.373834)
			(xy 171.169088 -297.32478) (xy 170.83024 -297.32478) (xy 170.829745 -297.349387) (xy 170.82185 -297.397964)
			(xy 170.806266 -297.444645) (xy 170.783395 -297.488222) (xy 170.75383 -297.527566) (xy 170.718337 -297.561658)
			(xy 170.677834 -297.589614) (xy 170.633372 -297.610712) (xy 170.586101 -297.624404) (xy 170.537246 -297.630336)
			(xy 170.488071 -297.628355) (xy 170.439852 -297.618511) (xy 170.393836 -297.601059) (xy 170.351215 -297.576452)
			(xy 170.313094 -297.545327) (xy 170.280459 -297.50849) (xy 170.254156 -297.466894) (xy 170.234865 -297.421618)
			(xy 170.223088 -297.373834) (xy 170.219128 -297.32478) (xy 169.88028 -297.32478) (xy 169.879785 -297.349387)
			(xy 169.87189 -297.397964) (xy 169.856306 -297.444645) (xy 169.833435 -297.488222) (xy 169.80387 -297.527566)
			(xy 169.768377 -297.561658) (xy 169.727874 -297.589614) (xy 169.683412 -297.610712) (xy 169.636141 -297.624404)
			(xy 169.587286 -297.630336) (xy 169.538111 -297.628355) (xy 169.489892 -297.618511) (xy 169.443876 -297.601059)
			(xy 169.401255 -297.576452) (xy 169.363134 -297.545327) (xy 169.330499 -297.50849) (xy 169.304196 -297.466894)
			(xy 169.284905 -297.421618) (xy 169.273128 -297.373834) (xy 169.269168 -297.32478) (xy 168.93032 -297.32478)
			(xy 168.929825 -297.349387) (xy 168.92193 -297.397964) (xy 168.906346 -297.444645) (xy 168.883475 -297.488222)
			(xy 168.85391 -297.527566) (xy 168.818417 -297.561658) (xy 168.777914 -297.589614) (xy 168.733452 -297.610712)
			(xy 168.686181 -297.624404) (xy 168.637326 -297.630336) (xy 168.588151 -297.628355) (xy 168.539932 -297.618511)
			(xy 168.493916 -297.601059) (xy 168.451295 -297.576452) (xy 168.413174 -297.545327) (xy 168.380539 -297.50849)
			(xy 168.354236 -297.466894) (xy 168.334945 -297.421618) (xy 168.323168 -297.373834) (xy 168.319208 -297.32478)
			(xy 167.98036 -297.32478) (xy 167.979865 -297.349387) (xy 167.97197 -297.397964) (xy 167.956386 -297.444645)
			(xy 167.933515 -297.488222) (xy 167.90395 -297.527566) (xy 167.868457 -297.561658) (xy 167.827954 -297.589614)
			(xy 167.783492 -297.610712) (xy 167.736221 -297.624404) (xy 167.687366 -297.630336) (xy 167.638191 -297.628355)
			(xy 167.589972 -297.618511) (xy 167.543956 -297.601059) (xy 167.501335 -297.576452) (xy 167.463214 -297.545327)
			(xy 167.430579 -297.50849) (xy 167.404276 -297.466894) (xy 167.384985 -297.421618) (xy 167.373208 -297.373834)
			(xy 167.369248 -297.32478) (xy 167.0304 -297.32478) (xy 167.029905 -297.349387) (xy 167.02201 -297.397964)
			(xy 167.006426 -297.444645) (xy 166.983555 -297.488222) (xy 166.95399 -297.527566) (xy 166.918497 -297.561658)
			(xy 166.877994 -297.589614) (xy 166.833532 -297.610712) (xy 166.786261 -297.624404) (xy 166.737406 -297.630336)
			(xy 166.688231 -297.628355) (xy 166.640012 -297.618511) (xy 166.593996 -297.601059) (xy 166.551375 -297.576452)
			(xy 166.513254 -297.545327) (xy 166.480619 -297.50849) (xy 166.454316 -297.466894) (xy 166.435025 -297.421618)
			(xy 166.423248 -297.373834) (xy 166.419288 -297.32478) (xy 166.080186 -297.32478) (xy 166.079691 -297.349387)
			(xy 166.071796 -297.397964) (xy 166.056212 -297.444645) (xy 166.033341 -297.488222) (xy 166.003776 -297.527566)
			(xy 165.968283 -297.561658) (xy 165.92778 -297.589614) (xy 165.883318 -297.610712) (xy 165.836047 -297.624404)
			(xy 165.787192 -297.630336) (xy 165.738017 -297.628355) (xy 165.689798 -297.618511) (xy 165.643782 -297.601059)
			(xy 165.601161 -297.576452) (xy 165.56304 -297.545327) (xy 165.530405 -297.50849) (xy 165.504102 -297.466894)
			(xy 165.484811 -297.421618) (xy 165.473034 -297.373834) (xy 165.469074 -297.32478) (xy 165.155103 -297.32478)
			(xy 165.155104 -297.35118) (xy 165.146726 -297.403277) (xy 165.130181 -297.453383) (xy 165.105891 -297.500226)
			(xy 165.074471 -297.542618) (xy 165.036719 -297.579483) (xy 164.993591 -297.609885) (xy 164.946184 -297.633054)
			(xy 164.895699 -297.648402) (xy 164.869622 -297.65244) (xy 164.86505 -297.653202) (xy 164.854636 -297.656504)
			(xy 164.850318 -297.657774) (xy 164.826696 -297.668696) (xy 164.819838 -297.675808) (xy 164.804852 -297.691556)
			(xy 164.80026 -297.696659) (xy 164.793804 -297.708769) (xy 164.792152 -297.715432) (xy 164.790882 -297.726354)
			(xy 164.790882 -297.873166) (xy 164.79134 -297.882803) (xy 164.798506 -297.900699) (xy 164.804852 -297.907964)
			(xy 164.820092 -297.923966) (xy 164.82695 -297.931332) (xy 164.850318 -297.941746) (xy 164.854636 -297.943016)
			(xy 164.86505 -297.946318) (xy 164.869622 -297.94708) (xy 164.895688 -297.951157) (xy 164.946164 -297.966502)
			(xy 164.993563 -297.989667) (xy 165.036683 -298.020065) (xy 165.074428 -298.056923) (xy 165.105842 -298.099308)
			(xy 165.130128 -298.146143) (xy 165.146668 -298.196239) (xy 165.155045 -298.248327) (xy 165.155044 -298.27474)
			(xy 165.469074 -298.27474) (xy 165.473034 -298.225686) (xy 165.484811 -298.177902) (xy 165.504102 -298.132626)
			(xy 165.530405 -298.09103) (xy 165.56304 -298.054193) (xy 165.601161 -298.023068) (xy 165.643782 -297.998461)
			(xy 165.689798 -297.981009) (xy 165.738017 -297.971165) (xy 165.787192 -297.969184) (xy 165.836047 -297.975116)
			(xy 165.883318 -297.988808) (xy 165.92778 -298.009906) (xy 165.968283 -298.037862) (xy 166.003776 -298.071954)
			(xy 166.033341 -298.111298) (xy 166.056212 -298.154875) (xy 166.071796 -298.201556) (xy 166.079691 -298.250133)
			(xy 166.080186 -298.27474) (xy 166.419288 -298.27474) (xy 166.423248 -298.225686) (xy 166.435025 -298.177902)
			(xy 166.454316 -298.132626) (xy 166.480619 -298.09103) (xy 166.513254 -298.054193) (xy 166.551375 -298.023068)
			(xy 166.593996 -297.998461) (xy 166.640012 -297.981009) (xy 166.688231 -297.971165) (xy 166.737406 -297.969184)
			(xy 166.786261 -297.975116) (xy 166.833532 -297.988808) (xy 166.877994 -298.009906) (xy 166.918497 -298.037862)
			(xy 166.95399 -298.071954) (xy 166.983555 -298.111298) (xy 167.006426 -298.154875) (xy 167.02201 -298.201556)
			(xy 167.029905 -298.250133) (xy 167.0304 -298.27474) (xy 167.369248 -298.27474) (xy 167.373208 -298.225686)
			(xy 167.384985 -298.177902) (xy 167.404276 -298.132626) (xy 167.430579 -298.09103) (xy 167.463214 -298.054193)
			(xy 167.501335 -298.023068) (xy 167.543956 -297.998461) (xy 167.589972 -297.981009) (xy 167.638191 -297.971165)
			(xy 167.687366 -297.969184) (xy 167.736221 -297.975116) (xy 167.783492 -297.988808) (xy 167.827954 -298.009906)
			(xy 167.868457 -298.037862) (xy 167.90395 -298.071954) (xy 167.933515 -298.111298) (xy 167.956386 -298.154875)
			(xy 167.97197 -298.201556) (xy 167.979865 -298.250133) (xy 167.98036 -298.27474) (xy 168.319208 -298.27474)
			(xy 168.323168 -298.225686) (xy 168.334945 -298.177902) (xy 168.354236 -298.132626) (xy 168.380539 -298.09103)
			(xy 168.413174 -298.054193) (xy 168.451295 -298.023068) (xy 168.493916 -297.998461) (xy 168.539932 -297.981009)
			(xy 168.588151 -297.971165) (xy 168.637326 -297.969184) (xy 168.686181 -297.975116) (xy 168.733452 -297.988808)
			(xy 168.777914 -298.009906) (xy 168.818417 -298.037862) (xy 168.85391 -298.071954) (xy 168.883475 -298.111298)
			(xy 168.906346 -298.154875) (xy 168.92193 -298.201556) (xy 168.929825 -298.250133) (xy 168.93032 -298.27474)
			(xy 169.269168 -298.27474) (xy 169.273128 -298.225686) (xy 169.284905 -298.177902) (xy 169.304196 -298.132626)
			(xy 169.330499 -298.09103) (xy 169.363134 -298.054193) (xy 169.401255 -298.023068) (xy 169.443876 -297.998461)
			(xy 169.489892 -297.981009) (xy 169.538111 -297.971165) (xy 169.587286 -297.969184) (xy 169.636141 -297.975116)
			(xy 169.683412 -297.988808) (xy 169.727874 -298.009906) (xy 169.768377 -298.037862) (xy 169.80387 -298.071954)
			(xy 169.833435 -298.111298) (xy 169.856306 -298.154875) (xy 169.87189 -298.201556) (xy 169.879785 -298.250133)
			(xy 169.88028 -298.27474) (xy 170.219128 -298.27474) (xy 170.223088 -298.225686) (xy 170.234865 -298.177902)
			(xy 170.254156 -298.132626) (xy 170.280459 -298.09103) (xy 170.313094 -298.054193) (xy 170.351215 -298.023068)
			(xy 170.393836 -297.998461) (xy 170.439852 -297.981009) (xy 170.488071 -297.971165) (xy 170.537246 -297.969184)
			(xy 170.586101 -297.975116) (xy 170.633372 -297.988808) (xy 170.677834 -298.009906) (xy 170.718337 -298.037862)
			(xy 170.75383 -298.071954) (xy 170.783395 -298.111298) (xy 170.806266 -298.154875) (xy 170.82185 -298.201556)
			(xy 170.829745 -298.250133) (xy 170.83024 -298.27474) (xy 171.169088 -298.27474) (xy 171.173048 -298.225686)
			(xy 171.184825 -298.177902) (xy 171.204116 -298.132626) (xy 171.230419 -298.09103) (xy 171.263054 -298.054193)
			(xy 171.301175 -298.023068) (xy 171.343796 -297.998461) (xy 171.389812 -297.981009) (xy 171.438031 -297.971165)
			(xy 171.487206 -297.969184) (xy 171.536061 -297.975116) (xy 171.583332 -297.988808) (xy 171.627794 -298.009906)
			(xy 171.668297 -298.037862) (xy 171.70379 -298.071954) (xy 171.733355 -298.111298) (xy 171.756226 -298.154875)
			(xy 171.77181 -298.201556) (xy 171.779705 -298.250133) (xy 171.7802 -298.27474) (xy 172.119048 -298.27474)
			(xy 172.123008 -298.225686) (xy 172.134785 -298.177902) (xy 172.154076 -298.132626) (xy 172.180379 -298.09103)
			(xy 172.213014 -298.054193) (xy 172.251135 -298.023068) (xy 172.293756 -297.998461) (xy 172.339772 -297.981009)
			(xy 172.387991 -297.971165) (xy 172.437166 -297.969184) (xy 172.486021 -297.975116) (xy 172.533292 -297.988808)
			(xy 172.577754 -298.009906) (xy 172.618257 -298.037862) (xy 172.65375 -298.071954) (xy 172.683315 -298.111298)
			(xy 172.706186 -298.154875) (xy 172.72177 -298.201556) (xy 172.729665 -298.250133) (xy 172.73016 -298.27474)
			(xy 173.069262 -298.27474) (xy 173.073222 -298.225686) (xy 173.084999 -298.177902) (xy 173.10429 -298.132626)
			(xy 173.130593 -298.09103) (xy 173.163228 -298.054193) (xy 173.201349 -298.023068) (xy 173.24397 -297.998461)
			(xy 173.289986 -297.981009) (xy 173.338205 -297.971165) (xy 173.38738 -297.969184) (xy 173.436235 -297.975116)
			(xy 173.483506 -297.988808) (xy 173.527968 -298.009906) (xy 173.568471 -298.037862) (xy 173.603964 -298.071954)
			(xy 173.633529 -298.111298) (xy 173.6564 -298.154875) (xy 173.671984 -298.201556) (xy 173.679879 -298.250133)
			(xy 173.680374 -298.27474) (xy 174.019222 -298.27474) (xy 174.023182 -298.225686) (xy 174.034959 -298.177902)
			(xy 174.05425 -298.132626) (xy 174.080553 -298.09103) (xy 174.113188 -298.054193) (xy 174.151309 -298.023068)
			(xy 174.19393 -297.998461) (xy 174.239946 -297.981009) (xy 174.288165 -297.971165) (xy 174.33734 -297.969184)
			(xy 174.386195 -297.975116) (xy 174.433466 -297.988808) (xy 174.477928 -298.009906) (xy 174.518431 -298.037862)
			(xy 174.553924 -298.071954) (xy 174.583489 -298.111298) (xy 174.60636 -298.154875) (xy 174.621944 -298.201556)
			(xy 174.629839 -298.250133) (xy 174.630334 -298.27474) (xy 175.919142 -298.27474) (xy 175.923102 -298.225686)
			(xy 175.934879 -298.177902) (xy 175.95417 -298.132626) (xy 175.980473 -298.09103) (xy 176.013108 -298.054193)
			(xy 176.051229 -298.023068) (xy 176.09385 -297.998461) (xy 176.139866 -297.981009) (xy 176.188085 -297.971165)
			(xy 176.23726 -297.969184) (xy 176.286115 -297.975116) (xy 176.333386 -297.988808) (xy 176.377848 -298.009906)
			(xy 176.418351 -298.037862) (xy 176.453844 -298.071954) (xy 176.483409 -298.111298) (xy 176.50628 -298.154875)
			(xy 176.521864 -298.201556) (xy 176.529759 -298.250133) (xy 176.530254 -298.27474) (xy 176.869102 -298.27474)
			(xy 176.873062 -298.225686) (xy 176.884839 -298.177902) (xy 176.90413 -298.132626) (xy 176.930433 -298.09103)
			(xy 176.963068 -298.054193) (xy 177.001189 -298.023068) (xy 177.04381 -297.998461) (xy 177.089826 -297.981009)
			(xy 177.138045 -297.971165) (xy 177.18722 -297.969184) (xy 177.236075 -297.975116) (xy 177.283346 -297.988808)
			(xy 177.327808 -298.009906) (xy 177.368311 -298.037862) (xy 177.403804 -298.071954) (xy 177.433369 -298.111298)
			(xy 177.45624 -298.154875) (xy 177.471824 -298.201556) (xy 177.479719 -298.250133) (xy 177.480214 -298.27474)
			(xy 177.819062 -298.27474) (xy 177.823022 -298.225686) (xy 177.834799 -298.177902) (xy 177.85409 -298.132626)
			(xy 177.880393 -298.09103) (xy 177.913028 -298.054193) (xy 177.951149 -298.023068) (xy 177.99377 -297.998461)
			(xy 178.039786 -297.981009) (xy 178.088005 -297.971165) (xy 178.13718 -297.969184) (xy 178.186035 -297.975116)
			(xy 178.233306 -297.988808) (xy 178.277768 -298.009906) (xy 178.318271 -298.037862) (xy 178.353764 -298.071954)
			(xy 178.383329 -298.111298) (xy 178.4062 -298.154875) (xy 178.421784 -298.201556) (xy 178.429679 -298.250133)
			(xy 178.430174 -298.27474) (xy 178.769276 -298.27474) (xy 178.773236 -298.225686) (xy 178.785013 -298.177902)
			(xy 178.804304 -298.132626) (xy 178.830607 -298.09103) (xy 178.863242 -298.054193) (xy 178.901363 -298.023068)
			(xy 178.943984 -297.998461) (xy 178.99 -297.981009) (xy 179.038219 -297.971165) (xy 179.087394 -297.969184)
			(xy 179.136249 -297.975116) (xy 179.18352 -297.988808) (xy 179.227982 -298.009906) (xy 179.268485 -298.037862)
			(xy 179.303978 -298.071954) (xy 179.333543 -298.111298) (xy 179.356414 -298.154875) (xy 179.371998 -298.201556)
			(xy 179.379893 -298.250133) (xy 179.380388 -298.27474) (xy 179.719236 -298.27474) (xy 179.723196 -298.225686)
			(xy 179.734973 -298.177902) (xy 179.754264 -298.132626) (xy 179.780567 -298.09103) (xy 179.813202 -298.054193)
			(xy 179.851323 -298.023068) (xy 179.893944 -297.998461) (xy 179.93996 -297.981009) (xy 179.988179 -297.971165)
			(xy 180.037354 -297.969184) (xy 180.086209 -297.975116) (xy 180.13348 -297.988808) (xy 180.177942 -298.009906)
			(xy 180.218445 -298.037862) (xy 180.253938 -298.071954) (xy 180.283503 -298.111298) (xy 180.306374 -298.154875)
			(xy 180.321958 -298.201556) (xy 180.329853 -298.250133) (xy 180.330348 -298.27474) (xy 180.669196 -298.27474)
			(xy 180.673156 -298.225686) (xy 180.684933 -298.177902) (xy 180.704224 -298.132626) (xy 180.730527 -298.09103)
			(xy 180.763162 -298.054193) (xy 180.801283 -298.023068) (xy 180.843904 -297.998461) (xy 180.88992 -297.981009)
			(xy 180.938139 -297.971165) (xy 180.987314 -297.969184) (xy 181.036169 -297.975116) (xy 181.08344 -297.988808)
			(xy 181.127902 -298.009906) (xy 181.168405 -298.037862) (xy 181.203898 -298.071954) (xy 181.233463 -298.111298)
			(xy 181.256334 -298.154875) (xy 181.271918 -298.201556) (xy 181.279813 -298.250133) (xy 181.280308 -298.27474)
			(xy 181.619156 -298.27474) (xy 181.623116 -298.225686) (xy 181.634893 -298.177902) (xy 181.654184 -298.132626)
			(xy 181.680487 -298.09103) (xy 181.713122 -298.054193) (xy 181.751243 -298.023068) (xy 181.793864 -297.998461)
			(xy 181.83988 -297.981009) (xy 181.888099 -297.971165) (xy 181.937274 -297.969184) (xy 181.986129 -297.975116)
			(xy 182.0334 -297.988808) (xy 182.077862 -298.009906) (xy 182.118365 -298.037862) (xy 182.153858 -298.071954)
			(xy 182.183423 -298.111298) (xy 182.206294 -298.154875) (xy 182.221878 -298.201556) (xy 182.229773 -298.250133)
			(xy 182.230268 -298.27474) (xy 182.569116 -298.27474) (xy 182.573076 -298.225686) (xy 182.584853 -298.177902)
			(xy 182.604144 -298.132626) (xy 182.630447 -298.09103) (xy 182.663082 -298.054193) (xy 182.701203 -298.023068)
			(xy 182.743824 -297.998461) (xy 182.78984 -297.981009) (xy 182.838059 -297.971165) (xy 182.887234 -297.969184)
			(xy 182.936089 -297.975116) (xy 182.98336 -297.988808) (xy 183.027822 -298.009906) (xy 183.068325 -298.037862)
			(xy 183.103818 -298.071954) (xy 183.133383 -298.111298) (xy 183.156254 -298.154875) (xy 183.171838 -298.201556)
			(xy 183.179733 -298.250133) (xy 183.180228 -298.27474) (xy 183.519076 -298.27474) (xy 183.523036 -298.225686)
			(xy 183.534813 -298.177902) (xy 183.554104 -298.132626) (xy 183.580407 -298.09103) (xy 183.613042 -298.054193)
			(xy 183.651163 -298.023068) (xy 183.693784 -297.998461) (xy 183.7398 -297.981009) (xy 183.788019 -297.971165)
			(xy 183.837194 -297.969184) (xy 183.886049 -297.975116) (xy 183.93332 -297.988808) (xy 183.977782 -298.009906)
			(xy 184.018285 -298.037862) (xy 184.053778 -298.071954) (xy 184.083343 -298.111298) (xy 184.106214 -298.154875)
			(xy 184.121798 -298.201556) (xy 184.129693 -298.250133) (xy 184.130188 -298.27474) (xy 184.469036 -298.27474)
			(xy 184.472996 -298.225686) (xy 184.484773 -298.177902) (xy 184.504064 -298.132626) (xy 184.530367 -298.09103)
			(xy 184.563002 -298.054193) (xy 184.601123 -298.023068) (xy 184.643744 -297.998461) (xy 184.68976 -297.981009)
			(xy 184.737979 -297.971165) (xy 184.787154 -297.969184) (xy 184.836009 -297.975116) (xy 184.88328 -297.988808)
			(xy 184.927742 -298.009906) (xy 184.968245 -298.037862) (xy 185.003738 -298.071954) (xy 185.033303 -298.111298)
			(xy 185.056174 -298.154875) (xy 185.071758 -298.201556) (xy 185.079653 -298.250133) (xy 185.080148 -298.27474)
			(xy 185.41925 -298.27474) (xy 185.42321 -298.225686) (xy 185.434987 -298.177902) (xy 185.454278 -298.132626)
			(xy 185.480581 -298.09103) (xy 185.513216 -298.054193) (xy 185.551337 -298.023068) (xy 185.593958 -297.998461)
			(xy 185.639974 -297.981009) (xy 185.688193 -297.971165) (xy 185.737368 -297.969184) (xy 185.786223 -297.975116)
			(xy 185.833494 -297.988808) (xy 185.877956 -298.009906) (xy 185.918459 -298.037862) (xy 185.953952 -298.071954)
			(xy 185.983517 -298.111298) (xy 186.006388 -298.154875) (xy 186.021972 -298.201556) (xy 186.029867 -298.250133)
			(xy 186.030362 -298.27474) (xy 187.31917 -298.27474) (xy 187.32313 -298.225686) (xy 187.334907 -298.177902)
			(xy 187.354198 -298.132626) (xy 187.380501 -298.09103) (xy 187.413136 -298.054193) (xy 187.451257 -298.023068)
			(xy 187.493878 -297.998461) (xy 187.539894 -297.981009) (xy 187.588113 -297.971165) (xy 187.637288 -297.969184)
			(xy 187.686143 -297.975116) (xy 187.733414 -297.988808) (xy 187.777876 -298.009906) (xy 187.818379 -298.037862)
			(xy 187.853872 -298.071954) (xy 187.883437 -298.111298) (xy 187.906308 -298.154875) (xy 187.921892 -298.201556)
			(xy 187.929787 -298.250133) (xy 187.930282 -298.27474) (xy 188.26913 -298.27474) (xy 188.27309 -298.225686)
			(xy 188.284867 -298.177902) (xy 188.304158 -298.132626) (xy 188.330461 -298.09103) (xy 188.363096 -298.054193)
			(xy 188.401217 -298.023068) (xy 188.443838 -297.998461) (xy 188.489854 -297.981009) (xy 188.538073 -297.971165)
			(xy 188.587248 -297.969184) (xy 188.636103 -297.975116) (xy 188.683374 -297.988808) (xy 188.727836 -298.009906)
			(xy 188.768339 -298.037862) (xy 188.803832 -298.071954) (xy 188.833397 -298.111298) (xy 188.856268 -298.154875)
			(xy 188.871852 -298.201556) (xy 188.879747 -298.250133) (xy 188.880242 -298.27474) (xy 189.21909 -298.27474)
			(xy 189.22305 -298.225686) (xy 189.234827 -298.177902) (xy 189.254118 -298.132626) (xy 189.280421 -298.09103)
			(xy 189.313056 -298.054193) (xy 189.351177 -298.023068) (xy 189.393798 -297.998461) (xy 189.439814 -297.981009)
			(xy 189.488033 -297.971165) (xy 189.537208 -297.969184) (xy 189.586063 -297.975116) (xy 189.633334 -297.988808)
			(xy 189.677796 -298.009906) (xy 189.718299 -298.037862) (xy 189.753792 -298.071954) (xy 189.783357 -298.111298)
			(xy 189.806228 -298.154875) (xy 189.821812 -298.201556) (xy 189.829707 -298.250133) (xy 189.830202 -298.27474)
			(xy 190.16905 -298.27474) (xy 190.17301 -298.225686) (xy 190.184787 -298.177902) (xy 190.204078 -298.132626)
			(xy 190.230381 -298.09103) (xy 190.263016 -298.054193) (xy 190.301137 -298.023068) (xy 190.343758 -297.998461)
			(xy 190.389774 -297.981009) (xy 190.437993 -297.971165) (xy 190.487168 -297.969184) (xy 190.536023 -297.975116)
			(xy 190.583294 -297.988808) (xy 190.627756 -298.009906) (xy 190.668259 -298.037862) (xy 190.703752 -298.071954)
			(xy 190.733317 -298.111298) (xy 190.756188 -298.154875) (xy 190.771772 -298.201556) (xy 190.779667 -298.250133)
			(xy 190.780162 -298.27474) (xy 191.119264 -298.27474) (xy 191.123224 -298.225686) (xy 191.135001 -298.177902)
			(xy 191.154292 -298.132626) (xy 191.180595 -298.09103) (xy 191.21323 -298.054193) (xy 191.251351 -298.023068)
			(xy 191.293972 -297.998461) (xy 191.339988 -297.981009) (xy 191.388207 -297.971165) (xy 191.437382 -297.969184)
			(xy 191.486237 -297.975116) (xy 191.533508 -297.988808) (xy 191.57797 -298.009906) (xy 191.618473 -298.037862)
			(xy 191.653966 -298.071954) (xy 191.683531 -298.111298) (xy 191.706402 -298.154875) (xy 191.721986 -298.201556)
			(xy 191.729881 -298.250133) (xy 191.730376 -298.27474) (xy 192.069224 -298.27474) (xy 192.073184 -298.225686)
			(xy 192.084961 -298.177902) (xy 192.104252 -298.132626) (xy 192.130555 -298.09103) (xy 192.16319 -298.054193)
			(xy 192.201311 -298.023068) (xy 192.243932 -297.998461) (xy 192.289948 -297.981009) (xy 192.338167 -297.971165)
			(xy 192.387342 -297.969184) (xy 192.436197 -297.975116) (xy 192.483468 -297.988808) (xy 192.52793 -298.009906)
			(xy 192.568433 -298.037862) (xy 192.603926 -298.071954) (xy 192.633491 -298.111298) (xy 192.656362 -298.154875)
			(xy 192.671946 -298.201556) (xy 192.679841 -298.250133) (xy 192.680336 -298.27474) (xy 193.019184 -298.27474)
			(xy 193.023144 -298.225686) (xy 193.034921 -298.177902) (xy 193.054212 -298.132626) (xy 193.080515 -298.09103)
			(xy 193.11315 -298.054193) (xy 193.151271 -298.023068) (xy 193.193892 -297.998461) (xy 193.239908 -297.981009)
			(xy 193.288127 -297.971165) (xy 193.337302 -297.969184) (xy 193.386157 -297.975116) (xy 193.433428 -297.988808)
			(xy 193.47789 -298.009906) (xy 193.518393 -298.037862) (xy 193.553886 -298.071954) (xy 193.583451 -298.111298)
			(xy 193.606322 -298.154875) (xy 193.621906 -298.201556) (xy 193.629801 -298.250133) (xy 193.630296 -298.27474)
			(xy 193.969144 -298.27474) (xy 193.973104 -298.225686) (xy 193.984881 -298.177902) (xy 194.004172 -298.132626)
			(xy 194.030475 -298.09103) (xy 194.06311 -298.054193) (xy 194.101231 -298.023068) (xy 194.143852 -297.998461)
			(xy 194.189868 -297.981009) (xy 194.238087 -297.971165) (xy 194.287262 -297.969184) (xy 194.336117 -297.975116)
			(xy 194.383388 -297.988808) (xy 194.42785 -298.009906) (xy 194.468353 -298.037862) (xy 194.503846 -298.071954)
			(xy 194.533411 -298.111298) (xy 194.556282 -298.154875) (xy 194.571866 -298.201556) (xy 194.579761 -298.250133)
			(xy 194.580256 -298.27474) (xy 194.919104 -298.27474) (xy 194.923064 -298.225686) (xy 194.934841 -298.177902)
			(xy 194.954132 -298.132626) (xy 194.980435 -298.09103) (xy 195.01307 -298.054193) (xy 195.051191 -298.023068)
			(xy 195.093812 -297.998461) (xy 195.139828 -297.981009) (xy 195.188047 -297.971165) (xy 195.237222 -297.969184)
			(xy 195.286077 -297.975116) (xy 195.333348 -297.988808) (xy 195.37781 -298.009906) (xy 195.418313 -298.037862)
			(xy 195.453806 -298.071954) (xy 195.483371 -298.111298) (xy 195.506242 -298.154875) (xy 195.521826 -298.201556)
			(xy 195.529721 -298.250133) (xy 195.530216 -298.27474) (xy 195.869064 -298.27474) (xy 195.873024 -298.225686)
			(xy 195.884801 -298.177902) (xy 195.904092 -298.132626) (xy 195.930395 -298.09103) (xy 195.96303 -298.054193)
			(xy 196.001151 -298.023068) (xy 196.043772 -297.998461) (xy 196.089788 -297.981009) (xy 196.138007 -297.971165)
			(xy 196.187182 -297.969184) (xy 196.236037 -297.975116) (xy 196.283308 -297.988808) (xy 196.32777 -298.009906)
			(xy 196.368273 -298.037862) (xy 196.403766 -298.071954) (xy 196.433331 -298.111298) (xy 196.456202 -298.154875)
			(xy 196.471786 -298.201556) (xy 196.479681 -298.250133) (xy 196.480176 -298.27474) (xy 196.819278 -298.27474)
			(xy 196.823238 -298.225686) (xy 196.835015 -298.177902) (xy 196.854306 -298.132626) (xy 196.880609 -298.09103)
			(xy 196.913244 -298.054193) (xy 196.951365 -298.023068) (xy 196.993986 -297.998461) (xy 197.040002 -297.981009)
			(xy 197.088221 -297.971165) (xy 197.137396 -297.969184) (xy 197.186251 -297.975116) (xy 197.233522 -297.988808)
			(xy 197.277984 -298.009906) (xy 197.318487 -298.037862) (xy 197.35398 -298.071954) (xy 197.383545 -298.111298)
			(xy 197.406416 -298.154875) (xy 197.422 -298.201556) (xy 197.429895 -298.250133) (xy 197.43039 -298.27474)
			(xy 197.769238 -298.27474) (xy 197.773198 -298.225686) (xy 197.784975 -298.177902) (xy 197.804266 -298.132626)
			(xy 197.830569 -298.09103) (xy 197.863204 -298.054193) (xy 197.901325 -298.023068) (xy 197.943946 -297.998461)
			(xy 197.989962 -297.981009) (xy 198.038181 -297.971165) (xy 198.087356 -297.969184) (xy 198.136211 -297.975116)
			(xy 198.183482 -297.988808) (xy 198.227944 -298.009906) (xy 198.268447 -298.037862) (xy 198.30394 -298.071954)
			(xy 198.333505 -298.111298) (xy 198.356376 -298.154875) (xy 198.37196 -298.201556) (xy 198.379855 -298.250133)
			(xy 198.38035 -298.27474) (xy 198.719198 -298.27474) (xy 198.723158 -298.225686) (xy 198.734935 -298.177902)
			(xy 198.754226 -298.132626) (xy 198.780529 -298.09103) (xy 198.813164 -298.054193) (xy 198.851285 -298.023068)
			(xy 198.893906 -297.998461) (xy 198.939922 -297.981009) (xy 198.988141 -297.971165) (xy 199.037316 -297.969184)
			(xy 199.086171 -297.975116) (xy 199.133442 -297.988808) (xy 199.177904 -298.009906) (xy 199.218407 -298.037862)
			(xy 199.2539 -298.071954) (xy 199.283465 -298.111298) (xy 199.306336 -298.154875) (xy 199.32192 -298.201556)
			(xy 199.329815 -298.250133) (xy 199.33031 -298.27474) (xy 199.329815 -298.299347) (xy 199.32192 -298.347924)
			(xy 199.321344 -298.349649) (xy 199.767688 -298.349649) (xy 199.767688 -298.296351) (xy 199.775631 -298.243647)
			(xy 199.791341 -298.192717) (xy 199.814467 -298.144696) (xy 199.844491 -298.100659) (xy 199.880743 -298.061588)
			(xy 199.922414 -298.028357) (xy 199.968572 -298.001708) (xy 200.018186 -297.982236) (xy 200.070148 -297.970376)
			(xy 200.123298 -297.966393) (xy 200.176448 -297.970376) (xy 200.22841 -297.982236) (xy 200.235858 -297.985159)
			(xy 200.882748 -297.985159) (xy 200.882748 -297.931861) (xy 200.890691 -297.879157) (xy 200.906401 -297.828227)
			(xy 200.929527 -297.780206) (xy 200.959551 -297.736169) (xy 200.995803 -297.697098) (xy 201.037474 -297.663867)
			(xy 201.083632 -297.637218) (xy 201.133246 -297.617746) (xy 201.185208 -297.605886) (xy 201.238358 -297.601903)
			(xy 201.291508 -297.605886) (xy 201.34347 -297.617746) (xy 201.393084 -297.637218) (xy 201.439242 -297.663867)
			(xy 201.473008 -297.690794) (xy 202.399644 -297.690794) (xy 202.403715 -297.635172) (xy 202.415841 -297.580735)
			(xy 202.435764 -297.528644) (xy 202.46306 -297.480009) (xy 202.497146 -297.435866) (xy 202.537295 -297.397157)
			(xy 202.582653 -297.364706) (xy 202.632253 -297.339205) (xy 202.685037 -297.321198) (xy 202.73988 -297.311068)
			(xy 202.795614 -297.309031) (xy 202.851051 -297.315131) (xy 202.905008 -297.329237) (xy 202.956337 -297.351049)
			(xy 202.995283 -297.374818) (xy 208.715862 -297.374818) (xy 208.719933 -297.319196) (xy 208.732059 -297.264759)
			(xy 208.751982 -297.212668) (xy 208.779278 -297.164033) (xy 208.813364 -297.11989) (xy 208.853513 -297.081181)
			(xy 208.898871 -297.04873) (xy 208.948471 -297.023229) (xy 209.001255 -297.005222) (xy 209.056098 -296.995092)
			(xy 209.111832 -296.993055) (xy 209.167269 -296.999155) (xy 209.221226 -297.013261) (xy 209.272555 -297.035073)
			(xy 209.320161 -297.064127) (xy 209.363029 -297.099802) (xy 209.400246 -297.141339) (xy 209.431019 -297.187852)
			(xy 209.454691 -297.238349) (xy 209.470759 -297.291756) (xy 209.478879 -297.346932) (xy 209.479388 -297.374818)
			(xy 209.478879 -297.402704) (xy 209.470759 -297.45788) (xy 209.454691 -297.511287) (xy 209.431019 -297.561784)
			(xy 209.400246 -297.608297) (xy 209.363029 -297.649834) (xy 209.320161 -297.685509) (xy 209.272555 -297.714563)
			(xy 209.221226 -297.736375) (xy 209.167269 -297.750481) (xy 209.111832 -297.756581) (xy 209.056098 -297.754544)
			(xy 209.001255 -297.744414) (xy 208.948471 -297.726407) (xy 208.898871 -297.700906) (xy 208.853513 -297.668455)
			(xy 208.813364 -297.629746) (xy 208.779278 -297.585603) (xy 208.751982 -297.536968) (xy 208.732059 -297.484877)
			(xy 208.719933 -297.43044) (xy 208.715862 -297.374818) (xy 202.995283 -297.374818) (xy 203.003943 -297.380103)
			(xy 203.046811 -297.415778) (xy 203.084028 -297.457315) (xy 203.114801 -297.503828) (xy 203.138473 -297.554325)
			(xy 203.154541 -297.607732) (xy 203.162661 -297.662908) (xy 203.16317 -297.690794) (xy 203.162661 -297.71868)
			(xy 203.154541 -297.773856) (xy 203.138473 -297.827263) (xy 203.114801 -297.87776) (xy 203.084028 -297.924273)
			(xy 203.046811 -297.96581) (xy 203.003943 -298.001485) (xy 202.956337 -298.030539) (xy 202.905008 -298.052351)
			(xy 202.851051 -298.066457) (xy 202.795614 -298.072557) (xy 202.73988 -298.07052) (xy 202.685037 -298.06039)
			(xy 202.632253 -298.042383) (xy 202.582653 -298.016882) (xy 202.537295 -297.984431) (xy 202.497146 -297.945722)
			(xy 202.46306 -297.901579) (xy 202.435764 -297.852944) (xy 202.415841 -297.800853) (xy 202.403715 -297.746416)
			(xy 202.399644 -297.690794) (xy 201.473008 -297.690794) (xy 201.480913 -297.697098) (xy 201.517165 -297.736169)
			(xy 201.547189 -297.780206) (xy 201.570315 -297.828227) (xy 201.586025 -297.879157) (xy 201.593968 -297.931861)
			(xy 201.594466 -297.95851) (xy 201.593968 -297.985159) (xy 201.586025 -298.037863) (xy 201.570315 -298.088793)
			(xy 201.547189 -298.136814) (xy 201.517165 -298.180851) (xy 201.480913 -298.219922) (xy 201.439242 -298.253153)
			(xy 201.393084 -298.279802) (xy 201.34347 -298.299274) (xy 201.291508 -298.311134) (xy 201.238358 -298.315118)
			(xy 201.185208 -298.311134) (xy 201.133246 -298.299274) (xy 201.083632 -298.279802) (xy 201.037474 -298.253153)
			(xy 200.995803 -298.219922) (xy 200.959551 -298.180851) (xy 200.929527 -298.136814) (xy 200.906401 -298.088793)
			(xy 200.890691 -298.037863) (xy 200.882748 -297.985159) (xy 200.235858 -297.985159) (xy 200.278024 -298.001708)
			(xy 200.324182 -298.028357) (xy 200.365853 -298.061588) (xy 200.402105 -298.100659) (xy 200.432129 -298.144696)
			(xy 200.455255 -298.192717) (xy 200.470965 -298.243647) (xy 200.478908 -298.296351) (xy 200.479406 -298.323)
			(xy 200.478908 -298.349649) (xy 200.470965 -298.402353) (xy 200.455255 -298.453283) (xy 200.432129 -298.501304)
			(xy 200.402105 -298.545341) (xy 200.365853 -298.584412) (xy 200.324182 -298.617643) (xy 200.278024 -298.644292)
			(xy 200.22841 -298.663764) (xy 200.176448 -298.675624) (xy 200.123298 -298.679608) (xy 200.070148 -298.675624)
			(xy 200.018186 -298.663764) (xy 199.968572 -298.644292) (xy 199.922414 -298.617643) (xy 199.880743 -298.584412)
			(xy 199.844491 -298.545341) (xy 199.814467 -298.501304) (xy 199.791341 -298.453283) (xy 199.775631 -298.402353)
			(xy 199.767688 -298.349649) (xy 199.321344 -298.349649) (xy 199.306336 -298.394605) (xy 199.283465 -298.438182)
			(xy 199.2539 -298.477526) (xy 199.218407 -298.511618) (xy 199.177904 -298.539574) (xy 199.133442 -298.560672)
			(xy 199.086171 -298.574364) (xy 199.037316 -298.580296) (xy 198.988141 -298.578315) (xy 198.939922 -298.568471)
			(xy 198.893906 -298.551019) (xy 198.851285 -298.526412) (xy 198.813164 -298.495287) (xy 198.780529 -298.45845)
			(xy 198.754226 -298.416854) (xy 198.734935 -298.371578) (xy 198.723158 -298.323794) (xy 198.719198 -298.27474)
			(xy 198.38035 -298.27474) (xy 198.379855 -298.299347) (xy 198.37196 -298.347924) (xy 198.356376 -298.394605)
			(xy 198.333505 -298.438182) (xy 198.30394 -298.477526) (xy 198.268447 -298.511618) (xy 198.227944 -298.539574)
			(xy 198.183482 -298.560672) (xy 198.136211 -298.574364) (xy 198.087356 -298.580296) (xy 198.038181 -298.578315)
			(xy 197.989962 -298.568471) (xy 197.943946 -298.551019) (xy 197.901325 -298.526412) (xy 197.863204 -298.495287)
			(xy 197.830569 -298.45845) (xy 197.804266 -298.416854) (xy 197.784975 -298.371578) (xy 197.773198 -298.323794)
			(xy 197.769238 -298.27474) (xy 197.43039 -298.27474) (xy 197.429895 -298.299347) (xy 197.422 -298.347924)
			(xy 197.406416 -298.394605) (xy 197.383545 -298.438182) (xy 197.35398 -298.477526) (xy 197.318487 -298.511618)
			(xy 197.277984 -298.539574) (xy 197.233522 -298.560672) (xy 197.186251 -298.574364) (xy 197.137396 -298.580296)
			(xy 197.088221 -298.578315) (xy 197.040002 -298.568471) (xy 196.993986 -298.551019) (xy 196.951365 -298.526412)
			(xy 196.913244 -298.495287) (xy 196.880609 -298.45845) (xy 196.854306 -298.416854) (xy 196.835015 -298.371578)
			(xy 196.823238 -298.323794) (xy 196.819278 -298.27474) (xy 196.480176 -298.27474) (xy 196.479681 -298.299347)
			(xy 196.471786 -298.347924) (xy 196.456202 -298.394605) (xy 196.433331 -298.438182) (xy 196.403766 -298.477526)
			(xy 196.368273 -298.511618) (xy 196.32777 -298.539574) (xy 196.283308 -298.560672) (xy 196.236037 -298.574364)
			(xy 196.187182 -298.580296) (xy 196.138007 -298.578315) (xy 196.089788 -298.568471) (xy 196.043772 -298.551019)
			(xy 196.001151 -298.526412) (xy 195.96303 -298.495287) (xy 195.930395 -298.45845) (xy 195.904092 -298.416854)
			(xy 195.884801 -298.371578) (xy 195.873024 -298.323794) (xy 195.869064 -298.27474) (xy 195.530216 -298.27474)
			(xy 195.529721 -298.299347) (xy 195.521826 -298.347924) (xy 195.506242 -298.394605) (xy 195.483371 -298.438182)
			(xy 195.453806 -298.477526) (xy 195.418313 -298.511618) (xy 195.37781 -298.539574) (xy 195.333348 -298.560672)
			(xy 195.286077 -298.574364) (xy 195.237222 -298.580296) (xy 195.188047 -298.578315) (xy 195.139828 -298.568471)
			(xy 195.093812 -298.551019) (xy 195.051191 -298.526412) (xy 195.01307 -298.495287) (xy 194.980435 -298.45845)
			(xy 194.954132 -298.416854) (xy 194.934841 -298.371578) (xy 194.923064 -298.323794) (xy 194.919104 -298.27474)
			(xy 194.580256 -298.27474) (xy 194.579761 -298.299347) (xy 194.571866 -298.347924) (xy 194.556282 -298.394605)
			(xy 194.533411 -298.438182) (xy 194.503846 -298.477526) (xy 194.468353 -298.511618) (xy 194.42785 -298.539574)
			(xy 194.383388 -298.560672) (xy 194.336117 -298.574364) (xy 194.287262 -298.580296) (xy 194.238087 -298.578315)
			(xy 194.189868 -298.568471) (xy 194.143852 -298.551019) (xy 194.101231 -298.526412) (xy 194.06311 -298.495287)
			(xy 194.030475 -298.45845) (xy 194.004172 -298.416854) (xy 193.984881 -298.371578) (xy 193.973104 -298.323794)
			(xy 193.969144 -298.27474) (xy 193.630296 -298.27474) (xy 193.629801 -298.299347) (xy 193.621906 -298.347924)
			(xy 193.606322 -298.394605) (xy 193.583451 -298.438182) (xy 193.553886 -298.477526) (xy 193.518393 -298.511618)
			(xy 193.47789 -298.539574) (xy 193.433428 -298.560672) (xy 193.386157 -298.574364) (xy 193.337302 -298.580296)
			(xy 193.288127 -298.578315) (xy 193.239908 -298.568471) (xy 193.193892 -298.551019) (xy 193.151271 -298.526412)
			(xy 193.11315 -298.495287) (xy 193.080515 -298.45845) (xy 193.054212 -298.416854) (xy 193.034921 -298.371578)
			(xy 193.023144 -298.323794) (xy 193.019184 -298.27474) (xy 192.680336 -298.27474) (xy 192.679841 -298.299347)
			(xy 192.671946 -298.347924) (xy 192.656362 -298.394605) (xy 192.633491 -298.438182) (xy 192.603926 -298.477526)
			(xy 192.568433 -298.511618) (xy 192.52793 -298.539574) (xy 192.483468 -298.560672) (xy 192.436197 -298.574364)
			(xy 192.387342 -298.580296) (xy 192.338167 -298.578315) (xy 192.289948 -298.568471) (xy 192.243932 -298.551019)
			(xy 192.201311 -298.526412) (xy 192.16319 -298.495287) (xy 192.130555 -298.45845) (xy 192.104252 -298.416854)
			(xy 192.084961 -298.371578) (xy 192.073184 -298.323794) (xy 192.069224 -298.27474) (xy 191.730376 -298.27474)
			(xy 191.729881 -298.299347) (xy 191.721986 -298.347924) (xy 191.706402 -298.394605) (xy 191.683531 -298.438182)
			(xy 191.653966 -298.477526) (xy 191.618473 -298.511618) (xy 191.57797 -298.539574) (xy 191.533508 -298.560672)
			(xy 191.486237 -298.574364) (xy 191.437382 -298.580296) (xy 191.388207 -298.578315) (xy 191.339988 -298.568471)
			(xy 191.293972 -298.551019) (xy 191.251351 -298.526412) (xy 191.21323 -298.495287) (xy 191.180595 -298.45845)
			(xy 191.154292 -298.416854) (xy 191.135001 -298.371578) (xy 191.123224 -298.323794) (xy 191.119264 -298.27474)
			(xy 190.780162 -298.27474) (xy 190.779667 -298.299347) (xy 190.771772 -298.347924) (xy 190.756188 -298.394605)
			(xy 190.733317 -298.438182) (xy 190.703752 -298.477526) (xy 190.668259 -298.511618) (xy 190.627756 -298.539574)
			(xy 190.583294 -298.560672) (xy 190.536023 -298.574364) (xy 190.487168 -298.580296) (xy 190.437993 -298.578315)
			(xy 190.389774 -298.568471) (xy 190.343758 -298.551019) (xy 190.301137 -298.526412) (xy 190.263016 -298.495287)
			(xy 190.230381 -298.45845) (xy 190.204078 -298.416854) (xy 190.184787 -298.371578) (xy 190.17301 -298.323794)
			(xy 190.16905 -298.27474) (xy 189.830202 -298.27474) (xy 189.829707 -298.299347) (xy 189.821812 -298.347924)
			(xy 189.806228 -298.394605) (xy 189.783357 -298.438182) (xy 189.753792 -298.477526) (xy 189.718299 -298.511618)
			(xy 189.677796 -298.539574) (xy 189.633334 -298.560672) (xy 189.586063 -298.574364) (xy 189.537208 -298.580296)
			(xy 189.488033 -298.578315) (xy 189.439814 -298.568471) (xy 189.393798 -298.551019) (xy 189.351177 -298.526412)
			(xy 189.313056 -298.495287) (xy 189.280421 -298.45845) (xy 189.254118 -298.416854) (xy 189.234827 -298.371578)
			(xy 189.22305 -298.323794) (xy 189.21909 -298.27474) (xy 188.880242 -298.27474) (xy 188.879747 -298.299347)
			(xy 188.871852 -298.347924) (xy 188.856268 -298.394605) (xy 188.833397 -298.438182) (xy 188.803832 -298.477526)
			(xy 188.768339 -298.511618) (xy 188.727836 -298.539574) (xy 188.683374 -298.560672) (xy 188.636103 -298.574364)
			(xy 188.587248 -298.580296) (xy 188.538073 -298.578315) (xy 188.489854 -298.568471) (xy 188.443838 -298.551019)
			(xy 188.401217 -298.526412) (xy 188.363096 -298.495287) (xy 188.330461 -298.45845) (xy 188.304158 -298.416854)
			(xy 188.284867 -298.371578) (xy 188.27309 -298.323794) (xy 188.26913 -298.27474) (xy 187.930282 -298.27474)
			(xy 187.929787 -298.299347) (xy 187.921892 -298.347924) (xy 187.906308 -298.394605) (xy 187.883437 -298.438182)
			(xy 187.853872 -298.477526) (xy 187.818379 -298.511618) (xy 187.777876 -298.539574) (xy 187.733414 -298.560672)
			(xy 187.686143 -298.574364) (xy 187.637288 -298.580296) (xy 187.588113 -298.578315) (xy 187.539894 -298.568471)
			(xy 187.493878 -298.551019) (xy 187.451257 -298.526412) (xy 187.413136 -298.495287) (xy 187.380501 -298.45845)
			(xy 187.354198 -298.416854) (xy 187.334907 -298.371578) (xy 187.32313 -298.323794) (xy 187.31917 -298.27474)
			(xy 186.030362 -298.27474) (xy 186.029867 -298.299347) (xy 186.021972 -298.347924) (xy 186.006388 -298.394605)
			(xy 185.983517 -298.438182) (xy 185.953952 -298.477526) (xy 185.918459 -298.511618) (xy 185.877956 -298.539574)
			(xy 185.833494 -298.560672) (xy 185.786223 -298.574364) (xy 185.737368 -298.580296) (xy 185.688193 -298.578315)
			(xy 185.639974 -298.568471) (xy 185.593958 -298.551019) (xy 185.551337 -298.526412) (xy 185.513216 -298.495287)
			(xy 185.480581 -298.45845) (xy 185.454278 -298.416854) (xy 185.434987 -298.371578) (xy 185.42321 -298.323794)
			(xy 185.41925 -298.27474) (xy 185.080148 -298.27474) (xy 185.079653 -298.299347) (xy 185.071758 -298.347924)
			(xy 185.056174 -298.394605) (xy 185.033303 -298.438182) (xy 185.003738 -298.477526) (xy 184.968245 -298.511618)
			(xy 184.927742 -298.539574) (xy 184.88328 -298.560672) (xy 184.836009 -298.574364) (xy 184.787154 -298.580296)
			(xy 184.737979 -298.578315) (xy 184.68976 -298.568471) (xy 184.643744 -298.551019) (xy 184.601123 -298.526412)
			(xy 184.563002 -298.495287) (xy 184.530367 -298.45845) (xy 184.504064 -298.416854) (xy 184.484773 -298.371578)
			(xy 184.472996 -298.323794) (xy 184.469036 -298.27474) (xy 184.130188 -298.27474) (xy 184.129693 -298.299347)
			(xy 184.121798 -298.347924) (xy 184.106214 -298.394605) (xy 184.083343 -298.438182) (xy 184.053778 -298.477526)
			(xy 184.018285 -298.511618) (xy 183.977782 -298.539574) (xy 183.93332 -298.560672) (xy 183.886049 -298.574364)
			(xy 183.837194 -298.580296) (xy 183.788019 -298.578315) (xy 183.7398 -298.568471) (xy 183.693784 -298.551019)
			(xy 183.651163 -298.526412) (xy 183.613042 -298.495287) (xy 183.580407 -298.45845) (xy 183.554104 -298.416854)
			(xy 183.534813 -298.371578) (xy 183.523036 -298.323794) (xy 183.519076 -298.27474) (xy 183.180228 -298.27474)
			(xy 183.179733 -298.299347) (xy 183.171838 -298.347924) (xy 183.156254 -298.394605) (xy 183.133383 -298.438182)
			(xy 183.103818 -298.477526) (xy 183.068325 -298.511618) (xy 183.027822 -298.539574) (xy 182.98336 -298.560672)
			(xy 182.936089 -298.574364) (xy 182.887234 -298.580296) (xy 182.838059 -298.578315) (xy 182.78984 -298.568471)
			(xy 182.743824 -298.551019) (xy 182.701203 -298.526412) (xy 182.663082 -298.495287) (xy 182.630447 -298.45845)
			(xy 182.604144 -298.416854) (xy 182.584853 -298.371578) (xy 182.573076 -298.323794) (xy 182.569116 -298.27474)
			(xy 182.230268 -298.27474) (xy 182.229773 -298.299347) (xy 182.221878 -298.347924) (xy 182.206294 -298.394605)
			(xy 182.183423 -298.438182) (xy 182.153858 -298.477526) (xy 182.118365 -298.511618) (xy 182.077862 -298.539574)
			(xy 182.0334 -298.560672) (xy 181.986129 -298.574364) (xy 181.937274 -298.580296) (xy 181.888099 -298.578315)
			(xy 181.83988 -298.568471) (xy 181.793864 -298.551019) (xy 181.751243 -298.526412) (xy 181.713122 -298.495287)
			(xy 181.680487 -298.45845) (xy 181.654184 -298.416854) (xy 181.634893 -298.371578) (xy 181.623116 -298.323794)
			(xy 181.619156 -298.27474) (xy 181.280308 -298.27474) (xy 181.279813 -298.299347) (xy 181.271918 -298.347924)
			(xy 181.256334 -298.394605) (xy 181.233463 -298.438182) (xy 181.203898 -298.477526) (xy 181.168405 -298.511618)
			(xy 181.127902 -298.539574) (xy 181.08344 -298.560672) (xy 181.036169 -298.574364) (xy 180.987314 -298.580296)
			(xy 180.938139 -298.578315) (xy 180.88992 -298.568471) (xy 180.843904 -298.551019) (xy 180.801283 -298.526412)
			(xy 180.763162 -298.495287) (xy 180.730527 -298.45845) (xy 180.704224 -298.416854) (xy 180.684933 -298.371578)
			(xy 180.673156 -298.323794) (xy 180.669196 -298.27474) (xy 180.330348 -298.27474) (xy 180.329853 -298.299347)
			(xy 180.321958 -298.347924) (xy 180.306374 -298.394605) (xy 180.283503 -298.438182) (xy 180.253938 -298.477526)
			(xy 180.218445 -298.511618) (xy 180.177942 -298.539574) (xy 180.13348 -298.560672) (xy 180.086209 -298.574364)
			(xy 180.037354 -298.580296) (xy 179.988179 -298.578315) (xy 179.93996 -298.568471) (xy 179.893944 -298.551019)
			(xy 179.851323 -298.526412) (xy 179.813202 -298.495287) (xy 179.780567 -298.45845) (xy 179.754264 -298.416854)
			(xy 179.734973 -298.371578) (xy 179.723196 -298.323794) (xy 179.719236 -298.27474) (xy 179.380388 -298.27474)
			(xy 179.379893 -298.299347) (xy 179.371998 -298.347924) (xy 179.356414 -298.394605) (xy 179.333543 -298.438182)
			(xy 179.303978 -298.477526) (xy 179.268485 -298.511618) (xy 179.227982 -298.539574) (xy 179.18352 -298.560672)
			(xy 179.136249 -298.574364) (xy 179.087394 -298.580296) (xy 179.038219 -298.578315) (xy 178.99 -298.568471)
			(xy 178.943984 -298.551019) (xy 178.901363 -298.526412) (xy 178.863242 -298.495287) (xy 178.830607 -298.45845)
			(xy 178.804304 -298.416854) (xy 178.785013 -298.371578) (xy 178.773236 -298.323794) (xy 178.769276 -298.27474)
			(xy 178.430174 -298.27474) (xy 178.429679 -298.299347) (xy 178.421784 -298.347924) (xy 178.4062 -298.394605)
			(xy 178.383329 -298.438182) (xy 178.353764 -298.477526) (xy 178.318271 -298.511618) (xy 178.277768 -298.539574)
			(xy 178.233306 -298.560672) (xy 178.186035 -298.574364) (xy 178.13718 -298.580296) (xy 178.088005 -298.578315)
			(xy 178.039786 -298.568471) (xy 177.99377 -298.551019) (xy 177.951149 -298.526412) (xy 177.913028 -298.495287)
			(xy 177.880393 -298.45845) (xy 177.85409 -298.416854) (xy 177.834799 -298.371578) (xy 177.823022 -298.323794)
			(xy 177.819062 -298.27474) (xy 177.480214 -298.27474) (xy 177.479719 -298.299347) (xy 177.471824 -298.347924)
			(xy 177.45624 -298.394605) (xy 177.433369 -298.438182) (xy 177.403804 -298.477526) (xy 177.368311 -298.511618)
			(xy 177.327808 -298.539574) (xy 177.283346 -298.560672) (xy 177.236075 -298.574364) (xy 177.18722 -298.580296)
			(xy 177.138045 -298.578315) (xy 177.089826 -298.568471) (xy 177.04381 -298.551019) (xy 177.001189 -298.526412)
			(xy 176.963068 -298.495287) (xy 176.930433 -298.45845) (xy 176.90413 -298.416854) (xy 176.884839 -298.371578)
			(xy 176.873062 -298.323794) (xy 176.869102 -298.27474) (xy 176.530254 -298.27474) (xy 176.529759 -298.299347)
			(xy 176.521864 -298.347924) (xy 176.50628 -298.394605) (xy 176.483409 -298.438182) (xy 176.453844 -298.477526)
			(xy 176.418351 -298.511618) (xy 176.377848 -298.539574) (xy 176.333386 -298.560672) (xy 176.286115 -298.574364)
			(xy 176.23726 -298.580296) (xy 176.188085 -298.578315) (xy 176.139866 -298.568471) (xy 176.09385 -298.551019)
			(xy 176.051229 -298.526412) (xy 176.013108 -298.495287) (xy 175.980473 -298.45845) (xy 175.95417 -298.416854)
			(xy 175.934879 -298.371578) (xy 175.923102 -298.323794) (xy 175.919142 -298.27474) (xy 174.630334 -298.27474)
			(xy 174.629839 -298.299347) (xy 174.621944 -298.347924) (xy 174.60636 -298.394605) (xy 174.583489 -298.438182)
			(xy 174.553924 -298.477526) (xy 174.518431 -298.511618) (xy 174.477928 -298.539574) (xy 174.433466 -298.560672)
			(xy 174.386195 -298.574364) (xy 174.33734 -298.580296) (xy 174.288165 -298.578315) (xy 174.239946 -298.568471)
			(xy 174.19393 -298.551019) (xy 174.151309 -298.526412) (xy 174.113188 -298.495287) (xy 174.080553 -298.45845)
			(xy 174.05425 -298.416854) (xy 174.034959 -298.371578) (xy 174.023182 -298.323794) (xy 174.019222 -298.27474)
			(xy 173.680374 -298.27474) (xy 173.679879 -298.299347) (xy 173.671984 -298.347924) (xy 173.6564 -298.394605)
			(xy 173.633529 -298.438182) (xy 173.603964 -298.477526) (xy 173.568471 -298.511618) (xy 173.527968 -298.539574)
			(xy 173.483506 -298.560672) (xy 173.436235 -298.574364) (xy 173.38738 -298.580296) (xy 173.338205 -298.578315)
			(xy 173.289986 -298.568471) (xy 173.24397 -298.551019) (xy 173.201349 -298.526412) (xy 173.163228 -298.495287)
			(xy 173.130593 -298.45845) (xy 173.10429 -298.416854) (xy 173.084999 -298.371578) (xy 173.073222 -298.323794)
			(xy 173.069262 -298.27474) (xy 172.73016 -298.27474) (xy 172.729665 -298.299347) (xy 172.72177 -298.347924)
			(xy 172.706186 -298.394605) (xy 172.683315 -298.438182) (xy 172.65375 -298.477526) (xy 172.618257 -298.511618)
			(xy 172.577754 -298.539574) (xy 172.533292 -298.560672) (xy 172.486021 -298.574364) (xy 172.437166 -298.580296)
			(xy 172.387991 -298.578315) (xy 172.339772 -298.568471) (xy 172.293756 -298.551019) (xy 172.251135 -298.526412)
			(xy 172.213014 -298.495287) (xy 172.180379 -298.45845) (xy 172.154076 -298.416854) (xy 172.134785 -298.371578)
			(xy 172.123008 -298.323794) (xy 172.119048 -298.27474) (xy 171.7802 -298.27474) (xy 171.779705 -298.299347)
			(xy 171.77181 -298.347924) (xy 171.756226 -298.394605) (xy 171.733355 -298.438182) (xy 171.70379 -298.477526)
			(xy 171.668297 -298.511618) (xy 171.627794 -298.539574) (xy 171.583332 -298.560672) (xy 171.536061 -298.574364)
			(xy 171.487206 -298.580296) (xy 171.438031 -298.578315) (xy 171.389812 -298.568471) (xy 171.343796 -298.551019)
			(xy 171.301175 -298.526412) (xy 171.263054 -298.495287) (xy 171.230419 -298.45845) (xy 171.204116 -298.416854)
			(xy 171.184825 -298.371578) (xy 171.173048 -298.323794) (xy 171.169088 -298.27474) (xy 170.83024 -298.27474)
			(xy 170.829745 -298.299347) (xy 170.82185 -298.347924) (xy 170.806266 -298.394605) (xy 170.783395 -298.438182)
			(xy 170.75383 -298.477526) (xy 170.718337 -298.511618) (xy 170.677834 -298.539574) (xy 170.633372 -298.560672)
			(xy 170.586101 -298.574364) (xy 170.537246 -298.580296) (xy 170.488071 -298.578315) (xy 170.439852 -298.568471)
			(xy 170.393836 -298.551019) (xy 170.351215 -298.526412) (xy 170.313094 -298.495287) (xy 170.280459 -298.45845)
			(xy 170.254156 -298.416854) (xy 170.234865 -298.371578) (xy 170.223088 -298.323794) (xy 170.219128 -298.27474)
			(xy 169.88028 -298.27474) (xy 169.879785 -298.299347) (xy 169.87189 -298.347924) (xy 169.856306 -298.394605)
			(xy 169.833435 -298.438182) (xy 169.80387 -298.477526) (xy 169.768377 -298.511618) (xy 169.727874 -298.539574)
			(xy 169.683412 -298.560672) (xy 169.636141 -298.574364) (xy 169.587286 -298.580296) (xy 169.538111 -298.578315)
			(xy 169.489892 -298.568471) (xy 169.443876 -298.551019) (xy 169.401255 -298.526412) (xy 169.363134 -298.495287)
			(xy 169.330499 -298.45845) (xy 169.304196 -298.416854) (xy 169.284905 -298.371578) (xy 169.273128 -298.323794)
			(xy 169.269168 -298.27474) (xy 168.93032 -298.27474) (xy 168.929825 -298.299347) (xy 168.92193 -298.347924)
			(xy 168.906346 -298.394605) (xy 168.883475 -298.438182) (xy 168.85391 -298.477526) (xy 168.818417 -298.511618)
			(xy 168.777914 -298.539574) (xy 168.733452 -298.560672) (xy 168.686181 -298.574364) (xy 168.637326 -298.580296)
			(xy 168.588151 -298.578315) (xy 168.539932 -298.568471) (xy 168.493916 -298.551019) (xy 168.451295 -298.526412)
			(xy 168.413174 -298.495287) (xy 168.380539 -298.45845) (xy 168.354236 -298.416854) (xy 168.334945 -298.371578)
			(xy 168.323168 -298.323794) (xy 168.319208 -298.27474) (xy 167.98036 -298.27474) (xy 167.979865 -298.299347)
			(xy 167.97197 -298.347924) (xy 167.956386 -298.394605) (xy 167.933515 -298.438182) (xy 167.90395 -298.477526)
			(xy 167.868457 -298.511618) (xy 167.827954 -298.539574) (xy 167.783492 -298.560672) (xy 167.736221 -298.574364)
			(xy 167.687366 -298.580296) (xy 167.638191 -298.578315) (xy 167.589972 -298.568471) (xy 167.543956 -298.551019)
			(xy 167.501335 -298.526412) (xy 167.463214 -298.495287) (xy 167.430579 -298.45845) (xy 167.404276 -298.416854)
			(xy 167.384985 -298.371578) (xy 167.373208 -298.323794) (xy 167.369248 -298.27474) (xy 167.0304 -298.27474)
			(xy 167.029905 -298.299347) (xy 167.02201 -298.347924) (xy 167.006426 -298.394605) (xy 166.983555 -298.438182)
			(xy 166.95399 -298.477526) (xy 166.918497 -298.511618) (xy 166.877994 -298.539574) (xy 166.833532 -298.560672)
			(xy 166.786261 -298.574364) (xy 166.737406 -298.580296) (xy 166.688231 -298.578315) (xy 166.640012 -298.568471)
			(xy 166.593996 -298.551019) (xy 166.551375 -298.526412) (xy 166.513254 -298.495287) (xy 166.480619 -298.45845)
			(xy 166.454316 -298.416854) (xy 166.435025 -298.371578) (xy 166.423248 -298.323794) (xy 166.419288 -298.27474)
			(xy 166.080186 -298.27474) (xy 166.079691 -298.299347) (xy 166.071796 -298.347924) (xy 166.056212 -298.394605)
			(xy 166.033341 -298.438182) (xy 166.003776 -298.477526) (xy 165.968283 -298.511618) (xy 165.92778 -298.539574)
			(xy 165.883318 -298.560672) (xy 165.836047 -298.574364) (xy 165.787192 -298.580296) (xy 165.738017 -298.578315)
			(xy 165.689798 -298.568471) (xy 165.643782 -298.551019) (xy 165.601161 -298.526412) (xy 165.56304 -298.495287)
			(xy 165.530405 -298.45845) (xy 165.504102 -298.416854) (xy 165.484811 -298.371578) (xy 165.473034 -298.323794)
			(xy 165.469074 -298.27474) (xy 165.155044 -298.27474) (xy 165.155044 -298.301084) (xy 165.146666 -298.353171)
			(xy 165.130124 -298.403267) (xy 165.105837 -298.450101) (xy 165.074421 -298.492485) (xy 165.036674 -298.529342)
			(xy 164.993554 -298.559738) (xy 164.946154 -298.582902) (xy 164.895678 -298.598245) (xy 164.869622 -298.6024)
			(xy 164.86505 -298.603162) (xy 164.854636 -298.606464) (xy 164.850318 -298.607734) (xy 164.826696 -298.618656)
			(xy 164.819838 -298.625768) (xy 164.804852 -298.641516) (xy 164.800265 -298.646622) (xy 164.793824 -298.658735)
			(xy 164.792152 -298.665392) (xy 164.790882 -298.676314) (xy 164.790882 -298.69765) (xy 202.569062 -298.69765)
			(xy 202.573133 -298.642028) (xy 202.585259 -298.587591) (xy 202.605182 -298.5355) (xy 202.632478 -298.486865)
			(xy 202.666564 -298.442722) (xy 202.706713 -298.404013) (xy 202.752071 -298.371562) (xy 202.801671 -298.346061)
			(xy 202.854455 -298.328054) (xy 202.909298 -298.317924) (xy 202.965032 -298.315887) (xy 203.020469 -298.321987)
			(xy 203.074426 -298.336093) (xy 203.125755 -298.357905) (xy 203.173361 -298.386959) (xy 203.216229 -298.422634)
			(xy 203.253446 -298.464171) (xy 203.284219 -298.510684) (xy 203.307891 -298.561181) (xy 203.323959 -298.614588)
			(xy 203.332079 -298.669764) (xy 203.332588 -298.69765) (xy 203.332079 -298.725536) (xy 203.323959 -298.780712)
			(xy 203.307891 -298.834119) (xy 203.284219 -298.884616) (xy 203.253446 -298.931129) (xy 203.216229 -298.972666)
			(xy 203.173361 -299.008341) (xy 203.125755 -299.037395) (xy 203.074426 -299.059207) (xy 203.020469 -299.073313)
			(xy 202.965032 -299.079413) (xy 202.909298 -299.077376) (xy 202.854455 -299.067246) (xy 202.801671 -299.049239)
			(xy 202.752071 -299.023738) (xy 202.706713 -298.991287) (xy 202.666564 -298.952578) (xy 202.632478 -298.908435)
			(xy 202.605182 -298.8598) (xy 202.585259 -298.807709) (xy 202.573133 -298.753272) (xy 202.569062 -298.69765)
			(xy 164.790882 -298.69765) (xy 164.790882 -298.82338) (xy 164.791053 -298.829533) (xy 164.794012 -298.841477)
			(xy 164.796724 -298.847002) (xy 164.804852 -298.858178) (xy 164.819584 -298.873672) (xy 164.826188 -298.880784)
			(xy 164.849302 -298.891706) (xy 164.852858 -298.892722) (xy 164.86505 -298.896532) (xy 164.869622 -298.897294)
			(xy 164.895695 -298.901371) (xy 164.946185 -298.916719) (xy 164.993597 -298.939888) (xy 165.036728 -298.970292)
			(xy 165.074485 -299.007159) (xy 165.105908 -299.049553) (xy 165.130202 -299.096399) (xy 165.146748 -299.146508)
			(xy 165.155129 -299.198609) (xy 165.155129 -299.224954) (xy 165.469074 -299.224954) (xy 165.473034 -299.1759)
			(xy 165.484811 -299.128116) (xy 165.504102 -299.08284) (xy 165.530405 -299.041244) (xy 165.56304 -299.004407)
			(xy 165.601161 -298.973282) (xy 165.643782 -298.948675) (xy 165.689798 -298.931223) (xy 165.738017 -298.921379)
			(xy 165.787192 -298.919398) (xy 165.836047 -298.92533) (xy 165.883318 -298.939022) (xy 165.92778 -298.96012)
			(xy 165.968283 -298.988076) (xy 166.003776 -299.022168) (xy 166.033341 -299.061512) (xy 166.056212 -299.105089)
			(xy 166.071796 -299.15177) (xy 166.079691 -299.200347) (xy 166.080186 -299.224954) (xy 166.419288 -299.224954)
			(xy 166.423248 -299.1759) (xy 166.435025 -299.128116) (xy 166.454316 -299.08284) (xy 166.480619 -299.041244)
			(xy 166.513254 -299.004407) (xy 166.551375 -298.973282) (xy 166.593996 -298.948675) (xy 166.640012 -298.931223)
			(xy 166.688231 -298.921379) (xy 166.737406 -298.919398) (xy 166.786261 -298.92533) (xy 166.833532 -298.939022)
			(xy 166.877994 -298.96012) (xy 166.918497 -298.988076) (xy 166.95399 -299.022168) (xy 166.983555 -299.061512)
			(xy 167.006426 -299.105089) (xy 167.02201 -299.15177) (xy 167.029905 -299.200347) (xy 167.0304 -299.224954)
			(xy 167.369248 -299.224954) (xy 167.373208 -299.1759) (xy 167.384985 -299.128116) (xy 167.404276 -299.08284)
			(xy 167.430579 -299.041244) (xy 167.463214 -299.004407) (xy 167.501335 -298.973282) (xy 167.543956 -298.948675)
			(xy 167.589972 -298.931223) (xy 167.638191 -298.921379) (xy 167.687366 -298.919398) (xy 167.736221 -298.92533)
			(xy 167.783492 -298.939022) (xy 167.827954 -298.96012) (xy 167.868457 -298.988076) (xy 167.90395 -299.022168)
			(xy 167.933515 -299.061512) (xy 167.956386 -299.105089) (xy 167.97197 -299.15177) (xy 167.979865 -299.200347)
			(xy 167.98036 -299.224954) (xy 168.319208 -299.224954) (xy 168.323168 -299.1759) (xy 168.334945 -299.128116)
			(xy 168.354236 -299.08284) (xy 168.380539 -299.041244) (xy 168.413174 -299.004407) (xy 168.451295 -298.973282)
			(xy 168.493916 -298.948675) (xy 168.539932 -298.931223) (xy 168.588151 -298.921379) (xy 168.637326 -298.919398)
			(xy 168.686181 -298.92533) (xy 168.733452 -298.939022) (xy 168.777914 -298.96012) (xy 168.818417 -298.988076)
			(xy 168.85391 -299.022168) (xy 168.883475 -299.061512) (xy 168.906346 -299.105089) (xy 168.92193 -299.15177)
			(xy 168.929825 -299.200347) (xy 168.93032 -299.224954) (xy 169.269168 -299.224954) (xy 169.273128 -299.1759)
			(xy 169.284905 -299.128116) (xy 169.304196 -299.08284) (xy 169.330499 -299.041244) (xy 169.363134 -299.004407)
			(xy 169.401255 -298.973282) (xy 169.443876 -298.948675) (xy 169.489892 -298.931223) (xy 169.538111 -298.921379)
			(xy 169.587286 -298.919398) (xy 169.636141 -298.92533) (xy 169.683412 -298.939022) (xy 169.727874 -298.96012)
			(xy 169.768377 -298.988076) (xy 169.80387 -299.022168) (xy 169.833435 -299.061512) (xy 169.856306 -299.105089)
			(xy 169.87189 -299.15177) (xy 169.879785 -299.200347) (xy 169.88028 -299.224954) (xy 170.219128 -299.224954)
			(xy 170.223088 -299.1759) (xy 170.234865 -299.128116) (xy 170.254156 -299.08284) (xy 170.280459 -299.041244)
			(xy 170.313094 -299.004407) (xy 170.351215 -298.973282) (xy 170.393836 -298.948675) (xy 170.439852 -298.931223)
			(xy 170.488071 -298.921379) (xy 170.537246 -298.919398) (xy 170.586101 -298.92533) (xy 170.633372 -298.939022)
			(xy 170.677834 -298.96012) (xy 170.718337 -298.988076) (xy 170.75383 -299.022168) (xy 170.783395 -299.061512)
			(xy 170.806266 -299.105089) (xy 170.82185 -299.15177) (xy 170.829745 -299.200347) (xy 170.83024 -299.224954)
			(xy 171.169088 -299.224954) (xy 171.173048 -299.1759) (xy 171.184825 -299.128116) (xy 171.204116 -299.08284)
			(xy 171.230419 -299.041244) (xy 171.263054 -299.004407) (xy 171.301175 -298.973282) (xy 171.343796 -298.948675)
			(xy 171.389812 -298.931223) (xy 171.438031 -298.921379) (xy 171.487206 -298.919398) (xy 171.536061 -298.92533)
			(xy 171.583332 -298.939022) (xy 171.627794 -298.96012) (xy 171.668297 -298.988076) (xy 171.70379 -299.022168)
			(xy 171.733355 -299.061512) (xy 171.756226 -299.105089) (xy 171.77181 -299.15177) (xy 171.779705 -299.200347)
			(xy 171.7802 -299.224954) (xy 172.119048 -299.224954) (xy 172.123008 -299.1759) (xy 172.134785 -299.128116)
			(xy 172.154076 -299.08284) (xy 172.180379 -299.041244) (xy 172.213014 -299.004407) (xy 172.251135 -298.973282)
			(xy 172.293756 -298.948675) (xy 172.339772 -298.931223) (xy 172.387991 -298.921379) (xy 172.437166 -298.919398)
			(xy 172.486021 -298.92533) (xy 172.533292 -298.939022) (xy 172.577754 -298.96012) (xy 172.618257 -298.988076)
			(xy 172.65375 -299.022168) (xy 172.683315 -299.061512) (xy 172.706186 -299.105089) (xy 172.72177 -299.15177)
			(xy 172.729665 -299.200347) (xy 172.73016 -299.224954) (xy 173.069262 -299.224954) (xy 173.073222 -299.1759)
			(xy 173.084999 -299.128116) (xy 173.10429 -299.08284) (xy 173.130593 -299.041244) (xy 173.163228 -299.004407)
			(xy 173.201349 -298.973282) (xy 173.24397 -298.948675) (xy 173.289986 -298.931223) (xy 173.338205 -298.921379)
			(xy 173.38738 -298.919398) (xy 173.436235 -298.92533) (xy 173.483506 -298.939022) (xy 173.527968 -298.96012)
			(xy 173.568471 -298.988076) (xy 173.603964 -299.022168) (xy 173.633529 -299.061512) (xy 173.6564 -299.105089)
			(xy 173.671984 -299.15177) (xy 173.679879 -299.200347) (xy 173.680374 -299.224954) (xy 174.019222 -299.224954)
			(xy 174.023182 -299.1759) (xy 174.034959 -299.128116) (xy 174.05425 -299.08284) (xy 174.080553 -299.041244)
			(xy 174.113188 -299.004407) (xy 174.151309 -298.973282) (xy 174.19393 -298.948675) (xy 174.239946 -298.931223)
			(xy 174.288165 -298.921379) (xy 174.33734 -298.919398) (xy 174.386195 -298.92533) (xy 174.433466 -298.939022)
			(xy 174.477928 -298.96012) (xy 174.518431 -298.988076) (xy 174.553924 -299.022168) (xy 174.583489 -299.061512)
			(xy 174.60636 -299.105089) (xy 174.621944 -299.15177) (xy 174.629839 -299.200347) (xy 174.630334 -299.224954)
			(xy 175.919142 -299.224954) (xy 175.923102 -299.1759) (xy 175.934879 -299.128116) (xy 175.95417 -299.08284)
			(xy 175.980473 -299.041244) (xy 176.013108 -299.004407) (xy 176.051229 -298.973282) (xy 176.09385 -298.948675)
			(xy 176.139866 -298.931223) (xy 176.188085 -298.921379) (xy 176.23726 -298.919398) (xy 176.286115 -298.92533)
			(xy 176.333386 -298.939022) (xy 176.377848 -298.96012) (xy 176.418351 -298.988076) (xy 176.453844 -299.022168)
			(xy 176.483409 -299.061512) (xy 176.50628 -299.105089) (xy 176.521864 -299.15177) (xy 176.529759 -299.200347)
			(xy 176.530254 -299.224954) (xy 176.869102 -299.224954) (xy 176.873062 -299.1759) (xy 176.884839 -299.128116)
			(xy 176.90413 -299.08284) (xy 176.930433 -299.041244) (xy 176.963068 -299.004407) (xy 177.001189 -298.973282)
			(xy 177.04381 -298.948675) (xy 177.089826 -298.931223) (xy 177.138045 -298.921379) (xy 177.18722 -298.919398)
			(xy 177.236075 -298.92533) (xy 177.283346 -298.939022) (xy 177.327808 -298.96012) (xy 177.368311 -298.988076)
			(xy 177.403804 -299.022168) (xy 177.433369 -299.061512) (xy 177.45624 -299.105089) (xy 177.471824 -299.15177)
			(xy 177.479719 -299.200347) (xy 177.480214 -299.224954) (xy 177.819062 -299.224954) (xy 177.823022 -299.1759)
			(xy 177.834799 -299.128116) (xy 177.85409 -299.08284) (xy 177.880393 -299.041244) (xy 177.913028 -299.004407)
			(xy 177.951149 -298.973282) (xy 177.99377 -298.948675) (xy 178.039786 -298.931223) (xy 178.088005 -298.921379)
			(xy 178.13718 -298.919398) (xy 178.186035 -298.92533) (xy 178.233306 -298.939022) (xy 178.277768 -298.96012)
			(xy 178.318271 -298.988076) (xy 178.353764 -299.022168) (xy 178.383329 -299.061512) (xy 178.4062 -299.105089)
			(xy 178.421784 -299.15177) (xy 178.429679 -299.200347) (xy 178.430174 -299.224954) (xy 178.769276 -299.224954)
			(xy 178.773236 -299.1759) (xy 178.785013 -299.128116) (xy 178.804304 -299.08284) (xy 178.830607 -299.041244)
			(xy 178.863242 -299.004407) (xy 178.901363 -298.973282) (xy 178.943984 -298.948675) (xy 178.99 -298.931223)
			(xy 179.038219 -298.921379) (xy 179.087394 -298.919398) (xy 179.136249 -298.92533) (xy 179.18352 -298.939022)
			(xy 179.227982 -298.96012) (xy 179.268485 -298.988076) (xy 179.303978 -299.022168) (xy 179.333543 -299.061512)
			(xy 179.356414 -299.105089) (xy 179.371998 -299.15177) (xy 179.379893 -299.200347) (xy 179.380388 -299.224954)
			(xy 179.719236 -299.224954) (xy 179.723196 -299.1759) (xy 179.734973 -299.128116) (xy 179.754264 -299.08284)
			(xy 179.780567 -299.041244) (xy 179.813202 -299.004407) (xy 179.851323 -298.973282) (xy 179.893944 -298.948675)
			(xy 179.93996 -298.931223) (xy 179.988179 -298.921379) (xy 180.037354 -298.919398) (xy 180.086209 -298.92533)
			(xy 180.13348 -298.939022) (xy 180.177942 -298.96012) (xy 180.218445 -298.988076) (xy 180.253938 -299.022168)
			(xy 180.283503 -299.061512) (xy 180.306374 -299.105089) (xy 180.321958 -299.15177) (xy 180.329853 -299.200347)
			(xy 180.330348 -299.224954) (xy 180.669196 -299.224954) (xy 180.673156 -299.1759) (xy 180.684933 -299.128116)
			(xy 180.704224 -299.08284) (xy 180.730527 -299.041244) (xy 180.763162 -299.004407) (xy 180.801283 -298.973282)
			(xy 180.843904 -298.948675) (xy 180.88992 -298.931223) (xy 180.938139 -298.921379) (xy 180.987314 -298.919398)
			(xy 181.036169 -298.92533) (xy 181.08344 -298.939022) (xy 181.127902 -298.96012) (xy 181.168405 -298.988076)
			(xy 181.203898 -299.022168) (xy 181.233463 -299.061512) (xy 181.256334 -299.105089) (xy 181.271918 -299.15177)
			(xy 181.279813 -299.200347) (xy 181.280308 -299.224954) (xy 181.619156 -299.224954) (xy 181.623116 -299.1759)
			(xy 181.634893 -299.128116) (xy 181.654184 -299.08284) (xy 181.680487 -299.041244) (xy 181.713122 -299.004407)
			(xy 181.751243 -298.973282) (xy 181.793864 -298.948675) (xy 181.83988 -298.931223) (xy 181.888099 -298.921379)
			(xy 181.937274 -298.919398) (xy 181.986129 -298.92533) (xy 182.0334 -298.939022) (xy 182.077862 -298.96012)
			(xy 182.118365 -298.988076) (xy 182.153858 -299.022168) (xy 182.183423 -299.061512) (xy 182.206294 -299.105089)
			(xy 182.221878 -299.15177) (xy 182.229773 -299.200347) (xy 182.230268 -299.224954) (xy 182.569116 -299.224954)
			(xy 182.573076 -299.1759) (xy 182.584853 -299.128116) (xy 182.604144 -299.08284) (xy 182.630447 -299.041244)
			(xy 182.663082 -299.004407) (xy 182.701203 -298.973282) (xy 182.743824 -298.948675) (xy 182.78984 -298.931223)
			(xy 182.838059 -298.921379) (xy 182.887234 -298.919398) (xy 182.936089 -298.92533) (xy 182.98336 -298.939022)
			(xy 183.027822 -298.96012) (xy 183.068325 -298.988076) (xy 183.103818 -299.022168) (xy 183.133383 -299.061512)
			(xy 183.156254 -299.105089) (xy 183.171838 -299.15177) (xy 183.179733 -299.200347) (xy 183.180228 -299.224954)
			(xy 183.519076 -299.224954) (xy 183.523036 -299.1759) (xy 183.534813 -299.128116) (xy 183.554104 -299.08284)
			(xy 183.580407 -299.041244) (xy 183.613042 -299.004407) (xy 183.651163 -298.973282) (xy 183.693784 -298.948675)
			(xy 183.7398 -298.931223) (xy 183.788019 -298.921379) (xy 183.837194 -298.919398) (xy 183.886049 -298.92533)
			(xy 183.93332 -298.939022) (xy 183.977782 -298.96012) (xy 184.018285 -298.988076) (xy 184.053778 -299.022168)
			(xy 184.083343 -299.061512) (xy 184.106214 -299.105089) (xy 184.121798 -299.15177) (xy 184.129693 -299.200347)
			(xy 184.130188 -299.224954) (xy 184.469036 -299.224954) (xy 184.472996 -299.1759) (xy 184.484773 -299.128116)
			(xy 184.504064 -299.08284) (xy 184.530367 -299.041244) (xy 184.563002 -299.004407) (xy 184.601123 -298.973282)
			(xy 184.643744 -298.948675) (xy 184.68976 -298.931223) (xy 184.737979 -298.921379) (xy 184.787154 -298.919398)
			(xy 184.836009 -298.92533) (xy 184.88328 -298.939022) (xy 184.927742 -298.96012) (xy 184.968245 -298.988076)
			(xy 185.003738 -299.022168) (xy 185.033303 -299.061512) (xy 185.056174 -299.105089) (xy 185.071758 -299.15177)
			(xy 185.079653 -299.200347) (xy 185.080148 -299.224954) (xy 185.41925 -299.224954) (xy 185.42321 -299.1759)
			(xy 185.434987 -299.128116) (xy 185.454278 -299.08284) (xy 185.480581 -299.041244) (xy 185.513216 -299.004407)
			(xy 185.551337 -298.973282) (xy 185.593958 -298.948675) (xy 185.639974 -298.931223) (xy 185.688193 -298.921379)
			(xy 185.737368 -298.919398) (xy 185.786223 -298.92533) (xy 185.833494 -298.939022) (xy 185.877956 -298.96012)
			(xy 185.918459 -298.988076) (xy 185.953952 -299.022168) (xy 185.983517 -299.061512) (xy 186.006388 -299.105089)
			(xy 186.021972 -299.15177) (xy 186.029867 -299.200347) (xy 186.030362 -299.224954) (xy 186.36921 -299.224954)
			(xy 186.37317 -299.1759) (xy 186.384947 -299.128116) (xy 186.404238 -299.08284) (xy 186.430541 -299.041244)
			(xy 186.463176 -299.004407) (xy 186.501297 -298.973282) (xy 186.543918 -298.948675) (xy 186.589934 -298.931223)
			(xy 186.638153 -298.921379) (xy 186.687328 -298.919398) (xy 186.736183 -298.92533) (xy 186.783454 -298.939022)
			(xy 186.827916 -298.96012) (xy 186.868419 -298.988076) (xy 186.903912 -299.022168) (xy 186.933477 -299.061512)
			(xy 186.956348 -299.105089) (xy 186.971932 -299.15177) (xy 186.979827 -299.200347) (xy 186.980322 -299.224954)
			(xy 187.31917 -299.224954) (xy 187.32313 -299.1759) (xy 187.334907 -299.128116) (xy 187.354198 -299.08284)
			(xy 187.380501 -299.041244) (xy 187.413136 -299.004407) (xy 187.451257 -298.973282) (xy 187.493878 -298.948675)
			(xy 187.539894 -298.931223) (xy 187.588113 -298.921379) (xy 187.637288 -298.919398) (xy 187.686143 -298.92533)
			(xy 187.733414 -298.939022) (xy 187.777876 -298.96012) (xy 187.818379 -298.988076) (xy 187.853872 -299.022168)
			(xy 187.883437 -299.061512) (xy 187.906308 -299.105089) (xy 187.921892 -299.15177) (xy 187.929787 -299.200347)
			(xy 187.930282 -299.224954) (xy 188.26913 -299.224954) (xy 188.27309 -299.1759) (xy 188.284867 -299.128116)
			(xy 188.304158 -299.08284) (xy 188.330461 -299.041244) (xy 188.363096 -299.004407) (xy 188.401217 -298.973282)
			(xy 188.443838 -298.948675) (xy 188.489854 -298.931223) (xy 188.538073 -298.921379) (xy 188.587248 -298.919398)
			(xy 188.636103 -298.92533) (xy 188.683374 -298.939022) (xy 188.727836 -298.96012) (xy 188.768339 -298.988076)
			(xy 188.803832 -299.022168) (xy 188.833397 -299.061512) (xy 188.856268 -299.105089) (xy 188.871852 -299.15177)
			(xy 188.879747 -299.200347) (xy 188.880242 -299.224954) (xy 189.21909 -299.224954) (xy 189.22305 -299.1759)
			(xy 189.234827 -299.128116) (xy 189.254118 -299.08284) (xy 189.280421 -299.041244) (xy 189.313056 -299.004407)
			(xy 189.351177 -298.973282) (xy 189.393798 -298.948675) (xy 189.439814 -298.931223) (xy 189.488033 -298.921379)
			(xy 189.537208 -298.919398) (xy 189.586063 -298.92533) (xy 189.633334 -298.939022) (xy 189.677796 -298.96012)
			(xy 189.718299 -298.988076) (xy 189.753792 -299.022168) (xy 189.783357 -299.061512) (xy 189.806228 -299.105089)
			(xy 189.821812 -299.15177) (xy 189.829707 -299.200347) (xy 189.830202 -299.224954) (xy 192.069224 -299.224954)
			(xy 192.073184 -299.1759) (xy 192.084961 -299.128116) (xy 192.104252 -299.08284) (xy 192.130555 -299.041244)
			(xy 192.16319 -299.004407) (xy 192.201311 -298.973282) (xy 192.243932 -298.948675) (xy 192.289948 -298.931223)
			(xy 192.338167 -298.921379) (xy 192.387342 -298.919398) (xy 192.436197 -298.92533) (xy 192.483468 -298.939022)
			(xy 192.52793 -298.96012) (xy 192.568433 -298.988076) (xy 192.603926 -299.022168) (xy 192.633491 -299.061512)
			(xy 192.656362 -299.105089) (xy 192.671946 -299.15177) (xy 192.679841 -299.200347) (xy 192.680336 -299.224954)
			(xy 193.019184 -299.224954) (xy 193.023144 -299.1759) (xy 193.034921 -299.128116) (xy 193.054212 -299.08284)
			(xy 193.080515 -299.041244) (xy 193.11315 -299.004407) (xy 193.151271 -298.973282) (xy 193.193892 -298.948675)
			(xy 193.239908 -298.931223) (xy 193.288127 -298.921379) (xy 193.337302 -298.919398) (xy 193.386157 -298.92533)
			(xy 193.433428 -298.939022) (xy 193.47789 -298.96012) (xy 193.518393 -298.988076) (xy 193.553886 -299.022168)
			(xy 193.583451 -299.061512) (xy 193.606322 -299.105089) (xy 193.621906 -299.15177) (xy 193.629801 -299.200347)
			(xy 193.630296 -299.224954) (xy 193.969144 -299.224954) (xy 193.973104 -299.1759) (xy 193.984881 -299.128116)
			(xy 194.004172 -299.08284) (xy 194.030475 -299.041244) (xy 194.06311 -299.004407) (xy 194.101231 -298.973282)
			(xy 194.143852 -298.948675) (xy 194.189868 -298.931223) (xy 194.238087 -298.921379) (xy 194.287262 -298.919398)
			(xy 194.336117 -298.92533) (xy 194.383388 -298.939022) (xy 194.42785 -298.96012) (xy 194.468353 -298.988076)
			(xy 194.503846 -299.022168) (xy 194.533411 -299.061512) (xy 194.556282 -299.105089) (xy 194.571866 -299.15177)
			(xy 194.579761 -299.200347) (xy 194.580256 -299.224954) (xy 194.919104 -299.224954) (xy 194.923064 -299.1759)
			(xy 194.934841 -299.128116) (xy 194.954132 -299.08284) (xy 194.980435 -299.041244) (xy 195.01307 -299.004407)
			(xy 195.051191 -298.973282) (xy 195.093812 -298.948675) (xy 195.139828 -298.931223) (xy 195.188047 -298.921379)
			(xy 195.237222 -298.919398) (xy 195.286077 -298.92533) (xy 195.333348 -298.939022) (xy 195.37781 -298.96012)
			(xy 195.418313 -298.988076) (xy 195.453806 -299.022168) (xy 195.483371 -299.061512) (xy 195.506242 -299.105089)
			(xy 195.521826 -299.15177) (xy 195.529721 -299.200347) (xy 195.530216 -299.224954) (xy 195.869064 -299.224954)
			(xy 195.873024 -299.1759) (xy 195.884801 -299.128116) (xy 195.904092 -299.08284) (xy 195.930395 -299.041244)
			(xy 195.96303 -299.004407) (xy 196.001151 -298.973282) (xy 196.043772 -298.948675) (xy 196.089788 -298.931223)
			(xy 196.138007 -298.921379) (xy 196.187182 -298.919398) (xy 196.236037 -298.92533) (xy 196.283308 -298.939022)
			(xy 196.32777 -298.96012) (xy 196.368273 -298.988076) (xy 196.403766 -299.022168) (xy 196.433331 -299.061512)
			(xy 196.456202 -299.105089) (xy 196.471786 -299.15177) (xy 196.479681 -299.200347) (xy 196.480176 -299.224954)
			(xy 196.819278 -299.224954) (xy 196.823238 -299.1759) (xy 196.835015 -299.128116) (xy 196.854306 -299.08284)
			(xy 196.880609 -299.041244) (xy 196.913244 -299.004407) (xy 196.951365 -298.973282) (xy 196.993986 -298.948675)
			(xy 197.040002 -298.931223) (xy 197.088221 -298.921379) (xy 197.137396 -298.919398) (xy 197.186251 -298.92533)
			(xy 197.233522 -298.939022) (xy 197.277984 -298.96012) (xy 197.318487 -298.988076) (xy 197.35398 -299.022168)
			(xy 197.383545 -299.061512) (xy 197.406416 -299.105089) (xy 197.422 -299.15177) (xy 197.429895 -299.200347)
			(xy 197.43039 -299.224954) (xy 197.769238 -299.224954) (xy 197.773198 -299.1759) (xy 197.784975 -299.128116)
			(xy 197.804266 -299.08284) (xy 197.830569 -299.041244) (xy 197.863204 -299.004407) (xy 197.901325 -298.973282)
			(xy 197.943946 -298.948675) (xy 197.989962 -298.931223) (xy 198.038181 -298.921379) (xy 198.087356 -298.919398)
			(xy 198.136211 -298.92533) (xy 198.183482 -298.939022) (xy 198.227944 -298.96012) (xy 198.268447 -298.988076)
			(xy 198.30394 -299.022168) (xy 198.333505 -299.061512) (xy 198.356376 -299.105089) (xy 198.37196 -299.15177)
			(xy 198.379855 -299.200347) (xy 198.38035 -299.224954) (xy 198.719198 -299.224954) (xy 198.723158 -299.1759)
			(xy 198.734935 -299.128116) (xy 198.754226 -299.08284) (xy 198.780529 -299.041244) (xy 198.813164 -299.004407)
			(xy 198.851285 -298.973282) (xy 198.893906 -298.948675) (xy 198.939922 -298.931223) (xy 198.988141 -298.921379)
			(xy 199.037316 -298.919398) (xy 199.086171 -298.92533) (xy 199.133442 -298.939022) (xy 199.177904 -298.96012)
			(xy 199.218407 -298.988076) (xy 199.2539 -299.022168) (xy 199.283465 -299.061512) (xy 199.306336 -299.105089)
			(xy 199.32192 -299.15177) (xy 199.329815 -299.200347) (xy 199.33031 -299.224954) (xy 199.329815 -299.249561)
			(xy 199.326012 -299.27296) (xy 206.414622 -299.27296) (xy 206.418693 -299.217338) (xy 206.430819 -299.162901)
			(xy 206.450742 -299.11081) (xy 206.478038 -299.062175) (xy 206.512124 -299.018032) (xy 206.552273 -298.979323)
			(xy 206.597631 -298.946872) (xy 206.647231 -298.921371) (xy 206.700015 -298.903364) (xy 206.754858 -298.893234)
			(xy 206.810592 -298.891197) (xy 206.866029 -298.897297) (xy 206.919986 -298.911403) (xy 206.971315 -298.933215)
			(xy 207.018921 -298.962269) (xy 207.061789 -298.997944) (xy 207.099006 -299.039481) (xy 207.129779 -299.085994)
			(xy 207.153451 -299.136491) (xy 207.169519 -299.189898) (xy 207.177639 -299.245074) (xy 207.178148 -299.27296)
			(xy 207.177639 -299.300846) (xy 207.169519 -299.356022) (xy 207.153451 -299.409429) (xy 207.129779 -299.459926)
			(xy 207.099006 -299.506439) (xy 207.061789 -299.547976) (xy 207.018921 -299.583651) (xy 206.971315 -299.612705)
			(xy 206.919986 -299.634517) (xy 206.866029 -299.648623) (xy 206.810592 -299.654723) (xy 206.754858 -299.652686)
			(xy 206.700015 -299.642556) (xy 206.647231 -299.624549) (xy 206.597631 -299.599048) (xy 206.552273 -299.566597)
			(xy 206.512124 -299.527888) (xy 206.478038 -299.483745) (xy 206.450742 -299.43511) (xy 206.430819 -299.383019)
			(xy 206.418693 -299.328582) (xy 206.414622 -299.27296) (xy 199.326012 -299.27296) (xy 199.32192 -299.298138)
			(xy 199.306336 -299.344819) (xy 199.283465 -299.388396) (xy 199.2539 -299.42774) (xy 199.218407 -299.461832)
			(xy 199.177904 -299.489788) (xy 199.133442 -299.510886) (xy 199.086171 -299.524578) (xy 199.037316 -299.53051)
			(xy 198.988141 -299.528529) (xy 198.939922 -299.518685) (xy 198.893906 -299.501233) (xy 198.851285 -299.476626)
			(xy 198.813164 -299.445501) (xy 198.780529 -299.408664) (xy 198.754226 -299.367068) (xy 198.734935 -299.321792)
			(xy 198.723158 -299.274008) (xy 198.719198 -299.224954) (xy 198.38035 -299.224954) (xy 198.379855 -299.249561)
			(xy 198.37196 -299.298138) (xy 198.356376 -299.344819) (xy 198.333505 -299.388396) (xy 198.30394 -299.42774)
			(xy 198.268447 -299.461832) (xy 198.227944 -299.489788) (xy 198.183482 -299.510886) (xy 198.136211 -299.524578)
			(xy 198.087356 -299.53051) (xy 198.038181 -299.528529) (xy 197.989962 -299.518685) (xy 197.943946 -299.501233)
			(xy 197.901325 -299.476626) (xy 197.863204 -299.445501) (xy 197.830569 -299.408664) (xy 197.804266 -299.367068)
			(xy 197.784975 -299.321792) (xy 197.773198 -299.274008) (xy 197.769238 -299.224954) (xy 197.43039 -299.224954)
			(xy 197.429895 -299.249561) (xy 197.422 -299.298138) (xy 197.406416 -299.344819) (xy 197.383545 -299.388396)
			(xy 197.35398 -299.42774) (xy 197.318487 -299.461832) (xy 197.277984 -299.489788) (xy 197.233522 -299.510886)
			(xy 197.186251 -299.524578) (xy 197.137396 -299.53051) (xy 197.088221 -299.528529) (xy 197.040002 -299.518685)
			(xy 196.993986 -299.501233) (xy 196.951365 -299.476626) (xy 196.913244 -299.445501) (xy 196.880609 -299.408664)
			(xy 196.854306 -299.367068) (xy 196.835015 -299.321792) (xy 196.823238 -299.274008) (xy 196.819278 -299.224954)
			(xy 196.480176 -299.224954) (xy 196.479681 -299.249561) (xy 196.471786 -299.298138) (xy 196.456202 -299.344819)
			(xy 196.433331 -299.388396) (xy 196.403766 -299.42774) (xy 196.368273 -299.461832) (xy 196.32777 -299.489788)
			(xy 196.283308 -299.510886) (xy 196.236037 -299.524578) (xy 196.187182 -299.53051) (xy 196.138007 -299.528529)
			(xy 196.089788 -299.518685) (xy 196.043772 -299.501233) (xy 196.001151 -299.476626) (xy 195.96303 -299.445501)
			(xy 195.930395 -299.408664) (xy 195.904092 -299.367068) (xy 195.884801 -299.321792) (xy 195.873024 -299.274008)
			(xy 195.869064 -299.224954) (xy 195.530216 -299.224954) (xy 195.529721 -299.249561) (xy 195.521826 -299.298138)
			(xy 195.506242 -299.344819) (xy 195.483371 -299.388396) (xy 195.453806 -299.42774) (xy 195.418313 -299.461832)
			(xy 195.37781 -299.489788) (xy 195.333348 -299.510886) (xy 195.286077 -299.524578) (xy 195.237222 -299.53051)
			(xy 195.188047 -299.528529) (xy 195.139828 -299.518685) (xy 195.093812 -299.501233) (xy 195.051191 -299.476626)
			(xy 195.01307 -299.445501) (xy 194.980435 -299.408664) (xy 194.954132 -299.367068) (xy 194.934841 -299.321792)
			(xy 194.923064 -299.274008) (xy 194.919104 -299.224954) (xy 194.580256 -299.224954) (xy 194.579761 -299.249561)
			(xy 194.571866 -299.298138) (xy 194.556282 -299.344819) (xy 194.533411 -299.388396) (xy 194.503846 -299.42774)
			(xy 194.468353 -299.461832) (xy 194.42785 -299.489788) (xy 194.383388 -299.510886) (xy 194.336117 -299.524578)
			(xy 194.287262 -299.53051) (xy 194.238087 -299.528529) (xy 194.189868 -299.518685) (xy 194.143852 -299.501233)
			(xy 194.101231 -299.476626) (xy 194.06311 -299.445501) (xy 194.030475 -299.408664) (xy 194.004172 -299.367068)
			(xy 193.984881 -299.321792) (xy 193.973104 -299.274008) (xy 193.969144 -299.224954) (xy 193.630296 -299.224954)
			(xy 193.629801 -299.249561) (xy 193.621906 -299.298138) (xy 193.606322 -299.344819) (xy 193.583451 -299.388396)
			(xy 193.553886 -299.42774) (xy 193.518393 -299.461832) (xy 193.47789 -299.489788) (xy 193.433428 -299.510886)
			(xy 193.386157 -299.524578) (xy 193.337302 -299.53051) (xy 193.288127 -299.528529) (xy 193.239908 -299.518685)
			(xy 193.193892 -299.501233) (xy 193.151271 -299.476626) (xy 193.11315 -299.445501) (xy 193.080515 -299.408664)
			(xy 193.054212 -299.367068) (xy 193.034921 -299.321792) (xy 193.023144 -299.274008) (xy 193.019184 -299.224954)
			(xy 192.680336 -299.224954) (xy 192.679841 -299.249561) (xy 192.671946 -299.298138) (xy 192.656362 -299.344819)
			(xy 192.633491 -299.388396) (xy 192.603926 -299.42774) (xy 192.568433 -299.461832) (xy 192.52793 -299.489788)
			(xy 192.483468 -299.510886) (xy 192.436197 -299.524578) (xy 192.387342 -299.53051) (xy 192.338167 -299.528529)
			(xy 192.289948 -299.518685) (xy 192.243932 -299.501233) (xy 192.201311 -299.476626) (xy 192.16319 -299.445501)
			(xy 192.130555 -299.408664) (xy 192.104252 -299.367068) (xy 192.084961 -299.321792) (xy 192.073184 -299.274008)
			(xy 192.069224 -299.224954) (xy 189.830202 -299.224954) (xy 189.829707 -299.249561) (xy 189.821812 -299.298138)
			(xy 189.806228 -299.344819) (xy 189.783357 -299.388396) (xy 189.753792 -299.42774) (xy 189.718299 -299.461832)
			(xy 189.677796 -299.489788) (xy 189.633334 -299.510886) (xy 189.586063 -299.524578) (xy 189.537208 -299.53051)
			(xy 189.488033 -299.528529) (xy 189.439814 -299.518685) (xy 189.393798 -299.501233) (xy 189.351177 -299.476626)
			(xy 189.313056 -299.445501) (xy 189.280421 -299.408664) (xy 189.254118 -299.367068) (xy 189.234827 -299.321792)
			(xy 189.22305 -299.274008) (xy 189.21909 -299.224954) (xy 188.880242 -299.224954) (xy 188.879747 -299.249561)
			(xy 188.871852 -299.298138) (xy 188.856268 -299.344819) (xy 188.833397 -299.388396) (xy 188.803832 -299.42774)
			(xy 188.768339 -299.461832) (xy 188.727836 -299.489788) (xy 188.683374 -299.510886) (xy 188.636103 -299.524578)
			(xy 188.587248 -299.53051) (xy 188.538073 -299.528529) (xy 188.489854 -299.518685) (xy 188.443838 -299.501233)
			(xy 188.401217 -299.476626) (xy 188.363096 -299.445501) (xy 188.330461 -299.408664) (xy 188.304158 -299.367068)
			(xy 188.284867 -299.321792) (xy 188.27309 -299.274008) (xy 188.26913 -299.224954) (xy 187.930282 -299.224954)
			(xy 187.929787 -299.249561) (xy 187.921892 -299.298138) (xy 187.906308 -299.344819) (xy 187.883437 -299.388396)
			(xy 187.853872 -299.42774) (xy 187.818379 -299.461832) (xy 187.777876 -299.489788) (xy 187.733414 -299.510886)
			(xy 187.686143 -299.524578) (xy 187.637288 -299.53051) (xy 187.588113 -299.528529) (xy 187.539894 -299.518685)
			(xy 187.493878 -299.501233) (xy 187.451257 -299.476626) (xy 187.413136 -299.445501) (xy 187.380501 -299.408664)
			(xy 187.354198 -299.367068) (xy 187.334907 -299.321792) (xy 187.32313 -299.274008) (xy 187.31917 -299.224954)
			(xy 186.980322 -299.224954) (xy 186.979827 -299.249561) (xy 186.971932 -299.298138) (xy 186.956348 -299.344819)
			(xy 186.933477 -299.388396) (xy 186.903912 -299.42774) (xy 186.868419 -299.461832) (xy 186.827916 -299.489788)
			(xy 186.783454 -299.510886) (xy 186.736183 -299.524578) (xy 186.687328 -299.53051) (xy 186.638153 -299.528529)
			(xy 186.589934 -299.518685) (xy 186.543918 -299.501233) (xy 186.501297 -299.476626) (xy 186.463176 -299.445501)
			(xy 186.430541 -299.408664) (xy 186.404238 -299.367068) (xy 186.384947 -299.321792) (xy 186.37317 -299.274008)
			(xy 186.36921 -299.224954) (xy 186.030362 -299.224954) (xy 186.029867 -299.249561) (xy 186.021972 -299.298138)
			(xy 186.006388 -299.344819) (xy 185.983517 -299.388396) (xy 185.953952 -299.42774) (xy 185.918459 -299.461832)
			(xy 185.877956 -299.489788) (xy 185.833494 -299.510886) (xy 185.786223 -299.524578) (xy 185.737368 -299.53051)
			(xy 185.688193 -299.528529) (xy 185.639974 -299.518685) (xy 185.593958 -299.501233) (xy 185.551337 -299.476626)
			(xy 185.513216 -299.445501) (xy 185.480581 -299.408664) (xy 185.454278 -299.367068) (xy 185.434987 -299.321792)
			(xy 185.42321 -299.274008) (xy 185.41925 -299.224954) (xy 185.080148 -299.224954) (xy 185.079653 -299.249561)
			(xy 185.071758 -299.298138) (xy 185.056174 -299.344819) (xy 185.033303 -299.388396) (xy 185.003738 -299.42774)
			(xy 184.968245 -299.461832) (xy 184.927742 -299.489788) (xy 184.88328 -299.510886) (xy 184.836009 -299.524578)
			(xy 184.787154 -299.53051) (xy 184.737979 -299.528529) (xy 184.68976 -299.518685) (xy 184.643744 -299.501233)
			(xy 184.601123 -299.476626) (xy 184.563002 -299.445501) (xy 184.530367 -299.408664) (xy 184.504064 -299.367068)
			(xy 184.484773 -299.321792) (xy 184.472996 -299.274008) (xy 184.469036 -299.224954) (xy 184.130188 -299.224954)
			(xy 184.129693 -299.249561) (xy 184.121798 -299.298138) (xy 184.106214 -299.344819) (xy 184.083343 -299.388396)
			(xy 184.053778 -299.42774) (xy 184.018285 -299.461832) (xy 183.977782 -299.489788) (xy 183.93332 -299.510886)
			(xy 183.886049 -299.524578) (xy 183.837194 -299.53051) (xy 183.788019 -299.528529) (xy 183.7398 -299.518685)
			(xy 183.693784 -299.501233) (xy 183.651163 -299.476626) (xy 183.613042 -299.445501) (xy 183.580407 -299.408664)
			(xy 183.554104 -299.367068) (xy 183.534813 -299.321792) (xy 183.523036 -299.274008) (xy 183.519076 -299.224954)
			(xy 183.180228 -299.224954) (xy 183.179733 -299.249561) (xy 183.171838 -299.298138) (xy 183.156254 -299.344819)
			(xy 183.133383 -299.388396) (xy 183.103818 -299.42774) (xy 183.068325 -299.461832) (xy 183.027822 -299.489788)
			(xy 182.98336 -299.510886) (xy 182.936089 -299.524578) (xy 182.887234 -299.53051) (xy 182.838059 -299.528529)
			(xy 182.78984 -299.518685) (xy 182.743824 -299.501233) (xy 182.701203 -299.476626) (xy 182.663082 -299.445501)
			(xy 182.630447 -299.408664) (xy 182.604144 -299.367068) (xy 182.584853 -299.321792) (xy 182.573076 -299.274008)
			(xy 182.569116 -299.224954) (xy 182.230268 -299.224954) (xy 182.229773 -299.249561) (xy 182.221878 -299.298138)
			(xy 182.206294 -299.344819) (xy 182.183423 -299.388396) (xy 182.153858 -299.42774) (xy 182.118365 -299.461832)
			(xy 182.077862 -299.489788) (xy 182.0334 -299.510886) (xy 181.986129 -299.524578) (xy 181.937274 -299.53051)
			(xy 181.888099 -299.528529) (xy 181.83988 -299.518685) (xy 181.793864 -299.501233) (xy 181.751243 -299.476626)
			(xy 181.713122 -299.445501) (xy 181.680487 -299.408664) (xy 181.654184 -299.367068) (xy 181.634893 -299.321792)
			(xy 181.623116 -299.274008) (xy 181.619156 -299.224954) (xy 181.280308 -299.224954) (xy 181.279813 -299.249561)
			(xy 181.271918 -299.298138) (xy 181.256334 -299.344819) (xy 181.233463 -299.388396) (xy 181.203898 -299.42774)
			(xy 181.168405 -299.461832) (xy 181.127902 -299.489788) (xy 181.08344 -299.510886) (xy 181.036169 -299.524578)
			(xy 180.987314 -299.53051) (xy 180.938139 -299.528529) (xy 180.88992 -299.518685) (xy 180.843904 -299.501233)
			(xy 180.801283 -299.476626) (xy 180.763162 -299.445501) (xy 180.730527 -299.408664) (xy 180.704224 -299.367068)
			(xy 180.684933 -299.321792) (xy 180.673156 -299.274008) (xy 180.669196 -299.224954) (xy 180.330348 -299.224954)
			(xy 180.329853 -299.249561) (xy 180.321958 -299.298138) (xy 180.306374 -299.344819) (xy 180.283503 -299.388396)
			(xy 180.253938 -299.42774) (xy 180.218445 -299.461832) (xy 180.177942 -299.489788) (xy 180.13348 -299.510886)
			(xy 180.086209 -299.524578) (xy 180.037354 -299.53051) (xy 179.988179 -299.528529) (xy 179.93996 -299.518685)
			(xy 179.893944 -299.501233) (xy 179.851323 -299.476626) (xy 179.813202 -299.445501) (xy 179.780567 -299.408664)
			(xy 179.754264 -299.367068) (xy 179.734973 -299.321792) (xy 179.723196 -299.274008) (xy 179.719236 -299.224954)
			(xy 179.380388 -299.224954) (xy 179.379893 -299.249561) (xy 179.371998 -299.298138) (xy 179.356414 -299.344819)
			(xy 179.333543 -299.388396) (xy 179.303978 -299.42774) (xy 179.268485 -299.461832) (xy 179.227982 -299.489788)
			(xy 179.18352 -299.510886) (xy 179.136249 -299.524578) (xy 179.087394 -299.53051) (xy 179.038219 -299.528529)
			(xy 178.99 -299.518685) (xy 178.943984 -299.501233) (xy 178.901363 -299.476626) (xy 178.863242 -299.445501)
			(xy 178.830607 -299.408664) (xy 178.804304 -299.367068) (xy 178.785013 -299.321792) (xy 178.773236 -299.274008)
			(xy 178.769276 -299.224954) (xy 178.430174 -299.224954) (xy 178.429679 -299.249561) (xy 178.421784 -299.298138)
			(xy 178.4062 -299.344819) (xy 178.383329 -299.388396) (xy 178.353764 -299.42774) (xy 178.318271 -299.461832)
			(xy 178.277768 -299.489788) (xy 178.233306 -299.510886) (xy 178.186035 -299.524578) (xy 178.13718 -299.53051)
			(xy 178.088005 -299.528529) (xy 178.039786 -299.518685) (xy 177.99377 -299.501233) (xy 177.951149 -299.476626)
			(xy 177.913028 -299.445501) (xy 177.880393 -299.408664) (xy 177.85409 -299.367068) (xy 177.834799 -299.321792)
			(xy 177.823022 -299.274008) (xy 177.819062 -299.224954) (xy 177.480214 -299.224954) (xy 177.479719 -299.249561)
			(xy 177.471824 -299.298138) (xy 177.45624 -299.344819) (xy 177.433369 -299.388396) (xy 177.403804 -299.42774)
			(xy 177.368311 -299.461832) (xy 177.327808 -299.489788) (xy 177.283346 -299.510886) (xy 177.236075 -299.524578)
			(xy 177.18722 -299.53051) (xy 177.138045 -299.528529) (xy 177.089826 -299.518685) (xy 177.04381 -299.501233)
			(xy 177.001189 -299.476626) (xy 176.963068 -299.445501) (xy 176.930433 -299.408664) (xy 176.90413 -299.367068)
			(xy 176.884839 -299.321792) (xy 176.873062 -299.274008) (xy 176.869102 -299.224954) (xy 176.530254 -299.224954)
			(xy 176.529759 -299.249561) (xy 176.521864 -299.298138) (xy 176.50628 -299.344819) (xy 176.483409 -299.388396)
			(xy 176.453844 -299.42774) (xy 176.418351 -299.461832) (xy 176.377848 -299.489788) (xy 176.333386 -299.510886)
			(xy 176.286115 -299.524578) (xy 176.23726 -299.53051) (xy 176.188085 -299.528529) (xy 176.139866 -299.518685)
			(xy 176.09385 -299.501233) (xy 176.051229 -299.476626) (xy 176.013108 -299.445501) (xy 175.980473 -299.408664)
			(xy 175.95417 -299.367068) (xy 175.934879 -299.321792) (xy 175.923102 -299.274008) (xy 175.919142 -299.224954)
			(xy 174.630334 -299.224954) (xy 174.629839 -299.249561) (xy 174.621944 -299.298138) (xy 174.60636 -299.344819)
			(xy 174.583489 -299.388396) (xy 174.553924 -299.42774) (xy 174.518431 -299.461832) (xy 174.477928 -299.489788)
			(xy 174.433466 -299.510886) (xy 174.386195 -299.524578) (xy 174.33734 -299.53051) (xy 174.288165 -299.528529)
			(xy 174.239946 -299.518685) (xy 174.19393 -299.501233) (xy 174.151309 -299.476626) (xy 174.113188 -299.445501)
			(xy 174.080553 -299.408664) (xy 174.05425 -299.367068) (xy 174.034959 -299.321792) (xy 174.023182 -299.274008)
			(xy 174.019222 -299.224954) (xy 173.680374 -299.224954) (xy 173.679879 -299.249561) (xy 173.671984 -299.298138)
			(xy 173.6564 -299.344819) (xy 173.633529 -299.388396) (xy 173.603964 -299.42774) (xy 173.568471 -299.461832)
			(xy 173.527968 -299.489788) (xy 173.483506 -299.510886) (xy 173.436235 -299.524578) (xy 173.38738 -299.53051)
			(xy 173.338205 -299.528529) (xy 173.289986 -299.518685) (xy 173.24397 -299.501233) (xy 173.201349 -299.476626)
			(xy 173.163228 -299.445501) (xy 173.130593 -299.408664) (xy 173.10429 -299.367068) (xy 173.084999 -299.321792)
			(xy 173.073222 -299.274008) (xy 173.069262 -299.224954) (xy 172.73016 -299.224954) (xy 172.729665 -299.249561)
			(xy 172.72177 -299.298138) (xy 172.706186 -299.344819) (xy 172.683315 -299.388396) (xy 172.65375 -299.42774)
			(xy 172.618257 -299.461832) (xy 172.577754 -299.489788) (xy 172.533292 -299.510886) (xy 172.486021 -299.524578)
			(xy 172.437166 -299.53051) (xy 172.387991 -299.528529) (xy 172.339772 -299.518685) (xy 172.293756 -299.501233)
			(xy 172.251135 -299.476626) (xy 172.213014 -299.445501) (xy 172.180379 -299.408664) (xy 172.154076 -299.367068)
			(xy 172.134785 -299.321792) (xy 172.123008 -299.274008) (xy 172.119048 -299.224954) (xy 171.7802 -299.224954)
			(xy 171.779705 -299.249561) (xy 171.77181 -299.298138) (xy 171.756226 -299.344819) (xy 171.733355 -299.388396)
			(xy 171.70379 -299.42774) (xy 171.668297 -299.461832) (xy 171.627794 -299.489788) (xy 171.583332 -299.510886)
			(xy 171.536061 -299.524578) (xy 171.487206 -299.53051) (xy 171.438031 -299.528529) (xy 171.389812 -299.518685)
			(xy 171.343796 -299.501233) (xy 171.301175 -299.476626) (xy 171.263054 -299.445501) (xy 171.230419 -299.408664)
			(xy 171.204116 -299.367068) (xy 171.184825 -299.321792) (xy 171.173048 -299.274008) (xy 171.169088 -299.224954)
			(xy 170.83024 -299.224954) (xy 170.829745 -299.249561) (xy 170.82185 -299.298138) (xy 170.806266 -299.344819)
			(xy 170.783395 -299.388396) (xy 170.75383 -299.42774) (xy 170.718337 -299.461832) (xy 170.677834 -299.489788)
			(xy 170.633372 -299.510886) (xy 170.586101 -299.524578) (xy 170.537246 -299.53051) (xy 170.488071 -299.528529)
			(xy 170.439852 -299.518685) (xy 170.393836 -299.501233) (xy 170.351215 -299.476626) (xy 170.313094 -299.445501)
			(xy 170.280459 -299.408664) (xy 170.254156 -299.367068) (xy 170.234865 -299.321792) (xy 170.223088 -299.274008)
			(xy 170.219128 -299.224954) (xy 169.88028 -299.224954) (xy 169.879785 -299.249561) (xy 169.87189 -299.298138)
			(xy 169.856306 -299.344819) (xy 169.833435 -299.388396) (xy 169.80387 -299.42774) (xy 169.768377 -299.461832)
			(xy 169.727874 -299.489788) (xy 169.683412 -299.510886) (xy 169.636141 -299.524578) (xy 169.587286 -299.53051)
			(xy 169.538111 -299.528529) (xy 169.489892 -299.518685) (xy 169.443876 -299.501233) (xy 169.401255 -299.476626)
			(xy 169.363134 -299.445501) (xy 169.330499 -299.408664) (xy 169.304196 -299.367068) (xy 169.284905 -299.321792)
			(xy 169.273128 -299.274008) (xy 169.269168 -299.224954) (xy 168.93032 -299.224954) (xy 168.929825 -299.249561)
			(xy 168.92193 -299.298138) (xy 168.906346 -299.344819) (xy 168.883475 -299.388396) (xy 168.85391 -299.42774)
			(xy 168.818417 -299.461832) (xy 168.777914 -299.489788) (xy 168.733452 -299.510886) (xy 168.686181 -299.524578)
			(xy 168.637326 -299.53051) (xy 168.588151 -299.528529) (xy 168.539932 -299.518685) (xy 168.493916 -299.501233)
			(xy 168.451295 -299.476626) (xy 168.413174 -299.445501) (xy 168.380539 -299.408664) (xy 168.354236 -299.367068)
			(xy 168.334945 -299.321792) (xy 168.323168 -299.274008) (xy 168.319208 -299.224954) (xy 167.98036 -299.224954)
			(xy 167.979865 -299.249561) (xy 167.97197 -299.298138) (xy 167.956386 -299.344819) (xy 167.933515 -299.388396)
			(xy 167.90395 -299.42774) (xy 167.868457 -299.461832) (xy 167.827954 -299.489788) (xy 167.783492 -299.510886)
			(xy 167.736221 -299.524578) (xy 167.687366 -299.53051) (xy 167.638191 -299.528529) (xy 167.589972 -299.518685)
			(xy 167.543956 -299.501233) (xy 167.501335 -299.476626) (xy 167.463214 -299.445501) (xy 167.430579 -299.408664)
			(xy 167.404276 -299.367068) (xy 167.384985 -299.321792) (xy 167.373208 -299.274008) (xy 167.369248 -299.224954)
			(xy 167.0304 -299.224954) (xy 167.029905 -299.249561) (xy 167.02201 -299.298138) (xy 167.006426 -299.344819)
			(xy 166.983555 -299.388396) (xy 166.95399 -299.42774) (xy 166.918497 -299.461832) (xy 166.877994 -299.489788)
			(xy 166.833532 -299.510886) (xy 166.786261 -299.524578) (xy 166.737406 -299.53051) (xy 166.688231 -299.528529)
			(xy 166.640012 -299.518685) (xy 166.593996 -299.501233) (xy 166.551375 -299.476626) (xy 166.513254 -299.445501)
			(xy 166.480619 -299.408664) (xy 166.454316 -299.367068) (xy 166.435025 -299.321792) (xy 166.423248 -299.274008)
			(xy 166.419288 -299.224954) (xy 166.080186 -299.224954) (xy 166.079691 -299.249561) (xy 166.071796 -299.298138)
			(xy 166.056212 -299.344819) (xy 166.033341 -299.388396) (xy 166.003776 -299.42774) (xy 165.968283 -299.461832)
			(xy 165.92778 -299.489788) (xy 165.883318 -299.510886) (xy 165.836047 -299.524578) (xy 165.787192 -299.53051)
			(xy 165.738017 -299.528529) (xy 165.689798 -299.518685) (xy 165.643782 -299.501233) (xy 165.601161 -299.476626)
			(xy 165.56304 -299.445501) (xy 165.530405 -299.408664) (xy 165.504102 -299.367068) (xy 165.484811 -299.321792)
			(xy 165.473034 -299.274008) (xy 165.469074 -299.224954) (xy 165.155129 -299.224954) (xy 165.15513 -299.251379)
			(xy 165.146751 -299.30348) (xy 165.130207 -299.35359) (xy 165.105915 -299.400437) (xy 165.074493 -299.442832)
			(xy 165.036738 -299.4797) (xy 164.993607 -299.510106) (xy 164.946196 -299.533277) (xy 164.895708 -299.548626)
			(xy 164.869622 -299.552614) (xy 164.86505 -299.553376) (xy 164.854636 -299.556678) (xy 164.850318 -299.557948)
			(xy 164.826696 -299.56887) (xy 164.819838 -299.575982) (xy 164.804852 -299.59173) (xy 164.800267 -299.596836)
			(xy 164.793828 -299.608951) (xy 164.792152 -299.615606) (xy 164.790882 -299.626528) (xy 164.790882 -299.76445)
			(xy 204.14183 -299.76445) (xy 204.145901 -299.708828) (xy 204.158027 -299.654391) (xy 204.17795 -299.6023)
			(xy 204.205246 -299.553665) (xy 204.239332 -299.509522) (xy 204.279481 -299.470813) (xy 204.324839 -299.438362)
			(xy 204.374439 -299.412861) (xy 204.427223 -299.394854) (xy 204.482066 -299.384724) (xy 204.5378 -299.382687)
			(xy 204.593237 -299.388787) (xy 204.647194 -299.402893) (xy 204.698523 -299.424705) (xy 204.746129 -299.453759)
			(xy 204.788997 -299.489434) (xy 204.826214 -299.530971) (xy 204.856987 -299.577484) (xy 204.880659 -299.627981)
			(xy 204.896727 -299.681388) (xy 204.904847 -299.736564) (xy 204.905356 -299.76445) (xy 204.905078 -299.77969)
			(xy 208.738468 -299.77969) (xy 208.742539 -299.724068) (xy 208.754665 -299.669631) (xy 208.774588 -299.61754)
			(xy 208.801884 -299.568905) (xy 208.83597 -299.524762) (xy 208.876119 -299.486053) (xy 208.921477 -299.453602)
			(xy 208.971077 -299.428101) (xy 209.023861 -299.410094) (xy 209.078704 -299.399964) (xy 209.134438 -299.397927)
			(xy 209.189875 -299.404027) (xy 209.243832 -299.418133) (xy 209.295161 -299.439945) (xy 209.342767 -299.468999)
			(xy 209.385635 -299.504674) (xy 209.422852 -299.546211) (xy 209.453625 -299.592724) (xy 209.477297 -299.643221)
			(xy 209.493365 -299.696628) (xy 209.501485 -299.751804) (xy 209.501994 -299.77969) (xy 209.501485 -299.807576)
			(xy 209.493365 -299.862752) (xy 209.477297 -299.916159) (xy 209.453625 -299.966656) (xy 209.422852 -300.013169)
			(xy 209.385635 -300.054706) (xy 209.342767 -300.090381) (xy 209.295161 -300.119435) (xy 209.243832 -300.141247)
			(xy 209.189875 -300.155353) (xy 209.134438 -300.161453) (xy 209.078704 -300.159416) (xy 209.023861 -300.149286)
			(xy 208.971077 -300.131279) (xy 208.921477 -300.105778) (xy 208.876119 -300.073327) (xy 208.83597 -300.034618)
			(xy 208.801884 -299.990475) (xy 208.774588 -299.94184) (xy 208.754665 -299.889749) (xy 208.742539 -299.835312)
			(xy 208.738468 -299.77969) (xy 204.905078 -299.77969) (xy 204.904847 -299.792336) (xy 204.896727 -299.847512)
			(xy 204.880659 -299.900919) (xy 204.856987 -299.951416) (xy 204.826214 -299.997929) (xy 204.788997 -300.039466)
			(xy 204.746129 -300.075141) (xy 204.698523 -300.104195) (xy 204.647194 -300.126007) (xy 204.593237 -300.140113)
			(xy 204.5378 -300.146213) (xy 204.482066 -300.144176) (xy 204.427223 -300.134046) (xy 204.374439 -300.116039)
			(xy 204.324839 -300.090538) (xy 204.279481 -300.058087) (xy 204.239332 -300.019378) (xy 204.205246 -299.975235)
			(xy 204.17795 -299.9266) (xy 204.158027 -299.874509) (xy 204.145901 -299.820072) (xy 204.14183 -299.76445)
			(xy 164.790882 -299.76445) (xy 164.790882 -299.77334) (xy 164.791048 -299.779494) (xy 164.793999 -299.791442)
			(xy 164.796724 -299.796962) (xy 164.804852 -299.808138) (xy 164.819584 -299.823632) (xy 164.826188 -299.830744)
			(xy 164.849302 -299.841666) (xy 164.852858 -299.842682) (xy 164.86505 -299.846492) (xy 164.869622 -299.847254)
			(xy 164.895691 -299.851331) (xy 164.946171 -299.866677) (xy 164.993573 -299.889843) (xy 165.036696 -299.920243)
			(xy 165.074445 -299.957104) (xy 165.105862 -299.999491) (xy 165.13015 -300.046329) (xy 165.146693 -300.09643)
			(xy 165.15507 -300.148521) (xy 165.15507 -300.174914) (xy 165.469074 -300.174914) (xy 165.473034 -300.12586)
			(xy 165.484811 -300.078076) (xy 165.504102 -300.0328) (xy 165.530405 -299.991204) (xy 165.56304 -299.954367)
			(xy 165.601161 -299.923242) (xy 165.643782 -299.898635) (xy 165.689798 -299.881183) (xy 165.738017 -299.871339)
			(xy 165.787192 -299.869358) (xy 165.836047 -299.87529) (xy 165.883318 -299.888982) (xy 165.92778 -299.91008)
			(xy 165.968283 -299.938036) (xy 166.003776 -299.972128) (xy 166.033341 -300.011472) (xy 166.056212 -300.055049)
			(xy 166.071796 -300.10173) (xy 166.079691 -300.150307) (xy 166.080186 -300.174914) (xy 166.419288 -300.174914)
			(xy 166.423248 -300.12586) (xy 166.435025 -300.078076) (xy 166.454316 -300.0328) (xy 166.480619 -299.991204)
			(xy 166.513254 -299.954367) (xy 166.551375 -299.923242) (xy 166.593996 -299.898635) (xy 166.640012 -299.881183)
			(xy 166.688231 -299.871339) (xy 166.737406 -299.869358) (xy 166.786261 -299.87529) (xy 166.833532 -299.888982)
			(xy 166.877994 -299.91008) (xy 166.918497 -299.938036) (xy 166.95399 -299.972128) (xy 166.983555 -300.011472)
			(xy 167.006426 -300.055049) (xy 167.02201 -300.10173) (xy 167.029905 -300.150307) (xy 167.0304 -300.174914)
			(xy 167.369248 -300.174914) (xy 167.373208 -300.12586) (xy 167.384985 -300.078076) (xy 167.404276 -300.0328)
			(xy 167.430579 -299.991204) (xy 167.463214 -299.954367) (xy 167.501335 -299.923242) (xy 167.543956 -299.898635)
			(xy 167.589972 -299.881183) (xy 167.638191 -299.871339) (xy 167.687366 -299.869358) (xy 167.736221 -299.87529)
			(xy 167.783492 -299.888982) (xy 167.827954 -299.91008) (xy 167.868457 -299.938036) (xy 167.90395 -299.972128)
			(xy 167.933515 -300.011472) (xy 167.956386 -300.055049) (xy 167.97197 -300.10173) (xy 167.979865 -300.150307)
			(xy 167.98036 -300.174914) (xy 168.319208 -300.174914) (xy 168.323168 -300.12586) (xy 168.334945 -300.078076)
			(xy 168.354236 -300.0328) (xy 168.380539 -299.991204) (xy 168.413174 -299.954367) (xy 168.451295 -299.923242)
			(xy 168.493916 -299.898635) (xy 168.539932 -299.881183) (xy 168.588151 -299.871339) (xy 168.637326 -299.869358)
			(xy 168.686181 -299.87529) (xy 168.733452 -299.888982) (xy 168.777914 -299.91008) (xy 168.818417 -299.938036)
			(xy 168.85391 -299.972128) (xy 168.883475 -300.011472) (xy 168.906346 -300.055049) (xy 168.92193 -300.10173)
			(xy 168.929825 -300.150307) (xy 168.93032 -300.174914) (xy 169.269168 -300.174914) (xy 169.273128 -300.12586)
			(xy 169.284905 -300.078076) (xy 169.304196 -300.0328) (xy 169.330499 -299.991204) (xy 169.363134 -299.954367)
			(xy 169.401255 -299.923242) (xy 169.443876 -299.898635) (xy 169.489892 -299.881183) (xy 169.538111 -299.871339)
			(xy 169.587286 -299.869358) (xy 169.636141 -299.87529) (xy 169.683412 -299.888982) (xy 169.727874 -299.91008)
			(xy 169.768377 -299.938036) (xy 169.80387 -299.972128) (xy 169.833435 -300.011472) (xy 169.856306 -300.055049)
			(xy 169.87189 -300.10173) (xy 169.879785 -300.150307) (xy 169.88028 -300.174914) (xy 170.219128 -300.174914)
			(xy 170.223088 -300.12586) (xy 170.234865 -300.078076) (xy 170.254156 -300.0328) (xy 170.280459 -299.991204)
			(xy 170.313094 -299.954367) (xy 170.351215 -299.923242) (xy 170.393836 -299.898635) (xy 170.439852 -299.881183)
			(xy 170.488071 -299.871339) (xy 170.537246 -299.869358) (xy 170.586101 -299.87529) (xy 170.633372 -299.888982)
			(xy 170.677834 -299.91008) (xy 170.718337 -299.938036) (xy 170.75383 -299.972128) (xy 170.783395 -300.011472)
			(xy 170.806266 -300.055049) (xy 170.82185 -300.10173) (xy 170.829745 -300.150307) (xy 170.83024 -300.174914)
			(xy 171.169088 -300.174914) (xy 171.173048 -300.12586) (xy 171.184825 -300.078076) (xy 171.204116 -300.0328)
			(xy 171.230419 -299.991204) (xy 171.263054 -299.954367) (xy 171.301175 -299.923242) (xy 171.343796 -299.898635)
			(xy 171.389812 -299.881183) (xy 171.438031 -299.871339) (xy 171.487206 -299.869358) (xy 171.536061 -299.87529)
			(xy 171.583332 -299.888982) (xy 171.627794 -299.91008) (xy 171.668297 -299.938036) (xy 171.70379 -299.972128)
			(xy 171.733355 -300.011472) (xy 171.756226 -300.055049) (xy 171.77181 -300.10173) (xy 171.779705 -300.150307)
			(xy 171.7802 -300.174914) (xy 172.119048 -300.174914) (xy 172.123008 -300.12586) (xy 172.134785 -300.078076)
			(xy 172.154076 -300.0328) (xy 172.180379 -299.991204) (xy 172.213014 -299.954367) (xy 172.251135 -299.923242)
			(xy 172.293756 -299.898635) (xy 172.339772 -299.881183) (xy 172.387991 -299.871339) (xy 172.437166 -299.869358)
			(xy 172.486021 -299.87529) (xy 172.533292 -299.888982) (xy 172.577754 -299.91008) (xy 172.618257 -299.938036)
			(xy 172.65375 -299.972128) (xy 172.683315 -300.011472) (xy 172.706186 -300.055049) (xy 172.72177 -300.10173)
			(xy 172.729665 -300.150307) (xy 172.73016 -300.174914) (xy 173.069262 -300.174914) (xy 173.073222 -300.12586)
			(xy 173.084999 -300.078076) (xy 173.10429 -300.0328) (xy 173.130593 -299.991204) (xy 173.163228 -299.954367)
			(xy 173.201349 -299.923242) (xy 173.24397 -299.898635) (xy 173.289986 -299.881183) (xy 173.338205 -299.871339)
			(xy 173.38738 -299.869358) (xy 173.436235 -299.87529) (xy 173.483506 -299.888982) (xy 173.527968 -299.91008)
			(xy 173.568471 -299.938036) (xy 173.603964 -299.972128) (xy 173.633529 -300.011472) (xy 173.6564 -300.055049)
			(xy 173.671984 -300.10173) (xy 173.679879 -300.150307) (xy 173.680374 -300.174914) (xy 174.019222 -300.174914)
			(xy 174.023182 -300.12586) (xy 174.034959 -300.078076) (xy 174.05425 -300.0328) (xy 174.080553 -299.991204)
			(xy 174.113188 -299.954367) (xy 174.151309 -299.923242) (xy 174.19393 -299.898635) (xy 174.239946 -299.881183)
			(xy 174.288165 -299.871339) (xy 174.33734 -299.869358) (xy 174.386195 -299.87529) (xy 174.433466 -299.888982)
			(xy 174.477928 -299.91008) (xy 174.518431 -299.938036) (xy 174.553924 -299.972128) (xy 174.583489 -300.011472)
			(xy 174.60636 -300.055049) (xy 174.621944 -300.10173) (xy 174.629839 -300.150307) (xy 174.630334 -300.174914)
			(xy 175.919142 -300.174914) (xy 175.923102 -300.12586) (xy 175.934879 -300.078076) (xy 175.95417 -300.0328)
			(xy 175.980473 -299.991204) (xy 176.013108 -299.954367) (xy 176.051229 -299.923242) (xy 176.09385 -299.898635)
			(xy 176.139866 -299.881183) (xy 176.188085 -299.871339) (xy 176.23726 -299.869358) (xy 176.286115 -299.87529)
			(xy 176.333386 -299.888982) (xy 176.377848 -299.91008) (xy 176.418351 -299.938036) (xy 176.453844 -299.972128)
			(xy 176.483409 -300.011472) (xy 176.50628 -300.055049) (xy 176.521864 -300.10173) (xy 176.529759 -300.150307)
			(xy 176.530254 -300.174914) (xy 176.869102 -300.174914) (xy 176.873062 -300.12586) (xy 176.884839 -300.078076)
			(xy 176.90413 -300.0328) (xy 176.930433 -299.991204) (xy 176.963068 -299.954367) (xy 177.001189 -299.923242)
			(xy 177.04381 -299.898635) (xy 177.089826 -299.881183) (xy 177.138045 -299.871339) (xy 177.18722 -299.869358)
			(xy 177.236075 -299.87529) (xy 177.283346 -299.888982) (xy 177.327808 -299.91008) (xy 177.368311 -299.938036)
			(xy 177.403804 -299.972128) (xy 177.433369 -300.011472) (xy 177.45624 -300.055049) (xy 177.471824 -300.10173)
			(xy 177.479719 -300.150307) (xy 177.480214 -300.174914) (xy 177.819062 -300.174914) (xy 177.823022 -300.12586)
			(xy 177.834799 -300.078076) (xy 177.85409 -300.0328) (xy 177.880393 -299.991204) (xy 177.913028 -299.954367)
			(xy 177.951149 -299.923242) (xy 177.99377 -299.898635) (xy 178.039786 -299.881183) (xy 178.088005 -299.871339)
			(xy 178.13718 -299.869358) (xy 178.186035 -299.87529) (xy 178.233306 -299.888982) (xy 178.277768 -299.91008)
			(xy 178.318271 -299.938036) (xy 178.353764 -299.972128) (xy 178.383329 -300.011472) (xy 178.4062 -300.055049)
			(xy 178.421784 -300.10173) (xy 178.429679 -300.150307) (xy 178.430174 -300.174914) (xy 178.769276 -300.174914)
			(xy 178.773236 -300.12586) (xy 178.785013 -300.078076) (xy 178.804304 -300.0328) (xy 178.830607 -299.991204)
			(xy 178.863242 -299.954367) (xy 178.901363 -299.923242) (xy 178.943984 -299.898635) (xy 178.99 -299.881183)
			(xy 179.038219 -299.871339) (xy 179.087394 -299.869358) (xy 179.136249 -299.87529) (xy 179.18352 -299.888982)
			(xy 179.227982 -299.91008) (xy 179.268485 -299.938036) (xy 179.303978 -299.972128) (xy 179.333543 -300.011472)
			(xy 179.356414 -300.055049) (xy 179.371998 -300.10173) (xy 179.379893 -300.150307) (xy 179.380388 -300.174914)
			(xy 179.719236 -300.174914) (xy 179.723196 -300.12586) (xy 179.734973 -300.078076) (xy 179.754264 -300.0328)
			(xy 179.780567 -299.991204) (xy 179.813202 -299.954367) (xy 179.851323 -299.923242) (xy 179.893944 -299.898635)
			(xy 179.93996 -299.881183) (xy 179.988179 -299.871339) (xy 180.037354 -299.869358) (xy 180.086209 -299.87529)
			(xy 180.13348 -299.888982) (xy 180.177942 -299.91008) (xy 180.218445 -299.938036) (xy 180.253938 -299.972128)
			(xy 180.283503 -300.011472) (xy 180.306374 -300.055049) (xy 180.321958 -300.10173) (xy 180.329853 -300.150307)
			(xy 180.330348 -300.174914) (xy 180.669196 -300.174914) (xy 180.673156 -300.12586) (xy 180.684933 -300.078076)
			(xy 180.704224 -300.0328) (xy 180.730527 -299.991204) (xy 180.763162 -299.954367) (xy 180.801283 -299.923242)
			(xy 180.843904 -299.898635) (xy 180.88992 -299.881183) (xy 180.938139 -299.871339) (xy 180.987314 -299.869358)
			(xy 181.036169 -299.87529) (xy 181.08344 -299.888982) (xy 181.127902 -299.91008) (xy 181.168405 -299.938036)
			(xy 181.203898 -299.972128) (xy 181.233463 -300.011472) (xy 181.256334 -300.055049) (xy 181.271918 -300.10173)
			(xy 181.279813 -300.150307) (xy 181.280308 -300.174914) (xy 181.619156 -300.174914) (xy 181.623116 -300.12586)
			(xy 181.634893 -300.078076) (xy 181.654184 -300.0328) (xy 181.680487 -299.991204) (xy 181.713122 -299.954367)
			(xy 181.751243 -299.923242) (xy 181.793864 -299.898635) (xy 181.83988 -299.881183) (xy 181.888099 -299.871339)
			(xy 181.937274 -299.869358) (xy 181.986129 -299.87529) (xy 182.0334 -299.888982) (xy 182.077862 -299.91008)
			(xy 182.118365 -299.938036) (xy 182.153858 -299.972128) (xy 182.183423 -300.011472) (xy 182.206294 -300.055049)
			(xy 182.221878 -300.10173) (xy 182.229773 -300.150307) (xy 182.230268 -300.174914) (xy 182.569116 -300.174914)
			(xy 182.573076 -300.12586) (xy 182.584853 -300.078076) (xy 182.604144 -300.0328) (xy 182.630447 -299.991204)
			(xy 182.663082 -299.954367) (xy 182.701203 -299.923242) (xy 182.743824 -299.898635) (xy 182.78984 -299.881183)
			(xy 182.838059 -299.871339) (xy 182.887234 -299.869358) (xy 182.936089 -299.87529) (xy 182.98336 -299.888982)
			(xy 183.027822 -299.91008) (xy 183.068325 -299.938036) (xy 183.103818 -299.972128) (xy 183.133383 -300.011472)
			(xy 183.156254 -300.055049) (xy 183.171838 -300.10173) (xy 183.179733 -300.150307) (xy 183.180228 -300.174914)
			(xy 183.519076 -300.174914) (xy 183.523036 -300.12586) (xy 183.534813 -300.078076) (xy 183.554104 -300.0328)
			(xy 183.580407 -299.991204) (xy 183.613042 -299.954367) (xy 183.651163 -299.923242) (xy 183.693784 -299.898635)
			(xy 183.7398 -299.881183) (xy 183.788019 -299.871339) (xy 183.837194 -299.869358) (xy 183.886049 -299.87529)
			(xy 183.93332 -299.888982) (xy 183.977782 -299.91008) (xy 184.018285 -299.938036) (xy 184.053778 -299.972128)
			(xy 184.083343 -300.011472) (xy 184.106214 -300.055049) (xy 184.121798 -300.10173) (xy 184.129693 -300.150307)
			(xy 184.130188 -300.174914) (xy 184.469036 -300.174914) (xy 184.472996 -300.12586) (xy 184.484773 -300.078076)
			(xy 184.504064 -300.0328) (xy 184.530367 -299.991204) (xy 184.563002 -299.954367) (xy 184.601123 -299.923242)
			(xy 184.643744 -299.898635) (xy 184.68976 -299.881183) (xy 184.737979 -299.871339) (xy 184.787154 -299.869358)
			(xy 184.836009 -299.87529) (xy 184.88328 -299.888982) (xy 184.927742 -299.91008) (xy 184.968245 -299.938036)
			(xy 185.003738 -299.972128) (xy 185.033303 -300.011472) (xy 185.056174 -300.055049) (xy 185.071758 -300.10173)
			(xy 185.079653 -300.150307) (xy 185.080148 -300.174914) (xy 185.41925 -300.174914) (xy 185.42321 -300.12586)
			(xy 185.434987 -300.078076) (xy 185.454278 -300.0328) (xy 185.480581 -299.991204) (xy 185.513216 -299.954367)
			(xy 185.551337 -299.923242) (xy 185.593958 -299.898635) (xy 185.639974 -299.881183) (xy 185.688193 -299.871339)
			(xy 185.737368 -299.869358) (xy 185.786223 -299.87529) (xy 185.833494 -299.888982) (xy 185.877956 -299.91008)
			(xy 185.918459 -299.938036) (xy 185.953952 -299.972128) (xy 185.983517 -300.011472) (xy 186.006388 -300.055049)
			(xy 186.021972 -300.10173) (xy 186.029867 -300.150307) (xy 186.030362 -300.174914) (xy 186.36921 -300.174914)
			(xy 186.37317 -300.12586) (xy 186.384947 -300.078076) (xy 186.404238 -300.0328) (xy 186.430541 -299.991204)
			(xy 186.463176 -299.954367) (xy 186.501297 -299.923242) (xy 186.543918 -299.898635) (xy 186.589934 -299.881183)
			(xy 186.638153 -299.871339) (xy 186.687328 -299.869358) (xy 186.736183 -299.87529) (xy 186.783454 -299.888982)
			(xy 186.827916 -299.91008) (xy 186.868419 -299.938036) (xy 186.903912 -299.972128) (xy 186.933477 -300.011472)
			(xy 186.956348 -300.055049) (xy 186.971932 -300.10173) (xy 186.979827 -300.150307) (xy 186.980322 -300.174914)
			(xy 187.31917 -300.174914) (xy 187.32313 -300.12586) (xy 187.334907 -300.078076) (xy 187.354198 -300.0328)
			(xy 187.380501 -299.991204) (xy 187.413136 -299.954367) (xy 187.451257 -299.923242) (xy 187.493878 -299.898635)
			(xy 187.539894 -299.881183) (xy 187.588113 -299.871339) (xy 187.637288 -299.869358) (xy 187.686143 -299.87529)
			(xy 187.733414 -299.888982) (xy 187.777876 -299.91008) (xy 187.818379 -299.938036) (xy 187.853872 -299.972128)
			(xy 187.883437 -300.011472) (xy 187.906308 -300.055049) (xy 187.921892 -300.10173) (xy 187.929787 -300.150307)
			(xy 187.930282 -300.174914) (xy 188.26913 -300.174914) (xy 188.27309 -300.12586) (xy 188.284867 -300.078076)
			(xy 188.304158 -300.0328) (xy 188.330461 -299.991204) (xy 188.363096 -299.954367) (xy 188.401217 -299.923242)
			(xy 188.443838 -299.898635) (xy 188.489854 -299.881183) (xy 188.538073 -299.871339) (xy 188.587248 -299.869358)
			(xy 188.636103 -299.87529) (xy 188.683374 -299.888982) (xy 188.727836 -299.91008) (xy 188.768339 -299.938036)
			(xy 188.803832 -299.972128) (xy 188.833397 -300.011472) (xy 188.856268 -300.055049) (xy 188.871852 -300.10173)
			(xy 188.879747 -300.150307) (xy 188.880242 -300.174914) (xy 189.21909 -300.174914) (xy 189.22305 -300.12586)
			(xy 189.234827 -300.078076) (xy 189.254118 -300.0328) (xy 189.280421 -299.991204) (xy 189.313056 -299.954367)
			(xy 189.351177 -299.923242) (xy 189.393798 -299.898635) (xy 189.439814 -299.881183) (xy 189.488033 -299.871339)
			(xy 189.537208 -299.869358) (xy 189.586063 -299.87529) (xy 189.633334 -299.888982) (xy 189.677796 -299.91008)
			(xy 189.718299 -299.938036) (xy 189.753792 -299.972128) (xy 189.783357 -300.011472) (xy 189.806228 -300.055049)
			(xy 189.821812 -300.10173) (xy 189.829707 -300.150307) (xy 189.830202 -300.174914) (xy 190.16905 -300.174914)
			(xy 190.17301 -300.12586) (xy 190.184787 -300.078076) (xy 190.204078 -300.0328) (xy 190.230381 -299.991204)
			(xy 190.263016 -299.954367) (xy 190.301137 -299.923242) (xy 190.343758 -299.898635) (xy 190.389774 -299.881183)
			(xy 190.437993 -299.871339) (xy 190.487168 -299.869358) (xy 190.536023 -299.87529) (xy 190.583294 -299.888982)
			(xy 190.627756 -299.91008) (xy 190.668259 -299.938036) (xy 190.703752 -299.972128) (xy 190.733317 -300.011472)
			(xy 190.756188 -300.055049) (xy 190.771772 -300.10173) (xy 190.779667 -300.150307) (xy 190.780162 -300.174914)
			(xy 191.119264 -300.174914) (xy 191.123224 -300.12586) (xy 191.135001 -300.078076) (xy 191.154292 -300.0328)
			(xy 191.180595 -299.991204) (xy 191.21323 -299.954367) (xy 191.251351 -299.923242) (xy 191.293972 -299.898635)
			(xy 191.339988 -299.881183) (xy 191.388207 -299.871339) (xy 191.437382 -299.869358) (xy 191.486237 -299.87529)
			(xy 191.533508 -299.888982) (xy 191.57797 -299.91008) (xy 191.618473 -299.938036) (xy 191.653966 -299.972128)
			(xy 191.683531 -300.011472) (xy 191.706402 -300.055049) (xy 191.721986 -300.10173) (xy 191.729881 -300.150307)
			(xy 191.730376 -300.174914) (xy 192.069224 -300.174914) (xy 192.073184 -300.12586) (xy 192.084961 -300.078076)
			(xy 192.104252 -300.0328) (xy 192.130555 -299.991204) (xy 192.16319 -299.954367) (xy 192.201311 -299.923242)
			(xy 192.243932 -299.898635) (xy 192.289948 -299.881183) (xy 192.338167 -299.871339) (xy 192.387342 -299.869358)
			(xy 192.436197 -299.87529) (xy 192.483468 -299.888982) (xy 192.52793 -299.91008) (xy 192.568433 -299.938036)
			(xy 192.603926 -299.972128) (xy 192.633491 -300.011472) (xy 192.656362 -300.055049) (xy 192.671946 -300.10173)
			(xy 192.679841 -300.150307) (xy 192.680336 -300.174914) (xy 193.019184 -300.174914) (xy 193.023144 -300.12586)
			(xy 193.034921 -300.078076) (xy 193.054212 -300.0328) (xy 193.080515 -299.991204) (xy 193.11315 -299.954367)
			(xy 193.151271 -299.923242) (xy 193.193892 -299.898635) (xy 193.239908 -299.881183) (xy 193.288127 -299.871339)
			(xy 193.337302 -299.869358) (xy 193.386157 -299.87529) (xy 193.433428 -299.888982) (xy 193.47789 -299.91008)
			(xy 193.518393 -299.938036) (xy 193.553886 -299.972128) (xy 193.583451 -300.011472) (xy 193.606322 -300.055049)
			(xy 193.621906 -300.10173) (xy 193.629801 -300.150307) (xy 193.630296 -300.174914) (xy 193.969144 -300.174914)
			(xy 193.973104 -300.12586) (xy 193.984881 -300.078076) (xy 194.004172 -300.0328) (xy 194.030475 -299.991204)
			(xy 194.06311 -299.954367) (xy 194.101231 -299.923242) (xy 194.143852 -299.898635) (xy 194.189868 -299.881183)
			(xy 194.238087 -299.871339) (xy 194.287262 -299.869358) (xy 194.336117 -299.87529) (xy 194.383388 -299.888982)
			(xy 194.42785 -299.91008) (xy 194.468353 -299.938036) (xy 194.503846 -299.972128) (xy 194.533411 -300.011472)
			(xy 194.556282 -300.055049) (xy 194.571866 -300.10173) (xy 194.579761 -300.150307) (xy 194.580256 -300.174914)
			(xy 194.919104 -300.174914) (xy 194.923064 -300.12586) (xy 194.934841 -300.078076) (xy 194.954132 -300.0328)
			(xy 194.980435 -299.991204) (xy 195.01307 -299.954367) (xy 195.051191 -299.923242) (xy 195.093812 -299.898635)
			(xy 195.139828 -299.881183) (xy 195.188047 -299.871339) (xy 195.237222 -299.869358) (xy 195.286077 -299.87529)
			(xy 195.333348 -299.888982) (xy 195.37781 -299.91008) (xy 195.418313 -299.938036) (xy 195.453806 -299.972128)
			(xy 195.483371 -300.011472) (xy 195.506242 -300.055049) (xy 195.521826 -300.10173) (xy 195.529721 -300.150307)
			(xy 195.530216 -300.174914) (xy 195.869064 -300.174914) (xy 195.873024 -300.12586) (xy 195.884801 -300.078076)
			(xy 195.904092 -300.0328) (xy 195.930395 -299.991204) (xy 195.96303 -299.954367) (xy 196.001151 -299.923242)
			(xy 196.043772 -299.898635) (xy 196.089788 -299.881183) (xy 196.138007 -299.871339) (xy 196.187182 -299.869358)
			(xy 196.236037 -299.87529) (xy 196.283308 -299.888982) (xy 196.32777 -299.91008) (xy 196.368273 -299.938036)
			(xy 196.403766 -299.972128) (xy 196.433331 -300.011472) (xy 196.456202 -300.055049) (xy 196.471786 -300.10173)
			(xy 196.479681 -300.150307) (xy 196.480176 -300.174914) (xy 196.819278 -300.174914) (xy 196.823238 -300.12586)
			(xy 196.835015 -300.078076) (xy 196.854306 -300.0328) (xy 196.880609 -299.991204) (xy 196.913244 -299.954367)
			(xy 196.951365 -299.923242) (xy 196.993986 -299.898635) (xy 197.040002 -299.881183) (xy 197.088221 -299.871339)
			(xy 197.137396 -299.869358) (xy 197.186251 -299.87529) (xy 197.233522 -299.888982) (xy 197.277984 -299.91008)
			(xy 197.318487 -299.938036) (xy 197.35398 -299.972128) (xy 197.383545 -300.011472) (xy 197.406416 -300.055049)
			(xy 197.422 -300.10173) (xy 197.429895 -300.150307) (xy 197.43039 -300.174914) (xy 197.769238 -300.174914)
			(xy 197.773198 -300.12586) (xy 197.784975 -300.078076) (xy 197.804266 -300.0328) (xy 197.830569 -299.991204)
			(xy 197.863204 -299.954367) (xy 197.901325 -299.923242) (xy 197.943946 -299.898635) (xy 197.989962 -299.881183)
			(xy 198.038181 -299.871339) (xy 198.087356 -299.869358) (xy 198.136211 -299.87529) (xy 198.183482 -299.888982)
			(xy 198.227944 -299.91008) (xy 198.268447 -299.938036) (xy 198.30394 -299.972128) (xy 198.333505 -300.011472)
			(xy 198.356376 -300.055049) (xy 198.37196 -300.10173) (xy 198.379855 -300.150307) (xy 198.38035 -300.174914)
			(xy 198.719198 -300.174914) (xy 198.723158 -300.12586) (xy 198.734935 -300.078076) (xy 198.754226 -300.0328)
			(xy 198.780529 -299.991204) (xy 198.813164 -299.954367) (xy 198.851285 -299.923242) (xy 198.893906 -299.898635)
			(xy 198.939922 -299.881183) (xy 198.988141 -299.871339) (xy 199.037316 -299.869358) (xy 199.086171 -299.87529)
			(xy 199.133442 -299.888982) (xy 199.177904 -299.91008) (xy 199.218407 -299.938036) (xy 199.2539 -299.972128)
			(xy 199.283465 -300.011472) (xy 199.306336 -300.055049) (xy 199.32192 -300.10173) (xy 199.329815 -300.150307)
			(xy 199.33031 -300.174914) (xy 199.329815 -300.199521) (xy 199.32192 -300.248098) (xy 199.306336 -300.294779)
			(xy 199.283465 -300.338356) (xy 199.2539 -300.3777) (xy 199.218407 -300.411792) (xy 199.177904 -300.439748)
			(xy 199.133442 -300.460846) (xy 199.086171 -300.474538) (xy 199.037316 -300.48047) (xy 198.988141 -300.478489)
			(xy 198.939922 -300.468645) (xy 198.893906 -300.451193) (xy 198.851285 -300.426586) (xy 198.813164 -300.395461)
			(xy 198.780529 -300.358624) (xy 198.754226 -300.317028) (xy 198.734935 -300.271752) (xy 198.723158 -300.223968)
			(xy 198.719198 -300.174914) (xy 198.38035 -300.174914) (xy 198.379855 -300.199521) (xy 198.37196 -300.248098)
			(xy 198.356376 -300.294779) (xy 198.333505 -300.338356) (xy 198.30394 -300.3777) (xy 198.268447 -300.411792)
			(xy 198.227944 -300.439748) (xy 198.183482 -300.460846) (xy 198.136211 -300.474538) (xy 198.087356 -300.48047)
			(xy 198.038181 -300.478489) (xy 197.989962 -300.468645) (xy 197.943946 -300.451193) (xy 197.901325 -300.426586)
			(xy 197.863204 -300.395461) (xy 197.830569 -300.358624) (xy 197.804266 -300.317028) (xy 197.784975 -300.271752)
			(xy 197.773198 -300.223968) (xy 197.769238 -300.174914) (xy 197.43039 -300.174914) (xy 197.429895 -300.199521)
			(xy 197.422 -300.248098) (xy 197.406416 -300.294779) (xy 197.383545 -300.338356) (xy 197.35398 -300.3777)
			(xy 197.318487 -300.411792) (xy 197.277984 -300.439748) (xy 197.233522 -300.460846) (xy 197.186251 -300.474538)
			(xy 197.137396 -300.48047) (xy 197.088221 -300.478489) (xy 197.040002 -300.468645) (xy 196.993986 -300.451193)
			(xy 196.951365 -300.426586) (xy 196.913244 -300.395461) (xy 196.880609 -300.358624) (xy 196.854306 -300.317028)
			(xy 196.835015 -300.271752) (xy 196.823238 -300.223968) (xy 196.819278 -300.174914) (xy 196.480176 -300.174914)
			(xy 196.479681 -300.199521) (xy 196.471786 -300.248098) (xy 196.456202 -300.294779) (xy 196.433331 -300.338356)
			(xy 196.403766 -300.3777) (xy 196.368273 -300.411792) (xy 196.32777 -300.439748) (xy 196.283308 -300.460846)
			(xy 196.236037 -300.474538) (xy 196.187182 -300.48047) (xy 196.138007 -300.478489) (xy 196.089788 -300.468645)
			(xy 196.043772 -300.451193) (xy 196.001151 -300.426586) (xy 195.96303 -300.395461) (xy 195.930395 -300.358624)
			(xy 195.904092 -300.317028) (xy 195.884801 -300.271752) (xy 195.873024 -300.223968) (xy 195.869064 -300.174914)
			(xy 195.530216 -300.174914) (xy 195.529721 -300.199521) (xy 195.521826 -300.248098) (xy 195.506242 -300.294779)
			(xy 195.483371 -300.338356) (xy 195.453806 -300.3777) (xy 195.418313 -300.411792) (xy 195.37781 -300.439748)
			(xy 195.333348 -300.460846) (xy 195.286077 -300.474538) (xy 195.237222 -300.48047) (xy 195.188047 -300.478489)
			(xy 195.139828 -300.468645) (xy 195.093812 -300.451193) (xy 195.051191 -300.426586) (xy 195.01307 -300.395461)
			(xy 194.980435 -300.358624) (xy 194.954132 -300.317028) (xy 194.934841 -300.271752) (xy 194.923064 -300.223968)
			(xy 194.919104 -300.174914) (xy 194.580256 -300.174914) (xy 194.579761 -300.199521) (xy 194.571866 -300.248098)
			(xy 194.556282 -300.294779) (xy 194.533411 -300.338356) (xy 194.503846 -300.3777) (xy 194.468353 -300.411792)
			(xy 194.42785 -300.439748) (xy 194.383388 -300.460846) (xy 194.336117 -300.474538) (xy 194.287262 -300.48047)
			(xy 194.238087 -300.478489) (xy 194.189868 -300.468645) (xy 194.143852 -300.451193) (xy 194.101231 -300.426586)
			(xy 194.06311 -300.395461) (xy 194.030475 -300.358624) (xy 194.004172 -300.317028) (xy 193.984881 -300.271752)
			(xy 193.973104 -300.223968) (xy 193.969144 -300.174914) (xy 193.630296 -300.174914) (xy 193.629801 -300.199521)
			(xy 193.621906 -300.248098) (xy 193.606322 -300.294779) (xy 193.583451 -300.338356) (xy 193.553886 -300.3777)
			(xy 193.518393 -300.411792) (xy 193.47789 -300.439748) (xy 193.433428 -300.460846) (xy 193.386157 -300.474538)
			(xy 193.337302 -300.48047) (xy 193.288127 -300.478489) (xy 193.239908 -300.468645) (xy 193.193892 -300.451193)
			(xy 193.151271 -300.426586) (xy 193.11315 -300.395461) (xy 193.080515 -300.358624) (xy 193.054212 -300.317028)
			(xy 193.034921 -300.271752) (xy 193.023144 -300.223968) (xy 193.019184 -300.174914) (xy 192.680336 -300.174914)
			(xy 192.679841 -300.199521) (xy 192.671946 -300.248098) (xy 192.656362 -300.294779) (xy 192.633491 -300.338356)
			(xy 192.603926 -300.3777) (xy 192.568433 -300.411792) (xy 192.52793 -300.439748) (xy 192.483468 -300.460846)
			(xy 192.436197 -300.474538) (xy 192.387342 -300.48047) (xy 192.338167 -300.478489) (xy 192.289948 -300.468645)
			(xy 192.243932 -300.451193) (xy 192.201311 -300.426586) (xy 192.16319 -300.395461) (xy 192.130555 -300.358624)
			(xy 192.104252 -300.317028) (xy 192.084961 -300.271752) (xy 192.073184 -300.223968) (xy 192.069224 -300.174914)
			(xy 191.730376 -300.174914) (xy 191.729881 -300.199521) (xy 191.721986 -300.248098) (xy 191.706402 -300.294779)
			(xy 191.683531 -300.338356) (xy 191.653966 -300.3777) (xy 191.618473 -300.411792) (xy 191.57797 -300.439748)
			(xy 191.533508 -300.460846) (xy 191.486237 -300.474538) (xy 191.437382 -300.48047) (xy 191.388207 -300.478489)
			(xy 191.339988 -300.468645) (xy 191.293972 -300.451193) (xy 191.251351 -300.426586) (xy 191.21323 -300.395461)
			(xy 191.180595 -300.358624) (xy 191.154292 -300.317028) (xy 191.135001 -300.271752) (xy 191.123224 -300.223968)
			(xy 191.119264 -300.174914) (xy 190.780162 -300.174914) (xy 190.779667 -300.199521) (xy 190.771772 -300.248098)
			(xy 190.756188 -300.294779) (xy 190.733317 -300.338356) (xy 190.703752 -300.3777) (xy 190.668259 -300.411792)
			(xy 190.627756 -300.439748) (xy 190.583294 -300.460846) (xy 190.536023 -300.474538) (xy 190.487168 -300.48047)
			(xy 190.437993 -300.478489) (xy 190.389774 -300.468645) (xy 190.343758 -300.451193) (xy 190.301137 -300.426586)
			(xy 190.263016 -300.395461) (xy 190.230381 -300.358624) (xy 190.204078 -300.317028) (xy 190.184787 -300.271752)
			(xy 190.17301 -300.223968) (xy 190.16905 -300.174914) (xy 189.830202 -300.174914) (xy 189.829707 -300.199521)
			(xy 189.821812 -300.248098) (xy 189.806228 -300.294779) (xy 189.783357 -300.338356) (xy 189.753792 -300.3777)
			(xy 189.718299 -300.411792) (xy 189.677796 -300.439748) (xy 189.633334 -300.460846) (xy 189.586063 -300.474538)
			(xy 189.537208 -300.48047) (xy 189.488033 -300.478489) (xy 189.439814 -300.468645) (xy 189.393798 -300.451193)
			(xy 189.351177 -300.426586) (xy 189.313056 -300.395461) (xy 189.280421 -300.358624) (xy 189.254118 -300.317028)
			(xy 189.234827 -300.271752) (xy 189.22305 -300.223968) (xy 189.21909 -300.174914) (xy 188.880242 -300.174914)
			(xy 188.879747 -300.199521) (xy 188.871852 -300.248098) (xy 188.856268 -300.294779) (xy 188.833397 -300.338356)
			(xy 188.803832 -300.3777) (xy 188.768339 -300.411792) (xy 188.727836 -300.439748) (xy 188.683374 -300.460846)
			(xy 188.636103 -300.474538) (xy 188.587248 -300.48047) (xy 188.538073 -300.478489) (xy 188.489854 -300.468645)
			(xy 188.443838 -300.451193) (xy 188.401217 -300.426586) (xy 188.363096 -300.395461) (xy 188.330461 -300.358624)
			(xy 188.304158 -300.317028) (xy 188.284867 -300.271752) (xy 188.27309 -300.223968) (xy 188.26913 -300.174914)
			(xy 187.930282 -300.174914) (xy 187.929787 -300.199521) (xy 187.921892 -300.248098) (xy 187.906308 -300.294779)
			(xy 187.883437 -300.338356) (xy 187.853872 -300.3777) (xy 187.818379 -300.411792) (xy 187.777876 -300.439748)
			(xy 187.733414 -300.460846) (xy 187.686143 -300.474538) (xy 187.637288 -300.48047) (xy 187.588113 -300.478489)
			(xy 187.539894 -300.468645) (xy 187.493878 -300.451193) (xy 187.451257 -300.426586) (xy 187.413136 -300.395461)
			(xy 187.380501 -300.358624) (xy 187.354198 -300.317028) (xy 187.334907 -300.271752) (xy 187.32313 -300.223968)
			(xy 187.31917 -300.174914) (xy 186.980322 -300.174914) (xy 186.979827 -300.199521) (xy 186.971932 -300.248098)
			(xy 186.956348 -300.294779) (xy 186.933477 -300.338356) (xy 186.903912 -300.3777) (xy 186.868419 -300.411792)
			(xy 186.827916 -300.439748) (xy 186.783454 -300.460846) (xy 186.736183 -300.474538) (xy 186.687328 -300.48047)
			(xy 186.638153 -300.478489) (xy 186.589934 -300.468645) (xy 186.543918 -300.451193) (xy 186.501297 -300.426586)
			(xy 186.463176 -300.395461) (xy 186.430541 -300.358624) (xy 186.404238 -300.317028) (xy 186.384947 -300.271752)
			(xy 186.37317 -300.223968) (xy 186.36921 -300.174914) (xy 186.030362 -300.174914) (xy 186.029867 -300.199521)
			(xy 186.021972 -300.248098) (xy 186.006388 -300.294779) (xy 185.983517 -300.338356) (xy 185.953952 -300.3777)
			(xy 185.918459 -300.411792) (xy 185.877956 -300.439748) (xy 185.833494 -300.460846) (xy 185.786223 -300.474538)
			(xy 185.737368 -300.48047) (xy 185.688193 -300.478489) (xy 185.639974 -300.468645) (xy 185.593958 -300.451193)
			(xy 185.551337 -300.426586) (xy 185.513216 -300.395461) (xy 185.480581 -300.358624) (xy 185.454278 -300.317028)
			(xy 185.434987 -300.271752) (xy 185.42321 -300.223968) (xy 185.41925 -300.174914) (xy 185.080148 -300.174914)
			(xy 185.079653 -300.199521) (xy 185.071758 -300.248098) (xy 185.056174 -300.294779) (xy 185.033303 -300.338356)
			(xy 185.003738 -300.3777) (xy 184.968245 -300.411792) (xy 184.927742 -300.439748) (xy 184.88328 -300.460846)
			(xy 184.836009 -300.474538) (xy 184.787154 -300.48047) (xy 184.737979 -300.478489) (xy 184.68976 -300.468645)
			(xy 184.643744 -300.451193) (xy 184.601123 -300.426586) (xy 184.563002 -300.395461) (xy 184.530367 -300.358624)
			(xy 184.504064 -300.317028) (xy 184.484773 -300.271752) (xy 184.472996 -300.223968) (xy 184.469036 -300.174914)
			(xy 184.130188 -300.174914) (xy 184.129693 -300.199521) (xy 184.121798 -300.248098) (xy 184.106214 -300.294779)
			(xy 184.083343 -300.338356) (xy 184.053778 -300.3777) (xy 184.018285 -300.411792) (xy 183.977782 -300.439748)
			(xy 183.93332 -300.460846) (xy 183.886049 -300.474538) (xy 183.837194 -300.48047) (xy 183.788019 -300.478489)
			(xy 183.7398 -300.468645) (xy 183.693784 -300.451193) (xy 183.651163 -300.426586) (xy 183.613042 -300.395461)
			(xy 183.580407 -300.358624) (xy 183.554104 -300.317028) (xy 183.534813 -300.271752) (xy 183.523036 -300.223968)
			(xy 183.519076 -300.174914) (xy 183.180228 -300.174914) (xy 183.179733 -300.199521) (xy 183.171838 -300.248098)
			(xy 183.156254 -300.294779) (xy 183.133383 -300.338356) (xy 183.103818 -300.3777) (xy 183.068325 -300.411792)
			(xy 183.027822 -300.439748) (xy 182.98336 -300.460846) (xy 182.936089 -300.474538) (xy 182.887234 -300.48047)
			(xy 182.838059 -300.478489) (xy 182.78984 -300.468645) (xy 182.743824 -300.451193) (xy 182.701203 -300.426586)
			(xy 182.663082 -300.395461) (xy 182.630447 -300.358624) (xy 182.604144 -300.317028) (xy 182.584853 -300.271752)
			(xy 182.573076 -300.223968) (xy 182.569116 -300.174914) (xy 182.230268 -300.174914) (xy 182.229773 -300.199521)
			(xy 182.221878 -300.248098) (xy 182.206294 -300.294779) (xy 182.183423 -300.338356) (xy 182.153858 -300.3777)
			(xy 182.118365 -300.411792) (xy 182.077862 -300.439748) (xy 182.0334 -300.460846) (xy 181.986129 -300.474538)
			(xy 181.937274 -300.48047) (xy 181.888099 -300.478489) (xy 181.83988 -300.468645) (xy 181.793864 -300.451193)
			(xy 181.751243 -300.426586) (xy 181.713122 -300.395461) (xy 181.680487 -300.358624) (xy 181.654184 -300.317028)
			(xy 181.634893 -300.271752) (xy 181.623116 -300.223968) (xy 181.619156 -300.174914) (xy 181.280308 -300.174914)
			(xy 181.279813 -300.199521) (xy 181.271918 -300.248098) (xy 181.256334 -300.294779) (xy 181.233463 -300.338356)
			(xy 181.203898 -300.3777) (xy 181.168405 -300.411792) (xy 181.127902 -300.439748) (xy 181.08344 -300.460846)
			(xy 181.036169 -300.474538) (xy 180.987314 -300.48047) (xy 180.938139 -300.478489) (xy 180.88992 -300.468645)
			(xy 180.843904 -300.451193) (xy 180.801283 -300.426586) (xy 180.763162 -300.395461) (xy 180.730527 -300.358624)
			(xy 180.704224 -300.317028) (xy 180.684933 -300.271752) (xy 180.673156 -300.223968) (xy 180.669196 -300.174914)
			(xy 180.330348 -300.174914) (xy 180.329853 -300.199521) (xy 180.321958 -300.248098) (xy 180.306374 -300.294779)
			(xy 180.283503 -300.338356) (xy 180.253938 -300.3777) (xy 180.218445 -300.411792) (xy 180.177942 -300.439748)
			(xy 180.13348 -300.460846) (xy 180.086209 -300.474538) (xy 180.037354 -300.48047) (xy 179.988179 -300.478489)
			(xy 179.93996 -300.468645) (xy 179.893944 -300.451193) (xy 179.851323 -300.426586) (xy 179.813202 -300.395461)
			(xy 179.780567 -300.358624) (xy 179.754264 -300.317028) (xy 179.734973 -300.271752) (xy 179.723196 -300.223968)
			(xy 179.719236 -300.174914) (xy 179.380388 -300.174914) (xy 179.379893 -300.199521) (xy 179.371998 -300.248098)
			(xy 179.356414 -300.294779) (xy 179.333543 -300.338356) (xy 179.303978 -300.3777) (xy 179.268485 -300.411792)
			(xy 179.227982 -300.439748) (xy 179.18352 -300.460846) (xy 179.136249 -300.474538) (xy 179.087394 -300.48047)
			(xy 179.038219 -300.478489) (xy 178.99 -300.468645) (xy 178.943984 -300.451193) (xy 178.901363 -300.426586)
			(xy 178.863242 -300.395461) (xy 178.830607 -300.358624) (xy 178.804304 -300.317028) (xy 178.785013 -300.271752)
			(xy 178.773236 -300.223968) (xy 178.769276 -300.174914) (xy 178.430174 -300.174914) (xy 178.429679 -300.199521)
			(xy 178.421784 -300.248098) (xy 178.4062 -300.294779) (xy 178.383329 -300.338356) (xy 178.353764 -300.3777)
			(xy 178.318271 -300.411792) (xy 178.277768 -300.439748) (xy 178.233306 -300.460846) (xy 178.186035 -300.474538)
			(xy 178.13718 -300.48047) (xy 178.088005 -300.478489) (xy 178.039786 -300.468645) (xy 177.99377 -300.451193)
			(xy 177.951149 -300.426586) (xy 177.913028 -300.395461) (xy 177.880393 -300.358624) (xy 177.85409 -300.317028)
			(xy 177.834799 -300.271752) (xy 177.823022 -300.223968) (xy 177.819062 -300.174914) (xy 177.480214 -300.174914)
			(xy 177.479719 -300.199521) (xy 177.471824 -300.248098) (xy 177.45624 -300.294779) (xy 177.433369 -300.338356)
			(xy 177.403804 -300.3777) (xy 177.368311 -300.411792) (xy 177.327808 -300.439748) (xy 177.283346 -300.460846)
			(xy 177.236075 -300.474538) (xy 177.18722 -300.48047) (xy 177.138045 -300.478489) (xy 177.089826 -300.468645)
			(xy 177.04381 -300.451193) (xy 177.001189 -300.426586) (xy 176.963068 -300.395461) (xy 176.930433 -300.358624)
			(xy 176.90413 -300.317028) (xy 176.884839 -300.271752) (xy 176.873062 -300.223968) (xy 176.869102 -300.174914)
			(xy 176.530254 -300.174914) (xy 176.529759 -300.199521) (xy 176.521864 -300.248098) (xy 176.50628 -300.294779)
			(xy 176.483409 -300.338356) (xy 176.453844 -300.3777) (xy 176.418351 -300.411792) (xy 176.377848 -300.439748)
			(xy 176.333386 -300.460846) (xy 176.286115 -300.474538) (xy 176.23726 -300.48047) (xy 176.188085 -300.478489)
			(xy 176.139866 -300.468645) (xy 176.09385 -300.451193) (xy 176.051229 -300.426586) (xy 176.013108 -300.395461)
			(xy 175.980473 -300.358624) (xy 175.95417 -300.317028) (xy 175.934879 -300.271752) (xy 175.923102 -300.223968)
			(xy 175.919142 -300.174914) (xy 174.630334 -300.174914) (xy 174.629839 -300.199521) (xy 174.621944 -300.248098)
			(xy 174.60636 -300.294779) (xy 174.583489 -300.338356) (xy 174.553924 -300.3777) (xy 174.518431 -300.411792)
			(xy 174.477928 -300.439748) (xy 174.433466 -300.460846) (xy 174.386195 -300.474538) (xy 174.33734 -300.48047)
			(xy 174.288165 -300.478489) (xy 174.239946 -300.468645) (xy 174.19393 -300.451193) (xy 174.151309 -300.426586)
			(xy 174.113188 -300.395461) (xy 174.080553 -300.358624) (xy 174.05425 -300.317028) (xy 174.034959 -300.271752)
			(xy 174.023182 -300.223968) (xy 174.019222 -300.174914) (xy 173.680374 -300.174914) (xy 173.679879 -300.199521)
			(xy 173.671984 -300.248098) (xy 173.6564 -300.294779) (xy 173.633529 -300.338356) (xy 173.603964 -300.3777)
			(xy 173.568471 -300.411792) (xy 173.527968 -300.439748) (xy 173.483506 -300.460846) (xy 173.436235 -300.474538)
			(xy 173.38738 -300.48047) (xy 173.338205 -300.478489) (xy 173.289986 -300.468645) (xy 173.24397 -300.451193)
			(xy 173.201349 -300.426586) (xy 173.163228 -300.395461) (xy 173.130593 -300.358624) (xy 173.10429 -300.317028)
			(xy 173.084999 -300.271752) (xy 173.073222 -300.223968) (xy 173.069262 -300.174914) (xy 172.73016 -300.174914)
			(xy 172.729665 -300.199521) (xy 172.72177 -300.248098) (xy 172.706186 -300.294779) (xy 172.683315 -300.338356)
			(xy 172.65375 -300.3777) (xy 172.618257 -300.411792) (xy 172.577754 -300.439748) (xy 172.533292 -300.460846)
			(xy 172.486021 -300.474538) (xy 172.437166 -300.48047) (xy 172.387991 -300.478489) (xy 172.339772 -300.468645)
			(xy 172.293756 -300.451193) (xy 172.251135 -300.426586) (xy 172.213014 -300.395461) (xy 172.180379 -300.358624)
			(xy 172.154076 -300.317028) (xy 172.134785 -300.271752) (xy 172.123008 -300.223968) (xy 172.119048 -300.174914)
			(xy 171.7802 -300.174914) (xy 171.779705 -300.199521) (xy 171.77181 -300.248098) (xy 171.756226 -300.294779)
			(xy 171.733355 -300.338356) (xy 171.70379 -300.3777) (xy 171.668297 -300.411792) (xy 171.627794 -300.439748)
			(xy 171.583332 -300.460846) (xy 171.536061 -300.474538) (xy 171.487206 -300.48047) (xy 171.438031 -300.478489)
			(xy 171.389812 -300.468645) (xy 171.343796 -300.451193) (xy 171.301175 -300.426586) (xy 171.263054 -300.395461)
			(xy 171.230419 -300.358624) (xy 171.204116 -300.317028) (xy 171.184825 -300.271752) (xy 171.173048 -300.223968)
			(xy 171.169088 -300.174914) (xy 170.83024 -300.174914) (xy 170.829745 -300.199521) (xy 170.82185 -300.248098)
			(xy 170.806266 -300.294779) (xy 170.783395 -300.338356) (xy 170.75383 -300.3777) (xy 170.718337 -300.411792)
			(xy 170.677834 -300.439748) (xy 170.633372 -300.460846) (xy 170.586101 -300.474538) (xy 170.537246 -300.48047)
			(xy 170.488071 -300.478489) (xy 170.439852 -300.468645) (xy 170.393836 -300.451193) (xy 170.351215 -300.426586)
			(xy 170.313094 -300.395461) (xy 170.280459 -300.358624) (xy 170.254156 -300.317028) (xy 170.234865 -300.271752)
			(xy 170.223088 -300.223968) (xy 170.219128 -300.174914) (xy 169.88028 -300.174914) (xy 169.879785 -300.199521)
			(xy 169.87189 -300.248098) (xy 169.856306 -300.294779) (xy 169.833435 -300.338356) (xy 169.80387 -300.3777)
			(xy 169.768377 -300.411792) (xy 169.727874 -300.439748) (xy 169.683412 -300.460846) (xy 169.636141 -300.474538)
			(xy 169.587286 -300.48047) (xy 169.538111 -300.478489) (xy 169.489892 -300.468645) (xy 169.443876 -300.451193)
			(xy 169.401255 -300.426586) (xy 169.363134 -300.395461) (xy 169.330499 -300.358624) (xy 169.304196 -300.317028)
			(xy 169.284905 -300.271752) (xy 169.273128 -300.223968) (xy 169.269168 -300.174914) (xy 168.93032 -300.174914)
			(xy 168.929825 -300.199521) (xy 168.92193 -300.248098) (xy 168.906346 -300.294779) (xy 168.883475 -300.338356)
			(xy 168.85391 -300.3777) (xy 168.818417 -300.411792) (xy 168.777914 -300.439748) (xy 168.733452 -300.460846)
			(xy 168.686181 -300.474538) (xy 168.637326 -300.48047) (xy 168.588151 -300.478489) (xy 168.539932 -300.468645)
			(xy 168.493916 -300.451193) (xy 168.451295 -300.426586) (xy 168.413174 -300.395461) (xy 168.380539 -300.358624)
			(xy 168.354236 -300.317028) (xy 168.334945 -300.271752) (xy 168.323168 -300.223968) (xy 168.319208 -300.174914)
			(xy 167.98036 -300.174914) (xy 167.979865 -300.199521) (xy 167.97197 -300.248098) (xy 167.956386 -300.294779)
			(xy 167.933515 -300.338356) (xy 167.90395 -300.3777) (xy 167.868457 -300.411792) (xy 167.827954 -300.439748)
			(xy 167.783492 -300.460846) (xy 167.736221 -300.474538) (xy 167.687366 -300.48047) (xy 167.638191 -300.478489)
			(xy 167.589972 -300.468645) (xy 167.543956 -300.451193) (xy 167.501335 -300.426586) (xy 167.463214 -300.395461)
			(xy 167.430579 -300.358624) (xy 167.404276 -300.317028) (xy 167.384985 -300.271752) (xy 167.373208 -300.223968)
			(xy 167.369248 -300.174914) (xy 167.0304 -300.174914) (xy 167.029905 -300.199521) (xy 167.02201 -300.248098)
			(xy 167.006426 -300.294779) (xy 166.983555 -300.338356) (xy 166.95399 -300.3777) (xy 166.918497 -300.411792)
			(xy 166.877994 -300.439748) (xy 166.833532 -300.460846) (xy 166.786261 -300.474538) (xy 166.737406 -300.48047)
			(xy 166.688231 -300.478489) (xy 166.640012 -300.468645) (xy 166.593996 -300.451193) (xy 166.551375 -300.426586)
			(xy 166.513254 -300.395461) (xy 166.480619 -300.358624) (xy 166.454316 -300.317028) (xy 166.435025 -300.271752)
			(xy 166.423248 -300.223968) (xy 166.419288 -300.174914) (xy 166.080186 -300.174914) (xy 166.079691 -300.199521)
			(xy 166.071796 -300.248098) (xy 166.056212 -300.294779) (xy 166.033341 -300.338356) (xy 166.003776 -300.3777)
			(xy 165.968283 -300.411792) (xy 165.92778 -300.439748) (xy 165.883318 -300.460846) (xy 165.836047 -300.474538)
			(xy 165.787192 -300.48047) (xy 165.738017 -300.478489) (xy 165.689798 -300.468645) (xy 165.643782 -300.451193)
			(xy 165.601161 -300.426586) (xy 165.56304 -300.395461) (xy 165.530405 -300.358624) (xy 165.504102 -300.317028)
			(xy 165.484811 -300.271752) (xy 165.473034 -300.223968) (xy 165.469074 -300.174914) (xy 165.15507 -300.174914)
			(xy 165.15507 -300.201282) (xy 165.146692 -300.253374) (xy 165.130149 -300.303474) (xy 165.10586 -300.350312)
			(xy 165.074443 -300.392699) (xy 165.036693 -300.42956) (xy 164.99357 -300.459959) (xy 164.946167 -300.483125)
			(xy 164.895687 -300.49847) (xy 164.869622 -300.502574) (xy 164.86505 -300.503336) (xy 164.854636 -300.506638)
			(xy 164.850318 -300.507908) (xy 164.826696 -300.51883) (xy 164.819838 -300.525942) (xy 164.804852 -300.54169)
			(xy 164.800263 -300.546794) (xy 164.793815 -300.558907) (xy 164.792152 -300.565566) (xy 164.790882 -300.576488)
			(xy 164.790882 -300.7233) (xy 164.791055 -300.729452) (xy 164.794018 -300.741394) (xy 164.796724 -300.746922)
			(xy 164.804852 -300.758098) (xy 164.819584 -300.773592) (xy 164.826188 -300.780704) (xy 164.849302 -300.791626)
			(xy 164.852858 -300.792642) (xy 164.86505 -300.796452) (xy 164.869622 -300.797214) (xy 164.895694 -300.801291)
			(xy 164.94618 -300.816638) (xy 164.993589 -300.839806) (xy 165.036718 -300.870209) (xy 165.074472 -300.907074)
			(xy 165.105893 -300.949466) (xy 165.130185 -300.996309) (xy 165.14673 -301.046415) (xy 165.155109 -301.098513)
			(xy 165.155109 -301.124874) (xy 165.469074 -301.124874) (xy 165.473034 -301.07582) (xy 165.484811 -301.028036)
			(xy 165.504102 -300.98276) (xy 165.530405 -300.941164) (xy 165.56304 -300.904327) (xy 165.601161 -300.873202)
			(xy 165.643782 -300.848595) (xy 165.689798 -300.831143) (xy 165.738017 -300.821299) (xy 165.787192 -300.819318)
			(xy 165.836047 -300.82525) (xy 165.883318 -300.838942) (xy 165.92778 -300.86004) (xy 165.968283 -300.887996)
			(xy 166.003776 -300.922088) (xy 166.033341 -300.961432) (xy 166.056212 -301.005009) (xy 166.071796 -301.05169)
			(xy 166.079691 -301.100267) (xy 166.080186 -301.124874) (xy 166.419288 -301.124874) (xy 166.423248 -301.07582)
			(xy 166.435025 -301.028036) (xy 166.454316 -300.98276) (xy 166.480619 -300.941164) (xy 166.513254 -300.904327)
			(xy 166.551375 -300.873202) (xy 166.593996 -300.848595) (xy 166.640012 -300.831143) (xy 166.688231 -300.821299)
			(xy 166.737406 -300.819318) (xy 166.786261 -300.82525) (xy 166.833532 -300.838942) (xy 166.877994 -300.86004)
			(xy 166.918497 -300.887996) (xy 166.95399 -300.922088) (xy 166.983555 -300.961432) (xy 167.006426 -301.005009)
			(xy 167.02201 -301.05169) (xy 167.029905 -301.100267) (xy 167.0304 -301.124874) (xy 167.369248 -301.124874)
			(xy 167.373208 -301.07582) (xy 167.384985 -301.028036) (xy 167.404276 -300.98276) (xy 167.430579 -300.941164)
			(xy 167.463214 -300.904327) (xy 167.501335 -300.873202) (xy 167.543956 -300.848595) (xy 167.589972 -300.831143)
			(xy 167.638191 -300.821299) (xy 167.687366 -300.819318) (xy 167.736221 -300.82525) (xy 167.783492 -300.838942)
			(xy 167.827954 -300.86004) (xy 167.868457 -300.887996) (xy 167.90395 -300.922088) (xy 167.933515 -300.961432)
			(xy 167.956386 -301.005009) (xy 167.97197 -301.05169) (xy 167.979865 -301.100267) (xy 167.98036 -301.124874)
			(xy 168.319208 -301.124874) (xy 168.323168 -301.07582) (xy 168.334945 -301.028036) (xy 168.354236 -300.98276)
			(xy 168.380539 -300.941164) (xy 168.413174 -300.904327) (xy 168.451295 -300.873202) (xy 168.493916 -300.848595)
			(xy 168.539932 -300.831143) (xy 168.588151 -300.821299) (xy 168.637326 -300.819318) (xy 168.686181 -300.82525)
			(xy 168.733452 -300.838942) (xy 168.777914 -300.86004) (xy 168.818417 -300.887996) (xy 168.85391 -300.922088)
			(xy 168.883475 -300.961432) (xy 168.906346 -301.005009) (xy 168.92193 -301.05169) (xy 168.929825 -301.100267)
			(xy 168.93032 -301.124874) (xy 169.269168 -301.124874) (xy 169.273128 -301.07582) (xy 169.284905 -301.028036)
			(xy 169.304196 -300.98276) (xy 169.330499 -300.941164) (xy 169.363134 -300.904327) (xy 169.401255 -300.873202)
			(xy 169.443876 -300.848595) (xy 169.489892 -300.831143) (xy 169.538111 -300.821299) (xy 169.587286 -300.819318)
			(xy 169.636141 -300.82525) (xy 169.683412 -300.838942) (xy 169.727874 -300.86004) (xy 169.768377 -300.887996)
			(xy 169.80387 -300.922088) (xy 169.833435 -300.961432) (xy 169.856306 -301.005009) (xy 169.87189 -301.05169)
			(xy 169.879785 -301.100267) (xy 169.88028 -301.124874) (xy 170.219128 -301.124874) (xy 170.223088 -301.07582)
			(xy 170.234865 -301.028036) (xy 170.254156 -300.98276) (xy 170.280459 -300.941164) (xy 170.313094 -300.904327)
			(xy 170.351215 -300.873202) (xy 170.393836 -300.848595) (xy 170.439852 -300.831143) (xy 170.488071 -300.821299)
			(xy 170.537246 -300.819318) (xy 170.586101 -300.82525) (xy 170.633372 -300.838942) (xy 170.677834 -300.86004)
			(xy 170.718337 -300.887996) (xy 170.75383 -300.922088) (xy 170.783395 -300.961432) (xy 170.806266 -301.005009)
			(xy 170.82185 -301.05169) (xy 170.829745 -301.100267) (xy 170.83024 -301.124874) (xy 171.169088 -301.124874)
			(xy 171.173048 -301.07582) (xy 171.184825 -301.028036) (xy 171.204116 -300.98276) (xy 171.230419 -300.941164)
			(xy 171.263054 -300.904327) (xy 171.301175 -300.873202) (xy 171.343796 -300.848595) (xy 171.389812 -300.831143)
			(xy 171.438031 -300.821299) (xy 171.487206 -300.819318) (xy 171.536061 -300.82525) (xy 171.583332 -300.838942)
			(xy 171.627794 -300.86004) (xy 171.668297 -300.887996) (xy 171.70379 -300.922088) (xy 171.733355 -300.961432)
			(xy 171.756226 -301.005009) (xy 171.77181 -301.05169) (xy 171.779705 -301.100267) (xy 171.7802 -301.124874)
			(xy 172.119048 -301.124874) (xy 172.123008 -301.07582) (xy 172.134785 -301.028036) (xy 172.154076 -300.98276)
			(xy 172.180379 -300.941164) (xy 172.213014 -300.904327) (xy 172.251135 -300.873202) (xy 172.293756 -300.848595)
			(xy 172.339772 -300.831143) (xy 172.387991 -300.821299) (xy 172.437166 -300.819318) (xy 172.486021 -300.82525)
			(xy 172.533292 -300.838942) (xy 172.577754 -300.86004) (xy 172.618257 -300.887996) (xy 172.65375 -300.922088)
			(xy 172.683315 -300.961432) (xy 172.706186 -301.005009) (xy 172.72177 -301.05169) (xy 172.729665 -301.100267)
			(xy 172.73016 -301.124874) (xy 173.069262 -301.124874) (xy 173.073222 -301.07582) (xy 173.084999 -301.028036)
			(xy 173.10429 -300.98276) (xy 173.130593 -300.941164) (xy 173.163228 -300.904327) (xy 173.201349 -300.873202)
			(xy 173.24397 -300.848595) (xy 173.289986 -300.831143) (xy 173.338205 -300.821299) (xy 173.38738 -300.819318)
			(xy 173.436235 -300.82525) (xy 173.483506 -300.838942) (xy 173.527968 -300.86004) (xy 173.568471 -300.887996)
			(xy 173.603964 -300.922088) (xy 173.633529 -300.961432) (xy 173.6564 -301.005009) (xy 173.671984 -301.05169)
			(xy 173.679879 -301.100267) (xy 173.680374 -301.124874) (xy 174.019222 -301.124874) (xy 174.023182 -301.07582)
			(xy 174.034959 -301.028036) (xy 174.05425 -300.98276) (xy 174.080553 -300.941164) (xy 174.113188 -300.904327)
			(xy 174.151309 -300.873202) (xy 174.19393 -300.848595) (xy 174.239946 -300.831143) (xy 174.288165 -300.821299)
			(xy 174.33734 -300.819318) (xy 174.386195 -300.82525) (xy 174.433466 -300.838942) (xy 174.477928 -300.86004)
			(xy 174.518431 -300.887996) (xy 174.553924 -300.922088) (xy 174.583489 -300.961432) (xy 174.60636 -301.005009)
			(xy 174.621944 -301.05169) (xy 174.629839 -301.100267) (xy 174.630334 -301.124874) (xy 175.919142 -301.124874)
			(xy 175.923102 -301.07582) (xy 175.934879 -301.028036) (xy 175.95417 -300.98276) (xy 175.980473 -300.941164)
			(xy 176.013108 -300.904327) (xy 176.051229 -300.873202) (xy 176.09385 -300.848595) (xy 176.139866 -300.831143)
			(xy 176.188085 -300.821299) (xy 176.23726 -300.819318) (xy 176.286115 -300.82525) (xy 176.333386 -300.838942)
			(xy 176.377848 -300.86004) (xy 176.418351 -300.887996) (xy 176.453844 -300.922088) (xy 176.483409 -300.961432)
			(xy 176.50628 -301.005009) (xy 176.521864 -301.05169) (xy 176.529759 -301.100267) (xy 176.530254 -301.124874)
			(xy 176.869102 -301.124874) (xy 176.873062 -301.07582) (xy 176.884839 -301.028036) (xy 176.90413 -300.98276)
			(xy 176.930433 -300.941164) (xy 176.963068 -300.904327) (xy 177.001189 -300.873202) (xy 177.04381 -300.848595)
			(xy 177.089826 -300.831143) (xy 177.138045 -300.821299) (xy 177.18722 -300.819318) (xy 177.236075 -300.82525)
			(xy 177.283346 -300.838942) (xy 177.327808 -300.86004) (xy 177.368311 -300.887996) (xy 177.403804 -300.922088)
			(xy 177.433369 -300.961432) (xy 177.45624 -301.005009) (xy 177.471824 -301.05169) (xy 177.479719 -301.100267)
			(xy 177.480214 -301.124874) (xy 177.819062 -301.124874) (xy 177.823022 -301.07582) (xy 177.834799 -301.028036)
			(xy 177.85409 -300.98276) (xy 177.880393 -300.941164) (xy 177.913028 -300.904327) (xy 177.951149 -300.873202)
			(xy 177.99377 -300.848595) (xy 178.039786 -300.831143) (xy 178.088005 -300.821299) (xy 178.13718 -300.819318)
			(xy 178.186035 -300.82525) (xy 178.233306 -300.838942) (xy 178.277768 -300.86004) (xy 178.318271 -300.887996)
			(xy 178.353764 -300.922088) (xy 178.383329 -300.961432) (xy 178.4062 -301.005009) (xy 178.421784 -301.05169)
			(xy 178.429679 -301.100267) (xy 178.430174 -301.124874) (xy 178.769276 -301.124874) (xy 178.773236 -301.07582)
			(xy 178.785013 -301.028036) (xy 178.804304 -300.98276) (xy 178.830607 -300.941164) (xy 178.863242 -300.904327)
			(xy 178.901363 -300.873202) (xy 178.943984 -300.848595) (xy 178.99 -300.831143) (xy 179.038219 -300.821299)
			(xy 179.087394 -300.819318) (xy 179.136249 -300.82525) (xy 179.18352 -300.838942) (xy 179.227982 -300.86004)
			(xy 179.268485 -300.887996) (xy 179.303978 -300.922088) (xy 179.333543 -300.961432) (xy 179.356414 -301.005009)
			(xy 179.371998 -301.05169) (xy 179.379893 -301.100267) (xy 179.380388 -301.124874) (xy 179.719236 -301.124874)
			(xy 179.723196 -301.07582) (xy 179.734973 -301.028036) (xy 179.754264 -300.98276) (xy 179.780567 -300.941164)
			(xy 179.813202 -300.904327) (xy 179.851323 -300.873202) (xy 179.893944 -300.848595) (xy 179.93996 -300.831143)
			(xy 179.988179 -300.821299) (xy 180.037354 -300.819318) (xy 180.086209 -300.82525) (xy 180.13348 -300.838942)
			(xy 180.177942 -300.86004) (xy 180.218445 -300.887996) (xy 180.253938 -300.922088) (xy 180.283503 -300.961432)
			(xy 180.306374 -301.005009) (xy 180.321958 -301.05169) (xy 180.329853 -301.100267) (xy 180.330348 -301.124874)
			(xy 180.669196 -301.124874) (xy 180.673156 -301.07582) (xy 180.684933 -301.028036) (xy 180.704224 -300.98276)
			(xy 180.730527 -300.941164) (xy 180.763162 -300.904327) (xy 180.801283 -300.873202) (xy 180.843904 -300.848595)
			(xy 180.88992 -300.831143) (xy 180.938139 -300.821299) (xy 180.987314 -300.819318) (xy 181.036169 -300.82525)
			(xy 181.08344 -300.838942) (xy 181.127902 -300.86004) (xy 181.168405 -300.887996) (xy 181.203898 -300.922088)
			(xy 181.233463 -300.961432) (xy 181.256334 -301.005009) (xy 181.271918 -301.05169) (xy 181.279813 -301.100267)
			(xy 181.280308 -301.124874) (xy 181.619156 -301.124874) (xy 181.623116 -301.07582) (xy 181.634893 -301.028036)
			(xy 181.654184 -300.98276) (xy 181.680487 -300.941164) (xy 181.713122 -300.904327) (xy 181.751243 -300.873202)
			(xy 181.793864 -300.848595) (xy 181.83988 -300.831143) (xy 181.888099 -300.821299) (xy 181.937274 -300.819318)
			(xy 181.986129 -300.82525) (xy 182.0334 -300.838942) (xy 182.077862 -300.86004) (xy 182.118365 -300.887996)
			(xy 182.153858 -300.922088) (xy 182.183423 -300.961432) (xy 182.206294 -301.005009) (xy 182.221878 -301.05169)
			(xy 182.229773 -301.100267) (xy 182.230268 -301.124874) (xy 182.569116 -301.124874) (xy 182.573076 -301.07582)
			(xy 182.584853 -301.028036) (xy 182.604144 -300.98276) (xy 182.630447 -300.941164) (xy 182.663082 -300.904327)
			(xy 182.701203 -300.873202) (xy 182.743824 -300.848595) (xy 182.78984 -300.831143) (xy 182.838059 -300.821299)
			(xy 182.887234 -300.819318) (xy 182.936089 -300.82525) (xy 182.98336 -300.838942) (xy 183.027822 -300.86004)
			(xy 183.068325 -300.887996) (xy 183.103818 -300.922088) (xy 183.133383 -300.961432) (xy 183.156254 -301.005009)
			(xy 183.171838 -301.05169) (xy 183.179733 -301.100267) (xy 183.180228 -301.124874) (xy 183.519076 -301.124874)
			(xy 183.523036 -301.07582) (xy 183.534813 -301.028036) (xy 183.554104 -300.98276) (xy 183.580407 -300.941164)
			(xy 183.613042 -300.904327) (xy 183.651163 -300.873202) (xy 183.693784 -300.848595) (xy 183.7398 -300.831143)
			(xy 183.788019 -300.821299) (xy 183.837194 -300.819318) (xy 183.886049 -300.82525) (xy 183.93332 -300.838942)
			(xy 183.977782 -300.86004) (xy 184.018285 -300.887996) (xy 184.053778 -300.922088) (xy 184.083343 -300.961432)
			(xy 184.106214 -301.005009) (xy 184.121798 -301.05169) (xy 184.129693 -301.100267) (xy 184.130188 -301.124874)
			(xy 184.469036 -301.124874) (xy 184.472996 -301.07582) (xy 184.484773 -301.028036) (xy 184.504064 -300.98276)
			(xy 184.530367 -300.941164) (xy 184.563002 -300.904327) (xy 184.601123 -300.873202) (xy 184.643744 -300.848595)
			(xy 184.68976 -300.831143) (xy 184.737979 -300.821299) (xy 184.787154 -300.819318) (xy 184.836009 -300.82525)
			(xy 184.88328 -300.838942) (xy 184.927742 -300.86004) (xy 184.968245 -300.887996) (xy 185.003738 -300.922088)
			(xy 185.033303 -300.961432) (xy 185.056174 -301.005009) (xy 185.071758 -301.05169) (xy 185.079653 -301.100267)
			(xy 185.080148 -301.124874) (xy 185.41925 -301.124874) (xy 185.42321 -301.07582) (xy 185.434987 -301.028036)
			(xy 185.454278 -300.98276) (xy 185.480581 -300.941164) (xy 185.513216 -300.904327) (xy 185.551337 -300.873202)
			(xy 185.593958 -300.848595) (xy 185.639974 -300.831143) (xy 185.688193 -300.821299) (xy 185.737368 -300.819318)
			(xy 185.786223 -300.82525) (xy 185.833494 -300.838942) (xy 185.877956 -300.86004) (xy 185.918459 -300.887996)
			(xy 185.953952 -300.922088) (xy 185.983517 -300.961432) (xy 186.006388 -301.005009) (xy 186.021972 -301.05169)
			(xy 186.029867 -301.100267) (xy 186.030362 -301.124874) (xy 186.36921 -301.124874) (xy 186.37317 -301.07582)
			(xy 186.384947 -301.028036) (xy 186.404238 -300.98276) (xy 186.430541 -300.941164) (xy 186.463176 -300.904327)
			(xy 186.501297 -300.873202) (xy 186.543918 -300.848595) (xy 186.589934 -300.831143) (xy 186.638153 -300.821299)
			(xy 186.687328 -300.819318) (xy 186.736183 -300.82525) (xy 186.783454 -300.838942) (xy 186.827916 -300.86004)
			(xy 186.868419 -300.887996) (xy 186.903912 -300.922088) (xy 186.933477 -300.961432) (xy 186.956348 -301.005009)
			(xy 186.971932 -301.05169) (xy 186.979827 -301.100267) (xy 186.980322 -301.124874) (xy 187.31917 -301.124874)
			(xy 187.32313 -301.07582) (xy 187.334907 -301.028036) (xy 187.354198 -300.98276) (xy 187.380501 -300.941164)
			(xy 187.413136 -300.904327) (xy 187.451257 -300.873202) (xy 187.493878 -300.848595) (xy 187.539894 -300.831143)
			(xy 187.588113 -300.821299) (xy 187.637288 -300.819318) (xy 187.686143 -300.82525) (xy 187.733414 -300.838942)
			(xy 187.777876 -300.86004) (xy 187.818379 -300.887996) (xy 187.853872 -300.922088) (xy 187.883437 -300.961432)
			(xy 187.906308 -301.005009) (xy 187.921892 -301.05169) (xy 187.929787 -301.100267) (xy 187.930282 -301.124874)
			(xy 188.26913 -301.124874) (xy 188.27309 -301.07582) (xy 188.284867 -301.028036) (xy 188.304158 -300.98276)
			(xy 188.330461 -300.941164) (xy 188.363096 -300.904327) (xy 188.401217 -300.873202) (xy 188.443838 -300.848595)
			(xy 188.489854 -300.831143) (xy 188.538073 -300.821299) (xy 188.587248 -300.819318) (xy 188.636103 -300.82525)
			(xy 188.683374 -300.838942) (xy 188.727836 -300.86004) (xy 188.768339 -300.887996) (xy 188.803832 -300.922088)
			(xy 188.833397 -300.961432) (xy 188.856268 -301.005009) (xy 188.871852 -301.05169) (xy 188.879747 -301.100267)
			(xy 188.880242 -301.124874) (xy 189.21909 -301.124874) (xy 189.22305 -301.07582) (xy 189.234827 -301.028036)
			(xy 189.254118 -300.98276) (xy 189.280421 -300.941164) (xy 189.313056 -300.904327) (xy 189.351177 -300.873202)
			(xy 189.393798 -300.848595) (xy 189.439814 -300.831143) (xy 189.488033 -300.821299) (xy 189.537208 -300.819318)
			(xy 189.586063 -300.82525) (xy 189.633334 -300.838942) (xy 189.677796 -300.86004) (xy 189.718299 -300.887996)
			(xy 189.753792 -300.922088) (xy 189.783357 -300.961432) (xy 189.806228 -301.005009) (xy 189.821812 -301.05169)
			(xy 189.829707 -301.100267) (xy 189.830202 -301.124874) (xy 189.829707 -301.149481) (xy 189.821812 -301.198058)
			(xy 189.806228 -301.244739) (xy 189.783357 -301.288316) (xy 189.753792 -301.32766) (xy 189.718299 -301.361752)
			(xy 189.677796 -301.389708) (xy 189.633334 -301.410806) (xy 189.586063 -301.424498) (xy 189.537208 -301.43043)
			(xy 189.488033 -301.428449) (xy 189.439814 -301.418605) (xy 189.393798 -301.401153) (xy 189.351177 -301.376546)
			(xy 189.313056 -301.345421) (xy 189.280421 -301.308584) (xy 189.254118 -301.266988) (xy 189.234827 -301.221712)
			(xy 189.22305 -301.173928) (xy 189.21909 -301.124874) (xy 188.880242 -301.124874) (xy 188.879747 -301.149481)
			(xy 188.871852 -301.198058) (xy 188.856268 -301.244739) (xy 188.833397 -301.288316) (xy 188.803832 -301.32766)
			(xy 188.768339 -301.361752) (xy 188.727836 -301.389708) (xy 188.683374 -301.410806) (xy 188.636103 -301.424498)
			(xy 188.587248 -301.43043) (xy 188.538073 -301.428449) (xy 188.489854 -301.418605) (xy 188.443838 -301.401153)
			(xy 188.401217 -301.376546) (xy 188.363096 -301.345421) (xy 188.330461 -301.308584) (xy 188.304158 -301.266988)
			(xy 188.284867 -301.221712) (xy 188.27309 -301.173928) (xy 188.26913 -301.124874) (xy 187.930282 -301.124874)
			(xy 187.929787 -301.149481) (xy 187.921892 -301.198058) (xy 187.906308 -301.244739) (xy 187.883437 -301.288316)
			(xy 187.853872 -301.32766) (xy 187.818379 -301.361752) (xy 187.777876 -301.389708) (xy 187.733414 -301.410806)
			(xy 187.686143 -301.424498) (xy 187.637288 -301.43043) (xy 187.588113 -301.428449) (xy 187.539894 -301.418605)
			(xy 187.493878 -301.401153) (xy 187.451257 -301.376546) (xy 187.413136 -301.345421) (xy 187.380501 -301.308584)
			(xy 187.354198 -301.266988) (xy 187.334907 -301.221712) (xy 187.32313 -301.173928) (xy 187.31917 -301.124874)
			(xy 186.980322 -301.124874) (xy 186.979827 -301.149481) (xy 186.971932 -301.198058) (xy 186.956348 -301.244739)
			(xy 186.933477 -301.288316) (xy 186.903912 -301.32766) (xy 186.868419 -301.361752) (xy 186.827916 -301.389708)
			(xy 186.783454 -301.410806) (xy 186.736183 -301.424498) (xy 186.687328 -301.43043) (xy 186.638153 -301.428449)
			(xy 186.589934 -301.418605) (xy 186.543918 -301.401153) (xy 186.501297 -301.376546) (xy 186.463176 -301.345421)
			(xy 186.430541 -301.308584) (xy 186.404238 -301.266988) (xy 186.384947 -301.221712) (xy 186.37317 -301.173928)
			(xy 186.36921 -301.124874) (xy 186.030362 -301.124874) (xy 186.029867 -301.149481) (xy 186.021972 -301.198058)
			(xy 186.006388 -301.244739) (xy 185.983517 -301.288316) (xy 185.953952 -301.32766) (xy 185.918459 -301.361752)
			(xy 185.877956 -301.389708) (xy 185.833494 -301.410806) (xy 185.786223 -301.424498) (xy 185.737368 -301.43043)
			(xy 185.688193 -301.428449) (xy 185.639974 -301.418605) (xy 185.593958 -301.401153) (xy 185.551337 -301.376546)
			(xy 185.513216 -301.345421) (xy 185.480581 -301.308584) (xy 185.454278 -301.266988) (xy 185.434987 -301.221712)
			(xy 185.42321 -301.173928) (xy 185.41925 -301.124874) (xy 185.080148 -301.124874) (xy 185.079653 -301.149481)
			(xy 185.071758 -301.198058) (xy 185.056174 -301.244739) (xy 185.033303 -301.288316) (xy 185.003738 -301.32766)
			(xy 184.968245 -301.361752) (xy 184.927742 -301.389708) (xy 184.88328 -301.410806) (xy 184.836009 -301.424498)
			(xy 184.787154 -301.43043) (xy 184.737979 -301.428449) (xy 184.68976 -301.418605) (xy 184.643744 -301.401153)
			(xy 184.601123 -301.376546) (xy 184.563002 -301.345421) (xy 184.530367 -301.308584) (xy 184.504064 -301.266988)
			(xy 184.484773 -301.221712) (xy 184.472996 -301.173928) (xy 184.469036 -301.124874) (xy 184.130188 -301.124874)
			(xy 184.129693 -301.149481) (xy 184.121798 -301.198058) (xy 184.106214 -301.244739) (xy 184.083343 -301.288316)
			(xy 184.053778 -301.32766) (xy 184.018285 -301.361752) (xy 183.977782 -301.389708) (xy 183.93332 -301.410806)
			(xy 183.886049 -301.424498) (xy 183.837194 -301.43043) (xy 183.788019 -301.428449) (xy 183.7398 -301.418605)
			(xy 183.693784 -301.401153) (xy 183.651163 -301.376546) (xy 183.613042 -301.345421) (xy 183.580407 -301.308584)
			(xy 183.554104 -301.266988) (xy 183.534813 -301.221712) (xy 183.523036 -301.173928) (xy 183.519076 -301.124874)
			(xy 183.180228 -301.124874) (xy 183.179733 -301.149481) (xy 183.171838 -301.198058) (xy 183.156254 -301.244739)
			(xy 183.133383 -301.288316) (xy 183.103818 -301.32766) (xy 183.068325 -301.361752) (xy 183.027822 -301.389708)
			(xy 182.98336 -301.410806) (xy 182.936089 -301.424498) (xy 182.887234 -301.43043) (xy 182.838059 -301.428449)
			(xy 182.78984 -301.418605) (xy 182.743824 -301.401153) (xy 182.701203 -301.376546) (xy 182.663082 -301.345421)
			(xy 182.630447 -301.308584) (xy 182.604144 -301.266988) (xy 182.584853 -301.221712) (xy 182.573076 -301.173928)
			(xy 182.569116 -301.124874) (xy 182.230268 -301.124874) (xy 182.229773 -301.149481) (xy 182.221878 -301.198058)
			(xy 182.206294 -301.244739) (xy 182.183423 -301.288316) (xy 182.153858 -301.32766) (xy 182.118365 -301.361752)
			(xy 182.077862 -301.389708) (xy 182.0334 -301.410806) (xy 181.986129 -301.424498) (xy 181.937274 -301.43043)
			(xy 181.888099 -301.428449) (xy 181.83988 -301.418605) (xy 181.793864 -301.401153) (xy 181.751243 -301.376546)
			(xy 181.713122 -301.345421) (xy 181.680487 -301.308584) (xy 181.654184 -301.266988) (xy 181.634893 -301.221712)
			(xy 181.623116 -301.173928) (xy 181.619156 -301.124874) (xy 181.280308 -301.124874) (xy 181.279813 -301.149481)
			(xy 181.271918 -301.198058) (xy 181.256334 -301.244739) (xy 181.233463 -301.288316) (xy 181.203898 -301.32766)
			(xy 181.168405 -301.361752) (xy 181.127902 -301.389708) (xy 181.08344 -301.410806) (xy 181.036169 -301.424498)
			(xy 180.987314 -301.43043) (xy 180.938139 -301.428449) (xy 180.88992 -301.418605) (xy 180.843904 -301.401153)
			(xy 180.801283 -301.376546) (xy 180.763162 -301.345421) (xy 180.730527 -301.308584) (xy 180.704224 -301.266988)
			(xy 180.684933 -301.221712) (xy 180.673156 -301.173928) (xy 180.669196 -301.124874) (xy 180.330348 -301.124874)
			(xy 180.329853 -301.149481) (xy 180.321958 -301.198058) (xy 180.306374 -301.244739) (xy 180.283503 -301.288316)
			(xy 180.253938 -301.32766) (xy 180.218445 -301.361752) (xy 180.177942 -301.389708) (xy 180.13348 -301.410806)
			(xy 180.086209 -301.424498) (xy 180.037354 -301.43043) (xy 179.988179 -301.428449) (xy 179.93996 -301.418605)
			(xy 179.893944 -301.401153) (xy 179.851323 -301.376546) (xy 179.813202 -301.345421) (xy 179.780567 -301.308584)
			(xy 179.754264 -301.266988) (xy 179.734973 -301.221712) (xy 179.723196 -301.173928) (xy 179.719236 -301.124874)
			(xy 179.380388 -301.124874) (xy 179.379893 -301.149481) (xy 179.371998 -301.198058) (xy 179.356414 -301.244739)
			(xy 179.333543 -301.288316) (xy 179.303978 -301.32766) (xy 179.268485 -301.361752) (xy 179.227982 -301.389708)
			(xy 179.18352 -301.410806) (xy 179.136249 -301.424498) (xy 179.087394 -301.43043) (xy 179.038219 -301.428449)
			(xy 178.99 -301.418605) (xy 178.943984 -301.401153) (xy 178.901363 -301.376546) (xy 178.863242 -301.345421)
			(xy 178.830607 -301.308584) (xy 178.804304 -301.266988) (xy 178.785013 -301.221712) (xy 178.773236 -301.173928)
			(xy 178.769276 -301.124874) (xy 178.430174 -301.124874) (xy 178.429679 -301.149481) (xy 178.421784 -301.198058)
			(xy 178.4062 -301.244739) (xy 178.383329 -301.288316) (xy 178.353764 -301.32766) (xy 178.318271 -301.361752)
			(xy 178.277768 -301.389708) (xy 178.233306 -301.410806) (xy 178.186035 -301.424498) (xy 178.13718 -301.43043)
			(xy 178.088005 -301.428449) (xy 178.039786 -301.418605) (xy 177.99377 -301.401153) (xy 177.951149 -301.376546)
			(xy 177.913028 -301.345421) (xy 177.880393 -301.308584) (xy 177.85409 -301.266988) (xy 177.834799 -301.221712)
			(xy 177.823022 -301.173928) (xy 177.819062 -301.124874) (xy 177.480214 -301.124874) (xy 177.479719 -301.149481)
			(xy 177.471824 -301.198058) (xy 177.45624 -301.244739) (xy 177.433369 -301.288316) (xy 177.403804 -301.32766)
			(xy 177.368311 -301.361752) (xy 177.327808 -301.389708) (xy 177.283346 -301.410806) (xy 177.236075 -301.424498)
			(xy 177.18722 -301.43043) (xy 177.138045 -301.428449) (xy 177.089826 -301.418605) (xy 177.04381 -301.401153)
			(xy 177.001189 -301.376546) (xy 176.963068 -301.345421) (xy 176.930433 -301.308584) (xy 176.90413 -301.266988)
			(xy 176.884839 -301.221712) (xy 176.873062 -301.173928) (xy 176.869102 -301.124874) (xy 176.530254 -301.124874)
			(xy 176.529759 -301.149481) (xy 176.521864 -301.198058) (xy 176.50628 -301.244739) (xy 176.483409 -301.288316)
			(xy 176.453844 -301.32766) (xy 176.418351 -301.361752) (xy 176.377848 -301.389708) (xy 176.333386 -301.410806)
			(xy 176.286115 -301.424498) (xy 176.23726 -301.43043) (xy 176.188085 -301.428449) (xy 176.139866 -301.418605)
			(xy 176.09385 -301.401153) (xy 176.051229 -301.376546) (xy 176.013108 -301.345421) (xy 175.980473 -301.308584)
			(xy 175.95417 -301.266988) (xy 175.934879 -301.221712) (xy 175.923102 -301.173928) (xy 175.919142 -301.124874)
			(xy 174.630334 -301.124874) (xy 174.629839 -301.149481) (xy 174.621944 -301.198058) (xy 174.60636 -301.244739)
			(xy 174.583489 -301.288316) (xy 174.553924 -301.32766) (xy 174.518431 -301.361752) (xy 174.477928 -301.389708)
			(xy 174.433466 -301.410806) (xy 174.386195 -301.424498) (xy 174.33734 -301.43043) (xy 174.288165 -301.428449)
			(xy 174.239946 -301.418605) (xy 174.19393 -301.401153) (xy 174.151309 -301.376546) (xy 174.113188 -301.345421)
			(xy 174.080553 -301.308584) (xy 174.05425 -301.266988) (xy 174.034959 -301.221712) (xy 174.023182 -301.173928)
			(xy 174.019222 -301.124874) (xy 173.680374 -301.124874) (xy 173.679879 -301.149481) (xy 173.671984 -301.198058)
			(xy 173.6564 -301.244739) (xy 173.633529 -301.288316) (xy 173.603964 -301.32766) (xy 173.568471 -301.361752)
			(xy 173.527968 -301.389708) (xy 173.483506 -301.410806) (xy 173.436235 -301.424498) (xy 173.38738 -301.43043)
			(xy 173.338205 -301.428449) (xy 173.289986 -301.418605) (xy 173.24397 -301.401153) (xy 173.201349 -301.376546)
			(xy 173.163228 -301.345421) (xy 173.130593 -301.308584) (xy 173.10429 -301.266988) (xy 173.084999 -301.221712)
			(xy 173.073222 -301.173928) (xy 173.069262 -301.124874) (xy 172.73016 -301.124874) (xy 172.729665 -301.149481)
			(xy 172.72177 -301.198058) (xy 172.706186 -301.244739) (xy 172.683315 -301.288316) (xy 172.65375 -301.32766)
			(xy 172.618257 -301.361752) (xy 172.577754 -301.389708) (xy 172.533292 -301.410806) (xy 172.486021 -301.424498)
			(xy 172.437166 -301.43043) (xy 172.387991 -301.428449) (xy 172.339772 -301.418605) (xy 172.293756 -301.401153)
			(xy 172.251135 -301.376546) (xy 172.213014 -301.345421) (xy 172.180379 -301.308584) (xy 172.154076 -301.266988)
			(xy 172.134785 -301.221712) (xy 172.123008 -301.173928) (xy 172.119048 -301.124874) (xy 171.7802 -301.124874)
			(xy 171.779705 -301.149481) (xy 171.77181 -301.198058) (xy 171.756226 -301.244739) (xy 171.733355 -301.288316)
			(xy 171.70379 -301.32766) (xy 171.668297 -301.361752) (xy 171.627794 -301.389708) (xy 171.583332 -301.410806)
			(xy 171.536061 -301.424498) (xy 171.487206 -301.43043) (xy 171.438031 -301.428449) (xy 171.389812 -301.418605)
			(xy 171.343796 -301.401153) (xy 171.301175 -301.376546) (xy 171.263054 -301.345421) (xy 171.230419 -301.308584)
			(xy 171.204116 -301.266988) (xy 171.184825 -301.221712) (xy 171.173048 -301.173928) (xy 171.169088 -301.124874)
			(xy 170.83024 -301.124874) (xy 170.829745 -301.149481) (xy 170.82185 -301.198058) (xy 170.806266 -301.244739)
			(xy 170.783395 -301.288316) (xy 170.75383 -301.32766) (xy 170.718337 -301.361752) (xy 170.677834 -301.389708)
			(xy 170.633372 -301.410806) (xy 170.586101 -301.424498) (xy 170.537246 -301.43043) (xy 170.488071 -301.428449)
			(xy 170.439852 -301.418605) (xy 170.393836 -301.401153) (xy 170.351215 -301.376546) (xy 170.313094 -301.345421)
			(xy 170.280459 -301.308584) (xy 170.254156 -301.266988) (xy 170.234865 -301.221712) (xy 170.223088 -301.173928)
			(xy 170.219128 -301.124874) (xy 169.88028 -301.124874) (xy 169.879785 -301.149481) (xy 169.87189 -301.198058)
			(xy 169.856306 -301.244739) (xy 169.833435 -301.288316) (xy 169.80387 -301.32766) (xy 169.768377 -301.361752)
			(xy 169.727874 -301.389708) (xy 169.683412 -301.410806) (xy 169.636141 -301.424498) (xy 169.587286 -301.43043)
			(xy 169.538111 -301.428449) (xy 169.489892 -301.418605) (xy 169.443876 -301.401153) (xy 169.401255 -301.376546)
			(xy 169.363134 -301.345421) (xy 169.330499 -301.308584) (xy 169.304196 -301.266988) (xy 169.284905 -301.221712)
			(xy 169.273128 -301.173928) (xy 169.269168 -301.124874) (xy 168.93032 -301.124874) (xy 168.929825 -301.149481)
			(xy 168.92193 -301.198058) (xy 168.906346 -301.244739) (xy 168.883475 -301.288316) (xy 168.85391 -301.32766)
			(xy 168.818417 -301.361752) (xy 168.777914 -301.389708) (xy 168.733452 -301.410806) (xy 168.686181 -301.424498)
			(xy 168.637326 -301.43043) (xy 168.588151 -301.428449) (xy 168.539932 -301.418605) (xy 168.493916 -301.401153)
			(xy 168.451295 -301.376546) (xy 168.413174 -301.345421) (xy 168.380539 -301.308584) (xy 168.354236 -301.266988)
			(xy 168.334945 -301.221712) (xy 168.323168 -301.173928) (xy 168.319208 -301.124874) (xy 167.98036 -301.124874)
			(xy 167.979865 -301.149481) (xy 167.97197 -301.198058) (xy 167.956386 -301.244739) (xy 167.933515 -301.288316)
			(xy 167.90395 -301.32766) (xy 167.868457 -301.361752) (xy 167.827954 -301.389708) (xy 167.783492 -301.410806)
			(xy 167.736221 -301.424498) (xy 167.687366 -301.43043) (xy 167.638191 -301.428449) (xy 167.589972 -301.418605)
			(xy 167.543956 -301.401153) (xy 167.501335 -301.376546) (xy 167.463214 -301.345421) (xy 167.430579 -301.308584)
			(xy 167.404276 -301.266988) (xy 167.384985 -301.221712) (xy 167.373208 -301.173928) (xy 167.369248 -301.124874)
			(xy 167.0304 -301.124874) (xy 167.029905 -301.149481) (xy 167.02201 -301.198058) (xy 167.006426 -301.244739)
			(xy 166.983555 -301.288316) (xy 166.95399 -301.32766) (xy 166.918497 -301.361752) (xy 166.877994 -301.389708)
			(xy 166.833532 -301.410806) (xy 166.786261 -301.424498) (xy 166.737406 -301.43043) (xy 166.688231 -301.428449)
			(xy 166.640012 -301.418605) (xy 166.593996 -301.401153) (xy 166.551375 -301.376546) (xy 166.513254 -301.345421)
			(xy 166.480619 -301.308584) (xy 166.454316 -301.266988) (xy 166.435025 -301.221712) (xy 166.423248 -301.173928)
			(xy 166.419288 -301.124874) (xy 166.080186 -301.124874) (xy 166.079691 -301.149481) (xy 166.071796 -301.198058)
			(xy 166.056212 -301.244739) (xy 166.033341 -301.288316) (xy 166.003776 -301.32766) (xy 165.968283 -301.361752)
			(xy 165.92778 -301.389708) (xy 165.883318 -301.410806) (xy 165.836047 -301.424498) (xy 165.787192 -301.43043)
			(xy 165.738017 -301.428449) (xy 165.689798 -301.418605) (xy 165.643782 -301.401153) (xy 165.601161 -301.376546)
			(xy 165.56304 -301.345421) (xy 165.530405 -301.308584) (xy 165.504102 -301.266988) (xy 165.484811 -301.221712)
			(xy 165.473034 -301.173928) (xy 165.469074 -301.124874) (xy 165.155109 -301.124874) (xy 165.15511 -301.15128)
			(xy 165.146732 -301.203378) (xy 165.130187 -301.253485) (xy 165.105897 -301.300328) (xy 165.074476 -301.342721)
			(xy 165.036723 -301.379587) (xy 164.993595 -301.40999) (xy 164.946187 -301.433159) (xy 164.895701 -301.448507)
			(xy 164.869622 -301.452534) (xy 164.86505 -301.453296) (xy 164.854636 -301.456598) (xy 164.850318 -301.457868)
			(xy 164.826696 -301.46879) (xy 164.819838 -301.475902) (xy 164.804852 -301.49165) (xy 164.800269 -301.496757)
			(xy 164.793835 -301.508873) (xy 164.792152 -301.515526) (xy 164.790882 -301.526448) (xy 164.790882 -302.074834)
			(xy 165.469074 -302.074834) (xy 165.473034 -302.02578) (xy 165.484811 -301.977996) (xy 165.504102 -301.93272)
			(xy 165.530405 -301.891124) (xy 165.56304 -301.854287) (xy 165.601161 -301.823162) (xy 165.643782 -301.798555)
			(xy 165.689798 -301.781103) (xy 165.738017 -301.771259) (xy 165.787192 -301.769278) (xy 165.836047 -301.77521)
			(xy 165.883318 -301.788902) (xy 165.92778 -301.81) (xy 165.968283 -301.837956) (xy 166.003776 -301.872048)
			(xy 166.033341 -301.911392) (xy 166.056212 -301.954969) (xy 166.071796 -302.00165) (xy 166.079691 -302.050227)
			(xy 166.080186 -302.074834) (xy 166.419288 -302.074834) (xy 166.423248 -302.02578) (xy 166.435025 -301.977996)
			(xy 166.454316 -301.93272) (xy 166.480619 -301.891124) (xy 166.513254 -301.854287) (xy 166.551375 -301.823162)
			(xy 166.593996 -301.798555) (xy 166.640012 -301.781103) (xy 166.688231 -301.771259) (xy 166.737406 -301.769278)
			(xy 166.786261 -301.77521) (xy 166.833532 -301.788902) (xy 166.877994 -301.81) (xy 166.918497 -301.837956)
			(xy 166.95399 -301.872048) (xy 166.983555 -301.911392) (xy 167.006426 -301.954969) (xy 167.02201 -302.00165)
			(xy 167.029905 -302.050227) (xy 167.0304 -302.074834) (xy 167.369248 -302.074834) (xy 167.373208 -302.02578)
			(xy 167.384985 -301.977996) (xy 167.404276 -301.93272) (xy 167.430579 -301.891124) (xy 167.463214 -301.854287)
			(xy 167.501335 -301.823162) (xy 167.543956 -301.798555) (xy 167.589972 -301.781103) (xy 167.638191 -301.771259)
			(xy 167.687366 -301.769278) (xy 167.736221 -301.77521) (xy 167.783492 -301.788902) (xy 167.827954 -301.81)
			(xy 167.868457 -301.837956) (xy 167.90395 -301.872048) (xy 167.933515 -301.911392) (xy 167.956386 -301.954969)
			(xy 167.97197 -302.00165) (xy 167.979865 -302.050227) (xy 167.98036 -302.074834) (xy 168.319208 -302.074834)
			(xy 168.323168 -302.02578) (xy 168.334945 -301.977996) (xy 168.354236 -301.93272) (xy 168.380539 -301.891124)
			(xy 168.413174 -301.854287) (xy 168.451295 -301.823162) (xy 168.493916 -301.798555) (xy 168.539932 -301.781103)
			(xy 168.588151 -301.771259) (xy 168.637326 -301.769278) (xy 168.686181 -301.77521) (xy 168.733452 -301.788902)
			(xy 168.777914 -301.81) (xy 168.818417 -301.837956) (xy 168.85391 -301.872048) (xy 168.883475 -301.911392)
			(xy 168.906346 -301.954969) (xy 168.92193 -302.00165) (xy 168.929825 -302.050227) (xy 168.93032 -302.074834)
			(xy 169.269168 -302.074834) (xy 169.273128 -302.02578) (xy 169.284905 -301.977996) (xy 169.304196 -301.93272)
			(xy 169.330499 -301.891124) (xy 169.363134 -301.854287) (xy 169.401255 -301.823162) (xy 169.443876 -301.798555)
			(xy 169.489892 -301.781103) (xy 169.538111 -301.771259) (xy 169.587286 -301.769278) (xy 169.636141 -301.77521)
			(xy 169.683412 -301.788902) (xy 169.727874 -301.81) (xy 169.768377 -301.837956) (xy 169.80387 -301.872048)
			(xy 169.833435 -301.911392) (xy 169.856306 -301.954969) (xy 169.87189 -302.00165) (xy 169.879785 -302.050227)
			(xy 169.88028 -302.074834) (xy 170.219128 -302.074834) (xy 170.223088 -302.02578) (xy 170.234865 -301.977996)
			(xy 170.254156 -301.93272) (xy 170.280459 -301.891124) (xy 170.313094 -301.854287) (xy 170.351215 -301.823162)
			(xy 170.393836 -301.798555) (xy 170.439852 -301.781103) (xy 170.488071 -301.771259) (xy 170.537246 -301.769278)
			(xy 170.586101 -301.77521) (xy 170.633372 -301.788902) (xy 170.677834 -301.81) (xy 170.718337 -301.837956)
			(xy 170.75383 -301.872048) (xy 170.783395 -301.911392) (xy 170.806266 -301.954969) (xy 170.82185 -302.00165)
			(xy 170.829745 -302.050227) (xy 170.83024 -302.074834) (xy 171.169088 -302.074834) (xy 171.173048 -302.02578)
			(xy 171.184825 -301.977996) (xy 171.204116 -301.93272) (xy 171.230419 -301.891124) (xy 171.263054 -301.854287)
			(xy 171.301175 -301.823162) (xy 171.343796 -301.798555) (xy 171.389812 -301.781103) (xy 171.438031 -301.771259)
			(xy 171.487206 -301.769278) (xy 171.536061 -301.77521) (xy 171.583332 -301.788902) (xy 171.627794 -301.81)
			(xy 171.668297 -301.837956) (xy 171.70379 -301.872048) (xy 171.733355 -301.911392) (xy 171.756226 -301.954969)
			(xy 171.77181 -302.00165) (xy 171.779705 -302.050227) (xy 171.7802 -302.074834) (xy 172.119048 -302.074834)
			(xy 172.123008 -302.02578) (xy 172.134785 -301.977996) (xy 172.154076 -301.93272) (xy 172.180379 -301.891124)
			(xy 172.213014 -301.854287) (xy 172.251135 -301.823162) (xy 172.293756 -301.798555) (xy 172.339772 -301.781103)
			(xy 172.387991 -301.771259) (xy 172.437166 -301.769278) (xy 172.486021 -301.77521) (xy 172.533292 -301.788902)
			(xy 172.577754 -301.81) (xy 172.618257 -301.837956) (xy 172.65375 -301.872048) (xy 172.683315 -301.911392)
			(xy 172.706186 -301.954969) (xy 172.72177 -302.00165) (xy 172.729665 -302.050227) (xy 172.73016 -302.074834)
			(xy 173.069262 -302.074834) (xy 173.073222 -302.02578) (xy 173.084999 -301.977996) (xy 173.10429 -301.93272)
			(xy 173.130593 -301.891124) (xy 173.163228 -301.854287) (xy 173.201349 -301.823162) (xy 173.24397 -301.798555)
			(xy 173.289986 -301.781103) (xy 173.338205 -301.771259) (xy 173.38738 -301.769278) (xy 173.436235 -301.77521)
			(xy 173.483506 -301.788902) (xy 173.527968 -301.81) (xy 173.568471 -301.837956) (xy 173.603964 -301.872048)
			(xy 173.633529 -301.911392) (xy 173.6564 -301.954969) (xy 173.671984 -302.00165) (xy 173.679879 -302.050227)
			(xy 173.680374 -302.074834) (xy 174.019222 -302.074834) (xy 174.023182 -302.02578) (xy 174.034959 -301.977996)
			(xy 174.05425 -301.93272) (xy 174.080553 -301.891124) (xy 174.113188 -301.854287) (xy 174.151309 -301.823162)
			(xy 174.19393 -301.798555) (xy 174.239946 -301.781103) (xy 174.288165 -301.771259) (xy 174.33734 -301.769278)
			(xy 174.386195 -301.77521) (xy 174.433466 -301.788902) (xy 174.477928 -301.81) (xy 174.518431 -301.837956)
			(xy 174.553924 -301.872048) (xy 174.583489 -301.911392) (xy 174.60636 -301.954969) (xy 174.621944 -302.00165)
			(xy 174.629839 -302.050227) (xy 174.630334 -302.074834) (xy 175.919142 -302.074834) (xy 175.923102 -302.02578)
			(xy 175.934879 -301.977996) (xy 175.95417 -301.93272) (xy 175.980473 -301.891124) (xy 176.013108 -301.854287)
			(xy 176.051229 -301.823162) (xy 176.09385 -301.798555) (xy 176.139866 -301.781103) (xy 176.188085 -301.771259)
			(xy 176.23726 -301.769278) (xy 176.286115 -301.77521) (xy 176.333386 -301.788902) (xy 176.377848 -301.81)
			(xy 176.418351 -301.837956) (xy 176.453844 -301.872048) (xy 176.483409 -301.911392) (xy 176.50628 -301.954969)
			(xy 176.521864 -302.00165) (xy 176.529759 -302.050227) (xy 176.530254 -302.074834) (xy 176.869102 -302.074834)
			(xy 176.873062 -302.02578) (xy 176.884839 -301.977996) (xy 176.90413 -301.93272) (xy 176.930433 -301.891124)
			(xy 176.963068 -301.854287) (xy 177.001189 -301.823162) (xy 177.04381 -301.798555) (xy 177.089826 -301.781103)
			(xy 177.138045 -301.771259) (xy 177.18722 -301.769278) (xy 177.236075 -301.77521) (xy 177.283346 -301.788902)
			(xy 177.327808 -301.81) (xy 177.368311 -301.837956) (xy 177.403804 -301.872048) (xy 177.433369 -301.911392)
			(xy 177.45624 -301.954969) (xy 177.471824 -302.00165) (xy 177.479719 -302.050227) (xy 177.480214 -302.074834)
			(xy 177.819062 -302.074834) (xy 177.823022 -302.02578) (xy 177.834799 -301.977996) (xy 177.85409 -301.93272)
			(xy 177.880393 -301.891124) (xy 177.913028 -301.854287) (xy 177.951149 -301.823162) (xy 177.99377 -301.798555)
			(xy 178.039786 -301.781103) (xy 178.088005 -301.771259) (xy 178.13718 -301.769278) (xy 178.186035 -301.77521)
			(xy 178.233306 -301.788902) (xy 178.277768 -301.81) (xy 178.318271 -301.837956) (xy 178.353764 -301.872048)
			(xy 178.383329 -301.911392) (xy 178.4062 -301.954969) (xy 178.421784 -302.00165) (xy 178.429679 -302.050227)
			(xy 178.430174 -302.074834) (xy 178.769276 -302.074834) (xy 178.773236 -302.02578) (xy 178.785013 -301.977996)
			(xy 178.804304 -301.93272) (xy 178.830607 -301.891124) (xy 178.863242 -301.854287) (xy 178.901363 -301.823162)
			(xy 178.943984 -301.798555) (xy 178.99 -301.781103) (xy 179.038219 -301.771259) (xy 179.087394 -301.769278)
			(xy 179.136249 -301.77521) (xy 179.18352 -301.788902) (xy 179.227982 -301.81) (xy 179.268485 -301.837956)
			(xy 179.303978 -301.872048) (xy 179.333543 -301.911392) (xy 179.356414 -301.954969) (xy 179.371998 -302.00165)
			(xy 179.379893 -302.050227) (xy 179.380388 -302.074834) (xy 179.719236 -302.074834) (xy 179.723196 -302.02578)
			(xy 179.734973 -301.977996) (xy 179.754264 -301.93272) (xy 179.780567 -301.891124) (xy 179.813202 -301.854287)
			(xy 179.851323 -301.823162) (xy 179.893944 -301.798555) (xy 179.93996 -301.781103) (xy 179.988179 -301.771259)
			(xy 180.037354 -301.769278) (xy 180.086209 -301.77521) (xy 180.13348 -301.788902) (xy 180.177942 -301.81)
			(xy 180.218445 -301.837956) (xy 180.253938 -301.872048) (xy 180.283503 -301.911392) (xy 180.306374 -301.954969)
			(xy 180.321958 -302.00165) (xy 180.329853 -302.050227) (xy 180.330348 -302.074834) (xy 180.669196 -302.074834)
			(xy 180.673156 -302.02578) (xy 180.684933 -301.977996) (xy 180.704224 -301.93272) (xy 180.730527 -301.891124)
			(xy 180.763162 -301.854287) (xy 180.801283 -301.823162) (xy 180.843904 -301.798555) (xy 180.88992 -301.781103)
			(xy 180.938139 -301.771259) (xy 180.987314 -301.769278) (xy 181.036169 -301.77521) (xy 181.08344 -301.788902)
			(xy 181.127902 -301.81) (xy 181.168405 -301.837956) (xy 181.203898 -301.872048) (xy 181.233463 -301.911392)
			(xy 181.256334 -301.954969) (xy 181.271918 -302.00165) (xy 181.279813 -302.050227) (xy 181.280308 -302.074834)
			(xy 181.619156 -302.074834) (xy 181.623116 -302.02578) (xy 181.634893 -301.977996) (xy 181.654184 -301.93272)
			(xy 181.680487 -301.891124) (xy 181.713122 -301.854287) (xy 181.751243 -301.823162) (xy 181.793864 -301.798555)
			(xy 181.83988 -301.781103) (xy 181.888099 -301.771259) (xy 181.937274 -301.769278) (xy 181.986129 -301.77521)
			(xy 182.0334 -301.788902) (xy 182.077862 -301.81) (xy 182.118365 -301.837956) (xy 182.153858 -301.872048)
			(xy 182.183423 -301.911392) (xy 182.206294 -301.954969) (xy 182.221878 -302.00165) (xy 182.229773 -302.050227)
			(xy 182.230268 -302.074834) (xy 182.569116 -302.074834) (xy 182.573076 -302.02578) (xy 182.584853 -301.977996)
			(xy 182.604144 -301.93272) (xy 182.630447 -301.891124) (xy 182.663082 -301.854287) (xy 182.701203 -301.823162)
			(xy 182.743824 -301.798555) (xy 182.78984 -301.781103) (xy 182.838059 -301.771259) (xy 182.887234 -301.769278)
			(xy 182.936089 -301.77521) (xy 182.98336 -301.788902) (xy 183.027822 -301.81) (xy 183.068325 -301.837956)
			(xy 183.103818 -301.872048) (xy 183.133383 -301.911392) (xy 183.156254 -301.954969) (xy 183.171838 -302.00165)
			(xy 183.179733 -302.050227) (xy 183.180228 -302.074834) (xy 183.519076 -302.074834) (xy 183.523036 -302.02578)
			(xy 183.534813 -301.977996) (xy 183.554104 -301.93272) (xy 183.580407 -301.891124) (xy 183.613042 -301.854287)
			(xy 183.651163 -301.823162) (xy 183.693784 -301.798555) (xy 183.7398 -301.781103) (xy 183.788019 -301.771259)
			(xy 183.837194 -301.769278) (xy 183.886049 -301.77521) (xy 183.93332 -301.788902) (xy 183.977782 -301.81)
			(xy 184.018285 -301.837956) (xy 184.053778 -301.872048) (xy 184.083343 -301.911392) (xy 184.106214 -301.954969)
			(xy 184.121798 -302.00165) (xy 184.129693 -302.050227) (xy 184.130188 -302.074834) (xy 184.469036 -302.074834)
			(xy 184.472996 -302.02578) (xy 184.484773 -301.977996) (xy 184.504064 -301.93272) (xy 184.530367 -301.891124)
			(xy 184.563002 -301.854287) (xy 184.601123 -301.823162) (xy 184.643744 -301.798555) (xy 184.68976 -301.781103)
			(xy 184.737979 -301.771259) (xy 184.787154 -301.769278) (xy 184.836009 -301.77521) (xy 184.88328 -301.788902)
			(xy 184.927742 -301.81) (xy 184.968245 -301.837956) (xy 185.003738 -301.872048) (xy 185.033303 -301.911392)
			(xy 185.056174 -301.954969) (xy 185.071758 -302.00165) (xy 185.079653 -302.050227) (xy 185.080148 -302.074834)
			(xy 185.41925 -302.074834) (xy 185.42321 -302.02578) (xy 185.434987 -301.977996) (xy 185.454278 -301.93272)
			(xy 185.480581 -301.891124) (xy 185.513216 -301.854287) (xy 185.551337 -301.823162) (xy 185.593958 -301.798555)
			(xy 185.639974 -301.781103) (xy 185.688193 -301.771259) (xy 185.737368 -301.769278) (xy 185.786223 -301.77521)
			(xy 185.833494 -301.788902) (xy 185.877956 -301.81) (xy 185.918459 -301.837956) (xy 185.953952 -301.872048)
			(xy 185.983517 -301.911392) (xy 186.006388 -301.954969) (xy 186.021972 -302.00165) (xy 186.029867 -302.050227)
			(xy 186.030362 -302.074834) (xy 186.36921 -302.074834) (xy 186.37317 -302.02578) (xy 186.384947 -301.977996)
			(xy 186.404238 -301.93272) (xy 186.430541 -301.891124) (xy 186.463176 -301.854287) (xy 186.501297 -301.823162)
			(xy 186.543918 -301.798555) (xy 186.589934 -301.781103) (xy 186.638153 -301.771259) (xy 186.687328 -301.769278)
			(xy 186.736183 -301.77521) (xy 186.783454 -301.788902) (xy 186.827916 -301.81) (xy 186.868419 -301.837956)
			(xy 186.903912 -301.872048) (xy 186.933477 -301.911392) (xy 186.956348 -301.954969) (xy 186.971932 -302.00165)
			(xy 186.979827 -302.050227) (xy 186.980322 -302.074834) (xy 187.31917 -302.074834) (xy 187.32313 -302.02578)
			(xy 187.334907 -301.977996) (xy 187.354198 -301.93272) (xy 187.380501 -301.891124) (xy 187.413136 -301.854287)
			(xy 187.451257 -301.823162) (xy 187.493878 -301.798555) (xy 187.539894 -301.781103) (xy 187.588113 -301.771259)
			(xy 187.637288 -301.769278) (xy 187.686143 -301.77521) (xy 187.733414 -301.788902) (xy 187.777876 -301.81)
			(xy 187.818379 -301.837956) (xy 187.853872 -301.872048) (xy 187.883437 -301.911392) (xy 187.906308 -301.954969)
			(xy 187.921892 -302.00165) (xy 187.929787 -302.050227) (xy 187.930282 -302.074834) (xy 188.26913 -302.074834)
			(xy 188.27309 -302.02578) (xy 188.284867 -301.977996) (xy 188.304158 -301.93272) (xy 188.330461 -301.891124)
			(xy 188.363096 -301.854287) (xy 188.401217 -301.823162) (xy 188.443838 -301.798555) (xy 188.489854 -301.781103)
			(xy 188.538073 -301.771259) (xy 188.587248 -301.769278) (xy 188.636103 -301.77521) (xy 188.683374 -301.788902)
			(xy 188.727836 -301.81) (xy 188.768339 -301.837956) (xy 188.803832 -301.872048) (xy 188.833397 -301.911392)
			(xy 188.856268 -301.954969) (xy 188.871852 -302.00165) (xy 188.879747 -302.050227) (xy 188.880242 -302.074834)
			(xy 188.880076 -302.083066) (xy 189.219187 -302.083066) (xy 189.221877 -302.033498) (xy 189.232551 -301.985017)
			(xy 189.250928 -301.938902) (xy 189.276523 -301.896368) (xy 189.308663 -301.858535) (xy 189.3465 -301.8264)
			(xy 189.389038 -301.80081) (xy 189.435155 -301.782439) (xy 189.483637 -301.771771) (xy 189.533206 -301.769088)
			(xy 189.582557 -301.774459) (xy 189.630388 -301.787744) (xy 189.67544 -301.808592) (xy 189.716525 -301.836454)
			(xy 189.752561 -301.870596) (xy 189.782599 -301.910118) (xy 189.805847 -301.95398) (xy 189.821693 -302.001024)
			(xy 189.829719 -302.050013) (xy 189.83004 -302.06653) (xy 191.119415 -302.06653) (xy 191.124779 -302.017186)
			(xy 191.138056 -301.969361) (xy 191.158894 -301.924313) (xy 191.186745 -301.88323) (xy 191.220876 -301.847194)
			(xy 191.260387 -301.817154) (xy 191.304237 -301.793901) (xy 191.351272 -301.778049) (xy 191.400251 -301.770014)
			(xy 191.425068 -301.769526) (xy 191.439251 -301.769707) (xy 191.467491 -301.772376) (xy 191.481456 -301.77486)
			(xy 191.493902 -301.777146) (xy 191.517524 -301.76978) (xy 191.594994 -301.69231) (xy 191.60236 -301.668688)
			(xy 191.600074 -301.656242) (xy 191.597593 -301.642277) (xy 191.594924 -301.614037) (xy 191.59474 -301.599854)
			(xy 191.595096 -301.575857) (xy 191.602611 -301.528456) (xy 191.617449 -301.482813) (xy 191.639244 -301.440054)
			(xy 191.66746 -301.40123) (xy 191.701402 -301.367299) (xy 191.740234 -301.339095) (xy 191.783 -301.317313)
			(xy 191.828647 -301.302489) (xy 191.876051 -301.294989) (xy 191.900048 -301.294546) (xy 191.914231 -301.294731)
			(xy 191.942471 -301.297397) (xy 191.956436 -301.29988) (xy 191.968882 -301.302166) (xy 191.992504 -301.2948)
			(xy 192.069974 -301.21733) (xy 192.07734 -301.193708) (xy 192.075054 -301.181262) (xy 192.072577 -301.167296)
			(xy 192.069905 -301.139057) (xy 192.06972 -301.124874) (xy 192.070206 -301.100056) (xy 192.07824 -301.051075)
			(xy 192.094092 -301.004039) (xy 192.117345 -300.960187) (xy 192.147385 -300.920674) (xy 192.183422 -300.886542)
			(xy 192.224507 -300.858689) (xy 192.269556 -300.837849) (xy 192.317382 -300.824572) (xy 192.366727 -300.819207)
			(xy 192.41629 -300.821895) (xy 192.464765 -300.832566) (xy 192.510875 -300.850939) (xy 192.553406 -300.876529)
			(xy 192.591236 -300.908663) (xy 192.62337 -300.946493) (xy 192.64896 -300.989023) (xy 192.667333 -301.035133)
			(xy 192.678004 -301.083608) (xy 192.680243 -301.124874) (xy 193.019184 -301.124874) (xy 193.023144 -301.07582)
			(xy 193.034921 -301.028036) (xy 193.054212 -300.98276) (xy 193.080515 -300.941164) (xy 193.11315 -300.904327)
			(xy 193.151271 -300.873202) (xy 193.193892 -300.848595) (xy 193.239908 -300.831143) (xy 193.288127 -300.821299)
			(xy 193.337302 -300.819318) (xy 193.386157 -300.82525) (xy 193.433428 -300.838942) (xy 193.47789 -300.86004)
			(xy 193.518393 -300.887996) (xy 193.553886 -300.922088) (xy 193.583451 -300.961432) (xy 193.606322 -301.005009)
			(xy 193.621906 -301.05169) (xy 193.629801 -301.100267) (xy 193.630296 -301.124874) (xy 193.969144 -301.124874)
			(xy 193.973104 -301.07582) (xy 193.984881 -301.028036) (xy 194.004172 -300.98276) (xy 194.030475 -300.941164)
			(xy 194.06311 -300.904327) (xy 194.101231 -300.873202) (xy 194.143852 -300.848595) (xy 194.189868 -300.831143)
			(xy 194.238087 -300.821299) (xy 194.287262 -300.819318) (xy 194.336117 -300.82525) (xy 194.383388 -300.838942)
			(xy 194.42785 -300.86004) (xy 194.468353 -300.887996) (xy 194.503846 -300.922088) (xy 194.533411 -300.961432)
			(xy 194.556282 -301.005009) (xy 194.571866 -301.05169) (xy 194.579761 -301.100267) (xy 194.580256 -301.124874)
			(xy 194.919104 -301.124874) (xy 194.923064 -301.07582) (xy 194.934841 -301.028036) (xy 194.954132 -300.98276)
			(xy 194.980435 -300.941164) (xy 195.01307 -300.904327) (xy 195.051191 -300.873202) (xy 195.093812 -300.848595)
			(xy 195.139828 -300.831143) (xy 195.188047 -300.821299) (xy 195.237222 -300.819318) (xy 195.286077 -300.82525)
			(xy 195.333348 -300.838942) (xy 195.37781 -300.86004) (xy 195.418313 -300.887996) (xy 195.453806 -300.922088)
			(xy 195.483371 -300.961432) (xy 195.506242 -301.005009) (xy 195.521826 -301.05169) (xy 195.529721 -301.100267)
			(xy 195.530216 -301.124874) (xy 195.869064 -301.124874) (xy 195.873024 -301.07582) (xy 195.884801 -301.028036)
			(xy 195.904092 -300.98276) (xy 195.930395 -300.941164) (xy 195.96303 -300.904327) (xy 196.001151 -300.873202)
			(xy 196.043772 -300.848595) (xy 196.089788 -300.831143) (xy 196.138007 -300.821299) (xy 196.187182 -300.819318)
			(xy 196.236037 -300.82525) (xy 196.283308 -300.838942) (xy 196.32777 -300.86004) (xy 196.368273 -300.887996)
			(xy 196.403766 -300.922088) (xy 196.433331 -300.961432) (xy 196.456202 -301.005009) (xy 196.471786 -301.05169)
			(xy 196.479681 -301.100267) (xy 196.480176 -301.124874) (xy 196.819278 -301.124874) (xy 196.823238 -301.07582)
			(xy 196.835015 -301.028036) (xy 196.854306 -300.98276) (xy 196.880609 -300.941164) (xy 196.913244 -300.904327)
			(xy 196.951365 -300.873202) (xy 196.993986 -300.848595) (xy 197.040002 -300.831143) (xy 197.088221 -300.821299)
			(xy 197.137396 -300.819318) (xy 197.186251 -300.82525) (xy 197.233522 -300.838942) (xy 197.277984 -300.86004)
			(xy 197.318487 -300.887996) (xy 197.35398 -300.922088) (xy 197.383545 -300.961432) (xy 197.406416 -301.005009)
			(xy 197.422 -301.05169) (xy 197.429895 -301.100267) (xy 197.43039 -301.124874) (xy 197.769238 -301.124874)
			(xy 197.773198 -301.07582) (xy 197.784975 -301.028036) (xy 197.804266 -300.98276) (xy 197.830569 -300.941164)
			(xy 197.863204 -300.904327) (xy 197.901325 -300.873202) (xy 197.943946 -300.848595) (xy 197.989962 -300.831143)
			(xy 198.038181 -300.821299) (xy 198.087356 -300.819318) (xy 198.136211 -300.82525) (xy 198.183482 -300.838942)
			(xy 198.227944 -300.86004) (xy 198.268447 -300.887996) (xy 198.30394 -300.922088) (xy 198.333505 -300.961432)
			(xy 198.356376 -301.005009) (xy 198.37196 -301.05169) (xy 198.379855 -301.100267) (xy 198.38035 -301.124874)
			(xy 198.719198 -301.124874) (xy 198.723158 -301.07582) (xy 198.734935 -301.028036) (xy 198.754226 -300.98276)
			(xy 198.780529 -300.941164) (xy 198.813164 -300.904327) (xy 198.851285 -300.873202) (xy 198.893906 -300.848595)
			(xy 198.939922 -300.831143) (xy 198.988141 -300.821299) (xy 199.037316 -300.819318) (xy 199.086171 -300.82525)
			(xy 199.133442 -300.838942) (xy 199.177904 -300.86004) (xy 199.218407 -300.887996) (xy 199.2539 -300.922088)
			(xy 199.283465 -300.961432) (xy 199.306336 -301.005009) (xy 199.32192 -301.05169) (xy 199.329815 -301.100267)
			(xy 199.33031 -301.124874) (xy 199.329815 -301.149481) (xy 199.32192 -301.198058) (xy 199.306336 -301.244739)
			(xy 199.297259 -301.262034) (xy 201.475846 -301.262034) (xy 201.479917 -301.206412) (xy 201.492043 -301.151975)
			(xy 201.511966 -301.099884) (xy 201.539262 -301.051249) (xy 201.573348 -301.007106) (xy 201.613497 -300.968397)
			(xy 201.658855 -300.935946) (xy 201.708455 -300.910445) (xy 201.761239 -300.892438) (xy 201.816082 -300.882308)
			(xy 201.871816 -300.880271) (xy 201.927253 -300.886371) (xy 201.98121 -300.900477) (xy 202.032539 -300.922289)
			(xy 202.080145 -300.951343) (xy 202.123013 -300.987018) (xy 202.16023 -301.028555) (xy 202.169172 -301.04207)
			(xy 206.417162 -301.04207) (xy 206.421233 -300.986448) (xy 206.433359 -300.932011) (xy 206.453282 -300.87992)
			(xy 206.480578 -300.831285) (xy 206.514664 -300.787142) (xy 206.554813 -300.748433) (xy 206.600171 -300.715982)
			(xy 206.649771 -300.690481) (xy 206.702555 -300.672474) (xy 206.757398 -300.662344) (xy 206.813132 -300.660307)
			(xy 206.868569 -300.666407) (xy 206.922526 -300.680513) (xy 206.973855 -300.702325) (xy 207.021461 -300.731379)
			(xy 207.064329 -300.767054) (xy 207.101546 -300.808591) (xy 207.132319 -300.855104) (xy 207.155991 -300.905601)
			(xy 207.172059 -300.959008) (xy 207.180179 -301.014184) (xy 207.180688 -301.04207) (xy 207.180535 -301.050452)
			(xy 208.791046 -301.050452) (xy 208.795117 -300.99483) (xy 208.807243 -300.940393) (xy 208.827166 -300.888302)
			(xy 208.854462 -300.839667) (xy 208.888548 -300.795524) (xy 208.928697 -300.756815) (xy 208.974055 -300.724364)
			(xy 209.023655 -300.698863) (xy 209.076439 -300.680856) (xy 209.131282 -300.670726) (xy 209.187016 -300.668689)
			(xy 209.242453 -300.674789) (xy 209.29641 -300.688895) (xy 209.347739 -300.710707) (xy 209.395345 -300.739761)
			(xy 209.438213 -300.775436) (xy 209.47543 -300.816973) (xy 209.506203 -300.863486) (xy 209.529875 -300.913983)
			(xy 209.545943 -300.96739) (xy 209.554063 -301.022566) (xy 209.554572 -301.050452) (xy 209.554063 -301.078338)
			(xy 209.545943 -301.133514) (xy 209.529875 -301.186921) (xy 209.506203 -301.237418) (xy 209.47543 -301.283931)
			(xy 209.438213 -301.325468) (xy 209.395345 -301.361143) (xy 209.347739 -301.390197) (xy 209.29641 -301.412009)
			(xy 209.242453 -301.426115) (xy 209.187016 -301.432215) (xy 209.131282 -301.430178) (xy 209.076439 -301.420048)
			(xy 209.023655 -301.402041) (xy 208.974055 -301.37654) (xy 208.928697 -301.344089) (xy 208.888548 -301.30538)
			(xy 208.854462 -301.261237) (xy 208.827166 -301.212602) (xy 208.807243 -301.160511) (xy 208.795117 -301.106074)
			(xy 208.791046 -301.050452) (xy 207.180535 -301.050452) (xy 207.180179 -301.069956) (xy 207.172059 -301.125132)
			(xy 207.155991 -301.178539) (xy 207.132319 -301.229036) (xy 207.101546 -301.275549) (xy 207.064329 -301.317086)
			(xy 207.021461 -301.352761) (xy 206.973855 -301.381815) (xy 206.922526 -301.403627) (xy 206.868569 -301.417733)
			(xy 206.813132 -301.423833) (xy 206.757398 -301.421796) (xy 206.702555 -301.411666) (xy 206.649771 -301.393659)
			(xy 206.600171 -301.368158) (xy 206.554813 -301.335707) (xy 206.514664 -301.296998) (xy 206.480578 -301.252855)
			(xy 206.453282 -301.20422) (xy 206.433359 -301.152129) (xy 206.421233 -301.097692) (xy 206.417162 -301.04207)
			(xy 202.169172 -301.04207) (xy 202.191003 -301.075068) (xy 202.214675 -301.125565) (xy 202.230743 -301.178972)
			(xy 202.238863 -301.234148) (xy 202.239372 -301.262034) (xy 202.238863 -301.28992) (xy 202.230743 -301.345096)
			(xy 202.214675 -301.398503) (xy 202.191003 -301.449) (xy 202.16023 -301.495513) (xy 202.123013 -301.53705)
			(xy 202.080145 -301.572725) (xy 202.032539 -301.601779) (xy 201.98121 -301.623591) (xy 201.927253 -301.637697)
			(xy 201.871816 -301.643797) (xy 201.816082 -301.64176) (xy 201.761239 -301.63163) (xy 201.708455 -301.613623)
			(xy 201.658855 -301.588122) (xy 201.613497 -301.555671) (xy 201.573348 -301.516962) (xy 201.539262 -301.472819)
			(xy 201.511966 -301.424184) (xy 201.492043 -301.372093) (xy 201.479917 -301.317656) (xy 201.475846 -301.262034)
			(xy 199.297259 -301.262034) (xy 199.283465 -301.288316) (xy 199.2539 -301.32766) (xy 199.218407 -301.361752)
			(xy 199.177904 -301.389708) (xy 199.133442 -301.410806) (xy 199.086171 -301.424498) (xy 199.037316 -301.43043)
			(xy 198.988141 -301.428449) (xy 198.939922 -301.418605) (xy 198.893906 -301.401153) (xy 198.851285 -301.376546)
			(xy 198.813164 -301.345421) (xy 198.780529 -301.308584) (xy 198.754226 -301.266988) (xy 198.734935 -301.221712)
			(xy 198.723158 -301.173928) (xy 198.719198 -301.124874) (xy 198.38035 -301.124874) (xy 198.379855 -301.149481)
			(xy 198.37196 -301.198058) (xy 198.356376 -301.244739) (xy 198.333505 -301.288316) (xy 198.30394 -301.32766)
			(xy 198.268447 -301.361752) (xy 198.227944 -301.389708) (xy 198.183482 -301.410806) (xy 198.136211 -301.424498)
			(xy 198.087356 -301.43043) (xy 198.038181 -301.428449) (xy 197.989962 -301.418605) (xy 197.943946 -301.401153)
			(xy 197.901325 -301.376546) (xy 197.863204 -301.345421) (xy 197.830569 -301.308584) (xy 197.804266 -301.266988)
			(xy 197.784975 -301.221712) (xy 197.773198 -301.173928) (xy 197.769238 -301.124874) (xy 197.43039 -301.124874)
			(xy 197.429895 -301.149481) (xy 197.422 -301.198058) (xy 197.406416 -301.244739) (xy 197.383545 -301.288316)
			(xy 197.35398 -301.32766) (xy 197.318487 -301.361752) (xy 197.277984 -301.389708) (xy 197.233522 -301.410806)
			(xy 197.186251 -301.424498) (xy 197.137396 -301.43043) (xy 197.088221 -301.428449) (xy 197.040002 -301.418605)
			(xy 196.993986 -301.401153) (xy 196.951365 -301.376546) (xy 196.913244 -301.345421) (xy 196.880609 -301.308584)
			(xy 196.854306 -301.266988) (xy 196.835015 -301.221712) (xy 196.823238 -301.173928) (xy 196.819278 -301.124874)
			(xy 196.480176 -301.124874) (xy 196.479681 -301.149481) (xy 196.471786 -301.198058) (xy 196.456202 -301.244739)
			(xy 196.433331 -301.288316) (xy 196.403766 -301.32766) (xy 196.368273 -301.361752) (xy 196.32777 -301.389708)
			(xy 196.283308 -301.410806) (xy 196.236037 -301.424498) (xy 196.187182 -301.43043) (xy 196.138007 -301.428449)
			(xy 196.089788 -301.418605) (xy 196.043772 -301.401153) (xy 196.001151 -301.376546) (xy 195.96303 -301.345421)
			(xy 195.930395 -301.308584) (xy 195.904092 -301.266988) (xy 195.884801 -301.221712) (xy 195.873024 -301.173928)
			(xy 195.869064 -301.124874) (xy 195.530216 -301.124874) (xy 195.529721 -301.149481) (xy 195.521826 -301.198058)
			(xy 195.506242 -301.244739) (xy 195.483371 -301.288316) (xy 195.453806 -301.32766) (xy 195.418313 -301.361752)
			(xy 195.37781 -301.389708) (xy 195.333348 -301.410806) (xy 195.286077 -301.424498) (xy 195.237222 -301.43043)
			(xy 195.188047 -301.428449) (xy 195.139828 -301.418605) (xy 195.093812 -301.401153) (xy 195.051191 -301.376546)
			(xy 195.01307 -301.345421) (xy 194.980435 -301.308584) (xy 194.954132 -301.266988) (xy 194.934841 -301.221712)
			(xy 194.923064 -301.173928) (xy 194.919104 -301.124874) (xy 194.580256 -301.124874) (xy 194.579761 -301.149481)
			(xy 194.571866 -301.198058) (xy 194.556282 -301.244739) (xy 194.533411 -301.288316) (xy 194.503846 -301.32766)
			(xy 194.468353 -301.361752) (xy 194.42785 -301.389708) (xy 194.383388 -301.410806) (xy 194.336117 -301.424498)
			(xy 194.287262 -301.43043) (xy 194.238087 -301.428449) (xy 194.189868 -301.418605) (xy 194.143852 -301.401153)
			(xy 194.101231 -301.376546) (xy 194.06311 -301.345421) (xy 194.030475 -301.308584) (xy 194.004172 -301.266988)
			(xy 193.984881 -301.221712) (xy 193.973104 -301.173928) (xy 193.969144 -301.124874) (xy 193.630296 -301.124874)
			(xy 193.629801 -301.149481) (xy 193.621906 -301.198058) (xy 193.606322 -301.244739) (xy 193.583451 -301.288316)
			(xy 193.553886 -301.32766) (xy 193.518393 -301.361752) (xy 193.47789 -301.389708) (xy 193.433428 -301.410806)
			(xy 193.386157 -301.424498) (xy 193.337302 -301.43043) (xy 193.288127 -301.428449) (xy 193.239908 -301.418605)
			(xy 193.193892 -301.401153) (xy 193.151271 -301.376546) (xy 193.11315 -301.345421) (xy 193.080515 -301.308584)
			(xy 193.054212 -301.266988) (xy 193.034921 -301.221712) (xy 193.023144 -301.173928) (xy 193.019184 -301.124874)
			(xy 192.680243 -301.124874) (xy 192.680693 -301.133171) (xy 192.675328 -301.182516) (xy 192.662052 -301.230343)
			(xy 192.641212 -301.275392) (xy 192.61336 -301.316476) (xy 192.579227 -301.352513) (xy 192.539715 -301.382554)
			(xy 192.495863 -301.405807) (xy 192.448827 -301.42166) (xy 192.399846 -301.429694) (xy 192.375028 -301.430182)
			(xy 192.360845 -301.430002) (xy 192.332605 -301.427332) (xy 192.31864 -301.424848) (xy 192.306194 -301.422562)
			(xy 192.282572 -301.429928) (xy 192.205102 -301.507398) (xy 192.197736 -301.53102) (xy 192.200022 -301.543466)
			(xy 192.202504 -301.557431) (xy 192.205172 -301.585671) (xy 192.205356 -301.599854) (xy 192.204795 -301.623842)
			(xy 192.197297 -301.671227) (xy 192.182479 -301.716856) (xy 192.160706 -301.759606) (xy 192.132512 -301.798423)
			(xy 192.098594 -301.832351) (xy 192.059786 -301.860556) (xy 192.017043 -301.882343) (xy 191.971419 -301.897175)
			(xy 191.924035 -301.904688) (xy 191.900048 -301.905162) (xy 191.885865 -301.904979) (xy 191.857625 -301.902311)
			(xy 191.84366 -301.899828) (xy 191.831214 -301.897542) (xy 191.807592 -301.904908) (xy 191.730122 -301.982378)
			(xy 191.722756 -302.006) (xy 191.725042 -302.018446) (xy 191.72752 -302.032412) (xy 191.730191 -302.060651)
			(xy 191.730376 -302.074834) (xy 191.729886 -302.099651) (xy 191.721851 -302.14863) (xy 191.705998 -302.195664)
			(xy 191.682745 -302.239514) (xy 191.652705 -302.279025) (xy 191.616668 -302.313156) (xy 191.575585 -302.341007)
			(xy 191.530537 -302.361845) (xy 191.482712 -302.375121) (xy 191.433368 -302.380485) (xy 191.383807 -302.377796)
			(xy 191.335334 -302.367125) (xy 191.289226 -302.348753) (xy 191.246697 -302.323163) (xy 191.208868 -302.29103)
			(xy 191.176736 -302.253201) (xy 191.151147 -302.210672) (xy 191.132774 -302.164564) (xy 191.122103 -302.116091)
			(xy 191.119415 -302.06653) (xy 189.83004 -302.06653) (xy 189.830202 -302.074834) (xy 189.83003 -302.089017)
			(xy 189.827355 -302.117257) (xy 189.824868 -302.131222) (xy 189.822699 -302.145186) (xy 189.825283 -302.173317)
			(xy 189.835476 -302.199663) (xy 189.852496 -302.222208) (xy 189.875043 -302.239227) (xy 189.90139 -302.249418)
			(xy 189.92952 -302.252001) (xy 189.943486 -302.24984) (xy 189.957453 -302.24737) (xy 189.985692 -302.244694)
			(xy 189.999874 -302.244506) (xy 190.024697 -302.24495) (xy 190.07369 -302.252978) (xy 190.120739 -302.268826)
			(xy 190.164604 -302.292077) (xy 190.20413 -302.322119) (xy 190.238274 -302.358159) (xy 190.266138 -302.399249)
			(xy 190.286988 -302.444305) (xy 190.300273 -302.492141) (xy 190.305644 -302.541495) (xy 190.305194 -302.549814)
			(xy 192.544204 -302.549814) (xy 192.548164 -302.50076) (xy 192.559941 -302.452976) (xy 192.579232 -302.4077)
			(xy 192.605535 -302.366104) (xy 192.63817 -302.329267) (xy 192.676291 -302.298142) (xy 192.718912 -302.273535)
			(xy 192.764928 -302.256083) (xy 192.813147 -302.246239) (xy 192.862322 -302.244258) (xy 192.911177 -302.25019)
			(xy 192.958448 -302.263882) (xy 193.00291 -302.28498) (xy 193.043413 -302.312936) (xy 193.078906 -302.347028)
			(xy 193.108471 -302.386372) (xy 193.131342 -302.429949) (xy 193.146926 -302.47663) (xy 193.154821 -302.525207)
			(xy 193.155149 -302.541536) (xy 193.494295 -302.541536) (xy 193.499659 -302.492188) (xy 193.512935 -302.444359)
			(xy 193.533774 -302.399308) (xy 193.561628 -302.358221) (xy 193.595761 -302.322181) (xy 193.635274 -302.292138)
			(xy 193.679128 -302.268884) (xy 193.726166 -302.25303) (xy 193.775149 -302.244994) (xy 193.799968 -302.244506)
			(xy 193.814151 -302.244687) (xy 193.842391 -302.247356) (xy 193.856356 -302.24984) (xy 193.870331 -302.251931)
			(xy 193.898454 -302.249363) (xy 193.924796 -302.239185) (xy 193.94734 -302.222177) (xy 193.964359 -302.199642)
			(xy 193.974551 -302.173305) (xy 193.977134 -302.145183) (xy 193.974974 -302.131222) (xy 193.972491 -302.117257)
			(xy 193.969823 -302.089017) (xy 193.96964 -302.074834) (xy 193.970041 -302.050011) (xy 193.978068 -302.001017)
			(xy 193.993915 -301.953967) (xy 194.017164 -301.910101) (xy 194.047205 -301.870574) (xy 194.083244 -301.836428)
			(xy 194.124333 -301.808562) (xy 194.169388 -301.78771) (xy 194.217224 -301.774422) (xy 194.266579 -301.769048)
			(xy 194.316153 -301.77173) (xy 194.36464 -301.782396) (xy 194.410763 -301.800766) (xy 194.453307 -301.826356)
			(xy 194.49115 -301.858492) (xy 194.523296 -301.896326) (xy 194.548897 -301.938863) (xy 194.56728 -301.984981)
			(xy 194.577959 -302.033466) (xy 194.580208 -302.074834) (xy 195.869064 -302.074834) (xy 195.873024 -302.02578)
			(xy 195.884801 -301.977996) (xy 195.904092 -301.93272) (xy 195.930395 -301.891124) (xy 195.96303 -301.854287)
			(xy 196.001151 -301.823162) (xy 196.043772 -301.798555) (xy 196.089788 -301.781103) (xy 196.138007 -301.771259)
			(xy 196.187182 -301.769278) (xy 196.236037 -301.77521) (xy 196.283308 -301.788902) (xy 196.32777 -301.81)
			(xy 196.368273 -301.837956) (xy 196.403766 -301.872048) (xy 196.433331 -301.911392) (xy 196.456202 -301.954969)
			(xy 196.471786 -302.00165) (xy 196.479681 -302.050227) (xy 196.480176 -302.074834) (xy 197.769238 -302.074834)
			(xy 197.773198 -302.02578) (xy 197.784975 -301.977996) (xy 197.804266 -301.93272) (xy 197.830569 -301.891124)
			(xy 197.863204 -301.854287) (xy 197.901325 -301.823162) (xy 197.943946 -301.798555) (xy 197.989962 -301.781103)
			(xy 198.038181 -301.771259) (xy 198.087356 -301.769278) (xy 198.136211 -301.77521) (xy 198.183482 -301.788902)
			(xy 198.227944 -301.81) (xy 198.268447 -301.837956) (xy 198.30394 -301.872048) (xy 198.333505 -301.911392)
			(xy 198.356376 -301.954969) (xy 198.37196 -302.00165) (xy 198.379855 -302.050227) (xy 198.38035 -302.074834)
			(xy 198.719198 -302.074834) (xy 198.723158 -302.02578) (xy 198.734935 -301.977996) (xy 198.754226 -301.93272)
			(xy 198.780529 -301.891124) (xy 198.813164 -301.854287) (xy 198.851285 -301.823162) (xy 198.893906 -301.798555)
			(xy 198.939922 -301.781103) (xy 198.988141 -301.771259) (xy 199.037316 -301.769278) (xy 199.086171 -301.77521)
			(xy 199.133442 -301.788902) (xy 199.177904 -301.81) (xy 199.218407 -301.837956) (xy 199.22015 -301.83963)
			(xy 202.44765 -301.83963) (xy 202.451721 -301.784008) (xy 202.463847 -301.729571) (xy 202.48377 -301.67748)
			(xy 202.511066 -301.628845) (xy 202.545152 -301.584702) (xy 202.585301 -301.545993) (xy 202.630659 -301.513542)
			(xy 202.680259 -301.488041) (xy 202.733043 -301.470034) (xy 202.787886 -301.459904) (xy 202.84362 -301.457867)
			(xy 202.899057 -301.463967) (xy 202.953014 -301.478073) (xy 203.004343 -301.499885) (xy 203.051949 -301.528939)
			(xy 203.080393 -301.55261) (xy 204.219808 -301.55261) (xy 204.223879 -301.496988) (xy 204.236005 -301.442551)
			(xy 204.255928 -301.39046) (xy 204.283224 -301.341825) (xy 204.31731 -301.297682) (xy 204.357459 -301.258973)
			(xy 204.402817 -301.226522) (xy 204.452417 -301.201021) (xy 204.505201 -301.183014) (xy 204.560044 -301.172884)
			(xy 204.615778 -301.170847) (xy 204.671215 -301.176947) (xy 204.725172 -301.191053) (xy 204.776501 -301.212865)
			(xy 204.824107 -301.241919) (xy 204.866975 -301.277594) (xy 204.904192 -301.319131) (xy 204.934965 -301.365644)
			(xy 204.958637 -301.416141) (xy 204.974705 -301.469548) (xy 204.982825 -301.524724) (xy 204.983334 -301.55261)
			(xy 204.983162 -301.562008) (xy 205.203804 -301.562008) (xy 205.207875 -301.506386) (xy 205.220001 -301.451949)
			(xy 205.239924 -301.399858) (xy 205.26722 -301.351223) (xy 205.301306 -301.30708) (xy 205.341455 -301.268371)
			(xy 205.386813 -301.23592) (xy 205.436413 -301.210419) (xy 205.489197 -301.192412) (xy 205.54404 -301.182282)
			(xy 205.599774 -301.180245) (xy 205.655211 -301.186345) (xy 205.709168 -301.200451) (xy 205.760497 -301.222263)
			(xy 205.808103 -301.251317) (xy 205.850971 -301.286992) (xy 205.888188 -301.328529) (xy 205.918961 -301.375042)
			(xy 205.942633 -301.425539) (xy 205.958701 -301.478946) (xy 205.966821 -301.534122) (xy 205.96733 -301.562008)
			(xy 205.967061 -301.57674) (xy 207.613248 -301.57674) (xy 207.617319 -301.521118) (xy 207.629445 -301.466681)
			(xy 207.649368 -301.41459) (xy 207.676664 -301.365955) (xy 207.71075 -301.321812) (xy 207.750899 -301.283103)
			(xy 207.796257 -301.250652) (xy 207.845857 -301.225151) (xy 207.898641 -301.207144) (xy 207.953484 -301.197014)
			(xy 208.009218 -301.194977) (xy 208.064655 -301.201077) (xy 208.118612 -301.215183) (xy 208.169941 -301.236995)
			(xy 208.217547 -301.266049) (xy 208.260415 -301.301724) (xy 208.297632 -301.343261) (xy 208.328405 -301.389774)
			(xy 208.352077 -301.440271) (xy 208.368145 -301.493678) (xy 208.376265 -301.548854) (xy 208.376774 -301.57674)
			(xy 208.376265 -301.604626) (xy 208.368145 -301.659802) (xy 208.352077 -301.713209) (xy 208.328405 -301.763706)
			(xy 208.297632 -301.810219) (xy 208.260415 -301.851756) (xy 208.217547 -301.887431) (xy 208.169941 -301.916485)
			(xy 208.118612 -301.938297) (xy 208.064655 -301.952403) (xy 208.009218 -301.958503) (xy 207.953484 -301.956466)
			(xy 207.898641 -301.946336) (xy 207.845857 -301.928329) (xy 207.796257 -301.902828) (xy 207.750899 -301.870377)
			(xy 207.71075 -301.831668) (xy 207.676664 -301.787525) (xy 207.649368 -301.73889) (xy 207.629445 -301.686799)
			(xy 207.617319 -301.632362) (xy 207.613248 -301.57674) (xy 205.967061 -301.57674) (xy 205.966821 -301.589894)
			(xy 205.958701 -301.64507) (xy 205.942633 -301.698477) (xy 205.918961 -301.748974) (xy 205.888188 -301.795487)
			(xy 205.850971 -301.837024) (xy 205.808103 -301.872699) (xy 205.760497 -301.901753) (xy 205.709168 -301.923565)
			(xy 205.655211 -301.937671) (xy 205.599774 -301.943771) (xy 205.54404 -301.941734) (xy 205.489197 -301.931604)
			(xy 205.436413 -301.913597) (xy 205.386813 -301.888096) (xy 205.341455 -301.855645) (xy 205.301306 -301.816936)
			(xy 205.26722 -301.772793) (xy 205.239924 -301.724158) (xy 205.220001 -301.672067) (xy 205.207875 -301.61763)
			(xy 205.203804 -301.562008) (xy 204.983162 -301.562008) (xy 204.982825 -301.580496) (xy 204.974705 -301.635672)
			(xy 204.958637 -301.689079) (xy 204.934965 -301.739576) (xy 204.904192 -301.786089) (xy 204.866975 -301.827626)
			(xy 204.824107 -301.863301) (xy 204.776501 -301.892355) (xy 204.725172 -301.914167) (xy 204.671215 -301.928273)
			(xy 204.615778 -301.934373) (xy 204.560044 -301.932336) (xy 204.505201 -301.922206) (xy 204.452417 -301.904199)
			(xy 204.402817 -301.878698) (xy 204.357459 -301.846247) (xy 204.31731 -301.807538) (xy 204.283224 -301.763395)
			(xy 204.255928 -301.71476) (xy 204.236005 -301.662669) (xy 204.223879 -301.608232) (xy 204.219808 -301.55261)
			(xy 203.080393 -301.55261) (xy 203.094817 -301.564614) (xy 203.132034 -301.606151) (xy 203.162807 -301.652664)
			(xy 203.186479 -301.703161) (xy 203.202547 -301.756568) (xy 203.210667 -301.811744) (xy 203.211176 -301.83963)
			(xy 203.210667 -301.867516) (xy 203.202547 -301.922692) (xy 203.186479 -301.976099) (xy 203.162807 -302.026596)
			(xy 203.132034 -302.073109) (xy 203.094817 -302.114646) (xy 203.051949 -302.150321) (xy 203.004343 -302.179375)
			(xy 202.953014 -302.201187) (xy 202.899057 -302.215293) (xy 202.84362 -302.221393) (xy 202.787886 -302.219356)
			(xy 202.733043 -302.209226) (xy 202.680259 -302.191219) (xy 202.630659 -302.165718) (xy 202.585301 -302.133267)
			(xy 202.545152 -302.094558) (xy 202.511066 -302.050415) (xy 202.48377 -302.00178) (xy 202.463847 -301.949689)
			(xy 202.451721 -301.895252) (xy 202.44765 -301.83963) (xy 199.22015 -301.83963) (xy 199.2539 -301.872048)
			(xy 199.283465 -301.911392) (xy 199.306336 -301.954969) (xy 199.32192 -302.00165) (xy 199.329815 -302.050227)
			(xy 199.33031 -302.074834) (xy 199.329815 -302.099441) (xy 199.32192 -302.148018) (xy 199.306336 -302.194699)
			(xy 199.283465 -302.238276) (xy 199.2539 -302.27762) (xy 199.218407 -302.311712) (xy 199.177904 -302.339668)
			(xy 199.133442 -302.360766) (xy 199.086171 -302.374458) (xy 199.037316 -302.38039) (xy 198.988141 -302.378409)
			(xy 198.939922 -302.368565) (xy 198.893906 -302.351113) (xy 198.851285 -302.326506) (xy 198.813164 -302.295381)
			(xy 198.780529 -302.258544) (xy 198.754226 -302.216948) (xy 198.734935 -302.171672) (xy 198.723158 -302.123888)
			(xy 198.719198 -302.074834) (xy 198.38035 -302.074834) (xy 198.379855 -302.099441) (xy 198.37196 -302.148018)
			(xy 198.356376 -302.194699) (xy 198.333505 -302.238276) (xy 198.30394 -302.27762) (xy 198.268447 -302.311712)
			(xy 198.227944 -302.339668) (xy 198.183482 -302.360766) (xy 198.136211 -302.374458) (xy 198.087356 -302.38039)
			(xy 198.038181 -302.378409) (xy 197.989962 -302.368565) (xy 197.943946 -302.351113) (xy 197.901325 -302.326506)
			(xy 197.863204 -302.295381) (xy 197.830569 -302.258544) (xy 197.804266 -302.216948) (xy 197.784975 -302.171672)
			(xy 197.773198 -302.123888) (xy 197.769238 -302.074834) (xy 196.480176 -302.074834) (xy 196.479681 -302.099441)
			(xy 196.471786 -302.148018) (xy 196.456202 -302.194699) (xy 196.433331 -302.238276) (xy 196.403766 -302.27762)
			(xy 196.368273 -302.311712) (xy 196.32777 -302.339668) (xy 196.283308 -302.360766) (xy 196.236037 -302.374458)
			(xy 196.187182 -302.38039) (xy 196.138007 -302.378409) (xy 196.089788 -302.368565) (xy 196.043772 -302.351113)
			(xy 196.001151 -302.326506) (xy 195.96303 -302.295381) (xy 195.930395 -302.258544) (xy 195.904092 -302.216948)
			(xy 195.884801 -302.171672) (xy 195.873024 -302.123888) (xy 195.869064 -302.074834) (xy 194.580208 -302.074834)
			(xy 194.580654 -302.083039) (xy 194.575293 -302.132396) (xy 194.562018 -302.180235) (xy 194.541179 -302.225296)
			(xy 194.513324 -302.266392) (xy 194.479187 -302.30244) (xy 194.439668 -302.332491) (xy 194.395808 -302.355753)
			(xy 194.348763 -302.371613) (xy 194.299771 -302.379652) (xy 194.274948 -302.380142) (xy 194.260765 -302.379958)
			(xy 194.232525 -302.377291) (xy 194.21856 -302.374808) (xy 194.204603 -302.372573) (xy 194.176462 -302.375162)
			(xy 194.150108 -302.385363) (xy 194.127558 -302.402395) (xy 194.110537 -302.424954) (xy 194.10035 -302.451314)
			(xy 194.097776 -302.479456) (xy 194.099942 -302.493426) (xy 194.102418 -302.507392) (xy 194.10509 -302.535632)
			(xy 194.105276 -302.549814) (xy 194.104807 -302.574633) (xy 194.096775 -302.623617) (xy 194.080923 -302.670655)
			(xy 194.060431 -302.709305) (xy 200.909418 -302.709305) (xy 200.909418 -302.656007) (xy 200.917361 -302.603303)
			(xy 200.933071 -302.552373) (xy 200.956197 -302.504352) (xy 200.986221 -302.460315) (xy 201.022473 -302.421244)
			(xy 201.064144 -302.388013) (xy 201.110302 -302.361364) (xy 201.159916 -302.341892) (xy 201.211878 -302.330032)
			(xy 201.265028 -302.326049) (xy 201.318178 -302.330032) (xy 201.37014 -302.341892) (xy 201.419754 -302.361364)
			(xy 201.465912 -302.388013) (xy 201.507583 -302.421244) (xy 201.543835 -302.460315) (xy 201.573859 -302.504352)
			(xy 201.596985 -302.552373) (xy 201.612695 -302.603303) (xy 201.620638 -302.656007) (xy 201.621136 -302.682656)
			(xy 201.620638 -302.709305) (xy 201.612695 -302.762009) (xy 201.596985 -302.812939) (xy 201.573859 -302.86096)
			(xy 201.543835 -302.904997) (xy 201.507583 -302.944068) (xy 201.465912 -302.977299) (xy 201.419754 -303.003948)
			(xy 201.37014 -303.02342) (xy 201.318178 -303.03528) (xy 201.265028 -303.039264) (xy 201.211878 -303.03528)
			(xy 201.159916 -303.02342) (xy 201.110302 -303.003948) (xy 201.064144 -302.977299) (xy 201.022473 -302.944068)
			(xy 200.986221 -302.904997) (xy 200.956197 -302.86096) (xy 200.933071 -302.812939) (xy 200.917361 -302.762009)
			(xy 200.909418 -302.709305) (xy 194.060431 -302.709305) (xy 194.057671 -302.71451) (xy 194.027631 -302.754026)
			(xy 193.991593 -302.788161) (xy 193.950508 -302.816017) (xy 193.905458 -302.836859) (xy 193.857629 -302.850138)
			(xy 193.808282 -302.855505) (xy 193.758717 -302.852818) (xy 193.71024 -302.842148) (xy 193.664127 -302.823776)
			(xy 193.621594 -302.798185) (xy 193.583761 -302.766052) (xy 193.551625 -302.728221) (xy 193.526032 -302.685689)
			(xy 193.507658 -302.639577) (xy 193.496985 -302.591101) (xy 193.494295 -302.541536) (xy 193.155149 -302.541536)
			(xy 193.155316 -302.549814) (xy 193.154821 -302.574421) (xy 193.146926 -302.622998) (xy 193.131342 -302.669679)
			(xy 193.108471 -302.713256) (xy 193.078906 -302.7526) (xy 193.043413 -302.786692) (xy 193.00291 -302.814648)
			(xy 192.958448 -302.835746) (xy 192.911177 -302.849438) (xy 192.862322 -302.85537) (xy 192.813147 -302.853389)
			(xy 192.764928 -302.843545) (xy 192.718912 -302.826093) (xy 192.676291 -302.801486) (xy 192.63817 -302.770361)
			(xy 192.605535 -302.733524) (xy 192.579232 -302.691928) (xy 192.559941 -302.646652) (xy 192.548164 -302.598868)
			(xy 192.544204 -302.549814) (xy 190.305194 -302.549814) (xy 190.30296 -302.591069) (xy 190.292291 -302.639556)
			(xy 190.273918 -302.685677) (xy 190.248326 -302.728219) (xy 190.216188 -302.766059) (xy 190.178351 -302.798202)
			(xy 190.135813 -302.8238) (xy 190.089694 -302.842179) (xy 190.041209 -302.852855) (xy 189.991636 -302.855545)
			(xy 189.94228 -302.85018) (xy 189.894442 -302.836901) (xy 189.849383 -302.816058) (xy 189.80829 -302.788199)
			(xy 189.772245 -302.754059) (xy 189.742199 -302.714538) (xy 189.718942 -302.670676) (xy 189.703087 -302.623629)
			(xy 189.695053 -302.574637) (xy 189.694566 -302.549814) (xy 189.694745 -302.535631) (xy 189.697416 -302.507391)
			(xy 189.6999 -302.493426) (xy 189.702057 -302.479458) (xy 189.699484 -302.451325) (xy 189.689298 -302.424975)
			(xy 189.672279 -302.402426) (xy 189.649731 -302.385406) (xy 189.623381 -302.375218) (xy 189.595248 -302.372643)
			(xy 189.581282 -302.374808) (xy 189.567316 -302.377283) (xy 189.539076 -302.379956) (xy 189.524894 -302.380142)
			(xy 189.500073 -302.379616) (xy 189.451086 -302.371583) (xy 189.404043 -302.355731) (xy 189.360185 -302.332478)
			(xy 189.320666 -302.302434) (xy 189.286529 -302.266394) (xy 189.258672 -302.225305) (xy 189.23783 -302.18025)
			(xy 189.224552 -302.132417) (xy 189.219187 -302.083066) (xy 188.880076 -302.083066) (xy 188.879747 -302.099441)
			(xy 188.871852 -302.148018) (xy 188.856268 -302.194699) (xy 188.833397 -302.238276) (xy 188.803832 -302.27762)
			(xy 188.768339 -302.311712) (xy 188.727836 -302.339668) (xy 188.683374 -302.360766) (xy 188.636103 -302.374458)
			(xy 188.587248 -302.38039) (xy 188.538073 -302.378409) (xy 188.489854 -302.368565) (xy 188.443838 -302.351113)
			(xy 188.401217 -302.326506) (xy 188.363096 -302.295381) (xy 188.330461 -302.258544) (xy 188.304158 -302.216948)
			(xy 188.284867 -302.171672) (xy 188.27309 -302.123888) (xy 188.26913 -302.074834) (xy 187.930282 -302.074834)
			(xy 187.929787 -302.099441) (xy 187.921892 -302.148018) (xy 187.906308 -302.194699) (xy 187.883437 -302.238276)
			(xy 187.853872 -302.27762) (xy 187.818379 -302.311712) (xy 187.777876 -302.339668) (xy 187.733414 -302.360766)
			(xy 187.686143 -302.374458) (xy 187.637288 -302.38039) (xy 187.588113 -302.378409) (xy 187.539894 -302.368565)
			(xy 187.493878 -302.351113) (xy 187.451257 -302.326506) (xy 187.413136 -302.295381) (xy 187.380501 -302.258544)
			(xy 187.354198 -302.216948) (xy 187.334907 -302.171672) (xy 187.32313 -302.123888) (xy 187.31917 -302.074834)
			(xy 186.980322 -302.074834) (xy 186.979827 -302.099441) (xy 186.971932 -302.148018) (xy 186.956348 -302.194699)
			(xy 186.933477 -302.238276) (xy 186.903912 -302.27762) (xy 186.868419 -302.311712) (xy 186.827916 -302.339668)
			(xy 186.783454 -302.360766) (xy 186.736183 -302.374458) (xy 186.687328 -302.38039) (xy 186.638153 -302.378409)
			(xy 186.589934 -302.368565) (xy 186.543918 -302.351113) (xy 186.501297 -302.326506) (xy 186.463176 -302.295381)
			(xy 186.430541 -302.258544) (xy 186.404238 -302.216948) (xy 186.384947 -302.171672) (xy 186.37317 -302.123888)
			(xy 186.36921 -302.074834) (xy 186.030362 -302.074834) (xy 186.029867 -302.099441) (xy 186.021972 -302.148018)
			(xy 186.006388 -302.194699) (xy 185.983517 -302.238276) (xy 185.953952 -302.27762) (xy 185.918459 -302.311712)
			(xy 185.877956 -302.339668) (xy 185.833494 -302.360766) (xy 185.786223 -302.374458) (xy 185.737368 -302.38039)
			(xy 185.688193 -302.378409) (xy 185.639974 -302.368565) (xy 185.593958 -302.351113) (xy 185.551337 -302.326506)
			(xy 185.513216 -302.295381) (xy 185.480581 -302.258544) (xy 185.454278 -302.216948) (xy 185.434987 -302.171672)
			(xy 185.42321 -302.123888) (xy 185.41925 -302.074834) (xy 185.080148 -302.074834) (xy 185.079653 -302.099441)
			(xy 185.071758 -302.148018) (xy 185.056174 -302.194699) (xy 185.033303 -302.238276) (xy 185.003738 -302.27762)
			(xy 184.968245 -302.311712) (xy 184.927742 -302.339668) (xy 184.88328 -302.360766) (xy 184.836009 -302.374458)
			(xy 184.787154 -302.38039) (xy 184.737979 -302.378409) (xy 184.68976 -302.368565) (xy 184.643744 -302.351113)
			(xy 184.601123 -302.326506) (xy 184.563002 -302.295381) (xy 184.530367 -302.258544) (xy 184.504064 -302.216948)
			(xy 184.484773 -302.171672) (xy 184.472996 -302.123888) (xy 184.469036 -302.074834) (xy 184.130188 -302.074834)
			(xy 184.129693 -302.099441) (xy 184.121798 -302.148018) (xy 184.106214 -302.194699) (xy 184.083343 -302.238276)
			(xy 184.053778 -302.27762) (xy 184.018285 -302.311712) (xy 183.977782 -302.339668) (xy 183.93332 -302.360766)
			(xy 183.886049 -302.374458) (xy 183.837194 -302.38039) (xy 183.788019 -302.378409) (xy 183.7398 -302.368565)
			(xy 183.693784 -302.351113) (xy 183.651163 -302.326506) (xy 183.613042 -302.295381) (xy 183.580407 -302.258544)
			(xy 183.554104 -302.216948) (xy 183.534813 -302.171672) (xy 183.523036 -302.123888) (xy 183.519076 -302.074834)
			(xy 183.180228 -302.074834) (xy 183.179733 -302.099441) (xy 183.171838 -302.148018) (xy 183.156254 -302.194699)
			(xy 183.133383 -302.238276) (xy 183.103818 -302.27762) (xy 183.068325 -302.311712) (xy 183.027822 -302.339668)
			(xy 182.98336 -302.360766) (xy 182.936089 -302.374458) (xy 182.887234 -302.38039) (xy 182.838059 -302.378409)
			(xy 182.78984 -302.368565) (xy 182.743824 -302.351113) (xy 182.701203 -302.326506) (xy 182.663082 -302.295381)
			(xy 182.630447 -302.258544) (xy 182.604144 -302.216948) (xy 182.584853 -302.171672) (xy 182.573076 -302.123888)
			(xy 182.569116 -302.074834) (xy 182.230268 -302.074834) (xy 182.229773 -302.099441) (xy 182.221878 -302.148018)
			(xy 182.206294 -302.194699) (xy 182.183423 -302.238276) (xy 182.153858 -302.27762) (xy 182.118365 -302.311712)
			(xy 182.077862 -302.339668) (xy 182.0334 -302.360766) (xy 181.986129 -302.374458) (xy 181.937274 -302.38039)
			(xy 181.888099 -302.378409) (xy 181.83988 -302.368565) (xy 181.793864 -302.351113) (xy 181.751243 -302.326506)
			(xy 181.713122 -302.295381) (xy 181.680487 -302.258544) (xy 181.654184 -302.216948) (xy 181.634893 -302.171672)
			(xy 181.623116 -302.123888) (xy 181.619156 -302.074834) (xy 181.280308 -302.074834) (xy 181.279813 -302.099441)
			(xy 181.271918 -302.148018) (xy 181.256334 -302.194699) (xy 181.233463 -302.238276) (xy 181.203898 -302.27762)
			(xy 181.168405 -302.311712) (xy 181.127902 -302.339668) (xy 181.08344 -302.360766) (xy 181.036169 -302.374458)
			(xy 180.987314 -302.38039) (xy 180.938139 -302.378409) (xy 180.88992 -302.368565) (xy 180.843904 -302.351113)
			(xy 180.801283 -302.326506) (xy 180.763162 -302.295381) (xy 180.730527 -302.258544) (xy 180.704224 -302.216948)
			(xy 180.684933 -302.171672) (xy 180.673156 -302.123888) (xy 180.669196 -302.074834) (xy 180.330348 -302.074834)
			(xy 180.329853 -302.099441) (xy 180.321958 -302.148018) (xy 180.306374 -302.194699) (xy 180.283503 -302.238276)
			(xy 180.253938 -302.27762) (xy 180.218445 -302.311712) (xy 180.177942 -302.339668) (xy 180.13348 -302.360766)
			(xy 180.086209 -302.374458) (xy 180.037354 -302.38039) (xy 179.988179 -302.378409) (xy 179.93996 -302.368565)
			(xy 179.893944 -302.351113) (xy 179.851323 -302.326506) (xy 179.813202 -302.295381) (xy 179.780567 -302.258544)
			(xy 179.754264 -302.216948) (xy 179.734973 -302.171672) (xy 179.723196 -302.123888) (xy 179.719236 -302.074834)
			(xy 179.380388 -302.074834) (xy 179.379893 -302.099441) (xy 179.371998 -302.148018) (xy 179.356414 -302.194699)
			(xy 179.333543 -302.238276) (xy 179.303978 -302.27762) (xy 179.268485 -302.311712) (xy 179.227982 -302.339668)
			(xy 179.18352 -302.360766) (xy 179.136249 -302.374458) (xy 179.087394 -302.38039) (xy 179.038219 -302.378409)
			(xy 178.99 -302.368565) (xy 178.943984 -302.351113) (xy 178.901363 -302.326506) (xy 178.863242 -302.295381)
			(xy 178.830607 -302.258544) (xy 178.804304 -302.216948) (xy 178.785013 -302.171672) (xy 178.773236 -302.123888)
			(xy 178.769276 -302.074834) (xy 178.430174 -302.074834) (xy 178.429679 -302.099441) (xy 178.421784 -302.148018)
			(xy 178.4062 -302.194699) (xy 178.383329 -302.238276) (xy 178.353764 -302.27762) (xy 178.318271 -302.311712)
			(xy 178.277768 -302.339668) (xy 178.233306 -302.360766) (xy 178.186035 -302.374458) (xy 178.13718 -302.38039)
			(xy 178.088005 -302.378409) (xy 178.039786 -302.368565) (xy 177.99377 -302.351113) (xy 177.951149 -302.326506)
			(xy 177.913028 -302.295381) (xy 177.880393 -302.258544) (xy 177.85409 -302.216948) (xy 177.834799 -302.171672)
			(xy 177.823022 -302.123888) (xy 177.819062 -302.074834) (xy 177.480214 -302.074834) (xy 177.479719 -302.099441)
			(xy 177.471824 -302.148018) (xy 177.45624 -302.194699) (xy 177.433369 -302.238276) (xy 177.403804 -302.27762)
			(xy 177.368311 -302.311712) (xy 177.327808 -302.339668) (xy 177.283346 -302.360766) (xy 177.236075 -302.374458)
			(xy 177.18722 -302.38039) (xy 177.138045 -302.378409) (xy 177.089826 -302.368565) (xy 177.04381 -302.351113)
			(xy 177.001189 -302.326506) (xy 176.963068 -302.295381) (xy 176.930433 -302.258544) (xy 176.90413 -302.216948)
			(xy 176.884839 -302.171672) (xy 176.873062 -302.123888) (xy 176.869102 -302.074834) (xy 176.530254 -302.074834)
			(xy 176.529759 -302.099441) (xy 176.521864 -302.148018) (xy 176.50628 -302.194699) (xy 176.483409 -302.238276)
			(xy 176.453844 -302.27762) (xy 176.418351 -302.311712) (xy 176.377848 -302.339668) (xy 176.333386 -302.360766)
			(xy 176.286115 -302.374458) (xy 176.23726 -302.38039) (xy 176.188085 -302.378409) (xy 176.139866 -302.368565)
			(xy 176.09385 -302.351113) (xy 176.051229 -302.326506) (xy 176.013108 -302.295381) (xy 175.980473 -302.258544)
			(xy 175.95417 -302.216948) (xy 175.934879 -302.171672) (xy 175.923102 -302.123888) (xy 175.919142 -302.074834)
			(xy 174.630334 -302.074834) (xy 174.629839 -302.099441) (xy 174.621944 -302.148018) (xy 174.60636 -302.194699)
			(xy 174.583489 -302.238276) (xy 174.553924 -302.27762) (xy 174.518431 -302.311712) (xy 174.477928 -302.339668)
			(xy 174.433466 -302.360766) (xy 174.386195 -302.374458) (xy 174.33734 -302.38039) (xy 174.288165 -302.378409)
			(xy 174.239946 -302.368565) (xy 174.19393 -302.351113) (xy 174.151309 -302.326506) (xy 174.113188 -302.295381)
			(xy 174.080553 -302.258544) (xy 174.05425 -302.216948) (xy 174.034959 -302.171672) (xy 174.023182 -302.123888)
			(xy 174.019222 -302.074834) (xy 173.680374 -302.074834) (xy 173.679879 -302.099441) (xy 173.671984 -302.148018)
			(xy 173.6564 -302.194699) (xy 173.633529 -302.238276) (xy 173.603964 -302.27762) (xy 173.568471 -302.311712)
			(xy 173.527968 -302.339668) (xy 173.483506 -302.360766) (xy 173.436235 -302.374458) (xy 173.38738 -302.38039)
			(xy 173.338205 -302.378409) (xy 173.289986 -302.368565) (xy 173.24397 -302.351113) (xy 173.201349 -302.326506)
			(xy 173.163228 -302.295381) (xy 173.130593 -302.258544) (xy 173.10429 -302.216948) (xy 173.084999 -302.171672)
			(xy 173.073222 -302.123888) (xy 173.069262 -302.074834) (xy 172.73016 -302.074834) (xy 172.729665 -302.099441)
			(xy 172.72177 -302.148018) (xy 172.706186 -302.194699) (xy 172.683315 -302.238276) (xy 172.65375 -302.27762)
			(xy 172.618257 -302.311712) (xy 172.577754 -302.339668) (xy 172.533292 -302.360766) (xy 172.486021 -302.374458)
			(xy 172.437166 -302.38039) (xy 172.387991 -302.378409) (xy 172.339772 -302.368565) (xy 172.293756 -302.351113)
			(xy 172.251135 -302.326506) (xy 172.213014 -302.295381) (xy 172.180379 -302.258544) (xy 172.154076 -302.216948)
			(xy 172.134785 -302.171672) (xy 172.123008 -302.123888) (xy 172.119048 -302.074834) (xy 171.7802 -302.074834)
			(xy 171.779705 -302.099441) (xy 171.77181 -302.148018) (xy 171.756226 -302.194699) (xy 171.733355 -302.238276)
			(xy 171.70379 -302.27762) (xy 171.668297 -302.311712) (xy 171.627794 -302.339668) (xy 171.583332 -302.360766)
			(xy 171.536061 -302.374458) (xy 171.487206 -302.38039) (xy 171.438031 -302.378409) (xy 171.389812 -302.368565)
			(xy 171.343796 -302.351113) (xy 171.301175 -302.326506) (xy 171.263054 -302.295381) (xy 171.230419 -302.258544)
			(xy 171.204116 -302.216948) (xy 171.184825 -302.171672) (xy 171.173048 -302.123888) (xy 171.169088 -302.074834)
			(xy 170.83024 -302.074834) (xy 170.829745 -302.099441) (xy 170.82185 -302.148018) (xy 170.806266 -302.194699)
			(xy 170.783395 -302.238276) (xy 170.75383 -302.27762) (xy 170.718337 -302.311712) (xy 170.677834 -302.339668)
			(xy 170.633372 -302.360766) (xy 170.586101 -302.374458) (xy 170.537246 -302.38039) (xy 170.488071 -302.378409)
			(xy 170.439852 -302.368565) (xy 170.393836 -302.351113) (xy 170.351215 -302.326506) (xy 170.313094 -302.295381)
			(xy 170.280459 -302.258544) (xy 170.254156 -302.216948) (xy 170.234865 -302.171672) (xy 170.223088 -302.123888)
			(xy 170.219128 -302.074834) (xy 169.88028 -302.074834) (xy 169.879785 -302.099441) (xy 169.87189 -302.148018)
			(xy 169.856306 -302.194699) (xy 169.833435 -302.238276) (xy 169.80387 -302.27762) (xy 169.768377 -302.311712)
			(xy 169.727874 -302.339668) (xy 169.683412 -302.360766) (xy 169.636141 -302.374458) (xy 169.587286 -302.38039)
			(xy 169.538111 -302.378409) (xy 169.489892 -302.368565) (xy 169.443876 -302.351113) (xy 169.401255 -302.326506)
			(xy 169.363134 -302.295381) (xy 169.330499 -302.258544) (xy 169.304196 -302.216948) (xy 169.284905 -302.171672)
			(xy 169.273128 -302.123888) (xy 169.269168 -302.074834) (xy 168.93032 -302.074834) (xy 168.929825 -302.099441)
			(xy 168.92193 -302.148018) (xy 168.906346 -302.194699) (xy 168.883475 -302.238276) (xy 168.85391 -302.27762)
			(xy 168.818417 -302.311712) (xy 168.777914 -302.339668) (xy 168.733452 -302.360766) (xy 168.686181 -302.374458)
			(xy 168.637326 -302.38039) (xy 168.588151 -302.378409) (xy 168.539932 -302.368565) (xy 168.493916 -302.351113)
			(xy 168.451295 -302.326506) (xy 168.413174 -302.295381) (xy 168.380539 -302.258544) (xy 168.354236 -302.216948)
			(xy 168.334945 -302.171672) (xy 168.323168 -302.123888) (xy 168.319208 -302.074834) (xy 167.98036 -302.074834)
			(xy 167.979865 -302.099441) (xy 167.97197 -302.148018) (xy 167.956386 -302.194699) (xy 167.933515 -302.238276)
			(xy 167.90395 -302.27762) (xy 167.868457 -302.311712) (xy 167.827954 -302.339668) (xy 167.783492 -302.360766)
			(xy 167.736221 -302.374458) (xy 167.687366 -302.38039) (xy 167.638191 -302.378409) (xy 167.589972 -302.368565)
			(xy 167.543956 -302.351113) (xy 167.501335 -302.326506) (xy 167.463214 -302.295381) (xy 167.430579 -302.258544)
			(xy 167.404276 -302.216948) (xy 167.384985 -302.171672) (xy 167.373208 -302.123888) (xy 167.369248 -302.074834)
			(xy 167.0304 -302.074834) (xy 167.029905 -302.099441) (xy 167.02201 -302.148018) (xy 167.006426 -302.194699)
			(xy 166.983555 -302.238276) (xy 166.95399 -302.27762) (xy 166.918497 -302.311712) (xy 166.877994 -302.339668)
			(xy 166.833532 -302.360766) (xy 166.786261 -302.374458) (xy 166.737406 -302.38039) (xy 166.688231 -302.378409)
			(xy 166.640012 -302.368565) (xy 166.593996 -302.351113) (xy 166.551375 -302.326506) (xy 166.513254 -302.295381)
			(xy 166.480619 -302.258544) (xy 166.454316 -302.216948) (xy 166.435025 -302.171672) (xy 166.423248 -302.123888)
			(xy 166.419288 -302.074834) (xy 166.080186 -302.074834) (xy 166.079691 -302.099441) (xy 166.071796 -302.148018)
			(xy 166.056212 -302.194699) (xy 166.033341 -302.238276) (xy 166.003776 -302.27762) (xy 165.968283 -302.311712)
			(xy 165.92778 -302.339668) (xy 165.883318 -302.360766) (xy 165.836047 -302.374458) (xy 165.787192 -302.38039)
			(xy 165.738017 -302.378409) (xy 165.689798 -302.368565) (xy 165.643782 -302.351113) (xy 165.601161 -302.326506)
			(xy 165.56304 -302.295381) (xy 165.530405 -302.258544) (xy 165.504102 -302.216948) (xy 165.484811 -302.171672)
			(xy 165.473034 -302.123888) (xy 165.469074 -302.074834) (xy 164.790882 -302.074834) (xy 164.790882 -302.62322)
			(xy 164.791349 -302.632853) (xy 164.798529 -302.650736) (xy 164.804852 -302.658018) (xy 164.820092 -302.67402)
			(xy 164.82695 -302.681386) (xy 164.850318 -302.6918) (xy 164.854636 -302.69307) (xy 164.86505 -302.696372)
			(xy 164.869622 -302.697134) (xy 164.895692 -302.701211) (xy 164.946175 -302.716557) (xy 164.993581 -302.739725)
			(xy 165.036707 -302.770126) (xy 165.074458 -302.806989) (xy 165.105878 -302.849378) (xy 165.130167 -302.896219)
			(xy 165.146711 -302.946322) (xy 165.15509 -302.998417) (xy 165.15509 -303.024794) (xy 165.469074 -303.024794)
			(xy 165.473034 -302.97574) (xy 165.484811 -302.927956) (xy 165.504102 -302.88268) (xy 165.530405 -302.841084)
			(xy 165.56304 -302.804247) (xy 165.601161 -302.773122) (xy 165.643782 -302.748515) (xy 165.689798 -302.731063)
			(xy 165.738017 -302.721219) (xy 165.787192 -302.719238) (xy 165.836047 -302.72517) (xy 165.883318 -302.738862)
			(xy 165.92778 -302.75996) (xy 165.968283 -302.787916) (xy 166.003776 -302.822008) (xy 166.033341 -302.861352)
			(xy 166.056212 -302.904929) (xy 166.071796 -302.95161) (xy 166.079691 -303.000187) (xy 166.080186 -303.024794)
			(xy 184.469036 -303.024794) (xy 184.472996 -302.97574) (xy 184.484773 -302.927956) (xy 184.504064 -302.88268)
			(xy 184.530367 -302.841084) (xy 184.563002 -302.804247) (xy 184.601123 -302.773122) (xy 184.643744 -302.748515)
			(xy 184.68976 -302.731063) (xy 184.737979 -302.721219) (xy 184.787154 -302.719238) (xy 184.836009 -302.72517)
			(xy 184.88328 -302.738862) (xy 184.927742 -302.75996) (xy 184.968245 -302.787916) (xy 185.003738 -302.822008)
			(xy 185.033303 -302.861352) (xy 185.056174 -302.904929) (xy 185.071758 -302.95161) (xy 185.079653 -303.000187)
			(xy 185.080148 -303.024794) (xy 185.41925 -303.024794) (xy 185.42321 -302.97574) (xy 185.434987 -302.927956)
			(xy 185.454278 -302.88268) (xy 185.480581 -302.841084) (xy 185.513216 -302.804247) (xy 185.551337 -302.773122)
			(xy 185.593958 -302.748515) (xy 185.639974 -302.731063) (xy 185.688193 -302.721219) (xy 185.737368 -302.719238)
			(xy 185.786223 -302.72517) (xy 185.833494 -302.738862) (xy 185.877956 -302.75996) (xy 185.918459 -302.787916)
			(xy 185.953952 -302.822008) (xy 185.983517 -302.861352) (xy 186.006388 -302.904929) (xy 186.021972 -302.95161)
			(xy 186.029867 -303.000187) (xy 186.030362 -303.024794) (xy 186.36921 -303.024794) (xy 186.37317 -302.97574)
			(xy 186.384947 -302.927956) (xy 186.404238 -302.88268) (xy 186.430541 -302.841084) (xy 186.463176 -302.804247)
			(xy 186.501297 -302.773122) (xy 186.543918 -302.748515) (xy 186.589934 -302.731063) (xy 186.638153 -302.721219)
			(xy 186.687328 -302.719238) (xy 186.736183 -302.72517) (xy 186.783454 -302.738862) (xy 186.827916 -302.75996)
			(xy 186.868419 -302.787916) (xy 186.903912 -302.822008) (xy 186.933477 -302.861352) (xy 186.956348 -302.904929)
			(xy 186.971932 -302.95161) (xy 186.979827 -303.000187) (xy 186.980322 -303.024794) (xy 187.31917 -303.024794)
			(xy 187.32313 -302.97574) (xy 187.334907 -302.927956) (xy 187.354198 -302.88268) (xy 187.380501 -302.841084)
			(xy 187.413136 -302.804247) (xy 187.451257 -302.773122) (xy 187.493878 -302.748515) (xy 187.539894 -302.731063)
			(xy 187.588113 -302.721219) (xy 187.637288 -302.719238) (xy 187.686143 -302.72517) (xy 187.733414 -302.738862)
			(xy 187.777876 -302.75996) (xy 187.818379 -302.787916) (xy 187.853872 -302.822008) (xy 187.883437 -302.861352)
			(xy 187.906308 -302.904929) (xy 187.921892 -302.95161) (xy 187.929787 -303.000187) (xy 187.930282 -303.024794)
			(xy 188.26913 -303.024794) (xy 188.27309 -302.97574) (xy 188.284867 -302.927956) (xy 188.304158 -302.88268)
			(xy 188.330461 -302.841084) (xy 188.363096 -302.804247) (xy 188.401217 -302.773122) (xy 188.443838 -302.748515)
			(xy 188.489854 -302.731063) (xy 188.538073 -302.721219) (xy 188.587248 -302.719238) (xy 188.636103 -302.72517)
			(xy 188.683374 -302.738862) (xy 188.727836 -302.75996) (xy 188.768339 -302.787916) (xy 188.803832 -302.822008)
			(xy 188.833397 -302.861352) (xy 188.856268 -302.904929) (xy 188.871852 -302.95161) (xy 188.879747 -303.000187)
			(xy 188.880242 -303.024794) (xy 188.879747 -303.049401) (xy 188.871852 -303.097978) (xy 188.856268 -303.144659)
			(xy 188.833397 -303.188236) (xy 188.803832 -303.22758) (xy 188.768339 -303.261672) (xy 188.727836 -303.289628)
			(xy 188.683374 -303.310726) (xy 188.636103 -303.324418) (xy 188.587248 -303.33035) (xy 188.538073 -303.328369)
			(xy 188.489854 -303.318525) (xy 188.443838 -303.301073) (xy 188.401217 -303.276466) (xy 188.363096 -303.245341)
			(xy 188.330461 -303.208504) (xy 188.304158 -303.166908) (xy 188.284867 -303.121632) (xy 188.27309 -303.073848)
			(xy 188.26913 -303.024794) (xy 187.930282 -303.024794) (xy 187.929787 -303.049401) (xy 187.921892 -303.097978)
			(xy 187.906308 -303.144659) (xy 187.883437 -303.188236) (xy 187.853872 -303.22758) (xy 187.818379 -303.261672)
			(xy 187.777876 -303.289628) (xy 187.733414 -303.310726) (xy 187.686143 -303.324418) (xy 187.637288 -303.33035)
			(xy 187.588113 -303.328369) (xy 187.539894 -303.318525) (xy 187.493878 -303.301073) (xy 187.451257 -303.276466)
			(xy 187.413136 -303.245341) (xy 187.380501 -303.208504) (xy 187.354198 -303.166908) (xy 187.334907 -303.121632)
			(xy 187.32313 -303.073848) (xy 187.31917 -303.024794) (xy 186.980322 -303.024794) (xy 186.979827 -303.049401)
			(xy 186.971932 -303.097978) (xy 186.956348 -303.144659) (xy 186.933477 -303.188236) (xy 186.903912 -303.22758)
			(xy 186.868419 -303.261672) (xy 186.827916 -303.289628) (xy 186.783454 -303.310726) (xy 186.736183 -303.324418)
			(xy 186.687328 -303.33035) (xy 186.638153 -303.328369) (xy 186.589934 -303.318525) (xy 186.543918 -303.301073)
			(xy 186.501297 -303.276466) (xy 186.463176 -303.245341) (xy 186.430541 -303.208504) (xy 186.404238 -303.166908)
			(xy 186.384947 -303.121632) (xy 186.37317 -303.073848) (xy 186.36921 -303.024794) (xy 186.030362 -303.024794)
			(xy 186.029867 -303.049401) (xy 186.021972 -303.097978) (xy 186.006388 -303.144659) (xy 185.983517 -303.188236)
			(xy 185.953952 -303.22758) (xy 185.918459 -303.261672) (xy 185.877956 -303.289628) (xy 185.833494 -303.310726)
			(xy 185.786223 -303.324418) (xy 185.737368 -303.33035) (xy 185.688193 -303.328369) (xy 185.639974 -303.318525)
			(xy 185.593958 -303.301073) (xy 185.551337 -303.276466) (xy 185.513216 -303.245341) (xy 185.480581 -303.208504)
			(xy 185.454278 -303.166908) (xy 185.434987 -303.121632) (xy 185.42321 -303.073848) (xy 185.41925 -303.024794)
			(xy 185.080148 -303.024794) (xy 185.079653 -303.049401) (xy 185.071758 -303.097978) (xy 185.056174 -303.144659)
			(xy 185.033303 -303.188236) (xy 185.003738 -303.22758) (xy 184.968245 -303.261672) (xy 184.927742 -303.289628)
			(xy 184.88328 -303.310726) (xy 184.836009 -303.324418) (xy 184.787154 -303.33035) (xy 184.737979 -303.328369)
			(xy 184.68976 -303.318525) (xy 184.643744 -303.301073) (xy 184.601123 -303.276466) (xy 184.563002 -303.245341)
			(xy 184.530367 -303.208504) (xy 184.504064 -303.166908) (xy 184.484773 -303.121632) (xy 184.472996 -303.073848)
			(xy 184.469036 -303.024794) (xy 166.080186 -303.024794) (xy 166.079691 -303.049401) (xy 166.071796 -303.097978)
			(xy 166.056212 -303.144659) (xy 166.033341 -303.188236) (xy 166.003776 -303.22758) (xy 165.968283 -303.261672)
			(xy 165.92778 -303.289628) (xy 165.883318 -303.310726) (xy 165.836047 -303.324418) (xy 165.787192 -303.33035)
			(xy 165.738017 -303.328369) (xy 165.689798 -303.318525) (xy 165.643782 -303.301073) (xy 165.601161 -303.276466)
			(xy 165.56304 -303.245341) (xy 165.530405 -303.208504) (xy 165.504102 -303.166908) (xy 165.484811 -303.121632)
			(xy 165.473034 -303.073848) (xy 165.469074 -303.024794) (xy 165.15509 -303.024794) (xy 165.15509 -303.051181)
			(xy 165.146712 -303.103276) (xy 165.130168 -303.153379) (xy 165.105878 -303.20022) (xy 165.07446 -303.24261)
			(xy 165.036708 -303.279473) (xy 164.993583 -303.309874) (xy 164.946177 -303.333042) (xy 164.895694 -303.348388)
			(xy 164.869622 -303.352454) (xy 164.86505 -303.353216) (xy 164.854636 -303.356518) (xy 164.850318 -303.357788)
			(xy 164.826696 -303.36871) (xy 164.819838 -303.375822) (xy 164.804852 -303.39157) (xy 164.800261 -303.396674)
			(xy 164.793808 -303.408785) (xy 164.792152 -303.415446) (xy 164.790882 -303.426368) (xy 164.790882 -303.499774)
			(xy 189.69407 -303.499774) (xy 189.69803 -303.45072) (xy 189.709807 -303.402936) (xy 189.729098 -303.35766)
			(xy 189.755401 -303.316064) (xy 189.788036 -303.279227) (xy 189.826157 -303.248102) (xy 189.868778 -303.223495)
			(xy 189.914794 -303.206043) (xy 189.963013 -303.196199) (xy 190.012188 -303.194218) (xy 190.061043 -303.20015)
			(xy 190.108314 -303.213842) (xy 190.152776 -303.23494) (xy 190.193279 -303.262896) (xy 190.228772 -303.296988)
			(xy 190.258337 -303.336332) (xy 190.281208 -303.379909) (xy 190.296792 -303.42659) (xy 190.304687 -303.475167)
			(xy 190.305182 -303.499774) (xy 190.644284 -303.499774) (xy 190.648244 -303.45072) (xy 190.660021 -303.402936)
			(xy 190.679312 -303.35766) (xy 190.705615 -303.316064) (xy 190.73825 -303.279227) (xy 190.776371 -303.248102)
			(xy 190.818992 -303.223495) (xy 190.865008 -303.206043) (xy 190.913227 -303.196199) (xy 190.962402 -303.194218)
			(xy 191.011257 -303.20015) (xy 191.058528 -303.213842) (xy 191.10299 -303.23494) (xy 191.143493 -303.262896)
			(xy 191.178986 -303.296988) (xy 191.208551 -303.336332) (xy 191.231422 -303.379909) (xy 191.247006 -303.42659)
			(xy 191.254901 -303.475167) (xy 191.255396 -303.499774) (xy 191.594244 -303.499774) (xy 191.598204 -303.45072)
			(xy 191.609981 -303.402936) (xy 191.629272 -303.35766) (xy 191.655575 -303.316064) (xy 191.68821 -303.279227)
			(xy 191.726331 -303.248102) (xy 191.768952 -303.223495) (xy 191.814968 -303.206043) (xy 191.863187 -303.196199)
			(xy 191.912362 -303.194218) (xy 191.961217 -303.20015) (xy 192.008488 -303.213842) (xy 192.05295 -303.23494)
			(xy 192.093453 -303.262896) (xy 192.128946 -303.296988) (xy 192.158511 -303.336332) (xy 192.181382 -303.379909)
			(xy 192.196966 -303.42659) (xy 192.204861 -303.475167) (xy 192.20519 -303.491507) (xy 194.444155 -303.491507)
			(xy 194.449525 -303.442151) (xy 194.462809 -303.394313) (xy 194.483658 -303.349255) (xy 194.511522 -303.308164)
			(xy 194.545667 -303.272122) (xy 194.585193 -303.242079) (xy 194.629059 -303.218827) (xy 194.67611 -303.202978)
			(xy 194.725104 -303.19495) (xy 194.749928 -303.194466) (xy 194.764111 -303.194639) (xy 194.792351 -303.197314)
			(xy 194.806316 -303.1998) (xy 194.820277 -303.202001) (xy 194.848414 -303.199417) (xy 194.874766 -303.189222)
			(xy 194.897316 -303.172196) (xy 194.914336 -303.149642) (xy 194.924524 -303.123288) (xy 194.927099 -303.09515)
			(xy 194.924934 -303.081182) (xy 194.922459 -303.067216) (xy 194.919786 -303.038976) (xy 194.9196 -303.024794)
			(xy 194.920084 -302.999974) (xy 194.928116 -302.950988) (xy 194.943967 -302.903946) (xy 194.96722 -302.860089)
			(xy 194.997261 -302.820571) (xy 195.0333 -302.786434) (xy 195.074387 -302.758577) (xy 195.11944 -302.737734)
			(xy 195.167271 -302.724454) (xy 195.21662 -302.719087) (xy 195.266187 -302.721775) (xy 195.314667 -302.732446)
			(xy 195.360782 -302.75082) (xy 195.403316 -302.776412) (xy 195.44115 -302.808548) (xy 195.473287 -302.846382)
			(xy 195.498879 -302.888917) (xy 195.517253 -302.935031) (xy 195.527925 -302.983511) (xy 195.530164 -303.024794)
			(xy 195.869064 -303.024794) (xy 195.873024 -302.97574) (xy 195.884801 -302.927956) (xy 195.904092 -302.88268)
			(xy 195.930395 -302.841084) (xy 195.96303 -302.804247) (xy 196.001151 -302.773122) (xy 196.043772 -302.748515)
			(xy 196.089788 -302.731063) (xy 196.138007 -302.721219) (xy 196.187182 -302.719238) (xy 196.236037 -302.72517)
			(xy 196.283308 -302.738862) (xy 196.32777 -302.75996) (xy 196.368273 -302.787916) (xy 196.403766 -302.822008)
			(xy 196.433331 -302.861352) (xy 196.456202 -302.904929) (xy 196.471786 -302.95161) (xy 196.479681 -303.000187)
			(xy 196.480176 -303.024794) (xy 196.819278 -303.024794) (xy 196.823238 -302.97574) (xy 196.835015 -302.927956)
			(xy 196.854306 -302.88268) (xy 196.880609 -302.841084) (xy 196.913244 -302.804247) (xy 196.951365 -302.773122)
			(xy 196.993986 -302.748515) (xy 197.040002 -302.731063) (xy 197.088221 -302.721219) (xy 197.137396 -302.719238)
			(xy 197.186251 -302.72517) (xy 197.233522 -302.738862) (xy 197.277984 -302.75996) (xy 197.318487 -302.787916)
			(xy 197.35398 -302.822008) (xy 197.383545 -302.861352) (xy 197.406416 -302.904929) (xy 197.422 -302.95161)
			(xy 197.429895 -303.000187) (xy 197.43039 -303.024794) (xy 197.769238 -303.024794) (xy 197.773198 -302.97574)
			(xy 197.784975 -302.927956) (xy 197.804266 -302.88268) (xy 197.830569 -302.841084) (xy 197.863204 -302.804247)
			(xy 197.901325 -302.773122) (xy 197.943946 -302.748515) (xy 197.989962 -302.731063) (xy 198.038181 -302.721219)
			(xy 198.087356 -302.719238) (xy 198.136211 -302.72517) (xy 198.183482 -302.738862) (xy 198.227944 -302.75996)
			(xy 198.268447 -302.787916) (xy 198.30394 -302.822008) (xy 198.333505 -302.861352) (xy 198.356376 -302.904929)
			(xy 198.37196 -302.95161) (xy 198.379855 -303.000187) (xy 198.38035 -303.024794) (xy 198.703958 -303.024794)
			(xy 198.707918 -302.97574) (xy 198.719695 -302.927956) (xy 198.738986 -302.88268) (xy 198.765289 -302.841084)
			(xy 198.797924 -302.804247) (xy 198.836045 -302.773122) (xy 198.878666 -302.748515) (xy 198.924682 -302.731063)
			(xy 198.972901 -302.721219) (xy 199.022076 -302.719238) (xy 199.070931 -302.72517) (xy 199.118202 -302.738862)
			(xy 199.162664 -302.75996) (xy 199.203167 -302.787916) (xy 199.23866 -302.822008) (xy 199.268225 -302.861352)
			(xy 199.291096 -302.904929) (xy 199.30668 -302.95161) (xy 199.314575 -303.000187) (xy 199.31507 -303.024794)
			(xy 199.314575 -303.049401) (xy 199.309984 -303.077651) (xy 203.951303 -303.077651) (xy 203.951303 -303.023149)
			(xy 203.95906 -302.969202) (xy 203.974416 -302.916908) (xy 203.997058 -302.867332) (xy 204.026525 -302.821483)
			(xy 204.062218 -302.780295) (xy 204.103409 -302.744606) (xy 204.14926 -302.715142) (xy 204.198838 -302.692505)
			(xy 204.251133 -302.677153) (xy 204.305081 -302.669401) (xy 204.332332 -302.66894) (xy 204.360674 -302.669466)
			(xy 204.416737 -302.677839) (xy 204.470941 -302.694424) (xy 204.522089 -302.718857) (xy 204.569054 -302.750597)
			(xy 204.610798 -302.788944) (xy 204.629004 -302.810672) (xy 204.637791 -302.820791) (xy 204.659494 -302.836494)
			(xy 204.684534 -302.846013) (xy 204.711188 -302.848695) (xy 204.737622 -302.844356) (xy 204.762019 -302.833292)
			(xy 204.782701 -302.816266) (xy 204.790802 -302.805592) (xy 204.806246 -302.784717) (xy 204.841816 -302.746889)
			(xy 204.882188 -302.714234) (xy 204.926614 -302.687356) (xy 204.974275 -302.66675) (xy 205.02429 -302.652797)
			(xy 205.075736 -302.645755) (xy 205.101698 -302.645318) (xy 205.128953 -302.645729) (xy 205.182908 -302.653486)
			(xy 205.235209 -302.668843) (xy 205.284793 -302.691487) (xy 205.33065 -302.720957) (xy 205.371846 -302.756653)
			(xy 205.407542 -302.797849) (xy 205.437012 -302.843705) (xy 205.459656 -302.893289) (xy 205.475014 -302.94559)
			(xy 205.482771 -302.999545) (xy 205.482771 -303.026826) (xy 205.73568 -303.026826) (xy 205.739751 -302.971204)
			(xy 205.751877 -302.916767) (xy 205.7718 -302.864676) (xy 205.799096 -302.816041) (xy 205.833182 -302.771898)
			(xy 205.873331 -302.733189) (xy 205.918689 -302.700738) (xy 205.968289 -302.675237) (xy 206.021073 -302.65723)
			(xy 206.075916 -302.6471) (xy 206.13165 -302.645063) (xy 206.187087 -302.651163) (xy 206.241044 -302.665269)
			(xy 206.292373 -302.687081) (xy 206.339979 -302.716135) (xy 206.382847 -302.75181) (xy 206.420064 -302.793347)
			(xy 206.450837 -302.83986) (xy 206.474509 -302.890357) (xy 206.490577 -302.943764) (xy 206.498697 -302.99894)
			(xy 206.499206 -303.026826) (xy 206.75168 -303.026826) (xy 206.755751 -302.971204) (xy 206.767877 -302.916767)
			(xy 206.7878 -302.864676) (xy 206.815096 -302.816041) (xy 206.849182 -302.771898) (xy 206.889331 -302.733189)
			(xy 206.934689 -302.700738) (xy 206.984289 -302.675237) (xy 207.037073 -302.65723) (xy 207.091916 -302.6471)
			(xy 207.14765 -302.645063) (xy 207.203087 -302.651163) (xy 207.257044 -302.665269) (xy 207.308373 -302.687081)
			(xy 207.355979 -302.716135) (xy 207.398847 -302.75181) (xy 207.436064 -302.793347) (xy 207.466837 -302.83986)
			(xy 207.490509 -302.890357) (xy 207.506577 -302.943764) (xy 207.514697 -302.99894) (xy 207.515206 -303.026826)
			(xy 207.76768 -303.026826) (xy 207.771751 -302.971204) (xy 207.783877 -302.916767) (xy 207.8038 -302.864676)
			(xy 207.831096 -302.816041) (xy 207.865182 -302.771898) (xy 207.905331 -302.733189) (xy 207.950689 -302.700738)
			(xy 208.000289 -302.675237) (xy 208.053073 -302.65723) (xy 208.107916 -302.6471) (xy 208.16365 -302.645063)
			(xy 208.219087 -302.651163) (xy 208.273044 -302.665269) (xy 208.324373 -302.687081) (xy 208.371979 -302.716135)
			(xy 208.414847 -302.75181) (xy 208.452064 -302.793347) (xy 208.482837 -302.83986) (xy 208.506509 -302.890357)
			(xy 208.522577 -302.943764) (xy 208.530697 -302.99894) (xy 208.531206 -303.026826) (xy 208.78368 -303.026826)
			(xy 208.787751 -302.971204) (xy 208.799877 -302.916767) (xy 208.8198 -302.864676) (xy 208.847096 -302.816041)
			(xy 208.881182 -302.771898) (xy 208.921331 -302.733189) (xy 208.966689 -302.700738) (xy 209.016289 -302.675237)
			(xy 209.069073 -302.65723) (xy 209.123916 -302.6471) (xy 209.17965 -302.645063) (xy 209.235087 -302.651163)
			(xy 209.289044 -302.665269) (xy 209.340373 -302.687081) (xy 209.387979 -302.716135) (xy 209.430847 -302.75181)
			(xy 209.468064 -302.793347) (xy 209.498837 -302.83986) (xy 209.522509 -302.890357) (xy 209.538577 -302.943764)
			(xy 209.546697 -302.99894) (xy 209.547206 -303.026826) (xy 209.546697 -303.054712) (xy 209.538577 -303.109888)
			(xy 209.522509 -303.163295) (xy 209.498837 -303.213792) (xy 209.468064 -303.260305) (xy 209.430847 -303.301842)
			(xy 209.387979 -303.337517) (xy 209.340373 -303.366571) (xy 209.289044 -303.388383) (xy 209.235087 -303.402489)
			(xy 209.17965 -303.408589) (xy 209.123916 -303.406552) (xy 209.069073 -303.396422) (xy 209.016289 -303.378415)
			(xy 208.966689 -303.352914) (xy 208.921331 -303.320463) (xy 208.881182 -303.281754) (xy 208.847096 -303.237611)
			(xy 208.8198 -303.188976) (xy 208.799877 -303.136885) (xy 208.787751 -303.082448) (xy 208.78368 -303.026826)
			(xy 208.531206 -303.026826) (xy 208.530697 -303.054712) (xy 208.522577 -303.109888) (xy 208.506509 -303.163295)
			(xy 208.482837 -303.213792) (xy 208.452064 -303.260305) (xy 208.414847 -303.301842) (xy 208.371979 -303.337517)
			(xy 208.324373 -303.366571) (xy 208.273044 -303.388383) (xy 208.219087 -303.402489) (xy 208.16365 -303.408589)
			(xy 208.107916 -303.406552) (xy 208.053073 -303.396422) (xy 208.000289 -303.378415) (xy 207.950689 -303.352914)
			(xy 207.905331 -303.320463) (xy 207.865182 -303.281754) (xy 207.831096 -303.237611) (xy 207.8038 -303.188976)
			(xy 207.783877 -303.136885) (xy 207.771751 -303.082448) (xy 207.76768 -303.026826) (xy 207.515206 -303.026826)
			(xy 207.514697 -303.054712) (xy 207.506577 -303.109888) (xy 207.490509 -303.163295) (xy 207.466837 -303.213792)
			(xy 207.436064 -303.260305) (xy 207.398847 -303.301842) (xy 207.355979 -303.337517) (xy 207.308373 -303.366571)
			(xy 207.257044 -303.388383) (xy 207.203087 -303.402489) (xy 207.14765 -303.408589) (xy 207.091916 -303.406552)
			(xy 207.037073 -303.396422) (xy 206.984289 -303.378415) (xy 206.934689 -303.352914) (xy 206.889331 -303.320463)
			(xy 206.849182 -303.281754) (xy 206.815096 -303.237611) (xy 206.7878 -303.188976) (xy 206.767877 -303.136885)
			(xy 206.755751 -303.082448) (xy 206.75168 -303.026826) (xy 206.499206 -303.026826) (xy 206.498697 -303.054712)
			(xy 206.490577 -303.109888) (xy 206.474509 -303.163295) (xy 206.450837 -303.213792) (xy 206.420064 -303.260305)
			(xy 206.382847 -303.301842) (xy 206.339979 -303.337517) (xy 206.292373 -303.366571) (xy 206.241044 -303.388383)
			(xy 206.187087 -303.402489) (xy 206.13165 -303.408589) (xy 206.075916 -303.406552) (xy 206.021073 -303.396422)
			(xy 205.968289 -303.378415) (xy 205.918689 -303.352914) (xy 205.873331 -303.320463) (xy 205.833182 -303.281754)
			(xy 205.799096 -303.237611) (xy 205.7718 -303.188976) (xy 205.751877 -303.136885) (xy 205.739751 -303.082448)
			(xy 205.73568 -303.026826) (xy 205.482771 -303.026826) (xy 205.482771 -303.054055) (xy 205.475014 -303.10801)
			(xy 205.459656 -303.160311) (xy 205.437012 -303.209895) (xy 205.407542 -303.255751) (xy 205.371846 -303.296947)
			(xy 205.33065 -303.332643) (xy 205.284793 -303.362113) (xy 205.235209 -303.384757) (xy 205.182908 -303.400114)
			(xy 205.128953 -303.407871) (xy 205.101698 -303.408334) (xy 205.073355 -303.40783) (xy 205.017293 -303.399449)
			(xy 204.96309 -303.382857) (xy 204.911942 -303.358421) (xy 204.864978 -303.326678) (xy 204.823233 -303.28833)
			(xy 204.805026 -303.266602) (xy 204.796314 -303.256414) (xy 204.774592 -303.240716) (xy 204.749535 -303.231205)
			(xy 204.722868 -303.228533) (xy 204.696422 -303.232885) (xy 204.672017 -303.243962) (xy 204.65133 -303.261001)
			(xy 204.643228 -303.271682) (xy 204.627819 -303.292584) (xy 204.592244 -303.330412) (xy 204.551867 -303.363066)
			(xy 204.507434 -303.389942) (xy 204.459767 -303.410543) (xy 204.409746 -303.42449) (xy 204.358296 -303.431523)
			(xy 204.332332 -303.431956) (xy 204.305081 -303.431399) (xy 204.251133 -303.423647) (xy 204.198838 -303.408295)
			(xy 204.14926 -303.385658) (xy 204.103409 -303.356194) (xy 204.062218 -303.320505) (xy 204.026525 -303.279317)
			(xy 203.997058 -303.233468) (xy 203.974416 -303.183892) (xy 203.95906 -303.131598) (xy 203.951303 -303.077651)
			(xy 199.309984 -303.077651) (xy 199.30668 -303.097978) (xy 199.291096 -303.144659) (xy 199.268225 -303.188236)
			(xy 199.23866 -303.22758) (xy 199.203167 -303.261672) (xy 199.162664 -303.289628) (xy 199.118202 -303.310726)
			(xy 199.070931 -303.324418) (xy 199.022076 -303.33035) (xy 198.972901 -303.328369) (xy 198.924682 -303.318525)
			(xy 198.878666 -303.301073) (xy 198.836045 -303.276466) (xy 198.797924 -303.245341) (xy 198.765289 -303.208504)
			(xy 198.738986 -303.166908) (xy 198.719695 -303.121632) (xy 198.707918 -303.073848) (xy 198.703958 -303.024794)
			(xy 198.38035 -303.024794) (xy 198.379855 -303.049401) (xy 198.37196 -303.097978) (xy 198.356376 -303.144659)
			(xy 198.333505 -303.188236) (xy 198.30394 -303.22758) (xy 198.268447 -303.261672) (xy 198.227944 -303.289628)
			(xy 198.183482 -303.310726) (xy 198.136211 -303.324418) (xy 198.087356 -303.33035) (xy 198.038181 -303.328369)
			(xy 197.989962 -303.318525) (xy 197.943946 -303.301073) (xy 197.901325 -303.276466) (xy 197.863204 -303.245341)
			(xy 197.830569 -303.208504) (xy 197.804266 -303.166908) (xy 197.784975 -303.121632) (xy 197.773198 -303.073848)
			(xy 197.769238 -303.024794) (xy 197.43039 -303.024794) (xy 197.429895 -303.049401) (xy 197.422 -303.097978)
			(xy 197.406416 -303.144659) (xy 197.383545 -303.188236) (xy 197.35398 -303.22758) (xy 197.318487 -303.261672)
			(xy 197.277984 -303.289628) (xy 197.233522 -303.310726) (xy 197.186251 -303.324418) (xy 197.137396 -303.33035)
			(xy 197.088221 -303.328369) (xy 197.040002 -303.318525) (xy 196.993986 -303.301073) (xy 196.951365 -303.276466)
			(xy 196.913244 -303.245341) (xy 196.880609 -303.208504) (xy 196.854306 -303.166908) (xy 196.835015 -303.121632)
			(xy 196.823238 -303.073848) (xy 196.819278 -303.024794) (xy 196.480176 -303.024794) (xy 196.479681 -303.049401)
			(xy 196.471786 -303.097978) (xy 196.456202 -303.144659) (xy 196.433331 -303.188236) (xy 196.403766 -303.22758)
			(xy 196.368273 -303.261672) (xy 196.32777 -303.289628) (xy 196.283308 -303.310726) (xy 196.236037 -303.324418)
			(xy 196.187182 -303.33035) (xy 196.138007 -303.328369) (xy 196.089788 -303.318525) (xy 196.043772 -303.301073)
			(xy 196.001151 -303.276466) (xy 195.96303 -303.245341) (xy 195.930395 -303.208504) (xy 195.904092 -303.166908)
			(xy 195.884801 -303.121632) (xy 195.873024 -303.073848) (xy 195.869064 -303.024794) (xy 195.530164 -303.024794)
			(xy 195.530613 -303.033078) (xy 195.525246 -303.082427) (xy 195.511967 -303.130259) (xy 195.491124 -303.175311)
			(xy 195.463267 -303.216398) (xy 195.429131 -303.252437) (xy 195.389613 -303.282479) (xy 195.345756 -303.305732)
			(xy 195.298714 -303.321583) (xy 195.249728 -303.329616) (xy 195.224908 -303.330102) (xy 195.210725 -303.329924)
			(xy 195.182485 -303.327253) (xy 195.16852 -303.324768) (xy 195.15455 -303.322643) (xy 195.126423 -303.325217)
			(xy 195.100078 -303.335401) (xy 195.077533 -303.352414) (xy 195.060514 -303.374955) (xy 195.050323 -303.401296)
			(xy 195.047741 -303.429423) (xy 195.049902 -303.443386) (xy 195.052373 -303.457353) (xy 195.055048 -303.485592)
			(xy 195.055236 -303.499774) (xy 195.05475 -303.524598) (xy 195.046722 -303.573592) (xy 195.030873 -303.620642)
			(xy 195.00762 -303.664508) (xy 194.977577 -303.704034) (xy 194.941535 -303.738179) (xy 194.900443 -303.766043)
			(xy 194.855385 -303.786891) (xy 194.807547 -303.800175) (xy 194.758191 -303.805545) (xy 194.708616 -303.802858)
			(xy 194.660128 -303.792186) (xy 194.614007 -303.77381) (xy 194.571465 -303.748214) (xy 194.533626 -303.716073)
			(xy 194.501485 -303.678233) (xy 194.475889 -303.635692) (xy 194.457513 -303.58957) (xy 194.446842 -303.541082)
			(xy 194.444155 -303.491507) (xy 192.20519 -303.491507) (xy 192.205356 -303.499774) (xy 192.204861 -303.524381)
			(xy 192.196966 -303.572958) (xy 192.181382 -303.619639) (xy 192.158511 -303.663216) (xy 192.128946 -303.70256)
			(xy 192.093453 -303.736652) (xy 192.05295 -303.764608) (xy 192.008488 -303.785706) (xy 191.961217 -303.799398)
			(xy 191.912362 -303.80533) (xy 191.863187 -303.803349) (xy 191.814968 -303.793505) (xy 191.768952 -303.776053)
			(xy 191.726331 -303.751446) (xy 191.68821 -303.720321) (xy 191.655575 -303.683484) (xy 191.629272 -303.641888)
			(xy 191.609981 -303.596612) (xy 191.598204 -303.548828) (xy 191.594244 -303.499774) (xy 191.255396 -303.499774)
			(xy 191.254901 -303.524381) (xy 191.247006 -303.572958) (xy 191.231422 -303.619639) (xy 191.208551 -303.663216)
			(xy 191.178986 -303.70256) (xy 191.143493 -303.736652) (xy 191.10299 -303.764608) (xy 191.058528 -303.785706)
			(xy 191.011257 -303.799398) (xy 190.962402 -303.80533) (xy 190.913227 -303.803349) (xy 190.865008 -303.793505)
			(xy 190.818992 -303.776053) (xy 190.776371 -303.751446) (xy 190.73825 -303.720321) (xy 190.705615 -303.683484)
			(xy 190.679312 -303.641888) (xy 190.660021 -303.596612) (xy 190.648244 -303.548828) (xy 190.644284 -303.499774)
			(xy 190.305182 -303.499774) (xy 190.304687 -303.524381) (xy 190.296792 -303.572958) (xy 190.281208 -303.619639)
			(xy 190.258337 -303.663216) (xy 190.228772 -303.70256) (xy 190.193279 -303.736652) (xy 190.152776 -303.764608)
			(xy 190.108314 -303.785706) (xy 190.061043 -303.799398) (xy 190.012188 -303.80533) (xy 189.963013 -303.803349)
			(xy 189.914794 -303.793505) (xy 189.868778 -303.776053) (xy 189.826157 -303.751446) (xy 189.788036 -303.720321)
			(xy 189.755401 -303.683484) (xy 189.729098 -303.641888) (xy 189.709807 -303.596612) (xy 189.69803 -303.548828)
			(xy 189.69407 -303.499774) (xy 164.790882 -303.499774) (xy 164.790882 -303.57318) (xy 164.791342 -303.582816)
			(xy 164.798512 -303.600709) (xy 164.804852 -303.607978) (xy 164.820092 -303.62398) (xy 164.82695 -303.631346)
			(xy 164.850318 -303.64176) (xy 164.854636 -303.64303) (xy 164.86505 -303.646332) (xy 164.869622 -303.647094)
			(xy 164.895695 -303.651171) (xy 164.946185 -303.666519) (xy 164.993597 -303.689688) (xy 165.036728 -303.720092)
			(xy 165.074485 -303.756959) (xy 165.105908 -303.799353) (xy 165.130202 -303.846199) (xy 165.146748 -303.896308)
			(xy 165.155129 -303.948409) (xy 165.155129 -303.974754) (xy 165.469074 -303.974754) (xy 165.473034 -303.9257)
			(xy 165.484811 -303.877916) (xy 165.504102 -303.83264) (xy 165.530405 -303.791044) (xy 165.56304 -303.754207)
			(xy 165.601161 -303.723082) (xy 165.643782 -303.698475) (xy 165.689798 -303.681023) (xy 165.738017 -303.671179)
			(xy 165.787192 -303.669198) (xy 165.836047 -303.67513) (xy 165.883318 -303.688822) (xy 165.92778 -303.70992)
			(xy 165.968283 -303.737876) (xy 166.003776 -303.771968) (xy 166.033341 -303.811312) (xy 166.056212 -303.854889)
			(xy 166.071796 -303.90157) (xy 166.079691 -303.950147) (xy 166.080186 -303.974754) (xy 166.419288 -303.974754)
			(xy 166.423248 -303.9257) (xy 166.435025 -303.877916) (xy 166.454316 -303.83264) (xy 166.480619 -303.791044)
			(xy 166.513254 -303.754207) (xy 166.551375 -303.723082) (xy 166.593996 -303.698475) (xy 166.640012 -303.681023)
			(xy 166.688231 -303.671179) (xy 166.737406 -303.669198) (xy 166.786261 -303.67513) (xy 166.833532 -303.688822)
			(xy 166.877994 -303.70992) (xy 166.918497 -303.737876) (xy 166.95399 -303.771968) (xy 166.983555 -303.811312)
			(xy 167.006426 -303.854889) (xy 167.02201 -303.90157) (xy 167.029905 -303.950147) (xy 167.0304 -303.974754)
			(xy 167.369248 -303.974754) (xy 167.373208 -303.9257) (xy 167.384985 -303.877916) (xy 167.404276 -303.83264)
			(xy 167.430579 -303.791044) (xy 167.463214 -303.754207) (xy 167.501335 -303.723082) (xy 167.543956 -303.698475)
			(xy 167.589972 -303.681023) (xy 167.638191 -303.671179) (xy 167.687366 -303.669198) (xy 167.736221 -303.67513)
			(xy 167.783492 -303.688822) (xy 167.827954 -303.70992) (xy 167.868457 -303.737876) (xy 167.90395 -303.771968)
			(xy 167.933515 -303.811312) (xy 167.956386 -303.854889) (xy 167.97197 -303.90157) (xy 167.979865 -303.950147)
			(xy 167.98036 -303.974754) (xy 168.319208 -303.974754) (xy 168.323168 -303.9257) (xy 168.334945 -303.877916)
			(xy 168.354236 -303.83264) (xy 168.380539 -303.791044) (xy 168.413174 -303.754207) (xy 168.451295 -303.723082)
			(xy 168.493916 -303.698475) (xy 168.539932 -303.681023) (xy 168.588151 -303.671179) (xy 168.637326 -303.669198)
			(xy 168.686181 -303.67513) (xy 168.733452 -303.688822) (xy 168.777914 -303.70992) (xy 168.818417 -303.737876)
			(xy 168.85391 -303.771968) (xy 168.883475 -303.811312) (xy 168.906346 -303.854889) (xy 168.92193 -303.90157)
			(xy 168.929825 -303.950147) (xy 168.93032 -303.974754) (xy 169.269168 -303.974754) (xy 169.273128 -303.9257)
			(xy 169.284905 -303.877916) (xy 169.304196 -303.83264) (xy 169.330499 -303.791044) (xy 169.363134 -303.754207)
			(xy 169.401255 -303.723082) (xy 169.443876 -303.698475) (xy 169.489892 -303.681023) (xy 169.538111 -303.671179)
			(xy 169.587286 -303.669198) (xy 169.636141 -303.67513) (xy 169.683412 -303.688822) (xy 169.727874 -303.70992)
			(xy 169.768377 -303.737876) (xy 169.80387 -303.771968) (xy 169.833435 -303.811312) (xy 169.856306 -303.854889)
			(xy 169.87189 -303.90157) (xy 169.879785 -303.950147) (xy 169.88028 -303.974754) (xy 170.219128 -303.974754)
			(xy 170.223088 -303.9257) (xy 170.234865 -303.877916) (xy 170.254156 -303.83264) (xy 170.280459 -303.791044)
			(xy 170.313094 -303.754207) (xy 170.351215 -303.723082) (xy 170.393836 -303.698475) (xy 170.439852 -303.681023)
			(xy 170.488071 -303.671179) (xy 170.537246 -303.669198) (xy 170.586101 -303.67513) (xy 170.633372 -303.688822)
			(xy 170.677834 -303.70992) (xy 170.718337 -303.737876) (xy 170.75383 -303.771968) (xy 170.783395 -303.811312)
			(xy 170.806266 -303.854889) (xy 170.82185 -303.90157) (xy 170.829745 -303.950147) (xy 170.83024 -303.974754)
			(xy 171.169088 -303.974754) (xy 171.173048 -303.9257) (xy 171.184825 -303.877916) (xy 171.204116 -303.83264)
			(xy 171.230419 -303.791044) (xy 171.263054 -303.754207) (xy 171.301175 -303.723082) (xy 171.343796 -303.698475)
			(xy 171.389812 -303.681023) (xy 171.438031 -303.671179) (xy 171.487206 -303.669198) (xy 171.536061 -303.67513)
			(xy 171.583332 -303.688822) (xy 171.627794 -303.70992) (xy 171.668297 -303.737876) (xy 171.70379 -303.771968)
			(xy 171.733355 -303.811312) (xy 171.756226 -303.854889) (xy 171.77181 -303.90157) (xy 171.779705 -303.950147)
			(xy 171.7802 -303.974754) (xy 172.119048 -303.974754) (xy 172.123008 -303.9257) (xy 172.134785 -303.877916)
			(xy 172.154076 -303.83264) (xy 172.180379 -303.791044) (xy 172.213014 -303.754207) (xy 172.251135 -303.723082)
			(xy 172.293756 -303.698475) (xy 172.339772 -303.681023) (xy 172.387991 -303.671179) (xy 172.437166 -303.669198)
			(xy 172.486021 -303.67513) (xy 172.533292 -303.688822) (xy 172.577754 -303.70992) (xy 172.618257 -303.737876)
			(xy 172.65375 -303.771968) (xy 172.683315 -303.811312) (xy 172.706186 -303.854889) (xy 172.72177 -303.90157)
			(xy 172.729665 -303.950147) (xy 172.73016 -303.974754) (xy 173.069262 -303.974754) (xy 173.073222 -303.9257)
			(xy 173.084999 -303.877916) (xy 173.10429 -303.83264) (xy 173.130593 -303.791044) (xy 173.163228 -303.754207)
			(xy 173.201349 -303.723082) (xy 173.24397 -303.698475) (xy 173.289986 -303.681023) (xy 173.338205 -303.671179)
			(xy 173.38738 -303.669198) (xy 173.436235 -303.67513) (xy 173.483506 -303.688822) (xy 173.527968 -303.70992)
			(xy 173.568471 -303.737876) (xy 173.603964 -303.771968) (xy 173.633529 -303.811312) (xy 173.6564 -303.854889)
			(xy 173.671984 -303.90157) (xy 173.679879 -303.950147) (xy 173.680374 -303.974754) (xy 174.019222 -303.974754)
			(xy 174.023182 -303.9257) (xy 174.034959 -303.877916) (xy 174.05425 -303.83264) (xy 174.080553 -303.791044)
			(xy 174.113188 -303.754207) (xy 174.151309 -303.723082) (xy 174.19393 -303.698475) (xy 174.239946 -303.681023)
			(xy 174.288165 -303.671179) (xy 174.33734 -303.669198) (xy 174.386195 -303.67513) (xy 174.433466 -303.688822)
			(xy 174.477928 -303.70992) (xy 174.518431 -303.737876) (xy 174.553924 -303.771968) (xy 174.583489 -303.811312)
			(xy 174.60636 -303.854889) (xy 174.621944 -303.90157) (xy 174.629839 -303.950147) (xy 174.630334 -303.974754)
			(xy 175.919142 -303.974754) (xy 175.923102 -303.9257) (xy 175.934879 -303.877916) (xy 175.95417 -303.83264)
			(xy 175.980473 -303.791044) (xy 176.013108 -303.754207) (xy 176.051229 -303.723082) (xy 176.09385 -303.698475)
			(xy 176.139866 -303.681023) (xy 176.188085 -303.671179) (xy 176.23726 -303.669198) (xy 176.286115 -303.67513)
			(xy 176.333386 -303.688822) (xy 176.377848 -303.70992) (xy 176.418351 -303.737876) (xy 176.453844 -303.771968)
			(xy 176.483409 -303.811312) (xy 176.50628 -303.854889) (xy 176.521864 -303.90157) (xy 176.529759 -303.950147)
			(xy 176.530254 -303.974754) (xy 176.869102 -303.974754) (xy 176.873062 -303.9257) (xy 176.884839 -303.877916)
			(xy 176.90413 -303.83264) (xy 176.930433 -303.791044) (xy 176.963068 -303.754207) (xy 177.001189 -303.723082)
			(xy 177.04381 -303.698475) (xy 177.089826 -303.681023) (xy 177.138045 -303.671179) (xy 177.18722 -303.669198)
			(xy 177.236075 -303.67513) (xy 177.283346 -303.688822) (xy 177.327808 -303.70992) (xy 177.368311 -303.737876)
			(xy 177.403804 -303.771968) (xy 177.433369 -303.811312) (xy 177.45624 -303.854889) (xy 177.471824 -303.90157)
			(xy 177.479719 -303.950147) (xy 177.480214 -303.974754) (xy 177.819062 -303.974754) (xy 177.823022 -303.9257)
			(xy 177.834799 -303.877916) (xy 177.85409 -303.83264) (xy 177.880393 -303.791044) (xy 177.913028 -303.754207)
			(xy 177.951149 -303.723082) (xy 177.99377 -303.698475) (xy 178.039786 -303.681023) (xy 178.088005 -303.671179)
			(xy 178.13718 -303.669198) (xy 178.186035 -303.67513) (xy 178.233306 -303.688822) (xy 178.277768 -303.70992)
			(xy 178.318271 -303.737876) (xy 178.353764 -303.771968) (xy 178.383329 -303.811312) (xy 178.4062 -303.854889)
			(xy 178.421784 -303.90157) (xy 178.429679 -303.950147) (xy 178.430174 -303.974754) (xy 178.769276 -303.974754)
			(xy 178.773236 -303.9257) (xy 178.785013 -303.877916) (xy 178.804304 -303.83264) (xy 178.830607 -303.791044)
			(xy 178.863242 -303.754207) (xy 178.901363 -303.723082) (xy 178.943984 -303.698475) (xy 178.99 -303.681023)
			(xy 179.038219 -303.671179) (xy 179.087394 -303.669198) (xy 179.136249 -303.67513) (xy 179.18352 -303.688822)
			(xy 179.227982 -303.70992) (xy 179.268485 -303.737876) (xy 179.303978 -303.771968) (xy 179.333543 -303.811312)
			(xy 179.356414 -303.854889) (xy 179.371998 -303.90157) (xy 179.379893 -303.950147) (xy 179.380388 -303.974754)
			(xy 179.719236 -303.974754) (xy 179.723196 -303.9257) (xy 179.734973 -303.877916) (xy 179.754264 -303.83264)
			(xy 179.780567 -303.791044) (xy 179.813202 -303.754207) (xy 179.851323 -303.723082) (xy 179.893944 -303.698475)
			(xy 179.93996 -303.681023) (xy 179.988179 -303.671179) (xy 180.037354 -303.669198) (xy 180.086209 -303.67513)
			(xy 180.13348 -303.688822) (xy 180.177942 -303.70992) (xy 180.218445 -303.737876) (xy 180.253938 -303.771968)
			(xy 180.283503 -303.811312) (xy 180.306374 -303.854889) (xy 180.321958 -303.90157) (xy 180.329853 -303.950147)
			(xy 180.330348 -303.974754) (xy 180.669196 -303.974754) (xy 180.673156 -303.9257) (xy 180.684933 -303.877916)
			(xy 180.704224 -303.83264) (xy 180.730527 -303.791044) (xy 180.763162 -303.754207) (xy 180.801283 -303.723082)
			(xy 180.843904 -303.698475) (xy 180.88992 -303.681023) (xy 180.938139 -303.671179) (xy 180.987314 -303.669198)
			(xy 181.036169 -303.67513) (xy 181.08344 -303.688822) (xy 181.127902 -303.70992) (xy 181.168405 -303.737876)
			(xy 181.203898 -303.771968) (xy 181.233463 -303.811312) (xy 181.256334 -303.854889) (xy 181.271918 -303.90157)
			(xy 181.279813 -303.950147) (xy 181.280308 -303.974754) (xy 181.619156 -303.974754) (xy 181.623116 -303.9257)
			(xy 181.634893 -303.877916) (xy 181.654184 -303.83264) (xy 181.680487 -303.791044) (xy 181.713122 -303.754207)
			(xy 181.751243 -303.723082) (xy 181.793864 -303.698475) (xy 181.83988 -303.681023) (xy 181.888099 -303.671179)
			(xy 181.937274 -303.669198) (xy 181.986129 -303.67513) (xy 182.0334 -303.688822) (xy 182.077862 -303.70992)
			(xy 182.118365 -303.737876) (xy 182.153858 -303.771968) (xy 182.183423 -303.811312) (xy 182.206294 -303.854889)
			(xy 182.221878 -303.90157) (xy 182.229773 -303.950147) (xy 182.230268 -303.974754) (xy 182.569116 -303.974754)
			(xy 182.573076 -303.9257) (xy 182.584853 -303.877916) (xy 182.604144 -303.83264) (xy 182.630447 -303.791044)
			(xy 182.663082 -303.754207) (xy 182.701203 -303.723082) (xy 182.743824 -303.698475) (xy 182.78984 -303.681023)
			(xy 182.838059 -303.671179) (xy 182.887234 -303.669198) (xy 182.936089 -303.67513) (xy 182.98336 -303.688822)
			(xy 183.027822 -303.70992) (xy 183.068325 -303.737876) (xy 183.103818 -303.771968) (xy 183.133383 -303.811312)
			(xy 183.156254 -303.854889) (xy 183.171838 -303.90157) (xy 183.179733 -303.950147) (xy 183.180228 -303.974754)
			(xy 183.519076 -303.974754) (xy 183.523036 -303.9257) (xy 183.534813 -303.877916) (xy 183.554104 -303.83264)
			(xy 183.580407 -303.791044) (xy 183.613042 -303.754207) (xy 183.651163 -303.723082) (xy 183.693784 -303.698475)
			(xy 183.7398 -303.681023) (xy 183.788019 -303.671179) (xy 183.837194 -303.669198) (xy 183.886049 -303.67513)
			(xy 183.93332 -303.688822) (xy 183.977782 -303.70992) (xy 184.018285 -303.737876) (xy 184.053778 -303.771968)
			(xy 184.083343 -303.811312) (xy 184.106214 -303.854889) (xy 184.121798 -303.90157) (xy 184.129693 -303.950147)
			(xy 184.130091 -303.969928) (xy 184.474116 -303.969928) (xy 184.478076 -303.920874) (xy 184.489853 -303.87309)
			(xy 184.509144 -303.827814) (xy 184.535447 -303.786218) (xy 184.568082 -303.749381) (xy 184.606203 -303.718256)
			(xy 184.648824 -303.693649) (xy 184.69484 -303.676197) (xy 184.743059 -303.666353) (xy 184.792234 -303.664372)
			(xy 184.841089 -303.670304) (xy 184.88836 -303.683996) (xy 184.932822 -303.705094) (xy 184.973325 -303.73305)
			(xy 185.008818 -303.767142) (xy 185.038383 -303.806486) (xy 185.061254 -303.850063) (xy 185.076838 -303.896744)
			(xy 185.084733 -303.945321) (xy 185.085228 -303.969928) (xy 185.085131 -303.974754) (xy 185.41925 -303.974754)
			(xy 185.42321 -303.9257) (xy 185.434987 -303.877916) (xy 185.454278 -303.83264) (xy 185.480581 -303.791044)
			(xy 185.513216 -303.754207) (xy 185.551337 -303.723082) (xy 185.593958 -303.698475) (xy 185.639974 -303.681023)
			(xy 185.688193 -303.671179) (xy 185.737368 -303.669198) (xy 185.786223 -303.67513) (xy 185.833494 -303.688822)
			(xy 185.877956 -303.70992) (xy 185.918459 -303.737876) (xy 185.953952 -303.771968) (xy 185.983517 -303.811312)
			(xy 186.006388 -303.854889) (xy 186.021972 -303.90157) (xy 186.029867 -303.950147) (xy 186.030362 -303.974754)
			(xy 186.36921 -303.974754) (xy 186.37317 -303.9257) (xy 186.384947 -303.877916) (xy 186.404238 -303.83264)
			(xy 186.430541 -303.791044) (xy 186.463176 -303.754207) (xy 186.501297 -303.723082) (xy 186.543918 -303.698475)
			(xy 186.589934 -303.681023) (xy 186.638153 -303.671179) (xy 186.687328 -303.669198) (xy 186.736183 -303.67513)
			(xy 186.783454 -303.688822) (xy 186.827916 -303.70992) (xy 186.868419 -303.737876) (xy 186.903912 -303.771968)
			(xy 186.933477 -303.811312) (xy 186.956348 -303.854889) (xy 186.971932 -303.90157) (xy 186.979827 -303.950147)
			(xy 186.980322 -303.974754) (xy 187.31917 -303.974754) (xy 187.32313 -303.9257) (xy 187.334907 -303.877916)
			(xy 187.354198 -303.83264) (xy 187.380501 -303.791044) (xy 187.413136 -303.754207) (xy 187.451257 -303.723082)
			(xy 187.493878 -303.698475) (xy 187.539894 -303.681023) (xy 187.588113 -303.671179) (xy 187.637288 -303.669198)
			(xy 187.686143 -303.67513) (xy 187.733414 -303.688822) (xy 187.777876 -303.70992) (xy 187.818379 -303.737876)
			(xy 187.853872 -303.771968) (xy 187.883437 -303.811312) (xy 187.906308 -303.854889) (xy 187.921892 -303.90157)
			(xy 187.929787 -303.950147) (xy 187.930282 -303.974754) (xy 188.26913 -303.974754) (xy 188.27309 -303.9257)
			(xy 188.284867 -303.877916) (xy 188.304158 -303.83264) (xy 188.330461 -303.791044) (xy 188.363096 -303.754207)
			(xy 188.401217 -303.723082) (xy 188.443838 -303.698475) (xy 188.489854 -303.681023) (xy 188.538073 -303.671179)
			(xy 188.587248 -303.669198) (xy 188.636103 -303.67513) (xy 188.683374 -303.688822) (xy 188.727836 -303.70992)
			(xy 188.768339 -303.737876) (xy 188.803832 -303.771968) (xy 188.833397 -303.811312) (xy 188.856268 -303.854889)
			(xy 188.871852 -303.90157) (xy 188.879747 -303.950147) (xy 188.880242 -303.974754) (xy 188.879747 -303.999361)
			(xy 188.871852 -304.047938) (xy 188.856268 -304.094619) (xy 188.833397 -304.138196) (xy 188.803832 -304.17754)
			(xy 188.768339 -304.211632) (xy 188.727836 -304.239588) (xy 188.683374 -304.260686) (xy 188.636103 -304.274378)
			(xy 188.587248 -304.28031) (xy 188.538073 -304.278329) (xy 188.489854 -304.268485) (xy 188.443838 -304.251033)
			(xy 188.401217 -304.226426) (xy 188.363096 -304.195301) (xy 188.330461 -304.158464) (xy 188.304158 -304.116868)
			(xy 188.284867 -304.071592) (xy 188.27309 -304.023808) (xy 188.26913 -303.974754) (xy 187.930282 -303.974754)
			(xy 187.929787 -303.999361) (xy 187.921892 -304.047938) (xy 187.906308 -304.094619) (xy 187.883437 -304.138196)
			(xy 187.853872 -304.17754) (xy 187.818379 -304.211632) (xy 187.777876 -304.239588) (xy 187.733414 -304.260686)
			(xy 187.686143 -304.274378) (xy 187.637288 -304.28031) (xy 187.588113 -304.278329) (xy 187.539894 -304.268485)
			(xy 187.493878 -304.251033) (xy 187.451257 -304.226426) (xy 187.413136 -304.195301) (xy 187.380501 -304.158464)
			(xy 187.354198 -304.116868) (xy 187.334907 -304.071592) (xy 187.32313 -304.023808) (xy 187.31917 -303.974754)
			(xy 186.980322 -303.974754) (xy 186.979827 -303.999361) (xy 186.971932 -304.047938) (xy 186.956348 -304.094619)
			(xy 186.933477 -304.138196) (xy 186.903912 -304.17754) (xy 186.868419 -304.211632) (xy 186.827916 -304.239588)
			(xy 186.783454 -304.260686) (xy 186.736183 -304.274378) (xy 186.687328 -304.28031) (xy 186.638153 -304.278329)
			(xy 186.589934 -304.268485) (xy 186.543918 -304.251033) (xy 186.501297 -304.226426) (xy 186.463176 -304.195301)
			(xy 186.430541 -304.158464) (xy 186.404238 -304.116868) (xy 186.384947 -304.071592) (xy 186.37317 -304.023808)
			(xy 186.36921 -303.974754) (xy 186.030362 -303.974754) (xy 186.029867 -303.999361) (xy 186.021972 -304.047938)
			(xy 186.006388 -304.094619) (xy 185.983517 -304.138196) (xy 185.953952 -304.17754) (xy 185.918459 -304.211632)
			(xy 185.877956 -304.239588) (xy 185.833494 -304.260686) (xy 185.786223 -304.274378) (xy 185.737368 -304.28031)
			(xy 185.688193 -304.278329) (xy 185.639974 -304.268485) (xy 185.593958 -304.251033) (xy 185.551337 -304.226426)
			(xy 185.513216 -304.195301) (xy 185.480581 -304.158464) (xy 185.454278 -304.116868) (xy 185.434987 -304.071592)
			(xy 185.42321 -304.023808) (xy 185.41925 -303.974754) (xy 185.085131 -303.974754) (xy 185.084733 -303.994535)
			(xy 185.076838 -304.043112) (xy 185.061254 -304.089793) (xy 185.038383 -304.13337) (xy 185.008818 -304.172714)
			(xy 184.973325 -304.206806) (xy 184.932822 -304.234762) (xy 184.88836 -304.25586) (xy 184.841089 -304.269552)
			(xy 184.792234 -304.275484) (xy 184.743059 -304.273503) (xy 184.69484 -304.263659) (xy 184.648824 -304.246207)
			(xy 184.606203 -304.2216) (xy 184.568082 -304.190475) (xy 184.535447 -304.153638) (xy 184.509144 -304.112042)
			(xy 184.489853 -304.066766) (xy 184.478076 -304.018982) (xy 184.474116 -303.969928) (xy 184.130091 -303.969928)
			(xy 184.130188 -303.974754) (xy 184.129693 -303.999361) (xy 184.121798 -304.047938) (xy 184.106214 -304.094619)
			(xy 184.083343 -304.138196) (xy 184.053778 -304.17754) (xy 184.018285 -304.211632) (xy 183.977782 -304.239588)
			(xy 183.93332 -304.260686) (xy 183.886049 -304.274378) (xy 183.837194 -304.28031) (xy 183.788019 -304.278329)
			(xy 183.7398 -304.268485) (xy 183.693784 -304.251033) (xy 183.651163 -304.226426) (xy 183.613042 -304.195301)
			(xy 183.580407 -304.158464) (xy 183.554104 -304.116868) (xy 183.534813 -304.071592) (xy 183.523036 -304.023808)
			(xy 183.519076 -303.974754) (xy 183.180228 -303.974754) (xy 183.179733 -303.999361) (xy 183.171838 -304.047938)
			(xy 183.156254 -304.094619) (xy 183.133383 -304.138196) (xy 183.103818 -304.17754) (xy 183.068325 -304.211632)
			(xy 183.027822 -304.239588) (xy 182.98336 -304.260686) (xy 182.936089 -304.274378) (xy 182.887234 -304.28031)
			(xy 182.838059 -304.278329) (xy 182.78984 -304.268485) (xy 182.743824 -304.251033) (xy 182.701203 -304.226426)
			(xy 182.663082 -304.195301) (xy 182.630447 -304.158464) (xy 182.604144 -304.116868) (xy 182.584853 -304.071592)
			(xy 182.573076 -304.023808) (xy 182.569116 -303.974754) (xy 182.230268 -303.974754) (xy 182.229773 -303.999361)
			(xy 182.221878 -304.047938) (xy 182.206294 -304.094619) (xy 182.183423 -304.138196) (xy 182.153858 -304.17754)
			(xy 182.118365 -304.211632) (xy 182.077862 -304.239588) (xy 182.0334 -304.260686) (xy 181.986129 -304.274378)
			(xy 181.937274 -304.28031) (xy 181.888099 -304.278329) (xy 181.83988 -304.268485) (xy 181.793864 -304.251033)
			(xy 181.751243 -304.226426) (xy 181.713122 -304.195301) (xy 181.680487 -304.158464) (xy 181.654184 -304.116868)
			(xy 181.634893 -304.071592) (xy 181.623116 -304.023808) (xy 181.619156 -303.974754) (xy 181.280308 -303.974754)
			(xy 181.279813 -303.999361) (xy 181.271918 -304.047938) (xy 181.256334 -304.094619) (xy 181.233463 -304.138196)
			(xy 181.203898 -304.17754) (xy 181.168405 -304.211632) (xy 181.127902 -304.239588) (xy 181.08344 -304.260686)
			(xy 181.036169 -304.274378) (xy 180.987314 -304.28031) (xy 180.938139 -304.278329) (xy 180.88992 -304.268485)
			(xy 180.843904 -304.251033) (xy 180.801283 -304.226426) (xy 180.763162 -304.195301) (xy 180.730527 -304.158464)
			(xy 180.704224 -304.116868) (xy 180.684933 -304.071592) (xy 180.673156 -304.023808) (xy 180.669196 -303.974754)
			(xy 180.330348 -303.974754) (xy 180.329853 -303.999361) (xy 180.321958 -304.047938) (xy 180.306374 -304.094619)
			(xy 180.283503 -304.138196) (xy 180.253938 -304.17754) (xy 180.218445 -304.211632) (xy 180.177942 -304.239588)
			(xy 180.13348 -304.260686) (xy 180.086209 -304.274378) (xy 180.037354 -304.28031) (xy 179.988179 -304.278329)
			(xy 179.93996 -304.268485) (xy 179.893944 -304.251033) (xy 179.851323 -304.226426) (xy 179.813202 -304.195301)
			(xy 179.780567 -304.158464) (xy 179.754264 -304.116868) (xy 179.734973 -304.071592) (xy 179.723196 -304.023808)
			(xy 179.719236 -303.974754) (xy 179.380388 -303.974754) (xy 179.379893 -303.999361) (xy 179.371998 -304.047938)
			(xy 179.356414 -304.094619) (xy 179.333543 -304.138196) (xy 179.303978 -304.17754) (xy 179.268485 -304.211632)
			(xy 179.227982 -304.239588) (xy 179.18352 -304.260686) (xy 179.136249 -304.274378) (xy 179.087394 -304.28031)
			(xy 179.038219 -304.278329) (xy 178.99 -304.268485) (xy 178.943984 -304.251033) (xy 178.901363 -304.226426)
			(xy 178.863242 -304.195301) (xy 178.830607 -304.158464) (xy 178.804304 -304.116868) (xy 178.785013 -304.071592)
			(xy 178.773236 -304.023808) (xy 178.769276 -303.974754) (xy 178.430174 -303.974754) (xy 178.429679 -303.999361)
			(xy 178.421784 -304.047938) (xy 178.4062 -304.094619) (xy 178.383329 -304.138196) (xy 178.353764 -304.17754)
			(xy 178.318271 -304.211632) (xy 178.277768 -304.239588) (xy 178.233306 -304.260686) (xy 178.186035 -304.274378)
			(xy 178.13718 -304.28031) (xy 178.088005 -304.278329) (xy 178.039786 -304.268485) (xy 177.99377 -304.251033)
			(xy 177.951149 -304.226426) (xy 177.913028 -304.195301) (xy 177.880393 -304.158464) (xy 177.85409 -304.116868)
			(xy 177.834799 -304.071592) (xy 177.823022 -304.023808) (xy 177.819062 -303.974754) (xy 177.480214 -303.974754)
			(xy 177.479719 -303.999361) (xy 177.471824 -304.047938) (xy 177.45624 -304.094619) (xy 177.433369 -304.138196)
			(xy 177.403804 -304.17754) (xy 177.368311 -304.211632) (xy 177.327808 -304.239588) (xy 177.283346 -304.260686)
			(xy 177.236075 -304.274378) (xy 177.18722 -304.28031) (xy 177.138045 -304.278329) (xy 177.089826 -304.268485)
			(xy 177.04381 -304.251033) (xy 177.001189 -304.226426) (xy 176.963068 -304.195301) (xy 176.930433 -304.158464)
			(xy 176.90413 -304.116868) (xy 176.884839 -304.071592) (xy 176.873062 -304.023808) (xy 176.869102 -303.974754)
			(xy 176.530254 -303.974754) (xy 176.529759 -303.999361) (xy 176.521864 -304.047938) (xy 176.50628 -304.094619)
			(xy 176.483409 -304.138196) (xy 176.453844 -304.17754) (xy 176.418351 -304.211632) (xy 176.377848 -304.239588)
			(xy 176.333386 -304.260686) (xy 176.286115 -304.274378) (xy 176.23726 -304.28031) (xy 176.188085 -304.278329)
			(xy 176.139866 -304.268485) (xy 176.09385 -304.251033) (xy 176.051229 -304.226426) (xy 176.013108 -304.195301)
			(xy 175.980473 -304.158464) (xy 175.95417 -304.116868) (xy 175.934879 -304.071592) (xy 175.923102 -304.023808)
			(xy 175.919142 -303.974754) (xy 174.630334 -303.974754) (xy 174.629839 -303.999361) (xy 174.621944 -304.047938)
			(xy 174.60636 -304.094619) (xy 174.583489 -304.138196) (xy 174.553924 -304.17754) (xy 174.518431 -304.211632)
			(xy 174.477928 -304.239588) (xy 174.433466 -304.260686) (xy 174.386195 -304.274378) (xy 174.33734 -304.28031)
			(xy 174.288165 -304.278329) (xy 174.239946 -304.268485) (xy 174.19393 -304.251033) (xy 174.151309 -304.226426)
			(xy 174.113188 -304.195301) (xy 174.080553 -304.158464) (xy 174.05425 -304.116868) (xy 174.034959 -304.071592)
			(xy 174.023182 -304.023808) (xy 174.019222 -303.974754) (xy 173.680374 -303.974754) (xy 173.679879 -303.999361)
			(xy 173.671984 -304.047938) (xy 173.6564 -304.094619) (xy 173.633529 -304.138196) (xy 173.603964 -304.17754)
			(xy 173.568471 -304.211632) (xy 173.527968 -304.239588) (xy 173.483506 -304.260686) (xy 173.436235 -304.274378)
			(xy 173.38738 -304.28031) (xy 173.338205 -304.278329) (xy 173.289986 -304.268485) (xy 173.24397 -304.251033)
			(xy 173.201349 -304.226426) (xy 173.163228 -304.195301) (xy 173.130593 -304.158464) (xy 173.10429 -304.116868)
			(xy 173.084999 -304.071592) (xy 173.073222 -304.023808) (xy 173.069262 -303.974754) (xy 172.73016 -303.974754)
			(xy 172.729665 -303.999361) (xy 172.72177 -304.047938) (xy 172.706186 -304.094619) (xy 172.683315 -304.138196)
			(xy 172.65375 -304.17754) (xy 172.618257 -304.211632) (xy 172.577754 -304.239588) (xy 172.533292 -304.260686)
			(xy 172.486021 -304.274378) (xy 172.437166 -304.28031) (xy 172.387991 -304.278329) (xy 172.339772 -304.268485)
			(xy 172.293756 -304.251033) (xy 172.251135 -304.226426) (xy 172.213014 -304.195301) (xy 172.180379 -304.158464)
			(xy 172.154076 -304.116868) (xy 172.134785 -304.071592) (xy 172.123008 -304.023808) (xy 172.119048 -303.974754)
			(xy 171.7802 -303.974754) (xy 171.779705 -303.999361) (xy 171.77181 -304.047938) (xy 171.756226 -304.094619)
			(xy 171.733355 -304.138196) (xy 171.70379 -304.17754) (xy 171.668297 -304.211632) (xy 171.627794 -304.239588)
			(xy 171.583332 -304.260686) (xy 171.536061 -304.274378) (xy 171.487206 -304.28031) (xy 171.438031 -304.278329)
			(xy 171.389812 -304.268485) (xy 171.343796 -304.251033) (xy 171.301175 -304.226426) (xy 171.263054 -304.195301)
			(xy 171.230419 -304.158464) (xy 171.204116 -304.116868) (xy 171.184825 -304.071592) (xy 171.173048 -304.023808)
			(xy 171.169088 -303.974754) (xy 170.83024 -303.974754) (xy 170.829745 -303.999361) (xy 170.82185 -304.047938)
			(xy 170.806266 -304.094619) (xy 170.783395 -304.138196) (xy 170.75383 -304.17754) (xy 170.718337 -304.211632)
			(xy 170.677834 -304.239588) (xy 170.633372 -304.260686) (xy 170.586101 -304.274378) (xy 170.537246 -304.28031)
			(xy 170.488071 -304.278329) (xy 170.439852 -304.268485) (xy 170.393836 -304.251033) (xy 170.351215 -304.226426)
			(xy 170.313094 -304.195301) (xy 170.280459 -304.158464) (xy 170.254156 -304.116868) (xy 170.234865 -304.071592)
			(xy 170.223088 -304.023808) (xy 170.219128 -303.974754) (xy 169.88028 -303.974754) (xy 169.879785 -303.999361)
			(xy 169.87189 -304.047938) (xy 169.856306 -304.094619) (xy 169.833435 -304.138196) (xy 169.80387 -304.17754)
			(xy 169.768377 -304.211632) (xy 169.727874 -304.239588) (xy 169.683412 -304.260686) (xy 169.636141 -304.274378)
			(xy 169.587286 -304.28031) (xy 169.538111 -304.278329) (xy 169.489892 -304.268485) (xy 169.443876 -304.251033)
			(xy 169.401255 -304.226426) (xy 169.363134 -304.195301) (xy 169.330499 -304.158464) (xy 169.304196 -304.116868)
			(xy 169.284905 -304.071592) (xy 169.273128 -304.023808) (xy 169.269168 -303.974754) (xy 168.93032 -303.974754)
			(xy 168.929825 -303.999361) (xy 168.92193 -304.047938) (xy 168.906346 -304.094619) (xy 168.883475 -304.138196)
			(xy 168.85391 -304.17754) (xy 168.818417 -304.211632) (xy 168.777914 -304.239588) (xy 168.733452 -304.260686)
			(xy 168.686181 -304.274378) (xy 168.637326 -304.28031) (xy 168.588151 -304.278329) (xy 168.539932 -304.268485)
			(xy 168.493916 -304.251033) (xy 168.451295 -304.226426) (xy 168.413174 -304.195301) (xy 168.380539 -304.158464)
			(xy 168.354236 -304.116868) (xy 168.334945 -304.071592) (xy 168.323168 -304.023808) (xy 168.319208 -303.974754)
			(xy 167.98036 -303.974754) (xy 167.979865 -303.999361) (xy 167.97197 -304.047938) (xy 167.956386 -304.094619)
			(xy 167.933515 -304.138196) (xy 167.90395 -304.17754) (xy 167.868457 -304.211632) (xy 167.827954 -304.239588)
			(xy 167.783492 -304.260686) (xy 167.736221 -304.274378) (xy 167.687366 -304.28031) (xy 167.638191 -304.278329)
			(xy 167.589972 -304.268485) (xy 167.543956 -304.251033) (xy 167.501335 -304.226426) (xy 167.463214 -304.195301)
			(xy 167.430579 -304.158464) (xy 167.404276 -304.116868) (xy 167.384985 -304.071592) (xy 167.373208 -304.023808)
			(xy 167.369248 -303.974754) (xy 167.0304 -303.974754) (xy 167.029905 -303.999361) (xy 167.02201 -304.047938)
			(xy 167.006426 -304.094619) (xy 166.983555 -304.138196) (xy 166.95399 -304.17754) (xy 166.918497 -304.211632)
			(xy 166.877994 -304.239588) (xy 166.833532 -304.260686) (xy 166.786261 -304.274378) (xy 166.737406 -304.28031)
			(xy 166.688231 -304.278329) (xy 166.640012 -304.268485) (xy 166.593996 -304.251033) (xy 166.551375 -304.226426)
			(xy 166.513254 -304.195301) (xy 166.480619 -304.158464) (xy 166.454316 -304.116868) (xy 166.435025 -304.071592)
			(xy 166.423248 -304.023808) (xy 166.419288 -303.974754) (xy 166.080186 -303.974754) (xy 166.079691 -303.999361)
			(xy 166.071796 -304.047938) (xy 166.056212 -304.094619) (xy 166.033341 -304.138196) (xy 166.003776 -304.17754)
			(xy 165.968283 -304.211632) (xy 165.92778 -304.239588) (xy 165.883318 -304.260686) (xy 165.836047 -304.274378)
			(xy 165.787192 -304.28031) (xy 165.738017 -304.278329) (xy 165.689798 -304.268485) (xy 165.643782 -304.251033)
			(xy 165.601161 -304.226426) (xy 165.56304 -304.195301) (xy 165.530405 -304.158464) (xy 165.504102 -304.116868)
			(xy 165.484811 -304.071592) (xy 165.473034 -304.023808) (xy 165.469074 -303.974754) (xy 165.155129 -303.974754)
			(xy 165.15513 -304.001179) (xy 165.146751 -304.05328) (xy 165.130207 -304.10339) (xy 165.105915 -304.150237)
			(xy 165.074493 -304.192632) (xy 165.036738 -304.2295) (xy 164.993607 -304.259906) (xy 164.946196 -304.283077)
			(xy 164.895708 -304.298426) (xy 164.869622 -304.302414) (xy 164.86505 -304.303176) (xy 164.852858 -304.306986)
			(xy 164.849556 -304.308002) (xy 164.826188 -304.318924) (xy 164.819584 -304.326036) (xy 164.804852 -304.34153)
			(xy 164.796724 -304.352706) (xy 164.79403 -304.358237) (xy 164.791079 -304.370178) (xy 164.790882 -304.376328)
			(xy 164.790882 -304.449734) (xy 189.69407 -304.449734) (xy 189.69803 -304.40068) (xy 189.709807 -304.352896)
			(xy 189.729098 -304.30762) (xy 189.755401 -304.266024) (xy 189.788036 -304.229187) (xy 189.826157 -304.198062)
			(xy 189.868778 -304.173455) (xy 189.914794 -304.156003) (xy 189.963013 -304.146159) (xy 190.012188 -304.144178)
			(xy 190.061043 -304.15011) (xy 190.108314 -304.163802) (xy 190.152776 -304.1849) (xy 190.193279 -304.212856)
			(xy 190.228772 -304.246948) (xy 190.258337 -304.286292) (xy 190.281208 -304.329869) (xy 190.296792 -304.37655)
			(xy 190.304687 -304.425127) (xy 190.305182 -304.449734) (xy 190.304687 -304.474341) (xy 190.304508 -304.475442)
			(xy 190.62344 -304.475442) (xy 190.62344 -304.424026) (xy 190.631483 -304.373244) (xy 190.647371 -304.324345)
			(xy 190.670714 -304.278533) (xy 190.700935 -304.236937) (xy 190.737291 -304.200581) (xy 190.778887 -304.17036)
			(xy 190.824699 -304.147017) (xy 190.873598 -304.131129) (xy 190.92438 -304.123086) (xy 190.975796 -304.123086)
			(xy 191.026578 -304.131129) (xy 191.075477 -304.147017) (xy 191.121289 -304.17036) (xy 191.162885 -304.200581)
			(xy 191.199241 -304.236937) (xy 191.229462 -304.278533) (xy 191.252805 -304.324345) (xy 191.268693 -304.373244)
			(xy 191.276736 -304.424026) (xy 191.27724 -304.449734) (xy 191.276736 -304.475442) (xy 191.5734 -304.475442)
			(xy 191.5734 -304.424026) (xy 191.581443 -304.373244) (xy 191.597331 -304.324345) (xy 191.620674 -304.278533)
			(xy 191.650895 -304.236937) (xy 191.687251 -304.200581) (xy 191.728847 -304.17036) (xy 191.774659 -304.147017)
			(xy 191.823558 -304.131129) (xy 191.87434 -304.123086) (xy 191.925756 -304.123086) (xy 191.976538 -304.131129)
			(xy 192.025437 -304.147017) (xy 192.071249 -304.17036) (xy 192.112845 -304.200581) (xy 192.149201 -304.236937)
			(xy 192.179422 -304.278533) (xy 192.202765 -304.324345) (xy 192.218653 -304.373244) (xy 192.226696 -304.424026)
			(xy 192.2272 -304.449734) (xy 192.544204 -304.449734) (xy 192.548164 -304.40068) (xy 192.559941 -304.352896)
			(xy 192.579232 -304.30762) (xy 192.605535 -304.266024) (xy 192.63817 -304.229187) (xy 192.676291 -304.198062)
			(xy 192.718912 -304.173455) (xy 192.764928 -304.156003) (xy 192.813147 -304.146159) (xy 192.862322 -304.144178)
			(xy 192.911177 -304.15011) (xy 192.958448 -304.163802) (xy 193.00291 -304.1849) (xy 193.043413 -304.212856)
			(xy 193.078906 -304.246948) (xy 193.108471 -304.286292) (xy 193.131342 -304.329869) (xy 193.146926 -304.37655)
			(xy 193.154821 -304.425127) (xy 193.155316 -304.449734) (xy 193.494164 -304.449734) (xy 193.498124 -304.40068)
			(xy 193.509901 -304.352896) (xy 193.529192 -304.30762) (xy 193.555495 -304.266024) (xy 193.58813 -304.229187)
			(xy 193.626251 -304.198062) (xy 193.668872 -304.173455) (xy 193.714888 -304.156003) (xy 193.763107 -304.146159)
			(xy 193.812282 -304.144178) (xy 193.861137 -304.15011) (xy 193.908408 -304.163802) (xy 193.95287 -304.1849)
			(xy 193.993373 -304.212856) (xy 194.028866 -304.246948) (xy 194.058431 -304.286292) (xy 194.081302 -304.329869)
			(xy 194.096886 -304.37655) (xy 194.104781 -304.425127) (xy 194.105276 -304.449734) (xy 194.444124 -304.449734)
			(xy 194.448084 -304.40068) (xy 194.459861 -304.352896) (xy 194.479152 -304.30762) (xy 194.505455 -304.266024)
			(xy 194.53809 -304.229187) (xy 194.576211 -304.198062) (xy 194.618832 -304.173455) (xy 194.664848 -304.156003)
			(xy 194.713067 -304.146159) (xy 194.762242 -304.144178) (xy 194.811097 -304.15011) (xy 194.858368 -304.163802)
			(xy 194.90283 -304.1849) (xy 194.943333 -304.212856) (xy 194.978826 -304.246948) (xy 195.008391 -304.286292)
			(xy 195.031262 -304.329869) (xy 195.046846 -304.37655) (xy 195.054741 -304.425127) (xy 195.055069 -304.441416)
			(xy 195.394215 -304.441416) (xy 195.399582 -304.392073) (xy 195.412861 -304.344247) (xy 195.433702 -304.2992)
			(xy 195.461556 -304.258118) (xy 195.495689 -304.222083) (xy 195.535202 -304.192044) (xy 195.579054 -304.168794)
			(xy 195.62609 -304.152944) (xy 195.675071 -304.144913) (xy 195.699888 -304.144426) (xy 195.714071 -304.144604)
			(xy 195.742311 -304.147275) (xy 195.756276 -304.14976) (xy 195.768722 -304.152046) (xy 195.792344 -304.14468)
			(xy 195.869814 -304.06721) (xy 195.87718 -304.043588) (xy 195.874894 -304.031142) (xy 195.872413 -304.017177)
			(xy 195.869744 -303.988937) (xy 195.86956 -303.974754) (xy 195.870082 -303.949499) (xy 195.878395 -303.899677)
			(xy 195.894796 -303.851903) (xy 195.918837 -303.80748) (xy 195.949861 -303.76762) (xy 195.987023 -303.73341)
			(xy 196.029309 -303.705784) (xy 196.075565 -303.685494) (xy 196.12453 -303.673094) (xy 196.174868 -303.668923)
			(xy 196.225206 -303.673094) (xy 196.274171 -303.685494) (xy 196.320427 -303.705784) (xy 196.362713 -303.73341)
			(xy 196.399875 -303.76762) (xy 196.430899 -303.80748) (xy 196.45494 -303.851903) (xy 196.471341 -303.899677)
			(xy 196.479654 -303.949499) (xy 196.480176 -303.974754) (xy 196.479993 -303.988937) (xy 196.477325 -304.017177)
			(xy 196.474842 -304.031142) (xy 196.472556 -304.043588) (xy 196.479922 -304.06721) (xy 196.557392 -304.14468)
			(xy 196.581014 -304.152046) (xy 196.59346 -304.14976) (xy 196.607425 -304.14728) (xy 196.635665 -304.14461)
			(xy 196.649848 -304.144426) (xy 196.664095 -304.144588) (xy 196.692463 -304.147261) (xy 196.70649 -304.14976)
			(xy 196.718682 -304.152046) (xy 196.742812 -304.14468) (xy 196.820028 -304.067464) (xy 196.827394 -304.043588)
			(xy 196.825108 -304.031142) (xy 196.822628 -304.017177) (xy 196.819958 -303.988937) (xy 196.819774 -303.974754)
			(xy 196.820296 -303.949499) (xy 196.828609 -303.899677) (xy 196.84501 -303.851903) (xy 196.869051 -303.80748)
			(xy 196.900075 -303.76762) (xy 196.937237 -303.73341) (xy 196.979523 -303.705784) (xy 197.025779 -303.685494)
			(xy 197.074744 -303.673094) (xy 197.125082 -303.668923) (xy 197.17542 -303.673094) (xy 197.224385 -303.685494)
			(xy 197.270641 -303.705784) (xy 197.299387 -303.724564) (xy 201.429364 -303.724564) (xy 201.433435 -303.668942)
			(xy 201.445561 -303.614505) (xy 201.465484 -303.562414) (xy 201.49278 -303.513779) (xy 201.526866 -303.469636)
			(xy 201.567015 -303.430927) (xy 201.612373 -303.398476) (xy 201.661973 -303.372975) (xy 201.714757 -303.354968)
			(xy 201.7696 -303.344838) (xy 201.825334 -303.342801) (xy 201.880771 -303.348901) (xy 201.934728 -303.363007)
			(xy 201.986057 -303.384819) (xy 202.033663 -303.413873) (xy 202.076531 -303.449548) (xy 202.113748 -303.491085)
			(xy 202.144521 -303.537598) (xy 202.168193 -303.588095) (xy 202.184261 -303.641502) (xy 202.192381 -303.696678)
			(xy 202.19289 -303.724564) (xy 202.192381 -303.75245) (xy 202.184261 -303.807626) (xy 202.168193 -303.861033)
			(xy 202.144521 -303.91153) (xy 202.113748 -303.958043) (xy 202.076531 -303.99958) (xy 202.033663 -304.035255)
			(xy 201.986057 -304.064309) (xy 201.934728 -304.086121) (xy 201.880771 -304.100227) (xy 201.825334 -304.106327)
			(xy 201.7696 -304.10429) (xy 201.714757 -304.09416) (xy 201.661973 -304.076153) (xy 201.612373 -304.050652)
			(xy 201.567015 -304.018201) (xy 201.526866 -303.979492) (xy 201.49278 -303.935349) (xy 201.465484 -303.886714)
			(xy 201.445561 -303.834623) (xy 201.433435 -303.780186) (xy 201.429364 -303.724564) (xy 197.299387 -303.724564)
			(xy 197.312927 -303.73341) (xy 197.350089 -303.76762) (xy 197.381113 -303.80748) (xy 197.405154 -303.851903)
			(xy 197.421555 -303.899677) (xy 197.429868 -303.949499) (xy 197.43039 -303.974754) (xy 197.430313 -303.984625)
			(xy 197.429045 -304.004326) (xy 197.42785 -304.014124) (xy 197.426326 -304.026062) (xy 197.4342 -304.048668)
			(xy 197.510654 -304.122328) (xy 197.533514 -304.129186) (xy 197.545452 -304.127408) (xy 197.559002 -304.125256)
			(xy 197.586343 -304.122965) (xy 197.600062 -304.122836) (xy 197.625755 -304.123238) (xy 197.676509 -304.131271)
			(xy 197.725382 -304.147145) (xy 197.771169 -304.170468) (xy 197.812745 -304.200667) (xy 197.849084 -304.236998)
			(xy 197.879293 -304.278567) (xy 197.902627 -304.324349) (xy 197.918511 -304.373218) (xy 197.926556 -304.42397)
			(xy 197.926561 -304.475356) (xy 197.926547 -304.475442) (xy 198.223374 -304.475442) (xy 198.223374 -304.424026)
			(xy 198.231417 -304.373244) (xy 198.247305 -304.324345) (xy 198.270648 -304.278533) (xy 198.300869 -304.236937)
			(xy 198.337225 -304.200581) (xy 198.378821 -304.17036) (xy 198.424633 -304.147017) (xy 198.473532 -304.131129)
			(xy 198.524314 -304.123086) (xy 198.57573 -304.123086) (xy 198.626512 -304.131129) (xy 198.675411 -304.147017)
			(xy 198.721223 -304.17036) (xy 198.762819 -304.200581) (xy 198.799175 -304.236937) (xy 198.829396 -304.278533)
			(xy 198.852739 -304.324345) (xy 198.868627 -304.373244) (xy 198.87667 -304.424026) (xy 198.877174 -304.449734)
			(xy 199.194432 -304.449734) (xy 199.198392 -304.40068) (xy 199.210169 -304.352896) (xy 199.22946 -304.30762)
			(xy 199.255763 -304.266024) (xy 199.288398 -304.229187) (xy 199.326519 -304.198062) (xy 199.36914 -304.173455)
			(xy 199.415156 -304.156003) (xy 199.463375 -304.146159) (xy 199.51255 -304.144178) (xy 199.561405 -304.15011)
			(xy 199.608676 -304.163802) (xy 199.653138 -304.1849) (xy 199.693641 -304.212856) (xy 199.729134 -304.246948)
			(xy 199.758699 -304.286292) (xy 199.78157 -304.329869) (xy 199.797154 -304.37655) (xy 199.805049 -304.425127)
			(xy 199.805544 -304.449734) (xy 199.805049 -304.474341) (xy 199.797154 -304.522918) (xy 199.78157 -304.569599)
			(xy 199.758699 -304.613176) (xy 199.729134 -304.65252) (xy 199.693641 -304.686612) (xy 199.653138 -304.714568)
			(xy 199.608676 -304.735666) (xy 199.561405 -304.749358) (xy 199.51255 -304.75529) (xy 199.463375 -304.753309)
			(xy 199.415156 -304.743465) (xy 199.36914 -304.726013) (xy 199.326519 -304.701406) (xy 199.288398 -304.670281)
			(xy 199.255763 -304.633444) (xy 199.22946 -304.591848) (xy 199.210169 -304.546572) (xy 199.198392 -304.498788)
			(xy 199.194432 -304.449734) (xy 198.877174 -304.449734) (xy 198.87667 -304.475442) (xy 198.868627 -304.526224)
			(xy 198.852739 -304.575123) (xy 198.829396 -304.620935) (xy 198.799175 -304.662531) (xy 198.762819 -304.698887)
			(xy 198.721223 -304.729108) (xy 198.675411 -304.752451) (xy 198.626512 -304.768339) (xy 198.57573 -304.776382)
			(xy 198.524314 -304.776382) (xy 198.473532 -304.768339) (xy 198.424633 -304.752451) (xy 198.378821 -304.729108)
			(xy 198.337225 -304.698887) (xy 198.300869 -304.662531) (xy 198.270648 -304.620935) (xy 198.247305 -304.575123)
			(xy 198.231417 -304.526224) (xy 198.223374 -304.475442) (xy 197.926547 -304.475442) (xy 197.918529 -304.52611)
			(xy 197.902655 -304.574983) (xy 197.879331 -304.620771) (xy 197.849132 -304.662346) (xy 197.812801 -304.698685)
			(xy 197.771232 -304.728894) (xy 197.72545 -304.752227) (xy 197.67658 -304.768112) (xy 197.625828 -304.776156)
			(xy 197.574442 -304.776161) (xy 197.523688 -304.768128) (xy 197.474816 -304.752254) (xy 197.429028 -304.728931)
			(xy 197.387453 -304.698731) (xy 197.351114 -304.6624) (xy 197.320906 -304.620831) (xy 197.297572 -304.575048)
			(xy 197.281688 -304.526179) (xy 197.273644 -304.475427) (xy 197.273164 -304.449734) (xy 197.273303 -304.436016)
			(xy 197.275596 -304.408675) (xy 197.277736 -304.395124) (xy 197.279514 -304.383186) (xy 197.272656 -304.360326)
			(xy 197.198996 -304.283872) (xy 197.17639 -304.275998) (xy 197.164452 -304.277522) (xy 197.154653 -304.27871)
			(xy 197.134953 -304.279981) (xy 197.125082 -304.280062) (xy 197.110835 -304.279896) (xy 197.082467 -304.277226)
			(xy 197.06844 -304.274728) (xy 197.056248 -304.272442) (xy 197.032118 -304.279808) (xy 196.954902 -304.357024)
			(xy 196.947536 -304.3809) (xy 196.949822 -304.393346) (xy 196.952301 -304.407311) (xy 196.954971 -304.435551)
			(xy 196.955156 -304.449734) (xy 196.954634 -304.474989) (xy 196.946321 -304.524811) (xy 196.92992 -304.572585)
			(xy 196.905879 -304.617008) (xy 196.874855 -304.656868) (xy 196.837693 -304.691078) (xy 196.795407 -304.718704)
			(xy 196.749151 -304.738994) (xy 196.700186 -304.751394) (xy 196.649848 -304.755565) (xy 196.59951 -304.751394)
			(xy 196.550545 -304.738994) (xy 196.504289 -304.718704) (xy 196.462003 -304.691078) (xy 196.424841 -304.656868)
			(xy 196.393817 -304.617008) (xy 196.369776 -304.572585) (xy 196.353375 -304.524811) (xy 196.345062 -304.474989)
			(xy 196.34454 -304.449734) (xy 196.344721 -304.435551) (xy 196.34739 -304.407311) (xy 196.349874 -304.393346)
			(xy 196.35216 -304.3809) (xy 196.344794 -304.357278) (xy 196.267324 -304.279808) (xy 196.243702 -304.272442)
			(xy 196.231256 -304.274728) (xy 196.217291 -304.277207) (xy 196.189051 -304.279877) (xy 196.174868 -304.280062)
			(xy 196.160685 -304.279891) (xy 196.132445 -304.277215) (xy 196.11848 -304.274728) (xy 196.106034 -304.272442)
			(xy 196.082412 -304.279808) (xy 196.004942 -304.357278) (xy 195.997576 -304.3809) (xy 195.999862 -304.393346)
			(xy 196.00234 -304.407312) (xy 196.005011 -304.435551) (xy 196.005196 -304.449734) (xy 196.004686 -304.474551)
			(xy 195.99665 -304.523531) (xy 195.980797 -304.570566) (xy 195.957544 -304.614416) (xy 195.927503 -304.653928)
			(xy 195.891465 -304.688058) (xy 195.850381 -304.715909) (xy 195.805332 -304.736747) (xy 195.757506 -304.750022)
			(xy 195.708162 -304.755385) (xy 195.6586 -304.752695) (xy 195.610127 -304.742023) (xy 195.564018 -304.723649)
			(xy 195.521489 -304.698058) (xy 195.483661 -304.665923) (xy 195.45153 -304.628093) (xy 195.425941 -304.585562)
			(xy 195.407571 -304.539452) (xy 195.396902 -304.490978) (xy 195.394215 -304.441416) (xy 195.055069 -304.441416)
			(xy 195.055236 -304.449734) (xy 195.054741 -304.474341) (xy 195.046846 -304.522918) (xy 195.031262 -304.569599)
			(xy 195.008391 -304.613176) (xy 194.978826 -304.65252) (xy 194.943333 -304.686612) (xy 194.90283 -304.714568)
			(xy 194.858368 -304.735666) (xy 194.811097 -304.749358) (xy 194.762242 -304.75529) (xy 194.713067 -304.753309)
			(xy 194.664848 -304.743465) (xy 194.618832 -304.726013) (xy 194.576211 -304.701406) (xy 194.53809 -304.670281)
			(xy 194.505455 -304.633444) (xy 194.479152 -304.591848) (xy 194.459861 -304.546572) (xy 194.448084 -304.498788)
			(xy 194.444124 -304.449734) (xy 194.105276 -304.449734) (xy 194.104781 -304.474341) (xy 194.096886 -304.522918)
			(xy 194.081302 -304.569599) (xy 194.058431 -304.613176) (xy 194.028866 -304.65252) (xy 193.993373 -304.686612)
			(xy 193.95287 -304.714568) (xy 193.908408 -304.735666) (xy 193.861137 -304.749358) (xy 193.812282 -304.75529)
			(xy 193.763107 -304.753309) (xy 193.714888 -304.743465) (xy 193.668872 -304.726013) (xy 193.626251 -304.701406)
			(xy 193.58813 -304.670281) (xy 193.555495 -304.633444) (xy 193.529192 -304.591848) (xy 193.509901 -304.546572)
			(xy 193.498124 -304.498788) (xy 193.494164 -304.449734) (xy 193.155316 -304.449734) (xy 193.154821 -304.474341)
			(xy 193.146926 -304.522918) (xy 193.131342 -304.569599) (xy 193.108471 -304.613176) (xy 193.078906 -304.65252)
			(xy 193.043413 -304.686612) (xy 193.00291 -304.714568) (xy 192.958448 -304.735666) (xy 192.911177 -304.749358)
			(xy 192.862322 -304.75529) (xy 192.813147 -304.753309) (xy 192.764928 -304.743465) (xy 192.718912 -304.726013)
			(xy 192.676291 -304.701406) (xy 192.63817 -304.670281) (xy 192.605535 -304.633444) (xy 192.579232 -304.591848)
			(xy 192.559941 -304.546572) (xy 192.548164 -304.498788) (xy 192.544204 -304.449734) (xy 192.2272 -304.449734)
			(xy 192.226696 -304.475442) (xy 192.218653 -304.526224) (xy 192.202765 -304.575123) (xy 192.179422 -304.620935)
			(xy 192.149201 -304.662531) (xy 192.112845 -304.698887) (xy 192.071249 -304.729108) (xy 192.025437 -304.752451)
			(xy 191.976538 -304.768339) (xy 191.925756 -304.776382) (xy 191.87434 -304.776382) (xy 191.823558 -304.768339)
			(xy 191.774659 -304.752451) (xy 191.728847 -304.729108) (xy 191.687251 -304.698887) (xy 191.650895 -304.662531)
			(xy 191.620674 -304.620935) (xy 191.597331 -304.575123) (xy 191.581443 -304.526224) (xy 191.5734 -304.475442)
			(xy 191.276736 -304.475442) (xy 191.268693 -304.526224) (xy 191.252805 -304.575123) (xy 191.229462 -304.620935)
			(xy 191.199241 -304.662531) (xy 191.162885 -304.698887) (xy 191.121289 -304.729108) (xy 191.075477 -304.752451)
			(xy 191.026578 -304.768339) (xy 190.975796 -304.776382) (xy 190.92438 -304.776382) (xy 190.873598 -304.768339)
			(xy 190.824699 -304.752451) (xy 190.778887 -304.729108) (xy 190.737291 -304.698887) (xy 190.700935 -304.662531)
			(xy 190.670714 -304.620935) (xy 190.647371 -304.575123) (xy 190.631483 -304.526224) (xy 190.62344 -304.475442)
			(xy 190.304508 -304.475442) (xy 190.296792 -304.522918) (xy 190.281208 -304.569599) (xy 190.258337 -304.613176)
			(xy 190.228772 -304.65252) (xy 190.193279 -304.686612) (xy 190.152776 -304.714568) (xy 190.108314 -304.735666)
			(xy 190.061043 -304.749358) (xy 190.012188 -304.75529) (xy 189.963013 -304.753309) (xy 189.914794 -304.743465)
			(xy 189.868778 -304.726013) (xy 189.826157 -304.701406) (xy 189.788036 -304.670281) (xy 189.755401 -304.633444)
			(xy 189.729098 -304.591848) (xy 189.709807 -304.546572) (xy 189.69803 -304.498788) (xy 189.69407 -304.449734)
			(xy 164.790882 -304.449734) (xy 164.790882 -304.52314) (xy 164.791353 -304.532771) (xy 164.798538 -304.55065)
			(xy 164.804852 -304.557938) (xy 164.820092 -304.57394) (xy 164.82695 -304.581306) (xy 164.850318 -304.59172)
			(xy 164.854636 -304.59299) (xy 164.86505 -304.596292) (xy 164.869622 -304.597054) (xy 164.895691 -304.601131)
			(xy 164.946171 -304.616477) (xy 164.993573 -304.639643) (xy 165.036696 -304.670043) (xy 165.074445 -304.706904)
			(xy 165.105862 -304.749291) (xy 165.13015 -304.796129) (xy 165.146693 -304.84623) (xy 165.15507 -304.898321)
			(xy 165.15507 -304.924714) (xy 165.469074 -304.924714) (xy 165.473034 -304.87566) (xy 165.484811 -304.827876)
			(xy 165.504102 -304.7826) (xy 165.530405 -304.741004) (xy 165.56304 -304.704167) (xy 165.601161 -304.673042)
			(xy 165.643782 -304.648435) (xy 165.689798 -304.630983) (xy 165.738017 -304.621139) (xy 165.787192 -304.619158)
			(xy 165.836047 -304.62509) (xy 165.883318 -304.638782) (xy 165.92778 -304.65988) (xy 165.968283 -304.687836)
			(xy 166.003776 -304.721928) (xy 166.033341 -304.761272) (xy 166.056212 -304.804849) (xy 166.071796 -304.85153)
			(xy 166.079691 -304.900107) (xy 166.080186 -304.924714) (xy 166.419288 -304.924714) (xy 166.423248 -304.87566)
			(xy 166.435025 -304.827876) (xy 166.454316 -304.7826) (xy 166.480619 -304.741004) (xy 166.513254 -304.704167)
			(xy 166.551375 -304.673042) (xy 166.593996 -304.648435) (xy 166.640012 -304.630983) (xy 166.688231 -304.621139)
			(xy 166.737406 -304.619158) (xy 166.786261 -304.62509) (xy 166.833532 -304.638782) (xy 166.877994 -304.65988)
			(xy 166.918497 -304.687836) (xy 166.95399 -304.721928) (xy 166.983555 -304.761272) (xy 167.006426 -304.804849)
			(xy 167.02201 -304.85153) (xy 167.029905 -304.900107) (xy 167.0304 -304.924714) (xy 167.369248 -304.924714)
			(xy 167.373208 -304.87566) (xy 167.384985 -304.827876) (xy 167.404276 -304.7826) (xy 167.430579 -304.741004)
			(xy 167.463214 -304.704167) (xy 167.501335 -304.673042) (xy 167.543956 -304.648435) (xy 167.589972 -304.630983)
			(xy 167.638191 -304.621139) (xy 167.687366 -304.619158) (xy 167.736221 -304.62509) (xy 167.783492 -304.638782)
			(xy 167.827954 -304.65988) (xy 167.868457 -304.687836) (xy 167.90395 -304.721928) (xy 167.933515 -304.761272)
			(xy 167.956386 -304.804849) (xy 167.97197 -304.85153) (xy 167.979865 -304.900107) (xy 167.98036 -304.924714)
			(xy 168.319208 -304.924714) (xy 168.323168 -304.87566) (xy 168.334945 -304.827876) (xy 168.354236 -304.7826)
			(xy 168.380539 -304.741004) (xy 168.413174 -304.704167) (xy 168.451295 -304.673042) (xy 168.493916 -304.648435)
			(xy 168.539932 -304.630983) (xy 168.588151 -304.621139) (xy 168.637326 -304.619158) (xy 168.686181 -304.62509)
			(xy 168.733452 -304.638782) (xy 168.777914 -304.65988) (xy 168.818417 -304.687836) (xy 168.85391 -304.721928)
			(xy 168.883475 -304.761272) (xy 168.906346 -304.804849) (xy 168.92193 -304.85153) (xy 168.929825 -304.900107)
			(xy 168.93032 -304.924714) (xy 169.269168 -304.924714) (xy 169.273128 -304.87566) (xy 169.284905 -304.827876)
			(xy 169.304196 -304.7826) (xy 169.330499 -304.741004) (xy 169.363134 -304.704167) (xy 169.401255 -304.673042)
			(xy 169.443876 -304.648435) (xy 169.489892 -304.630983) (xy 169.538111 -304.621139) (xy 169.587286 -304.619158)
			(xy 169.636141 -304.62509) (xy 169.683412 -304.638782) (xy 169.727874 -304.65988) (xy 169.768377 -304.687836)
			(xy 169.80387 -304.721928) (xy 169.833435 -304.761272) (xy 169.856306 -304.804849) (xy 169.87189 -304.85153)
			(xy 169.879785 -304.900107) (xy 169.88028 -304.924714) (xy 170.219128 -304.924714) (xy 170.223088 -304.87566)
			(xy 170.234865 -304.827876) (xy 170.254156 -304.7826) (xy 170.280459 -304.741004) (xy 170.313094 -304.704167)
			(xy 170.351215 -304.673042) (xy 170.393836 -304.648435) (xy 170.439852 -304.630983) (xy 170.488071 -304.621139)
			(xy 170.537246 -304.619158) (xy 170.586101 -304.62509) (xy 170.633372 -304.638782) (xy 170.677834 -304.65988)
			(xy 170.718337 -304.687836) (xy 170.75383 -304.721928) (xy 170.783395 -304.761272) (xy 170.806266 -304.804849)
			(xy 170.82185 -304.85153) (xy 170.829745 -304.900107) (xy 170.83024 -304.924714) (xy 171.169088 -304.924714)
			(xy 171.173048 -304.87566) (xy 171.184825 -304.827876) (xy 171.204116 -304.7826) (xy 171.230419 -304.741004)
			(xy 171.263054 -304.704167) (xy 171.301175 -304.673042) (xy 171.343796 -304.648435) (xy 171.389812 -304.630983)
			(xy 171.438031 -304.621139) (xy 171.487206 -304.619158) (xy 171.536061 -304.62509) (xy 171.583332 -304.638782)
			(xy 171.627794 -304.65988) (xy 171.668297 -304.687836) (xy 171.70379 -304.721928) (xy 171.733355 -304.761272)
			(xy 171.756226 -304.804849) (xy 171.77181 -304.85153) (xy 171.779705 -304.900107) (xy 171.7802 -304.924714)
			(xy 172.119048 -304.924714) (xy 172.123008 -304.87566) (xy 172.134785 -304.827876) (xy 172.154076 -304.7826)
			(xy 172.180379 -304.741004) (xy 172.213014 -304.704167) (xy 172.251135 -304.673042) (xy 172.293756 -304.648435)
			(xy 172.339772 -304.630983) (xy 172.387991 -304.621139) (xy 172.437166 -304.619158) (xy 172.486021 -304.62509)
			(xy 172.533292 -304.638782) (xy 172.577754 -304.65988) (xy 172.618257 -304.687836) (xy 172.65375 -304.721928)
			(xy 172.683315 -304.761272) (xy 172.706186 -304.804849) (xy 172.72177 -304.85153) (xy 172.729665 -304.900107)
			(xy 172.73016 -304.924714) (xy 173.069262 -304.924714) (xy 173.073222 -304.87566) (xy 173.084999 -304.827876)
			(xy 173.10429 -304.7826) (xy 173.130593 -304.741004) (xy 173.163228 -304.704167) (xy 173.201349 -304.673042)
			(xy 173.24397 -304.648435) (xy 173.289986 -304.630983) (xy 173.338205 -304.621139) (xy 173.38738 -304.619158)
			(xy 173.436235 -304.62509) (xy 173.483506 -304.638782) (xy 173.527968 -304.65988) (xy 173.568471 -304.687836)
			(xy 173.603964 -304.721928) (xy 173.633529 -304.761272) (xy 173.6564 -304.804849) (xy 173.671984 -304.85153)
			(xy 173.679879 -304.900107) (xy 173.680374 -304.924714) (xy 174.019222 -304.924714) (xy 174.023182 -304.87566)
			(xy 174.034959 -304.827876) (xy 174.05425 -304.7826) (xy 174.080553 -304.741004) (xy 174.113188 -304.704167)
			(xy 174.151309 -304.673042) (xy 174.19393 -304.648435) (xy 174.239946 -304.630983) (xy 174.288165 -304.621139)
			(xy 174.33734 -304.619158) (xy 174.386195 -304.62509) (xy 174.433466 -304.638782) (xy 174.477928 -304.65988)
			(xy 174.518431 -304.687836) (xy 174.553924 -304.721928) (xy 174.583489 -304.761272) (xy 174.60636 -304.804849)
			(xy 174.621944 -304.85153) (xy 174.629839 -304.900107) (xy 174.630334 -304.924714) (xy 175.919142 -304.924714)
			(xy 175.923102 -304.87566) (xy 175.934879 -304.827876) (xy 175.95417 -304.7826) (xy 175.980473 -304.741004)
			(xy 176.013108 -304.704167) (xy 176.051229 -304.673042) (xy 176.09385 -304.648435) (xy 176.139866 -304.630983)
			(xy 176.188085 -304.621139) (xy 176.23726 -304.619158) (xy 176.286115 -304.62509) (xy 176.333386 -304.638782)
			(xy 176.377848 -304.65988) (xy 176.418351 -304.687836) (xy 176.453844 -304.721928) (xy 176.483409 -304.761272)
			(xy 176.50628 -304.804849) (xy 176.521864 -304.85153) (xy 176.529759 -304.900107) (xy 176.530254 -304.924714)
			(xy 176.869102 -304.924714) (xy 176.873062 -304.87566) (xy 176.884839 -304.827876) (xy 176.90413 -304.7826)
			(xy 176.930433 -304.741004) (xy 176.963068 -304.704167) (xy 177.001189 -304.673042) (xy 177.04381 -304.648435)
			(xy 177.089826 -304.630983) (xy 177.138045 -304.621139) (xy 177.18722 -304.619158) (xy 177.236075 -304.62509)
			(xy 177.283346 -304.638782) (xy 177.327808 -304.65988) (xy 177.368311 -304.687836) (xy 177.403804 -304.721928)
			(xy 177.433369 -304.761272) (xy 177.45624 -304.804849) (xy 177.471824 -304.85153) (xy 177.479719 -304.900107)
			(xy 177.480214 -304.924714) (xy 177.819062 -304.924714) (xy 177.823022 -304.87566) (xy 177.834799 -304.827876)
			(xy 177.85409 -304.7826) (xy 177.880393 -304.741004) (xy 177.913028 -304.704167) (xy 177.951149 -304.673042)
			(xy 177.99377 -304.648435) (xy 178.039786 -304.630983) (xy 178.088005 -304.621139) (xy 178.13718 -304.619158)
			(xy 178.186035 -304.62509) (xy 178.233306 -304.638782) (xy 178.277768 -304.65988) (xy 178.318271 -304.687836)
			(xy 178.353764 -304.721928) (xy 178.383329 -304.761272) (xy 178.4062 -304.804849) (xy 178.421784 -304.85153)
			(xy 178.429679 -304.900107) (xy 178.430174 -304.924714) (xy 178.769276 -304.924714) (xy 178.773236 -304.87566)
			(xy 178.785013 -304.827876) (xy 178.804304 -304.7826) (xy 178.830607 -304.741004) (xy 178.863242 -304.704167)
			(xy 178.901363 -304.673042) (xy 178.943984 -304.648435) (xy 178.99 -304.630983) (xy 179.038219 -304.621139)
			(xy 179.087394 -304.619158) (xy 179.136249 -304.62509) (xy 179.18352 -304.638782) (xy 179.227982 -304.65988)
			(xy 179.268485 -304.687836) (xy 179.303978 -304.721928) (xy 179.333543 -304.761272) (xy 179.356414 -304.804849)
			(xy 179.371998 -304.85153) (xy 179.379893 -304.900107) (xy 179.380388 -304.924714) (xy 179.719236 -304.924714)
			(xy 179.723196 -304.87566) (xy 179.734973 -304.827876) (xy 179.754264 -304.7826) (xy 179.780567 -304.741004)
			(xy 179.813202 -304.704167) (xy 179.851323 -304.673042) (xy 179.893944 -304.648435) (xy 179.93996 -304.630983)
			(xy 179.988179 -304.621139) (xy 180.037354 -304.619158) (xy 180.086209 -304.62509) (xy 180.13348 -304.638782)
			(xy 180.177942 -304.65988) (xy 180.218445 -304.687836) (xy 180.253938 -304.721928) (xy 180.283503 -304.761272)
			(xy 180.306374 -304.804849) (xy 180.321958 -304.85153) (xy 180.329853 -304.900107) (xy 180.330348 -304.924714)
			(xy 180.669196 -304.924714) (xy 180.673156 -304.87566) (xy 180.684933 -304.827876) (xy 180.704224 -304.7826)
			(xy 180.730527 -304.741004) (xy 180.763162 -304.704167) (xy 180.801283 -304.673042) (xy 180.843904 -304.648435)
			(xy 180.88992 -304.630983) (xy 180.938139 -304.621139) (xy 180.987314 -304.619158) (xy 181.036169 -304.62509)
			(xy 181.08344 -304.638782) (xy 181.127902 -304.65988) (xy 181.168405 -304.687836) (xy 181.203898 -304.721928)
			(xy 181.233463 -304.761272) (xy 181.256334 -304.804849) (xy 181.271918 -304.85153) (xy 181.279813 -304.900107)
			(xy 181.280308 -304.924714) (xy 181.619156 -304.924714) (xy 181.623116 -304.87566) (xy 181.634893 -304.827876)
			(xy 181.654184 -304.7826) (xy 181.680487 -304.741004) (xy 181.713122 -304.704167) (xy 181.751243 -304.673042)
			(xy 181.793864 -304.648435) (xy 181.83988 -304.630983) (xy 181.888099 -304.621139) (xy 181.937274 -304.619158)
			(xy 181.986129 -304.62509) (xy 182.0334 -304.638782) (xy 182.077862 -304.65988) (xy 182.118365 -304.687836)
			(xy 182.153858 -304.721928) (xy 182.183423 -304.761272) (xy 182.206294 -304.804849) (xy 182.221878 -304.85153)
			(xy 182.229773 -304.900107) (xy 182.230268 -304.924714) (xy 182.569116 -304.924714) (xy 182.573076 -304.87566)
			(xy 182.584853 -304.827876) (xy 182.604144 -304.7826) (xy 182.630447 -304.741004) (xy 182.663082 -304.704167)
			(xy 182.701203 -304.673042) (xy 182.743824 -304.648435) (xy 182.78984 -304.630983) (xy 182.838059 -304.621139)
			(xy 182.887234 -304.619158) (xy 182.936089 -304.62509) (xy 182.98336 -304.638782) (xy 183.027822 -304.65988)
			(xy 183.068325 -304.687836) (xy 183.103818 -304.721928) (xy 183.133383 -304.761272) (xy 183.156254 -304.804849)
			(xy 183.171838 -304.85153) (xy 183.179733 -304.900107) (xy 183.180228 -304.924714) (xy 183.519076 -304.924714)
			(xy 183.523036 -304.87566) (xy 183.534813 -304.827876) (xy 183.554104 -304.7826) (xy 183.580407 -304.741004)
			(xy 183.613042 -304.704167) (xy 183.651163 -304.673042) (xy 183.693784 -304.648435) (xy 183.7398 -304.630983)
			(xy 183.788019 -304.621139) (xy 183.837194 -304.619158) (xy 183.886049 -304.62509) (xy 183.93332 -304.638782)
			(xy 183.977782 -304.65988) (xy 184.018285 -304.687836) (xy 184.053778 -304.721928) (xy 184.083343 -304.761272)
			(xy 184.106214 -304.804849) (xy 184.121798 -304.85153) (xy 184.129693 -304.900107) (xy 184.130188 -304.924714)
			(xy 184.469036 -304.924714) (xy 184.472996 -304.87566) (xy 184.484773 -304.827876) (xy 184.504064 -304.7826)
			(xy 184.530367 -304.741004) (xy 184.563002 -304.704167) (xy 184.601123 -304.673042) (xy 184.643744 -304.648435)
			(xy 184.68976 -304.630983) (xy 184.737979 -304.621139) (xy 184.787154 -304.619158) (xy 184.836009 -304.62509)
			(xy 184.88328 -304.638782) (xy 184.927742 -304.65988) (xy 184.968245 -304.687836) (xy 185.003738 -304.721928)
			(xy 185.033303 -304.761272) (xy 185.056174 -304.804849) (xy 185.071758 -304.85153) (xy 185.079653 -304.900107)
			(xy 185.080148 -304.924714) (xy 185.41925 -304.924714) (xy 185.42321 -304.87566) (xy 185.434987 -304.827876)
			(xy 185.454278 -304.7826) (xy 185.480581 -304.741004) (xy 185.513216 -304.704167) (xy 185.551337 -304.673042)
			(xy 185.593958 -304.648435) (xy 185.639974 -304.630983) (xy 185.688193 -304.621139) (xy 185.737368 -304.619158)
			(xy 185.786223 -304.62509) (xy 185.833494 -304.638782) (xy 185.877956 -304.65988) (xy 185.918459 -304.687836)
			(xy 185.953952 -304.721928) (xy 185.983517 -304.761272) (xy 186.006388 -304.804849) (xy 186.021972 -304.85153)
			(xy 186.029867 -304.900107) (xy 186.030362 -304.924714) (xy 186.36921 -304.924714) (xy 186.37317 -304.87566)
			(xy 186.384947 -304.827876) (xy 186.404238 -304.7826) (xy 186.430541 -304.741004) (xy 186.463176 -304.704167)
			(xy 186.501297 -304.673042) (xy 186.543918 -304.648435) (xy 186.589934 -304.630983) (xy 186.638153 -304.621139)
			(xy 186.687328 -304.619158) (xy 186.736183 -304.62509) (xy 186.783454 -304.638782) (xy 186.827916 -304.65988)
			(xy 186.868419 -304.687836) (xy 186.903912 -304.721928) (xy 186.933477 -304.761272) (xy 186.956348 -304.804849)
			(xy 186.971932 -304.85153) (xy 186.979827 -304.900107) (xy 186.980322 -304.924714) (xy 187.31917 -304.924714)
			(xy 187.32313 -304.87566) (xy 187.334907 -304.827876) (xy 187.354198 -304.7826) (xy 187.380501 -304.741004)
			(xy 187.413136 -304.704167) (xy 187.451257 -304.673042) (xy 187.493878 -304.648435) (xy 187.539894 -304.630983)
			(xy 187.588113 -304.621139) (xy 187.637288 -304.619158) (xy 187.686143 -304.62509) (xy 187.733414 -304.638782)
			(xy 187.777876 -304.65988) (xy 187.818379 -304.687836) (xy 187.853872 -304.721928) (xy 187.883437 -304.761272)
			(xy 187.906308 -304.804849) (xy 187.921892 -304.85153) (xy 187.929787 -304.900107) (xy 187.930282 -304.924714)
			(xy 188.26913 -304.924714) (xy 188.27309 -304.87566) (xy 188.284867 -304.827876) (xy 188.304158 -304.7826)
			(xy 188.330461 -304.741004) (xy 188.363096 -304.704167) (xy 188.401217 -304.673042) (xy 188.443838 -304.648435)
			(xy 188.489854 -304.630983) (xy 188.538073 -304.621139) (xy 188.587248 -304.619158) (xy 188.636103 -304.62509)
			(xy 188.683374 -304.638782) (xy 188.727836 -304.65988) (xy 188.768339 -304.687836) (xy 188.803832 -304.721928)
			(xy 188.833397 -304.761272) (xy 188.843256 -304.780056) (xy 203.949711 -304.780056) (xy 203.949711 -304.725544)
			(xy 203.957469 -304.671586) (xy 203.972827 -304.619281) (xy 203.995473 -304.569695) (xy 204.024945 -304.523836)
			(xy 204.060644 -304.482638) (xy 204.101842 -304.44694) (xy 204.147702 -304.417469) (xy 204.197289 -304.394824)
			(xy 204.249594 -304.379467) (xy 204.303552 -304.37171) (xy 204.330808 -304.371248) (xy 204.357952 -304.371727)
			(xy 204.411695 -304.379403) (xy 204.463805 -304.394627) (xy 204.513227 -304.417092) (xy 204.558962 -304.446341)
			(xy 204.600084 -304.481785) (xy 204.63576 -304.522705) (xy 204.665269 -304.568273) (xy 204.688013 -304.617567)
			(xy 204.703533 -304.669589) (xy 204.707998 -304.696368) (xy 204.710733 -304.711218) (xy 204.723778 -304.738439)
			(xy 204.744199 -304.760668) (xy 204.770219 -304.775969) (xy 204.799571 -304.783011) (xy 204.829701 -304.78118)
			(xy 204.857985 -304.770637) (xy 204.870304 -304.7619) (xy 204.89035 -304.747071) (xy 204.933571 -304.722205)
			(xy 204.979661 -304.703176) (xy 205.027835 -304.690307) (xy 205.077274 -304.683818) (xy 205.102206 -304.683414)
			(xy 205.129459 -304.683856) (xy 205.183409 -304.691614) (xy 205.235706 -304.70697) (xy 205.285285 -304.729613)
			(xy 205.331137 -304.759081) (xy 205.372329 -304.794775) (xy 205.408022 -304.835967) (xy 205.43749 -304.88182)
			(xy 205.460132 -304.9314) (xy 205.475487 -304.983697) (xy 205.483244 -305.037647) (xy 205.483244 -305.064922)
			(xy 205.735172 -305.064922) (xy 205.739243 -305.0093) (xy 205.751369 -304.954863) (xy 205.771292 -304.902772)
			(xy 205.798588 -304.854137) (xy 205.832674 -304.809994) (xy 205.872823 -304.771285) (xy 205.918181 -304.738834)
			(xy 205.967781 -304.713333) (xy 206.020565 -304.695326) (xy 206.075408 -304.685196) (xy 206.131142 -304.683159)
			(xy 206.186579 -304.689259) (xy 206.240536 -304.703365) (xy 206.291865 -304.725177) (xy 206.339471 -304.754231)
			(xy 206.382339 -304.789906) (xy 206.419556 -304.831443) (xy 206.450329 -304.877956) (xy 206.474001 -304.928453)
			(xy 206.490069 -304.98186) (xy 206.498189 -305.037036) (xy 206.498698 -305.064922) (xy 206.743552 -305.064922)
			(xy 206.747623 -305.0093) (xy 206.759749 -304.954863) (xy 206.779672 -304.902772) (xy 206.806968 -304.854137)
			(xy 206.841054 -304.809994) (xy 206.881203 -304.771285) (xy 206.926561 -304.738834) (xy 206.976161 -304.713333)
			(xy 207.028945 -304.695326) (xy 207.083788 -304.685196) (xy 207.139522 -304.683159) (xy 207.194959 -304.689259)
			(xy 207.248916 -304.703365) (xy 207.300245 -304.725177) (xy 207.347851 -304.754231) (xy 207.390719 -304.789906)
			(xy 207.427936 -304.831443) (xy 207.458709 -304.877956) (xy 207.482381 -304.928453) (xy 207.498449 -304.98186)
			(xy 207.506569 -305.037036) (xy 207.507059 -305.063906) (xy 207.768188 -305.063906) (xy 207.772259 -305.008284)
			(xy 207.784385 -304.953847) (xy 207.804308 -304.901756) (xy 207.831604 -304.853121) (xy 207.86569 -304.808978)
			(xy 207.905839 -304.770269) (xy 207.951197 -304.737818) (xy 208.000797 -304.712317) (xy 208.053581 -304.69431)
			(xy 208.108424 -304.68418) (xy 208.164158 -304.682143) (xy 208.219595 -304.688243) (xy 208.273552 -304.702349)
			(xy 208.324881 -304.724161) (xy 208.372487 -304.753215) (xy 208.415355 -304.78889) (xy 208.452572 -304.830427)
			(xy 208.483345 -304.87694) (xy 208.507017 -304.927437) (xy 208.523085 -304.980844) (xy 208.531205 -305.03602)
			(xy 208.531389 -305.046126) (xy 208.784188 -305.046126) (xy 208.788259 -304.990504) (xy 208.800385 -304.936067)
			(xy 208.820308 -304.883976) (xy 208.847604 -304.835341) (xy 208.88169 -304.791198) (xy 208.921839 -304.752489)
			(xy 208.967197 -304.720038) (xy 209.016797 -304.694537) (xy 209.069581 -304.67653) (xy 209.124424 -304.6664)
			(xy 209.180158 -304.664363) (xy 209.235595 -304.670463) (xy 209.289552 -304.684569) (xy 209.340881 -304.706381)
			(xy 209.388487 -304.735435) (xy 209.431355 -304.77111) (xy 209.468572 -304.812647) (xy 209.499345 -304.85916)
			(xy 209.523017 -304.909657) (xy 209.539085 -304.963064) (xy 209.547205 -305.01824) (xy 209.547714 -305.046126)
			(xy 209.547205 -305.074012) (xy 209.539085 -305.129188) (xy 209.523017 -305.182595) (xy 209.499345 -305.233092)
			(xy 209.468572 -305.279605) (xy 209.431355 -305.321142) (xy 209.388487 -305.356817) (xy 209.340881 -305.385871)
			(xy 209.289552 -305.407683) (xy 209.235595 -305.421789) (xy 209.180158 -305.427889) (xy 209.124424 -305.425852)
			(xy 209.069581 -305.415722) (xy 209.016797 -305.397715) (xy 208.967197 -305.372214) (xy 208.921839 -305.339763)
			(xy 208.88169 -305.301054) (xy 208.847604 -305.256911) (xy 208.820308 -305.208276) (xy 208.800385 -305.156185)
			(xy 208.788259 -305.101748) (xy 208.784188 -305.046126) (xy 208.531389 -305.046126) (xy 208.531714 -305.063906)
			(xy 208.531205 -305.091792) (xy 208.523085 -305.146968) (xy 208.507017 -305.200375) (xy 208.483345 -305.250872)
			(xy 208.452572 -305.297385) (xy 208.415355 -305.338922) (xy 208.372487 -305.374597) (xy 208.324881 -305.403651)
			(xy 208.273552 -305.425463) (xy 208.219595 -305.439569) (xy 208.164158 -305.445669) (xy 208.108424 -305.443632)
			(xy 208.053581 -305.433502) (xy 208.000797 -305.415495) (xy 207.951197 -305.389994) (xy 207.905839 -305.357543)
			(xy 207.86569 -305.318834) (xy 207.831604 -305.274691) (xy 207.804308 -305.226056) (xy 207.784385 -305.173965)
			(xy 207.772259 -305.119528) (xy 207.768188 -305.063906) (xy 207.507059 -305.063906) (xy 207.507078 -305.064922)
			(xy 207.506569 -305.092808) (xy 207.498449 -305.147984) (xy 207.482381 -305.201391) (xy 207.458709 -305.251888)
			(xy 207.427936 -305.298401) (xy 207.390719 -305.339938) (xy 207.347851 -305.375613) (xy 207.300245 -305.404667)
			(xy 207.248916 -305.426479) (xy 207.194959 -305.440585) (xy 207.139522 -305.446685) (xy 207.083788 -305.444648)
			(xy 207.028945 -305.434518) (xy 206.976161 -305.416511) (xy 206.926561 -305.39101) (xy 206.881203 -305.358559)
			(xy 206.841054 -305.31985) (xy 206.806968 -305.275707) (xy 206.779672 -305.227072) (xy 206.759749 -305.174981)
			(xy 206.747623 -305.120544) (xy 206.743552 -305.064922) (xy 206.498698 -305.064922) (xy 206.498189 -305.092808)
			(xy 206.490069 -305.147984) (xy 206.474001 -305.201391) (xy 206.450329 -305.251888) (xy 206.419556 -305.298401)
			(xy 206.382339 -305.339938) (xy 206.339471 -305.375613) (xy 206.291865 -305.404667) (xy 206.240536 -305.426479)
			(xy 206.186579 -305.440585) (xy 206.131142 -305.446685) (xy 206.075408 -305.444648) (xy 206.020565 -305.434518)
			(xy 205.967781 -305.416511) (xy 205.918181 -305.39101) (xy 205.872823 -305.358559) (xy 205.832674 -305.31985)
			(xy 205.798588 -305.275707) (xy 205.771292 -305.227072) (xy 205.751369 -305.174981) (xy 205.739243 -305.120544)
			(xy 205.735172 -305.064922) (xy 205.483244 -305.064922) (xy 205.483244 -305.092153) (xy 205.475487 -305.146103)
			(xy 205.460132 -305.1984) (xy 205.43749 -305.24798) (xy 205.408022 -305.293833) (xy 205.372329 -305.335025)
			(xy 205.331137 -305.370719) (xy 205.285285 -305.400187) (xy 205.235706 -305.42283) (xy 205.183409 -305.438186)
			(xy 205.129459 -305.445944) (xy 205.102206 -305.44643) (xy 205.075061 -305.445957) (xy 205.021317 -305.438282)
			(xy 204.969206 -305.423059) (xy 204.919783 -305.400594) (xy 204.874047 -305.371344) (xy 204.832925 -305.3359)
			(xy 204.797249 -305.294979) (xy 204.767741 -305.249409) (xy 204.744997 -305.200114) (xy 204.72948 -305.148089)
			(xy 204.725016 -305.12131) (xy 204.722271 -305.106463) (xy 204.709224 -305.079247) (xy 204.688803 -305.057023)
			(xy 204.662787 -305.041723) (xy 204.633438 -305.034681) (xy 204.603312 -305.036508) (xy 204.575029 -305.047045)
			(xy 204.56271 -305.055778) (xy 204.542667 -305.070611) (xy 204.499445 -305.095475) (xy 204.453354 -305.114502)
			(xy 204.405179 -305.12737) (xy 204.35574 -305.13386) (xy 204.330808 -305.134264) (xy 204.303552 -305.13389)
			(xy 204.249594 -305.126133) (xy 204.197289 -305.110776) (xy 204.147702 -305.088131) (xy 204.101842 -305.05866)
			(xy 204.060644 -305.022962) (xy 204.024945 -304.981764) (xy 203.995473 -304.935905) (xy 203.972827 -304.886319)
			(xy 203.957469 -304.834014) (xy 203.949711 -304.780056) (xy 188.843256 -304.780056) (xy 188.856268 -304.804849)
			(xy 188.871852 -304.85153) (xy 188.879747 -304.900107) (xy 188.880242 -304.924714) (xy 188.879747 -304.949321)
			(xy 188.871852 -304.997898) (xy 188.856268 -305.044579) (xy 188.833397 -305.088156) (xy 188.803832 -305.1275)
			(xy 188.768339 -305.161592) (xy 188.727836 -305.189548) (xy 188.683374 -305.210646) (xy 188.636103 -305.224338)
			(xy 188.587248 -305.23027) (xy 188.538073 -305.228289) (xy 188.489854 -305.218445) (xy 188.443838 -305.200993)
			(xy 188.401217 -305.176386) (xy 188.363096 -305.145261) (xy 188.330461 -305.108424) (xy 188.304158 -305.066828)
			(xy 188.284867 -305.021552) (xy 188.27309 -304.973768) (xy 188.26913 -304.924714) (xy 187.930282 -304.924714)
			(xy 187.929787 -304.949321) (xy 187.921892 -304.997898) (xy 187.906308 -305.044579) (xy 187.883437 -305.088156)
			(xy 187.853872 -305.1275) (xy 187.818379 -305.161592) (xy 187.777876 -305.189548) (xy 187.733414 -305.210646)
			(xy 187.686143 -305.224338) (xy 187.637288 -305.23027) (xy 187.588113 -305.228289) (xy 187.539894 -305.218445)
			(xy 187.493878 -305.200993) (xy 187.451257 -305.176386) (xy 187.413136 -305.145261) (xy 187.380501 -305.108424)
			(xy 187.354198 -305.066828) (xy 187.334907 -305.021552) (xy 187.32313 -304.973768) (xy 187.31917 -304.924714)
			(xy 186.980322 -304.924714) (xy 186.979827 -304.949321) (xy 186.971932 -304.997898) (xy 186.956348 -305.044579)
			(xy 186.933477 -305.088156) (xy 186.903912 -305.1275) (xy 186.868419 -305.161592) (xy 186.827916 -305.189548)
			(xy 186.783454 -305.210646) (xy 186.736183 -305.224338) (xy 186.687328 -305.23027) (xy 186.638153 -305.228289)
			(xy 186.589934 -305.218445) (xy 186.543918 -305.200993) (xy 186.501297 -305.176386) (xy 186.463176 -305.145261)
			(xy 186.430541 -305.108424) (xy 186.404238 -305.066828) (xy 186.384947 -305.021552) (xy 186.37317 -304.973768)
			(xy 186.36921 -304.924714) (xy 186.030362 -304.924714) (xy 186.029867 -304.949321) (xy 186.021972 -304.997898)
			(xy 186.006388 -305.044579) (xy 185.983517 -305.088156) (xy 185.953952 -305.1275) (xy 185.918459 -305.161592)
			(xy 185.877956 -305.189548) (xy 185.833494 -305.210646) (xy 185.786223 -305.224338) (xy 185.737368 -305.23027)
			(xy 185.688193 -305.228289) (xy 185.639974 -305.218445) (xy 185.593958 -305.200993) (xy 185.551337 -305.176386)
			(xy 185.513216 -305.145261) (xy 185.480581 -305.108424) (xy 185.454278 -305.066828) (xy 185.434987 -305.021552)
			(xy 185.42321 -304.973768) (xy 185.41925 -304.924714) (xy 185.080148 -304.924714) (xy 185.079653 -304.949321)
			(xy 185.071758 -304.997898) (xy 185.056174 -305.044579) (xy 185.033303 -305.088156) (xy 185.003738 -305.1275)
			(xy 184.968245 -305.161592) (xy 184.927742 -305.189548) (xy 184.88328 -305.210646) (xy 184.836009 -305.224338)
			(xy 184.787154 -305.23027) (xy 184.737979 -305.228289) (xy 184.68976 -305.218445) (xy 184.643744 -305.200993)
			(xy 184.601123 -305.176386) (xy 184.563002 -305.145261) (xy 184.530367 -305.108424) (xy 184.504064 -305.066828)
			(xy 184.484773 -305.021552) (xy 184.472996 -304.973768) (xy 184.469036 -304.924714) (xy 184.130188 -304.924714)
			(xy 184.129693 -304.949321) (xy 184.121798 -304.997898) (xy 184.106214 -305.044579) (xy 184.083343 -305.088156)
			(xy 184.053778 -305.1275) (xy 184.018285 -305.161592) (xy 183.977782 -305.189548) (xy 183.93332 -305.210646)
			(xy 183.886049 -305.224338) (xy 183.837194 -305.23027) (xy 183.788019 -305.228289) (xy 183.7398 -305.218445)
			(xy 183.693784 -305.200993) (xy 183.651163 -305.176386) (xy 183.613042 -305.145261) (xy 183.580407 -305.108424)
			(xy 183.554104 -305.066828) (xy 183.534813 -305.021552) (xy 183.523036 -304.973768) (xy 183.519076 -304.924714)
			(xy 183.180228 -304.924714) (xy 183.179733 -304.949321) (xy 183.171838 -304.997898) (xy 183.156254 -305.044579)
			(xy 183.133383 -305.088156) (xy 183.103818 -305.1275) (xy 183.068325 -305.161592) (xy 183.027822 -305.189548)
			(xy 182.98336 -305.210646) (xy 182.936089 -305.224338) (xy 182.887234 -305.23027) (xy 182.838059 -305.228289)
			(xy 182.78984 -305.218445) (xy 182.743824 -305.200993) (xy 182.701203 -305.176386) (xy 182.663082 -305.145261)
			(xy 182.630447 -305.108424) (xy 182.604144 -305.066828) (xy 182.584853 -305.021552) (xy 182.573076 -304.973768)
			(xy 182.569116 -304.924714) (xy 182.230268 -304.924714) (xy 182.229773 -304.949321) (xy 182.221878 -304.997898)
			(xy 182.206294 -305.044579) (xy 182.183423 -305.088156) (xy 182.153858 -305.1275) (xy 182.118365 -305.161592)
			(xy 182.077862 -305.189548) (xy 182.0334 -305.210646) (xy 181.986129 -305.224338) (xy 181.937274 -305.23027)
			(xy 181.888099 -305.228289) (xy 181.83988 -305.218445) (xy 181.793864 -305.200993) (xy 181.751243 -305.176386)
			(xy 181.713122 -305.145261) (xy 181.680487 -305.108424) (xy 181.654184 -305.066828) (xy 181.634893 -305.021552)
			(xy 181.623116 -304.973768) (xy 181.619156 -304.924714) (xy 181.280308 -304.924714) (xy 181.279813 -304.949321)
			(xy 181.271918 -304.997898) (xy 181.256334 -305.044579) (xy 181.233463 -305.088156) (xy 181.203898 -305.1275)
			(xy 181.168405 -305.161592) (xy 181.127902 -305.189548) (xy 181.08344 -305.210646) (xy 181.036169 -305.224338)
			(xy 180.987314 -305.23027) (xy 180.938139 -305.228289) (xy 180.88992 -305.218445) (xy 180.843904 -305.200993)
			(xy 180.801283 -305.176386) (xy 180.763162 -305.145261) (xy 180.730527 -305.108424) (xy 180.704224 -305.066828)
			(xy 180.684933 -305.021552) (xy 180.673156 -304.973768) (xy 180.669196 -304.924714) (xy 180.330348 -304.924714)
			(xy 180.329853 -304.949321) (xy 180.321958 -304.997898) (xy 180.306374 -305.044579) (xy 180.283503 -305.088156)
			(xy 180.253938 -305.1275) (xy 180.218445 -305.161592) (xy 180.177942 -305.189548) (xy 180.13348 -305.210646)
			(xy 180.086209 -305.224338) (xy 180.037354 -305.23027) (xy 179.988179 -305.228289) (xy 179.93996 -305.218445)
			(xy 179.893944 -305.200993) (xy 179.851323 -305.176386) (xy 179.813202 -305.145261) (xy 179.780567 -305.108424)
			(xy 179.754264 -305.066828) (xy 179.734973 -305.021552) (xy 179.723196 -304.973768) (xy 179.719236 -304.924714)
			(xy 179.380388 -304.924714) (xy 179.379893 -304.949321) (xy 179.371998 -304.997898) (xy 179.356414 -305.044579)
			(xy 179.333543 -305.088156) (xy 179.303978 -305.1275) (xy 179.268485 -305.161592) (xy 179.227982 -305.189548)
			(xy 179.18352 -305.210646) (xy 179.136249 -305.224338) (xy 179.087394 -305.23027) (xy 179.038219 -305.228289)
			(xy 178.99 -305.218445) (xy 178.943984 -305.200993) (xy 178.901363 -305.176386) (xy 178.863242 -305.145261)
			(xy 178.830607 -305.108424) (xy 178.804304 -305.066828) (xy 178.785013 -305.021552) (xy 178.773236 -304.973768)
			(xy 178.769276 -304.924714) (xy 178.430174 -304.924714) (xy 178.429679 -304.949321) (xy 178.421784 -304.997898)
			(xy 178.4062 -305.044579) (xy 178.383329 -305.088156) (xy 178.353764 -305.1275) (xy 178.318271 -305.161592)
			(xy 178.277768 -305.189548) (xy 178.233306 -305.210646) (xy 178.186035 -305.224338) (xy 178.13718 -305.23027)
			(xy 178.088005 -305.228289) (xy 178.039786 -305.218445) (xy 177.99377 -305.200993) (xy 177.951149 -305.176386)
			(xy 177.913028 -305.145261) (xy 177.880393 -305.108424) (xy 177.85409 -305.066828) (xy 177.834799 -305.021552)
			(xy 177.823022 -304.973768) (xy 177.819062 -304.924714) (xy 177.480214 -304.924714) (xy 177.479719 -304.949321)
			(xy 177.471824 -304.997898) (xy 177.45624 -305.044579) (xy 177.433369 -305.088156) (xy 177.403804 -305.1275)
			(xy 177.368311 -305.161592) (xy 177.327808 -305.189548) (xy 177.283346 -305.210646) (xy 177.236075 -305.224338)
			(xy 177.18722 -305.23027) (xy 177.138045 -305.228289) (xy 177.089826 -305.218445) (xy 177.04381 -305.200993)
			(xy 177.001189 -305.176386) (xy 176.963068 -305.145261) (xy 176.930433 -305.108424) (xy 176.90413 -305.066828)
			(xy 176.884839 -305.021552) (xy 176.873062 -304.973768) (xy 176.869102 -304.924714) (xy 176.530254 -304.924714)
			(xy 176.529759 -304.949321) (xy 176.521864 -304.997898) (xy 176.50628 -305.044579) (xy 176.483409 -305.088156)
			(xy 176.453844 -305.1275) (xy 176.418351 -305.161592) (xy 176.377848 -305.189548) (xy 176.333386 -305.210646)
			(xy 176.286115 -305.224338) (xy 176.23726 -305.23027) (xy 176.188085 -305.228289) (xy 176.139866 -305.218445)
			(xy 176.09385 -305.200993) (xy 176.051229 -305.176386) (xy 176.013108 -305.145261) (xy 175.980473 -305.108424)
			(xy 175.95417 -305.066828) (xy 175.934879 -305.021552) (xy 175.923102 -304.973768) (xy 175.919142 -304.924714)
			(xy 174.630334 -304.924714) (xy 174.629839 -304.949321) (xy 174.621944 -304.997898) (xy 174.60636 -305.044579)
			(xy 174.583489 -305.088156) (xy 174.553924 -305.1275) (xy 174.518431 -305.161592) (xy 174.477928 -305.189548)
			(xy 174.433466 -305.210646) (xy 174.386195 -305.224338) (xy 174.33734 -305.23027) (xy 174.288165 -305.228289)
			(xy 174.239946 -305.218445) (xy 174.19393 -305.200993) (xy 174.151309 -305.176386) (xy 174.113188 -305.145261)
			(xy 174.080553 -305.108424) (xy 174.05425 -305.066828) (xy 174.034959 -305.021552) (xy 174.023182 -304.973768)
			(xy 174.019222 -304.924714) (xy 173.680374 -304.924714) (xy 173.679879 -304.949321) (xy 173.671984 -304.997898)
			(xy 173.6564 -305.044579) (xy 173.633529 -305.088156) (xy 173.603964 -305.1275) (xy 173.568471 -305.161592)
			(xy 173.527968 -305.189548) (xy 173.483506 -305.210646) (xy 173.436235 -305.224338) (xy 173.38738 -305.23027)
			(xy 173.338205 -305.228289) (xy 173.289986 -305.218445) (xy 173.24397 -305.200993) (xy 173.201349 -305.176386)
			(xy 173.163228 -305.145261) (xy 173.130593 -305.108424) (xy 173.10429 -305.066828) (xy 173.084999 -305.021552)
			(xy 173.073222 -304.973768) (xy 173.069262 -304.924714) (xy 172.73016 -304.924714) (xy 172.729665 -304.949321)
			(xy 172.72177 -304.997898) (xy 172.706186 -305.044579) (xy 172.683315 -305.088156) (xy 172.65375 -305.1275)
			(xy 172.618257 -305.161592) (xy 172.577754 -305.189548) (xy 172.533292 -305.210646) (xy 172.486021 -305.224338)
			(xy 172.437166 -305.23027) (xy 172.387991 -305.228289) (xy 172.339772 -305.218445) (xy 172.293756 -305.200993)
			(xy 172.251135 -305.176386) (xy 172.213014 -305.145261) (xy 172.180379 -305.108424) (xy 172.154076 -305.066828)
			(xy 172.134785 -305.021552) (xy 172.123008 -304.973768) (xy 172.119048 -304.924714) (xy 171.7802 -304.924714)
			(xy 171.779705 -304.949321) (xy 171.77181 -304.997898) (xy 171.756226 -305.044579) (xy 171.733355 -305.088156)
			(xy 171.70379 -305.1275) (xy 171.668297 -305.161592) (xy 171.627794 -305.189548) (xy 171.583332 -305.210646)
			(xy 171.536061 -305.224338) (xy 171.487206 -305.23027) (xy 171.438031 -305.228289) (xy 171.389812 -305.218445)
			(xy 171.343796 -305.200993) (xy 171.301175 -305.176386) (xy 171.263054 -305.145261) (xy 171.230419 -305.108424)
			(xy 171.204116 -305.066828) (xy 171.184825 -305.021552) (xy 171.173048 -304.973768) (xy 171.169088 -304.924714)
			(xy 170.83024 -304.924714) (xy 170.829745 -304.949321) (xy 170.82185 -304.997898) (xy 170.806266 -305.044579)
			(xy 170.783395 -305.088156) (xy 170.75383 -305.1275) (xy 170.718337 -305.161592) (xy 170.677834 -305.189548)
			(xy 170.633372 -305.210646) (xy 170.586101 -305.224338) (xy 170.537246 -305.23027) (xy 170.488071 -305.228289)
			(xy 170.439852 -305.218445) (xy 170.393836 -305.200993) (xy 170.351215 -305.176386) (xy 170.313094 -305.145261)
			(xy 170.280459 -305.108424) (xy 170.254156 -305.066828) (xy 170.234865 -305.021552) (xy 170.223088 -304.973768)
			(xy 170.219128 -304.924714) (xy 169.88028 -304.924714) (xy 169.879785 -304.949321) (xy 169.87189 -304.997898)
			(xy 169.856306 -305.044579) (xy 169.833435 -305.088156) (xy 169.80387 -305.1275) (xy 169.768377 -305.161592)
			(xy 169.727874 -305.189548) (xy 169.683412 -305.210646) (xy 169.636141 -305.224338) (xy 169.587286 -305.23027)
			(xy 169.538111 -305.228289) (xy 169.489892 -305.218445) (xy 169.443876 -305.200993) (xy 169.401255 -305.176386)
			(xy 169.363134 -305.145261) (xy 169.330499 -305.108424) (xy 169.304196 -305.066828) (xy 169.284905 -305.021552)
			(xy 169.273128 -304.973768) (xy 169.269168 -304.924714) (xy 168.93032 -304.924714) (xy 168.929825 -304.949321)
			(xy 168.92193 -304.997898) (xy 168.906346 -305.044579) (xy 168.883475 -305.088156) (xy 168.85391 -305.1275)
			(xy 168.818417 -305.161592) (xy 168.777914 -305.189548) (xy 168.733452 -305.210646) (xy 168.686181 -305.224338)
			(xy 168.637326 -305.23027) (xy 168.588151 -305.228289) (xy 168.539932 -305.218445) (xy 168.493916 -305.200993)
			(xy 168.451295 -305.176386) (xy 168.413174 -305.145261) (xy 168.380539 -305.108424) (xy 168.354236 -305.066828)
			(xy 168.334945 -305.021552) (xy 168.323168 -304.973768) (xy 168.319208 -304.924714) (xy 167.98036 -304.924714)
			(xy 167.979865 -304.949321) (xy 167.97197 -304.997898) (xy 167.956386 -305.044579) (xy 167.933515 -305.088156)
			(xy 167.90395 -305.1275) (xy 167.868457 -305.161592) (xy 167.827954 -305.189548) (xy 167.783492 -305.210646)
			(xy 167.736221 -305.224338) (xy 167.687366 -305.23027) (xy 167.638191 -305.228289) (xy 167.589972 -305.218445)
			(xy 167.543956 -305.200993) (xy 167.501335 -305.176386) (xy 167.463214 -305.145261) (xy 167.430579 -305.108424)
			(xy 167.404276 -305.066828) (xy 167.384985 -305.021552) (xy 167.373208 -304.973768) (xy 167.369248 -304.924714)
			(xy 167.0304 -304.924714) (xy 167.029905 -304.949321) (xy 167.02201 -304.997898) (xy 167.006426 -305.044579)
			(xy 166.983555 -305.088156) (xy 166.95399 -305.1275) (xy 166.918497 -305.161592) (xy 166.877994 -305.189548)
			(xy 166.833532 -305.210646) (xy 166.786261 -305.224338) (xy 166.737406 -305.23027) (xy 166.688231 -305.228289)
			(xy 166.640012 -305.218445) (xy 166.593996 -305.200993) (xy 166.551375 -305.176386) (xy 166.513254 -305.145261)
			(xy 166.480619 -305.108424) (xy 166.454316 -305.066828) (xy 166.435025 -305.021552) (xy 166.423248 -304.973768)
			(xy 166.419288 -304.924714) (xy 166.080186 -304.924714) (xy 166.079691 -304.949321) (xy 166.071796 -304.997898)
			(xy 166.056212 -305.044579) (xy 166.033341 -305.088156) (xy 166.003776 -305.1275) (xy 165.968283 -305.161592)
			(xy 165.92778 -305.189548) (xy 165.883318 -305.210646) (xy 165.836047 -305.224338) (xy 165.787192 -305.23027)
			(xy 165.738017 -305.228289) (xy 165.689798 -305.218445) (xy 165.643782 -305.200993) (xy 165.601161 -305.176386)
			(xy 165.56304 -305.145261) (xy 165.530405 -305.108424) (xy 165.504102 -305.066828) (xy 165.484811 -305.021552)
			(xy 165.473034 -304.973768) (xy 165.469074 -304.924714) (xy 165.15507 -304.924714) (xy 165.15507 -304.951082)
			(xy 165.146692 -305.003174) (xy 165.130149 -305.053274) (xy 165.10586 -305.100112) (xy 165.074443 -305.142499)
			(xy 165.036693 -305.17936) (xy 164.99357 -305.209759) (xy 164.946167 -305.232925) (xy 164.895687 -305.24827)
			(xy 164.869622 -305.252374) (xy 164.86505 -305.253136) (xy 164.854636 -305.256438) (xy 164.850318 -305.257708)
			(xy 164.826696 -305.26863) (xy 164.819838 -305.275742) (xy 164.804852 -305.29149) (xy 164.800263 -305.296594)
			(xy 164.793815 -305.308707) (xy 164.792152 -305.315366) (xy 164.790882 -305.326288) (xy 164.790882 -305.399948)
			(xy 189.69407 -305.399948) (xy 189.69803 -305.350894) (xy 189.709807 -305.30311) (xy 189.729098 -305.257834)
			(xy 189.755401 -305.216238) (xy 189.788036 -305.179401) (xy 189.826157 -305.148276) (xy 189.868778 -305.123669)
			(xy 189.914794 -305.106217) (xy 189.963013 -305.096373) (xy 190.012188 -305.094392) (xy 190.061043 -305.100324)
			(xy 190.108314 -305.114016) (xy 190.152776 -305.135114) (xy 190.193279 -305.16307) (xy 190.228772 -305.197162)
			(xy 190.258337 -305.236506) (xy 190.281208 -305.280083) (xy 190.296792 -305.326764) (xy 190.304687 -305.375341)
			(xy 190.305182 -305.399948) (xy 190.644284 -305.399948) (xy 190.648244 -305.350894) (xy 190.660021 -305.30311)
			(xy 190.679312 -305.257834) (xy 190.705615 -305.216238) (xy 190.73825 -305.179401) (xy 190.776371 -305.148276)
			(xy 190.818992 -305.123669) (xy 190.865008 -305.106217) (xy 190.913227 -305.096373) (xy 190.962402 -305.094392)
			(xy 191.011257 -305.100324) (xy 191.058528 -305.114016) (xy 191.10299 -305.135114) (xy 191.143493 -305.16307)
			(xy 191.178986 -305.197162) (xy 191.208551 -305.236506) (xy 191.231422 -305.280083) (xy 191.247006 -305.326764)
			(xy 191.254901 -305.375341) (xy 191.255396 -305.399948) (xy 191.594244 -305.399948) (xy 191.598204 -305.350894)
			(xy 191.609981 -305.30311) (xy 191.629272 -305.257834) (xy 191.655575 -305.216238) (xy 191.68821 -305.179401)
			(xy 191.726331 -305.148276) (xy 191.768952 -305.123669) (xy 191.814968 -305.106217) (xy 191.863187 -305.096373)
			(xy 191.912362 -305.094392) (xy 191.961217 -305.100324) (xy 192.008488 -305.114016) (xy 192.05295 -305.135114)
			(xy 192.093453 -305.16307) (xy 192.128946 -305.197162) (xy 192.158511 -305.236506) (xy 192.181382 -305.280083)
			(xy 192.196966 -305.326764) (xy 192.204861 -305.375341) (xy 192.205356 -305.399948) (xy 192.204861 -305.424555)
			(xy 192.204682 -305.425656) (xy 192.52336 -305.425656) (xy 192.52336 -305.37424) (xy 192.531403 -305.323458)
			(xy 192.547291 -305.274559) (xy 192.570634 -305.228747) (xy 192.600855 -305.187151) (xy 192.637211 -305.150795)
			(xy 192.678807 -305.120574) (xy 192.724619 -305.097231) (xy 192.773518 -305.081343) (xy 192.8243 -305.0733)
			(xy 192.875716 -305.0733) (xy 192.926498 -305.081343) (xy 192.975397 -305.097231) (xy 193.021209 -305.120574)
			(xy 193.062805 -305.150795) (xy 193.099161 -305.187151) (xy 193.129382 -305.228747) (xy 193.152725 -305.274559)
			(xy 193.168613 -305.323458) (xy 193.176656 -305.37424) (xy 193.17716 -305.399948) (xy 193.176656 -305.425656)
			(xy 193.47332 -305.425656) (xy 193.47332 -305.37424) (xy 193.481363 -305.323458) (xy 193.497251 -305.274559)
			(xy 193.520594 -305.228747) (xy 193.550815 -305.187151) (xy 193.587171 -305.150795) (xy 193.628767 -305.120574)
			(xy 193.674579 -305.097231) (xy 193.723478 -305.081343) (xy 193.77426 -305.0733) (xy 193.825676 -305.0733)
			(xy 193.876458 -305.081343) (xy 193.925357 -305.097231) (xy 193.971169 -305.120574) (xy 194.012765 -305.150795)
			(xy 194.049121 -305.187151) (xy 194.079342 -305.228747) (xy 194.102685 -305.274559) (xy 194.118573 -305.323458)
			(xy 194.126616 -305.37424) (xy 194.12712 -305.399948) (xy 194.444124 -305.399948) (xy 194.448084 -305.350894)
			(xy 194.459861 -305.30311) (xy 194.479152 -305.257834) (xy 194.505455 -305.216238) (xy 194.53809 -305.179401)
			(xy 194.576211 -305.148276) (xy 194.618832 -305.123669) (xy 194.664848 -305.106217) (xy 194.713067 -305.096373)
			(xy 194.762242 -305.094392) (xy 194.811097 -305.100324) (xy 194.858368 -305.114016) (xy 194.90283 -305.135114)
			(xy 194.943333 -305.16307) (xy 194.978826 -305.197162) (xy 195.008391 -305.236506) (xy 195.031262 -305.280083)
			(xy 195.046846 -305.326764) (xy 195.054741 -305.375341) (xy 195.055236 -305.399948) (xy 195.054741 -305.424555)
			(xy 195.054562 -305.425656) (xy 195.37324 -305.425656) (xy 195.37324 -305.37424) (xy 195.381283 -305.323458)
			(xy 195.397171 -305.274559) (xy 195.420514 -305.228747) (xy 195.450735 -305.187151) (xy 195.487091 -305.150795)
			(xy 195.528687 -305.120574) (xy 195.574499 -305.097231) (xy 195.623398 -305.081343) (xy 195.67418 -305.0733)
			(xy 195.725596 -305.0733) (xy 195.776378 -305.081343) (xy 195.825277 -305.097231) (xy 195.871089 -305.120574)
			(xy 195.912685 -305.150795) (xy 195.949041 -305.187151) (xy 195.979262 -305.228747) (xy 196.002605 -305.274559)
			(xy 196.018493 -305.323458) (xy 196.026536 -305.37424) (xy 196.02704 -305.399948) (xy 196.026536 -305.425656)
			(xy 196.3232 -305.425656) (xy 196.3232 -305.37424) (xy 196.331243 -305.323458) (xy 196.347131 -305.274559)
			(xy 196.370474 -305.228747) (xy 196.400695 -305.187151) (xy 196.437051 -305.150795) (xy 196.478647 -305.120574)
			(xy 196.524459 -305.097231) (xy 196.573358 -305.081343) (xy 196.62414 -305.0733) (xy 196.675556 -305.0733)
			(xy 196.726338 -305.081343) (xy 196.775237 -305.097231) (xy 196.821049 -305.120574) (xy 196.862645 -305.150795)
			(xy 196.899001 -305.187151) (xy 196.929222 -305.228747) (xy 196.952565 -305.274559) (xy 196.968453 -305.323458)
			(xy 196.976496 -305.37424) (xy 196.977 -305.399948) (xy 197.294258 -305.399948) (xy 197.298218 -305.350894)
			(xy 197.309995 -305.30311) (xy 197.329286 -305.257834) (xy 197.355589 -305.216238) (xy 197.388224 -305.179401)
			(xy 197.426345 -305.148276) (xy 197.468966 -305.123669) (xy 197.514982 -305.106217) (xy 197.563201 -305.096373)
			(xy 197.612376 -305.094392) (xy 197.661231 -305.100324) (xy 197.708502 -305.114016) (xy 197.752964 -305.135114)
			(xy 197.793467 -305.16307) (xy 197.82896 -305.197162) (xy 197.858525 -305.236506) (xy 197.881396 -305.280083)
			(xy 197.89698 -305.326764) (xy 197.904875 -305.375341) (xy 197.90537 -305.399948) (xy 198.244218 -305.399948)
			(xy 198.248178 -305.350894) (xy 198.259955 -305.30311) (xy 198.279246 -305.257834) (xy 198.305549 -305.216238)
			(xy 198.338184 -305.179401) (xy 198.376305 -305.148276) (xy 198.418926 -305.123669) (xy 198.464942 -305.106217)
			(xy 198.513161 -305.096373) (xy 198.562336 -305.094392) (xy 198.611191 -305.100324) (xy 198.658462 -305.114016)
			(xy 198.702924 -305.135114) (xy 198.743427 -305.16307) (xy 198.77892 -305.197162) (xy 198.808485 -305.236506)
			(xy 198.831356 -305.280083) (xy 198.84694 -305.326764) (xy 198.854835 -305.375341) (xy 198.85533 -305.399948)
			(xy 198.854835 -305.424555) (xy 198.84694 -305.473132) (xy 198.831356 -305.519813) (xy 198.808485 -305.56339)
			(xy 198.77892 -305.602734) (xy 198.743427 -305.636826) (xy 198.702924 -305.664782) (xy 198.658462 -305.68588)
			(xy 198.611191 -305.699572) (xy 198.562336 -305.705504) (xy 198.513161 -305.703523) (xy 198.464942 -305.693679)
			(xy 198.418926 -305.676227) (xy 198.376305 -305.65162) (xy 198.338184 -305.620495) (xy 198.305549 -305.583658)
			(xy 198.279246 -305.542062) (xy 198.259955 -305.496786) (xy 198.248178 -305.449002) (xy 198.244218 -305.399948)
			(xy 197.90537 -305.399948) (xy 197.904875 -305.424555) (xy 197.89698 -305.473132) (xy 197.881396 -305.519813)
			(xy 197.858525 -305.56339) (xy 197.82896 -305.602734) (xy 197.793467 -305.636826) (xy 197.752964 -305.664782)
			(xy 197.708502 -305.68588) (xy 197.661231 -305.699572) (xy 197.612376 -305.705504) (xy 197.563201 -305.703523)
			(xy 197.514982 -305.693679) (xy 197.468966 -305.676227) (xy 197.426345 -305.65162) (xy 197.388224 -305.620495)
			(xy 197.355589 -305.583658) (xy 197.329286 -305.542062) (xy 197.309995 -305.496786) (xy 197.298218 -305.449002)
			(xy 197.294258 -305.399948) (xy 196.977 -305.399948) (xy 196.976496 -305.425656) (xy 196.968453 -305.476438)
			(xy 196.952565 -305.525337) (xy 196.929222 -305.571149) (xy 196.899001 -305.612745) (xy 196.862645 -305.649101)
			(xy 196.821049 -305.679322) (xy 196.775237 -305.702665) (xy 196.726338 -305.718553) (xy 196.675556 -305.726596)
			(xy 196.62414 -305.726596) (xy 196.573358 -305.718553) (xy 196.524459 -305.702665) (xy 196.478647 -305.679322)
			(xy 196.437051 -305.649101) (xy 196.400695 -305.612745) (xy 196.370474 -305.571149) (xy 196.347131 -305.525337)
			(xy 196.331243 -305.476438) (xy 196.3232 -305.425656) (xy 196.026536 -305.425656) (xy 196.018493 -305.476438)
			(xy 196.002605 -305.525337) (xy 195.979262 -305.571149) (xy 195.949041 -305.612745) (xy 195.912685 -305.649101)
			(xy 195.871089 -305.679322) (xy 195.825277 -305.702665) (xy 195.776378 -305.718553) (xy 195.725596 -305.726596)
			(xy 195.67418 -305.726596) (xy 195.623398 -305.718553) (xy 195.574499 -305.702665) (xy 195.528687 -305.679322)
			(xy 195.487091 -305.649101) (xy 195.450735 -305.612745) (xy 195.420514 -305.571149) (xy 195.397171 -305.525337)
			(xy 195.381283 -305.476438) (xy 195.37324 -305.425656) (xy 195.054562 -305.425656) (xy 195.046846 -305.473132)
			(xy 195.031262 -305.519813) (xy 195.008391 -305.56339) (xy 194.978826 -305.602734) (xy 194.943333 -305.636826)
			(xy 194.90283 -305.664782) (xy 194.858368 -305.68588) (xy 194.811097 -305.699572) (xy 194.762242 -305.705504)
			(xy 194.713067 -305.703523) (xy 194.664848 -305.693679) (xy 194.618832 -305.676227) (xy 194.576211 -305.65162)
			(xy 194.53809 -305.620495) (xy 194.505455 -305.583658) (xy 194.479152 -305.542062) (xy 194.459861 -305.496786)
			(xy 194.448084 -305.449002) (xy 194.444124 -305.399948) (xy 194.12712 -305.399948) (xy 194.126616 -305.425656)
			(xy 194.118573 -305.476438) (xy 194.102685 -305.525337) (xy 194.079342 -305.571149) (xy 194.049121 -305.612745)
			(xy 194.012765 -305.649101) (xy 193.971169 -305.679322) (xy 193.925357 -305.702665) (xy 193.876458 -305.718553)
			(xy 193.825676 -305.726596) (xy 193.77426 -305.726596) (xy 193.723478 -305.718553) (xy 193.674579 -305.702665)
			(xy 193.628767 -305.679322) (xy 193.587171 -305.649101) (xy 193.550815 -305.612745) (xy 193.520594 -305.571149)
			(xy 193.497251 -305.525337) (xy 193.481363 -305.476438) (xy 193.47332 -305.425656) (xy 193.176656 -305.425656)
			(xy 193.168613 -305.476438) (xy 193.152725 -305.525337) (xy 193.129382 -305.571149) (xy 193.099161 -305.612745)
			(xy 193.062805 -305.649101) (xy 193.021209 -305.679322) (xy 192.975397 -305.702665) (xy 192.926498 -305.718553)
			(xy 192.875716 -305.726596) (xy 192.8243 -305.726596) (xy 192.773518 -305.718553) (xy 192.724619 -305.702665)
			(xy 192.678807 -305.679322) (xy 192.637211 -305.649101) (xy 192.600855 -305.612745) (xy 192.570634 -305.571149)
			(xy 192.547291 -305.525337) (xy 192.531403 -305.476438) (xy 192.52336 -305.425656) (xy 192.204682 -305.425656)
			(xy 192.196966 -305.473132) (xy 192.181382 -305.519813) (xy 192.158511 -305.56339) (xy 192.128946 -305.602734)
			(xy 192.093453 -305.636826) (xy 192.05295 -305.664782) (xy 192.008488 -305.68588) (xy 191.961217 -305.699572)
			(xy 191.912362 -305.705504) (xy 191.863187 -305.703523) (xy 191.814968 -305.693679) (xy 191.768952 -305.676227)
			(xy 191.726331 -305.65162) (xy 191.68821 -305.620495) (xy 191.655575 -305.583658) (xy 191.629272 -305.542062)
			(xy 191.609981 -305.496786) (xy 191.598204 -305.449002) (xy 191.594244 -305.399948) (xy 191.255396 -305.399948)
			(xy 191.254901 -305.424555) (xy 191.247006 -305.473132) (xy 191.231422 -305.519813) (xy 191.208551 -305.56339)
			(xy 191.178986 -305.602734) (xy 191.143493 -305.636826) (xy 191.10299 -305.664782) (xy 191.058528 -305.68588)
			(xy 191.011257 -305.699572) (xy 190.962402 -305.705504) (xy 190.913227 -305.703523) (xy 190.865008 -305.693679)
			(xy 190.818992 -305.676227) (xy 190.776371 -305.65162) (xy 190.73825 -305.620495) (xy 190.705615 -305.583658)
			(xy 190.679312 -305.542062) (xy 190.660021 -305.496786) (xy 190.648244 -305.449002) (xy 190.644284 -305.399948)
			(xy 190.305182 -305.399948) (xy 190.304687 -305.424555) (xy 190.296792 -305.473132) (xy 190.281208 -305.519813)
			(xy 190.258337 -305.56339) (xy 190.228772 -305.602734) (xy 190.193279 -305.636826) (xy 190.152776 -305.664782)
			(xy 190.108314 -305.68588) (xy 190.061043 -305.699572) (xy 190.012188 -305.705504) (xy 189.963013 -305.703523)
			(xy 189.914794 -305.693679) (xy 189.868778 -305.676227) (xy 189.826157 -305.65162) (xy 189.788036 -305.620495)
			(xy 189.755401 -305.583658) (xy 189.729098 -305.542062) (xy 189.709807 -305.496786) (xy 189.69803 -305.449002)
			(xy 189.69407 -305.399948) (xy 164.790882 -305.399948) (xy 164.790882 -305.473354) (xy 164.79105 -305.479507)
			(xy 164.794003 -305.491454) (xy 164.796724 -305.496976) (xy 164.804852 -305.508152) (xy 164.819584 -305.523646)
			(xy 164.826188 -305.530758) (xy 164.849302 -305.54168) (xy 164.852858 -305.542696) (xy 164.86505 -305.546506)
			(xy 164.869622 -305.547268) (xy 164.895689 -305.551345) (xy 164.946167 -305.56669) (xy 164.993568 -305.589856)
			(xy 165.036689 -305.620255) (xy 165.074436 -305.657114) (xy 165.105851 -305.6995) (xy 165.130138 -305.746336)
			(xy 165.14668 -305.796435) (xy 165.155056 -305.848524) (xy 165.155056 -305.874928) (xy 165.469074 -305.874928)
			(xy 165.473034 -305.825874) (xy 165.484811 -305.77809) (xy 165.504102 -305.732814) (xy 165.530405 -305.691218)
			(xy 165.56304 -305.654381) (xy 165.601161 -305.623256) (xy 165.643782 -305.598649) (xy 165.689798 -305.581197)
			(xy 165.738017 -305.571353) (xy 165.787192 -305.569372) (xy 165.836047 -305.575304) (xy 165.883318 -305.588996)
			(xy 165.92778 -305.610094) (xy 165.968283 -305.63805) (xy 166.003776 -305.672142) (xy 166.033341 -305.711486)
			(xy 166.056212 -305.755063) (xy 166.071796 -305.801744) (xy 166.079691 -305.850321) (xy 166.080186 -305.874928)
			(xy 166.419288 -305.874928) (xy 166.423248 -305.825874) (xy 166.435025 -305.77809) (xy 166.454316 -305.732814)
			(xy 166.480619 -305.691218) (xy 166.513254 -305.654381) (xy 166.551375 -305.623256) (xy 166.593996 -305.598649)
			(xy 166.640012 -305.581197) (xy 166.688231 -305.571353) (xy 166.737406 -305.569372) (xy 166.786261 -305.575304)
			(xy 166.833532 -305.588996) (xy 166.877994 -305.610094) (xy 166.918497 -305.63805) (xy 166.95399 -305.672142)
			(xy 166.983555 -305.711486) (xy 167.006426 -305.755063) (xy 167.02201 -305.801744) (xy 167.029905 -305.850321)
			(xy 167.0304 -305.874928) (xy 167.369248 -305.874928) (xy 167.373208 -305.825874) (xy 167.384985 -305.77809)
			(xy 167.404276 -305.732814) (xy 167.430579 -305.691218) (xy 167.463214 -305.654381) (xy 167.501335 -305.623256)
			(xy 167.543956 -305.598649) (xy 167.589972 -305.581197) (xy 167.638191 -305.571353) (xy 167.687366 -305.569372)
			(xy 167.736221 -305.575304) (xy 167.783492 -305.588996) (xy 167.827954 -305.610094) (xy 167.868457 -305.63805)
			(xy 167.90395 -305.672142) (xy 167.933515 -305.711486) (xy 167.956386 -305.755063) (xy 167.97197 -305.801744)
			(xy 167.979865 -305.850321) (xy 167.98036 -305.874928) (xy 168.319208 -305.874928) (xy 168.323168 -305.825874)
			(xy 168.334945 -305.77809) (xy 168.354236 -305.732814) (xy 168.380539 -305.691218) (xy 168.413174 -305.654381)
			(xy 168.451295 -305.623256) (xy 168.493916 -305.598649) (xy 168.539932 -305.581197) (xy 168.588151 -305.571353)
			(xy 168.637326 -305.569372) (xy 168.686181 -305.575304) (xy 168.733452 -305.588996) (xy 168.777914 -305.610094)
			(xy 168.818417 -305.63805) (xy 168.85391 -305.672142) (xy 168.883475 -305.711486) (xy 168.906346 -305.755063)
			(xy 168.92193 -305.801744) (xy 168.929825 -305.850321) (xy 168.93032 -305.874928) (xy 169.269168 -305.874928)
			(xy 169.273128 -305.825874) (xy 169.284905 -305.77809) (xy 169.304196 -305.732814) (xy 169.330499 -305.691218)
			(xy 169.363134 -305.654381) (xy 169.401255 -305.623256) (xy 169.443876 -305.598649) (xy 169.489892 -305.581197)
			(xy 169.538111 -305.571353) (xy 169.587286 -305.569372) (xy 169.636141 -305.575304) (xy 169.683412 -305.588996)
			(xy 169.727874 -305.610094) (xy 169.768377 -305.63805) (xy 169.80387 -305.672142) (xy 169.833435 -305.711486)
			(xy 169.856306 -305.755063) (xy 169.87189 -305.801744) (xy 169.879785 -305.850321) (xy 169.88028 -305.874928)
			(xy 170.219128 -305.874928) (xy 170.223088 -305.825874) (xy 170.234865 -305.77809) (xy 170.254156 -305.732814)
			(xy 170.280459 -305.691218) (xy 170.313094 -305.654381) (xy 170.351215 -305.623256) (xy 170.393836 -305.598649)
			(xy 170.439852 -305.581197) (xy 170.488071 -305.571353) (xy 170.537246 -305.569372) (xy 170.586101 -305.575304)
			(xy 170.633372 -305.588996) (xy 170.677834 -305.610094) (xy 170.718337 -305.63805) (xy 170.75383 -305.672142)
			(xy 170.783395 -305.711486) (xy 170.806266 -305.755063) (xy 170.82185 -305.801744) (xy 170.829745 -305.850321)
			(xy 170.83024 -305.874928) (xy 171.169088 -305.874928) (xy 171.173048 -305.825874) (xy 171.184825 -305.77809)
			(xy 171.204116 -305.732814) (xy 171.230419 -305.691218) (xy 171.263054 -305.654381) (xy 171.301175 -305.623256)
			(xy 171.343796 -305.598649) (xy 171.389812 -305.581197) (xy 171.438031 -305.571353) (xy 171.487206 -305.569372)
			(xy 171.536061 -305.575304) (xy 171.583332 -305.588996) (xy 171.627794 -305.610094) (xy 171.668297 -305.63805)
			(xy 171.70379 -305.672142) (xy 171.733355 -305.711486) (xy 171.756226 -305.755063) (xy 171.77181 -305.801744)
			(xy 171.779705 -305.850321) (xy 171.7802 -305.874928) (xy 172.119048 -305.874928) (xy 172.123008 -305.825874)
			(xy 172.134785 -305.77809) (xy 172.154076 -305.732814) (xy 172.180379 -305.691218) (xy 172.213014 -305.654381)
			(xy 172.251135 -305.623256) (xy 172.293756 -305.598649) (xy 172.339772 -305.581197) (xy 172.387991 -305.571353)
			(xy 172.437166 -305.569372) (xy 172.486021 -305.575304) (xy 172.533292 -305.588996) (xy 172.577754 -305.610094)
			(xy 172.618257 -305.63805) (xy 172.65375 -305.672142) (xy 172.683315 -305.711486) (xy 172.706186 -305.755063)
			(xy 172.72177 -305.801744) (xy 172.729665 -305.850321) (xy 172.73016 -305.874928) (xy 173.069262 -305.874928)
			(xy 173.073222 -305.825874) (xy 173.084999 -305.77809) (xy 173.10429 -305.732814) (xy 173.130593 -305.691218)
			(xy 173.163228 -305.654381) (xy 173.201349 -305.623256) (xy 173.24397 -305.598649) (xy 173.289986 -305.581197)
			(xy 173.338205 -305.571353) (xy 173.38738 -305.569372) (xy 173.436235 -305.575304) (xy 173.483506 -305.588996)
			(xy 173.527968 -305.610094) (xy 173.568471 -305.63805) (xy 173.603964 -305.672142) (xy 173.633529 -305.711486)
			(xy 173.6564 -305.755063) (xy 173.671984 -305.801744) (xy 173.679879 -305.850321) (xy 173.680374 -305.874928)
			(xy 174.019222 -305.874928) (xy 174.023182 -305.825874) (xy 174.034959 -305.77809) (xy 174.05425 -305.732814)
			(xy 174.080553 -305.691218) (xy 174.113188 -305.654381) (xy 174.151309 -305.623256) (xy 174.19393 -305.598649)
			(xy 174.239946 -305.581197) (xy 174.288165 -305.571353) (xy 174.33734 -305.569372) (xy 174.386195 -305.575304)
			(xy 174.433466 -305.588996) (xy 174.477928 -305.610094) (xy 174.518431 -305.63805) (xy 174.553924 -305.672142)
			(xy 174.583489 -305.711486) (xy 174.60636 -305.755063) (xy 174.621944 -305.801744) (xy 174.629839 -305.850321)
			(xy 174.630334 -305.874928) (xy 175.919142 -305.874928) (xy 175.923102 -305.825874) (xy 175.934879 -305.77809)
			(xy 175.95417 -305.732814) (xy 175.980473 -305.691218) (xy 176.013108 -305.654381) (xy 176.051229 -305.623256)
			(xy 176.09385 -305.598649) (xy 176.139866 -305.581197) (xy 176.188085 -305.571353) (xy 176.23726 -305.569372)
			(xy 176.286115 -305.575304) (xy 176.333386 -305.588996) (xy 176.377848 -305.610094) (xy 176.418351 -305.63805)
			(xy 176.453844 -305.672142) (xy 176.483409 -305.711486) (xy 176.50628 -305.755063) (xy 176.521864 -305.801744)
			(xy 176.529759 -305.850321) (xy 176.530254 -305.874928) (xy 176.869102 -305.874928) (xy 176.873062 -305.825874)
			(xy 176.884839 -305.77809) (xy 176.90413 -305.732814) (xy 176.930433 -305.691218) (xy 176.963068 -305.654381)
			(xy 177.001189 -305.623256) (xy 177.04381 -305.598649) (xy 177.089826 -305.581197) (xy 177.138045 -305.571353)
			(xy 177.18722 -305.569372) (xy 177.236075 -305.575304) (xy 177.283346 -305.588996) (xy 177.327808 -305.610094)
			(xy 177.368311 -305.63805) (xy 177.403804 -305.672142) (xy 177.433369 -305.711486) (xy 177.45624 -305.755063)
			(xy 177.471824 -305.801744) (xy 177.479719 -305.850321) (xy 177.480214 -305.874928) (xy 177.819062 -305.874928)
			(xy 177.823022 -305.825874) (xy 177.834799 -305.77809) (xy 177.85409 -305.732814) (xy 177.880393 -305.691218)
			(xy 177.913028 -305.654381) (xy 177.951149 -305.623256) (xy 177.99377 -305.598649) (xy 178.039786 -305.581197)
			(xy 178.088005 -305.571353) (xy 178.13718 -305.569372) (xy 178.186035 -305.575304) (xy 178.233306 -305.588996)
			(xy 178.277768 -305.610094) (xy 178.318271 -305.63805) (xy 178.353764 -305.672142) (xy 178.383329 -305.711486)
			(xy 178.4062 -305.755063) (xy 178.421784 -305.801744) (xy 178.429679 -305.850321) (xy 178.430174 -305.874928)
			(xy 178.769276 -305.874928) (xy 178.773236 -305.825874) (xy 178.785013 -305.77809) (xy 178.804304 -305.732814)
			(xy 178.830607 -305.691218) (xy 178.863242 -305.654381) (xy 178.901363 -305.623256) (xy 178.943984 -305.598649)
			(xy 178.99 -305.581197) (xy 179.038219 -305.571353) (xy 179.087394 -305.569372) (xy 179.136249 -305.575304)
			(xy 179.18352 -305.588996) (xy 179.227982 -305.610094) (xy 179.268485 -305.63805) (xy 179.303978 -305.672142)
			(xy 179.333543 -305.711486) (xy 179.356414 -305.755063) (xy 179.371998 -305.801744) (xy 179.379893 -305.850321)
			(xy 179.380388 -305.874928) (xy 179.719236 -305.874928) (xy 179.723196 -305.825874) (xy 179.734973 -305.77809)
			(xy 179.754264 -305.732814) (xy 179.780567 -305.691218) (xy 179.813202 -305.654381) (xy 179.851323 -305.623256)
			(xy 179.893944 -305.598649) (xy 179.93996 -305.581197) (xy 179.988179 -305.571353) (xy 180.037354 -305.569372)
			(xy 180.086209 -305.575304) (xy 180.13348 -305.588996) (xy 180.177942 -305.610094) (xy 180.218445 -305.63805)
			(xy 180.253938 -305.672142) (xy 180.283503 -305.711486) (xy 180.306374 -305.755063) (xy 180.321958 -305.801744)
			(xy 180.329853 -305.850321) (xy 180.330348 -305.874928) (xy 180.669196 -305.874928) (xy 180.673156 -305.825874)
			(xy 180.684933 -305.77809) (xy 180.704224 -305.732814) (xy 180.730527 -305.691218) (xy 180.763162 -305.654381)
			(xy 180.801283 -305.623256) (xy 180.843904 -305.598649) (xy 180.88992 -305.581197) (xy 180.938139 -305.571353)
			(xy 180.987314 -305.569372) (xy 181.036169 -305.575304) (xy 181.08344 -305.588996) (xy 181.127902 -305.610094)
			(xy 181.168405 -305.63805) (xy 181.203898 -305.672142) (xy 181.233463 -305.711486) (xy 181.256334 -305.755063)
			(xy 181.271918 -305.801744) (xy 181.279813 -305.850321) (xy 181.280308 -305.874928) (xy 181.619156 -305.874928)
			(xy 181.623116 -305.825874) (xy 181.634893 -305.77809) (xy 181.654184 -305.732814) (xy 181.680487 -305.691218)
			(xy 181.713122 -305.654381) (xy 181.751243 -305.623256) (xy 181.793864 -305.598649) (xy 181.83988 -305.581197)
			(xy 181.888099 -305.571353) (xy 181.937274 -305.569372) (xy 181.986129 -305.575304) (xy 182.0334 -305.588996)
			(xy 182.077862 -305.610094) (xy 182.118365 -305.63805) (xy 182.153858 -305.672142) (xy 182.183423 -305.711486)
			(xy 182.206294 -305.755063) (xy 182.221878 -305.801744) (xy 182.229773 -305.850321) (xy 182.230268 -305.874928)
			(xy 182.569116 -305.874928) (xy 182.573076 -305.825874) (xy 182.584853 -305.77809) (xy 182.604144 -305.732814)
			(xy 182.630447 -305.691218) (xy 182.663082 -305.654381) (xy 182.701203 -305.623256) (xy 182.743824 -305.598649)
			(xy 182.78984 -305.581197) (xy 182.838059 -305.571353) (xy 182.887234 -305.569372) (xy 182.936089 -305.575304)
			(xy 182.98336 -305.588996) (xy 183.027822 -305.610094) (xy 183.068325 -305.63805) (xy 183.103818 -305.672142)
			(xy 183.133383 -305.711486) (xy 183.156254 -305.755063) (xy 183.171838 -305.801744) (xy 183.179733 -305.850321)
			(xy 183.180228 -305.874928) (xy 183.519076 -305.874928) (xy 183.523036 -305.825874) (xy 183.534813 -305.77809)
			(xy 183.554104 -305.732814) (xy 183.580407 -305.691218) (xy 183.613042 -305.654381) (xy 183.651163 -305.623256)
			(xy 183.693784 -305.598649) (xy 183.7398 -305.581197) (xy 183.788019 -305.571353) (xy 183.837194 -305.569372)
			(xy 183.886049 -305.575304) (xy 183.93332 -305.588996) (xy 183.977782 -305.610094) (xy 184.018285 -305.63805)
			(xy 184.053778 -305.672142) (xy 184.083343 -305.711486) (xy 184.106214 -305.755063) (xy 184.121798 -305.801744)
			(xy 184.129693 -305.850321) (xy 184.130188 -305.874928) (xy 184.469036 -305.874928) (xy 184.472996 -305.825874)
			(xy 184.484773 -305.77809) (xy 184.504064 -305.732814) (xy 184.530367 -305.691218) (xy 184.563002 -305.654381)
			(xy 184.601123 -305.623256) (xy 184.643744 -305.598649) (xy 184.68976 -305.581197) (xy 184.737979 -305.571353)
			(xy 184.787154 -305.569372) (xy 184.836009 -305.575304) (xy 184.88328 -305.588996) (xy 184.927742 -305.610094)
			(xy 184.968245 -305.63805) (xy 185.003738 -305.672142) (xy 185.033303 -305.711486) (xy 185.056174 -305.755063)
			(xy 185.071758 -305.801744) (xy 185.079653 -305.850321) (xy 185.080148 -305.874928) (xy 185.41925 -305.874928)
			(xy 185.42321 -305.825874) (xy 185.434987 -305.77809) (xy 185.454278 -305.732814) (xy 185.480581 -305.691218)
			(xy 185.513216 -305.654381) (xy 185.551337 -305.623256) (xy 185.593958 -305.598649) (xy 185.639974 -305.581197)
			(xy 185.688193 -305.571353) (xy 185.737368 -305.569372) (xy 185.786223 -305.575304) (xy 185.833494 -305.588996)
			(xy 185.877956 -305.610094) (xy 185.918459 -305.63805) (xy 185.953952 -305.672142) (xy 185.983517 -305.711486)
			(xy 186.006388 -305.755063) (xy 186.021972 -305.801744) (xy 186.029867 -305.850321) (xy 186.030362 -305.874928)
			(xy 186.36921 -305.874928) (xy 186.37317 -305.825874) (xy 186.384947 -305.77809) (xy 186.404238 -305.732814)
			(xy 186.430541 -305.691218) (xy 186.463176 -305.654381) (xy 186.501297 -305.623256) (xy 186.543918 -305.598649)
			(xy 186.589934 -305.581197) (xy 186.638153 -305.571353) (xy 186.687328 -305.569372) (xy 186.736183 -305.575304)
			(xy 186.783454 -305.588996) (xy 186.827916 -305.610094) (xy 186.868419 -305.63805) (xy 186.903912 -305.672142)
			(xy 186.933477 -305.711486) (xy 186.956348 -305.755063) (xy 186.971932 -305.801744) (xy 186.979827 -305.850321)
			(xy 186.980322 -305.874928) (xy 187.31917 -305.874928) (xy 187.32313 -305.825874) (xy 187.334907 -305.77809)
			(xy 187.354198 -305.732814) (xy 187.380501 -305.691218) (xy 187.413136 -305.654381) (xy 187.451257 -305.623256)
			(xy 187.493878 -305.598649) (xy 187.539894 -305.581197) (xy 187.588113 -305.571353) (xy 187.637288 -305.569372)
			(xy 187.686143 -305.575304) (xy 187.733414 -305.588996) (xy 187.777876 -305.610094) (xy 187.818379 -305.63805)
			(xy 187.853872 -305.672142) (xy 187.883437 -305.711486) (xy 187.906308 -305.755063) (xy 187.921892 -305.801744)
			(xy 187.929787 -305.850321) (xy 187.930282 -305.874928) (xy 188.26913 -305.874928) (xy 188.27309 -305.825874)
			(xy 188.284867 -305.77809) (xy 188.304158 -305.732814) (xy 188.330461 -305.691218) (xy 188.363096 -305.654381)
			(xy 188.401217 -305.623256) (xy 188.443838 -305.598649) (xy 188.489854 -305.581197) (xy 188.538073 -305.571353)
			(xy 188.587248 -305.569372) (xy 188.636103 -305.575304) (xy 188.683374 -305.588996) (xy 188.727836 -305.610094)
			(xy 188.768339 -305.63805) (xy 188.803832 -305.672142) (xy 188.833397 -305.711486) (xy 188.856268 -305.755063)
			(xy 188.871852 -305.801744) (xy 188.879747 -305.850321) (xy 188.880242 -305.874928) (xy 188.879747 -305.899535)
			(xy 188.871852 -305.948112) (xy 188.856268 -305.994793) (xy 188.833397 -306.03837) (xy 188.803832 -306.077714)
			(xy 188.768339 -306.111806) (xy 188.727836 -306.139762) (xy 188.683374 -306.16086) (xy 188.636103 -306.174552)
			(xy 188.587248 -306.180484) (xy 188.538073 -306.178503) (xy 188.489854 -306.168659) (xy 188.443838 -306.151207)
			(xy 188.401217 -306.1266) (xy 188.363096 -306.095475) (xy 188.330461 -306.058638) (xy 188.304158 -306.017042)
			(xy 188.284867 -305.971766) (xy 188.27309 -305.923982) (xy 188.26913 -305.874928) (xy 187.930282 -305.874928)
			(xy 187.929787 -305.899535) (xy 187.921892 -305.948112) (xy 187.906308 -305.994793) (xy 187.883437 -306.03837)
			(xy 187.853872 -306.077714) (xy 187.818379 -306.111806) (xy 187.777876 -306.139762) (xy 187.733414 -306.16086)
			(xy 187.686143 -306.174552) (xy 187.637288 -306.180484) (xy 187.588113 -306.178503) (xy 187.539894 -306.168659)
			(xy 187.493878 -306.151207) (xy 187.451257 -306.1266) (xy 187.413136 -306.095475) (xy 187.380501 -306.058638)
			(xy 187.354198 -306.017042) (xy 187.334907 -305.971766) (xy 187.32313 -305.923982) (xy 187.31917 -305.874928)
			(xy 186.980322 -305.874928) (xy 186.979827 -305.899535) (xy 186.971932 -305.948112) (xy 186.956348 -305.994793)
			(xy 186.933477 -306.03837) (xy 186.903912 -306.077714) (xy 186.868419 -306.111806) (xy 186.827916 -306.139762)
			(xy 186.783454 -306.16086) (xy 186.736183 -306.174552) (xy 186.687328 -306.180484) (xy 186.638153 -306.178503)
			(xy 186.589934 -306.168659) (xy 186.543918 -306.151207) (xy 186.501297 -306.1266) (xy 186.463176 -306.095475)
			(xy 186.430541 -306.058638) (xy 186.404238 -306.017042) (xy 186.384947 -305.971766) (xy 186.37317 -305.923982)
			(xy 186.36921 -305.874928) (xy 186.030362 -305.874928) (xy 186.029867 -305.899535) (xy 186.021972 -305.948112)
			(xy 186.006388 -305.994793) (xy 185.983517 -306.03837) (xy 185.953952 -306.077714) (xy 185.918459 -306.111806)
			(xy 185.877956 -306.139762) (xy 185.833494 -306.16086) (xy 185.786223 -306.174552) (xy 185.737368 -306.180484)
			(xy 185.688193 -306.178503) (xy 185.639974 -306.168659) (xy 185.593958 -306.151207) (xy 185.551337 -306.1266)
			(xy 185.513216 -306.095475) (xy 185.480581 -306.058638) (xy 185.454278 -306.017042) (xy 185.434987 -305.971766)
			(xy 185.42321 -305.923982) (xy 185.41925 -305.874928) (xy 185.080148 -305.874928) (xy 185.079653 -305.899535)
			(xy 185.071758 -305.948112) (xy 185.056174 -305.994793) (xy 185.033303 -306.03837) (xy 185.003738 -306.077714)
			(xy 184.968245 -306.111806) (xy 184.927742 -306.139762) (xy 184.88328 -306.16086) (xy 184.836009 -306.174552)
			(xy 184.787154 -306.180484) (xy 184.737979 -306.178503) (xy 184.68976 -306.168659) (xy 184.643744 -306.151207)
			(xy 184.601123 -306.1266) (xy 184.563002 -306.095475) (xy 184.530367 -306.058638) (xy 184.504064 -306.017042)
			(xy 184.484773 -305.971766) (xy 184.472996 -305.923982) (xy 184.469036 -305.874928) (xy 184.130188 -305.874928)
			(xy 184.129693 -305.899535) (xy 184.121798 -305.948112) (xy 184.106214 -305.994793) (xy 184.083343 -306.03837)
			(xy 184.053778 -306.077714) (xy 184.018285 -306.111806) (xy 183.977782 -306.139762) (xy 183.93332 -306.16086)
			(xy 183.886049 -306.174552) (xy 183.837194 -306.180484) (xy 183.788019 -306.178503) (xy 183.7398 -306.168659)
			(xy 183.693784 -306.151207) (xy 183.651163 -306.1266) (xy 183.613042 -306.095475) (xy 183.580407 -306.058638)
			(xy 183.554104 -306.017042) (xy 183.534813 -305.971766) (xy 183.523036 -305.923982) (xy 183.519076 -305.874928)
			(xy 183.180228 -305.874928) (xy 183.179733 -305.899535) (xy 183.171838 -305.948112) (xy 183.156254 -305.994793)
			(xy 183.133383 -306.03837) (xy 183.103818 -306.077714) (xy 183.068325 -306.111806) (xy 183.027822 -306.139762)
			(xy 182.98336 -306.16086) (xy 182.936089 -306.174552) (xy 182.887234 -306.180484) (xy 182.838059 -306.178503)
			(xy 182.78984 -306.168659) (xy 182.743824 -306.151207) (xy 182.701203 -306.1266) (xy 182.663082 -306.095475)
			(xy 182.630447 -306.058638) (xy 182.604144 -306.017042) (xy 182.584853 -305.971766) (xy 182.573076 -305.923982)
			(xy 182.569116 -305.874928) (xy 182.230268 -305.874928) (xy 182.229773 -305.899535) (xy 182.221878 -305.948112)
			(xy 182.206294 -305.994793) (xy 182.183423 -306.03837) (xy 182.153858 -306.077714) (xy 182.118365 -306.111806)
			(xy 182.077862 -306.139762) (xy 182.0334 -306.16086) (xy 181.986129 -306.174552) (xy 181.937274 -306.180484)
			(xy 181.888099 -306.178503) (xy 181.83988 -306.168659) (xy 181.793864 -306.151207) (xy 181.751243 -306.1266)
			(xy 181.713122 -306.095475) (xy 181.680487 -306.058638) (xy 181.654184 -306.017042) (xy 181.634893 -305.971766)
			(xy 181.623116 -305.923982) (xy 181.619156 -305.874928) (xy 181.280308 -305.874928) (xy 181.279813 -305.899535)
			(xy 181.271918 -305.948112) (xy 181.256334 -305.994793) (xy 181.233463 -306.03837) (xy 181.203898 -306.077714)
			(xy 181.168405 -306.111806) (xy 181.127902 -306.139762) (xy 181.08344 -306.16086) (xy 181.036169 -306.174552)
			(xy 180.987314 -306.180484) (xy 180.938139 -306.178503) (xy 180.88992 -306.168659) (xy 180.843904 -306.151207)
			(xy 180.801283 -306.1266) (xy 180.763162 -306.095475) (xy 180.730527 -306.058638) (xy 180.704224 -306.017042)
			(xy 180.684933 -305.971766) (xy 180.673156 -305.923982) (xy 180.669196 -305.874928) (xy 180.330348 -305.874928)
			(xy 180.329853 -305.899535) (xy 180.321958 -305.948112) (xy 180.306374 -305.994793) (xy 180.283503 -306.03837)
			(xy 180.253938 -306.077714) (xy 180.218445 -306.111806) (xy 180.177942 -306.139762) (xy 180.13348 -306.16086)
			(xy 180.086209 -306.174552) (xy 180.037354 -306.180484) (xy 179.988179 -306.178503) (xy 179.93996 -306.168659)
			(xy 179.893944 -306.151207) (xy 179.851323 -306.1266) (xy 179.813202 -306.095475) (xy 179.780567 -306.058638)
			(xy 179.754264 -306.017042) (xy 179.734973 -305.971766) (xy 179.723196 -305.923982) (xy 179.719236 -305.874928)
			(xy 179.380388 -305.874928) (xy 179.379893 -305.899535) (xy 179.371998 -305.948112) (xy 179.356414 -305.994793)
			(xy 179.333543 -306.03837) (xy 179.303978 -306.077714) (xy 179.268485 -306.111806) (xy 179.227982 -306.139762)
			(xy 179.18352 -306.16086) (xy 179.136249 -306.174552) (xy 179.087394 -306.180484) (xy 179.038219 -306.178503)
			(xy 178.99 -306.168659) (xy 178.943984 -306.151207) (xy 178.901363 -306.1266) (xy 178.863242 -306.095475)
			(xy 178.830607 -306.058638) (xy 178.804304 -306.017042) (xy 178.785013 -305.971766) (xy 178.773236 -305.923982)
			(xy 178.769276 -305.874928) (xy 178.430174 -305.874928) (xy 178.429679 -305.899535) (xy 178.421784 -305.948112)
			(xy 178.4062 -305.994793) (xy 178.383329 -306.03837) (xy 178.353764 -306.077714) (xy 178.318271 -306.111806)
			(xy 178.277768 -306.139762) (xy 178.233306 -306.16086) (xy 178.186035 -306.174552) (xy 178.13718 -306.180484)
			(xy 178.088005 -306.178503) (xy 178.039786 -306.168659) (xy 177.99377 -306.151207) (xy 177.951149 -306.1266)
			(xy 177.913028 -306.095475) (xy 177.880393 -306.058638) (xy 177.85409 -306.017042) (xy 177.834799 -305.971766)
			(xy 177.823022 -305.923982) (xy 177.819062 -305.874928) (xy 177.480214 -305.874928) (xy 177.479719 -305.899535)
			(xy 177.471824 -305.948112) (xy 177.45624 -305.994793) (xy 177.433369 -306.03837) (xy 177.403804 -306.077714)
			(xy 177.368311 -306.111806) (xy 177.327808 -306.139762) (xy 177.283346 -306.16086) (xy 177.236075 -306.174552)
			(xy 177.18722 -306.180484) (xy 177.138045 -306.178503) (xy 177.089826 -306.168659) (xy 177.04381 -306.151207)
			(xy 177.001189 -306.1266) (xy 176.963068 -306.095475) (xy 176.930433 -306.058638) (xy 176.90413 -306.017042)
			(xy 176.884839 -305.971766) (xy 176.873062 -305.923982) (xy 176.869102 -305.874928) (xy 176.530254 -305.874928)
			(xy 176.529759 -305.899535) (xy 176.521864 -305.948112) (xy 176.50628 -305.994793) (xy 176.483409 -306.03837)
			(xy 176.453844 -306.077714) (xy 176.418351 -306.111806) (xy 176.377848 -306.139762) (xy 176.333386 -306.16086)
			(xy 176.286115 -306.174552) (xy 176.23726 -306.180484) (xy 176.188085 -306.178503) (xy 176.139866 -306.168659)
			(xy 176.09385 -306.151207) (xy 176.051229 -306.1266) (xy 176.013108 -306.095475) (xy 175.980473 -306.058638)
			(xy 175.95417 -306.017042) (xy 175.934879 -305.971766) (xy 175.923102 -305.923982) (xy 175.919142 -305.874928)
			(xy 174.630334 -305.874928) (xy 174.629839 -305.899535) (xy 174.621944 -305.948112) (xy 174.60636 -305.994793)
			(xy 174.583489 -306.03837) (xy 174.553924 -306.077714) (xy 174.518431 -306.111806) (xy 174.477928 -306.139762)
			(xy 174.433466 -306.16086) (xy 174.386195 -306.174552) (xy 174.33734 -306.180484) (xy 174.288165 -306.178503)
			(xy 174.239946 -306.168659) (xy 174.19393 -306.151207) (xy 174.151309 -306.1266) (xy 174.113188 -306.095475)
			(xy 174.080553 -306.058638) (xy 174.05425 -306.017042) (xy 174.034959 -305.971766) (xy 174.023182 -305.923982)
			(xy 174.019222 -305.874928) (xy 173.680374 -305.874928) (xy 173.679879 -305.899535) (xy 173.671984 -305.948112)
			(xy 173.6564 -305.994793) (xy 173.633529 -306.03837) (xy 173.603964 -306.077714) (xy 173.568471 -306.111806)
			(xy 173.527968 -306.139762) (xy 173.483506 -306.16086) (xy 173.436235 -306.174552) (xy 173.38738 -306.180484)
			(xy 173.338205 -306.178503) (xy 173.289986 -306.168659) (xy 173.24397 -306.151207) (xy 173.201349 -306.1266)
			(xy 173.163228 -306.095475) (xy 173.130593 -306.058638) (xy 173.10429 -306.017042) (xy 173.084999 -305.971766)
			(xy 173.073222 -305.923982) (xy 173.069262 -305.874928) (xy 172.73016 -305.874928) (xy 172.729665 -305.899535)
			(xy 172.72177 -305.948112) (xy 172.706186 -305.994793) (xy 172.683315 -306.03837) (xy 172.65375 -306.077714)
			(xy 172.618257 -306.111806) (xy 172.577754 -306.139762) (xy 172.533292 -306.16086) (xy 172.486021 -306.174552)
			(xy 172.437166 -306.180484) (xy 172.387991 -306.178503) (xy 172.339772 -306.168659) (xy 172.293756 -306.151207)
			(xy 172.251135 -306.1266) (xy 172.213014 -306.095475) (xy 172.180379 -306.058638) (xy 172.154076 -306.017042)
			(xy 172.134785 -305.971766) (xy 172.123008 -305.923982) (xy 172.119048 -305.874928) (xy 171.7802 -305.874928)
			(xy 171.779705 -305.899535) (xy 171.77181 -305.948112) (xy 171.756226 -305.994793) (xy 171.733355 -306.03837)
			(xy 171.70379 -306.077714) (xy 171.668297 -306.111806) (xy 171.627794 -306.139762) (xy 171.583332 -306.16086)
			(xy 171.536061 -306.174552) (xy 171.487206 -306.180484) (xy 171.438031 -306.178503) (xy 171.389812 -306.168659)
			(xy 171.343796 -306.151207) (xy 171.301175 -306.1266) (xy 171.263054 -306.095475) (xy 171.230419 -306.058638)
			(xy 171.204116 -306.017042) (xy 171.184825 -305.971766) (xy 171.173048 -305.923982) (xy 171.169088 -305.874928)
			(xy 170.83024 -305.874928) (xy 170.829745 -305.899535) (xy 170.82185 -305.948112) (xy 170.806266 -305.994793)
			(xy 170.783395 -306.03837) (xy 170.75383 -306.077714) (xy 170.718337 -306.111806) (xy 170.677834 -306.139762)
			(xy 170.633372 -306.16086) (xy 170.586101 -306.174552) (xy 170.537246 -306.180484) (xy 170.488071 -306.178503)
			(xy 170.439852 -306.168659) (xy 170.393836 -306.151207) (xy 170.351215 -306.1266) (xy 170.313094 -306.095475)
			(xy 170.280459 -306.058638) (xy 170.254156 -306.017042) (xy 170.234865 -305.971766) (xy 170.223088 -305.923982)
			(xy 170.219128 -305.874928) (xy 169.88028 -305.874928) (xy 169.879785 -305.899535) (xy 169.87189 -305.948112)
			(xy 169.856306 -305.994793) (xy 169.833435 -306.03837) (xy 169.80387 -306.077714) (xy 169.768377 -306.111806)
			(xy 169.727874 -306.139762) (xy 169.683412 -306.16086) (xy 169.636141 -306.174552) (xy 169.587286 -306.180484)
			(xy 169.538111 -306.178503) (xy 169.489892 -306.168659) (xy 169.443876 -306.151207) (xy 169.401255 -306.1266)
			(xy 169.363134 -306.095475) (xy 169.330499 -306.058638) (xy 169.304196 -306.017042) (xy 169.284905 -305.971766)
			(xy 169.273128 -305.923982) (xy 169.269168 -305.874928) (xy 168.93032 -305.874928) (xy 168.929825 -305.899535)
			(xy 168.92193 -305.948112) (xy 168.906346 -305.994793) (xy 168.883475 -306.03837) (xy 168.85391 -306.077714)
			(xy 168.818417 -306.111806) (xy 168.777914 -306.139762) (xy 168.733452 -306.16086) (xy 168.686181 -306.174552)
			(xy 168.637326 -306.180484) (xy 168.588151 -306.178503) (xy 168.539932 -306.168659) (xy 168.493916 -306.151207)
			(xy 168.451295 -306.1266) (xy 168.413174 -306.095475) (xy 168.380539 -306.058638) (xy 168.354236 -306.017042)
			(xy 168.334945 -305.971766) (xy 168.323168 -305.923982) (xy 168.319208 -305.874928) (xy 167.98036 -305.874928)
			(xy 167.979865 -305.899535) (xy 167.97197 -305.948112) (xy 167.956386 -305.994793) (xy 167.933515 -306.03837)
			(xy 167.90395 -306.077714) (xy 167.868457 -306.111806) (xy 167.827954 -306.139762) (xy 167.783492 -306.16086)
			(xy 167.736221 -306.174552) (xy 167.687366 -306.180484) (xy 167.638191 -306.178503) (xy 167.589972 -306.168659)
			(xy 167.543956 -306.151207) (xy 167.501335 -306.1266) (xy 167.463214 -306.095475) (xy 167.430579 -306.058638)
			(xy 167.404276 -306.017042) (xy 167.384985 -305.971766) (xy 167.373208 -305.923982) (xy 167.369248 -305.874928)
			(xy 167.0304 -305.874928) (xy 167.029905 -305.899535) (xy 167.02201 -305.948112) (xy 167.006426 -305.994793)
			(xy 166.983555 -306.03837) (xy 166.95399 -306.077714) (xy 166.918497 -306.111806) (xy 166.877994 -306.139762)
			(xy 166.833532 -306.16086) (xy 166.786261 -306.174552) (xy 166.737406 -306.180484) (xy 166.688231 -306.178503)
			(xy 166.640012 -306.168659) (xy 166.593996 -306.151207) (xy 166.551375 -306.1266) (xy 166.513254 -306.095475)
			(xy 166.480619 -306.058638) (xy 166.454316 -306.017042) (xy 166.435025 -305.971766) (xy 166.423248 -305.923982)
			(xy 166.419288 -305.874928) (xy 166.080186 -305.874928) (xy 166.079691 -305.899535) (xy 166.071796 -305.948112)
			(xy 166.056212 -305.994793) (xy 166.033341 -306.03837) (xy 166.003776 -306.077714) (xy 165.968283 -306.111806)
			(xy 165.92778 -306.139762) (xy 165.883318 -306.16086) (xy 165.836047 -306.174552) (xy 165.787192 -306.180484)
			(xy 165.738017 -306.178503) (xy 165.689798 -306.168659) (xy 165.643782 -306.151207) (xy 165.601161 -306.1266)
			(xy 165.56304 -306.095475) (xy 165.530405 -306.058638) (xy 165.504102 -306.017042) (xy 165.484811 -305.971766)
			(xy 165.473034 -305.923982) (xy 165.469074 -305.874928) (xy 165.155056 -305.874928) (xy 165.155056 -305.901283)
			(xy 165.146678 -305.953372) (xy 165.130135 -306.003471) (xy 165.105847 -306.050306) (xy 165.074431 -306.092691)
			(xy 165.036683 -306.12955) (xy 164.993561 -306.159948) (xy 164.94616 -306.183112) (xy 164.895682 -306.198456)
			(xy 164.869622 -306.202588) (xy 164.86505 -306.20335) (xy 164.854636 -306.206652) (xy 164.850318 -306.207922)
			(xy 164.826696 -306.218844) (xy 164.819838 -306.225956) (xy 164.804852 -306.241704) (xy 164.800264 -306.246809)
			(xy 164.79382 -306.258922) (xy 164.792152 -306.26558) (xy 164.790882 -306.276502) (xy 164.790882 -306.349908)
			(xy 189.69407 -306.349908) (xy 189.69803 -306.300854) (xy 189.709807 -306.25307) (xy 189.729098 -306.207794)
			(xy 189.755401 -306.166198) (xy 189.788036 -306.129361) (xy 189.826157 -306.098236) (xy 189.868778 -306.073629)
			(xy 189.914794 -306.056177) (xy 189.963013 -306.046333) (xy 190.012188 -306.044352) (xy 190.061043 -306.050284)
			(xy 190.108314 -306.063976) (xy 190.152776 -306.085074) (xy 190.193279 -306.11303) (xy 190.228772 -306.147122)
			(xy 190.258337 -306.186466) (xy 190.281208 -306.230043) (xy 190.296792 -306.276724) (xy 190.304687 -306.325301)
			(xy 190.305182 -306.349908) (xy 190.304687 -306.374515) (xy 190.304508 -306.375616) (xy 190.62344 -306.375616)
			(xy 190.62344 -306.3242) (xy 190.631483 -306.273418) (xy 190.647371 -306.224519) (xy 190.670714 -306.178707)
			(xy 190.700935 -306.137111) (xy 190.737291 -306.100755) (xy 190.778887 -306.070534) (xy 190.824699 -306.047191)
			(xy 190.873598 -306.031303) (xy 190.92438 -306.02326) (xy 190.975796 -306.02326) (xy 191.026578 -306.031303)
			(xy 191.075477 -306.047191) (xy 191.121289 -306.070534) (xy 191.162885 -306.100755) (xy 191.199241 -306.137111)
			(xy 191.229462 -306.178707) (xy 191.252805 -306.224519) (xy 191.268693 -306.273418) (xy 191.276736 -306.3242)
			(xy 191.27724 -306.349908) (xy 191.276736 -306.375616) (xy 191.5734 -306.375616) (xy 191.5734 -306.3242)
			(xy 191.581443 -306.273418) (xy 191.597331 -306.224519) (xy 191.620674 -306.178707) (xy 191.650895 -306.137111)
			(xy 191.687251 -306.100755) (xy 191.728847 -306.070534) (xy 191.774659 -306.047191) (xy 191.823558 -306.031303)
			(xy 191.87434 -306.02326) (xy 191.925756 -306.02326) (xy 191.976538 -306.031303) (xy 192.025437 -306.047191)
			(xy 192.071249 -306.070534) (xy 192.112845 -306.100755) (xy 192.149201 -306.137111) (xy 192.179422 -306.178707)
			(xy 192.202765 -306.224519) (xy 192.218653 -306.273418) (xy 192.226696 -306.3242) (xy 192.2272 -306.349908)
			(xy 192.544204 -306.349908) (xy 192.548164 -306.300854) (xy 192.559941 -306.25307) (xy 192.579232 -306.207794)
			(xy 192.605535 -306.166198) (xy 192.63817 -306.129361) (xy 192.676291 -306.098236) (xy 192.718912 -306.073629)
			(xy 192.764928 -306.056177) (xy 192.813147 -306.046333) (xy 192.862322 -306.044352) (xy 192.911177 -306.050284)
			(xy 192.958448 -306.063976) (xy 193.00291 -306.085074) (xy 193.043413 -306.11303) (xy 193.078906 -306.147122)
			(xy 193.108471 -306.186466) (xy 193.131342 -306.230043) (xy 193.146926 -306.276724) (xy 193.154821 -306.325301)
			(xy 193.155316 -306.349908) (xy 193.494164 -306.349908) (xy 193.498124 -306.300854) (xy 193.509901 -306.25307)
			(xy 193.529192 -306.207794) (xy 193.555495 -306.166198) (xy 193.58813 -306.129361) (xy 193.626251 -306.098236)
			(xy 193.668872 -306.073629) (xy 193.714888 -306.056177) (xy 193.763107 -306.046333) (xy 193.812282 -306.044352)
			(xy 193.861137 -306.050284) (xy 193.908408 -306.063976) (xy 193.95287 -306.085074) (xy 193.993373 -306.11303)
			(xy 194.028866 -306.147122) (xy 194.058431 -306.186466) (xy 194.081302 -306.230043) (xy 194.096886 -306.276724)
			(xy 194.104781 -306.325301) (xy 194.105276 -306.349908) (xy 194.444124 -306.349908) (xy 194.448084 -306.300854)
			(xy 194.459861 -306.25307) (xy 194.479152 -306.207794) (xy 194.505455 -306.166198) (xy 194.53809 -306.129361)
			(xy 194.576211 -306.098236) (xy 194.618832 -306.073629) (xy 194.664848 -306.056177) (xy 194.713067 -306.046333)
			(xy 194.762242 -306.044352) (xy 194.811097 -306.050284) (xy 194.858368 -306.063976) (xy 194.90283 -306.085074)
			(xy 194.943333 -306.11303) (xy 194.978826 -306.147122) (xy 195.008391 -306.186466) (xy 195.031262 -306.230043)
			(xy 195.046846 -306.276724) (xy 195.054741 -306.325301) (xy 195.055236 -306.349908) (xy 195.394084 -306.349908)
			(xy 195.398044 -306.300854) (xy 195.409821 -306.25307) (xy 195.429112 -306.207794) (xy 195.455415 -306.166198)
			(xy 195.48805 -306.129361) (xy 195.526171 -306.098236) (xy 195.568792 -306.073629) (xy 195.614808 -306.056177)
			(xy 195.663027 -306.046333) (xy 195.712202 -306.044352) (xy 195.761057 -306.050284) (xy 195.808328 -306.063976)
			(xy 195.85279 -306.085074) (xy 195.893293 -306.11303) (xy 195.928786 -306.147122) (xy 195.958351 -306.186466)
			(xy 195.981222 -306.230043) (xy 195.996806 -306.276724) (xy 196.004701 -306.325301) (xy 196.005196 -306.349908)
			(xy 196.344044 -306.349908) (xy 196.348004 -306.300854) (xy 196.359781 -306.25307) (xy 196.379072 -306.207794)
			(xy 196.405375 -306.166198) (xy 196.43801 -306.129361) (xy 196.476131 -306.098236) (xy 196.518752 -306.073629)
			(xy 196.564768 -306.056177) (xy 196.612987 -306.046333) (xy 196.662162 -306.044352) (xy 196.711017 -306.050284)
			(xy 196.758288 -306.063976) (xy 196.80275 -306.085074) (xy 196.843253 -306.11303) (xy 196.878746 -306.147122)
			(xy 196.908311 -306.186466) (xy 196.931182 -306.230043) (xy 196.946766 -306.276724) (xy 196.954661 -306.325301)
			(xy 196.955156 -306.349908) (xy 196.954661 -306.374515) (xy 196.954482 -306.375616) (xy 197.273414 -306.375616)
			(xy 197.273414 -306.3242) (xy 197.281457 -306.273418) (xy 197.297345 -306.224519) (xy 197.320688 -306.178707)
			(xy 197.350909 -306.137111) (xy 197.387265 -306.100755) (xy 197.428861 -306.070534) (xy 197.474673 -306.047191)
			(xy 197.523572 -306.031303) (xy 197.574354 -306.02326) (xy 197.62577 -306.02326) (xy 197.676552 -306.031303)
			(xy 197.725451 -306.047191) (xy 197.771263 -306.070534) (xy 197.812859 -306.100755) (xy 197.849215 -306.137111)
			(xy 197.879436 -306.178707) (xy 197.902779 -306.224519) (xy 197.918667 -306.273418) (xy 197.92671 -306.3242)
			(xy 197.927214 -306.349908) (xy 197.92671 -306.375616) (xy 198.223374 -306.375616) (xy 198.223374 -306.3242)
			(xy 198.231417 -306.273418) (xy 198.247305 -306.224519) (xy 198.270648 -306.178707) (xy 198.300869 -306.137111)
			(xy 198.337225 -306.100755) (xy 198.378821 -306.070534) (xy 198.424633 -306.047191) (xy 198.473532 -306.031303)
			(xy 198.524314 -306.02326) (xy 198.57573 -306.02326) (xy 198.626512 -306.031303) (xy 198.675411 -306.047191)
			(xy 198.721223 -306.070534) (xy 198.762819 -306.100755) (xy 198.799175 -306.137111) (xy 198.829396 -306.178707)
			(xy 198.852739 -306.224519) (xy 198.868627 -306.273418) (xy 198.87667 -306.3242) (xy 198.877174 -306.349908)
			(xy 199.194432 -306.349908) (xy 199.198392 -306.300854) (xy 199.210169 -306.25307) (xy 199.22946 -306.207794)
			(xy 199.255763 -306.166198) (xy 199.288398 -306.129361) (xy 199.326519 -306.098236) (xy 199.36914 -306.073629)
			(xy 199.415156 -306.056177) (xy 199.463375 -306.046333) (xy 199.51255 -306.044352) (xy 199.561405 -306.050284)
			(xy 199.608676 -306.063976) (xy 199.653138 -306.085074) (xy 199.693641 -306.11303) (xy 199.729134 -306.147122)
			(xy 199.758699 -306.186466) (xy 199.78157 -306.230043) (xy 199.797154 -306.276724) (xy 199.805049 -306.325301)
			(xy 199.805544 -306.349908) (xy 199.805049 -306.374515) (xy 199.797154 -306.423092) (xy 199.78157 -306.469773)
			(xy 199.758699 -306.51335) (xy 199.729134 -306.552694) (xy 199.693641 -306.586786) (xy 199.653138 -306.614742)
			(xy 199.608676 -306.63584) (xy 199.561405 -306.649532) (xy 199.51255 -306.655464) (xy 199.463375 -306.653483)
			(xy 199.415156 -306.643639) (xy 199.36914 -306.626187) (xy 199.326519 -306.60158) (xy 199.288398 -306.570455)
			(xy 199.255763 -306.533618) (xy 199.22946 -306.492022) (xy 199.210169 -306.446746) (xy 199.198392 -306.398962)
			(xy 199.194432 -306.349908) (xy 198.877174 -306.349908) (xy 198.87667 -306.375616) (xy 198.868627 -306.426398)
			(xy 198.852739 -306.475297) (xy 198.829396 -306.521109) (xy 198.799175 -306.562705) (xy 198.762819 -306.599061)
			(xy 198.721223 -306.629282) (xy 198.675411 -306.652625) (xy 198.626512 -306.668513) (xy 198.57573 -306.676556)
			(xy 198.524314 -306.676556) (xy 198.473532 -306.668513) (xy 198.424633 -306.652625) (xy 198.378821 -306.629282)
			(xy 198.337225 -306.599061) (xy 198.300869 -306.562705) (xy 198.270648 -306.521109) (xy 198.247305 -306.475297)
			(xy 198.231417 -306.426398) (xy 198.223374 -306.375616) (xy 197.92671 -306.375616) (xy 197.918667 -306.426398)
			(xy 197.902779 -306.475297) (xy 197.879436 -306.521109) (xy 197.849215 -306.562705) (xy 197.812859 -306.599061)
			(xy 197.771263 -306.629282) (xy 197.725451 -306.652625) (xy 197.676552 -306.668513) (xy 197.62577 -306.676556)
			(xy 197.574354 -306.676556) (xy 197.523572 -306.668513) (xy 197.474673 -306.652625) (xy 197.428861 -306.629282)
			(xy 197.387265 -306.599061) (xy 197.350909 -306.562705) (xy 197.320688 -306.521109) (xy 197.297345 -306.475297)
			(xy 197.281457 -306.426398) (xy 197.273414 -306.375616) (xy 196.954482 -306.375616) (xy 196.946766 -306.423092)
			(xy 196.931182 -306.469773) (xy 196.908311 -306.51335) (xy 196.878746 -306.552694) (xy 196.843253 -306.586786)
			(xy 196.80275 -306.614742) (xy 196.758288 -306.63584) (xy 196.711017 -306.649532) (xy 196.662162 -306.655464)
			(xy 196.612987 -306.653483) (xy 196.564768 -306.643639) (xy 196.518752 -306.626187) (xy 196.476131 -306.60158)
			(xy 196.43801 -306.570455) (xy 196.405375 -306.533618) (xy 196.379072 -306.492022) (xy 196.359781 -306.446746)
			(xy 196.348004 -306.398962) (xy 196.344044 -306.349908) (xy 196.005196 -306.349908) (xy 196.004701 -306.374515)
			(xy 195.996806 -306.423092) (xy 195.981222 -306.469773) (xy 195.958351 -306.51335) (xy 195.928786 -306.552694)
			(xy 195.893293 -306.586786) (xy 195.85279 -306.614742) (xy 195.808328 -306.63584) (xy 195.761057 -306.649532)
			(xy 195.712202 -306.655464) (xy 195.663027 -306.653483) (xy 195.614808 -306.643639) (xy 195.568792 -306.626187)
			(xy 195.526171 -306.60158) (xy 195.48805 -306.570455) (xy 195.455415 -306.533618) (xy 195.429112 -306.492022)
			(xy 195.409821 -306.446746) (xy 195.398044 -306.398962) (xy 195.394084 -306.349908) (xy 195.055236 -306.349908)
			(xy 195.054741 -306.374515) (xy 195.046846 -306.423092) (xy 195.031262 -306.469773) (xy 195.008391 -306.51335)
			(xy 194.978826 -306.552694) (xy 194.943333 -306.586786) (xy 194.90283 -306.614742) (xy 194.858368 -306.63584)
			(xy 194.811097 -306.649532) (xy 194.762242 -306.655464) (xy 194.713067 -306.653483) (xy 194.664848 -306.643639)
			(xy 194.618832 -306.626187) (xy 194.576211 -306.60158) (xy 194.53809 -306.570455) (xy 194.505455 -306.533618)
			(xy 194.479152 -306.492022) (xy 194.459861 -306.446746) (xy 194.448084 -306.398962) (xy 194.444124 -306.349908)
			(xy 194.105276 -306.349908) (xy 194.104781 -306.374515) (xy 194.096886 -306.423092) (xy 194.081302 -306.469773)
			(xy 194.058431 -306.51335) (xy 194.028866 -306.552694) (xy 193.993373 -306.586786) (xy 193.95287 -306.614742)
			(xy 193.908408 -306.63584) (xy 193.861137 -306.649532) (xy 193.812282 -306.655464) (xy 193.763107 -306.653483)
			(xy 193.714888 -306.643639) (xy 193.668872 -306.626187) (xy 193.626251 -306.60158) (xy 193.58813 -306.570455)
			(xy 193.555495 -306.533618) (xy 193.529192 -306.492022) (xy 193.509901 -306.446746) (xy 193.498124 -306.398962)
			(xy 193.494164 -306.349908) (xy 193.155316 -306.349908) (xy 193.154821 -306.374515) (xy 193.146926 -306.423092)
			(xy 193.131342 -306.469773) (xy 193.108471 -306.51335) (xy 193.078906 -306.552694) (xy 193.043413 -306.586786)
			(xy 193.00291 -306.614742) (xy 192.958448 -306.63584) (xy 192.911177 -306.649532) (xy 192.862322 -306.655464)
			(xy 192.813147 -306.653483) (xy 192.764928 -306.643639) (xy 192.718912 -306.626187) (xy 192.676291 -306.60158)
			(xy 192.63817 -306.570455) (xy 192.605535 -306.533618) (xy 192.579232 -306.492022) (xy 192.559941 -306.446746)
			(xy 192.548164 -306.398962) (xy 192.544204 -306.349908) (xy 192.2272 -306.349908) (xy 192.226696 -306.375616)
			(xy 192.218653 -306.426398) (xy 192.202765 -306.475297) (xy 192.179422 -306.521109) (xy 192.149201 -306.562705)
			(xy 192.112845 -306.599061) (xy 192.071249 -306.629282) (xy 192.025437 -306.652625) (xy 191.976538 -306.668513)
			(xy 191.925756 -306.676556) (xy 191.87434 -306.676556) (xy 191.823558 -306.668513) (xy 191.774659 -306.652625)
			(xy 191.728847 -306.629282) (xy 191.687251 -306.599061) (xy 191.650895 -306.562705) (xy 191.620674 -306.521109)
			(xy 191.597331 -306.475297) (xy 191.581443 -306.426398) (xy 191.5734 -306.375616) (xy 191.276736 -306.375616)
			(xy 191.268693 -306.426398) (xy 191.252805 -306.475297) (xy 191.229462 -306.521109) (xy 191.199241 -306.562705)
			(xy 191.162885 -306.599061) (xy 191.121289 -306.629282) (xy 191.075477 -306.652625) (xy 191.026578 -306.668513)
			(xy 190.975796 -306.676556) (xy 190.92438 -306.676556) (xy 190.873598 -306.668513) (xy 190.824699 -306.652625)
			(xy 190.778887 -306.629282) (xy 190.737291 -306.599061) (xy 190.700935 -306.562705) (xy 190.670714 -306.521109)
			(xy 190.647371 -306.475297) (xy 190.631483 -306.426398) (xy 190.62344 -306.375616) (xy 190.304508 -306.375616)
			(xy 190.296792 -306.423092) (xy 190.281208 -306.469773) (xy 190.258337 -306.51335) (xy 190.228772 -306.552694)
			(xy 190.193279 -306.586786) (xy 190.152776 -306.614742) (xy 190.108314 -306.63584) (xy 190.061043 -306.649532)
			(xy 190.012188 -306.655464) (xy 189.963013 -306.653483) (xy 189.914794 -306.643639) (xy 189.868778 -306.626187)
			(xy 189.826157 -306.60158) (xy 189.788036 -306.570455) (xy 189.755401 -306.533618) (xy 189.729098 -306.492022)
			(xy 189.709807 -306.446746) (xy 189.69803 -306.398962) (xy 189.69407 -306.349908) (xy 164.790882 -306.349908)
			(xy 164.790882 -306.423314) (xy 164.791348 -306.432947) (xy 164.798526 -306.450832) (xy 164.804852 -306.458112)
			(xy 164.820092 -306.474114) (xy 164.82695 -306.48148) (xy 164.850318 -306.491894) (xy 164.854636 -306.493164)
			(xy 164.86505 -306.496466) (xy 164.869622 -306.497228) (xy 164.895693 -306.501305) (xy 164.946177 -306.516652)
			(xy 164.993584 -306.539819) (xy 165.03671 -306.570221) (xy 165.074462 -306.607084) (xy 165.105882 -306.649474)
			(xy 165.130172 -306.696316) (xy 165.146717 -306.74642) (xy 165.155095 -306.798516) (xy 165.155095 -306.824888)
			(xy 165.469074 -306.824888) (xy 165.473034 -306.775834) (xy 165.484811 -306.72805) (xy 165.504102 -306.682774)
			(xy 165.530405 -306.641178) (xy 165.56304 -306.604341) (xy 165.601161 -306.573216) (xy 165.643782 -306.548609)
			(xy 165.689798 -306.531157) (xy 165.738017 -306.521313) (xy 165.787192 -306.519332) (xy 165.836047 -306.525264)
			(xy 165.883318 -306.538956) (xy 165.92778 -306.560054) (xy 165.968283 -306.58801) (xy 166.003776 -306.622102)
			(xy 166.033341 -306.661446) (xy 166.056212 -306.705023) (xy 166.071796 -306.751704) (xy 166.079691 -306.800281)
			(xy 166.080186 -306.824888) (xy 166.419288 -306.824888) (xy 166.423248 -306.775834) (xy 166.435025 -306.72805)
			(xy 166.454316 -306.682774) (xy 166.480619 -306.641178) (xy 166.513254 -306.604341) (xy 166.551375 -306.573216)
			(xy 166.593996 -306.548609) (xy 166.640012 -306.531157) (xy 166.688231 -306.521313) (xy 166.737406 -306.519332)
			(xy 166.786261 -306.525264) (xy 166.833532 -306.538956) (xy 166.877994 -306.560054) (xy 166.918497 -306.58801)
			(xy 166.95399 -306.622102) (xy 166.983555 -306.661446) (xy 167.006426 -306.705023) (xy 167.02201 -306.751704)
			(xy 167.029905 -306.800281) (xy 167.0304 -306.824888) (xy 167.369248 -306.824888) (xy 167.373208 -306.775834)
			(xy 167.384985 -306.72805) (xy 167.404276 -306.682774) (xy 167.430579 -306.641178) (xy 167.463214 -306.604341)
			(xy 167.501335 -306.573216) (xy 167.543956 -306.548609) (xy 167.589972 -306.531157) (xy 167.638191 -306.521313)
			(xy 167.687366 -306.519332) (xy 167.736221 -306.525264) (xy 167.783492 -306.538956) (xy 167.827954 -306.560054)
			(xy 167.868457 -306.58801) (xy 167.90395 -306.622102) (xy 167.933515 -306.661446) (xy 167.956386 -306.705023)
			(xy 167.97197 -306.751704) (xy 167.979865 -306.800281) (xy 167.98036 -306.824888) (xy 168.319208 -306.824888)
			(xy 168.323168 -306.775834) (xy 168.334945 -306.72805) (xy 168.354236 -306.682774) (xy 168.380539 -306.641178)
			(xy 168.413174 -306.604341) (xy 168.451295 -306.573216) (xy 168.493916 -306.548609) (xy 168.539932 -306.531157)
			(xy 168.588151 -306.521313) (xy 168.637326 -306.519332) (xy 168.686181 -306.525264) (xy 168.733452 -306.538956)
			(xy 168.777914 -306.560054) (xy 168.818417 -306.58801) (xy 168.85391 -306.622102) (xy 168.883475 -306.661446)
			(xy 168.906346 -306.705023) (xy 168.92193 -306.751704) (xy 168.929825 -306.800281) (xy 168.93032 -306.824888)
			(xy 169.269168 -306.824888) (xy 169.273128 -306.775834) (xy 169.284905 -306.72805) (xy 169.304196 -306.682774)
			(xy 169.330499 -306.641178) (xy 169.363134 -306.604341) (xy 169.401255 -306.573216) (xy 169.443876 -306.548609)
			(xy 169.489892 -306.531157) (xy 169.538111 -306.521313) (xy 169.587286 -306.519332) (xy 169.636141 -306.525264)
			(xy 169.683412 -306.538956) (xy 169.727874 -306.560054) (xy 169.768377 -306.58801) (xy 169.80387 -306.622102)
			(xy 169.833435 -306.661446) (xy 169.856306 -306.705023) (xy 169.87189 -306.751704) (xy 169.879785 -306.800281)
			(xy 169.88028 -306.824888) (xy 170.219128 -306.824888) (xy 170.223088 -306.775834) (xy 170.234865 -306.72805)
			(xy 170.254156 -306.682774) (xy 170.280459 -306.641178) (xy 170.313094 -306.604341) (xy 170.351215 -306.573216)
			(xy 170.393836 -306.548609) (xy 170.439852 -306.531157) (xy 170.488071 -306.521313) (xy 170.537246 -306.519332)
			(xy 170.586101 -306.525264) (xy 170.633372 -306.538956) (xy 170.677834 -306.560054) (xy 170.718337 -306.58801)
			(xy 170.75383 -306.622102) (xy 170.783395 -306.661446) (xy 170.806266 -306.705023) (xy 170.82185 -306.751704)
			(xy 170.829745 -306.800281) (xy 170.83024 -306.824888) (xy 171.169088 -306.824888) (xy 171.173048 -306.775834)
			(xy 171.184825 -306.72805) (xy 171.204116 -306.682774) (xy 171.230419 -306.641178) (xy 171.263054 -306.604341)
			(xy 171.301175 -306.573216) (xy 171.343796 -306.548609) (xy 171.389812 -306.531157) (xy 171.438031 -306.521313)
			(xy 171.487206 -306.519332) (xy 171.536061 -306.525264) (xy 171.583332 -306.538956) (xy 171.627794 -306.560054)
			(xy 171.668297 -306.58801) (xy 171.70379 -306.622102) (xy 171.733355 -306.661446) (xy 171.756226 -306.705023)
			(xy 171.77181 -306.751704) (xy 171.779705 -306.800281) (xy 171.7802 -306.824888) (xy 172.119048 -306.824888)
			(xy 172.123008 -306.775834) (xy 172.134785 -306.72805) (xy 172.154076 -306.682774) (xy 172.180379 -306.641178)
			(xy 172.213014 -306.604341) (xy 172.251135 -306.573216) (xy 172.293756 -306.548609) (xy 172.339772 -306.531157)
			(xy 172.387991 -306.521313) (xy 172.437166 -306.519332) (xy 172.486021 -306.525264) (xy 172.533292 -306.538956)
			(xy 172.577754 -306.560054) (xy 172.618257 -306.58801) (xy 172.65375 -306.622102) (xy 172.683315 -306.661446)
			(xy 172.706186 -306.705023) (xy 172.72177 -306.751704) (xy 172.729665 -306.800281) (xy 172.73016 -306.824888)
			(xy 173.069262 -306.824888) (xy 173.073222 -306.775834) (xy 173.084999 -306.72805) (xy 173.10429 -306.682774)
			(xy 173.130593 -306.641178) (xy 173.163228 -306.604341) (xy 173.201349 -306.573216) (xy 173.24397 -306.548609)
			(xy 173.289986 -306.531157) (xy 173.338205 -306.521313) (xy 173.38738 -306.519332) (xy 173.436235 -306.525264)
			(xy 173.483506 -306.538956) (xy 173.527968 -306.560054) (xy 173.568471 -306.58801) (xy 173.603964 -306.622102)
			(xy 173.633529 -306.661446) (xy 173.6564 -306.705023) (xy 173.671984 -306.751704) (xy 173.679879 -306.800281)
			(xy 173.680374 -306.824888) (xy 174.019222 -306.824888) (xy 174.023182 -306.775834) (xy 174.034959 -306.72805)
			(xy 174.05425 -306.682774) (xy 174.080553 -306.641178) (xy 174.113188 -306.604341) (xy 174.151309 -306.573216)
			(xy 174.19393 -306.548609) (xy 174.239946 -306.531157) (xy 174.288165 -306.521313) (xy 174.33734 -306.519332)
			(xy 174.386195 -306.525264) (xy 174.433466 -306.538956) (xy 174.477928 -306.560054) (xy 174.518431 -306.58801)
			(xy 174.553924 -306.622102) (xy 174.583489 -306.661446) (xy 174.60636 -306.705023) (xy 174.621944 -306.751704)
			(xy 174.629839 -306.800281) (xy 174.630334 -306.824888) (xy 175.919142 -306.824888) (xy 175.923102 -306.775834)
			(xy 175.934879 -306.72805) (xy 175.95417 -306.682774) (xy 175.980473 -306.641178) (xy 176.013108 -306.604341)
			(xy 176.051229 -306.573216) (xy 176.09385 -306.548609) (xy 176.139866 -306.531157) (xy 176.188085 -306.521313)
			(xy 176.23726 -306.519332) (xy 176.286115 -306.525264) (xy 176.333386 -306.538956) (xy 176.377848 -306.560054)
			(xy 176.418351 -306.58801) (xy 176.453844 -306.622102) (xy 176.483409 -306.661446) (xy 176.50628 -306.705023)
			(xy 176.521864 -306.751704) (xy 176.529759 -306.800281) (xy 176.530254 -306.824888) (xy 176.869102 -306.824888)
			(xy 176.873062 -306.775834) (xy 176.884839 -306.72805) (xy 176.90413 -306.682774) (xy 176.930433 -306.641178)
			(xy 176.963068 -306.604341) (xy 177.001189 -306.573216) (xy 177.04381 -306.548609) (xy 177.089826 -306.531157)
			(xy 177.138045 -306.521313) (xy 177.18722 -306.519332) (xy 177.236075 -306.525264) (xy 177.283346 -306.538956)
			(xy 177.327808 -306.560054) (xy 177.368311 -306.58801) (xy 177.403804 -306.622102) (xy 177.433369 -306.661446)
			(xy 177.45624 -306.705023) (xy 177.471824 -306.751704) (xy 177.479719 -306.800281) (xy 177.480214 -306.824888)
			(xy 177.819062 -306.824888) (xy 177.823022 -306.775834) (xy 177.834799 -306.72805) (xy 177.85409 -306.682774)
			(xy 177.880393 -306.641178) (xy 177.913028 -306.604341) (xy 177.951149 -306.573216) (xy 177.99377 -306.548609)
			(xy 178.039786 -306.531157) (xy 178.088005 -306.521313) (xy 178.13718 -306.519332) (xy 178.186035 -306.525264)
			(xy 178.233306 -306.538956) (xy 178.277768 -306.560054) (xy 178.318271 -306.58801) (xy 178.353764 -306.622102)
			(xy 178.383329 -306.661446) (xy 178.4062 -306.705023) (xy 178.421784 -306.751704) (xy 178.429679 -306.800281)
			(xy 178.430174 -306.824888) (xy 178.769276 -306.824888) (xy 178.773236 -306.775834) (xy 178.785013 -306.72805)
			(xy 178.804304 -306.682774) (xy 178.830607 -306.641178) (xy 178.863242 -306.604341) (xy 178.901363 -306.573216)
			(xy 178.943984 -306.548609) (xy 178.99 -306.531157) (xy 179.038219 -306.521313) (xy 179.087394 -306.519332)
			(xy 179.136249 -306.525264) (xy 179.18352 -306.538956) (xy 179.227982 -306.560054) (xy 179.268485 -306.58801)
			(xy 179.303978 -306.622102) (xy 179.333543 -306.661446) (xy 179.356414 -306.705023) (xy 179.371998 -306.751704)
			(xy 179.379893 -306.800281) (xy 179.380388 -306.824888) (xy 179.719236 -306.824888) (xy 179.723196 -306.775834)
			(xy 179.734973 -306.72805) (xy 179.754264 -306.682774) (xy 179.780567 -306.641178) (xy 179.813202 -306.604341)
			(xy 179.851323 -306.573216) (xy 179.893944 -306.548609) (xy 179.93996 -306.531157) (xy 179.988179 -306.521313)
			(xy 180.037354 -306.519332) (xy 180.086209 -306.525264) (xy 180.13348 -306.538956) (xy 180.177942 -306.560054)
			(xy 180.218445 -306.58801) (xy 180.253938 -306.622102) (xy 180.283503 -306.661446) (xy 180.306374 -306.705023)
			(xy 180.321958 -306.751704) (xy 180.329853 -306.800281) (xy 180.330348 -306.824888) (xy 180.669196 -306.824888)
			(xy 180.673156 -306.775834) (xy 180.684933 -306.72805) (xy 180.704224 -306.682774) (xy 180.730527 -306.641178)
			(xy 180.763162 -306.604341) (xy 180.801283 -306.573216) (xy 180.843904 -306.548609) (xy 180.88992 -306.531157)
			(xy 180.938139 -306.521313) (xy 180.987314 -306.519332) (xy 181.036169 -306.525264) (xy 181.08344 -306.538956)
			(xy 181.127902 -306.560054) (xy 181.168405 -306.58801) (xy 181.203898 -306.622102) (xy 181.233463 -306.661446)
			(xy 181.256334 -306.705023) (xy 181.271918 -306.751704) (xy 181.279813 -306.800281) (xy 181.280308 -306.824888)
			(xy 181.619156 -306.824888) (xy 181.623116 -306.775834) (xy 181.634893 -306.72805) (xy 181.654184 -306.682774)
			(xy 181.680487 -306.641178) (xy 181.713122 -306.604341) (xy 181.751243 -306.573216) (xy 181.793864 -306.548609)
			(xy 181.83988 -306.531157) (xy 181.888099 -306.521313) (xy 181.937274 -306.519332) (xy 181.986129 -306.525264)
			(xy 182.0334 -306.538956) (xy 182.077862 -306.560054) (xy 182.118365 -306.58801) (xy 182.153858 -306.622102)
			(xy 182.183423 -306.661446) (xy 182.206294 -306.705023) (xy 182.221878 -306.751704) (xy 182.229773 -306.800281)
			(xy 182.230268 -306.824888) (xy 182.569116 -306.824888) (xy 182.573076 -306.775834) (xy 182.584853 -306.72805)
			(xy 182.604144 -306.682774) (xy 182.630447 -306.641178) (xy 182.663082 -306.604341) (xy 182.701203 -306.573216)
			(xy 182.743824 -306.548609) (xy 182.78984 -306.531157) (xy 182.838059 -306.521313) (xy 182.887234 -306.519332)
			(xy 182.936089 -306.525264) (xy 182.98336 -306.538956) (xy 183.027822 -306.560054) (xy 183.068325 -306.58801)
			(xy 183.103818 -306.622102) (xy 183.133383 -306.661446) (xy 183.156254 -306.705023) (xy 183.171838 -306.751704)
			(xy 183.179733 -306.800281) (xy 183.180228 -306.824888) (xy 183.519076 -306.824888) (xy 183.523036 -306.775834)
			(xy 183.534813 -306.72805) (xy 183.554104 -306.682774) (xy 183.580407 -306.641178) (xy 183.613042 -306.604341)
			(xy 183.651163 -306.573216) (xy 183.693784 -306.548609) (xy 183.7398 -306.531157) (xy 183.788019 -306.521313)
			(xy 183.837194 -306.519332) (xy 183.886049 -306.525264) (xy 183.93332 -306.538956) (xy 183.977782 -306.560054)
			(xy 184.018285 -306.58801) (xy 184.053778 -306.622102) (xy 184.083343 -306.661446) (xy 184.106214 -306.705023)
			(xy 184.121798 -306.751704) (xy 184.129693 -306.800281) (xy 184.130188 -306.824888) (xy 184.469036 -306.824888)
			(xy 184.472996 -306.775834) (xy 184.484773 -306.72805) (xy 184.504064 -306.682774) (xy 184.530367 -306.641178)
			(xy 184.563002 -306.604341) (xy 184.601123 -306.573216) (xy 184.643744 -306.548609) (xy 184.68976 -306.531157)
			(xy 184.737979 -306.521313) (xy 184.787154 -306.519332) (xy 184.836009 -306.525264) (xy 184.88328 -306.538956)
			(xy 184.927742 -306.560054) (xy 184.968245 -306.58801) (xy 185.003738 -306.622102) (xy 185.033303 -306.661446)
			(xy 185.056174 -306.705023) (xy 185.071758 -306.751704) (xy 185.079653 -306.800281) (xy 185.080148 -306.824888)
			(xy 185.41925 -306.824888) (xy 185.42321 -306.775834) (xy 185.434987 -306.72805) (xy 185.454278 -306.682774)
			(xy 185.480581 -306.641178) (xy 185.513216 -306.604341) (xy 185.551337 -306.573216) (xy 185.593958 -306.548609)
			(xy 185.639974 -306.531157) (xy 185.688193 -306.521313) (xy 185.737368 -306.519332) (xy 185.786223 -306.525264)
			(xy 185.833494 -306.538956) (xy 185.877956 -306.560054) (xy 185.918459 -306.58801) (xy 185.953952 -306.622102)
			(xy 185.983517 -306.661446) (xy 186.006388 -306.705023) (xy 186.021972 -306.751704) (xy 186.029867 -306.800281)
			(xy 186.030362 -306.824888) (xy 186.36921 -306.824888) (xy 186.37317 -306.775834) (xy 186.384947 -306.72805)
			(xy 186.404238 -306.682774) (xy 186.430541 -306.641178) (xy 186.463176 -306.604341) (xy 186.501297 -306.573216)
			(xy 186.543918 -306.548609) (xy 186.589934 -306.531157) (xy 186.638153 -306.521313) (xy 186.687328 -306.519332)
			(xy 186.736183 -306.525264) (xy 186.783454 -306.538956) (xy 186.827916 -306.560054) (xy 186.868419 -306.58801)
			(xy 186.903912 -306.622102) (xy 186.933477 -306.661446) (xy 186.956348 -306.705023) (xy 186.971932 -306.751704)
			(xy 186.979827 -306.800281) (xy 186.980322 -306.824888) (xy 187.31917 -306.824888) (xy 187.32313 -306.775834)
			(xy 187.334907 -306.72805) (xy 187.354198 -306.682774) (xy 187.380501 -306.641178) (xy 187.413136 -306.604341)
			(xy 187.451257 -306.573216) (xy 187.493878 -306.548609) (xy 187.539894 -306.531157) (xy 187.588113 -306.521313)
			(xy 187.637288 -306.519332) (xy 187.686143 -306.525264) (xy 187.733414 -306.538956) (xy 187.777876 -306.560054)
			(xy 187.818379 -306.58801) (xy 187.853872 -306.622102) (xy 187.883437 -306.661446) (xy 187.906308 -306.705023)
			(xy 187.921892 -306.751704) (xy 187.929787 -306.800281) (xy 187.930282 -306.824888) (xy 188.26913 -306.824888)
			(xy 188.27309 -306.775834) (xy 188.284867 -306.72805) (xy 188.304158 -306.682774) (xy 188.330461 -306.641178)
			(xy 188.363096 -306.604341) (xy 188.401217 -306.573216) (xy 188.443838 -306.548609) (xy 188.489854 -306.531157)
			(xy 188.538073 -306.521313) (xy 188.587248 -306.519332) (xy 188.636103 -306.525264) (xy 188.683374 -306.538956)
			(xy 188.727836 -306.560054) (xy 188.768339 -306.58801) (xy 188.803832 -306.622102) (xy 188.833397 -306.661446)
			(xy 188.856268 -306.705023) (xy 188.871852 -306.751704) (xy 188.879747 -306.800281) (xy 188.880242 -306.824888)
			(xy 188.879747 -306.849495) (xy 188.871852 -306.898072) (xy 188.856268 -306.944753) (xy 188.833397 -306.98833)
			(xy 188.803832 -307.027674) (xy 188.768339 -307.061766) (xy 188.727836 -307.089722) (xy 188.683374 -307.11082)
			(xy 188.636103 -307.124512) (xy 188.587248 -307.130444) (xy 188.538073 -307.128463) (xy 188.489854 -307.118619)
			(xy 188.443838 -307.101167) (xy 188.401217 -307.07656) (xy 188.363096 -307.045435) (xy 188.330461 -307.008598)
			(xy 188.304158 -306.967002) (xy 188.284867 -306.921726) (xy 188.27309 -306.873942) (xy 188.26913 -306.824888)
			(xy 187.930282 -306.824888) (xy 187.929787 -306.849495) (xy 187.921892 -306.898072) (xy 187.906308 -306.944753)
			(xy 187.883437 -306.98833) (xy 187.853872 -307.027674) (xy 187.818379 -307.061766) (xy 187.777876 -307.089722)
			(xy 187.733414 -307.11082) (xy 187.686143 -307.124512) (xy 187.637288 -307.130444) (xy 187.588113 -307.128463)
			(xy 187.539894 -307.118619) (xy 187.493878 -307.101167) (xy 187.451257 -307.07656) (xy 187.413136 -307.045435)
			(xy 187.380501 -307.008598) (xy 187.354198 -306.967002) (xy 187.334907 -306.921726) (xy 187.32313 -306.873942)
			(xy 187.31917 -306.824888) (xy 186.980322 -306.824888) (xy 186.979827 -306.849495) (xy 186.971932 -306.898072)
			(xy 186.956348 -306.944753) (xy 186.933477 -306.98833) (xy 186.903912 -307.027674) (xy 186.868419 -307.061766)
			(xy 186.827916 -307.089722) (xy 186.783454 -307.11082) (xy 186.736183 -307.124512) (xy 186.687328 -307.130444)
			(xy 186.638153 -307.128463) (xy 186.589934 -307.118619) (xy 186.543918 -307.101167) (xy 186.501297 -307.07656)
			(xy 186.463176 -307.045435) (xy 186.430541 -307.008598) (xy 186.404238 -306.967002) (xy 186.384947 -306.921726)
			(xy 186.37317 -306.873942) (xy 186.36921 -306.824888) (xy 186.030362 -306.824888) (xy 186.029867 -306.849495)
			(xy 186.021972 -306.898072) (xy 186.006388 -306.944753) (xy 185.983517 -306.98833) (xy 185.953952 -307.027674)
			(xy 185.918459 -307.061766) (xy 185.877956 -307.089722) (xy 185.833494 -307.11082) (xy 185.786223 -307.124512)
			(xy 185.737368 -307.130444) (xy 185.688193 -307.128463) (xy 185.639974 -307.118619) (xy 185.593958 -307.101167)
			(xy 185.551337 -307.07656) (xy 185.513216 -307.045435) (xy 185.480581 -307.008598) (xy 185.454278 -306.967002)
			(xy 185.434987 -306.921726) (xy 185.42321 -306.873942) (xy 185.41925 -306.824888) (xy 185.080148 -306.824888)
			(xy 185.079653 -306.849495) (xy 185.071758 -306.898072) (xy 185.056174 -306.944753) (xy 185.033303 -306.98833)
			(xy 185.003738 -307.027674) (xy 184.968245 -307.061766) (xy 184.927742 -307.089722) (xy 184.88328 -307.11082)
			(xy 184.836009 -307.124512) (xy 184.787154 -307.130444) (xy 184.737979 -307.128463) (xy 184.68976 -307.118619)
			(xy 184.643744 -307.101167) (xy 184.601123 -307.07656) (xy 184.563002 -307.045435) (xy 184.530367 -307.008598)
			(xy 184.504064 -306.967002) (xy 184.484773 -306.921726) (xy 184.472996 -306.873942) (xy 184.469036 -306.824888)
			(xy 184.130188 -306.824888) (xy 184.129693 -306.849495) (xy 184.121798 -306.898072) (xy 184.106214 -306.944753)
			(xy 184.083343 -306.98833) (xy 184.053778 -307.027674) (xy 184.018285 -307.061766) (xy 183.977782 -307.089722)
			(xy 183.93332 -307.11082) (xy 183.886049 -307.124512) (xy 183.837194 -307.130444) (xy 183.788019 -307.128463)
			(xy 183.7398 -307.118619) (xy 183.693784 -307.101167) (xy 183.651163 -307.07656) (xy 183.613042 -307.045435)
			(xy 183.580407 -307.008598) (xy 183.554104 -306.967002) (xy 183.534813 -306.921726) (xy 183.523036 -306.873942)
			(xy 183.519076 -306.824888) (xy 183.180228 -306.824888) (xy 183.179733 -306.849495) (xy 183.171838 -306.898072)
			(xy 183.156254 -306.944753) (xy 183.133383 -306.98833) (xy 183.103818 -307.027674) (xy 183.068325 -307.061766)
			(xy 183.027822 -307.089722) (xy 182.98336 -307.11082) (xy 182.936089 -307.124512) (xy 182.887234 -307.130444)
			(xy 182.838059 -307.128463) (xy 182.78984 -307.118619) (xy 182.743824 -307.101167) (xy 182.701203 -307.07656)
			(xy 182.663082 -307.045435) (xy 182.630447 -307.008598) (xy 182.604144 -306.967002) (xy 182.584853 -306.921726)
			(xy 182.573076 -306.873942) (xy 182.569116 -306.824888) (xy 182.230268 -306.824888) (xy 182.229773 -306.849495)
			(xy 182.221878 -306.898072) (xy 182.206294 -306.944753) (xy 182.183423 -306.98833) (xy 182.153858 -307.027674)
			(xy 182.118365 -307.061766) (xy 182.077862 -307.089722) (xy 182.0334 -307.11082) (xy 181.986129 -307.124512)
			(xy 181.937274 -307.130444) (xy 181.888099 -307.128463) (xy 181.83988 -307.118619) (xy 181.793864 -307.101167)
			(xy 181.751243 -307.07656) (xy 181.713122 -307.045435) (xy 181.680487 -307.008598) (xy 181.654184 -306.967002)
			(xy 181.634893 -306.921726) (xy 181.623116 -306.873942) (xy 181.619156 -306.824888) (xy 181.280308 -306.824888)
			(xy 181.279813 -306.849495) (xy 181.271918 -306.898072) (xy 181.256334 -306.944753) (xy 181.233463 -306.98833)
			(xy 181.203898 -307.027674) (xy 181.168405 -307.061766) (xy 181.127902 -307.089722) (xy 181.08344 -307.11082)
			(xy 181.036169 -307.124512) (xy 180.987314 -307.130444) (xy 180.938139 -307.128463) (xy 180.88992 -307.118619)
			(xy 180.843904 -307.101167) (xy 180.801283 -307.07656) (xy 180.763162 -307.045435) (xy 180.730527 -307.008598)
			(xy 180.704224 -306.967002) (xy 180.684933 -306.921726) (xy 180.673156 -306.873942) (xy 180.669196 -306.824888)
			(xy 180.330348 -306.824888) (xy 180.329853 -306.849495) (xy 180.321958 -306.898072) (xy 180.306374 -306.944753)
			(xy 180.283503 -306.98833) (xy 180.253938 -307.027674) (xy 180.218445 -307.061766) (xy 180.177942 -307.089722)
			(xy 180.13348 -307.11082) (xy 180.086209 -307.124512) (xy 180.037354 -307.130444) (xy 179.988179 -307.128463)
			(xy 179.93996 -307.118619) (xy 179.893944 -307.101167) (xy 179.851323 -307.07656) (xy 179.813202 -307.045435)
			(xy 179.780567 -307.008598) (xy 179.754264 -306.967002) (xy 179.734973 -306.921726) (xy 179.723196 -306.873942)
			(xy 179.719236 -306.824888) (xy 179.380388 -306.824888) (xy 179.379893 -306.849495) (xy 179.371998 -306.898072)
			(xy 179.356414 -306.944753) (xy 179.333543 -306.98833) (xy 179.303978 -307.027674) (xy 179.268485 -307.061766)
			(xy 179.227982 -307.089722) (xy 179.18352 -307.11082) (xy 179.136249 -307.124512) (xy 179.087394 -307.130444)
			(xy 179.038219 -307.128463) (xy 178.99 -307.118619) (xy 178.943984 -307.101167) (xy 178.901363 -307.07656)
			(xy 178.863242 -307.045435) (xy 178.830607 -307.008598) (xy 178.804304 -306.967002) (xy 178.785013 -306.921726)
			(xy 178.773236 -306.873942) (xy 178.769276 -306.824888) (xy 178.430174 -306.824888) (xy 178.429679 -306.849495)
			(xy 178.421784 -306.898072) (xy 178.4062 -306.944753) (xy 178.383329 -306.98833) (xy 178.353764 -307.027674)
			(xy 178.318271 -307.061766) (xy 178.277768 -307.089722) (xy 178.233306 -307.11082) (xy 178.186035 -307.124512)
			(xy 178.13718 -307.130444) (xy 178.088005 -307.128463) (xy 178.039786 -307.118619) (xy 177.99377 -307.101167)
			(xy 177.951149 -307.07656) (xy 177.913028 -307.045435) (xy 177.880393 -307.008598) (xy 177.85409 -306.967002)
			(xy 177.834799 -306.921726) (xy 177.823022 -306.873942) (xy 177.819062 -306.824888) (xy 177.480214 -306.824888)
			(xy 177.479719 -306.849495) (xy 177.471824 -306.898072) (xy 177.45624 -306.944753) (xy 177.433369 -306.98833)
			(xy 177.403804 -307.027674) (xy 177.368311 -307.061766) (xy 177.327808 -307.089722) (xy 177.283346 -307.11082)
			(xy 177.236075 -307.124512) (xy 177.18722 -307.130444) (xy 177.138045 -307.128463) (xy 177.089826 -307.118619)
			(xy 177.04381 -307.101167) (xy 177.001189 -307.07656) (xy 176.963068 -307.045435) (xy 176.930433 -307.008598)
			(xy 176.90413 -306.967002) (xy 176.884839 -306.921726) (xy 176.873062 -306.873942) (xy 176.869102 -306.824888)
			(xy 176.530254 -306.824888) (xy 176.529759 -306.849495) (xy 176.521864 -306.898072) (xy 176.50628 -306.944753)
			(xy 176.483409 -306.98833) (xy 176.453844 -307.027674) (xy 176.418351 -307.061766) (xy 176.377848 -307.089722)
			(xy 176.333386 -307.11082) (xy 176.286115 -307.124512) (xy 176.23726 -307.130444) (xy 176.188085 -307.128463)
			(xy 176.139866 -307.118619) (xy 176.09385 -307.101167) (xy 176.051229 -307.07656) (xy 176.013108 -307.045435)
			(xy 175.980473 -307.008598) (xy 175.95417 -306.967002) (xy 175.934879 -306.921726) (xy 175.923102 -306.873942)
			(xy 175.919142 -306.824888) (xy 174.630334 -306.824888) (xy 174.629839 -306.849495) (xy 174.621944 -306.898072)
			(xy 174.60636 -306.944753) (xy 174.583489 -306.98833) (xy 174.553924 -307.027674) (xy 174.518431 -307.061766)
			(xy 174.477928 -307.089722) (xy 174.433466 -307.11082) (xy 174.386195 -307.124512) (xy 174.33734 -307.130444)
			(xy 174.288165 -307.128463) (xy 174.239946 -307.118619) (xy 174.19393 -307.101167) (xy 174.151309 -307.07656)
			(xy 174.113188 -307.045435) (xy 174.080553 -307.008598) (xy 174.05425 -306.967002) (xy 174.034959 -306.921726)
			(xy 174.023182 -306.873942) (xy 174.019222 -306.824888) (xy 173.680374 -306.824888) (xy 173.679879 -306.849495)
			(xy 173.671984 -306.898072) (xy 173.6564 -306.944753) (xy 173.633529 -306.98833) (xy 173.603964 -307.027674)
			(xy 173.568471 -307.061766) (xy 173.527968 -307.089722) (xy 173.483506 -307.11082) (xy 173.436235 -307.124512)
			(xy 173.38738 -307.130444) (xy 173.338205 -307.128463) (xy 173.289986 -307.118619) (xy 173.24397 -307.101167)
			(xy 173.201349 -307.07656) (xy 173.163228 -307.045435) (xy 173.130593 -307.008598) (xy 173.10429 -306.967002)
			(xy 173.084999 -306.921726) (xy 173.073222 -306.873942) (xy 173.069262 -306.824888) (xy 172.73016 -306.824888)
			(xy 172.729665 -306.849495) (xy 172.72177 -306.898072) (xy 172.706186 -306.944753) (xy 172.683315 -306.98833)
			(xy 172.65375 -307.027674) (xy 172.618257 -307.061766) (xy 172.577754 -307.089722) (xy 172.533292 -307.11082)
			(xy 172.486021 -307.124512) (xy 172.437166 -307.130444) (xy 172.387991 -307.128463) (xy 172.339772 -307.118619)
			(xy 172.293756 -307.101167) (xy 172.251135 -307.07656) (xy 172.213014 -307.045435) (xy 172.180379 -307.008598)
			(xy 172.154076 -306.967002) (xy 172.134785 -306.921726) (xy 172.123008 -306.873942) (xy 172.119048 -306.824888)
			(xy 171.7802 -306.824888) (xy 171.779705 -306.849495) (xy 171.77181 -306.898072) (xy 171.756226 -306.944753)
			(xy 171.733355 -306.98833) (xy 171.70379 -307.027674) (xy 171.668297 -307.061766) (xy 171.627794 -307.089722)
			(xy 171.583332 -307.11082) (xy 171.536061 -307.124512) (xy 171.487206 -307.130444) (xy 171.438031 -307.128463)
			(xy 171.389812 -307.118619) (xy 171.343796 -307.101167) (xy 171.301175 -307.07656) (xy 171.263054 -307.045435)
			(xy 171.230419 -307.008598) (xy 171.204116 -306.967002) (xy 171.184825 -306.921726) (xy 171.173048 -306.873942)
			(xy 171.169088 -306.824888) (xy 170.83024 -306.824888) (xy 170.829745 -306.849495) (xy 170.82185 -306.898072)
			(xy 170.806266 -306.944753) (xy 170.783395 -306.98833) (xy 170.75383 -307.027674) (xy 170.718337 -307.061766)
			(xy 170.677834 -307.089722) (xy 170.633372 -307.11082) (xy 170.586101 -307.124512) (xy 170.537246 -307.130444)
			(xy 170.488071 -307.128463) (xy 170.439852 -307.118619) (xy 170.393836 -307.101167) (xy 170.351215 -307.07656)
			(xy 170.313094 -307.045435) (xy 170.280459 -307.008598) (xy 170.254156 -306.967002) (xy 170.234865 -306.921726)
			(xy 170.223088 -306.873942) (xy 170.219128 -306.824888) (xy 169.88028 -306.824888) (xy 169.879785 -306.849495)
			(xy 169.87189 -306.898072) (xy 169.856306 -306.944753) (xy 169.833435 -306.98833) (xy 169.80387 -307.027674)
			(xy 169.768377 -307.061766) (xy 169.727874 -307.089722) (xy 169.683412 -307.11082) (xy 169.636141 -307.124512)
			(xy 169.587286 -307.130444) (xy 169.538111 -307.128463) (xy 169.489892 -307.118619) (xy 169.443876 -307.101167)
			(xy 169.401255 -307.07656) (xy 169.363134 -307.045435) (xy 169.330499 -307.008598) (xy 169.304196 -306.967002)
			(xy 169.284905 -306.921726) (xy 169.273128 -306.873942) (xy 169.269168 -306.824888) (xy 168.93032 -306.824888)
			(xy 168.929825 -306.849495) (xy 168.92193 -306.898072) (xy 168.906346 -306.944753) (xy 168.883475 -306.98833)
			(xy 168.85391 -307.027674) (xy 168.818417 -307.061766) (xy 168.777914 -307.089722) (xy 168.733452 -307.11082)
			(xy 168.686181 -307.124512) (xy 168.637326 -307.130444) (xy 168.588151 -307.128463) (xy 168.539932 -307.118619)
			(xy 168.493916 -307.101167) (xy 168.451295 -307.07656) (xy 168.413174 -307.045435) (xy 168.380539 -307.008598)
			(xy 168.354236 -306.967002) (xy 168.334945 -306.921726) (xy 168.323168 -306.873942) (xy 168.319208 -306.824888)
			(xy 167.98036 -306.824888) (xy 167.979865 -306.849495) (xy 167.97197 -306.898072) (xy 167.956386 -306.944753)
			(xy 167.933515 -306.98833) (xy 167.90395 -307.027674) (xy 167.868457 -307.061766) (xy 167.827954 -307.089722)
			(xy 167.783492 -307.11082) (xy 167.736221 -307.124512) (xy 167.687366 -307.130444) (xy 167.638191 -307.128463)
			(xy 167.589972 -307.118619) (xy 167.543956 -307.101167) (xy 167.501335 -307.07656) (xy 167.463214 -307.045435)
			(xy 167.430579 -307.008598) (xy 167.404276 -306.967002) (xy 167.384985 -306.921726) (xy 167.373208 -306.873942)
			(xy 167.369248 -306.824888) (xy 167.0304 -306.824888) (xy 167.029905 -306.849495) (xy 167.02201 -306.898072)
			(xy 167.006426 -306.944753) (xy 166.983555 -306.98833) (xy 166.95399 -307.027674) (xy 166.918497 -307.061766)
			(xy 166.877994 -307.089722) (xy 166.833532 -307.11082) (xy 166.786261 -307.124512) (xy 166.737406 -307.130444)
			(xy 166.688231 -307.128463) (xy 166.640012 -307.118619) (xy 166.593996 -307.101167) (xy 166.551375 -307.07656)
			(xy 166.513254 -307.045435) (xy 166.480619 -307.008598) (xy 166.454316 -306.967002) (xy 166.435025 -306.921726)
			(xy 166.423248 -306.873942) (xy 166.419288 -306.824888) (xy 166.080186 -306.824888) (xy 166.079691 -306.849495)
			(xy 166.071796 -306.898072) (xy 166.056212 -306.944753) (xy 166.033341 -306.98833) (xy 166.003776 -307.027674)
			(xy 165.968283 -307.061766) (xy 165.92778 -307.089722) (xy 165.883318 -307.11082) (xy 165.836047 -307.124512)
			(xy 165.787192 -307.130444) (xy 165.738017 -307.128463) (xy 165.689798 -307.118619) (xy 165.643782 -307.101167)
			(xy 165.601161 -307.07656) (xy 165.56304 -307.045435) (xy 165.530405 -307.008598) (xy 165.504102 -306.967002)
			(xy 165.484811 -306.921726) (xy 165.473034 -306.873942) (xy 165.469074 -306.824888) (xy 165.155095 -306.824888)
			(xy 165.155096 -306.851281) (xy 165.146718 -306.903377) (xy 165.130174 -306.953481) (xy 165.105884 -307.000323)
			(xy 165.074465 -307.042713) (xy 165.036713 -307.079577) (xy 164.993586 -307.109979) (xy 164.94618 -307.133147)
			(xy 164.895696 -307.148494) (xy 164.869622 -307.152548) (xy 164.86505 -307.15331) (xy 164.854636 -307.156612)
			(xy 164.850318 -307.157882) (xy 164.826696 -307.168804) (xy 164.819838 -307.175916) (xy 164.804852 -307.191664)
			(xy 164.80026 -307.196767) (xy 164.793806 -307.208878) (xy 164.792152 -307.21554) (xy 164.790882 -307.226462)
			(xy 164.790882 -307.299868) (xy 189.69407 -307.299868) (xy 189.69803 -307.250814) (xy 189.709807 -307.20303)
			(xy 189.729098 -307.157754) (xy 189.755401 -307.116158) (xy 189.788036 -307.079321) (xy 189.826157 -307.048196)
			(xy 189.868778 -307.023589) (xy 189.914794 -307.006137) (xy 189.963013 -306.996293) (xy 190.012188 -306.994312)
			(xy 190.061043 -307.000244) (xy 190.108314 -307.013936) (xy 190.152776 -307.035034) (xy 190.193279 -307.06299)
			(xy 190.228772 -307.097082) (xy 190.258337 -307.136426) (xy 190.281208 -307.180003) (xy 190.296792 -307.226684)
			(xy 190.304687 -307.275261) (xy 190.305182 -307.299868) (xy 190.644284 -307.299868) (xy 190.648244 -307.250814)
			(xy 190.660021 -307.20303) (xy 190.679312 -307.157754) (xy 190.705615 -307.116158) (xy 190.73825 -307.079321)
			(xy 190.776371 -307.048196) (xy 190.818992 -307.023589) (xy 190.865008 -307.006137) (xy 190.913227 -306.996293)
			(xy 190.962402 -306.994312) (xy 191.011257 -307.000244) (xy 191.058528 -307.013936) (xy 191.10299 -307.035034)
			(xy 191.143493 -307.06299) (xy 191.178986 -307.097082) (xy 191.208551 -307.136426) (xy 191.231422 -307.180003)
			(xy 191.247006 -307.226684) (xy 191.254901 -307.275261) (xy 191.255396 -307.299868) (xy 191.594244 -307.299868)
			(xy 191.598204 -307.250814) (xy 191.609981 -307.20303) (xy 191.629272 -307.157754) (xy 191.655575 -307.116158)
			(xy 191.68821 -307.079321) (xy 191.726331 -307.048196) (xy 191.768952 -307.023589) (xy 191.814968 -307.006137)
			(xy 191.863187 -306.996293) (xy 191.912362 -306.994312) (xy 191.961217 -307.000244) (xy 192.008488 -307.013936)
			(xy 192.05295 -307.035034) (xy 192.093453 -307.06299) (xy 192.128946 -307.097082) (xy 192.158511 -307.136426)
			(xy 192.181382 -307.180003) (xy 192.196966 -307.226684) (xy 192.204861 -307.275261) (xy 192.205356 -307.299868)
			(xy 192.204861 -307.324475) (xy 192.204682 -307.325576) (xy 192.52336 -307.325576) (xy 192.52336 -307.27416)
			(xy 192.531403 -307.223378) (xy 192.547291 -307.174479) (xy 192.570634 -307.128667) (xy 192.600855 -307.087071)
			(xy 192.637211 -307.050715) (xy 192.678807 -307.020494) (xy 192.724619 -306.997151) (xy 192.773518 -306.981263)
			(xy 192.8243 -306.97322) (xy 192.875716 -306.97322) (xy 192.926498 -306.981263) (xy 192.975397 -306.997151)
			(xy 193.021209 -307.020494) (xy 193.062805 -307.050715) (xy 193.099161 -307.087071) (xy 193.129382 -307.128667)
			(xy 193.152725 -307.174479) (xy 193.168613 -307.223378) (xy 193.176656 -307.27416) (xy 193.17716 -307.299868)
			(xy 193.176656 -307.325576) (xy 193.47332 -307.325576) (xy 193.47332 -307.27416) (xy 193.481363 -307.223378)
			(xy 193.497251 -307.174479) (xy 193.520594 -307.128667) (xy 193.550815 -307.087071) (xy 193.587171 -307.050715)
			(xy 193.628767 -307.020494) (xy 193.674579 -306.997151) (xy 193.723478 -306.981263) (xy 193.77426 -306.97322)
			(xy 193.825676 -306.97322) (xy 193.876458 -306.981263) (xy 193.925357 -306.997151) (xy 193.971169 -307.020494)
			(xy 194.012765 -307.050715) (xy 194.049121 -307.087071) (xy 194.079342 -307.128667) (xy 194.102685 -307.174479)
			(xy 194.118573 -307.223378) (xy 194.126616 -307.27416) (xy 194.12712 -307.299868) (xy 194.444124 -307.299868)
			(xy 194.448084 -307.250814) (xy 194.459861 -307.20303) (xy 194.479152 -307.157754) (xy 194.505455 -307.116158)
			(xy 194.53809 -307.079321) (xy 194.576211 -307.048196) (xy 194.618832 -307.023589) (xy 194.664848 -307.006137)
			(xy 194.713067 -306.996293) (xy 194.762242 -306.994312) (xy 194.811097 -307.000244) (xy 194.858368 -307.013936)
			(xy 194.90283 -307.035034) (xy 194.943333 -307.06299) (xy 194.978826 -307.097082) (xy 195.008391 -307.136426)
			(xy 195.031262 -307.180003) (xy 195.046846 -307.226684) (xy 195.054741 -307.275261) (xy 195.055236 -307.299868)
			(xy 195.054741 -307.324475) (xy 195.054562 -307.325576) (xy 195.37324 -307.325576) (xy 195.37324 -307.27416)
			(xy 195.381283 -307.223378) (xy 195.397171 -307.174479) (xy 195.420514 -307.128667) (xy 195.450735 -307.087071)
			(xy 195.487091 -307.050715) (xy 195.528687 -307.020494) (xy 195.574499 -306.997151) (xy 195.623398 -306.981263)
			(xy 195.67418 -306.97322) (xy 195.725596 -306.97322) (xy 195.776378 -306.981263) (xy 195.825277 -306.997151)
			(xy 195.871089 -307.020494) (xy 195.912685 -307.050715) (xy 195.949041 -307.087071) (xy 195.979262 -307.128667)
			(xy 196.002605 -307.174479) (xy 196.018493 -307.223378) (xy 196.026536 -307.27416) (xy 196.02704 -307.299868)
			(xy 196.026536 -307.325576) (xy 196.3232 -307.325576) (xy 196.3232 -307.27416) (xy 196.331243 -307.223378)
			(xy 196.347131 -307.174479) (xy 196.370474 -307.128667) (xy 196.400695 -307.087071) (xy 196.437051 -307.050715)
			(xy 196.478647 -307.020494) (xy 196.524459 -306.997151) (xy 196.573358 -306.981263) (xy 196.62414 -306.97322)
			(xy 196.675556 -306.97322) (xy 196.726338 -306.981263) (xy 196.775237 -306.997151) (xy 196.821049 -307.020494)
			(xy 196.862645 -307.050715) (xy 196.899001 -307.087071) (xy 196.929222 -307.128667) (xy 196.952565 -307.174479)
			(xy 196.968453 -307.223378) (xy 196.976496 -307.27416) (xy 196.977 -307.299868) (xy 197.294258 -307.299868)
			(xy 197.298218 -307.250814) (xy 197.309995 -307.20303) (xy 197.329286 -307.157754) (xy 197.355589 -307.116158)
			(xy 197.388224 -307.079321) (xy 197.426345 -307.048196) (xy 197.468966 -307.023589) (xy 197.514982 -307.006137)
			(xy 197.563201 -306.996293) (xy 197.612376 -306.994312) (xy 197.661231 -307.000244) (xy 197.708502 -307.013936)
			(xy 197.752964 -307.035034) (xy 197.793467 -307.06299) (xy 197.82896 -307.097082) (xy 197.858525 -307.136426)
			(xy 197.881396 -307.180003) (xy 197.89698 -307.226684) (xy 197.904875 -307.275261) (xy 197.90537 -307.299868)
			(xy 198.244218 -307.299868) (xy 198.248178 -307.250814) (xy 198.259955 -307.20303) (xy 198.279246 -307.157754)
			(xy 198.305549 -307.116158) (xy 198.338184 -307.079321) (xy 198.376305 -307.048196) (xy 198.418926 -307.023589)
			(xy 198.464942 -307.006137) (xy 198.513161 -306.996293) (xy 198.562336 -306.994312) (xy 198.611191 -307.000244)
			(xy 198.658462 -307.013936) (xy 198.702924 -307.035034) (xy 198.743427 -307.06299) (xy 198.77892 -307.097082)
			(xy 198.808485 -307.136426) (xy 198.831356 -307.180003) (xy 198.84694 -307.226684) (xy 198.854835 -307.275261)
			(xy 198.85533 -307.299868) (xy 198.854835 -307.324475) (xy 198.84694 -307.373052) (xy 198.841336 -307.389837)
			(xy 207.250293 -307.389837) (xy 207.250295 -307.335337) (xy 207.258053 -307.281393) (xy 207.273409 -307.229101)
			(xy 207.296051 -307.179527) (xy 207.325517 -307.133679) (xy 207.361208 -307.092492) (xy 207.402397 -307.056804)
			(xy 207.448246 -307.02734) (xy 207.497821 -307.004701) (xy 207.550114 -306.989348) (xy 207.604059 -306.981594)
			(xy 207.658559 -306.981595) (xy 207.712504 -306.989352) (xy 207.764796 -307.004708) (xy 207.81437 -307.027349)
			(xy 207.860218 -307.056815) (xy 207.891846 -307.084222) (xy 208.814414 -307.084222) (xy 208.818485 -307.0286)
			(xy 208.830611 -306.974163) (xy 208.850534 -306.922072) (xy 208.87783 -306.873437) (xy 208.911916 -306.829294)
			(xy 208.952065 -306.790585) (xy 208.997423 -306.758134) (xy 209.047023 -306.732633) (xy 209.099807 -306.714626)
			(xy 209.15465 -306.704496) (xy 209.210384 -306.702459) (xy 209.265821 -306.708559) (xy 209.319778 -306.722665)
			(xy 209.371107 -306.744477) (xy 209.418713 -306.773531) (xy 209.461581 -306.809206) (xy 209.498798 -306.850743)
			(xy 209.529571 -306.897256) (xy 209.553243 -306.947753) (xy 209.569311 -307.00116) (xy 209.577431 -307.056336)
			(xy 209.57794 -307.084222) (xy 209.577431 -307.112108) (xy 209.569311 -307.167284) (xy 209.553243 -307.220691)
			(xy 209.529571 -307.271188) (xy 209.498798 -307.317701) (xy 209.461581 -307.359238) (xy 209.418713 -307.394913)
			(xy 209.371107 -307.423967) (xy 209.319778 -307.445779) (xy 209.265821 -307.459885) (xy 209.210384 -307.465985)
			(xy 209.15465 -307.463948) (xy 209.099807 -307.453818) (xy 209.047023 -307.435811) (xy 208.997423 -307.41031)
			(xy 208.952065 -307.377859) (xy 208.911916 -307.33915) (xy 208.87783 -307.295007) (xy 208.850534 -307.246372)
			(xy 208.830611 -307.194281) (xy 208.818485 -307.139844) (xy 208.814414 -307.084222) (xy 207.891846 -307.084222)
			(xy 207.901405 -307.092505) (xy 207.937094 -307.133694) (xy 207.966558 -307.179543) (xy 207.989197 -307.229118)
			(xy 208.004551 -307.281411) (xy 208.012306 -307.335356) (xy 208.012792 -307.362606) (xy 208.011014 -307.399182)
			(xy 208.009998 -307.410612) (xy 208.017618 -307.431694) (xy 208.089246 -307.503322) (xy 208.110582 -307.510942)
			(xy 208.122012 -307.509926) (xy 208.158588 -307.508148) (xy 208.185837 -307.508689) (xy 208.23978 -307.516443)
			(xy 208.292071 -307.531794) (xy 208.341645 -307.554431) (xy 208.387494 -307.583892) (xy 208.428683 -307.619577)
			(xy 208.464375 -307.660761) (xy 208.493842 -307.706605) (xy 208.516486 -307.756176) (xy 208.531845 -307.808465)
			(xy 208.539607 -307.862407) (xy 208.540096 -307.889656) (xy 208.539739 -307.912162) (xy 208.534396 -307.956856)
			(xy 208.529428 -307.97881) (xy 208.52638 -307.992018) (xy 208.533492 -308.017164) (xy 208.613756 -308.097428)
			(xy 208.638902 -308.10454) (xy 208.65211 -308.101492) (xy 208.674064 -308.096524) (xy 208.718758 -308.091181)
			(xy 208.741264 -308.090824) (xy 208.76852 -308.091216) (xy 208.822476 -308.098969) (xy 208.874781 -308.114322)
			(xy 208.924368 -308.136962) (xy 208.970228 -308.166428) (xy 209.011428 -308.202122) (xy 209.047129 -308.243315)
			(xy 209.076604 -308.28917) (xy 209.099254 -308.338753) (xy 209.114616 -308.391054) (xy 209.122379 -308.44501)
			(xy 209.122384 -308.499521) (xy 209.114631 -308.553478) (xy 209.099278 -308.605782) (xy 209.076638 -308.655369)
			(xy 209.047171 -308.701229) (xy 209.011477 -308.742429) (xy 208.970284 -308.77813) (xy 208.924429 -308.807605)
			(xy 208.874846 -308.830254) (xy 208.822544 -308.845616) (xy 208.768589 -308.853379) (xy 208.714078 -308.853383)
			(xy 208.660121 -308.84563) (xy 208.607817 -308.830277) (xy 208.55823 -308.807637) (xy 208.51237 -308.77817)
			(xy 208.47117 -308.742476) (xy 208.435469 -308.701283) (xy 208.405994 -308.655428) (xy 208.383345 -308.605845)
			(xy 208.367983 -308.553543) (xy 208.360221 -308.499587) (xy 208.359756 -308.472332) (xy 208.36011 -308.449826)
			(xy 208.365455 -308.405131) (xy 208.370424 -308.383178) (xy 208.373472 -308.36997) (xy 208.36636 -308.344824)
			(xy 208.286096 -308.26456) (xy 208.26095 -308.257448) (xy 208.247742 -308.260496) (xy 208.225787 -308.265455)
			(xy 208.181094 -308.270804) (xy 208.158588 -308.271164) (xy 208.131333 -308.270756) (xy 208.077378 -308.262996)
			(xy 208.025076 -308.247637) (xy 207.975493 -308.224989) (xy 207.929638 -308.195516) (xy 207.888444 -308.159817)
			(xy 207.85275 -308.118618) (xy 207.823284 -308.072758) (xy 207.800644 -308.023172) (xy 207.785292 -307.970868)
			(xy 207.77754 -307.916911) (xy 207.77708 -307.889656) (xy 207.778858 -307.85308) (xy 207.779874 -307.84165)
			(xy 207.772254 -307.820568) (xy 207.700626 -307.74894) (xy 207.67929 -307.74132) (xy 207.66786 -307.742336)
			(xy 207.631284 -307.744114) (xy 207.604034 -307.743605) (xy 207.550089 -307.735846) (xy 207.497798 -307.72049)
			(xy 207.448224 -307.697848) (xy 207.402377 -307.668381) (xy 207.36119 -307.63269) (xy 207.325502 -307.5915)
			(xy 207.296038 -307.545651) (xy 207.2734 -307.496075) (xy 207.258048 -307.443783) (xy 207.250293 -307.389837)
			(xy 198.841336 -307.389837) (xy 198.831356 -307.419733) (xy 198.808485 -307.46331) (xy 198.77892 -307.502654)
			(xy 198.743427 -307.536746) (xy 198.702924 -307.564702) (xy 198.658462 -307.5858) (xy 198.611191 -307.599492)
			(xy 198.562336 -307.605424) (xy 198.513161 -307.603443) (xy 198.464942 -307.593599) (xy 198.418926 -307.576147)
			(xy 198.376305 -307.55154) (xy 198.338184 -307.520415) (xy 198.305549 -307.483578) (xy 198.279246 -307.441982)
			(xy 198.259955 -307.396706) (xy 198.248178 -307.348922) (xy 198.244218 -307.299868) (xy 197.90537 -307.299868)
			(xy 197.904875 -307.324475) (xy 197.89698 -307.373052) (xy 197.881396 -307.419733) (xy 197.858525 -307.46331)
			(xy 197.82896 -307.502654) (xy 197.793467 -307.536746) (xy 197.752964 -307.564702) (xy 197.708502 -307.5858)
			(xy 197.661231 -307.599492) (xy 197.612376 -307.605424) (xy 197.563201 -307.603443) (xy 197.514982 -307.593599)
			(xy 197.468966 -307.576147) (xy 197.426345 -307.55154) (xy 197.388224 -307.520415) (xy 197.355589 -307.483578)
			(xy 197.329286 -307.441982) (xy 197.309995 -307.396706) (xy 197.298218 -307.348922) (xy 197.294258 -307.299868)
			(xy 196.977 -307.299868) (xy 196.976496 -307.325576) (xy 196.968453 -307.376358) (xy 196.952565 -307.425257)
			(xy 196.929222 -307.471069) (xy 196.899001 -307.512665) (xy 196.862645 -307.549021) (xy 196.821049 -307.579242)
			(xy 196.775237 -307.602585) (xy 196.726338 -307.618473) (xy 196.675556 -307.626516) (xy 196.62414 -307.626516)
			(xy 196.573358 -307.618473) (xy 196.524459 -307.602585) (xy 196.478647 -307.579242) (xy 196.437051 -307.549021)
			(xy 196.400695 -307.512665) (xy 196.370474 -307.471069) (xy 196.347131 -307.425257) (xy 196.331243 -307.376358)
			(xy 196.3232 -307.325576) (xy 196.026536 -307.325576) (xy 196.018493 -307.376358) (xy 196.002605 -307.425257)
			(xy 195.979262 -307.471069) (xy 195.949041 -307.512665) (xy 195.912685 -307.549021) (xy 195.871089 -307.579242)
			(xy 195.825277 -307.602585) (xy 195.776378 -307.618473) (xy 195.725596 -307.626516) (xy 195.67418 -307.626516)
			(xy 195.623398 -307.618473) (xy 195.574499 -307.602585) (xy 195.528687 -307.579242) (xy 195.487091 -307.549021)
			(xy 195.450735 -307.512665) (xy 195.420514 -307.471069) (xy 195.397171 -307.425257) (xy 195.381283 -307.376358)
			(xy 195.37324 -307.325576) (xy 195.054562 -307.325576) (xy 195.046846 -307.373052) (xy 195.031262 -307.419733)
			(xy 195.008391 -307.46331) (xy 194.978826 -307.502654) (xy 194.943333 -307.536746) (xy 194.90283 -307.564702)
			(xy 194.858368 -307.5858) (xy 194.811097 -307.599492) (xy 194.762242 -307.605424) (xy 194.713067 -307.603443)
			(xy 194.664848 -307.593599) (xy 194.618832 -307.576147) (xy 194.576211 -307.55154) (xy 194.53809 -307.520415)
			(xy 194.505455 -307.483578) (xy 194.479152 -307.441982) (xy 194.459861 -307.396706) (xy 194.448084 -307.348922)
			(xy 194.444124 -307.299868) (xy 194.12712 -307.299868) (xy 194.126616 -307.325576) (xy 194.118573 -307.376358)
			(xy 194.102685 -307.425257) (xy 194.079342 -307.471069) (xy 194.049121 -307.512665) (xy 194.012765 -307.549021)
			(xy 193.971169 -307.579242) (xy 193.925357 -307.602585) (xy 193.876458 -307.618473) (xy 193.825676 -307.626516)
			(xy 193.77426 -307.626516) (xy 193.723478 -307.618473) (xy 193.674579 -307.602585) (xy 193.628767 -307.579242)
			(xy 193.587171 -307.549021) (xy 193.550815 -307.512665) (xy 193.520594 -307.471069) (xy 193.497251 -307.425257)
			(xy 193.481363 -307.376358) (xy 193.47332 -307.325576) (xy 193.176656 -307.325576) (xy 193.168613 -307.376358)
			(xy 193.152725 -307.425257) (xy 193.129382 -307.471069) (xy 193.099161 -307.512665) (xy 193.062805 -307.549021)
			(xy 193.021209 -307.579242) (xy 192.975397 -307.602585) (xy 192.926498 -307.618473) (xy 192.875716 -307.626516)
			(xy 192.8243 -307.626516) (xy 192.773518 -307.618473) (xy 192.724619 -307.602585) (xy 192.678807 -307.579242)
			(xy 192.637211 -307.549021) (xy 192.600855 -307.512665) (xy 192.570634 -307.471069) (xy 192.547291 -307.425257)
			(xy 192.531403 -307.376358) (xy 192.52336 -307.325576) (xy 192.204682 -307.325576) (xy 192.196966 -307.373052)
			(xy 192.181382 -307.419733) (xy 192.158511 -307.46331) (xy 192.128946 -307.502654) (xy 192.093453 -307.536746)
			(xy 192.05295 -307.564702) (xy 192.008488 -307.5858) (xy 191.961217 -307.599492) (xy 191.912362 -307.605424)
			(xy 191.863187 -307.603443) (xy 191.814968 -307.593599) (xy 191.768952 -307.576147) (xy 191.726331 -307.55154)
			(xy 191.68821 -307.520415) (xy 191.655575 -307.483578) (xy 191.629272 -307.441982) (xy 191.609981 -307.396706)
			(xy 191.598204 -307.348922) (xy 191.594244 -307.299868) (xy 191.255396 -307.299868) (xy 191.254901 -307.324475)
			(xy 191.247006 -307.373052) (xy 191.231422 -307.419733) (xy 191.208551 -307.46331) (xy 191.178986 -307.502654)
			(xy 191.143493 -307.536746) (xy 191.10299 -307.564702) (xy 191.058528 -307.5858) (xy 191.011257 -307.599492)
			(xy 190.962402 -307.605424) (xy 190.913227 -307.603443) (xy 190.865008 -307.593599) (xy 190.818992 -307.576147)
			(xy 190.776371 -307.55154) (xy 190.73825 -307.520415) (xy 190.705615 -307.483578) (xy 190.679312 -307.441982)
			(xy 190.660021 -307.396706) (xy 190.648244 -307.348922) (xy 190.644284 -307.299868) (xy 190.305182 -307.299868)
			(xy 190.304687 -307.324475) (xy 190.296792 -307.373052) (xy 190.281208 -307.419733) (xy 190.258337 -307.46331)
			(xy 190.228772 -307.502654) (xy 190.193279 -307.536746) (xy 190.152776 -307.564702) (xy 190.108314 -307.5858)
			(xy 190.061043 -307.599492) (xy 190.012188 -307.605424) (xy 189.963013 -307.603443) (xy 189.914794 -307.593599)
			(xy 189.868778 -307.576147) (xy 189.826157 -307.55154) (xy 189.788036 -307.520415) (xy 189.755401 -307.483578)
			(xy 189.729098 -307.441982) (xy 189.709807 -307.396706) (xy 189.69803 -307.348922) (xy 189.69407 -307.299868)
			(xy 164.790882 -307.299868) (xy 164.790882 -307.373274) (xy 164.791052 -307.379427) (xy 164.79401 -307.391371)
			(xy 164.796724 -307.396896) (xy 164.804852 -307.408072) (xy 164.819584 -307.423566) (xy 164.826188 -307.430678)
			(xy 164.849302 -307.4416) (xy 164.852858 -307.442616) (xy 164.86505 -307.446426) (xy 164.869622 -307.447188)
			(xy 164.895688 -307.451265) (xy 164.946162 -307.46661) (xy 164.99356 -307.489775) (xy 165.036678 -307.520172)
			(xy 165.074423 -307.557029) (xy 165.105836 -307.599413) (xy 165.130121 -307.646247) (xy 165.146661 -307.696342)
			(xy 165.155037 -307.748429) (xy 165.155036 -307.774848) (xy 165.469074 -307.774848) (xy 165.473034 -307.725794)
			(xy 165.484811 -307.67801) (xy 165.504102 -307.632734) (xy 165.530405 -307.591138) (xy 165.56304 -307.554301)
			(xy 165.601161 -307.523176) (xy 165.643782 -307.498569) (xy 165.689798 -307.481117) (xy 165.738017 -307.471273)
			(xy 165.787192 -307.469292) (xy 165.836047 -307.475224) (xy 165.883318 -307.488916) (xy 165.92778 -307.510014)
			(xy 165.968283 -307.53797) (xy 166.003776 -307.572062) (xy 166.033341 -307.611406) (xy 166.056212 -307.654983)
			(xy 166.071796 -307.701664) (xy 166.079691 -307.750241) (xy 166.080186 -307.774848) (xy 166.419288 -307.774848)
			(xy 166.423248 -307.725794) (xy 166.435025 -307.67801) (xy 166.454316 -307.632734) (xy 166.480619 -307.591138)
			(xy 166.513254 -307.554301) (xy 166.551375 -307.523176) (xy 166.593996 -307.498569) (xy 166.640012 -307.481117)
			(xy 166.688231 -307.471273) (xy 166.737406 -307.469292) (xy 166.786261 -307.475224) (xy 166.833532 -307.488916)
			(xy 166.877994 -307.510014) (xy 166.918497 -307.53797) (xy 166.95399 -307.572062) (xy 166.983555 -307.611406)
			(xy 167.006426 -307.654983) (xy 167.02201 -307.701664) (xy 167.029905 -307.750241) (xy 167.0304 -307.774848)
			(xy 167.369248 -307.774848) (xy 167.373208 -307.725794) (xy 167.384985 -307.67801) (xy 167.404276 -307.632734)
			(xy 167.430579 -307.591138) (xy 167.463214 -307.554301) (xy 167.501335 -307.523176) (xy 167.543956 -307.498569)
			(xy 167.589972 -307.481117) (xy 167.638191 -307.471273) (xy 167.687366 -307.469292) (xy 167.736221 -307.475224)
			(xy 167.783492 -307.488916) (xy 167.827954 -307.510014) (xy 167.868457 -307.53797) (xy 167.90395 -307.572062)
			(xy 167.933515 -307.611406) (xy 167.956386 -307.654983) (xy 167.97197 -307.701664) (xy 167.979865 -307.750241)
			(xy 167.98036 -307.774848) (xy 168.319208 -307.774848) (xy 168.323168 -307.725794) (xy 168.334945 -307.67801)
			(xy 168.354236 -307.632734) (xy 168.380539 -307.591138) (xy 168.413174 -307.554301) (xy 168.451295 -307.523176)
			(xy 168.493916 -307.498569) (xy 168.539932 -307.481117) (xy 168.588151 -307.471273) (xy 168.637326 -307.469292)
			(xy 168.686181 -307.475224) (xy 168.733452 -307.488916) (xy 168.777914 -307.510014) (xy 168.818417 -307.53797)
			(xy 168.85391 -307.572062) (xy 168.883475 -307.611406) (xy 168.906346 -307.654983) (xy 168.92193 -307.701664)
			(xy 168.929825 -307.750241) (xy 168.93032 -307.774848) (xy 169.269168 -307.774848) (xy 169.273128 -307.725794)
			(xy 169.284905 -307.67801) (xy 169.304196 -307.632734) (xy 169.330499 -307.591138) (xy 169.363134 -307.554301)
			(xy 169.401255 -307.523176) (xy 169.443876 -307.498569) (xy 169.489892 -307.481117) (xy 169.538111 -307.471273)
			(xy 169.587286 -307.469292) (xy 169.636141 -307.475224) (xy 169.683412 -307.488916) (xy 169.727874 -307.510014)
			(xy 169.768377 -307.53797) (xy 169.80387 -307.572062) (xy 169.833435 -307.611406) (xy 169.856306 -307.654983)
			(xy 169.87189 -307.701664) (xy 169.879785 -307.750241) (xy 169.88028 -307.774848) (xy 170.219128 -307.774848)
			(xy 170.223088 -307.725794) (xy 170.234865 -307.67801) (xy 170.254156 -307.632734) (xy 170.280459 -307.591138)
			(xy 170.313094 -307.554301) (xy 170.351215 -307.523176) (xy 170.393836 -307.498569) (xy 170.439852 -307.481117)
			(xy 170.488071 -307.471273) (xy 170.537246 -307.469292) (xy 170.586101 -307.475224) (xy 170.633372 -307.488916)
			(xy 170.677834 -307.510014) (xy 170.718337 -307.53797) (xy 170.75383 -307.572062) (xy 170.783395 -307.611406)
			(xy 170.806266 -307.654983) (xy 170.82185 -307.701664) (xy 170.829745 -307.750241) (xy 170.83024 -307.774848)
			(xy 171.169088 -307.774848) (xy 171.173048 -307.725794) (xy 171.184825 -307.67801) (xy 171.204116 -307.632734)
			(xy 171.230419 -307.591138) (xy 171.263054 -307.554301) (xy 171.301175 -307.523176) (xy 171.343796 -307.498569)
			(xy 171.389812 -307.481117) (xy 171.438031 -307.471273) (xy 171.487206 -307.469292) (xy 171.536061 -307.475224)
			(xy 171.583332 -307.488916) (xy 171.627794 -307.510014) (xy 171.668297 -307.53797) (xy 171.70379 -307.572062)
			(xy 171.733355 -307.611406) (xy 171.756226 -307.654983) (xy 171.77181 -307.701664) (xy 171.779705 -307.750241)
			(xy 171.7802 -307.774848) (xy 172.119302 -307.774848) (xy 172.123262 -307.725794) (xy 172.135039 -307.67801)
			(xy 172.15433 -307.632734) (xy 172.180633 -307.591138) (xy 172.213268 -307.554301) (xy 172.251389 -307.523176)
			(xy 172.29401 -307.498569) (xy 172.340026 -307.481117) (xy 172.388245 -307.471273) (xy 172.43742 -307.469292)
			(xy 172.486275 -307.475224) (xy 172.533546 -307.488916) (xy 172.578008 -307.510014) (xy 172.618511 -307.53797)
			(xy 172.654004 -307.572062) (xy 172.683569 -307.611406) (xy 172.70644 -307.654983) (xy 172.722024 -307.701664)
			(xy 172.729919 -307.750241) (xy 172.730414 -307.774848) (xy 173.069262 -307.774848) (xy 173.073222 -307.725794)
			(xy 173.084999 -307.67801) (xy 173.10429 -307.632734) (xy 173.130593 -307.591138) (xy 173.163228 -307.554301)
			(xy 173.201349 -307.523176) (xy 173.24397 -307.498569) (xy 173.289986 -307.481117) (xy 173.338205 -307.471273)
			(xy 173.38738 -307.469292) (xy 173.436235 -307.475224) (xy 173.483506 -307.488916) (xy 173.527968 -307.510014)
			(xy 173.568471 -307.53797) (xy 173.603964 -307.572062) (xy 173.633529 -307.611406) (xy 173.6564 -307.654983)
			(xy 173.671984 -307.701664) (xy 173.679879 -307.750241) (xy 173.680374 -307.774848) (xy 174.019222 -307.774848)
			(xy 174.023182 -307.725794) (xy 174.034959 -307.67801) (xy 174.05425 -307.632734) (xy 174.080553 -307.591138)
			(xy 174.113188 -307.554301) (xy 174.151309 -307.523176) (xy 174.19393 -307.498569) (xy 174.239946 -307.481117)
			(xy 174.288165 -307.471273) (xy 174.33734 -307.469292) (xy 174.386195 -307.475224) (xy 174.433466 -307.488916)
			(xy 174.477928 -307.510014) (xy 174.518431 -307.53797) (xy 174.553924 -307.572062) (xy 174.583489 -307.611406)
			(xy 174.60636 -307.654983) (xy 174.621944 -307.701664) (xy 174.629839 -307.750241) (xy 174.630334 -307.774848)
			(xy 175.919142 -307.774848) (xy 175.923102 -307.725794) (xy 175.934879 -307.67801) (xy 175.95417 -307.632734)
			(xy 175.980473 -307.591138) (xy 176.013108 -307.554301) (xy 176.051229 -307.523176) (xy 176.09385 -307.498569)
			(xy 176.139866 -307.481117) (xy 176.188085 -307.471273) (xy 176.23726 -307.469292) (xy 176.286115 -307.475224)
			(xy 176.333386 -307.488916) (xy 176.377848 -307.510014) (xy 176.418351 -307.53797) (xy 176.453844 -307.572062)
			(xy 176.483409 -307.611406) (xy 176.50628 -307.654983) (xy 176.521864 -307.701664) (xy 176.529759 -307.750241)
			(xy 176.530254 -307.774848) (xy 176.869102 -307.774848) (xy 176.873062 -307.725794) (xy 176.884839 -307.67801)
			(xy 176.90413 -307.632734) (xy 176.930433 -307.591138) (xy 176.963068 -307.554301) (xy 177.001189 -307.523176)
			(xy 177.04381 -307.498569) (xy 177.089826 -307.481117) (xy 177.138045 -307.471273) (xy 177.18722 -307.469292)
			(xy 177.236075 -307.475224) (xy 177.283346 -307.488916) (xy 177.327808 -307.510014) (xy 177.368311 -307.53797)
			(xy 177.403804 -307.572062) (xy 177.433369 -307.611406) (xy 177.45624 -307.654983) (xy 177.471824 -307.701664)
			(xy 177.479719 -307.750241) (xy 177.480214 -307.774848) (xy 177.819062 -307.774848) (xy 177.823022 -307.725794)
			(xy 177.834799 -307.67801) (xy 177.85409 -307.632734) (xy 177.880393 -307.591138) (xy 177.913028 -307.554301)
			(xy 177.951149 -307.523176) (xy 177.99377 -307.498569) (xy 178.039786 -307.481117) (xy 178.088005 -307.471273)
			(xy 178.13718 -307.469292) (xy 178.186035 -307.475224) (xy 178.233306 -307.488916) (xy 178.277768 -307.510014)
			(xy 178.318271 -307.53797) (xy 178.353764 -307.572062) (xy 178.383329 -307.611406) (xy 178.4062 -307.654983)
			(xy 178.421784 -307.701664) (xy 178.429679 -307.750241) (xy 178.430169 -307.774594) (xy 178.769022 -307.774594)
			(xy 178.772982 -307.72554) (xy 178.784759 -307.677756) (xy 178.80405 -307.63248) (xy 178.830353 -307.590884)
			(xy 178.862988 -307.554047) (xy 178.901109 -307.522922) (xy 178.94373 -307.498315) (xy 178.989746 -307.480863)
			(xy 179.037965 -307.471019) (xy 179.08714 -307.469038) (xy 179.135995 -307.47497) (xy 179.183266 -307.488662)
			(xy 179.227728 -307.50976) (xy 179.268231 -307.537716) (xy 179.303724 -307.571808) (xy 179.333289 -307.611152)
			(xy 179.35616 -307.654729) (xy 179.371744 -307.70141) (xy 179.379639 -307.749987) (xy 179.380134 -307.774594)
			(xy 179.719236 -307.774594) (xy 179.723196 -307.72554) (xy 179.734973 -307.677756) (xy 179.754264 -307.63248)
			(xy 179.780567 -307.590884) (xy 179.813202 -307.554047) (xy 179.851323 -307.522922) (xy 179.893944 -307.498315)
			(xy 179.93996 -307.480863) (xy 179.988179 -307.471019) (xy 180.037354 -307.469038) (xy 180.086209 -307.47497)
			(xy 180.13348 -307.488662) (xy 180.177942 -307.50976) (xy 180.218445 -307.537716) (xy 180.253938 -307.571808)
			(xy 180.283503 -307.611152) (xy 180.306374 -307.654729) (xy 180.321958 -307.70141) (xy 180.329853 -307.749987)
			(xy 180.330348 -307.774594) (xy 180.330343 -307.774848) (xy 180.669196 -307.774848) (xy 180.673156 -307.725794)
			(xy 180.684933 -307.67801) (xy 180.704224 -307.632734) (xy 180.730527 -307.591138) (xy 180.763162 -307.554301)
			(xy 180.801283 -307.523176) (xy 180.843904 -307.498569) (xy 180.88992 -307.481117) (xy 180.938139 -307.471273)
			(xy 180.987314 -307.469292) (xy 181.036169 -307.475224) (xy 181.08344 -307.488916) (xy 181.127902 -307.510014)
			(xy 181.168405 -307.53797) (xy 181.203898 -307.572062) (xy 181.233463 -307.611406) (xy 181.256334 -307.654983)
			(xy 181.271918 -307.701664) (xy 181.279813 -307.750241) (xy 181.280308 -307.774848) (xy 181.619156 -307.774848)
			(xy 181.623116 -307.725794) (xy 181.634893 -307.67801) (xy 181.654184 -307.632734) (xy 181.680487 -307.591138)
			(xy 181.713122 -307.554301) (xy 181.751243 -307.523176) (xy 181.793864 -307.498569) (xy 181.83988 -307.481117)
			(xy 181.888099 -307.471273) (xy 181.937274 -307.469292) (xy 181.986129 -307.475224) (xy 182.0334 -307.488916)
			(xy 182.077862 -307.510014) (xy 182.118365 -307.53797) (xy 182.153858 -307.572062) (xy 182.183423 -307.611406)
			(xy 182.206294 -307.654983) (xy 182.221878 -307.701664) (xy 182.229773 -307.750241) (xy 182.230268 -307.774848)
			(xy 182.569116 -307.774848) (xy 182.573076 -307.725794) (xy 182.584853 -307.67801) (xy 182.604144 -307.632734)
			(xy 182.630447 -307.591138) (xy 182.663082 -307.554301) (xy 182.701203 -307.523176) (xy 182.743824 -307.498569)
			(xy 182.78984 -307.481117) (xy 182.838059 -307.471273) (xy 182.887234 -307.469292) (xy 182.936089 -307.475224)
			(xy 182.98336 -307.488916) (xy 183.027822 -307.510014) (xy 183.068325 -307.53797) (xy 183.103818 -307.572062)
			(xy 183.133383 -307.611406) (xy 183.156254 -307.654983) (xy 183.171838 -307.701664) (xy 183.179733 -307.750241)
			(xy 183.180228 -307.774848) (xy 183.519076 -307.774848) (xy 183.523036 -307.725794) (xy 183.534813 -307.67801)
			(xy 183.554104 -307.632734) (xy 183.580407 -307.591138) (xy 183.613042 -307.554301) (xy 183.651163 -307.523176)
			(xy 183.693784 -307.498569) (xy 183.7398 -307.481117) (xy 183.788019 -307.471273) (xy 183.837194 -307.469292)
			(xy 183.886049 -307.475224) (xy 183.93332 -307.488916) (xy 183.977782 -307.510014) (xy 184.018285 -307.53797)
			(xy 184.053778 -307.572062) (xy 184.083343 -307.611406) (xy 184.106214 -307.654983) (xy 184.121798 -307.701664)
			(xy 184.129693 -307.750241) (xy 184.130188 -307.774848) (xy 184.469036 -307.774848) (xy 184.472996 -307.725794)
			(xy 184.484773 -307.67801) (xy 184.504064 -307.632734) (xy 184.530367 -307.591138) (xy 184.563002 -307.554301)
			(xy 184.601123 -307.523176) (xy 184.643744 -307.498569) (xy 184.68976 -307.481117) (xy 184.737979 -307.471273)
			(xy 184.787154 -307.469292) (xy 184.836009 -307.475224) (xy 184.88328 -307.488916) (xy 184.927742 -307.510014)
			(xy 184.968245 -307.53797) (xy 185.003738 -307.572062) (xy 185.033303 -307.611406) (xy 185.056174 -307.654983)
			(xy 185.071758 -307.701664) (xy 185.079653 -307.750241) (xy 185.080148 -307.774848) (xy 185.41925 -307.774848)
			(xy 185.42321 -307.725794) (xy 185.434987 -307.67801) (xy 185.454278 -307.632734) (xy 185.480581 -307.591138)
			(xy 185.513216 -307.554301) (xy 185.551337 -307.523176) (xy 185.593958 -307.498569) (xy 185.639974 -307.481117)
			(xy 185.688193 -307.471273) (xy 185.737368 -307.469292) (xy 185.786223 -307.475224) (xy 185.833494 -307.488916)
			(xy 185.877956 -307.510014) (xy 185.918459 -307.53797) (xy 185.953952 -307.572062) (xy 185.983517 -307.611406)
			(xy 186.006388 -307.654983) (xy 186.021972 -307.701664) (xy 186.029867 -307.750241) (xy 186.030362 -307.774848)
			(xy 186.36921 -307.774848) (xy 186.37317 -307.725794) (xy 186.384947 -307.67801) (xy 186.404238 -307.632734)
			(xy 186.430541 -307.591138) (xy 186.463176 -307.554301) (xy 186.501297 -307.523176) (xy 186.543918 -307.498569)
			(xy 186.589934 -307.481117) (xy 186.638153 -307.471273) (xy 186.687328 -307.469292) (xy 186.736183 -307.475224)
			(xy 186.783454 -307.488916) (xy 186.827916 -307.510014) (xy 186.868419 -307.53797) (xy 186.903912 -307.572062)
			(xy 186.933477 -307.611406) (xy 186.956348 -307.654983) (xy 186.971932 -307.701664) (xy 186.979827 -307.750241)
			(xy 186.980322 -307.774848) (xy 187.31917 -307.774848) (xy 187.32313 -307.725794) (xy 187.334907 -307.67801)
			(xy 187.354198 -307.632734) (xy 187.380501 -307.591138) (xy 187.413136 -307.554301) (xy 187.451257 -307.523176)
			(xy 187.493878 -307.498569) (xy 187.539894 -307.481117) (xy 187.588113 -307.471273) (xy 187.637288 -307.469292)
			(xy 187.686143 -307.475224) (xy 187.733414 -307.488916) (xy 187.777876 -307.510014) (xy 187.818379 -307.53797)
			(xy 187.853872 -307.572062) (xy 187.883437 -307.611406) (xy 187.906308 -307.654983) (xy 187.921892 -307.701664)
			(xy 187.929787 -307.750241) (xy 187.930282 -307.774848) (xy 188.26913 -307.774848) (xy 188.27309 -307.725794)
			(xy 188.284867 -307.67801) (xy 188.304158 -307.632734) (xy 188.330461 -307.591138) (xy 188.363096 -307.554301)
			(xy 188.401217 -307.523176) (xy 188.443838 -307.498569) (xy 188.489854 -307.481117) (xy 188.538073 -307.471273)
			(xy 188.587248 -307.469292) (xy 188.636103 -307.475224) (xy 188.683374 -307.488916) (xy 188.727836 -307.510014)
			(xy 188.768339 -307.53797) (xy 188.803832 -307.572062) (xy 188.833397 -307.611406) (xy 188.856268 -307.654983)
			(xy 188.871852 -307.701664) (xy 188.879747 -307.750241) (xy 188.880242 -307.774848) (xy 188.879747 -307.799455)
			(xy 188.871852 -307.848032) (xy 188.856268 -307.894713) (xy 188.833397 -307.93829) (xy 188.803832 -307.977634)
			(xy 188.768339 -308.011726) (xy 188.727836 -308.039682) (xy 188.683374 -308.06078) (xy 188.636103 -308.074472)
			(xy 188.587248 -308.080404) (xy 188.538073 -308.078423) (xy 188.489854 -308.068579) (xy 188.443838 -308.051127)
			(xy 188.401217 -308.02652) (xy 188.363096 -307.995395) (xy 188.330461 -307.958558) (xy 188.304158 -307.916962)
			(xy 188.284867 -307.871686) (xy 188.27309 -307.823902) (xy 188.26913 -307.774848) (xy 187.930282 -307.774848)
			(xy 187.929787 -307.799455) (xy 187.921892 -307.848032) (xy 187.906308 -307.894713) (xy 187.883437 -307.93829)
			(xy 187.853872 -307.977634) (xy 187.818379 -308.011726) (xy 187.777876 -308.039682) (xy 187.733414 -308.06078)
			(xy 187.686143 -308.074472) (xy 187.637288 -308.080404) (xy 187.588113 -308.078423) (xy 187.539894 -308.068579)
			(xy 187.493878 -308.051127) (xy 187.451257 -308.02652) (xy 187.413136 -307.995395) (xy 187.380501 -307.958558)
			(xy 187.354198 -307.916962) (xy 187.334907 -307.871686) (xy 187.32313 -307.823902) (xy 187.31917 -307.774848)
			(xy 186.980322 -307.774848) (xy 186.979827 -307.799455) (xy 186.971932 -307.848032) (xy 186.956348 -307.894713)
			(xy 186.933477 -307.93829) (xy 186.903912 -307.977634) (xy 186.868419 -308.011726) (xy 186.827916 -308.039682)
			(xy 186.783454 -308.06078) (xy 186.736183 -308.074472) (xy 186.687328 -308.080404) (xy 186.638153 -308.078423)
			(xy 186.589934 -308.068579) (xy 186.543918 -308.051127) (xy 186.501297 -308.02652) (xy 186.463176 -307.995395)
			(xy 186.430541 -307.958558) (xy 186.404238 -307.916962) (xy 186.384947 -307.871686) (xy 186.37317 -307.823902)
			(xy 186.36921 -307.774848) (xy 186.030362 -307.774848) (xy 186.029867 -307.799455) (xy 186.021972 -307.848032)
			(xy 186.006388 -307.894713) (xy 185.983517 -307.93829) (xy 185.953952 -307.977634) (xy 185.918459 -308.011726)
			(xy 185.877956 -308.039682) (xy 185.833494 -308.06078) (xy 185.786223 -308.074472) (xy 185.737368 -308.080404)
			(xy 185.688193 -308.078423) (xy 185.639974 -308.068579) (xy 185.593958 -308.051127) (xy 185.551337 -308.02652)
			(xy 185.513216 -307.995395) (xy 185.480581 -307.958558) (xy 185.454278 -307.916962) (xy 185.434987 -307.871686)
			(xy 185.42321 -307.823902) (xy 185.41925 -307.774848) (xy 185.080148 -307.774848) (xy 185.079653 -307.799455)
			(xy 185.071758 -307.848032) (xy 185.056174 -307.894713) (xy 185.033303 -307.93829) (xy 185.003738 -307.977634)
			(xy 184.968245 -308.011726) (xy 184.927742 -308.039682) (xy 184.88328 -308.06078) (xy 184.836009 -308.074472)
			(xy 184.787154 -308.080404) (xy 184.737979 -308.078423) (xy 184.68976 -308.068579) (xy 184.643744 -308.051127)
			(xy 184.601123 -308.02652) (xy 184.563002 -307.995395) (xy 184.530367 -307.958558) (xy 184.504064 -307.916962)
			(xy 184.484773 -307.871686) (xy 184.472996 -307.823902) (xy 184.469036 -307.774848) (xy 184.130188 -307.774848)
			(xy 184.129693 -307.799455) (xy 184.121798 -307.848032) (xy 184.106214 -307.894713) (xy 184.083343 -307.93829)
			(xy 184.053778 -307.977634) (xy 184.018285 -308.011726) (xy 183.977782 -308.039682) (xy 183.93332 -308.06078)
			(xy 183.886049 -308.074472) (xy 183.837194 -308.080404) (xy 183.788019 -308.078423) (xy 183.7398 -308.068579)
			(xy 183.693784 -308.051127) (xy 183.651163 -308.02652) (xy 183.613042 -307.995395) (xy 183.580407 -307.958558)
			(xy 183.554104 -307.916962) (xy 183.534813 -307.871686) (xy 183.523036 -307.823902) (xy 183.519076 -307.774848)
			(xy 183.180228 -307.774848) (xy 183.179733 -307.799455) (xy 183.171838 -307.848032) (xy 183.156254 -307.894713)
			(xy 183.133383 -307.93829) (xy 183.103818 -307.977634) (xy 183.068325 -308.011726) (xy 183.027822 -308.039682)
			(xy 182.98336 -308.06078) (xy 182.936089 -308.074472) (xy 182.887234 -308.080404) (xy 182.838059 -308.078423)
			(xy 182.78984 -308.068579) (xy 182.743824 -308.051127) (xy 182.701203 -308.02652) (xy 182.663082 -307.995395)
			(xy 182.630447 -307.958558) (xy 182.604144 -307.916962) (xy 182.584853 -307.871686) (xy 182.573076 -307.823902)
			(xy 182.569116 -307.774848) (xy 182.230268 -307.774848) (xy 182.229773 -307.799455) (xy 182.221878 -307.848032)
			(xy 182.206294 -307.894713) (xy 182.183423 -307.93829) (xy 182.153858 -307.977634) (xy 182.118365 -308.011726)
			(xy 182.077862 -308.039682) (xy 182.0334 -308.06078) (xy 181.986129 -308.074472) (xy 181.937274 -308.080404)
			(xy 181.888099 -308.078423) (xy 181.83988 -308.068579) (xy 181.793864 -308.051127) (xy 181.751243 -308.02652)
			(xy 181.713122 -307.995395) (xy 181.680487 -307.958558) (xy 181.654184 -307.916962) (xy 181.634893 -307.871686)
			(xy 181.623116 -307.823902) (xy 181.619156 -307.774848) (xy 181.280308 -307.774848) (xy 181.279813 -307.799455)
			(xy 181.271918 -307.848032) (xy 181.256334 -307.894713) (xy 181.233463 -307.93829) (xy 181.203898 -307.977634)
			(xy 181.168405 -308.011726) (xy 181.127902 -308.039682) (xy 181.08344 -308.06078) (xy 181.036169 -308.074472)
			(xy 180.987314 -308.080404) (xy 180.938139 -308.078423) (xy 180.88992 -308.068579) (xy 180.843904 -308.051127)
			(xy 180.801283 -308.02652) (xy 180.763162 -307.995395) (xy 180.730527 -307.958558) (xy 180.704224 -307.916962)
			(xy 180.684933 -307.871686) (xy 180.673156 -307.823902) (xy 180.669196 -307.774848) (xy 180.330343 -307.774848)
			(xy 180.329853 -307.799201) (xy 180.321958 -307.847778) (xy 180.306374 -307.894459) (xy 180.283503 -307.938036)
			(xy 180.253938 -307.97738) (xy 180.218445 -308.011472) (xy 180.177942 -308.039428) (xy 180.13348 -308.060526)
			(xy 180.086209 -308.074218) (xy 180.037354 -308.08015) (xy 179.988179 -308.078169) (xy 179.93996 -308.068325)
			(xy 179.893944 -308.050873) (xy 179.851323 -308.026266) (xy 179.813202 -307.995141) (xy 179.780567 -307.958304)
			(xy 179.754264 -307.916708) (xy 179.734973 -307.871432) (xy 179.723196 -307.823648) (xy 179.719236 -307.774594)
			(xy 179.380134 -307.774594) (xy 179.379639 -307.799201) (xy 179.371744 -307.847778) (xy 179.35616 -307.894459)
			(xy 179.333289 -307.938036) (xy 179.303724 -307.97738) (xy 179.268231 -308.011472) (xy 179.227728 -308.039428)
			(xy 179.183266 -308.060526) (xy 179.135995 -308.074218) (xy 179.08714 -308.08015) (xy 179.037965 -308.078169)
			(xy 178.989746 -308.068325) (xy 178.94373 -308.050873) (xy 178.901109 -308.026266) (xy 178.862988 -307.995141)
			(xy 178.830353 -307.958304) (xy 178.80405 -307.916708) (xy 178.784759 -307.871432) (xy 178.772982 -307.823648)
			(xy 178.769022 -307.774594) (xy 178.430169 -307.774594) (xy 178.430174 -307.774848) (xy 178.429679 -307.799455)
			(xy 178.421784 -307.848032) (xy 178.4062 -307.894713) (xy 178.383329 -307.93829) (xy 178.353764 -307.977634)
			(xy 178.318271 -308.011726) (xy 178.277768 -308.039682) (xy 178.233306 -308.06078) (xy 178.186035 -308.074472)
			(xy 178.13718 -308.080404) (xy 178.088005 -308.078423) (xy 178.039786 -308.068579) (xy 177.99377 -308.051127)
			(xy 177.951149 -308.02652) (xy 177.913028 -307.995395) (xy 177.880393 -307.958558) (xy 177.85409 -307.916962)
			(xy 177.834799 -307.871686) (xy 177.823022 -307.823902) (xy 177.819062 -307.774848) (xy 177.480214 -307.774848)
			(xy 177.479719 -307.799455) (xy 177.471824 -307.848032) (xy 177.45624 -307.894713) (xy 177.433369 -307.93829)
			(xy 177.403804 -307.977634) (xy 177.368311 -308.011726) (xy 177.327808 -308.039682) (xy 177.283346 -308.06078)
			(xy 177.236075 -308.074472) (xy 177.18722 -308.080404) (xy 177.138045 -308.078423) (xy 177.089826 -308.068579)
			(xy 177.04381 -308.051127) (xy 177.001189 -308.02652) (xy 176.963068 -307.995395) (xy 176.930433 -307.958558)
			(xy 176.90413 -307.916962) (xy 176.884839 -307.871686) (xy 176.873062 -307.823902) (xy 176.869102 -307.774848)
			(xy 176.530254 -307.774848) (xy 176.529759 -307.799455) (xy 176.521864 -307.848032) (xy 176.50628 -307.894713)
			(xy 176.483409 -307.93829) (xy 176.453844 -307.977634) (xy 176.418351 -308.011726) (xy 176.377848 -308.039682)
			(xy 176.333386 -308.06078) (xy 176.286115 -308.074472) (xy 176.23726 -308.080404) (xy 176.188085 -308.078423)
			(xy 176.139866 -308.068579) (xy 176.09385 -308.051127) (xy 176.051229 -308.02652) (xy 176.013108 -307.995395)
			(xy 175.980473 -307.958558) (xy 175.95417 -307.916962) (xy 175.934879 -307.871686) (xy 175.923102 -307.823902)
			(xy 175.919142 -307.774848) (xy 174.630334 -307.774848) (xy 174.629839 -307.799455) (xy 174.621944 -307.848032)
			(xy 174.60636 -307.894713) (xy 174.583489 -307.93829) (xy 174.553924 -307.977634) (xy 174.518431 -308.011726)
			(xy 174.477928 -308.039682) (xy 174.433466 -308.06078) (xy 174.386195 -308.074472) (xy 174.33734 -308.080404)
			(xy 174.288165 -308.078423) (xy 174.239946 -308.068579) (xy 174.19393 -308.051127) (xy 174.151309 -308.02652)
			(xy 174.113188 -307.995395) (xy 174.080553 -307.958558) (xy 174.05425 -307.916962) (xy 174.034959 -307.871686)
			(xy 174.023182 -307.823902) (xy 174.019222 -307.774848) (xy 173.680374 -307.774848) (xy 173.679879 -307.799455)
			(xy 173.671984 -307.848032) (xy 173.6564 -307.894713) (xy 173.633529 -307.93829) (xy 173.603964 -307.977634)
			(xy 173.568471 -308.011726) (xy 173.527968 -308.039682) (xy 173.483506 -308.06078) (xy 173.436235 -308.074472)
			(xy 173.38738 -308.080404) (xy 173.338205 -308.078423) (xy 173.289986 -308.068579) (xy 173.24397 -308.051127)
			(xy 173.201349 -308.02652) (xy 173.163228 -307.995395) (xy 173.130593 -307.958558) (xy 173.10429 -307.916962)
			(xy 173.084999 -307.871686) (xy 173.073222 -307.823902) (xy 173.069262 -307.774848) (xy 172.730414 -307.774848)
			(xy 172.729919 -307.799455) (xy 172.722024 -307.848032) (xy 172.70644 -307.894713) (xy 172.683569 -307.93829)
			(xy 172.654004 -307.977634) (xy 172.618511 -308.011726) (xy 172.578008 -308.039682) (xy 172.533546 -308.06078)
			(xy 172.486275 -308.074472) (xy 172.43742 -308.080404) (xy 172.388245 -308.078423) (xy 172.340026 -308.068579)
			(xy 172.29401 -308.051127) (xy 172.251389 -308.02652) (xy 172.213268 -307.995395) (xy 172.180633 -307.958558)
			(xy 172.15433 -307.916962) (xy 172.135039 -307.871686) (xy 172.123262 -307.823902) (xy 172.119302 -307.774848)
			(xy 171.7802 -307.774848) (xy 171.779705 -307.799455) (xy 171.77181 -307.848032) (xy 171.756226 -307.894713)
			(xy 171.733355 -307.93829) (xy 171.70379 -307.977634) (xy 171.668297 -308.011726) (xy 171.627794 -308.039682)
			(xy 171.583332 -308.06078) (xy 171.536061 -308.074472) (xy 171.487206 -308.080404) (xy 171.438031 -308.078423)
			(xy 171.389812 -308.068579) (xy 171.343796 -308.051127) (xy 171.301175 -308.02652) (xy 171.263054 -307.995395)
			(xy 171.230419 -307.958558) (xy 171.204116 -307.916962) (xy 171.184825 -307.871686) (xy 171.173048 -307.823902)
			(xy 171.169088 -307.774848) (xy 170.83024 -307.774848) (xy 170.829745 -307.799455) (xy 170.82185 -307.848032)
			(xy 170.806266 -307.894713) (xy 170.783395 -307.93829) (xy 170.75383 -307.977634) (xy 170.718337 -308.011726)
			(xy 170.677834 -308.039682) (xy 170.633372 -308.06078) (xy 170.586101 -308.074472) (xy 170.537246 -308.080404)
			(xy 170.488071 -308.078423) (xy 170.439852 -308.068579) (xy 170.393836 -308.051127) (xy 170.351215 -308.02652)
			(xy 170.313094 -307.995395) (xy 170.280459 -307.958558) (xy 170.254156 -307.916962) (xy 170.234865 -307.871686)
			(xy 170.223088 -307.823902) (xy 170.219128 -307.774848) (xy 169.88028 -307.774848) (xy 169.879785 -307.799455)
			(xy 169.87189 -307.848032) (xy 169.856306 -307.894713) (xy 169.833435 -307.93829) (xy 169.80387 -307.977634)
			(xy 169.768377 -308.011726) (xy 169.727874 -308.039682) (xy 169.683412 -308.06078) (xy 169.636141 -308.074472)
			(xy 169.587286 -308.080404) (xy 169.538111 -308.078423) (xy 169.489892 -308.068579) (xy 169.443876 -308.051127)
			(xy 169.401255 -308.02652) (xy 169.363134 -307.995395) (xy 169.330499 -307.958558) (xy 169.304196 -307.916962)
			(xy 169.284905 -307.871686) (xy 169.273128 -307.823902) (xy 169.269168 -307.774848) (xy 168.93032 -307.774848)
			(xy 168.929825 -307.799455) (xy 168.92193 -307.848032) (xy 168.906346 -307.894713) (xy 168.883475 -307.93829)
			(xy 168.85391 -307.977634) (xy 168.818417 -308.011726) (xy 168.777914 -308.039682) (xy 168.733452 -308.06078)
			(xy 168.686181 -308.074472) (xy 168.637326 -308.080404) (xy 168.588151 -308.078423) (xy 168.539932 -308.068579)
			(xy 168.493916 -308.051127) (xy 168.451295 -308.02652) (xy 168.413174 -307.995395) (xy 168.380539 -307.958558)
			(xy 168.354236 -307.916962) (xy 168.334945 -307.871686) (xy 168.323168 -307.823902) (xy 168.319208 -307.774848)
			(xy 167.98036 -307.774848) (xy 167.979865 -307.799455) (xy 167.97197 -307.848032) (xy 167.956386 -307.894713)
			(xy 167.933515 -307.93829) (xy 167.90395 -307.977634) (xy 167.868457 -308.011726) (xy 167.827954 -308.039682)
			(xy 167.783492 -308.06078) (xy 167.736221 -308.074472) (xy 167.687366 -308.080404) (xy 167.638191 -308.078423)
			(xy 167.589972 -308.068579) (xy 167.543956 -308.051127) (xy 167.501335 -308.02652) (xy 167.463214 -307.995395)
			(xy 167.430579 -307.958558) (xy 167.404276 -307.916962) (xy 167.384985 -307.871686) (xy 167.373208 -307.823902)
			(xy 167.369248 -307.774848) (xy 167.0304 -307.774848) (xy 167.029905 -307.799455) (xy 167.02201 -307.848032)
			(xy 167.006426 -307.894713) (xy 166.983555 -307.93829) (xy 166.95399 -307.977634) (xy 166.918497 -308.011726)
			(xy 166.877994 -308.039682) (xy 166.833532 -308.06078) (xy 166.786261 -308.074472) (xy 166.737406 -308.080404)
			(xy 166.688231 -308.078423) (xy 166.640012 -308.068579) (xy 166.593996 -308.051127) (xy 166.551375 -308.02652)
			(xy 166.513254 -307.995395) (xy 166.480619 -307.958558) (xy 166.454316 -307.916962) (xy 166.435025 -307.871686)
			(xy 166.423248 -307.823902) (xy 166.419288 -307.774848) (xy 166.080186 -307.774848) (xy 166.079691 -307.799455)
			(xy 166.071796 -307.848032) (xy 166.056212 -307.894713) (xy 166.033341 -307.93829) (xy 166.003776 -307.977634)
			(xy 165.968283 -308.011726) (xy 165.92778 -308.039682) (xy 165.883318 -308.06078) (xy 165.836047 -308.074472)
			(xy 165.787192 -308.080404) (xy 165.738017 -308.078423) (xy 165.689798 -308.068579) (xy 165.643782 -308.051127)
			(xy 165.601161 -308.02652) (xy 165.56304 -307.995395) (xy 165.530405 -307.958558) (xy 165.504102 -307.916962)
			(xy 165.484811 -307.871686) (xy 165.473034 -307.823902) (xy 165.469074 -307.774848) (xy 165.155036 -307.774848)
			(xy 165.155036 -307.801184) (xy 165.146658 -307.85327) (xy 165.130116 -307.903365) (xy 165.105829 -307.950198)
			(xy 165.074414 -307.99258) (xy 165.036668 -308.029437) (xy 164.993549 -308.059832) (xy 164.94615 -308.082995)
			(xy 164.895675 -308.098338) (xy 164.869622 -308.102508) (xy 164.86505 -308.10327) (xy 164.854636 -308.106572)
			(xy 164.850318 -308.107842) (xy 164.826696 -308.118764) (xy 164.819838 -308.125876) (xy 164.804852 -308.141624)
			(xy 164.800266 -308.14673) (xy 164.793826 -308.158844) (xy 164.792152 -308.1655) (xy 164.790882 -308.176422)
			(xy 164.790882 -308.249828) (xy 189.69407 -308.249828) (xy 189.69803 -308.200774) (xy 189.709807 -308.15299)
			(xy 189.729098 -308.107714) (xy 189.755401 -308.066118) (xy 189.788036 -308.029281) (xy 189.826157 -307.998156)
			(xy 189.868778 -307.973549) (xy 189.914794 -307.956097) (xy 189.963013 -307.946253) (xy 190.012188 -307.944272)
			(xy 190.061043 -307.950204) (xy 190.108314 -307.963896) (xy 190.152776 -307.984994) (xy 190.193279 -308.01295)
			(xy 190.228772 -308.047042) (xy 190.258337 -308.086386) (xy 190.281208 -308.129963) (xy 190.296792 -308.176644)
			(xy 190.304687 -308.225221) (xy 190.305182 -308.249828) (xy 190.304687 -308.274435) (xy 190.304508 -308.275536)
			(xy 190.62344 -308.275536) (xy 190.62344 -308.22412) (xy 190.631483 -308.173338) (xy 190.647371 -308.124439)
			(xy 190.670714 -308.078627) (xy 190.700935 -308.037031) (xy 190.737291 -308.000675) (xy 190.778887 -307.970454)
			(xy 190.824699 -307.947111) (xy 190.873598 -307.931223) (xy 190.92438 -307.92318) (xy 190.975796 -307.92318)
			(xy 191.026578 -307.931223) (xy 191.075477 -307.947111) (xy 191.121289 -307.970454) (xy 191.162885 -308.000675)
			(xy 191.199241 -308.037031) (xy 191.229462 -308.078627) (xy 191.252805 -308.124439) (xy 191.268693 -308.173338)
			(xy 191.276736 -308.22412) (xy 191.27724 -308.249828) (xy 191.276736 -308.275536) (xy 191.5734 -308.275536)
			(xy 191.5734 -308.22412) (xy 191.581443 -308.173338) (xy 191.597331 -308.124439) (xy 191.620674 -308.078627)
			(xy 191.650895 -308.037031) (xy 191.687251 -308.000675) (xy 191.728847 -307.970454) (xy 191.774659 -307.947111)
			(xy 191.823558 -307.931223) (xy 191.87434 -307.92318) (xy 191.925756 -307.92318) (xy 191.976538 -307.931223)
			(xy 192.025437 -307.947111) (xy 192.071249 -307.970454) (xy 192.112845 -308.000675) (xy 192.149201 -308.037031)
			(xy 192.179422 -308.078627) (xy 192.202765 -308.124439) (xy 192.218653 -308.173338) (xy 192.226696 -308.22412)
			(xy 192.2272 -308.249828) (xy 192.544204 -308.249828) (xy 192.548164 -308.200774) (xy 192.559941 -308.15299)
			(xy 192.579232 -308.107714) (xy 192.605535 -308.066118) (xy 192.63817 -308.029281) (xy 192.676291 -307.998156)
			(xy 192.718912 -307.973549) (xy 192.764928 -307.956097) (xy 192.813147 -307.946253) (xy 192.862322 -307.944272)
			(xy 192.911177 -307.950204) (xy 192.958448 -307.963896) (xy 193.00291 -307.984994) (xy 193.043413 -308.01295)
			(xy 193.078906 -308.047042) (xy 193.108471 -308.086386) (xy 193.131342 -308.129963) (xy 193.146926 -308.176644)
			(xy 193.154821 -308.225221) (xy 193.155316 -308.249828) (xy 193.494164 -308.249828) (xy 193.498124 -308.200774)
			(xy 193.509901 -308.15299) (xy 193.529192 -308.107714) (xy 193.555495 -308.066118) (xy 193.58813 -308.029281)
			(xy 193.626251 -307.998156) (xy 193.668872 -307.973549) (xy 193.714888 -307.956097) (xy 193.763107 -307.946253)
			(xy 193.812282 -307.944272) (xy 193.861137 -307.950204) (xy 193.908408 -307.963896) (xy 193.95287 -307.984994)
			(xy 193.993373 -308.01295) (xy 194.028866 -308.047042) (xy 194.058431 -308.086386) (xy 194.081302 -308.129963)
			(xy 194.096886 -308.176644) (xy 194.104781 -308.225221) (xy 194.105276 -308.249828) (xy 194.444124 -308.249828)
			(xy 194.448084 -308.200774) (xy 194.459861 -308.15299) (xy 194.479152 -308.107714) (xy 194.505455 -308.066118)
			(xy 194.53809 -308.029281) (xy 194.576211 -307.998156) (xy 194.618832 -307.973549) (xy 194.664848 -307.956097)
			(xy 194.713067 -307.946253) (xy 194.762242 -307.944272) (xy 194.811097 -307.950204) (xy 194.858368 -307.963896)
			(xy 194.90283 -307.984994) (xy 194.943333 -308.01295) (xy 194.978826 -308.047042) (xy 195.008391 -308.086386)
			(xy 195.031262 -308.129963) (xy 195.046846 -308.176644) (xy 195.054741 -308.225221) (xy 195.055236 -308.249828)
			(xy 195.394084 -308.249828) (xy 195.398044 -308.200774) (xy 195.409821 -308.15299) (xy 195.429112 -308.107714)
			(xy 195.455415 -308.066118) (xy 195.48805 -308.029281) (xy 195.526171 -307.998156) (xy 195.568792 -307.973549)
			(xy 195.614808 -307.956097) (xy 195.663027 -307.946253) (xy 195.712202 -307.944272) (xy 195.761057 -307.950204)
			(xy 195.808328 -307.963896) (xy 195.85279 -307.984994) (xy 195.893293 -308.01295) (xy 195.928786 -308.047042)
			(xy 195.958351 -308.086386) (xy 195.981222 -308.129963) (xy 195.996806 -308.176644) (xy 196.004701 -308.225221)
			(xy 196.005196 -308.249828) (xy 196.344044 -308.249828) (xy 196.348004 -308.200774) (xy 196.359781 -308.15299)
			(xy 196.379072 -308.107714) (xy 196.405375 -308.066118) (xy 196.43801 -308.029281) (xy 196.476131 -307.998156)
			(xy 196.518752 -307.973549) (xy 196.564768 -307.956097) (xy 196.612987 -307.946253) (xy 196.662162 -307.944272)
			(xy 196.711017 -307.950204) (xy 196.758288 -307.963896) (xy 196.80275 -307.984994) (xy 196.843253 -308.01295)
			(xy 196.878746 -308.047042) (xy 196.908311 -308.086386) (xy 196.931182 -308.129963) (xy 196.946766 -308.176644)
			(xy 196.954661 -308.225221) (xy 196.955156 -308.249828) (xy 196.954661 -308.274435) (xy 196.954482 -308.275536)
			(xy 197.273414 -308.275536) (xy 197.273414 -308.22412) (xy 197.281457 -308.173338) (xy 197.297345 -308.124439)
			(xy 197.320688 -308.078627) (xy 197.350909 -308.037031) (xy 197.387265 -308.000675) (xy 197.428861 -307.970454)
			(xy 197.474673 -307.947111) (xy 197.523572 -307.931223) (xy 197.574354 -307.92318) (xy 197.62577 -307.92318)
			(xy 197.676552 -307.931223) (xy 197.725451 -307.947111) (xy 197.771263 -307.970454) (xy 197.812859 -308.000675)
			(xy 197.849215 -308.037031) (xy 197.879436 -308.078627) (xy 197.902779 -308.124439) (xy 197.918667 -308.173338)
			(xy 197.92671 -308.22412) (xy 197.927214 -308.249828) (xy 197.92671 -308.275536) (xy 198.223374 -308.275536)
			(xy 198.223374 -308.22412) (xy 198.231417 -308.173338) (xy 198.247305 -308.124439) (xy 198.270648 -308.078627)
			(xy 198.300869 -308.037031) (xy 198.337225 -308.000675) (xy 198.378821 -307.970454) (xy 198.424633 -307.947111)
			(xy 198.473532 -307.931223) (xy 198.524314 -307.92318) (xy 198.57573 -307.92318) (xy 198.626512 -307.931223)
			(xy 198.675411 -307.947111) (xy 198.721223 -307.970454) (xy 198.762819 -308.000675) (xy 198.799175 -308.037031)
			(xy 198.829396 -308.078627) (xy 198.852739 -308.124439) (xy 198.868627 -308.173338) (xy 198.87667 -308.22412)
			(xy 198.877174 -308.249828) (xy 199.194432 -308.249828) (xy 199.198392 -308.200774) (xy 199.210169 -308.15299)
			(xy 199.22946 -308.107714) (xy 199.255763 -308.066118) (xy 199.288398 -308.029281) (xy 199.326519 -307.998156)
			(xy 199.36914 -307.973549) (xy 199.415156 -307.956097) (xy 199.463375 -307.946253) (xy 199.51255 -307.944272)
			(xy 199.561405 -307.950204) (xy 199.608676 -307.963896) (xy 199.653138 -307.984994) (xy 199.693641 -308.01295)
			(xy 199.729134 -308.047042) (xy 199.758699 -308.086386) (xy 199.78157 -308.129963) (xy 199.797154 -308.176644)
			(xy 199.805049 -308.225221) (xy 199.805544 -308.249828) (xy 199.805049 -308.274435) (xy 199.797154 -308.323012)
			(xy 199.78157 -308.369693) (xy 199.758699 -308.41327) (xy 199.729134 -308.452614) (xy 199.693641 -308.486706)
			(xy 199.653138 -308.514662) (xy 199.608676 -308.53576) (xy 199.561405 -308.549452) (xy 199.51255 -308.555384)
			(xy 199.463375 -308.553403) (xy 199.415156 -308.543559) (xy 199.36914 -308.526107) (xy 199.326519 -308.5015)
			(xy 199.288398 -308.470375) (xy 199.255763 -308.433538) (xy 199.22946 -308.391942) (xy 199.210169 -308.346666)
			(xy 199.198392 -308.298882) (xy 199.194432 -308.249828) (xy 198.877174 -308.249828) (xy 198.87667 -308.275536)
			(xy 198.868627 -308.326318) (xy 198.852739 -308.375217) (xy 198.829396 -308.421029) (xy 198.799175 -308.462625)
			(xy 198.762819 -308.498981) (xy 198.721223 -308.529202) (xy 198.675411 -308.552545) (xy 198.626512 -308.568433)
			(xy 198.57573 -308.576476) (xy 198.524314 -308.576476) (xy 198.473532 -308.568433) (xy 198.424633 -308.552545)
			(xy 198.378821 -308.529202) (xy 198.337225 -308.498981) (xy 198.300869 -308.462625) (xy 198.270648 -308.421029)
			(xy 198.247305 -308.375217) (xy 198.231417 -308.326318) (xy 198.223374 -308.275536) (xy 197.92671 -308.275536)
			(xy 197.918667 -308.326318) (xy 197.902779 -308.375217) (xy 197.879436 -308.421029) (xy 197.849215 -308.462625)
			(xy 197.812859 -308.498981) (xy 197.771263 -308.529202) (xy 197.725451 -308.552545) (xy 197.676552 -308.568433)
			(xy 197.62577 -308.576476) (xy 197.574354 -308.576476) (xy 197.523572 -308.568433) (xy 197.474673 -308.552545)
			(xy 197.428861 -308.529202) (xy 197.387265 -308.498981) (xy 197.350909 -308.462625) (xy 197.320688 -308.421029)
			(xy 197.297345 -308.375217) (xy 197.281457 -308.326318) (xy 197.273414 -308.275536) (xy 196.954482 -308.275536)
			(xy 196.946766 -308.323012) (xy 196.931182 -308.369693) (xy 196.908311 -308.41327) (xy 196.878746 -308.452614)
			(xy 196.843253 -308.486706) (xy 196.80275 -308.514662) (xy 196.758288 -308.53576) (xy 196.711017 -308.549452)
			(xy 196.662162 -308.555384) (xy 196.612987 -308.553403) (xy 196.564768 -308.543559) (xy 196.518752 -308.526107)
			(xy 196.476131 -308.5015) (xy 196.43801 -308.470375) (xy 196.405375 -308.433538) (xy 196.379072 -308.391942)
			(xy 196.359781 -308.346666) (xy 196.348004 -308.298882) (xy 196.344044 -308.249828) (xy 196.005196 -308.249828)
			(xy 196.004701 -308.274435) (xy 195.996806 -308.323012) (xy 195.981222 -308.369693) (xy 195.958351 -308.41327)
			(xy 195.928786 -308.452614) (xy 195.893293 -308.486706) (xy 195.85279 -308.514662) (xy 195.808328 -308.53576)
			(xy 195.761057 -308.549452) (xy 195.712202 -308.555384) (xy 195.663027 -308.553403) (xy 195.614808 -308.543559)
			(xy 195.568792 -308.526107) (xy 195.526171 -308.5015) (xy 195.48805 -308.470375) (xy 195.455415 -308.433538)
			(xy 195.429112 -308.391942) (xy 195.409821 -308.346666) (xy 195.398044 -308.298882) (xy 195.394084 -308.249828)
			(xy 195.055236 -308.249828) (xy 195.054741 -308.274435) (xy 195.046846 -308.323012) (xy 195.031262 -308.369693)
			(xy 195.008391 -308.41327) (xy 194.978826 -308.452614) (xy 194.943333 -308.486706) (xy 194.90283 -308.514662)
			(xy 194.858368 -308.53576) (xy 194.811097 -308.549452) (xy 194.762242 -308.555384) (xy 194.713067 -308.553403)
			(xy 194.664848 -308.543559) (xy 194.618832 -308.526107) (xy 194.576211 -308.5015) (xy 194.53809 -308.470375)
			(xy 194.505455 -308.433538) (xy 194.479152 -308.391942) (xy 194.459861 -308.346666) (xy 194.448084 -308.298882)
			(xy 194.444124 -308.249828) (xy 194.105276 -308.249828) (xy 194.104781 -308.274435) (xy 194.096886 -308.323012)
			(xy 194.081302 -308.369693) (xy 194.058431 -308.41327) (xy 194.028866 -308.452614) (xy 193.993373 -308.486706)
			(xy 193.95287 -308.514662) (xy 193.908408 -308.53576) (xy 193.861137 -308.549452) (xy 193.812282 -308.555384)
			(xy 193.763107 -308.553403) (xy 193.714888 -308.543559) (xy 193.668872 -308.526107) (xy 193.626251 -308.5015)
			(xy 193.58813 -308.470375) (xy 193.555495 -308.433538) (xy 193.529192 -308.391942) (xy 193.509901 -308.346666)
			(xy 193.498124 -308.298882) (xy 193.494164 -308.249828) (xy 193.155316 -308.249828) (xy 193.154821 -308.274435)
			(xy 193.146926 -308.323012) (xy 193.131342 -308.369693) (xy 193.108471 -308.41327) (xy 193.078906 -308.452614)
			(xy 193.043413 -308.486706) (xy 193.00291 -308.514662) (xy 192.958448 -308.53576) (xy 192.911177 -308.549452)
			(xy 192.862322 -308.555384) (xy 192.813147 -308.553403) (xy 192.764928 -308.543559) (xy 192.718912 -308.526107)
			(xy 192.676291 -308.5015) (xy 192.63817 -308.470375) (xy 192.605535 -308.433538) (xy 192.579232 -308.391942)
			(xy 192.559941 -308.346666) (xy 192.548164 -308.298882) (xy 192.544204 -308.249828) (xy 192.2272 -308.249828)
			(xy 192.226696 -308.275536) (xy 192.218653 -308.326318) (xy 192.202765 -308.375217) (xy 192.179422 -308.421029)
			(xy 192.149201 -308.462625) (xy 192.112845 -308.498981) (xy 192.071249 -308.529202) (xy 192.025437 -308.552545)
			(xy 191.976538 -308.568433) (xy 191.925756 -308.576476) (xy 191.87434 -308.576476) (xy 191.823558 -308.568433)
			(xy 191.774659 -308.552545) (xy 191.728847 -308.529202) (xy 191.687251 -308.498981) (xy 191.650895 -308.462625)
			(xy 191.620674 -308.421029) (xy 191.597331 -308.375217) (xy 191.581443 -308.326318) (xy 191.5734 -308.275536)
			(xy 191.276736 -308.275536) (xy 191.268693 -308.326318) (xy 191.252805 -308.375217) (xy 191.229462 -308.421029)
			(xy 191.199241 -308.462625) (xy 191.162885 -308.498981) (xy 191.121289 -308.529202) (xy 191.075477 -308.552545)
			(xy 191.026578 -308.568433) (xy 190.975796 -308.576476) (xy 190.92438 -308.576476) (xy 190.873598 -308.568433)
			(xy 190.824699 -308.552545) (xy 190.778887 -308.529202) (xy 190.737291 -308.498981) (xy 190.700935 -308.462625)
			(xy 190.670714 -308.421029) (xy 190.647371 -308.375217) (xy 190.631483 -308.326318) (xy 190.62344 -308.275536)
			(xy 190.304508 -308.275536) (xy 190.296792 -308.323012) (xy 190.281208 -308.369693) (xy 190.258337 -308.41327)
			(xy 190.228772 -308.452614) (xy 190.193279 -308.486706) (xy 190.152776 -308.514662) (xy 190.108314 -308.53576)
			(xy 190.061043 -308.549452) (xy 190.012188 -308.555384) (xy 189.963013 -308.553403) (xy 189.914794 -308.543559)
			(xy 189.868778 -308.526107) (xy 189.826157 -308.5015) (xy 189.788036 -308.470375) (xy 189.755401 -308.433538)
			(xy 189.729098 -308.391942) (xy 189.709807 -308.346666) (xy 189.69803 -308.298882) (xy 189.69407 -308.249828)
			(xy 164.790882 -308.249828) (xy 164.790882 -308.323234) (xy 164.791048 -308.329388) (xy 164.793997 -308.341337)
			(xy 164.796724 -308.346856) (xy 164.804852 -308.358032) (xy 164.819584 -308.373526) (xy 164.826188 -308.380638)
			(xy 164.849302 -308.39156) (xy 164.852858 -308.392576) (xy 164.86505 -308.396386) (xy 164.869622 -308.397148)
			(xy 164.895691 -308.401225) (xy 164.946172 -308.416571) (xy 164.993576 -308.439738) (xy 165.0367 -308.470138)
			(xy 165.074449 -308.506999) (xy 165.105867 -308.549387) (xy 165.130155 -308.596226) (xy 165.146698 -308.646328)
			(xy 165.155076 -308.69842) (xy 165.155076 -308.724808) (xy 165.469074 -308.724808) (xy 165.473034 -308.675754)
			(xy 165.484811 -308.62797) (xy 165.504102 -308.582694) (xy 165.530405 -308.541098) (xy 165.56304 -308.504261)
			(xy 165.601161 -308.473136) (xy 165.643782 -308.448529) (xy 165.689798 -308.431077) (xy 165.738017 -308.421233)
			(xy 165.787192 -308.419252) (xy 165.836047 -308.425184) (xy 165.883318 -308.438876) (xy 165.92778 -308.459974)
			(xy 165.968283 -308.48793) (xy 166.003776 -308.522022) (xy 166.033341 -308.561366) (xy 166.056212 -308.604943)
			(xy 166.071796 -308.651624) (xy 166.079691 -308.700201) (xy 166.080186 -308.724808) (xy 166.419288 -308.724808)
			(xy 166.423248 -308.675754) (xy 166.435025 -308.62797) (xy 166.454316 -308.582694) (xy 166.480619 -308.541098)
			(xy 166.513254 -308.504261) (xy 166.551375 -308.473136) (xy 166.593996 -308.448529) (xy 166.640012 -308.431077)
			(xy 166.688231 -308.421233) (xy 166.737406 -308.419252) (xy 166.786261 -308.425184) (xy 166.833532 -308.438876)
			(xy 166.877994 -308.459974) (xy 166.918497 -308.48793) (xy 166.95399 -308.522022) (xy 166.983555 -308.561366)
			(xy 167.006426 -308.604943) (xy 167.02201 -308.651624) (xy 167.029905 -308.700201) (xy 167.0304 -308.724808)
			(xy 167.369248 -308.724808) (xy 167.373208 -308.675754) (xy 167.384985 -308.62797) (xy 167.404276 -308.582694)
			(xy 167.430579 -308.541098) (xy 167.463214 -308.504261) (xy 167.501335 -308.473136) (xy 167.543956 -308.448529)
			(xy 167.589972 -308.431077) (xy 167.638191 -308.421233) (xy 167.687366 -308.419252) (xy 167.736221 -308.425184)
			(xy 167.783492 -308.438876) (xy 167.827954 -308.459974) (xy 167.868457 -308.48793) (xy 167.90395 -308.522022)
			(xy 167.933515 -308.561366) (xy 167.956386 -308.604943) (xy 167.97197 -308.651624) (xy 167.979865 -308.700201)
			(xy 167.98036 -308.724808) (xy 168.319208 -308.724808) (xy 168.323168 -308.675754) (xy 168.334945 -308.62797)
			(xy 168.354236 -308.582694) (xy 168.380539 -308.541098) (xy 168.413174 -308.504261) (xy 168.451295 -308.473136)
			(xy 168.493916 -308.448529) (xy 168.539932 -308.431077) (xy 168.588151 -308.421233) (xy 168.637326 -308.419252)
			(xy 168.686181 -308.425184) (xy 168.733452 -308.438876) (xy 168.777914 -308.459974) (xy 168.818417 -308.48793)
			(xy 168.85391 -308.522022) (xy 168.883475 -308.561366) (xy 168.906346 -308.604943) (xy 168.92193 -308.651624)
			(xy 168.929825 -308.700201) (xy 168.93032 -308.724808) (xy 169.269168 -308.724808) (xy 169.273128 -308.675754)
			(xy 169.284905 -308.62797) (xy 169.304196 -308.582694) (xy 169.330499 -308.541098) (xy 169.363134 -308.504261)
			(xy 169.401255 -308.473136) (xy 169.443876 -308.448529) (xy 169.489892 -308.431077) (xy 169.538111 -308.421233)
			(xy 169.587286 -308.419252) (xy 169.636141 -308.425184) (xy 169.683412 -308.438876) (xy 169.727874 -308.459974)
			(xy 169.768377 -308.48793) (xy 169.80387 -308.522022) (xy 169.833435 -308.561366) (xy 169.856306 -308.604943)
			(xy 169.87189 -308.651624) (xy 169.879785 -308.700201) (xy 169.88028 -308.724808) (xy 170.219128 -308.724808)
			(xy 170.223088 -308.675754) (xy 170.234865 -308.62797) (xy 170.254156 -308.582694) (xy 170.280459 -308.541098)
			(xy 170.313094 -308.504261) (xy 170.351215 -308.473136) (xy 170.393836 -308.448529) (xy 170.439852 -308.431077)
			(xy 170.488071 -308.421233) (xy 170.537246 -308.419252) (xy 170.586101 -308.425184) (xy 170.633372 -308.438876)
			(xy 170.677834 -308.459974) (xy 170.718337 -308.48793) (xy 170.75383 -308.522022) (xy 170.783395 -308.561366)
			(xy 170.806266 -308.604943) (xy 170.82185 -308.651624) (xy 170.829745 -308.700201) (xy 170.83024 -308.724808)
			(xy 171.169088 -308.724808) (xy 171.173048 -308.675754) (xy 171.184825 -308.62797) (xy 171.204116 -308.582694)
			(xy 171.230419 -308.541098) (xy 171.263054 -308.504261) (xy 171.301175 -308.473136) (xy 171.343796 -308.448529)
			(xy 171.389812 -308.431077) (xy 171.438031 -308.421233) (xy 171.487206 -308.419252) (xy 171.536061 -308.425184)
			(xy 171.583332 -308.438876) (xy 171.627794 -308.459974) (xy 171.668297 -308.48793) (xy 171.70379 -308.522022)
			(xy 171.733355 -308.561366) (xy 171.756226 -308.604943) (xy 171.77181 -308.651624) (xy 171.779705 -308.700201)
			(xy 171.7802 -308.724808) (xy 172.119302 -308.724808) (xy 172.123262 -308.675754) (xy 172.135039 -308.62797)
			(xy 172.15433 -308.582694) (xy 172.180633 -308.541098) (xy 172.213268 -308.504261) (xy 172.251389 -308.473136)
			(xy 172.29401 -308.448529) (xy 172.340026 -308.431077) (xy 172.388245 -308.421233) (xy 172.43742 -308.419252)
			(xy 172.486275 -308.425184) (xy 172.533546 -308.438876) (xy 172.578008 -308.459974) (xy 172.618511 -308.48793)
			(xy 172.654004 -308.522022) (xy 172.683569 -308.561366) (xy 172.70644 -308.604943) (xy 172.722024 -308.651624)
			(xy 172.729919 -308.700201) (xy 172.730414 -308.724808) (xy 174.019222 -308.724808) (xy 174.023182 -308.675754)
			(xy 174.034959 -308.62797) (xy 174.05425 -308.582694) (xy 174.080553 -308.541098) (xy 174.113188 -308.504261)
			(xy 174.151309 -308.473136) (xy 174.19393 -308.448529) (xy 174.239946 -308.431077) (xy 174.288165 -308.421233)
			(xy 174.33734 -308.419252) (xy 174.386195 -308.425184) (xy 174.433466 -308.438876) (xy 174.477928 -308.459974)
			(xy 174.518431 -308.48793) (xy 174.553924 -308.522022) (xy 174.583489 -308.561366) (xy 174.60636 -308.604943)
			(xy 174.621944 -308.651624) (xy 174.629839 -308.700201) (xy 174.630334 -308.724808) (xy 174.630167 -308.733111)
			(xy 175.919135 -308.733111) (xy 175.921819 -308.683533) (xy 175.932489 -308.635042) (xy 175.950863 -308.588915)
			(xy 175.976458 -308.54637) (xy 176.008598 -308.508525) (xy 176.046439 -308.47638) (xy 176.088981 -308.45078)
			(xy 176.135105 -308.4324) (xy 176.183595 -308.421724) (xy 176.233173 -308.419034) (xy 176.282533 -308.424401)
			(xy 176.330375 -308.437683) (xy 176.375438 -308.45853) (xy 176.416534 -308.486394) (xy 176.45258 -308.520538)
			(xy 176.482628 -308.560065) (xy 176.505884 -308.603933) (xy 176.521737 -308.650985) (xy 176.529769 -308.699982)
			(xy 176.530254 -308.724808) (xy 176.530078 -308.738991) (xy 176.527405 -308.767231) (xy 176.52492 -308.781196)
			(xy 176.522634 -308.793642) (xy 176.53 -308.817264) (xy 176.60747 -308.894734) (xy 176.631092 -308.9021)
			(xy 176.643538 -308.899814) (xy 176.657504 -308.897336) (xy 176.685743 -308.894665) (xy 176.699926 -308.89448)
			(xy 176.714109 -308.894653) (xy 176.742349 -308.897328) (xy 176.756314 -308.899814) (xy 176.76876 -308.9021)
			(xy 176.792382 -308.894734) (xy 176.869852 -308.817264) (xy 176.877218 -308.793642) (xy 176.874932 -308.781196)
			(xy 176.872459 -308.76723) (xy 176.869785 -308.73899) (xy 176.869598 -308.724808) (xy 176.87012 -308.699553)
			(xy 176.878433 -308.649731) (xy 176.894834 -308.601957) (xy 176.918875 -308.557534) (xy 176.949899 -308.517674)
			(xy 176.987061 -308.483464) (xy 177.029347 -308.455838) (xy 177.075603 -308.435548) (xy 177.124568 -308.423148)
			(xy 177.174906 -308.418977) (xy 177.225244 -308.423148) (xy 177.274209 -308.435548) (xy 177.320465 -308.455838)
			(xy 177.362751 -308.483464) (xy 177.399913 -308.517674) (xy 177.430937 -308.557534) (xy 177.454978 -308.601957)
			(xy 177.471379 -308.649731) (xy 177.479692 -308.699553) (xy 177.480214 -308.724808) (xy 177.480038 -308.738991)
			(xy 177.477366 -308.767231) (xy 177.47488 -308.781196) (xy 177.472594 -308.793642) (xy 177.47996 -308.817264)
			(xy 177.55743 -308.894734) (xy 177.581052 -308.9021) (xy 177.593498 -308.899814) (xy 177.607465 -308.897342)
			(xy 177.635704 -308.894667) (xy 177.649886 -308.89448) (xy 177.664069 -308.894659) (xy 177.692309 -308.897329)
			(xy 177.706274 -308.899814) (xy 177.71872 -308.9021) (xy 177.742342 -308.894734) (xy 177.819812 -308.817264)
			(xy 177.827178 -308.793642) (xy 177.824892 -308.781196) (xy 177.822419 -308.76723) (xy 177.819745 -308.73899)
			(xy 177.819558 -308.724808) (xy 177.820069 -308.699986) (xy 177.8281 -308.650995) (xy 177.843951 -308.603949)
			(xy 177.867204 -308.560087) (xy 177.897247 -308.520566) (xy 177.933289 -308.486425) (xy 177.974379 -308.458565)
			(xy 178.019435 -308.43772) (xy 178.06727 -308.42444) (xy 178.116624 -308.419073) (xy 178.166195 -308.421762)
			(xy 178.214679 -308.432435) (xy 178.260797 -308.450812) (xy 178.303334 -308.476408) (xy 178.34117 -308.508548)
			(xy 178.373307 -308.546387) (xy 178.3989 -308.588926) (xy 178.417273 -308.635046) (xy 178.427942 -308.68353)
			(xy 178.430163 -308.724554) (xy 178.769022 -308.724554) (xy 178.772982 -308.6755) (xy 178.784759 -308.627716)
			(xy 178.80405 -308.58244) (xy 178.830353 -308.540844) (xy 178.862988 -308.504007) (xy 178.901109 -308.472882)
			(xy 178.94373 -308.448275) (xy 178.989746 -308.430823) (xy 179.037965 -308.420979) (xy 179.08714 -308.418998)
			(xy 179.135995 -308.42493) (xy 179.183266 -308.438622) (xy 179.227728 -308.45972) (xy 179.268231 -308.487676)
			(xy 179.303724 -308.521768) (xy 179.333289 -308.561112) (xy 179.35616 -308.604689) (xy 179.371744 -308.65137)
			(xy 179.379639 -308.699947) (xy 179.380134 -308.724554) (xy 179.380129 -308.724808) (xy 179.719236 -308.724808)
			(xy 179.723196 -308.675754) (xy 179.734973 -308.62797) (xy 179.754264 -308.582694) (xy 179.780567 -308.541098)
			(xy 179.813202 -308.504261) (xy 179.851323 -308.473136) (xy 179.893944 -308.448529) (xy 179.93996 -308.431077)
			(xy 179.988179 -308.421233) (xy 180.037354 -308.419252) (xy 180.086209 -308.425184) (xy 180.13348 -308.438876)
			(xy 180.177942 -308.459974) (xy 180.218445 -308.48793) (xy 180.253938 -308.522022) (xy 180.283503 -308.561366)
			(xy 180.306374 -308.604943) (xy 180.321958 -308.651624) (xy 180.329853 -308.700201) (xy 180.330348 -308.724808)
			(xy 180.669196 -308.724808) (xy 180.673156 -308.675754) (xy 180.684933 -308.62797) (xy 180.704224 -308.582694)
			(xy 180.730527 -308.541098) (xy 180.763162 -308.504261) (xy 180.801283 -308.473136) (xy 180.843904 -308.448529)
			(xy 180.88992 -308.431077) (xy 180.938139 -308.421233) (xy 180.987314 -308.419252) (xy 181.036169 -308.425184)
			(xy 181.08344 -308.438876) (xy 181.127902 -308.459974) (xy 181.168405 -308.48793) (xy 181.203898 -308.522022)
			(xy 181.233463 -308.561366) (xy 181.256334 -308.604943) (xy 181.271918 -308.651624) (xy 181.279813 -308.700201)
			(xy 181.280308 -308.724808) (xy 181.619156 -308.724808) (xy 181.623116 -308.675754) (xy 181.634893 -308.62797)
			(xy 181.654184 -308.582694) (xy 181.680487 -308.541098) (xy 181.713122 -308.504261) (xy 181.751243 -308.473136)
			(xy 181.793864 -308.448529) (xy 181.83988 -308.431077) (xy 181.888099 -308.421233) (xy 181.937274 -308.419252)
			(xy 181.986129 -308.425184) (xy 182.0334 -308.438876) (xy 182.077862 -308.459974) (xy 182.118365 -308.48793)
			(xy 182.153858 -308.522022) (xy 182.183423 -308.561366) (xy 182.206294 -308.604943) (xy 182.221878 -308.651624)
			(xy 182.229773 -308.700201) (xy 182.230268 -308.724808) (xy 182.569116 -308.724808) (xy 182.573076 -308.675754)
			(xy 182.584853 -308.62797) (xy 182.604144 -308.582694) (xy 182.630447 -308.541098) (xy 182.663082 -308.504261)
			(xy 182.701203 -308.473136) (xy 182.743824 -308.448529) (xy 182.78984 -308.431077) (xy 182.838059 -308.421233)
			(xy 182.887234 -308.419252) (xy 182.936089 -308.425184) (xy 182.98336 -308.438876) (xy 183.027822 -308.459974)
			(xy 183.068325 -308.48793) (xy 183.103818 -308.522022) (xy 183.133383 -308.561366) (xy 183.156254 -308.604943)
			(xy 183.171838 -308.651624) (xy 183.179733 -308.700201) (xy 183.180228 -308.724808) (xy 183.519076 -308.724808)
			(xy 183.523036 -308.675754) (xy 183.534813 -308.62797) (xy 183.554104 -308.582694) (xy 183.580407 -308.541098)
			(xy 183.613042 -308.504261) (xy 183.651163 -308.473136) (xy 183.693784 -308.448529) (xy 183.7398 -308.431077)
			(xy 183.788019 -308.421233) (xy 183.837194 -308.419252) (xy 183.886049 -308.425184) (xy 183.93332 -308.438876)
			(xy 183.977782 -308.459974) (xy 184.018285 -308.48793) (xy 184.053778 -308.522022) (xy 184.083343 -308.561366)
			(xy 184.106214 -308.604943) (xy 184.121798 -308.651624) (xy 184.129693 -308.700201) (xy 184.130188 -308.724808)
			(xy 184.46929 -308.724808) (xy 184.47325 -308.675754) (xy 184.485027 -308.62797) (xy 184.504318 -308.582694)
			(xy 184.530621 -308.541098) (xy 184.563256 -308.504261) (xy 184.601377 -308.473136) (xy 184.643998 -308.448529)
			(xy 184.690014 -308.431077) (xy 184.738233 -308.421233) (xy 184.787408 -308.419252) (xy 184.836263 -308.425184)
			(xy 184.883534 -308.438876) (xy 184.927996 -308.459974) (xy 184.968499 -308.48793) (xy 185.003992 -308.522022)
			(xy 185.033557 -308.561366) (xy 185.056428 -308.604943) (xy 185.072012 -308.651624) (xy 185.079907 -308.700201)
			(xy 185.080402 -308.724808) (xy 185.41925 -308.724808) (xy 185.42321 -308.675754) (xy 185.434987 -308.62797)
			(xy 185.454278 -308.582694) (xy 185.480581 -308.541098) (xy 185.513216 -308.504261) (xy 185.551337 -308.473136)
			(xy 185.593958 -308.448529) (xy 185.639974 -308.431077) (xy 185.688193 -308.421233) (xy 185.737368 -308.419252)
			(xy 185.786223 -308.425184) (xy 185.833494 -308.438876) (xy 185.877956 -308.459974) (xy 185.918459 -308.48793)
			(xy 185.953952 -308.522022) (xy 185.983517 -308.561366) (xy 186.006388 -308.604943) (xy 186.021972 -308.651624)
			(xy 186.029867 -308.700201) (xy 186.030362 -308.724808) (xy 186.36921 -308.724808) (xy 186.37317 -308.675754)
			(xy 186.384947 -308.62797) (xy 186.404238 -308.582694) (xy 186.430541 -308.541098) (xy 186.463176 -308.504261)
			(xy 186.501297 -308.473136) (xy 186.543918 -308.448529) (xy 186.589934 -308.431077) (xy 186.638153 -308.421233)
			(xy 186.687328 -308.419252) (xy 186.736183 -308.425184) (xy 186.783454 -308.438876) (xy 186.827916 -308.459974)
			(xy 186.868419 -308.48793) (xy 186.903912 -308.522022) (xy 186.933477 -308.561366) (xy 186.956348 -308.604943)
			(xy 186.971932 -308.651624) (xy 186.979827 -308.700201) (xy 186.980322 -308.724808) (xy 187.31917 -308.724808)
			(xy 187.32313 -308.675754) (xy 187.334907 -308.62797) (xy 187.354198 -308.582694) (xy 187.380501 -308.541098)
			(xy 187.413136 -308.504261) (xy 187.451257 -308.473136) (xy 187.493878 -308.448529) (xy 187.539894 -308.431077)
			(xy 187.588113 -308.421233) (xy 187.637288 -308.419252) (xy 187.686143 -308.425184) (xy 187.733414 -308.438876)
			(xy 187.777876 -308.459974) (xy 187.818379 -308.48793) (xy 187.853872 -308.522022) (xy 187.883437 -308.561366)
			(xy 187.906308 -308.604943) (xy 187.921892 -308.651624) (xy 187.929787 -308.700201) (xy 187.930282 -308.724808)
			(xy 188.26913 -308.724808) (xy 188.27309 -308.675754) (xy 188.284867 -308.62797) (xy 188.304158 -308.582694)
			(xy 188.330461 -308.541098) (xy 188.363096 -308.504261) (xy 188.401217 -308.473136) (xy 188.443838 -308.448529)
			(xy 188.489854 -308.431077) (xy 188.538073 -308.421233) (xy 188.587248 -308.419252) (xy 188.636103 -308.425184)
			(xy 188.683374 -308.438876) (xy 188.727836 -308.459974) (xy 188.768339 -308.48793) (xy 188.803832 -308.522022)
			(xy 188.833397 -308.561366) (xy 188.856268 -308.604943) (xy 188.871852 -308.651624) (xy 188.879747 -308.700201)
			(xy 188.880242 -308.724808) (xy 188.879747 -308.749415) (xy 188.871852 -308.797992) (xy 188.856268 -308.844673)
			(xy 188.833397 -308.88825) (xy 188.803832 -308.927594) (xy 188.768339 -308.961686) (xy 188.727836 -308.989642)
			(xy 188.683374 -309.01074) (xy 188.636103 -309.024432) (xy 188.587248 -309.030364) (xy 188.538073 -309.028383)
			(xy 188.489854 -309.018539) (xy 188.443838 -309.001087) (xy 188.401217 -308.97648) (xy 188.363096 -308.945355)
			(xy 188.330461 -308.908518) (xy 188.304158 -308.866922) (xy 188.284867 -308.821646) (xy 188.27309 -308.773862)
			(xy 188.26913 -308.724808) (xy 187.930282 -308.724808) (xy 187.929787 -308.749415) (xy 187.921892 -308.797992)
			(xy 187.906308 -308.844673) (xy 187.883437 -308.88825) (xy 187.853872 -308.927594) (xy 187.818379 -308.961686)
			(xy 187.777876 -308.989642) (xy 187.733414 -309.01074) (xy 187.686143 -309.024432) (xy 187.637288 -309.030364)
			(xy 187.588113 -309.028383) (xy 187.539894 -309.018539) (xy 187.493878 -309.001087) (xy 187.451257 -308.97648)
			(xy 187.413136 -308.945355) (xy 187.380501 -308.908518) (xy 187.354198 -308.866922) (xy 187.334907 -308.821646)
			(xy 187.32313 -308.773862) (xy 187.31917 -308.724808) (xy 186.980322 -308.724808) (xy 186.979827 -308.749415)
			(xy 186.971932 -308.797992) (xy 186.956348 -308.844673) (xy 186.933477 -308.88825) (xy 186.903912 -308.927594)
			(xy 186.868419 -308.961686) (xy 186.827916 -308.989642) (xy 186.783454 -309.01074) (xy 186.736183 -309.024432)
			(xy 186.687328 -309.030364) (xy 186.638153 -309.028383) (xy 186.589934 -309.018539) (xy 186.543918 -309.001087)
			(xy 186.501297 -308.97648) (xy 186.463176 -308.945355) (xy 186.430541 -308.908518) (xy 186.404238 -308.866922)
			(xy 186.384947 -308.821646) (xy 186.37317 -308.773862) (xy 186.36921 -308.724808) (xy 186.030362 -308.724808)
			(xy 186.029867 -308.749415) (xy 186.021972 -308.797992) (xy 186.006388 -308.844673) (xy 185.983517 -308.88825)
			(xy 185.953952 -308.927594) (xy 185.918459 -308.961686) (xy 185.877956 -308.989642) (xy 185.833494 -309.01074)
			(xy 185.786223 -309.024432) (xy 185.737368 -309.030364) (xy 185.688193 -309.028383) (xy 185.639974 -309.018539)
			(xy 185.593958 -309.001087) (xy 185.551337 -308.97648) (xy 185.513216 -308.945355) (xy 185.480581 -308.908518)
			(xy 185.454278 -308.866922) (xy 185.434987 -308.821646) (xy 185.42321 -308.773862) (xy 185.41925 -308.724808)
			(xy 185.080402 -308.724808) (xy 185.079907 -308.749415) (xy 185.072012 -308.797992) (xy 185.056428 -308.844673)
			(xy 185.033557 -308.88825) (xy 185.003992 -308.927594) (xy 184.968499 -308.961686) (xy 184.927996 -308.989642)
			(xy 184.883534 -309.01074) (xy 184.836263 -309.024432) (xy 184.787408 -309.030364) (xy 184.738233 -309.028383)
			(xy 184.690014 -309.018539) (xy 184.643998 -309.001087) (xy 184.601377 -308.97648) (xy 184.563256 -308.945355)
			(xy 184.530621 -308.908518) (xy 184.504318 -308.866922) (xy 184.485027 -308.821646) (xy 184.47325 -308.773862)
			(xy 184.46929 -308.724808) (xy 184.130188 -308.724808) (xy 184.129693 -308.749415) (xy 184.121798 -308.797992)
			(xy 184.106214 -308.844673) (xy 184.083343 -308.88825) (xy 184.053778 -308.927594) (xy 184.018285 -308.961686)
			(xy 183.977782 -308.989642) (xy 183.93332 -309.01074) (xy 183.886049 -309.024432) (xy 183.837194 -309.030364)
			(xy 183.788019 -309.028383) (xy 183.7398 -309.018539) (xy 183.693784 -309.001087) (xy 183.651163 -308.97648)
			(xy 183.613042 -308.945355) (xy 183.580407 -308.908518) (xy 183.554104 -308.866922) (xy 183.534813 -308.821646)
			(xy 183.523036 -308.773862) (xy 183.519076 -308.724808) (xy 183.180228 -308.724808) (xy 183.179733 -308.749415)
			(xy 183.171838 -308.797992) (xy 183.156254 -308.844673) (xy 183.133383 -308.88825) (xy 183.103818 -308.927594)
			(xy 183.068325 -308.961686) (xy 183.027822 -308.989642) (xy 182.98336 -309.01074) (xy 182.936089 -309.024432)
			(xy 182.887234 -309.030364) (xy 182.838059 -309.028383) (xy 182.78984 -309.018539) (xy 182.743824 -309.001087)
			(xy 182.701203 -308.97648) (xy 182.663082 -308.945355) (xy 182.630447 -308.908518) (xy 182.604144 -308.866922)
			(xy 182.584853 -308.821646) (xy 182.573076 -308.773862) (xy 182.569116 -308.724808) (xy 182.230268 -308.724808)
			(xy 182.229773 -308.749415) (xy 182.221878 -308.797992) (xy 182.206294 -308.844673) (xy 182.183423 -308.88825)
			(xy 182.153858 -308.927594) (xy 182.118365 -308.961686) (xy 182.077862 -308.989642) (xy 182.0334 -309.01074)
			(xy 181.986129 -309.024432) (xy 181.937274 -309.030364) (xy 181.888099 -309.028383) (xy 181.83988 -309.018539)
			(xy 181.793864 -309.001087) (xy 181.751243 -308.97648) (xy 181.713122 -308.945355) (xy 181.680487 -308.908518)
			(xy 181.654184 -308.866922) (xy 181.634893 -308.821646) (xy 181.623116 -308.773862) (xy 181.619156 -308.724808)
			(xy 181.280308 -308.724808) (xy 181.279813 -308.749415) (xy 181.271918 -308.797992) (xy 181.256334 -308.844673)
			(xy 181.233463 -308.88825) (xy 181.203898 -308.927594) (xy 181.168405 -308.961686) (xy 181.127902 -308.989642)
			(xy 181.08344 -309.01074) (xy 181.036169 -309.024432) (xy 180.987314 -309.030364) (xy 180.938139 -309.028383)
			(xy 180.88992 -309.018539) (xy 180.843904 -309.001087) (xy 180.801283 -308.97648) (xy 180.763162 -308.945355)
			(xy 180.730527 -308.908518) (xy 180.704224 -308.866922) (xy 180.684933 -308.821646) (xy 180.673156 -308.773862)
			(xy 180.669196 -308.724808) (xy 180.330348 -308.724808) (xy 180.329853 -308.749415) (xy 180.321958 -308.797992)
			(xy 180.306374 -308.844673) (xy 180.283503 -308.88825) (xy 180.253938 -308.927594) (xy 180.218445 -308.961686)
			(xy 180.177942 -308.989642) (xy 180.13348 -309.01074) (xy 180.086209 -309.024432) (xy 180.037354 -309.030364)
			(xy 179.988179 -309.028383) (xy 179.93996 -309.018539) (xy 179.893944 -309.001087) (xy 179.851323 -308.97648)
			(xy 179.813202 -308.945355) (xy 179.780567 -308.908518) (xy 179.754264 -308.866922) (xy 179.734973 -308.821646)
			(xy 179.723196 -308.773862) (xy 179.719236 -308.724808) (xy 179.380129 -308.724808) (xy 179.379639 -308.749161)
			(xy 179.371744 -308.797738) (xy 179.35616 -308.844419) (xy 179.333289 -308.887996) (xy 179.303724 -308.92734)
			(xy 179.268231 -308.961432) (xy 179.227728 -308.989388) (xy 179.183266 -309.010486) (xy 179.135995 -309.024178)
			(xy 179.08714 -309.03011) (xy 179.037965 -309.028129) (xy 178.989746 -309.018285) (xy 178.94373 -309.000833)
			(xy 178.901109 -308.976226) (xy 178.862988 -308.945101) (xy 178.830353 -308.908264) (xy 178.80405 -308.866668)
			(xy 178.784759 -308.821392) (xy 178.772982 -308.773608) (xy 178.769022 -308.724554) (xy 178.430163 -308.724554)
			(xy 178.430626 -308.733102) (xy 178.425255 -308.782455) (xy 178.411971 -308.830289) (xy 178.391122 -308.875344)
			(xy 178.363259 -308.916432) (xy 178.329115 -308.95247) (xy 178.289591 -308.98251) (xy 178.245727 -309.00576)
			(xy 178.19868 -309.021606) (xy 178.149688 -309.029633) (xy 178.124866 -309.030116) (xy 178.110683 -309.029944)
			(xy 178.082443 -309.027269) (xy 178.068478 -309.024782) (xy 178.056032 -309.022496) (xy 178.03241 -309.029862)
			(xy 177.95494 -309.107332) (xy 177.947574 -309.130954) (xy 177.94986 -309.1434) (xy 177.952332 -309.157367)
			(xy 177.955007 -309.185606) (xy 177.955194 -309.199788) (xy 189.69407 -309.199788) (xy 189.69803 -309.150734)
			(xy 189.709807 -309.10295) (xy 189.729098 -309.057674) (xy 189.755401 -309.016078) (xy 189.788036 -308.979241)
			(xy 189.826157 -308.948116) (xy 189.868778 -308.923509) (xy 189.914794 -308.906057) (xy 189.963013 -308.896213)
			(xy 190.012188 -308.894232) (xy 190.061043 -308.900164) (xy 190.108314 -308.913856) (xy 190.152776 -308.934954)
			(xy 190.193279 -308.96291) (xy 190.228772 -308.997002) (xy 190.258337 -309.036346) (xy 190.281208 -309.079923)
			(xy 190.296792 -309.126604) (xy 190.304687 -309.175181) (xy 190.305182 -309.199788) (xy 190.644284 -309.199788)
			(xy 190.648244 -309.150734) (xy 190.660021 -309.10295) (xy 190.679312 -309.057674) (xy 190.705615 -309.016078)
			(xy 190.73825 -308.979241) (xy 190.776371 -308.948116) (xy 190.818992 -308.923509) (xy 190.865008 -308.906057)
			(xy 190.913227 -308.896213) (xy 190.962402 -308.894232) (xy 191.011257 -308.900164) (xy 191.058528 -308.913856)
			(xy 191.10299 -308.934954) (xy 191.143493 -308.96291) (xy 191.178986 -308.997002) (xy 191.208551 -309.036346)
			(xy 191.231422 -309.079923) (xy 191.247006 -309.126604) (xy 191.254901 -309.175181) (xy 191.255396 -309.199788)
			(xy 191.594244 -309.199788) (xy 191.598204 -309.150734) (xy 191.609981 -309.10295) (xy 191.629272 -309.057674)
			(xy 191.655575 -309.016078) (xy 191.68821 -308.979241) (xy 191.726331 -308.948116) (xy 191.768952 -308.923509)
			(xy 191.814968 -308.906057) (xy 191.863187 -308.896213) (xy 191.912362 -308.894232) (xy 191.961217 -308.900164)
			(xy 192.008488 -308.913856) (xy 192.05295 -308.934954) (xy 192.093453 -308.96291) (xy 192.128946 -308.997002)
			(xy 192.158511 -309.036346) (xy 192.181382 -309.079923) (xy 192.196966 -309.126604) (xy 192.204861 -309.175181)
			(xy 192.205356 -309.199788) (xy 192.204861 -309.224395) (xy 192.204682 -309.225496) (xy 192.52336 -309.225496)
			(xy 192.52336 -309.17408) (xy 192.531403 -309.123298) (xy 192.547291 -309.074399) (xy 192.570634 -309.028587)
			(xy 192.600855 -308.986991) (xy 192.637211 -308.950635) (xy 192.678807 -308.920414) (xy 192.724619 -308.897071)
			(xy 192.773518 -308.881183) (xy 192.8243 -308.87314) (xy 192.875716 -308.87314) (xy 192.926498 -308.881183)
			(xy 192.975397 -308.897071) (xy 193.021209 -308.920414) (xy 193.062805 -308.950635) (xy 193.099161 -308.986991)
			(xy 193.129382 -309.028587) (xy 193.152725 -309.074399) (xy 193.168613 -309.123298) (xy 193.176656 -309.17408)
			(xy 193.17716 -309.199788) (xy 193.176656 -309.225496) (xy 193.47332 -309.225496) (xy 193.47332 -309.17408)
			(xy 193.481363 -309.123298) (xy 193.497251 -309.074399) (xy 193.520594 -309.028587) (xy 193.550815 -308.986991)
			(xy 193.587171 -308.950635) (xy 193.628767 -308.920414) (xy 193.674579 -308.897071) (xy 193.723478 -308.881183)
			(xy 193.77426 -308.87314) (xy 193.825676 -308.87314) (xy 193.876458 -308.881183) (xy 193.925357 -308.897071)
			(xy 193.971169 -308.920414) (xy 194.012765 -308.950635) (xy 194.049121 -308.986991) (xy 194.079342 -309.028587)
			(xy 194.102685 -309.074399) (xy 194.118573 -309.123298) (xy 194.126616 -309.17408) (xy 194.12712 -309.199788)
			(xy 194.444124 -309.199788) (xy 194.448084 -309.150734) (xy 194.459861 -309.10295) (xy 194.479152 -309.057674)
			(xy 194.505455 -309.016078) (xy 194.53809 -308.979241) (xy 194.576211 -308.948116) (xy 194.618832 -308.923509)
			(xy 194.664848 -308.906057) (xy 194.713067 -308.896213) (xy 194.762242 -308.894232) (xy 194.811097 -308.900164)
			(xy 194.858368 -308.913856) (xy 194.90283 -308.934954) (xy 194.943333 -308.96291) (xy 194.978826 -308.997002)
			(xy 195.008391 -309.036346) (xy 195.031262 -309.079923) (xy 195.046846 -309.126604) (xy 195.054741 -309.175181)
			(xy 195.055236 -309.199788) (xy 195.054741 -309.224395) (xy 195.054562 -309.225496) (xy 195.37324 -309.225496)
			(xy 195.37324 -309.17408) (xy 195.381283 -309.123298) (xy 195.397171 -309.074399) (xy 195.420514 -309.028587)
			(xy 195.450735 -308.986991) (xy 195.487091 -308.950635) (xy 195.528687 -308.920414) (xy 195.574499 -308.897071)
			(xy 195.623398 -308.881183) (xy 195.67418 -308.87314) (xy 195.725596 -308.87314) (xy 195.776378 -308.881183)
			(xy 195.825277 -308.897071) (xy 195.871089 -308.920414) (xy 195.912685 -308.950635) (xy 195.949041 -308.986991)
			(xy 195.979262 -309.028587) (xy 196.002605 -309.074399) (xy 196.018493 -309.123298) (xy 196.026536 -309.17408)
			(xy 196.02704 -309.199788) (xy 196.026536 -309.225496) (xy 196.3232 -309.225496) (xy 196.3232 -309.17408)
			(xy 196.331243 -309.123298) (xy 196.347131 -309.074399) (xy 196.370474 -309.028587) (xy 196.400695 -308.986991)
			(xy 196.437051 -308.950635) (xy 196.478647 -308.920414) (xy 196.524459 -308.897071) (xy 196.573358 -308.881183)
			(xy 196.62414 -308.87314) (xy 196.675556 -308.87314) (xy 196.726338 -308.881183) (xy 196.775237 -308.897071)
			(xy 196.821049 -308.920414) (xy 196.862645 -308.950635) (xy 196.899001 -308.986991) (xy 196.929222 -309.028587)
			(xy 196.952565 -309.074399) (xy 196.968453 -309.123298) (xy 196.976496 -309.17408) (xy 196.977 -309.199788)
			(xy 197.294258 -309.199788) (xy 197.298218 -309.150734) (xy 197.309995 -309.10295) (xy 197.329286 -309.057674)
			(xy 197.355589 -309.016078) (xy 197.388224 -308.979241) (xy 197.426345 -308.948116) (xy 197.468966 -308.923509)
			(xy 197.514982 -308.906057) (xy 197.563201 -308.896213) (xy 197.612376 -308.894232) (xy 197.661231 -308.900164)
			(xy 197.708502 -308.913856) (xy 197.752964 -308.934954) (xy 197.793467 -308.96291) (xy 197.82896 -308.997002)
			(xy 197.858525 -309.036346) (xy 197.881396 -309.079923) (xy 197.89698 -309.126604) (xy 197.904875 -309.175181)
			(xy 197.90537 -309.199788) (xy 198.244218 -309.199788) (xy 198.248178 -309.150734) (xy 198.259955 -309.10295)
			(xy 198.279246 -309.057674) (xy 198.305549 -309.016078) (xy 198.338184 -308.979241) (xy 198.376305 -308.948116)
			(xy 198.418926 -308.923509) (xy 198.464942 -308.906057) (xy 198.513161 -308.896213) (xy 198.562336 -308.894232)
			(xy 198.611191 -308.900164) (xy 198.658462 -308.913856) (xy 198.702924 -308.934954) (xy 198.743427 -308.96291)
			(xy 198.77892 -308.997002) (xy 198.808485 -309.036346) (xy 198.831356 -309.079923) (xy 198.84694 -309.126604)
			(xy 198.854835 -309.175181) (xy 198.85533 -309.199788) (xy 198.854835 -309.224395) (xy 198.84694 -309.272972)
			(xy 198.831356 -309.319653) (xy 198.808485 -309.36323) (xy 198.800515 -309.373836) (xy 204.602097 -309.373836)
			(xy 204.602099 -309.319337) (xy 204.609857 -309.265393) (xy 204.625213 -309.213102) (xy 204.647854 -309.163529)
			(xy 204.67732 -309.117682) (xy 204.71301 -309.076496) (xy 204.754198 -309.040808) (xy 204.800047 -309.011344)
			(xy 204.849621 -308.988706) (xy 204.901913 -308.973353) (xy 204.955857 -308.965598) (xy 205.010356 -308.965599)
			(xy 205.0643 -308.973356) (xy 205.116591 -308.98871) (xy 205.166165 -309.011351) (xy 205.212012 -309.040816)
			(xy 205.253199 -309.076505) (xy 205.288888 -309.117693) (xy 205.318352 -309.163541) (xy 205.340992 -309.213115)
			(xy 205.356346 -309.265406) (xy 205.364102 -309.319351) (xy 205.364588 -309.3466) (xy 205.36408 -309.365904)
			(xy 205.363572 -309.376826) (xy 205.371192 -309.396638) (xy 205.44028 -309.465472) (xy 205.460346 -309.473092)
			(xy 205.471268 -309.47233) (xy 205.492858 -309.471822) (xy 205.520114 -309.47221) (xy 205.574072 -309.479962)
			(xy 205.626378 -309.495314) (xy 205.675966 -309.517954) (xy 205.721828 -309.547421) (xy 205.763029 -309.583114)
			(xy 205.798731 -309.624308) (xy 205.828208 -309.670163) (xy 205.837505 -309.690516) (xy 209.57743 -309.690516)
			(xy 209.581501 -309.634894) (xy 209.593627 -309.580457) (xy 209.61355 -309.528366) (xy 209.640846 -309.479731)
			(xy 209.674932 -309.435588) (xy 209.715081 -309.396879) (xy 209.760439 -309.364428) (xy 209.810039 -309.338927)
			(xy 209.862823 -309.32092) (xy 209.917666 -309.31079) (xy 209.9734 -309.308753) (xy 210.028837 -309.314853)
			(xy 210.082794 -309.328959) (xy 210.134123 -309.350771) (xy 210.181729 -309.379825) (xy 210.224597 -309.4155)
			(xy 210.261814 -309.457037) (xy 210.292587 -309.50355) (xy 210.316259 -309.554047) (xy 210.332327 -309.607454)
			(xy 210.340447 -309.66263) (xy 210.340956 -309.690516) (xy 210.340447 -309.718402) (xy 210.332327 -309.773578)
			(xy 210.316259 -309.826985) (xy 210.292587 -309.877482) (xy 210.261814 -309.923995) (xy 210.224597 -309.965532)
			(xy 210.181729 -310.001207) (xy 210.134123 -310.030261) (xy 210.082794 -310.052073) (xy 210.028837 -310.066179)
			(xy 209.9734 -310.072279) (xy 209.917666 -310.070242) (xy 209.862823 -310.060112) (xy 209.810039 -310.042105)
			(xy 209.760439 -310.016604) (xy 209.715081 -309.984153) (xy 209.674932 -309.945444) (xy 209.640846 -309.901301)
			(xy 209.61355 -309.852666) (xy 209.593627 -309.800575) (xy 209.581501 -309.746138) (xy 209.57743 -309.690516)
			(xy 205.837505 -309.690516) (xy 205.850858 -309.719747) (xy 205.866221 -309.772049) (xy 205.873984 -309.826006)
			(xy 205.87399 -309.880518) (xy 205.866237 -309.934476) (xy 205.850884 -309.986782) (xy 205.828244 -310.03637)
			(xy 205.798777 -310.082231) (xy 205.763083 -310.123432) (xy 205.721889 -310.159134) (xy 205.676033 -310.18861)
			(xy 205.626449 -310.211259) (xy 205.574147 -310.226622) (xy 205.52019 -310.234385) (xy 205.465678 -310.234389)
			(xy 205.41172 -310.226636) (xy 205.359415 -310.211283) (xy 205.309827 -310.188642) (xy 205.263966 -310.159175)
			(xy 205.222765 -310.12348) (xy 205.187064 -310.082286) (xy 205.157589 -310.03643) (xy 205.134939 -309.986845)
			(xy 205.119577 -309.934543) (xy 205.111815 -309.880586) (xy 205.11135 -309.85333) (xy 205.111858 -309.834026)
			(xy 205.112366 -309.823104) (xy 205.104746 -309.803292) (xy 205.035658 -309.734458) (xy 205.015592 -309.726838)
			(xy 205.00467 -309.7276) (xy 204.98308 -309.728108) (xy 204.955831 -309.7276) (xy 204.901887 -309.719842)
			(xy 204.849596 -309.704485) (xy 204.800023 -309.681843) (xy 204.754177 -309.652376) (xy 204.712991 -309.616685)
			(xy 204.677304 -309.575496) (xy 204.647841 -309.529648) (xy 204.625203 -309.480073) (xy 204.609851 -309.427781)
			(xy 204.602097 -309.373836) (xy 198.800515 -309.373836) (xy 198.77892 -309.402574) (xy 198.743427 -309.436666)
			(xy 198.702924 -309.464622) (xy 198.658462 -309.48572) (xy 198.611191 -309.499412) (xy 198.562336 -309.505344)
			(xy 198.513161 -309.503363) (xy 198.464942 -309.493519) (xy 198.418926 -309.476067) (xy 198.376305 -309.45146)
			(xy 198.338184 -309.420335) (xy 198.305549 -309.383498) (xy 198.279246 -309.341902) (xy 198.259955 -309.296626)
			(xy 198.248178 -309.248842) (xy 198.244218 -309.199788) (xy 197.90537 -309.199788) (xy 197.904875 -309.224395)
			(xy 197.89698 -309.272972) (xy 197.881396 -309.319653) (xy 197.858525 -309.36323) (xy 197.82896 -309.402574)
			(xy 197.793467 -309.436666) (xy 197.752964 -309.464622) (xy 197.708502 -309.48572) (xy 197.661231 -309.499412)
			(xy 197.612376 -309.505344) (xy 197.563201 -309.503363) (xy 197.514982 -309.493519) (xy 197.468966 -309.476067)
			(xy 197.426345 -309.45146) (xy 197.388224 -309.420335) (xy 197.355589 -309.383498) (xy 197.329286 -309.341902)
			(xy 197.309995 -309.296626) (xy 197.298218 -309.248842) (xy 197.294258 -309.199788) (xy 196.977 -309.199788)
			(xy 196.976496 -309.225496) (xy 196.968453 -309.276278) (xy 196.952565 -309.325177) (xy 196.929222 -309.370989)
			(xy 196.899001 -309.412585) (xy 196.862645 -309.448941) (xy 196.821049 -309.479162) (xy 196.775237 -309.502505)
			(xy 196.726338 -309.518393) (xy 196.675556 -309.526436) (xy 196.62414 -309.526436) (xy 196.573358 -309.518393)
			(xy 196.524459 -309.502505) (xy 196.478647 -309.479162) (xy 196.437051 -309.448941) (xy 196.400695 -309.412585)
			(xy 196.370474 -309.370989) (xy 196.347131 -309.325177) (xy 196.331243 -309.276278) (xy 196.3232 -309.225496)
			(xy 196.026536 -309.225496) (xy 196.018493 -309.276278) (xy 196.002605 -309.325177) (xy 195.979262 -309.370989)
			(xy 195.949041 -309.412585) (xy 195.912685 -309.448941) (xy 195.871089 -309.479162) (xy 195.825277 -309.502505)
			(xy 195.776378 -309.518393) (xy 195.725596 -309.526436) (xy 195.67418 -309.526436) (xy 195.623398 -309.518393)
			(xy 195.574499 -309.502505) (xy 195.528687 -309.479162) (xy 195.487091 -309.448941) (xy 195.450735 -309.412585)
			(xy 195.420514 -309.370989) (xy 195.397171 -309.325177) (xy 195.381283 -309.276278) (xy 195.37324 -309.225496)
			(xy 195.054562 -309.225496) (xy 195.046846 -309.272972) (xy 195.031262 -309.319653) (xy 195.008391 -309.36323)
			(xy 194.978826 -309.402574) (xy 194.943333 -309.436666) (xy 194.90283 -309.464622) (xy 194.858368 -309.48572)
			(xy 194.811097 -309.499412) (xy 194.762242 -309.505344) (xy 194.713067 -309.503363) (xy 194.664848 -309.493519)
			(xy 194.618832 -309.476067) (xy 194.576211 -309.45146) (xy 194.53809 -309.420335) (xy 194.505455 -309.383498)
			(xy 194.479152 -309.341902) (xy 194.459861 -309.296626) (xy 194.448084 -309.248842) (xy 194.444124 -309.199788)
			(xy 194.12712 -309.199788) (xy 194.126616 -309.225496) (xy 194.118573 -309.276278) (xy 194.102685 -309.325177)
			(xy 194.079342 -309.370989) (xy 194.049121 -309.412585) (xy 194.012765 -309.448941) (xy 193.971169 -309.479162)
			(xy 193.925357 -309.502505) (xy 193.876458 -309.518393) (xy 193.825676 -309.526436) (xy 193.77426 -309.526436)
			(xy 193.723478 -309.518393) (xy 193.674579 -309.502505) (xy 193.628767 -309.479162) (xy 193.587171 -309.448941)
			(xy 193.550815 -309.412585) (xy 193.520594 -309.370989) (xy 193.497251 -309.325177) (xy 193.481363 -309.276278)
			(xy 193.47332 -309.225496) (xy 193.176656 -309.225496) (xy 193.168613 -309.276278) (xy 193.152725 -309.325177)
			(xy 193.129382 -309.370989) (xy 193.099161 -309.412585) (xy 193.062805 -309.448941) (xy 193.021209 -309.479162)
			(xy 192.975397 -309.502505) (xy 192.926498 -309.518393) (xy 192.875716 -309.526436) (xy 192.8243 -309.526436)
			(xy 192.773518 -309.518393) (xy 192.724619 -309.502505) (xy 192.678807 -309.479162) (xy 192.637211 -309.448941)
			(xy 192.600855 -309.412585) (xy 192.570634 -309.370989) (xy 192.547291 -309.325177) (xy 192.531403 -309.276278)
			(xy 192.52336 -309.225496) (xy 192.204682 -309.225496) (xy 192.196966 -309.272972) (xy 192.181382 -309.319653)
			(xy 192.158511 -309.36323) (xy 192.128946 -309.402574) (xy 192.093453 -309.436666) (xy 192.05295 -309.464622)
			(xy 192.008488 -309.48572) (xy 191.961217 -309.499412) (xy 191.912362 -309.505344) (xy 191.863187 -309.503363)
			(xy 191.814968 -309.493519) (xy 191.768952 -309.476067) (xy 191.726331 -309.45146) (xy 191.68821 -309.420335)
			(xy 191.655575 -309.383498) (xy 191.629272 -309.341902) (xy 191.609981 -309.296626) (xy 191.598204 -309.248842)
			(xy 191.594244 -309.199788) (xy 191.255396 -309.199788) (xy 191.254901 -309.224395) (xy 191.247006 -309.272972)
			(xy 191.231422 -309.319653) (xy 191.208551 -309.36323) (xy 191.178986 -309.402574) (xy 191.143493 -309.436666)
			(xy 191.10299 -309.464622) (xy 191.058528 -309.48572) (xy 191.011257 -309.499412) (xy 190.962402 -309.505344)
			(xy 190.913227 -309.503363) (xy 190.865008 -309.493519) (xy 190.818992 -309.476067) (xy 190.776371 -309.45146)
			(xy 190.73825 -309.420335) (xy 190.705615 -309.383498) (xy 190.679312 -309.341902) (xy 190.660021 -309.296626)
			(xy 190.648244 -309.248842) (xy 190.644284 -309.199788) (xy 190.305182 -309.199788) (xy 190.304687 -309.224395)
			(xy 190.296792 -309.272972) (xy 190.281208 -309.319653) (xy 190.258337 -309.36323) (xy 190.228772 -309.402574)
			(xy 190.193279 -309.436666) (xy 190.152776 -309.464622) (xy 190.108314 -309.48572) (xy 190.061043 -309.499412)
			(xy 190.012188 -309.505344) (xy 189.963013 -309.503363) (xy 189.914794 -309.493519) (xy 189.868778 -309.476067)
			(xy 189.826157 -309.45146) (xy 189.788036 -309.420335) (xy 189.755401 -309.383498) (xy 189.729098 -309.341902)
			(xy 189.709807 -309.296626) (xy 189.69803 -309.248842) (xy 189.69407 -309.199788) (xy 177.955194 -309.199788)
			(xy 177.954672 -309.225043) (xy 177.946359 -309.274865) (xy 177.929958 -309.322639) (xy 177.905917 -309.367062)
			(xy 177.874893 -309.406922) (xy 177.837731 -309.441132) (xy 177.795445 -309.468758) (xy 177.749189 -309.489048)
			(xy 177.700224 -309.501448) (xy 177.649886 -309.505619) (xy 177.599548 -309.501448) (xy 177.550583 -309.489048)
			(xy 177.504327 -309.468758) (xy 177.462041 -309.441132) (xy 177.424879 -309.406922) (xy 177.393855 -309.367062)
			(xy 177.369814 -309.322639) (xy 177.353413 -309.274865) (xy 177.3451 -309.225043) (xy 177.344578 -309.199788)
			(xy 177.344753 -309.185605) (xy 177.347426 -309.157365) (xy 177.349912 -309.1434) (xy 177.352198 -309.130954)
			(xy 177.344832 -309.107332) (xy 177.267362 -309.029862) (xy 177.24374 -309.022496) (xy 177.231294 -309.024782)
			(xy 177.217328 -309.027255) (xy 177.189088 -309.029929) (xy 177.174906 -309.030116) (xy 177.160723 -309.029938)
			(xy 177.132483 -309.027267) (xy 177.118518 -309.024782) (xy 177.106072 -309.022496) (xy 177.08245 -309.029862)
			(xy 177.00498 -309.107332) (xy 176.997614 -309.130954) (xy 176.9999 -309.1434) (xy 177.002373 -309.157367)
			(xy 177.005047 -309.185606) (xy 177.005234 -309.199788) (xy 177.004712 -309.225043) (xy 176.996399 -309.274865)
			(xy 176.979998 -309.322639) (xy 176.955957 -309.367062) (xy 176.924933 -309.406922) (xy 176.887771 -309.441132)
			(xy 176.845485 -309.468758) (xy 176.799229 -309.489048) (xy 176.750264 -309.501448) (xy 176.699926 -309.505619)
			(xy 176.649588 -309.501448) (xy 176.600623 -309.489048) (xy 176.554367 -309.468758) (xy 176.512081 -309.441132)
			(xy 176.474919 -309.406922) (xy 176.443895 -309.367062) (xy 176.419854 -309.322639) (xy 176.403453 -309.274865)
			(xy 176.39514 -309.225043) (xy 176.394618 -309.199788) (xy 176.394793 -309.185605) (xy 176.397466 -309.157365)
			(xy 176.399952 -309.1434) (xy 176.402238 -309.130954) (xy 176.394872 -309.107332) (xy 176.317402 -309.029862)
			(xy 176.29378 -309.022496) (xy 176.281334 -309.024782) (xy 176.267369 -309.027263) (xy 176.239129 -309.029932)
			(xy 176.224946 -309.030116) (xy 176.20012 -309.029672) (xy 176.151122 -309.021647) (xy 176.104068 -309.005799)
			(xy 176.060198 -308.982548) (xy 176.020667 -308.952506) (xy 175.986517 -308.916463) (xy 175.958649 -308.875371)
			(xy 175.937796 -308.830311) (xy 175.924508 -308.782471) (xy 175.919135 -308.733111) (xy 174.630167 -308.733111)
			(xy 174.629839 -308.749415) (xy 174.621944 -308.797992) (xy 174.60636 -308.844673) (xy 174.583489 -308.88825)
			(xy 174.553924 -308.927594) (xy 174.518431 -308.961686) (xy 174.477928 -308.989642) (xy 174.433466 -309.01074)
			(xy 174.386195 -309.024432) (xy 174.33734 -309.030364) (xy 174.288165 -309.028383) (xy 174.239946 -309.018539)
			(xy 174.19393 -309.001087) (xy 174.151309 -308.97648) (xy 174.113188 -308.945355) (xy 174.080553 -308.908518)
			(xy 174.05425 -308.866922) (xy 174.034959 -308.821646) (xy 174.023182 -308.773862) (xy 174.019222 -308.724808)
			(xy 172.730414 -308.724808) (xy 172.729919 -308.749415) (xy 172.722024 -308.797992) (xy 172.70644 -308.844673)
			(xy 172.683569 -308.88825) (xy 172.654004 -308.927594) (xy 172.618511 -308.961686) (xy 172.578008 -308.989642)
			(xy 172.533546 -309.01074) (xy 172.486275 -309.024432) (xy 172.43742 -309.030364) (xy 172.388245 -309.028383)
			(xy 172.340026 -309.018539) (xy 172.29401 -309.001087) (xy 172.251389 -308.97648) (xy 172.213268 -308.945355)
			(xy 172.180633 -308.908518) (xy 172.15433 -308.866922) (xy 172.135039 -308.821646) (xy 172.123262 -308.773862)
			(xy 172.119302 -308.724808) (xy 171.7802 -308.724808) (xy 171.779705 -308.749415) (xy 171.77181 -308.797992)
			(xy 171.756226 -308.844673) (xy 171.733355 -308.88825) (xy 171.70379 -308.927594) (xy 171.668297 -308.961686)
			(xy 171.627794 -308.989642) (xy 171.583332 -309.01074) (xy 171.536061 -309.024432) (xy 171.487206 -309.030364)
			(xy 171.438031 -309.028383) (xy 171.389812 -309.018539) (xy 171.343796 -309.001087) (xy 171.301175 -308.97648)
			(xy 171.263054 -308.945355) (xy 171.230419 -308.908518) (xy 171.204116 -308.866922) (xy 171.184825 -308.821646)
			(xy 171.173048 -308.773862) (xy 171.169088 -308.724808) (xy 170.83024 -308.724808) (xy 170.829745 -308.749415)
			(xy 170.82185 -308.797992) (xy 170.806266 -308.844673) (xy 170.783395 -308.88825) (xy 170.75383 -308.927594)
			(xy 170.718337 -308.961686) (xy 170.677834 -308.989642) (xy 170.633372 -309.01074) (xy 170.586101 -309.024432)
			(xy 170.537246 -309.030364) (xy 170.488071 -309.028383) (xy 170.439852 -309.018539) (xy 170.393836 -309.001087)
			(xy 170.351215 -308.97648) (xy 170.313094 -308.945355) (xy 170.280459 -308.908518) (xy 170.254156 -308.866922)
			(xy 170.234865 -308.821646) (xy 170.223088 -308.773862) (xy 170.219128 -308.724808) (xy 169.88028 -308.724808)
			(xy 169.879785 -308.749415) (xy 169.87189 -308.797992) (xy 169.856306 -308.844673) (xy 169.833435 -308.88825)
			(xy 169.80387 -308.927594) (xy 169.768377 -308.961686) (xy 169.727874 -308.989642) (xy 169.683412 -309.01074)
			(xy 169.636141 -309.024432) (xy 169.587286 -309.030364) (xy 169.538111 -309.028383) (xy 169.489892 -309.018539)
			(xy 169.443876 -309.001087) (xy 169.401255 -308.97648) (xy 169.363134 -308.945355) (xy 169.330499 -308.908518)
			(xy 169.304196 -308.866922) (xy 169.284905 -308.821646) (xy 169.273128 -308.773862) (xy 169.269168 -308.724808)
			(xy 168.93032 -308.724808) (xy 168.929825 -308.749415) (xy 168.92193 -308.797992) (xy 168.906346 -308.844673)
			(xy 168.883475 -308.88825) (xy 168.85391 -308.927594) (xy 168.818417 -308.961686) (xy 168.777914 -308.989642)
			(xy 168.733452 -309.01074) (xy 168.686181 -309.024432) (xy 168.637326 -309.030364) (xy 168.588151 -309.028383)
			(xy 168.539932 -309.018539) (xy 168.493916 -309.001087) (xy 168.451295 -308.97648) (xy 168.413174 -308.945355)
			(xy 168.380539 -308.908518) (xy 168.354236 -308.866922) (xy 168.334945 -308.821646) (xy 168.323168 -308.773862)
			(xy 168.319208 -308.724808) (xy 167.98036 -308.724808) (xy 167.979865 -308.749415) (xy 167.97197 -308.797992)
			(xy 167.956386 -308.844673) (xy 167.933515 -308.88825) (xy 167.90395 -308.927594) (xy 167.868457 -308.961686)
			(xy 167.827954 -308.989642) (xy 167.783492 -309.01074) (xy 167.736221 -309.024432) (xy 167.687366 -309.030364)
			(xy 167.638191 -309.028383) (xy 167.589972 -309.018539) (xy 167.543956 -309.001087) (xy 167.501335 -308.97648)
			(xy 167.463214 -308.945355) (xy 167.430579 -308.908518) (xy 167.404276 -308.866922) (xy 167.384985 -308.821646)
			(xy 167.373208 -308.773862) (xy 167.369248 -308.724808) (xy 167.0304 -308.724808) (xy 167.029905 -308.749415)
			(xy 167.02201 -308.797992) (xy 167.006426 -308.844673) (xy 166.983555 -308.88825) (xy 166.95399 -308.927594)
			(xy 166.918497 -308.961686) (xy 166.877994 -308.989642) (xy 166.833532 -309.01074) (xy 166.786261 -309.024432)
			(xy 166.737406 -309.030364) (xy 166.688231 -309.028383) (xy 166.640012 -309.018539) (xy 166.593996 -309.001087)
			(xy 166.551375 -308.97648) (xy 166.513254 -308.945355) (xy 166.480619 -308.908518) (xy 166.454316 -308.866922)
			(xy 166.435025 -308.821646) (xy 166.423248 -308.773862) (xy 166.419288 -308.724808) (xy 166.080186 -308.724808)
			(xy 166.079691 -308.749415) (xy 166.071796 -308.797992) (xy 166.056212 -308.844673) (xy 166.033341 -308.88825)
			(xy 166.003776 -308.927594) (xy 165.968283 -308.961686) (xy 165.92778 -308.989642) (xy 165.883318 -309.01074)
			(xy 165.836047 -309.024432) (xy 165.787192 -309.030364) (xy 165.738017 -309.028383) (xy 165.689798 -309.018539)
			(xy 165.643782 -309.001087) (xy 165.601161 -308.97648) (xy 165.56304 -308.945355) (xy 165.530405 -308.908518)
			(xy 165.504102 -308.866922) (xy 165.484811 -308.821646) (xy 165.473034 -308.773862) (xy 165.469074 -308.724808)
			(xy 165.155076 -308.724808) (xy 165.155076 -308.751182) (xy 165.146698 -308.803274) (xy 165.130154 -308.853376)
			(xy 165.105866 -308.900215) (xy 165.074448 -308.942602) (xy 165.036698 -308.979464) (xy 164.993574 -309.009863)
			(xy 164.94617 -309.03303) (xy 164.895689 -309.048375) (xy 164.869622 -309.052468) (xy 164.86505 -309.05323)
			(xy 164.854636 -309.056532) (xy 164.850318 -309.057802) (xy 164.826696 -309.068724) (xy 164.819838 -309.075836)
			(xy 164.804852 -309.091584) (xy 164.800262 -309.096688) (xy 164.793813 -309.1088) (xy 164.792152 -309.11546)
			(xy 164.790882 -309.126382) (xy 164.790882 -309.273194) (xy 164.791345 -309.282829) (xy 164.798518 -309.300718)
			(xy 164.804852 -309.307992) (xy 164.820092 -309.323994) (xy 164.82695 -309.33136) (xy 164.850318 -309.341774)
			(xy 164.854636 -309.343044) (xy 164.86505 -309.346346) (xy 164.869622 -309.347108) (xy 164.895787 -309.351199)
			(xy 164.946447 -309.366618) (xy 164.994002 -309.389916) (xy 165.037235 -309.420496) (xy 165.075041 -309.457576)
			(xy 165.106454 -309.500208) (xy 165.130669 -309.547302) (xy 165.147068 -309.597654) (xy 165.155231 -309.649976)
			(xy 165.15495 -309.70293) (xy 165.151054 -309.729124) (xy 165.149022 -309.741062) (xy 165.152578 -309.752492)
			(xy 165.154092 -309.757023) (xy 165.158567 -309.765461) (xy 165.161468 -309.769256) (xy 165.164262 -309.772304)
			(xy 165.22065 -309.831232) (xy 165.224877 -309.835467) (xy 165.234885 -309.842019) (xy 165.240462 -309.844186)
			(xy 165.251384 -309.847996) (xy 165.263322 -309.846726) (xy 165.27243 -309.845673) (xy 165.29073 -309.844531)
			(xy 165.299898 -309.84444) (xy 165.31408 -309.844626) (xy 165.34232 -309.847299) (xy 165.356286 -309.849774)
			(xy 165.368732 -309.85206) (xy 165.379908 -309.848758) (xy 165.384992 -309.847048) (xy 165.394342 -309.841794)
			(xy 165.39845 -309.838344) (xy 165.401244 -309.835804) (xy 165.460934 -309.776114) (xy 165.463474 -309.77332)
			(xy 165.466903 -309.769199) (xy 165.472146 -309.759849) (xy 165.473888 -309.754778) (xy 165.47719 -309.743602)
			(xy 165.474904 -309.731156) (xy 165.47242 -309.717191) (xy 165.469751 -309.688951) (xy 165.46957 -309.674768)
			(xy 165.470092 -309.649513) (xy 165.478405 -309.599691) (xy 165.494806 -309.551917) (xy 165.518847 -309.507494)
			(xy 165.549871 -309.467634) (xy 165.587033 -309.433424) (xy 165.629319 -309.405798) (xy 165.675575 -309.385508)
			(xy 165.72454 -309.373108) (xy 165.774878 -309.368937) (xy 165.825216 -309.373108) (xy 165.874181 -309.385508)
			(xy 165.920437 -309.405798) (xy 165.962723 -309.433424) (xy 165.999885 -309.467634) (xy 166.030909 -309.507494)
			(xy 166.05495 -309.551917) (xy 166.071351 -309.599691) (xy 166.079664 -309.649513) (xy 166.080186 -309.674768)
			(xy 166.080001 -309.688951) (xy 166.07733 -309.71719) (xy 166.074852 -309.731156) (xy 166.072566 -309.743602)
			(xy 166.075868 -309.754778) (xy 166.077577 -309.759863) (xy 166.082829 -309.769215) (xy 166.086282 -309.77332)
			(xy 166.088822 -309.776114) (xy 166.148512 -309.835804) (xy 166.151306 -309.838344) (xy 166.155428 -309.841773)
			(xy 166.164778 -309.847014) (xy 166.169848 -309.848758) (xy 166.181024 -309.85206) (xy 166.19347 -309.849774)
			(xy 166.207435 -309.847286) (xy 166.235675 -309.84461) (xy 166.249858 -309.84444) (xy 166.274675 -309.844922)
			(xy 166.323656 -309.852945) (xy 166.370694 -309.868787) (xy 166.414549 -309.89203) (xy 166.454066 -309.922061)
			(xy 166.488204 -309.95809) (xy 166.516064 -309.999168) (xy 166.536911 -310.044211) (xy 166.550196 -310.092034)
			(xy 166.55557 -310.141376) (xy 166.555117 -310.149748) (xy 166.894268 -310.149748) (xy 166.898228 -310.100694)
			(xy 166.910005 -310.05291) (xy 166.929296 -310.007634) (xy 166.955599 -309.966038) (xy 166.988234 -309.929201)
			(xy 167.026355 -309.898076) (xy 167.068976 -309.873469) (xy 167.114992 -309.856017) (xy 167.163211 -309.846173)
			(xy 167.212386 -309.844192) (xy 167.261241 -309.850124) (xy 167.308512 -309.863816) (xy 167.352974 -309.884914)
			(xy 167.393477 -309.91287) (xy 167.42897 -309.946962) (xy 167.458535 -309.986306) (xy 167.481406 -310.029883)
			(xy 167.49699 -310.076564) (xy 167.504885 -310.125141) (xy 167.50538 -310.149748) (xy 167.844228 -310.149748)
			(xy 167.848188 -310.100694) (xy 167.859965 -310.05291) (xy 167.879256 -310.007634) (xy 167.905559 -309.966038)
			(xy 167.938194 -309.929201) (xy 167.976315 -309.898076) (xy 168.018936 -309.873469) (xy 168.064952 -309.856017)
			(xy 168.113171 -309.846173) (xy 168.162346 -309.844192) (xy 168.211201 -309.850124) (xy 168.258472 -309.863816)
			(xy 168.302934 -309.884914) (xy 168.343437 -309.91287) (xy 168.37893 -309.946962) (xy 168.408495 -309.986306)
			(xy 168.431366 -310.029883) (xy 168.44695 -310.076564) (xy 168.454845 -310.125141) (xy 168.45534 -310.149748)
			(xy 168.794188 -310.149748) (xy 168.798148 -310.100694) (xy 168.809925 -310.05291) (xy 168.829216 -310.007634)
			(xy 168.855519 -309.966038) (xy 168.888154 -309.929201) (xy 168.926275 -309.898076) (xy 168.968896 -309.873469)
			(xy 169.014912 -309.856017) (xy 169.063131 -309.846173) (xy 169.112306 -309.844192) (xy 169.161161 -309.850124)
			(xy 169.208432 -309.863816) (xy 169.252894 -309.884914) (xy 169.293397 -309.91287) (xy 169.32889 -309.946962)
			(xy 169.358455 -309.986306) (xy 169.381326 -310.029883) (xy 169.39691 -310.076564) (xy 169.404805 -310.125141)
			(xy 169.4053 -310.149748) (xy 169.744148 -310.149748) (xy 169.748108 -310.100694) (xy 169.759885 -310.05291)
			(xy 169.779176 -310.007634) (xy 169.805479 -309.966038) (xy 169.838114 -309.929201) (xy 169.876235 -309.898076)
			(xy 169.918856 -309.873469) (xy 169.964872 -309.856017) (xy 170.013091 -309.846173) (xy 170.062266 -309.844192)
			(xy 170.111121 -309.850124) (xy 170.158392 -309.863816) (xy 170.202854 -309.884914) (xy 170.243357 -309.91287)
			(xy 170.27885 -309.946962) (xy 170.308415 -309.986306) (xy 170.331286 -310.029883) (xy 170.34687 -310.076564)
			(xy 170.354765 -310.125141) (xy 170.35526 -310.149748) (xy 170.694108 -310.149748) (xy 170.698068 -310.100694)
			(xy 170.709845 -310.05291) (xy 170.729136 -310.007634) (xy 170.755439 -309.966038) (xy 170.788074 -309.929201)
			(xy 170.826195 -309.898076) (xy 170.868816 -309.873469) (xy 170.914832 -309.856017) (xy 170.963051 -309.846173)
			(xy 171.012226 -309.844192) (xy 171.061081 -309.850124) (xy 171.108352 -309.863816) (xy 171.152814 -309.884914)
			(xy 171.193317 -309.91287) (xy 171.22881 -309.946962) (xy 171.258375 -309.986306) (xy 171.281246 -310.029883)
			(xy 171.29683 -310.076564) (xy 171.304725 -310.125141) (xy 171.305053 -310.141423) (xy 171.644229 -310.141423)
			(xy 171.649594 -310.092082) (xy 171.662871 -310.04426) (xy 171.683709 -309.999215) (xy 171.71156 -309.958134)
			(xy 171.74569 -309.922101) (xy 171.785199 -309.892063) (xy 171.829047 -309.868812) (xy 171.87608 -309.852961)
			(xy 171.925056 -309.844928) (xy 171.949872 -309.84444) (xy 171.964055 -309.84462) (xy 171.992295 -309.84729)
			(xy 172.00626 -309.849774) (xy 172.018706 -309.85206) (xy 172.042328 -309.844694) (xy 172.119798 -309.767224)
			(xy 172.127164 -309.743602) (xy 172.124878 -309.731156) (xy 172.122399 -309.71719) (xy 172.119729 -309.688951)
			(xy 172.119544 -309.674768) (xy 172.120066 -309.649513) (xy 172.128379 -309.599691) (xy 172.14478 -309.551917)
			(xy 172.168821 -309.507494) (xy 172.199845 -309.467634) (xy 172.237007 -309.433424) (xy 172.279293 -309.405798)
			(xy 172.325549 -309.385508) (xy 172.374514 -309.373108) (xy 172.424852 -309.368937) (xy 172.47519 -309.373108)
			(xy 172.524155 -309.385508) (xy 172.570411 -309.405798) (xy 172.612697 -309.433424) (xy 172.649859 -309.467634)
			(xy 172.680883 -309.507494) (xy 172.704924 -309.551917) (xy 172.721325 -309.599691) (xy 172.729638 -309.649513)
			(xy 172.73016 -309.674768) (xy 172.72998 -309.688951) (xy 172.72731 -309.717191) (xy 172.724826 -309.731156)
			(xy 172.72254 -309.743602) (xy 172.729906 -309.767478) (xy 172.807122 -309.844694) (xy 172.831252 -309.85206)
			(xy 172.843444 -309.849774) (xy 172.857472 -309.847286) (xy 172.88584 -309.844616) (xy 172.900086 -309.84444)
			(xy 172.924907 -309.844863) (xy 172.973897 -309.852892) (xy 173.020942 -309.86874) (xy 173.064803 -309.891991)
			(xy 173.104325 -309.922031) (xy 173.138467 -309.958069) (xy 173.166329 -309.999156) (xy 173.187176 -310.044209)
			(xy 173.200461 -310.092041) (xy 173.205832 -310.141393) (xy 173.20538 -310.149748) (xy 173.544242 -310.149748)
			(xy 173.548202 -310.100694) (xy 173.559979 -310.05291) (xy 173.57927 -310.007634) (xy 173.605573 -309.966038)
			(xy 173.638208 -309.929201) (xy 173.676329 -309.898076) (xy 173.71895 -309.873469) (xy 173.764966 -309.856017)
			(xy 173.813185 -309.846173) (xy 173.86236 -309.844192) (xy 173.911215 -309.850124) (xy 173.958486 -309.863816)
			(xy 174.002948 -309.884914) (xy 174.043451 -309.91287) (xy 174.078944 -309.946962) (xy 174.108509 -309.986306)
			(xy 174.13138 -310.029883) (xy 174.146964 -310.076564) (xy 174.154859 -310.125141) (xy 174.155354 -310.149748)
			(xy 174.494202 -310.149748) (xy 174.498162 -310.100694) (xy 174.509939 -310.05291) (xy 174.52923 -310.007634)
			(xy 174.555533 -309.966038) (xy 174.588168 -309.929201) (xy 174.626289 -309.898076) (xy 174.66891 -309.873469)
			(xy 174.714926 -309.856017) (xy 174.763145 -309.846173) (xy 174.81232 -309.844192) (xy 174.861175 -309.850124)
			(xy 174.908446 -309.863816) (xy 174.952908 -309.884914) (xy 174.993411 -309.91287) (xy 175.028904 -309.946962)
			(xy 175.058469 -309.986306) (xy 175.08134 -310.029883) (xy 175.096924 -310.076564) (xy 175.104819 -310.125141)
			(xy 175.105314 -310.149748) (xy 175.444162 -310.149748) (xy 175.448122 -310.100694) (xy 175.459899 -310.05291)
			(xy 175.47919 -310.007634) (xy 175.505493 -309.966038) (xy 175.538128 -309.929201) (xy 175.576249 -309.898076)
			(xy 175.61887 -309.873469) (xy 175.664886 -309.856017) (xy 175.713105 -309.846173) (xy 175.76228 -309.844192)
			(xy 175.811135 -309.850124) (xy 175.858406 -309.863816) (xy 175.902868 -309.884914) (xy 175.943371 -309.91287)
			(xy 175.978864 -309.946962) (xy 176.008429 -309.986306) (xy 176.0313 -310.029883) (xy 176.046884 -310.076564)
			(xy 176.054779 -310.125141) (xy 176.055274 -310.149748) (xy 176.394122 -310.149748) (xy 176.398082 -310.100694)
			(xy 176.409859 -310.05291) (xy 176.42915 -310.007634) (xy 176.455453 -309.966038) (xy 176.488088 -309.929201)
			(xy 176.526209 -309.898076) (xy 176.56883 -309.873469) (xy 176.614846 -309.856017) (xy 176.663065 -309.846173)
			(xy 176.71224 -309.844192) (xy 176.761095 -309.850124) (xy 176.808366 -309.863816) (xy 176.852828 -309.884914)
			(xy 176.893331 -309.91287) (xy 176.928824 -309.946962) (xy 176.958389 -309.986306) (xy 176.98126 -310.029883)
			(xy 176.996844 -310.076564) (xy 177.004739 -310.125141) (xy 177.005234 -310.149748) (xy 177.344082 -310.149748)
			(xy 177.348042 -310.100694) (xy 177.359819 -310.05291) (xy 177.37911 -310.007634) (xy 177.405413 -309.966038)
			(xy 177.438048 -309.929201) (xy 177.476169 -309.898076) (xy 177.51879 -309.873469) (xy 177.564806 -309.856017)
			(xy 177.613025 -309.846173) (xy 177.6622 -309.844192) (xy 177.711055 -309.850124) (xy 177.758326 -309.863816)
			(xy 177.802788 -309.884914) (xy 177.843291 -309.91287) (xy 177.878784 -309.946962) (xy 177.908349 -309.986306)
			(xy 177.93122 -310.029883) (xy 177.946804 -310.076564) (xy 177.954699 -310.125141) (xy 177.955194 -310.149748)
			(xy 178.294042 -310.149748) (xy 178.298002 -310.100694) (xy 178.309779 -310.05291) (xy 178.32907 -310.007634)
			(xy 178.355373 -309.966038) (xy 178.388008 -309.929201) (xy 178.426129 -309.898076) (xy 178.46875 -309.873469)
			(xy 178.514766 -309.856017) (xy 178.562985 -309.846173) (xy 178.61216 -309.844192) (xy 178.661015 -309.850124)
			(xy 178.708286 -309.863816) (xy 178.752748 -309.884914) (xy 178.793251 -309.91287) (xy 178.828744 -309.946962)
			(xy 178.858309 -309.986306) (xy 178.88118 -310.029883) (xy 178.896764 -310.076564) (xy 178.904659 -310.125141)
			(xy 178.905154 -310.149748) (xy 179.244256 -310.149748) (xy 179.248216 -310.100694) (xy 179.259993 -310.05291)
			(xy 179.279284 -310.007634) (xy 179.305587 -309.966038) (xy 179.338222 -309.929201) (xy 179.376343 -309.898076)
			(xy 179.418964 -309.873469) (xy 179.46498 -309.856017) (xy 179.513199 -309.846173) (xy 179.562374 -309.844192)
			(xy 179.611229 -309.850124) (xy 179.6585 -309.863816) (xy 179.702962 -309.884914) (xy 179.743465 -309.91287)
			(xy 179.778958 -309.946962) (xy 179.808523 -309.986306) (xy 179.831394 -310.029883) (xy 179.846978 -310.076564)
			(xy 179.854873 -310.125141) (xy 179.855368 -310.149748) (xy 180.194216 -310.149748) (xy 180.198176 -310.100694)
			(xy 180.209953 -310.05291) (xy 180.229244 -310.007634) (xy 180.255547 -309.966038) (xy 180.288182 -309.929201)
			(xy 180.326303 -309.898076) (xy 180.368924 -309.873469) (xy 180.41494 -309.856017) (xy 180.463159 -309.846173)
			(xy 180.512334 -309.844192) (xy 180.561189 -309.850124) (xy 180.60846 -309.863816) (xy 180.652922 -309.884914)
			(xy 180.693425 -309.91287) (xy 180.728918 -309.946962) (xy 180.758483 -309.986306) (xy 180.781354 -310.029883)
			(xy 180.796938 -310.076564) (xy 180.804833 -310.125141) (xy 180.805328 -310.149748) (xy 181.144176 -310.149748)
			(xy 181.148136 -310.100694) (xy 181.159913 -310.05291) (xy 181.179204 -310.007634) (xy 181.205507 -309.966038)
			(xy 181.238142 -309.929201) (xy 181.276263 -309.898076) (xy 181.318884 -309.873469) (xy 181.3649 -309.856017)
			(xy 181.413119 -309.846173) (xy 181.462294 -309.844192) (xy 181.511149 -309.850124) (xy 181.55842 -309.863816)
			(xy 181.602882 -309.884914) (xy 181.643385 -309.91287) (xy 181.678878 -309.946962) (xy 181.708443 -309.986306)
			(xy 181.731314 -310.029883) (xy 181.746898 -310.076564) (xy 181.754793 -310.125141) (xy 181.755288 -310.149748)
			(xy 182.094136 -310.149748) (xy 182.098096 -310.100694) (xy 182.109873 -310.05291) (xy 182.129164 -310.007634)
			(xy 182.155467 -309.966038) (xy 182.188102 -309.929201) (xy 182.226223 -309.898076) (xy 182.268844 -309.873469)
			(xy 182.31486 -309.856017) (xy 182.363079 -309.846173) (xy 182.412254 -309.844192) (xy 182.461109 -309.850124)
			(xy 182.50838 -309.863816) (xy 182.552842 -309.884914) (xy 182.593345 -309.91287) (xy 182.628838 -309.946962)
			(xy 182.658403 -309.986306) (xy 182.681274 -310.029883) (xy 182.696858 -310.076564) (xy 182.704753 -310.125141)
			(xy 182.705248 -310.149748) (xy 183.044096 -310.149748) (xy 183.048056 -310.100694) (xy 183.059833 -310.05291)
			(xy 183.079124 -310.007634) (xy 183.105427 -309.966038) (xy 183.138062 -309.929201) (xy 183.176183 -309.898076)
			(xy 183.218804 -309.873469) (xy 183.26482 -309.856017) (xy 183.313039 -309.846173) (xy 183.362214 -309.844192)
			(xy 183.411069 -309.850124) (xy 183.45834 -309.863816) (xy 183.502802 -309.884914) (xy 183.543305 -309.91287)
			(xy 183.578798 -309.946962) (xy 183.608363 -309.986306) (xy 183.631234 -310.029883) (xy 183.646818 -310.076564)
			(xy 183.654713 -310.125141) (xy 183.655208 -310.149748) (xy 183.994056 -310.149748) (xy 183.998016 -310.100694)
			(xy 184.009793 -310.05291) (xy 184.029084 -310.007634) (xy 184.055387 -309.966038) (xy 184.088022 -309.929201)
			(xy 184.126143 -309.898076) (xy 184.168764 -309.873469) (xy 184.21478 -309.856017) (xy 184.262999 -309.846173)
			(xy 184.312174 -309.844192) (xy 184.361029 -309.850124) (xy 184.4083 -309.863816) (xy 184.452762 -309.884914)
			(xy 184.493265 -309.91287) (xy 184.528758 -309.946962) (xy 184.558323 -309.986306) (xy 184.581194 -310.029883)
			(xy 184.596778 -310.076564) (xy 184.604673 -310.125141) (xy 184.605168 -310.149748) (xy 184.94427 -310.149748)
			(xy 184.94823 -310.100694) (xy 184.960007 -310.05291) (xy 184.979298 -310.007634) (xy 185.005601 -309.966038)
			(xy 185.038236 -309.929201) (xy 185.076357 -309.898076) (xy 185.118978 -309.873469) (xy 185.164994 -309.856017)
			(xy 185.213213 -309.846173) (xy 185.262388 -309.844192) (xy 185.311243 -309.850124) (xy 185.358514 -309.863816)
			(xy 185.402976 -309.884914) (xy 185.443479 -309.91287) (xy 185.478972 -309.946962) (xy 185.508537 -309.986306)
			(xy 185.531408 -310.029883) (xy 185.546992 -310.076564) (xy 185.554887 -310.125141) (xy 185.555382 -310.149748)
			(xy 185.89423 -310.149748) (xy 185.89819 -310.100694) (xy 185.909967 -310.05291) (xy 185.929258 -310.007634)
			(xy 185.955561 -309.966038) (xy 185.988196 -309.929201) (xy 186.026317 -309.898076) (xy 186.068938 -309.873469)
			(xy 186.114954 -309.856017) (xy 186.163173 -309.846173) (xy 186.212348 -309.844192) (xy 186.261203 -309.850124)
			(xy 186.308474 -309.863816) (xy 186.352936 -309.884914) (xy 186.393439 -309.91287) (xy 186.428932 -309.946962)
			(xy 186.458497 -309.986306) (xy 186.481368 -310.029883) (xy 186.496952 -310.076564) (xy 186.504847 -310.125141)
			(xy 186.505342 -310.149748) (xy 186.84419 -310.149748) (xy 186.84815 -310.100694) (xy 186.859927 -310.05291)
			(xy 186.879218 -310.007634) (xy 186.905521 -309.966038) (xy 186.938156 -309.929201) (xy 186.976277 -309.898076)
			(xy 187.018898 -309.873469) (xy 187.064914 -309.856017) (xy 187.113133 -309.846173) (xy 187.162308 -309.844192)
			(xy 187.211163 -309.850124) (xy 187.258434 -309.863816) (xy 187.302896 -309.884914) (xy 187.343399 -309.91287)
			(xy 187.378892 -309.946962) (xy 187.408457 -309.986306) (xy 187.431328 -310.029883) (xy 187.446912 -310.076564)
			(xy 187.454807 -310.125141) (xy 187.455302 -310.149748) (xy 187.79415 -310.149748) (xy 187.79811 -310.100694)
			(xy 187.809887 -310.05291) (xy 187.829178 -310.007634) (xy 187.855481 -309.966038) (xy 187.888116 -309.929201)
			(xy 187.926237 -309.898076) (xy 187.968858 -309.873469) (xy 188.014874 -309.856017) (xy 188.063093 -309.846173)
			(xy 188.112268 -309.844192) (xy 188.161123 -309.850124) (xy 188.208394 -309.863816) (xy 188.252856 -309.884914)
			(xy 188.293359 -309.91287) (xy 188.328852 -309.946962) (xy 188.358417 -309.986306) (xy 188.381288 -310.029883)
			(xy 188.396872 -310.076564) (xy 188.404767 -310.125141) (xy 188.405262 -310.149748) (xy 188.74411 -310.149748)
			(xy 188.74807 -310.100694) (xy 188.759847 -310.05291) (xy 188.779138 -310.007634) (xy 188.805441 -309.966038)
			(xy 188.838076 -309.929201) (xy 188.876197 -309.898076) (xy 188.918818 -309.873469) (xy 188.964834 -309.856017)
			(xy 189.013053 -309.846173) (xy 189.062228 -309.844192) (xy 189.111083 -309.850124) (xy 189.158354 -309.863816)
			(xy 189.202816 -309.884914) (xy 189.243319 -309.91287) (xy 189.278812 -309.946962) (xy 189.308377 -309.986306)
			(xy 189.331248 -310.029883) (xy 189.346832 -310.076564) (xy 189.354727 -310.125141) (xy 189.355222 -310.149748)
			(xy 189.69407 -310.149748) (xy 189.69803 -310.100694) (xy 189.709807 -310.05291) (xy 189.729098 -310.007634)
			(xy 189.755401 -309.966038) (xy 189.788036 -309.929201) (xy 189.826157 -309.898076) (xy 189.868778 -309.873469)
			(xy 189.914794 -309.856017) (xy 189.963013 -309.846173) (xy 190.012188 -309.844192) (xy 190.061043 -309.850124)
			(xy 190.108314 -309.863816) (xy 190.152776 -309.884914) (xy 190.193279 -309.91287) (xy 190.228772 -309.946962)
			(xy 190.258337 -309.986306) (xy 190.281208 -310.029883) (xy 190.296792 -310.076564) (xy 190.304687 -310.125141)
			(xy 190.305182 -310.149748) (xy 190.644284 -310.149748) (xy 190.648244 -310.100694) (xy 190.660021 -310.05291)
			(xy 190.679312 -310.007634) (xy 190.705615 -309.966038) (xy 190.73825 -309.929201) (xy 190.776371 -309.898076)
			(xy 190.818992 -309.873469) (xy 190.865008 -309.856017) (xy 190.913227 -309.846173) (xy 190.962402 -309.844192)
			(xy 191.011257 -309.850124) (xy 191.058528 -309.863816) (xy 191.10299 -309.884914) (xy 191.143493 -309.91287)
			(xy 191.178986 -309.946962) (xy 191.208551 -309.986306) (xy 191.231422 -310.029883) (xy 191.247006 -310.076564)
			(xy 191.254901 -310.125141) (xy 191.255396 -310.149748) (xy 191.594244 -310.149748) (xy 191.598204 -310.100694)
			(xy 191.609981 -310.05291) (xy 191.629272 -310.007634) (xy 191.655575 -309.966038) (xy 191.68821 -309.929201)
			(xy 191.726331 -309.898076) (xy 191.768952 -309.873469) (xy 191.814968 -309.856017) (xy 191.863187 -309.846173)
			(xy 191.912362 -309.844192) (xy 191.961217 -309.850124) (xy 192.008488 -309.863816) (xy 192.05295 -309.884914)
			(xy 192.093453 -309.91287) (xy 192.128946 -309.946962) (xy 192.158511 -309.986306) (xy 192.181382 -310.029883)
			(xy 192.196966 -310.076564) (xy 192.204861 -310.125141) (xy 192.205356 -310.149748) (xy 192.544204 -310.149748)
			(xy 192.548164 -310.100694) (xy 192.559941 -310.05291) (xy 192.579232 -310.007634) (xy 192.605535 -309.966038)
			(xy 192.63817 -309.929201) (xy 192.676291 -309.898076) (xy 192.718912 -309.873469) (xy 192.764928 -309.856017)
			(xy 192.813147 -309.846173) (xy 192.862322 -309.844192) (xy 192.911177 -309.850124) (xy 192.958448 -309.863816)
			(xy 193.00291 -309.884914) (xy 193.043413 -309.91287) (xy 193.078906 -309.946962) (xy 193.108471 -309.986306)
			(xy 193.131342 -310.029883) (xy 193.146926 -310.076564) (xy 193.154821 -310.125141) (xy 193.155316 -310.149748)
			(xy 193.494164 -310.149748) (xy 193.498124 -310.100694) (xy 193.509901 -310.05291) (xy 193.529192 -310.007634)
			(xy 193.555495 -309.966038) (xy 193.58813 -309.929201) (xy 193.626251 -309.898076) (xy 193.668872 -309.873469)
			(xy 193.714888 -309.856017) (xy 193.763107 -309.846173) (xy 193.812282 -309.844192) (xy 193.861137 -309.850124)
			(xy 193.908408 -309.863816) (xy 193.95287 -309.884914) (xy 193.993373 -309.91287) (xy 194.028866 -309.946962)
			(xy 194.058431 -309.986306) (xy 194.081302 -310.029883) (xy 194.096886 -310.076564) (xy 194.104781 -310.125141)
			(xy 194.105276 -310.149748) (xy 194.444124 -310.149748) (xy 194.448084 -310.100694) (xy 194.459861 -310.05291)
			(xy 194.479152 -310.007634) (xy 194.505455 -309.966038) (xy 194.53809 -309.929201) (xy 194.576211 -309.898076)
			(xy 194.618832 -309.873469) (xy 194.664848 -309.856017) (xy 194.713067 -309.846173) (xy 194.762242 -309.844192)
			(xy 194.811097 -309.850124) (xy 194.858368 -309.863816) (xy 194.90283 -309.884914) (xy 194.943333 -309.91287)
			(xy 194.978826 -309.946962) (xy 195.008391 -309.986306) (xy 195.031262 -310.029883) (xy 195.046846 -310.076564)
			(xy 195.054741 -310.125141) (xy 195.055236 -310.149748) (xy 195.394084 -310.149748) (xy 195.398044 -310.100694)
			(xy 195.409821 -310.05291) (xy 195.429112 -310.007634) (xy 195.455415 -309.966038) (xy 195.48805 -309.929201)
			(xy 195.526171 -309.898076) (xy 195.568792 -309.873469) (xy 195.614808 -309.856017) (xy 195.663027 -309.846173)
			(xy 195.712202 -309.844192) (xy 195.761057 -309.850124) (xy 195.808328 -309.863816) (xy 195.85279 -309.884914)
			(xy 195.893293 -309.91287) (xy 195.928786 -309.946962) (xy 195.958351 -309.986306) (xy 195.981222 -310.029883)
			(xy 195.996806 -310.076564) (xy 196.004701 -310.125141) (xy 196.005196 -310.149748) (xy 196.344044 -310.149748)
			(xy 196.348004 -310.100694) (xy 196.359781 -310.05291) (xy 196.379072 -310.007634) (xy 196.405375 -309.966038)
			(xy 196.43801 -309.929201) (xy 196.476131 -309.898076) (xy 196.518752 -309.873469) (xy 196.564768 -309.856017)
			(xy 196.612987 -309.846173) (xy 196.662162 -309.844192) (xy 196.711017 -309.850124) (xy 196.758288 -309.863816)
			(xy 196.80275 -309.884914) (xy 196.843253 -309.91287) (xy 196.878746 -309.946962) (xy 196.908311 -309.986306)
			(xy 196.931182 -310.029883) (xy 196.946766 -310.076564) (xy 196.954661 -310.125141) (xy 196.955156 -310.149748)
			(xy 196.954661 -310.174355) (xy 196.954482 -310.175456) (xy 197.273414 -310.175456) (xy 197.273414 -310.12404)
			(xy 197.281457 -310.073258) (xy 197.297345 -310.024359) (xy 197.320688 -309.978547) (xy 197.350909 -309.936951)
			(xy 197.387265 -309.900595) (xy 197.428861 -309.870374) (xy 197.474673 -309.847031) (xy 197.523572 -309.831143)
			(xy 197.574354 -309.8231) (xy 197.62577 -309.8231) (xy 197.676552 -309.831143) (xy 197.725451 -309.847031)
			(xy 197.771263 -309.870374) (xy 197.812859 -309.900595) (xy 197.849215 -309.936951) (xy 197.879436 -309.978547)
			(xy 197.902779 -310.024359) (xy 197.918667 -310.073258) (xy 197.92671 -310.12404) (xy 197.927214 -310.149748)
			(xy 197.92671 -310.175456) (xy 198.223374 -310.175456) (xy 198.223374 -310.12404) (xy 198.231417 -310.073258)
			(xy 198.247305 -310.024359) (xy 198.270648 -309.978547) (xy 198.300869 -309.936951) (xy 198.337225 -309.900595)
			(xy 198.378821 -309.870374) (xy 198.424633 -309.847031) (xy 198.473532 -309.831143) (xy 198.524314 -309.8231)
			(xy 198.57573 -309.8231) (xy 198.626512 -309.831143) (xy 198.675411 -309.847031) (xy 198.721223 -309.870374)
			(xy 198.762819 -309.900595) (xy 198.799175 -309.936951) (xy 198.829396 -309.978547) (xy 198.852739 -310.024359)
			(xy 198.868627 -310.073258) (xy 198.87667 -310.12404) (xy 198.877174 -310.149748) (xy 199.194432 -310.149748)
			(xy 199.198392 -310.100694) (xy 199.210169 -310.05291) (xy 199.22946 -310.007634) (xy 199.255763 -309.966038)
			(xy 199.288398 -309.929201) (xy 199.326519 -309.898076) (xy 199.36914 -309.873469) (xy 199.415156 -309.856017)
			(xy 199.463375 -309.846173) (xy 199.51255 -309.844192) (xy 199.561405 -309.850124) (xy 199.608676 -309.863816)
			(xy 199.653138 -309.884914) (xy 199.693641 -309.91287) (xy 199.729134 -309.946962) (xy 199.758699 -309.986306)
			(xy 199.78157 -310.029883) (xy 199.797154 -310.076564) (xy 199.805049 -310.125141) (xy 199.805544 -310.149748)
			(xy 199.805049 -310.174355) (xy 199.797154 -310.222932) (xy 199.78157 -310.269613) (xy 199.758699 -310.31319)
			(xy 199.729134 -310.352534) (xy 199.693641 -310.386626) (xy 199.653138 -310.414582) (xy 199.608676 -310.43568)
			(xy 199.561405 -310.449372) (xy 199.51255 -310.455304) (xy 199.463375 -310.453323) (xy 199.415156 -310.443479)
			(xy 199.36914 -310.426027) (xy 199.326519 -310.40142) (xy 199.288398 -310.370295) (xy 199.255763 -310.333458)
			(xy 199.22946 -310.291862) (xy 199.210169 -310.246586) (xy 199.198392 -310.198802) (xy 199.194432 -310.149748)
			(xy 198.877174 -310.149748) (xy 198.87667 -310.175456) (xy 198.868627 -310.226238) (xy 198.852739 -310.275137)
			(xy 198.829396 -310.320949) (xy 198.799175 -310.362545) (xy 198.762819 -310.398901) (xy 198.721223 -310.429122)
			(xy 198.675411 -310.452465) (xy 198.626512 -310.468353) (xy 198.57573 -310.476396) (xy 198.524314 -310.476396)
			(xy 198.473532 -310.468353) (xy 198.424633 -310.452465) (xy 198.378821 -310.429122) (xy 198.337225 -310.398901)
			(xy 198.300869 -310.362545) (xy 198.270648 -310.320949) (xy 198.247305 -310.275137) (xy 198.231417 -310.226238)
			(xy 198.223374 -310.175456) (xy 197.92671 -310.175456) (xy 197.918667 -310.226238) (xy 197.902779 -310.275137)
			(xy 197.879436 -310.320949) (xy 197.849215 -310.362545) (xy 197.812859 -310.398901) (xy 197.771263 -310.429122)
			(xy 197.725451 -310.452465) (xy 197.676552 -310.468353) (xy 197.62577 -310.476396) (xy 197.574354 -310.476396)
			(xy 197.523572 -310.468353) (xy 197.474673 -310.452465) (xy 197.428861 -310.429122) (xy 197.387265 -310.398901)
			(xy 197.350909 -310.362545) (xy 197.320688 -310.320949) (xy 197.297345 -310.275137) (xy 197.281457 -310.226238)
			(xy 197.273414 -310.175456) (xy 196.954482 -310.175456) (xy 196.946766 -310.222932) (xy 196.931182 -310.269613)
			(xy 196.908311 -310.31319) (xy 196.878746 -310.352534) (xy 196.843253 -310.386626) (xy 196.80275 -310.414582)
			(xy 196.758288 -310.43568) (xy 196.711017 -310.449372) (xy 196.662162 -310.455304) (xy 196.612987 -310.453323)
			(xy 196.564768 -310.443479) (xy 196.518752 -310.426027) (xy 196.476131 -310.40142) (xy 196.43801 -310.370295)
			(xy 196.405375 -310.333458) (xy 196.379072 -310.291862) (xy 196.359781 -310.246586) (xy 196.348004 -310.198802)
			(xy 196.344044 -310.149748) (xy 196.005196 -310.149748) (xy 196.004701 -310.174355) (xy 195.996806 -310.222932)
			(xy 195.981222 -310.269613) (xy 195.958351 -310.31319) (xy 195.928786 -310.352534) (xy 195.893293 -310.386626)
			(xy 195.85279 -310.414582) (xy 195.808328 -310.43568) (xy 195.761057 -310.449372) (xy 195.712202 -310.455304)
			(xy 195.663027 -310.453323) (xy 195.614808 -310.443479) (xy 195.568792 -310.426027) (xy 195.526171 -310.40142)
			(xy 195.48805 -310.370295) (xy 195.455415 -310.333458) (xy 195.429112 -310.291862) (xy 195.409821 -310.246586)
			(xy 195.398044 -310.198802) (xy 195.394084 -310.149748) (xy 195.055236 -310.149748) (xy 195.054741 -310.174355)
			(xy 195.046846 -310.222932) (xy 195.031262 -310.269613) (xy 195.008391 -310.31319) (xy 194.978826 -310.352534)
			(xy 194.943333 -310.386626) (xy 194.90283 -310.414582) (xy 194.858368 -310.43568) (xy 194.811097 -310.449372)
			(xy 194.762242 -310.455304) (xy 194.713067 -310.453323) (xy 194.664848 -310.443479) (xy 194.618832 -310.426027)
			(xy 194.576211 -310.40142) (xy 194.53809 -310.370295) (xy 194.505455 -310.333458) (xy 194.479152 -310.291862)
			(xy 194.459861 -310.246586) (xy 194.448084 -310.198802) (xy 194.444124 -310.149748) (xy 194.105276 -310.149748)
			(xy 194.104781 -310.174355) (xy 194.096886 -310.222932) (xy 194.081302 -310.269613) (xy 194.058431 -310.31319)
			(xy 194.028866 -310.352534) (xy 193.993373 -310.386626) (xy 193.95287 -310.414582) (xy 193.908408 -310.43568)
			(xy 193.861137 -310.449372) (xy 193.812282 -310.455304) (xy 193.763107 -310.453323) (xy 193.714888 -310.443479)
			(xy 193.668872 -310.426027) (xy 193.626251 -310.40142) (xy 193.58813 -310.370295) (xy 193.555495 -310.333458)
			(xy 193.529192 -310.291862) (xy 193.509901 -310.246586) (xy 193.498124 -310.198802) (xy 193.494164 -310.149748)
			(xy 193.155316 -310.149748) (xy 193.154821 -310.174355) (xy 193.146926 -310.222932) (xy 193.131342 -310.269613)
			(xy 193.108471 -310.31319) (xy 193.078906 -310.352534) (xy 193.043413 -310.386626) (xy 193.00291 -310.414582)
			(xy 192.958448 -310.43568) (xy 192.911177 -310.449372) (xy 192.862322 -310.455304) (xy 192.813147 -310.453323)
			(xy 192.764928 -310.443479) (xy 192.718912 -310.426027) (xy 192.676291 -310.40142) (xy 192.63817 -310.370295)
			(xy 192.605535 -310.333458) (xy 192.579232 -310.291862) (xy 192.559941 -310.246586) (xy 192.548164 -310.198802)
			(xy 192.544204 -310.149748) (xy 192.205356 -310.149748) (xy 192.204861 -310.174355) (xy 192.196966 -310.222932)
			(xy 192.181382 -310.269613) (xy 192.158511 -310.31319) (xy 192.128946 -310.352534) (xy 192.093453 -310.386626)
			(xy 192.05295 -310.414582) (xy 192.008488 -310.43568) (xy 191.961217 -310.449372) (xy 191.912362 -310.455304)
			(xy 191.863187 -310.453323) (xy 191.814968 -310.443479) (xy 191.768952 -310.426027) (xy 191.726331 -310.40142)
			(xy 191.68821 -310.370295) (xy 191.655575 -310.333458) (xy 191.629272 -310.291862) (xy 191.609981 -310.246586)
			(xy 191.598204 -310.198802) (xy 191.594244 -310.149748) (xy 191.255396 -310.149748) (xy 191.254901 -310.174355)
			(xy 191.247006 -310.222932) (xy 191.231422 -310.269613) (xy 191.208551 -310.31319) (xy 191.178986 -310.352534)
			(xy 191.143493 -310.386626) (xy 191.10299 -310.414582) (xy 191.058528 -310.43568) (xy 191.011257 -310.449372)
			(xy 190.962402 -310.455304) (xy 190.913227 -310.453323) (xy 190.865008 -310.443479) (xy 190.818992 -310.426027)
			(xy 190.776371 -310.40142) (xy 190.73825 -310.370295) (xy 190.705615 -310.333458) (xy 190.679312 -310.291862)
			(xy 190.660021 -310.246586) (xy 190.648244 -310.198802) (xy 190.644284 -310.149748) (xy 190.305182 -310.149748)
			(xy 190.304687 -310.174355) (xy 190.296792 -310.222932) (xy 190.281208 -310.269613) (xy 190.258337 -310.31319)
			(xy 190.228772 -310.352534) (xy 190.193279 -310.386626) (xy 190.152776 -310.414582) (xy 190.108314 -310.43568)
			(xy 190.061043 -310.449372) (xy 190.012188 -310.455304) (xy 189.963013 -310.453323) (xy 189.914794 -310.443479)
			(xy 189.868778 -310.426027) (xy 189.826157 -310.40142) (xy 189.788036 -310.370295) (xy 189.755401 -310.333458)
			(xy 189.729098 -310.291862) (xy 189.709807 -310.246586) (xy 189.69803 -310.198802) (xy 189.69407 -310.149748)
			(xy 189.355222 -310.149748) (xy 189.354727 -310.174355) (xy 189.346832 -310.222932) (xy 189.331248 -310.269613)
			(xy 189.308377 -310.31319) (xy 189.278812 -310.352534) (xy 189.243319 -310.386626) (xy 189.202816 -310.414582)
			(xy 189.158354 -310.43568) (xy 189.111083 -310.449372) (xy 189.062228 -310.455304) (xy 189.013053 -310.453323)
			(xy 188.964834 -310.443479) (xy 188.918818 -310.426027) (xy 188.876197 -310.40142) (xy 188.838076 -310.370295)
			(xy 188.805441 -310.333458) (xy 188.779138 -310.291862) (xy 188.759847 -310.246586) (xy 188.74807 -310.198802)
			(xy 188.74411 -310.149748) (xy 188.405262 -310.149748) (xy 188.404767 -310.174355) (xy 188.396872 -310.222932)
			(xy 188.381288 -310.269613) (xy 188.358417 -310.31319) (xy 188.328852 -310.352534) (xy 188.293359 -310.386626)
			(xy 188.252856 -310.414582) (xy 188.208394 -310.43568) (xy 188.161123 -310.449372) (xy 188.112268 -310.455304)
			(xy 188.063093 -310.453323) (xy 188.014874 -310.443479) (xy 187.968858 -310.426027) (xy 187.926237 -310.40142)
			(xy 187.888116 -310.370295) (xy 187.855481 -310.333458) (xy 187.829178 -310.291862) (xy 187.809887 -310.246586)
			(xy 187.79811 -310.198802) (xy 187.79415 -310.149748) (xy 187.455302 -310.149748) (xy 187.454807 -310.174355)
			(xy 187.446912 -310.222932) (xy 187.431328 -310.269613) (xy 187.408457 -310.31319) (xy 187.378892 -310.352534)
			(xy 187.343399 -310.386626) (xy 187.302896 -310.414582) (xy 187.258434 -310.43568) (xy 187.211163 -310.449372)
			(xy 187.162308 -310.455304) (xy 187.113133 -310.453323) (xy 187.064914 -310.443479) (xy 187.018898 -310.426027)
			(xy 186.976277 -310.40142) (xy 186.938156 -310.370295) (xy 186.905521 -310.333458) (xy 186.879218 -310.291862)
			(xy 186.859927 -310.246586) (xy 186.84815 -310.198802) (xy 186.84419 -310.149748) (xy 186.505342 -310.149748)
			(xy 186.504847 -310.174355) (xy 186.496952 -310.222932) (xy 186.481368 -310.269613) (xy 186.458497 -310.31319)
			(xy 186.428932 -310.352534) (xy 186.393439 -310.386626) (xy 186.352936 -310.414582) (xy 186.308474 -310.43568)
			(xy 186.261203 -310.449372) (xy 186.212348 -310.455304) (xy 186.163173 -310.453323) (xy 186.114954 -310.443479)
			(xy 186.068938 -310.426027) (xy 186.026317 -310.40142) (xy 185.988196 -310.370295) (xy 185.955561 -310.333458)
			(xy 185.929258 -310.291862) (xy 185.909967 -310.246586) (xy 185.89819 -310.198802) (xy 185.89423 -310.149748)
			(xy 185.555382 -310.149748) (xy 185.554887 -310.174355) (xy 185.546992 -310.222932) (xy 185.531408 -310.269613)
			(xy 185.508537 -310.31319) (xy 185.478972 -310.352534) (xy 185.443479 -310.386626) (xy 185.402976 -310.414582)
			(xy 185.358514 -310.43568) (xy 185.311243 -310.449372) (xy 185.262388 -310.455304) (xy 185.213213 -310.453323)
			(xy 185.164994 -310.443479) (xy 185.118978 -310.426027) (xy 185.076357 -310.40142) (xy 185.038236 -310.370295)
			(xy 185.005601 -310.333458) (xy 184.979298 -310.291862) (xy 184.960007 -310.246586) (xy 184.94823 -310.198802)
			(xy 184.94427 -310.149748) (xy 184.605168 -310.149748) (xy 184.604673 -310.174355) (xy 184.596778 -310.222932)
			(xy 184.581194 -310.269613) (xy 184.558323 -310.31319) (xy 184.528758 -310.352534) (xy 184.493265 -310.386626)
			(xy 184.452762 -310.414582) (xy 184.4083 -310.43568) (xy 184.361029 -310.449372) (xy 184.312174 -310.455304)
			(xy 184.262999 -310.453323) (xy 184.21478 -310.443479) (xy 184.168764 -310.426027) (xy 184.126143 -310.40142)
			(xy 184.088022 -310.370295) (xy 184.055387 -310.333458) (xy 184.029084 -310.291862) (xy 184.009793 -310.246586)
			(xy 183.998016 -310.198802) (xy 183.994056 -310.149748) (xy 183.655208 -310.149748) (xy 183.654713 -310.174355)
			(xy 183.646818 -310.222932) (xy 183.631234 -310.269613) (xy 183.608363 -310.31319) (xy 183.578798 -310.352534)
			(xy 183.543305 -310.386626) (xy 183.502802 -310.414582) (xy 183.45834 -310.43568) (xy 183.411069 -310.449372)
			(xy 183.362214 -310.455304) (xy 183.313039 -310.453323) (xy 183.26482 -310.443479) (xy 183.218804 -310.426027)
			(xy 183.176183 -310.40142) (xy 183.138062 -310.370295) (xy 183.105427 -310.333458) (xy 183.079124 -310.291862)
			(xy 183.059833 -310.246586) (xy 183.048056 -310.198802) (xy 183.044096 -310.149748) (xy 182.705248 -310.149748)
			(xy 182.704753 -310.174355) (xy 182.696858 -310.222932) (xy 182.681274 -310.269613) (xy 182.658403 -310.31319)
			(xy 182.628838 -310.352534) (xy 182.593345 -310.386626) (xy 182.552842 -310.414582) (xy 182.50838 -310.43568)
			(xy 182.461109 -310.449372) (xy 182.412254 -310.455304) (xy 182.363079 -310.453323) (xy 182.31486 -310.443479)
			(xy 182.268844 -310.426027) (xy 182.226223 -310.40142) (xy 182.188102 -310.370295) (xy 182.155467 -310.333458)
			(xy 182.129164 -310.291862) (xy 182.109873 -310.246586) (xy 182.098096 -310.198802) (xy 182.094136 -310.149748)
			(xy 181.755288 -310.149748) (xy 181.754793 -310.174355) (xy 181.746898 -310.222932) (xy 181.731314 -310.269613)
			(xy 181.708443 -310.31319) (xy 181.678878 -310.352534) (xy 181.643385 -310.386626) (xy 181.602882 -310.414582)
			(xy 181.55842 -310.43568) (xy 181.511149 -310.449372) (xy 181.462294 -310.455304) (xy 181.413119 -310.453323)
			(xy 181.3649 -310.443479) (xy 181.318884 -310.426027) (xy 181.276263 -310.40142) (xy 181.238142 -310.370295)
			(xy 181.205507 -310.333458) (xy 181.179204 -310.291862) (xy 181.159913 -310.246586) (xy 181.148136 -310.198802)
			(xy 181.144176 -310.149748) (xy 180.805328 -310.149748) (xy 180.804833 -310.174355) (xy 180.796938 -310.222932)
			(xy 180.781354 -310.269613) (xy 180.758483 -310.31319) (xy 180.728918 -310.352534) (xy 180.693425 -310.386626)
			(xy 180.652922 -310.414582) (xy 180.60846 -310.43568) (xy 180.561189 -310.449372) (xy 180.512334 -310.455304)
			(xy 180.463159 -310.453323) (xy 180.41494 -310.443479) (xy 180.368924 -310.426027) (xy 180.326303 -310.40142)
			(xy 180.288182 -310.370295) (xy 180.255547 -310.333458) (xy 180.229244 -310.291862) (xy 180.209953 -310.246586)
			(xy 180.198176 -310.198802) (xy 180.194216 -310.149748) (xy 179.855368 -310.149748) (xy 179.854873 -310.174355)
			(xy 179.846978 -310.222932) (xy 179.831394 -310.269613) (xy 179.808523 -310.31319) (xy 179.778958 -310.352534)
			(xy 179.743465 -310.386626) (xy 179.702962 -310.414582) (xy 179.6585 -310.43568) (xy 179.611229 -310.449372)
			(xy 179.562374 -310.455304) (xy 179.513199 -310.453323) (xy 179.46498 -310.443479) (xy 179.418964 -310.426027)
			(xy 179.376343 -310.40142) (xy 179.338222 -310.370295) (xy 179.305587 -310.333458) (xy 179.279284 -310.291862)
			(xy 179.259993 -310.246586) (xy 179.248216 -310.198802) (xy 179.244256 -310.149748) (xy 178.905154 -310.149748)
			(xy 178.904659 -310.174355) (xy 178.896764 -310.222932) (xy 178.88118 -310.269613) (xy 178.858309 -310.31319)
			(xy 178.828744 -310.352534) (xy 178.793251 -310.386626) (xy 178.752748 -310.414582) (xy 178.708286 -310.43568)
			(xy 178.661015 -310.449372) (xy 178.61216 -310.455304) (xy 178.562985 -310.453323) (xy 178.514766 -310.443479)
			(xy 178.46875 -310.426027) (xy 178.426129 -310.40142) (xy 178.388008 -310.370295) (xy 178.355373 -310.333458)
			(xy 178.32907 -310.291862) (xy 178.309779 -310.246586) (xy 178.298002 -310.198802) (xy 178.294042 -310.149748)
			(xy 177.955194 -310.149748) (xy 177.954699 -310.174355) (xy 177.946804 -310.222932) (xy 177.93122 -310.269613)
			(xy 177.908349 -310.31319) (xy 177.878784 -310.352534) (xy 177.843291 -310.386626) (xy 177.802788 -310.414582)
			(xy 177.758326 -310.43568) (xy 177.711055 -310.449372) (xy 177.6622 -310.455304) (xy 177.613025 -310.453323)
			(xy 177.564806 -310.443479) (xy 177.51879 -310.426027) (xy 177.476169 -310.40142) (xy 177.438048 -310.370295)
			(xy 177.405413 -310.333458) (xy 177.37911 -310.291862) (xy 177.359819 -310.246586) (xy 177.348042 -310.198802)
			(xy 177.344082 -310.149748) (xy 177.005234 -310.149748) (xy 177.004739 -310.174355) (xy 176.996844 -310.222932)
			(xy 176.98126 -310.269613) (xy 176.958389 -310.31319) (xy 176.928824 -310.352534) (xy 176.893331 -310.386626)
			(xy 176.852828 -310.414582) (xy 176.808366 -310.43568) (xy 176.761095 -310.449372) (xy 176.71224 -310.455304)
			(xy 176.663065 -310.453323) (xy 176.614846 -310.443479) (xy 176.56883 -310.426027) (xy 176.526209 -310.40142)
			(xy 176.488088 -310.370295) (xy 176.455453 -310.333458) (xy 176.42915 -310.291862) (xy 176.409859 -310.246586)
			(xy 176.398082 -310.198802) (xy 176.394122 -310.149748) (xy 176.055274 -310.149748) (xy 176.054779 -310.174355)
			(xy 176.046884 -310.222932) (xy 176.0313 -310.269613) (xy 176.008429 -310.31319) (xy 175.978864 -310.352534)
			(xy 175.943371 -310.386626) (xy 175.902868 -310.414582) (xy 175.858406 -310.43568) (xy 175.811135 -310.449372)
			(xy 175.76228 -310.455304) (xy 175.713105 -310.453323) (xy 175.664886 -310.443479) (xy 175.61887 -310.426027)
			(xy 175.576249 -310.40142) (xy 175.538128 -310.370295) (xy 175.505493 -310.333458) (xy 175.47919 -310.291862)
			(xy 175.459899 -310.246586) (xy 175.448122 -310.198802) (xy 175.444162 -310.149748) (xy 175.105314 -310.149748)
			(xy 175.104819 -310.174355) (xy 175.096924 -310.222932) (xy 175.08134 -310.269613) (xy 175.058469 -310.31319)
			(xy 175.028904 -310.352534) (xy 174.993411 -310.386626) (xy 174.952908 -310.414582) (xy 174.908446 -310.43568)
			(xy 174.861175 -310.449372) (xy 174.81232 -310.455304) (xy 174.763145 -310.453323) (xy 174.714926 -310.443479)
			(xy 174.66891 -310.426027) (xy 174.626289 -310.40142) (xy 174.588168 -310.370295) (xy 174.555533 -310.333458)
			(xy 174.52923 -310.291862) (xy 174.509939 -310.246586) (xy 174.498162 -310.198802) (xy 174.494202 -310.149748)
			(xy 174.155354 -310.149748) (xy 174.154859 -310.174355) (xy 174.146964 -310.222932) (xy 174.13138 -310.269613)
			(xy 174.108509 -310.31319) (xy 174.078944 -310.352534) (xy 174.043451 -310.386626) (xy 174.002948 -310.414582)
			(xy 173.958486 -310.43568) (xy 173.911215 -310.449372) (xy 173.86236 -310.455304) (xy 173.813185 -310.453323)
			(xy 173.764966 -310.443479) (xy 173.71895 -310.426027) (xy 173.676329 -310.40142) (xy 173.638208 -310.370295)
			(xy 173.605573 -310.333458) (xy 173.57927 -310.291862) (xy 173.559979 -310.246586) (xy 173.548202 -310.198802)
			(xy 173.544242 -310.149748) (xy 173.20538 -310.149748) (xy 173.203149 -310.190963) (xy 173.192481 -310.239446)
			(xy 173.174111 -310.285565) (xy 173.148521 -310.328104) (xy 173.116387 -310.365943) (xy 173.078554 -310.398085)
			(xy 173.03602 -310.423683) (xy 172.989905 -310.442063) (xy 172.941425 -310.45274) (xy 172.891855 -310.455434)
			(xy 172.842502 -310.450073) (xy 172.794667 -310.436798) (xy 172.74961 -310.415959) (xy 172.708517 -310.388106)
			(xy 172.672472 -310.353971) (xy 172.642424 -310.314455) (xy 172.619165 -310.270599) (xy 172.603307 -310.223557)
			(xy 172.595268 -310.174569) (xy 172.594778 -310.149748) (xy 172.594962 -310.135565) (xy 172.597629 -310.107325)
			(xy 172.600112 -310.09336) (xy 172.602398 -310.080914) (xy 172.595032 -310.057038) (xy 172.517816 -309.979822)
			(xy 172.493686 -309.972456) (xy 172.481494 -309.974742) (xy 172.467465 -309.977225) (xy 172.439098 -309.979898)
			(xy 172.424852 -309.980076) (xy 172.410669 -309.979893) (xy 172.382429 -309.977225) (xy 172.368464 -309.974742)
			(xy 172.356018 -309.972456) (xy 172.332396 -309.979822) (xy 172.254926 -310.057292) (xy 172.24756 -310.080914)
			(xy 172.249846 -310.09336) (xy 172.252326 -310.107325) (xy 172.254996 -310.135565) (xy 172.25518 -310.149748)
			(xy 172.25467 -310.174564) (xy 172.246634 -310.22354) (xy 172.23078 -310.270571) (xy 172.207526 -310.314418)
			(xy 172.177486 -310.353925) (xy 172.14145 -310.388052) (xy 172.100368 -310.415901) (xy 172.055321 -310.436736)
			(xy 172.007498 -310.450009) (xy 171.958157 -310.455371) (xy 171.908599 -310.452681) (xy 171.860129 -310.442009)
			(xy 171.814023 -310.423636) (xy 171.771498 -310.398046) (xy 171.733672 -310.365914) (xy 171.701542 -310.328086)
			(xy 171.675955 -310.285559) (xy 171.657585 -310.239452) (xy 171.646916 -310.190981) (xy 171.644229 -310.141423)
			(xy 171.305053 -310.141423) (xy 171.30522 -310.149748) (xy 171.304725 -310.174355) (xy 171.29683 -310.222932)
			(xy 171.281246 -310.269613) (xy 171.258375 -310.31319) (xy 171.22881 -310.352534) (xy 171.193317 -310.386626)
			(xy 171.152814 -310.414582) (xy 171.108352 -310.43568) (xy 171.061081 -310.449372) (xy 171.012226 -310.455304)
			(xy 170.963051 -310.453323) (xy 170.914832 -310.443479) (xy 170.868816 -310.426027) (xy 170.826195 -310.40142)
			(xy 170.788074 -310.370295) (xy 170.755439 -310.333458) (xy 170.729136 -310.291862) (xy 170.709845 -310.246586)
			(xy 170.698068 -310.198802) (xy 170.694108 -310.149748) (xy 170.35526 -310.149748) (xy 170.354765 -310.174355)
			(xy 170.34687 -310.222932) (xy 170.331286 -310.269613) (xy 170.308415 -310.31319) (xy 170.27885 -310.352534)
			(xy 170.243357 -310.386626) (xy 170.202854 -310.414582) (xy 170.158392 -310.43568) (xy 170.111121 -310.449372)
			(xy 170.062266 -310.455304) (xy 170.013091 -310.453323) (xy 169.964872 -310.443479) (xy 169.918856 -310.426027)
			(xy 169.876235 -310.40142) (xy 169.838114 -310.370295) (xy 169.805479 -310.333458) (xy 169.779176 -310.291862)
			(xy 169.759885 -310.246586) (xy 169.748108 -310.198802) (xy 169.744148 -310.149748) (xy 169.4053 -310.149748)
			(xy 169.404805 -310.174355) (xy 169.39691 -310.222932) (xy 169.381326 -310.269613) (xy 169.358455 -310.31319)
			(xy 169.32889 -310.352534) (xy 169.293397 -310.386626) (xy 169.252894 -310.414582) (xy 169.208432 -310.43568)
			(xy 169.161161 -310.449372) (xy 169.112306 -310.455304) (xy 169.063131 -310.453323) (xy 169.014912 -310.443479)
			(xy 168.968896 -310.426027) (xy 168.926275 -310.40142) (xy 168.888154 -310.370295) (xy 168.855519 -310.333458)
			(xy 168.829216 -310.291862) (xy 168.809925 -310.246586) (xy 168.798148 -310.198802) (xy 168.794188 -310.149748)
			(xy 168.45534 -310.149748) (xy 168.454845 -310.174355) (xy 168.44695 -310.222932) (xy 168.431366 -310.269613)
			(xy 168.408495 -310.31319) (xy 168.37893 -310.352534) (xy 168.343437 -310.386626) (xy 168.302934 -310.414582)
			(xy 168.258472 -310.43568) (xy 168.211201 -310.449372) (xy 168.162346 -310.455304) (xy 168.113171 -310.453323)
			(xy 168.064952 -310.443479) (xy 168.018936 -310.426027) (xy 167.976315 -310.40142) (xy 167.938194 -310.370295)
			(xy 167.905559 -310.333458) (xy 167.879256 -310.291862) (xy 167.859965 -310.246586) (xy 167.848188 -310.198802)
			(xy 167.844228 -310.149748) (xy 167.50538 -310.149748) (xy 167.504885 -310.174355) (xy 167.49699 -310.222932)
			(xy 167.481406 -310.269613) (xy 167.458535 -310.31319) (xy 167.42897 -310.352534) (xy 167.393477 -310.386626)
			(xy 167.352974 -310.414582) (xy 167.308512 -310.43568) (xy 167.261241 -310.449372) (xy 167.212386 -310.455304)
			(xy 167.163211 -310.453323) (xy 167.114992 -310.443479) (xy 167.068976 -310.426027) (xy 167.026355 -310.40142)
			(xy 166.988234 -310.370295) (xy 166.955599 -310.333458) (xy 166.929296 -310.291862) (xy 166.910005 -310.246586)
			(xy 166.898228 -310.198802) (xy 166.894268 -310.149748) (xy 166.555117 -310.149748) (xy 166.55289 -310.190937)
			(xy 166.542227 -310.239412) (xy 166.523862 -310.285523) (xy 166.49828 -310.328056) (xy 166.466153 -310.365889)
			(xy 166.428329 -310.398027) (xy 166.385804 -310.423622) (xy 166.339698 -310.442001) (xy 166.291226 -310.452678)
			(xy 166.241666 -310.455372) (xy 166.192322 -310.450013) (xy 166.144496 -310.436742) (xy 166.099446 -310.415908)
			(xy 166.05836 -310.388061) (xy 166.022321 -310.353933) (xy 165.992278 -310.314425) (xy 165.969023 -310.270576)
			(xy 165.953167 -310.223543) (xy 165.94513 -310.174565) (xy 165.94455 -310.149748) (xy 165.944734 -310.135565)
			(xy 165.947403 -310.107325) (xy 165.949884 -310.09336) (xy 165.95217 -310.080914) (xy 165.948868 -310.069738)
			(xy 165.947158 -310.064653) (xy 165.941904 -310.055304) (xy 165.938454 -310.051196) (xy 165.935914 -310.048402)
			(xy 165.876224 -309.988712) (xy 165.87343 -309.986172) (xy 165.86931 -309.98274) (xy 165.859963 -309.977491)
			(xy 165.854888 -309.975758) (xy 165.843712 -309.972456) (xy 165.831266 -309.974742) (xy 165.817301 -309.977226)
			(xy 165.789061 -309.979897) (xy 165.774878 -309.980076) (xy 165.760696 -309.979888) (xy 165.732457 -309.977213)
			(xy 165.71849 -309.974742) (xy 165.706044 -309.972456) (xy 165.694868 -309.975758) (xy 165.68978 -309.977463)
			(xy 165.680422 -309.982707) (xy 165.676326 -309.986172) (xy 165.673532 -309.988712) (xy 165.613842 -310.048402)
			(xy 165.611302 -310.051196) (xy 165.60787 -310.055316) (xy 165.602622 -310.064664) (xy 165.600888 -310.069738)
			(xy 165.597586 -310.080914) (xy 165.599872 -310.09336) (xy 165.602355 -310.107325) (xy 165.605023 -310.135565)
			(xy 165.605206 -310.149748) (xy 165.604732 -310.173737) (xy 165.59722 -310.221122) (xy 165.582388 -310.26675)
			(xy 165.560602 -310.309496) (xy 165.532398 -310.348308) (xy 165.49847 -310.38223) (xy 165.459653 -310.410428)
			(xy 165.416904 -310.432207) (xy 165.371274 -310.447031) (xy 165.323887 -310.454536) (xy 165.299898 -310.455056)
			(xy 165.29073 -310.454963) (xy 165.27243 -310.45382) (xy 165.263322 -310.45277) (xy 165.25113 -310.4515)
			(xy 165.240462 -310.45531) (xy 165.236802 -310.456686) (xy 165.229912 -310.460382) (xy 165.226746 -310.462676)
			(xy 165.22065 -310.468264) (xy 165.164262 -310.526938) (xy 165.161712 -310.52962) (xy 165.157371 -310.535613)
			(xy 165.155626 -310.538876) (xy 165.152324 -310.547258) (xy 165.148768 -310.558434) (xy 165.1508 -310.570372)
			(xy 165.152929 -310.58386) (xy 165.155215 -310.611074) (xy 165.155372 -310.624728) (xy 165.155372 -310.68518)
			(xy 205.94269 -310.68518) (xy 205.946761 -310.629558) (xy 205.958887 -310.575121) (xy 205.97881 -310.52303)
			(xy 206.006106 -310.474395) (xy 206.040192 -310.430252) (xy 206.080341 -310.391543) (xy 206.125699 -310.359092)
			(xy 206.175299 -310.333591) (xy 206.228083 -310.315584) (xy 206.282926 -310.305454) (xy 206.33866 -310.303417)
			(xy 206.394097 -310.309517) (xy 206.448054 -310.323623) (xy 206.499383 -310.345435) (xy 206.546989 -310.374489)
			(xy 206.589857 -310.410164) (xy 206.627074 -310.451701) (xy 206.657847 -310.498214) (xy 206.681519 -310.548711)
			(xy 206.697587 -310.602118) (xy 206.705707 -310.657294) (xy 206.706216 -310.68518) (xy 206.705707 -310.713066)
			(xy 206.697587 -310.768242) (xy 206.681519 -310.821649) (xy 206.657847 -310.872146) (xy 206.627074 -310.918659)
			(xy 206.589857 -310.960196) (xy 206.546989 -310.995871) (xy 206.499383 -311.024925) (xy 206.448054 -311.046737)
			(xy 206.394097 -311.060843) (xy 206.33866 -311.066943) (xy 206.282926 -311.064906) (xy 206.228083 -311.054776)
			(xy 206.175299 -311.036769) (xy 206.125699 -311.011268) (xy 206.080341 -310.978817) (xy 206.040192 -310.940108)
			(xy 206.006106 -310.895965) (xy 205.97881 -310.84733) (xy 205.958887 -310.795239) (xy 205.946761 -310.740802)
			(xy 205.94269 -310.68518) (xy 165.155372 -310.68518) (xy 165.155372 -310.69534) (xy 165.155626 -310.699658)
			(xy 165.155626 -310.700166) (xy 165.156651 -310.708044) (xy 165.162868 -310.722653) (xy 165.167818 -310.728868)
			(xy 165.172136 -310.733186) (xy 165.228524 -310.783732) (xy 165.232528 -310.787126) (xy 165.241617 -310.792375)
			(xy 165.246558 -310.794146) (xy 165.256718 -310.797448) (xy 165.26764 -310.796432) (xy 165.299898 -310.794654)
			(xy 165.325159 -310.795147) (xy 165.374992 -310.803462) (xy 165.422776 -310.819866) (xy 165.467209 -310.843912)
			(xy 165.507078 -310.874943) (xy 165.541296 -310.912113) (xy 165.568929 -310.954408) (xy 165.589223 -311.000675)
			(xy 165.601626 -311.049651) (xy 165.605795 -311.099962) (xy 165.944054 -311.099962) (xy 165.948014 -311.050908)
			(xy 165.959791 -311.003124) (xy 165.979082 -310.957848) (xy 166.005385 -310.916252) (xy 166.03802 -310.879415)
			(xy 166.076141 -310.84829) (xy 166.118762 -310.823683) (xy 166.164778 -310.806231) (xy 166.212997 -310.796387)
			(xy 166.262172 -310.794406) (xy 166.311027 -310.800338) (xy 166.358298 -310.81403) (xy 166.40276 -310.835128)
			(xy 166.443263 -310.863084) (xy 166.478756 -310.897176) (xy 166.508321 -310.93652) (xy 166.531192 -310.980097)
			(xy 166.546776 -311.026778) (xy 166.554671 -311.075355) (xy 166.555166 -311.099962) (xy 166.554671 -311.124569)
			(xy 166.554492 -311.12567) (xy 166.873424 -311.12567) (xy 166.873424 -311.074254) (xy 166.881467 -311.023472)
			(xy 166.897355 -310.974573) (xy 166.920698 -310.928761) (xy 166.950919 -310.887165) (xy 166.987275 -310.850809)
			(xy 167.028871 -310.820588) (xy 167.074683 -310.797245) (xy 167.123582 -310.781357) (xy 167.174364 -310.773314)
			(xy 167.22578 -310.773314) (xy 167.276562 -310.781357) (xy 167.325461 -310.797245) (xy 167.371273 -310.820588)
			(xy 167.412869 -310.850809) (xy 167.449225 -310.887165) (xy 167.479446 -310.928761) (xy 167.502789 -310.974573)
			(xy 167.518677 -311.023472) (xy 167.52672 -311.074254) (xy 167.527224 -311.099962) (xy 167.844228 -311.099962)
			(xy 167.848188 -311.050908) (xy 167.859965 -311.003124) (xy 167.879256 -310.957848) (xy 167.905559 -310.916252)
			(xy 167.938194 -310.879415) (xy 167.976315 -310.84829) (xy 168.018936 -310.823683) (xy 168.064952 -310.806231)
			(xy 168.113171 -310.796387) (xy 168.162346 -310.794406) (xy 168.211201 -310.800338) (xy 168.258472 -310.81403)
			(xy 168.302934 -310.835128) (xy 168.343437 -310.863084) (xy 168.37893 -310.897176) (xy 168.408495 -310.93652)
			(xy 168.431366 -310.980097) (xy 168.44695 -311.026778) (xy 168.454845 -311.075355) (xy 168.45534 -311.099962)
			(xy 168.454845 -311.124569) (xy 168.454666 -311.12567) (xy 168.773344 -311.12567) (xy 168.773344 -311.074254)
			(xy 168.781387 -311.023472) (xy 168.797275 -310.974573) (xy 168.820618 -310.928761) (xy 168.850839 -310.887165)
			(xy 168.887195 -310.850809) (xy 168.928791 -310.820588) (xy 168.974603 -310.797245) (xy 169.023502 -310.781357)
			(xy 169.074284 -310.773314) (xy 169.1257 -310.773314) (xy 169.176482 -310.781357) (xy 169.225381 -310.797245)
			(xy 169.271193 -310.820588) (xy 169.312789 -310.850809) (xy 169.349145 -310.887165) (xy 169.379366 -310.928761)
			(xy 169.402709 -310.974573) (xy 169.418597 -311.023472) (xy 169.42664 -311.074254) (xy 169.427144 -311.099962)
			(xy 169.744148 -311.099962) (xy 169.748108 -311.050908) (xy 169.759885 -311.003124) (xy 169.779176 -310.957848)
			(xy 169.805479 -310.916252) (xy 169.838114 -310.879415) (xy 169.876235 -310.84829) (xy 169.918856 -310.823683)
			(xy 169.964872 -310.806231) (xy 170.013091 -310.796387) (xy 170.062266 -310.794406) (xy 170.111121 -310.800338)
			(xy 170.158392 -310.81403) (xy 170.202854 -310.835128) (xy 170.243357 -310.863084) (xy 170.27885 -310.897176)
			(xy 170.308415 -310.93652) (xy 170.331286 -310.980097) (xy 170.34687 -311.026778) (xy 170.354765 -311.075355)
			(xy 170.35526 -311.099962) (xy 170.354765 -311.124569) (xy 170.354586 -311.12567) (xy 170.673264 -311.12567)
			(xy 170.673264 -311.074254) (xy 170.681307 -311.023472) (xy 170.697195 -310.974573) (xy 170.720538 -310.928761)
			(xy 170.750759 -310.887165) (xy 170.787115 -310.850809) (xy 170.828711 -310.820588) (xy 170.874523 -310.797245)
			(xy 170.923422 -310.781357) (xy 170.974204 -310.773314) (xy 171.02562 -310.773314) (xy 171.076402 -310.781357)
			(xy 171.125301 -310.797245) (xy 171.171113 -310.820588) (xy 171.212709 -310.850809) (xy 171.249065 -310.887165)
			(xy 171.279286 -310.928761) (xy 171.302629 -310.974573) (xy 171.318517 -311.023472) (xy 171.32656 -311.074254)
			(xy 171.327064 -311.099962) (xy 171.644068 -311.099962) (xy 171.648028 -311.050908) (xy 171.659805 -311.003124)
			(xy 171.679096 -310.957848) (xy 171.705399 -310.916252) (xy 171.738034 -310.879415) (xy 171.776155 -310.84829)
			(xy 171.818776 -310.823683) (xy 171.864792 -310.806231) (xy 171.913011 -310.796387) (xy 171.962186 -310.794406)
			(xy 172.011041 -310.800338) (xy 172.058312 -310.81403) (xy 172.102774 -310.835128) (xy 172.143277 -310.863084)
			(xy 172.17877 -310.897176) (xy 172.208335 -310.93652) (xy 172.231206 -310.980097) (xy 172.24679 -311.026778)
			(xy 172.254685 -311.075355) (xy 172.25518 -311.099962) (xy 172.254685 -311.124569) (xy 172.254506 -311.12567)
			(xy 172.573438 -311.12567) (xy 172.573438 -311.074254) (xy 172.581481 -311.023472) (xy 172.597369 -310.974573)
			(xy 172.620712 -310.928761) (xy 172.650933 -310.887165) (xy 172.687289 -310.850809) (xy 172.728885 -310.820588)
			(xy 172.774697 -310.797245) (xy 172.823596 -310.781357) (xy 172.874378 -310.773314) (xy 172.925794 -310.773314)
			(xy 172.976576 -310.781357) (xy 173.025475 -310.797245) (xy 173.071287 -310.820588) (xy 173.112883 -310.850809)
			(xy 173.149239 -310.887165) (xy 173.17946 -310.928761) (xy 173.202803 -310.974573) (xy 173.218691 -311.023472)
			(xy 173.226734 -311.074254) (xy 173.227238 -311.099962) (xy 173.544242 -311.099962) (xy 173.548202 -311.050908)
			(xy 173.559979 -311.003124) (xy 173.57927 -310.957848) (xy 173.605573 -310.916252) (xy 173.638208 -310.879415)
			(xy 173.676329 -310.84829) (xy 173.71895 -310.823683) (xy 173.764966 -310.806231) (xy 173.813185 -310.796387)
			(xy 173.86236 -310.794406) (xy 173.911215 -310.800338) (xy 173.958486 -310.81403) (xy 174.002948 -310.835128)
			(xy 174.043451 -310.863084) (xy 174.078944 -310.897176) (xy 174.108509 -310.93652) (xy 174.13138 -310.980097)
			(xy 174.146964 -311.026778) (xy 174.154859 -311.075355) (xy 174.155354 -311.099962) (xy 174.154859 -311.124569)
			(xy 174.15468 -311.12567) (xy 174.473358 -311.12567) (xy 174.473358 -311.074254) (xy 174.481401 -311.023472)
			(xy 174.497289 -310.974573) (xy 174.520632 -310.928761) (xy 174.550853 -310.887165) (xy 174.587209 -310.850809)
			(xy 174.628805 -310.820588) (xy 174.674617 -310.797245) (xy 174.723516 -310.781357) (xy 174.774298 -310.773314)
			(xy 174.825714 -310.773314) (xy 174.876496 -310.781357) (xy 174.925395 -310.797245) (xy 174.971207 -310.820588)
			(xy 175.012803 -310.850809) (xy 175.049159 -310.887165) (xy 175.07938 -310.928761) (xy 175.102723 -310.974573)
			(xy 175.118611 -311.023472) (xy 175.126654 -311.074254) (xy 175.127158 -311.099962) (xy 175.444162 -311.099962)
			(xy 175.448122 -311.050908) (xy 175.459899 -311.003124) (xy 175.47919 -310.957848) (xy 175.505493 -310.916252)
			(xy 175.538128 -310.879415) (xy 175.576249 -310.84829) (xy 175.61887 -310.823683) (xy 175.664886 -310.806231)
			(xy 175.713105 -310.796387) (xy 175.76228 -310.794406) (xy 175.811135 -310.800338) (xy 175.858406 -310.81403)
			(xy 175.902868 -310.835128) (xy 175.943371 -310.863084) (xy 175.978864 -310.897176) (xy 176.008429 -310.93652)
			(xy 176.0313 -310.980097) (xy 176.046884 -311.026778) (xy 176.054779 -311.075355) (xy 176.055274 -311.099962)
			(xy 176.054779 -311.124569) (xy 176.0546 -311.12567) (xy 176.373278 -311.12567) (xy 176.373278 -311.074254)
			(xy 176.381321 -311.023472) (xy 176.397209 -310.974573) (xy 176.420552 -310.928761) (xy 176.450773 -310.887165)
			(xy 176.487129 -310.850809) (xy 176.528725 -310.820588) (xy 176.574537 -310.797245) (xy 176.623436 -310.781357)
			(xy 176.674218 -310.773314) (xy 176.725634 -310.773314) (xy 176.776416 -310.781357) (xy 176.825315 -310.797245)
			(xy 176.871127 -310.820588) (xy 176.912723 -310.850809) (xy 176.949079 -310.887165) (xy 176.9793 -310.928761)
			(xy 177.002643 -310.974573) (xy 177.018531 -311.023472) (xy 177.026574 -311.074254) (xy 177.027078 -311.099962)
			(xy 177.344082 -311.099962) (xy 177.348042 -311.050908) (xy 177.359819 -311.003124) (xy 177.37911 -310.957848)
			(xy 177.405413 -310.916252) (xy 177.438048 -310.879415) (xy 177.476169 -310.84829) (xy 177.51879 -310.823683)
			(xy 177.564806 -310.806231) (xy 177.613025 -310.796387) (xy 177.6622 -310.794406) (xy 177.711055 -310.800338)
			(xy 177.758326 -310.81403) (xy 177.802788 -310.835128) (xy 177.843291 -310.863084) (xy 177.878784 -310.897176)
			(xy 177.908349 -310.93652) (xy 177.93122 -310.980097) (xy 177.946804 -311.026778) (xy 177.954699 -311.075355)
			(xy 177.955194 -311.099962) (xy 177.954699 -311.124569) (xy 177.95452 -311.12567) (xy 178.273198 -311.12567)
			(xy 178.273198 -311.074254) (xy 178.281241 -311.023472) (xy 178.297129 -310.974573) (xy 178.320472 -310.928761)
			(xy 178.350693 -310.887165) (xy 178.387049 -310.850809) (xy 178.428645 -310.820588) (xy 178.474457 -310.797245)
			(xy 178.523356 -310.781357) (xy 178.574138 -310.773314) (xy 178.625554 -310.773314) (xy 178.676336 -310.781357)
			(xy 178.725235 -310.797245) (xy 178.771047 -310.820588) (xy 178.812643 -310.850809) (xy 178.848999 -310.887165)
			(xy 178.87922 -310.928761) (xy 178.902563 -310.974573) (xy 178.918451 -311.023472) (xy 178.926494 -311.074254)
			(xy 178.926998 -311.099962) (xy 179.244256 -311.099962) (xy 179.248216 -311.050908) (xy 179.259993 -311.003124)
			(xy 179.279284 -310.957848) (xy 179.305587 -310.916252) (xy 179.338222 -310.879415) (xy 179.376343 -310.84829)
			(xy 179.418964 -310.823683) (xy 179.46498 -310.806231) (xy 179.513199 -310.796387) (xy 179.562374 -310.794406)
			(xy 179.611229 -310.800338) (xy 179.6585 -310.81403) (xy 179.702962 -310.835128) (xy 179.743465 -310.863084)
			(xy 179.778958 -310.897176) (xy 179.808523 -310.93652) (xy 179.831394 -310.980097) (xy 179.846978 -311.026778)
			(xy 179.854873 -311.075355) (xy 179.855368 -311.099962) (xy 179.854873 -311.124569) (xy 179.854694 -311.12567)
			(xy 180.173372 -311.12567) (xy 180.173372 -311.074254) (xy 180.181415 -311.023472) (xy 180.197303 -310.974573)
			(xy 180.220646 -310.928761) (xy 180.250867 -310.887165) (xy 180.287223 -310.850809) (xy 180.328819 -310.820588)
			(xy 180.374631 -310.797245) (xy 180.42353 -310.781357) (xy 180.474312 -310.773314) (xy 180.525728 -310.773314)
			(xy 180.57651 -310.781357) (xy 180.625409 -310.797245) (xy 180.671221 -310.820588) (xy 180.712817 -310.850809)
			(xy 180.749173 -310.887165) (xy 180.779394 -310.928761) (xy 180.802737 -310.974573) (xy 180.818625 -311.023472)
			(xy 180.826668 -311.074254) (xy 180.827172 -311.099962) (xy 181.144176 -311.099962) (xy 181.148136 -311.050908)
			(xy 181.159913 -311.003124) (xy 181.179204 -310.957848) (xy 181.205507 -310.916252) (xy 181.238142 -310.879415)
			(xy 181.276263 -310.84829) (xy 181.318884 -310.823683) (xy 181.3649 -310.806231) (xy 181.413119 -310.796387)
			(xy 181.462294 -310.794406) (xy 181.511149 -310.800338) (xy 181.55842 -310.81403) (xy 181.602882 -310.835128)
			(xy 181.643385 -310.863084) (xy 181.678878 -310.897176) (xy 181.708443 -310.93652) (xy 181.731314 -310.980097)
			(xy 181.746898 -311.026778) (xy 181.754793 -311.075355) (xy 181.755288 -311.099962) (xy 182.094136 -311.099962)
			(xy 182.098096 -311.050908) (xy 182.109873 -311.003124) (xy 182.129164 -310.957848) (xy 182.155467 -310.916252)
			(xy 182.188102 -310.879415) (xy 182.226223 -310.84829) (xy 182.268844 -310.823683) (xy 182.31486 -310.806231)
			(xy 182.363079 -310.796387) (xy 182.412254 -310.794406) (xy 182.461109 -310.800338) (xy 182.50838 -310.81403)
			(xy 182.552842 -310.835128) (xy 182.593345 -310.863084) (xy 182.628838 -310.897176) (xy 182.658403 -310.93652)
			(xy 182.681274 -310.980097) (xy 182.696858 -311.026778) (xy 182.704753 -311.075355) (xy 182.705248 -311.099962)
			(xy 183.044096 -311.099962) (xy 183.048056 -311.050908) (xy 183.059833 -311.003124) (xy 183.079124 -310.957848)
			(xy 183.105427 -310.916252) (xy 183.138062 -310.879415) (xy 183.176183 -310.84829) (xy 183.218804 -310.823683)
			(xy 183.26482 -310.806231) (xy 183.313039 -310.796387) (xy 183.362214 -310.794406) (xy 183.411069 -310.800338)
			(xy 183.45834 -310.81403) (xy 183.502802 -310.835128) (xy 183.543305 -310.863084) (xy 183.578798 -310.897176)
			(xy 183.608363 -310.93652) (xy 183.631234 -310.980097) (xy 183.646818 -311.026778) (xy 183.654713 -311.075355)
			(xy 183.655208 -311.099962) (xy 183.994056 -311.099962) (xy 183.998016 -311.050908) (xy 184.009793 -311.003124)
			(xy 184.029084 -310.957848) (xy 184.055387 -310.916252) (xy 184.088022 -310.879415) (xy 184.126143 -310.84829)
			(xy 184.168764 -310.823683) (xy 184.21478 -310.806231) (xy 184.262999 -310.796387) (xy 184.312174 -310.794406)
			(xy 184.361029 -310.800338) (xy 184.4083 -310.81403) (xy 184.452762 -310.835128) (xy 184.493265 -310.863084)
			(xy 184.528758 -310.897176) (xy 184.558323 -310.93652) (xy 184.581194 -310.980097) (xy 184.596778 -311.026778)
			(xy 184.604673 -311.075355) (xy 184.605168 -311.099962) (xy 184.94427 -311.099962) (xy 184.94823 -311.050908)
			(xy 184.960007 -311.003124) (xy 184.979298 -310.957848) (xy 185.005601 -310.916252) (xy 185.038236 -310.879415)
			(xy 185.076357 -310.84829) (xy 185.118978 -310.823683) (xy 185.164994 -310.806231) (xy 185.213213 -310.796387)
			(xy 185.262388 -310.794406) (xy 185.311243 -310.800338) (xy 185.358514 -310.81403) (xy 185.402976 -310.835128)
			(xy 185.443479 -310.863084) (xy 185.478972 -310.897176) (xy 185.508537 -310.93652) (xy 185.531408 -310.980097)
			(xy 185.546992 -311.026778) (xy 185.554887 -311.075355) (xy 185.555382 -311.099962) (xy 185.89423 -311.099962)
			(xy 185.89819 -311.050908) (xy 185.909967 -311.003124) (xy 185.929258 -310.957848) (xy 185.955561 -310.916252)
			(xy 185.988196 -310.879415) (xy 186.026317 -310.84829) (xy 186.068938 -310.823683) (xy 186.114954 -310.806231)
			(xy 186.163173 -310.796387) (xy 186.212348 -310.794406) (xy 186.261203 -310.800338) (xy 186.308474 -310.81403)
			(xy 186.352936 -310.835128) (xy 186.393439 -310.863084) (xy 186.428932 -310.897176) (xy 186.458497 -310.93652)
			(xy 186.481368 -310.980097) (xy 186.496952 -311.026778) (xy 186.504847 -311.075355) (xy 186.505342 -311.099962)
			(xy 186.84419 -311.099962) (xy 186.84815 -311.050908) (xy 186.859927 -311.003124) (xy 186.879218 -310.957848)
			(xy 186.905521 -310.916252) (xy 186.938156 -310.879415) (xy 186.976277 -310.84829) (xy 187.018898 -310.823683)
			(xy 187.064914 -310.806231) (xy 187.113133 -310.796387) (xy 187.162308 -310.794406) (xy 187.211163 -310.800338)
			(xy 187.258434 -310.81403) (xy 187.302896 -310.835128) (xy 187.343399 -310.863084) (xy 187.378892 -310.897176)
			(xy 187.408457 -310.93652) (xy 187.431328 -310.980097) (xy 187.446912 -311.026778) (xy 187.454807 -311.075355)
			(xy 187.455302 -311.099962) (xy 187.79415 -311.099962) (xy 187.79811 -311.050908) (xy 187.809887 -311.003124)
			(xy 187.829178 -310.957848) (xy 187.855481 -310.916252) (xy 187.888116 -310.879415) (xy 187.926237 -310.84829)
			(xy 187.968858 -310.823683) (xy 188.014874 -310.806231) (xy 188.063093 -310.796387) (xy 188.112268 -310.794406)
			(xy 188.161123 -310.800338) (xy 188.208394 -310.81403) (xy 188.252856 -310.835128) (xy 188.293359 -310.863084)
			(xy 188.328852 -310.897176) (xy 188.358417 -310.93652) (xy 188.381288 -310.980097) (xy 188.396872 -311.026778)
			(xy 188.404767 -311.075355) (xy 188.405262 -311.099962) (xy 188.74411 -311.099962) (xy 188.74807 -311.050908)
			(xy 188.759847 -311.003124) (xy 188.779138 -310.957848) (xy 188.805441 -310.916252) (xy 188.838076 -310.879415)
			(xy 188.876197 -310.84829) (xy 188.918818 -310.823683) (xy 188.964834 -310.806231) (xy 189.013053 -310.796387)
			(xy 189.062228 -310.794406) (xy 189.111083 -310.800338) (xy 189.158354 -310.81403) (xy 189.202816 -310.835128)
			(xy 189.243319 -310.863084) (xy 189.278812 -310.897176) (xy 189.308377 -310.93652) (xy 189.331248 -310.980097)
			(xy 189.346832 -311.026778) (xy 189.354727 -311.075355) (xy 189.355222 -311.099962) (xy 189.354727 -311.124569)
			(xy 189.354548 -311.12567) (xy 189.673226 -311.12567) (xy 189.673226 -311.074254) (xy 189.681269 -311.023472)
			(xy 189.697157 -310.974573) (xy 189.7205 -310.928761) (xy 189.750721 -310.887165) (xy 189.787077 -310.850809)
			(xy 189.828673 -310.820588) (xy 189.874485 -310.797245) (xy 189.923384 -310.781357) (xy 189.974166 -310.773314)
			(xy 190.025582 -310.773314) (xy 190.076364 -310.781357) (xy 190.125263 -310.797245) (xy 190.171075 -310.820588)
			(xy 190.212671 -310.850809) (xy 190.249027 -310.887165) (xy 190.279248 -310.928761) (xy 190.302591 -310.974573)
			(xy 190.318479 -311.023472) (xy 190.326522 -311.074254) (xy 190.327026 -311.099962) (xy 190.644284 -311.099962)
			(xy 190.648244 -311.050908) (xy 190.660021 -311.003124) (xy 190.679312 -310.957848) (xy 190.705615 -310.916252)
			(xy 190.73825 -310.879415) (xy 190.776371 -310.84829) (xy 190.818992 -310.823683) (xy 190.865008 -310.806231)
			(xy 190.913227 -310.796387) (xy 190.962402 -310.794406) (xy 191.011257 -310.800338) (xy 191.058528 -310.81403)
			(xy 191.10299 -310.835128) (xy 191.143493 -310.863084) (xy 191.178986 -310.897176) (xy 191.208551 -310.93652)
			(xy 191.231422 -310.980097) (xy 191.247006 -311.026778) (xy 191.254901 -311.075355) (xy 191.255396 -311.099962)
			(xy 191.254901 -311.124569) (xy 191.254722 -311.12567) (xy 191.5734 -311.12567) (xy 191.5734 -311.074254)
			(xy 191.581443 -311.023472) (xy 191.597331 -310.974573) (xy 191.620674 -310.928761) (xy 191.650895 -310.887165)
			(xy 191.687251 -310.850809) (xy 191.728847 -310.820588) (xy 191.774659 -310.797245) (xy 191.823558 -310.781357)
			(xy 191.87434 -310.773314) (xy 191.925756 -310.773314) (xy 191.976538 -310.781357) (xy 192.025437 -310.797245)
			(xy 192.071249 -310.820588) (xy 192.112845 -310.850809) (xy 192.149201 -310.887165) (xy 192.179422 -310.928761)
			(xy 192.202765 -310.974573) (xy 192.218653 -311.023472) (xy 192.226696 -311.074254) (xy 192.2272 -311.099962)
			(xy 192.544204 -311.099962) (xy 192.548164 -311.050908) (xy 192.559941 -311.003124) (xy 192.579232 -310.957848)
			(xy 192.605535 -310.916252) (xy 192.63817 -310.879415) (xy 192.676291 -310.84829) (xy 192.718912 -310.823683)
			(xy 192.764928 -310.806231) (xy 192.813147 -310.796387) (xy 192.862322 -310.794406) (xy 192.911177 -310.800338)
			(xy 192.958448 -310.81403) (xy 193.00291 -310.835128) (xy 193.043413 -310.863084) (xy 193.078906 -310.897176)
			(xy 193.108471 -310.93652) (xy 193.131342 -310.980097) (xy 193.146926 -311.026778) (xy 193.154821 -311.075355)
			(xy 193.155316 -311.099962) (xy 193.154821 -311.124569) (xy 193.154642 -311.12567) (xy 193.47332 -311.12567)
			(xy 193.47332 -311.074254) (xy 193.481363 -311.023472) (xy 193.497251 -310.974573) (xy 193.520594 -310.928761)
			(xy 193.550815 -310.887165) (xy 193.587171 -310.850809) (xy 193.628767 -310.820588) (xy 193.674579 -310.797245)
			(xy 193.723478 -310.781357) (xy 193.77426 -310.773314) (xy 193.825676 -310.773314) (xy 193.876458 -310.781357)
			(xy 193.925357 -310.797245) (xy 193.971169 -310.820588) (xy 194.012765 -310.850809) (xy 194.049121 -310.887165)
			(xy 194.079342 -310.928761) (xy 194.102685 -310.974573) (xy 194.118573 -311.023472) (xy 194.126616 -311.074254)
			(xy 194.12712 -311.099962) (xy 194.444124 -311.099962) (xy 194.448084 -311.050908) (xy 194.459861 -311.003124)
			(xy 194.479152 -310.957848) (xy 194.505455 -310.916252) (xy 194.53809 -310.879415) (xy 194.576211 -310.84829)
			(xy 194.618832 -310.823683) (xy 194.664848 -310.806231) (xy 194.713067 -310.796387) (xy 194.762242 -310.794406)
			(xy 194.811097 -310.800338) (xy 194.858368 -310.81403) (xy 194.90283 -310.835128) (xy 194.943333 -310.863084)
			(xy 194.978826 -310.897176) (xy 195.008391 -310.93652) (xy 195.031262 -310.980097) (xy 195.046846 -311.026778)
			(xy 195.054741 -311.075355) (xy 195.055236 -311.099962) (xy 195.054741 -311.124569) (xy 195.054562 -311.12567)
			(xy 195.37324 -311.12567) (xy 195.37324 -311.074254) (xy 195.381283 -311.023472) (xy 195.397171 -310.974573)
			(xy 195.420514 -310.928761) (xy 195.450735 -310.887165) (xy 195.487091 -310.850809) (xy 195.528687 -310.820588)
			(xy 195.574499 -310.797245) (xy 195.623398 -310.781357) (xy 195.67418 -310.773314) (xy 195.725596 -310.773314)
			(xy 195.776378 -310.781357) (xy 195.825277 -310.797245) (xy 195.871089 -310.820588) (xy 195.912685 -310.850809)
			(xy 195.949041 -310.887165) (xy 195.979262 -310.928761) (xy 196.002605 -310.974573) (xy 196.018493 -311.023472)
			(xy 196.026536 -311.074254) (xy 196.02704 -311.099962) (xy 196.344044 -311.099962) (xy 196.348004 -311.050908)
			(xy 196.359781 -311.003124) (xy 196.379072 -310.957848) (xy 196.405375 -310.916252) (xy 196.43801 -310.879415)
			(xy 196.476131 -310.84829) (xy 196.518752 -310.823683) (xy 196.564768 -310.806231) (xy 196.612987 -310.796387)
			(xy 196.662162 -310.794406) (xy 196.711017 -310.800338) (xy 196.758288 -310.81403) (xy 196.80275 -310.835128)
			(xy 196.843253 -310.863084) (xy 196.878746 -310.897176) (xy 196.908311 -310.93652) (xy 196.931182 -310.980097)
			(xy 196.946766 -311.026778) (xy 196.954661 -311.075355) (xy 196.955156 -311.099962) (xy 197.294258 -311.099962)
			(xy 197.298218 -311.050908) (xy 197.309995 -311.003124) (xy 197.329286 -310.957848) (xy 197.355589 -310.916252)
			(xy 197.388224 -310.879415) (xy 197.426345 -310.84829) (xy 197.468966 -310.823683) (xy 197.514982 -310.806231)
			(xy 197.563201 -310.796387) (xy 197.612376 -310.794406) (xy 197.661231 -310.800338) (xy 197.708502 -310.81403)
			(xy 197.752964 -310.835128) (xy 197.793467 -310.863084) (xy 197.82896 -310.897176) (xy 197.858525 -310.93652)
			(xy 197.881396 -310.980097) (xy 197.89698 -311.026778) (xy 197.904875 -311.075355) (xy 197.90537 -311.099962)
			(xy 198.244218 -311.099962) (xy 198.248178 -311.050908) (xy 198.259955 -311.003124) (xy 198.279246 -310.957848)
			(xy 198.305549 -310.916252) (xy 198.338184 -310.879415) (xy 198.376305 -310.84829) (xy 198.418926 -310.823683)
			(xy 198.464942 -310.806231) (xy 198.513161 -310.796387) (xy 198.562336 -310.794406) (xy 198.611191 -310.800338)
			(xy 198.658462 -310.81403) (xy 198.702924 -310.835128) (xy 198.743427 -310.863084) (xy 198.77892 -310.897176)
			(xy 198.808485 -310.93652) (xy 198.831356 -310.980097) (xy 198.84694 -311.026778) (xy 198.854835 -311.075355)
			(xy 198.85533 -311.099962) (xy 198.854835 -311.124569) (xy 198.84694 -311.173146) (xy 198.831356 -311.219827)
			(xy 198.808485 -311.263404) (xy 198.77892 -311.302748) (xy 198.743427 -311.33684) (xy 198.702924 -311.364796)
			(xy 198.669016 -311.380886) (xy 206.666706 -311.380886) (xy 206.674458 -311.326928) (xy 206.68981 -311.274621)
			(xy 206.71245 -311.225033) (xy 206.741917 -311.17917) (xy 206.777611 -311.137969) (xy 206.818805 -311.102266)
			(xy 206.86466 -311.072789) (xy 206.914245 -311.050139) (xy 206.966547 -311.034775) (xy 207.020504 -311.027012)
			(xy 207.075017 -311.027006) (xy 207.128976 -311.034759) (xy 207.181282 -311.050111) (xy 207.23087 -311.072752)
			(xy 207.276732 -311.102219) (xy 207.317934 -311.137913) (xy 207.353636 -311.179107) (xy 207.383112 -311.224963)
			(xy 207.405762 -311.274548) (xy 207.421125 -311.326851) (xy 207.428888 -311.380808) (xy 207.429354 -311.408064)
			(xy 207.429157 -311.425112) (xy 207.426103 -311.459072) (xy 207.423258 -311.475882) (xy 207.420972 -311.488328)
			(xy 207.428338 -311.51195) (xy 207.5053 -311.588912) (xy 207.528922 -311.596278) (xy 207.541368 -311.593992)
			(xy 207.558239 -311.591125) (xy 207.592328 -311.58807) (xy 207.60944 -311.587896) (xy 207.636692 -311.588341)
			(xy 207.690642 -311.596103) (xy 207.742938 -311.611463) (xy 207.792515 -311.634109) (xy 207.838366 -311.66358)
			(xy 207.879555 -311.699276) (xy 207.915246 -311.74047) (xy 207.944712 -311.786323) (xy 207.967352 -311.835904)
			(xy 207.982707 -311.888201) (xy 207.990463 -311.942152) (xy 207.990948 -311.969404) (xy 207.989932 -311.99836)
			(xy 207.988916 -312.009536) (xy 207.99679 -312.030364) (xy 208.067656 -312.100722) (xy 208.088484 -312.108088)
			(xy 208.099914 -312.107072) (xy 208.132426 -312.105802) (xy 208.159675 -312.106306) (xy 208.213617 -312.114065)
			(xy 208.265906 -312.129422) (xy 208.315478 -312.152064) (xy 208.361322 -312.181531) (xy 208.402507 -312.217221)
			(xy 208.438193 -312.25841) (xy 208.467655 -312.304257) (xy 208.490292 -312.353831) (xy 208.505643 -312.406122)
			(xy 208.513397 -312.460065) (xy 208.513395 -312.514563) (xy 208.505637 -312.568505) (xy 208.490282 -312.620795)
			(xy 208.467641 -312.670367) (xy 208.438176 -312.716213) (xy 208.402487 -312.757399) (xy 208.3613 -312.793086)
			(xy 208.315453 -312.822549) (xy 208.26588 -312.845187) (xy 208.21359 -312.860541) (xy 208.159647 -312.868296)
			(xy 208.105149 -312.868296) (xy 208.051206 -312.86054) (xy 207.998916 -312.845186) (xy 207.949343 -312.822547)
			(xy 207.903497 -312.793084) (xy 207.86231 -312.757396) (xy 207.826621 -312.71621) (xy 207.797157 -312.670364)
			(xy 207.774517 -312.620791) (xy 207.759162 -312.568502) (xy 207.751405 -312.514559) (xy 207.750918 -312.48731)
			(xy 207.751934 -312.458354) (xy 207.75295 -312.447178) (xy 207.745076 -312.42635) (xy 207.67421 -312.355992)
			(xy 207.653382 -312.348626) (xy 207.641952 -312.349642) (xy 207.60944 -312.350912) (xy 207.582188 -312.350408)
			(xy 207.528239 -312.342656) (xy 207.475942 -312.327305) (xy 207.426363 -312.304668) (xy 207.380509 -312.275204)
			(xy 207.339316 -312.239515) (xy 207.303622 -312.198326) (xy 207.274153 -312.152476) (xy 207.25151 -312.102899)
			(xy 207.236153 -312.050604) (xy 207.228396 -311.996656) (xy 207.227932 -311.969404) (xy 207.228138 -311.952356)
			(xy 207.231186 -311.918397) (xy 207.234028 -311.901586) (xy 207.236314 -311.88914) (xy 207.228948 -311.865518)
			(xy 207.151986 -311.788556) (xy 207.128364 -311.78119) (xy 207.115918 -311.783476) (xy 207.099047 -311.786346)
			(xy 207.064959 -311.789398) (xy 207.047846 -311.789572) (xy 207.02059 -311.789194) (xy 206.966631 -311.781443)
			(xy 206.914325 -311.766091) (xy 206.864735 -311.743452) (xy 206.818873 -311.713985) (xy 206.777671 -311.678292)
			(xy 206.741968 -311.637098) (xy 206.712491 -311.591242) (xy 206.68984 -311.541659) (xy 206.674476 -311.489356)
			(xy 206.666712 -311.435399) (xy 206.666706 -311.380886) (xy 198.669016 -311.380886) (xy 198.658462 -311.385894)
			(xy 198.611191 -311.399586) (xy 198.562336 -311.405518) (xy 198.513161 -311.403537) (xy 198.464942 -311.393693)
			(xy 198.418926 -311.376241) (xy 198.376305 -311.351634) (xy 198.338184 -311.320509) (xy 198.305549 -311.283672)
			(xy 198.279246 -311.242076) (xy 198.259955 -311.1968) (xy 198.248178 -311.149016) (xy 198.244218 -311.099962)
			(xy 197.90537 -311.099962) (xy 197.904875 -311.124569) (xy 197.89698 -311.173146) (xy 197.881396 -311.219827)
			(xy 197.858525 -311.263404) (xy 197.82896 -311.302748) (xy 197.793467 -311.33684) (xy 197.752964 -311.364796)
			(xy 197.708502 -311.385894) (xy 197.661231 -311.399586) (xy 197.612376 -311.405518) (xy 197.563201 -311.403537)
			(xy 197.514982 -311.393693) (xy 197.468966 -311.376241) (xy 197.426345 -311.351634) (xy 197.388224 -311.320509)
			(xy 197.355589 -311.283672) (xy 197.329286 -311.242076) (xy 197.309995 -311.1968) (xy 197.298218 -311.149016)
			(xy 197.294258 -311.099962) (xy 196.955156 -311.099962) (xy 196.954661 -311.124569) (xy 196.946766 -311.173146)
			(xy 196.931182 -311.219827) (xy 196.908311 -311.263404) (xy 196.878746 -311.302748) (xy 196.843253 -311.33684)
			(xy 196.80275 -311.364796) (xy 196.758288 -311.385894) (xy 196.711017 -311.399586) (xy 196.662162 -311.405518)
			(xy 196.612987 -311.403537) (xy 196.564768 -311.393693) (xy 196.518752 -311.376241) (xy 196.476131 -311.351634)
			(xy 196.43801 -311.320509) (xy 196.405375 -311.283672) (xy 196.379072 -311.242076) (xy 196.359781 -311.1968)
			(xy 196.348004 -311.149016) (xy 196.344044 -311.099962) (xy 196.02704 -311.099962) (xy 196.026536 -311.12567)
			(xy 196.018493 -311.176452) (xy 196.002605 -311.225351) (xy 195.979262 -311.271163) (xy 195.949041 -311.312759)
			(xy 195.912685 -311.349115) (xy 195.871089 -311.379336) (xy 195.825277 -311.402679) (xy 195.776378 -311.418567)
			(xy 195.725596 -311.42661) (xy 195.67418 -311.42661) (xy 195.623398 -311.418567) (xy 195.574499 -311.402679)
			(xy 195.528687 -311.379336) (xy 195.487091 -311.349115) (xy 195.450735 -311.312759) (xy 195.420514 -311.271163)
			(xy 195.397171 -311.225351) (xy 195.381283 -311.176452) (xy 195.37324 -311.12567) (xy 195.054562 -311.12567)
			(xy 195.046846 -311.173146) (xy 195.031262 -311.219827) (xy 195.008391 -311.263404) (xy 194.978826 -311.302748)
			(xy 194.943333 -311.33684) (xy 194.90283 -311.364796) (xy 194.858368 -311.385894) (xy 194.811097 -311.399586)
			(xy 194.762242 -311.405518) (xy 194.713067 -311.403537) (xy 194.664848 -311.393693) (xy 194.618832 -311.376241)
			(xy 194.576211 -311.351634) (xy 194.53809 -311.320509) (xy 194.505455 -311.283672) (xy 194.479152 -311.242076)
			(xy 194.459861 -311.1968) (xy 194.448084 -311.149016) (xy 194.444124 -311.099962) (xy 194.12712 -311.099962)
			(xy 194.126616 -311.12567) (xy 194.118573 -311.176452) (xy 194.102685 -311.225351) (xy 194.079342 -311.271163)
			(xy 194.049121 -311.312759) (xy 194.012765 -311.349115) (xy 193.971169 -311.379336) (xy 193.925357 -311.402679)
			(xy 193.876458 -311.418567) (xy 193.825676 -311.42661) (xy 193.77426 -311.42661) (xy 193.723478 -311.418567)
			(xy 193.674579 -311.402679) (xy 193.628767 -311.379336) (xy 193.587171 -311.349115) (xy 193.550815 -311.312759)
			(xy 193.520594 -311.271163) (xy 193.497251 -311.225351) (xy 193.481363 -311.176452) (xy 193.47332 -311.12567)
			(xy 193.154642 -311.12567) (xy 193.146926 -311.173146) (xy 193.131342 -311.219827) (xy 193.108471 -311.263404)
			(xy 193.078906 -311.302748) (xy 193.043413 -311.33684) (xy 193.00291 -311.364796) (xy 192.958448 -311.385894)
			(xy 192.911177 -311.399586) (xy 192.862322 -311.405518) (xy 192.813147 -311.403537) (xy 192.764928 -311.393693)
			(xy 192.718912 -311.376241) (xy 192.676291 -311.351634) (xy 192.63817 -311.320509) (xy 192.605535 -311.283672)
			(xy 192.579232 -311.242076) (xy 192.559941 -311.1968) (xy 192.548164 -311.149016) (xy 192.544204 -311.099962)
			(xy 192.2272 -311.099962) (xy 192.226696 -311.12567) (xy 192.218653 -311.176452) (xy 192.202765 -311.225351)
			(xy 192.179422 -311.271163) (xy 192.149201 -311.312759) (xy 192.112845 -311.349115) (xy 192.071249 -311.379336)
			(xy 192.025437 -311.402679) (xy 191.976538 -311.418567) (xy 191.925756 -311.42661) (xy 191.87434 -311.42661)
			(xy 191.823558 -311.418567) (xy 191.774659 -311.402679) (xy 191.728847 -311.379336) (xy 191.687251 -311.349115)
			(xy 191.650895 -311.312759) (xy 191.620674 -311.271163) (xy 191.597331 -311.225351) (xy 191.581443 -311.176452)
			(xy 191.5734 -311.12567) (xy 191.254722 -311.12567) (xy 191.247006 -311.173146) (xy 191.231422 -311.219827)
			(xy 191.208551 -311.263404) (xy 191.178986 -311.302748) (xy 191.143493 -311.33684) (xy 191.10299 -311.364796)
			(xy 191.058528 -311.385894) (xy 191.011257 -311.399586) (xy 190.962402 -311.405518) (xy 190.913227 -311.403537)
			(xy 190.865008 -311.393693) (xy 190.818992 -311.376241) (xy 190.776371 -311.351634) (xy 190.73825 -311.320509)
			(xy 190.705615 -311.283672) (xy 190.679312 -311.242076) (xy 190.660021 -311.1968) (xy 190.648244 -311.149016)
			(xy 190.644284 -311.099962) (xy 190.327026 -311.099962) (xy 190.326522 -311.12567) (xy 190.318479 -311.176452)
			(xy 190.302591 -311.225351) (xy 190.279248 -311.271163) (xy 190.249027 -311.312759) (xy 190.212671 -311.349115)
			(xy 190.171075 -311.379336) (xy 190.125263 -311.402679) (xy 190.076364 -311.418567) (xy 190.025582 -311.42661)
			(xy 189.974166 -311.42661) (xy 189.923384 -311.418567) (xy 189.874485 -311.402679) (xy 189.828673 -311.379336)
			(xy 189.787077 -311.349115) (xy 189.750721 -311.312759) (xy 189.7205 -311.271163) (xy 189.697157 -311.225351)
			(xy 189.681269 -311.176452) (xy 189.673226 -311.12567) (xy 189.354548 -311.12567) (xy 189.346832 -311.173146)
			(xy 189.331248 -311.219827) (xy 189.308377 -311.263404) (xy 189.278812 -311.302748) (xy 189.243319 -311.33684)
			(xy 189.202816 -311.364796) (xy 189.158354 -311.385894) (xy 189.111083 -311.399586) (xy 189.062228 -311.405518)
			(xy 189.013053 -311.403537) (xy 188.964834 -311.393693) (xy 188.918818 -311.376241) (xy 188.876197 -311.351634)
			(xy 188.838076 -311.320509) (xy 188.805441 -311.283672) (xy 188.779138 -311.242076) (xy 188.759847 -311.1968)
			(xy 188.74807 -311.149016) (xy 188.74411 -311.099962) (xy 188.405262 -311.099962) (xy 188.404767 -311.124569)
			(xy 188.396872 -311.173146) (xy 188.381288 -311.219827) (xy 188.358417 -311.263404) (xy 188.328852 -311.302748)
			(xy 188.293359 -311.33684) (xy 188.252856 -311.364796) (xy 188.208394 -311.385894) (xy 188.161123 -311.399586)
			(xy 188.112268 -311.405518) (xy 188.063093 -311.403537) (xy 188.014874 -311.393693) (xy 187.968858 -311.376241)
			(xy 187.926237 -311.351634) (xy 187.888116 -311.320509) (xy 187.855481 -311.283672) (xy 187.829178 -311.242076)
			(xy 187.809887 -311.1968) (xy 187.79811 -311.149016) (xy 187.79415 -311.099962) (xy 187.455302 -311.099962)
			(xy 187.454807 -311.124569) (xy 187.446912 -311.173146) (xy 187.431328 -311.219827) (xy 187.408457 -311.263404)
			(xy 187.378892 -311.302748) (xy 187.343399 -311.33684) (xy 187.302896 -311.364796) (xy 187.258434 -311.385894)
			(xy 187.211163 -311.399586) (xy 187.162308 -311.405518) (xy 187.113133 -311.403537) (xy 187.064914 -311.393693)
			(xy 187.018898 -311.376241) (xy 186.976277 -311.351634) (xy 186.938156 -311.320509) (xy 186.905521 -311.283672)
			(xy 186.879218 -311.242076) (xy 186.859927 -311.1968) (xy 186.84815 -311.149016) (xy 186.84419 -311.099962)
			(xy 186.505342 -311.099962) (xy 186.504847 -311.124569) (xy 186.496952 -311.173146) (xy 186.481368 -311.219827)
			(xy 186.458497 -311.263404) (xy 186.428932 -311.302748) (xy 186.393439 -311.33684) (xy 186.352936 -311.364796)
			(xy 186.308474 -311.385894) (xy 186.261203 -311.399586) (xy 186.212348 -311.405518) (xy 186.163173 -311.403537)
			(xy 186.114954 -311.393693) (xy 186.068938 -311.376241) (xy 186.026317 -311.351634) (xy 185.988196 -311.320509)
			(xy 185.955561 -311.283672) (xy 185.929258 -311.242076) (xy 185.909967 -311.1968) (xy 185.89819 -311.149016)
			(xy 185.89423 -311.099962) (xy 185.555382 -311.099962) (xy 185.554887 -311.124569) (xy 185.546992 -311.173146)
			(xy 185.531408 -311.219827) (xy 185.508537 -311.263404) (xy 185.478972 -311.302748) (xy 185.443479 -311.33684)
			(xy 185.402976 -311.364796) (xy 185.358514 -311.385894) (xy 185.311243 -311.399586) (xy 185.262388 -311.405518)
			(xy 185.213213 -311.403537) (xy 185.164994 -311.393693) (xy 185.118978 -311.376241) (xy 185.076357 -311.351634)
			(xy 185.038236 -311.320509) (xy 185.005601 -311.283672) (xy 184.979298 -311.242076) (xy 184.960007 -311.1968)
			(xy 184.94823 -311.149016) (xy 184.94427 -311.099962) (xy 184.605168 -311.099962) (xy 184.604673 -311.124569)
			(xy 184.596778 -311.173146) (xy 184.581194 -311.219827) (xy 184.558323 -311.263404) (xy 184.528758 -311.302748)
			(xy 184.493265 -311.33684) (xy 184.452762 -311.364796) (xy 184.4083 -311.385894) (xy 184.361029 -311.399586)
			(xy 184.312174 -311.405518) (xy 184.262999 -311.403537) (xy 184.21478 -311.393693) (xy 184.168764 -311.376241)
			(xy 184.126143 -311.351634) (xy 184.088022 -311.320509) (xy 184.055387 -311.283672) (xy 184.029084 -311.242076)
			(xy 184.009793 -311.1968) (xy 183.998016 -311.149016) (xy 183.994056 -311.099962) (xy 183.655208 -311.099962)
			(xy 183.654713 -311.124569) (xy 183.646818 -311.173146) (xy 183.631234 -311.219827) (xy 183.608363 -311.263404)
			(xy 183.578798 -311.302748) (xy 183.543305 -311.33684) (xy 183.502802 -311.364796) (xy 183.45834 -311.385894)
			(xy 183.411069 -311.399586) (xy 183.362214 -311.405518) (xy 183.313039 -311.403537) (xy 183.26482 -311.393693)
			(xy 183.218804 -311.376241) (xy 183.176183 -311.351634) (xy 183.138062 -311.320509) (xy 183.105427 -311.283672)
			(xy 183.079124 -311.242076) (xy 183.059833 -311.1968) (xy 183.048056 -311.149016) (xy 183.044096 -311.099962)
			(xy 182.705248 -311.099962) (xy 182.704753 -311.124569) (xy 182.696858 -311.173146) (xy 182.681274 -311.219827)
			(xy 182.658403 -311.263404) (xy 182.628838 -311.302748) (xy 182.593345 -311.33684) (xy 182.552842 -311.364796)
			(xy 182.50838 -311.385894) (xy 182.461109 -311.399586) (xy 182.412254 -311.405518) (xy 182.363079 -311.403537)
			(xy 182.31486 -311.393693) (xy 182.268844 -311.376241) (xy 182.226223 -311.351634) (xy 182.188102 -311.320509)
			(xy 182.155467 -311.283672) (xy 182.129164 -311.242076) (xy 182.109873 -311.1968) (xy 182.098096 -311.149016)
			(xy 182.094136 -311.099962) (xy 181.755288 -311.099962) (xy 181.754793 -311.124569) (xy 181.746898 -311.173146)
			(xy 181.731314 -311.219827) (xy 181.708443 -311.263404) (xy 181.678878 -311.302748) (xy 181.643385 -311.33684)
			(xy 181.602882 -311.364796) (xy 181.55842 -311.385894) (xy 181.511149 -311.399586) (xy 181.462294 -311.405518)
			(xy 181.413119 -311.403537) (xy 181.3649 -311.393693) (xy 181.318884 -311.376241) (xy 181.276263 -311.351634)
			(xy 181.238142 -311.320509) (xy 181.205507 -311.283672) (xy 181.179204 -311.242076) (xy 181.159913 -311.1968)
			(xy 181.148136 -311.149016) (xy 181.144176 -311.099962) (xy 180.827172 -311.099962) (xy 180.826668 -311.12567)
			(xy 180.818625 -311.176452) (xy 180.802737 -311.225351) (xy 180.779394 -311.271163) (xy 180.749173 -311.312759)
			(xy 180.712817 -311.349115) (xy 180.671221 -311.379336) (xy 180.625409 -311.402679) (xy 180.57651 -311.418567)
			(xy 180.525728 -311.42661) (xy 180.474312 -311.42661) (xy 180.42353 -311.418567) (xy 180.374631 -311.402679)
			(xy 180.328819 -311.379336) (xy 180.287223 -311.349115) (xy 180.250867 -311.312759) (xy 180.220646 -311.271163)
			(xy 180.197303 -311.225351) (xy 180.181415 -311.176452) (xy 180.173372 -311.12567) (xy 179.854694 -311.12567)
			(xy 179.846978 -311.173146) (xy 179.831394 -311.219827) (xy 179.808523 -311.263404) (xy 179.778958 -311.302748)
			(xy 179.743465 -311.33684) (xy 179.702962 -311.364796) (xy 179.6585 -311.385894) (xy 179.611229 -311.399586)
			(xy 179.562374 -311.405518) (xy 179.513199 -311.403537) (xy 179.46498 -311.393693) (xy 179.418964 -311.376241)
			(xy 179.376343 -311.351634) (xy 179.338222 -311.320509) (xy 179.305587 -311.283672) (xy 179.279284 -311.242076)
			(xy 179.259993 -311.1968) (xy 179.248216 -311.149016) (xy 179.244256 -311.099962) (xy 178.926998 -311.099962)
			(xy 178.926494 -311.12567) (xy 178.918451 -311.176452) (xy 178.902563 -311.225351) (xy 178.87922 -311.271163)
			(xy 178.848999 -311.312759) (xy 178.812643 -311.349115) (xy 178.771047 -311.379336) (xy 178.725235 -311.402679)
			(xy 178.676336 -311.418567) (xy 178.625554 -311.42661) (xy 178.574138 -311.42661) (xy 178.523356 -311.418567)
			(xy 178.474457 -311.402679) (xy 178.428645 -311.379336) (xy 178.387049 -311.349115) (xy 178.350693 -311.312759)
			(xy 178.320472 -311.271163) (xy 178.297129 -311.225351) (xy 178.281241 -311.176452) (xy 178.273198 -311.12567)
			(xy 177.95452 -311.12567) (xy 177.946804 -311.173146) (xy 177.93122 -311.219827) (xy 177.908349 -311.263404)
			(xy 177.878784 -311.302748) (xy 177.843291 -311.33684) (xy 177.802788 -311.364796) (xy 177.758326 -311.385894)
			(xy 177.711055 -311.399586) (xy 177.6622 -311.405518) (xy 177.613025 -311.403537) (xy 177.564806 -311.393693)
			(xy 177.51879 -311.376241) (xy 177.476169 -311.351634) (xy 177.438048 -311.320509) (xy 177.405413 -311.283672)
			(xy 177.37911 -311.242076) (xy 177.359819 -311.1968) (xy 177.348042 -311.149016) (xy 177.344082 -311.099962)
			(xy 177.027078 -311.099962) (xy 177.026574 -311.12567) (xy 177.018531 -311.176452) (xy 177.002643 -311.225351)
			(xy 176.9793 -311.271163) (xy 176.949079 -311.312759) (xy 176.912723 -311.349115) (xy 176.871127 -311.379336)
			(xy 176.825315 -311.402679) (xy 176.776416 -311.418567) (xy 176.725634 -311.42661) (xy 176.674218 -311.42661)
			(xy 176.623436 -311.418567) (xy 176.574537 -311.402679) (xy 176.528725 -311.379336) (xy 176.487129 -311.349115)
			(xy 176.450773 -311.312759) (xy 176.420552 -311.271163) (xy 176.397209 -311.225351) (xy 176.381321 -311.176452)
			(xy 176.373278 -311.12567) (xy 176.0546 -311.12567) (xy 176.046884 -311.173146) (xy 176.0313 -311.219827)
			(xy 176.008429 -311.263404) (xy 175.978864 -311.302748) (xy 175.943371 -311.33684) (xy 175.902868 -311.364796)
			(xy 175.858406 -311.385894) (xy 175.811135 -311.399586) (xy 175.76228 -311.405518) (xy 175.713105 -311.403537)
			(xy 175.664886 -311.393693) (xy 175.61887 -311.376241) (xy 175.576249 -311.351634) (xy 175.538128 -311.320509)
			(xy 175.505493 -311.283672) (xy 175.47919 -311.242076) (xy 175.459899 -311.1968) (xy 175.448122 -311.149016)
			(xy 175.444162 -311.099962) (xy 175.127158 -311.099962) (xy 175.126654 -311.12567) (xy 175.118611 -311.176452)
			(xy 175.102723 -311.225351) (xy 175.07938 -311.271163) (xy 175.049159 -311.312759) (xy 175.012803 -311.349115)
			(xy 174.971207 -311.379336) (xy 174.925395 -311.402679) (xy 174.876496 -311.418567) (xy 174.825714 -311.42661)
			(xy 174.774298 -311.42661) (xy 174.723516 -311.418567) (xy 174.674617 -311.402679) (xy 174.628805 -311.379336)
			(xy 174.587209 -311.349115) (xy 174.550853 -311.312759) (xy 174.520632 -311.271163) (xy 174.497289 -311.225351)
			(xy 174.481401 -311.176452) (xy 174.473358 -311.12567) (xy 174.15468 -311.12567) (xy 174.146964 -311.173146)
			(xy 174.13138 -311.219827) (xy 174.108509 -311.263404) (xy 174.078944 -311.302748) (xy 174.043451 -311.33684)
			(xy 174.002948 -311.364796) (xy 173.958486 -311.385894) (xy 173.911215 -311.399586) (xy 173.86236 -311.405518)
			(xy 173.813185 -311.403537) (xy 173.764966 -311.393693) (xy 173.71895 -311.376241) (xy 173.676329 -311.351634)
			(xy 173.638208 -311.320509) (xy 173.605573 -311.283672) (xy 173.57927 -311.242076) (xy 173.559979 -311.1968)
			(xy 173.548202 -311.149016) (xy 173.544242 -311.099962) (xy 173.227238 -311.099962) (xy 173.226734 -311.12567)
			(xy 173.218691 -311.176452) (xy 173.202803 -311.225351) (xy 173.17946 -311.271163) (xy 173.149239 -311.312759)
			(xy 173.112883 -311.349115) (xy 173.071287 -311.379336) (xy 173.025475 -311.402679) (xy 172.976576 -311.418567)
			(xy 172.925794 -311.42661) (xy 172.874378 -311.42661) (xy 172.823596 -311.418567) (xy 172.774697 -311.402679)
			(xy 172.728885 -311.379336) (xy 172.687289 -311.349115) (xy 172.650933 -311.312759) (xy 172.620712 -311.271163)
			(xy 172.597369 -311.225351) (xy 172.581481 -311.176452) (xy 172.573438 -311.12567) (xy 172.254506 -311.12567)
			(xy 172.24679 -311.173146) (xy 172.231206 -311.219827) (xy 172.208335 -311.263404) (xy 172.17877 -311.302748)
			(xy 172.143277 -311.33684) (xy 172.102774 -311.364796) (xy 172.058312 -311.385894) (xy 172.011041 -311.399586)
			(xy 171.962186 -311.405518) (xy 171.913011 -311.403537) (xy 171.864792 -311.393693) (xy 171.818776 -311.376241)
			(xy 171.776155 -311.351634) (xy 171.738034 -311.320509) (xy 171.705399 -311.283672) (xy 171.679096 -311.242076)
			(xy 171.659805 -311.1968) (xy 171.648028 -311.149016) (xy 171.644068 -311.099962) (xy 171.327064 -311.099962)
			(xy 171.32656 -311.12567) (xy 171.318517 -311.176452) (xy 171.302629 -311.225351) (xy 171.279286 -311.271163)
			(xy 171.249065 -311.312759) (xy 171.212709 -311.349115) (xy 171.171113 -311.379336) (xy 171.125301 -311.402679)
			(xy 171.076402 -311.418567) (xy 171.02562 -311.42661) (xy 170.974204 -311.42661) (xy 170.923422 -311.418567)
			(xy 170.874523 -311.402679) (xy 170.828711 -311.379336) (xy 170.787115 -311.349115) (xy 170.750759 -311.312759)
			(xy 170.720538 -311.271163) (xy 170.697195 -311.225351) (xy 170.681307 -311.176452) (xy 170.673264 -311.12567)
			(xy 170.354586 -311.12567) (xy 170.34687 -311.173146) (xy 170.331286 -311.219827) (xy 170.308415 -311.263404)
			(xy 170.27885 -311.302748) (xy 170.243357 -311.33684) (xy 170.202854 -311.364796) (xy 170.158392 -311.385894)
			(xy 170.111121 -311.399586) (xy 170.062266 -311.405518) (xy 170.013091 -311.403537) (xy 169.964872 -311.393693)
			(xy 169.918856 -311.376241) (xy 169.876235 -311.351634) (xy 169.838114 -311.320509) (xy 169.805479 -311.283672)
			(xy 169.779176 -311.242076) (xy 169.759885 -311.1968) (xy 169.748108 -311.149016) (xy 169.744148 -311.099962)
			(xy 169.427144 -311.099962) (xy 169.42664 -311.12567) (xy 169.418597 -311.176452) (xy 169.402709 -311.225351)
			(xy 169.379366 -311.271163) (xy 169.349145 -311.312759) (xy 169.312789 -311.349115) (xy 169.271193 -311.379336)
			(xy 169.225381 -311.402679) (xy 169.176482 -311.418567) (xy 169.1257 -311.42661) (xy 169.074284 -311.42661)
			(xy 169.023502 -311.418567) (xy 168.974603 -311.402679) (xy 168.928791 -311.379336) (xy 168.887195 -311.349115)
			(xy 168.850839 -311.312759) (xy 168.820618 -311.271163) (xy 168.797275 -311.225351) (xy 168.781387 -311.176452)
			(xy 168.773344 -311.12567) (xy 168.454666 -311.12567) (xy 168.44695 -311.173146) (xy 168.431366 -311.219827)
			(xy 168.408495 -311.263404) (xy 168.37893 -311.302748) (xy 168.343437 -311.33684) (xy 168.302934 -311.364796)
			(xy 168.258472 -311.385894) (xy 168.211201 -311.399586) (xy 168.162346 -311.405518) (xy 168.113171 -311.403537)
			(xy 168.064952 -311.393693) (xy 168.018936 -311.376241) (xy 167.976315 -311.351634) (xy 167.938194 -311.320509)
			(xy 167.905559 -311.283672) (xy 167.879256 -311.242076) (xy 167.859965 -311.1968) (xy 167.848188 -311.149016)
			(xy 167.844228 -311.099962) (xy 167.527224 -311.099962) (xy 167.52672 -311.12567) (xy 167.518677 -311.176452)
			(xy 167.502789 -311.225351) (xy 167.479446 -311.271163) (xy 167.449225 -311.312759) (xy 167.412869 -311.349115)
			(xy 167.371273 -311.379336) (xy 167.325461 -311.402679) (xy 167.276562 -311.418567) (xy 167.22578 -311.42661)
			(xy 167.174364 -311.42661) (xy 167.123582 -311.418567) (xy 167.074683 -311.402679) (xy 167.028871 -311.379336)
			(xy 166.987275 -311.349115) (xy 166.950919 -311.312759) (xy 166.920698 -311.271163) (xy 166.897355 -311.225351)
			(xy 166.881467 -311.176452) (xy 166.873424 -311.12567) (xy 166.554492 -311.12567) (xy 166.546776 -311.173146)
			(xy 166.531192 -311.219827) (xy 166.508321 -311.263404) (xy 166.478756 -311.302748) (xy 166.443263 -311.33684)
			(xy 166.40276 -311.364796) (xy 166.358298 -311.385894) (xy 166.311027 -311.399586) (xy 166.262172 -311.405518)
			(xy 166.212997 -311.403537) (xy 166.164778 -311.393693) (xy 166.118762 -311.376241) (xy 166.076141 -311.351634)
			(xy 166.03802 -311.320509) (xy 166.005385 -311.283672) (xy 165.979082 -311.242076) (xy 165.959791 -311.1968)
			(xy 165.948014 -311.149016) (xy 165.944054 -311.099962) (xy 165.605795 -311.099962) (xy 165.605798 -311.1)
			(xy 165.601626 -311.150349) (xy 165.589223 -311.199325) (xy 165.568929 -311.245592) (xy 165.541296 -311.287887)
			(xy 165.507078 -311.325057) (xy 165.467209 -311.356088) (xy 165.422776 -311.380134) (xy 165.374992 -311.396538)
			(xy 165.325159 -311.404853) (xy 165.299898 -311.40527) (xy 165.26764 -311.403492) (xy 165.256718 -311.402476)
			(xy 165.246558 -311.405778) (xy 165.241605 -311.407522) (xy 165.232514 -311.412777) (xy 165.228524 -311.416192)
			(xy 165.172136 -311.466738) (xy 165.167818 -311.471056) (xy 165.162845 -311.477255) (xy 165.15664 -311.491875)
			(xy 165.155626 -311.499758) (xy 165.155626 -311.500266) (xy 165.155372 -311.504584) (xy 165.155372 -311.566052)
			(xy 165.155626 -311.566306) (xy 165.155626 -311.574942) (xy 165.155465 -311.588596) (xy 165.153177 -311.615809)
			(xy 165.151054 -311.629298) (xy 165.149022 -311.641236) (xy 165.152578 -311.652666) (xy 165.15409 -311.657198)
			(xy 165.158561 -311.665639) (xy 165.161468 -311.66943) (xy 165.164262 -311.672478) (xy 165.22065 -311.731406)
			(xy 165.224876 -311.735642) (xy 165.234883 -311.742197) (xy 165.240462 -311.74436) (xy 165.251384 -311.74817)
			(xy 165.263576 -311.7469) (xy 165.27262 -311.745851) (xy 165.290794 -311.744708) (xy 165.299898 -311.744614)
			(xy 165.325154 -311.745106) (xy 165.374977 -311.75342) (xy 165.422752 -311.769821) (xy 165.467176 -311.793862)
			(xy 165.507038 -311.824887) (xy 165.541249 -311.86205) (xy 165.568876 -311.904337) (xy 165.589167 -311.950594)
			(xy 165.601567 -311.999561) (xy 165.605738 -312.0499) (xy 165.605736 -312.049922) (xy 165.944054 -312.049922)
			(xy 165.948014 -312.000868) (xy 165.959791 -311.953084) (xy 165.979082 -311.907808) (xy 166.005385 -311.866212)
			(xy 166.03802 -311.829375) (xy 166.076141 -311.79825) (xy 166.118762 -311.773643) (xy 166.164778 -311.756191)
			(xy 166.212997 -311.746347) (xy 166.262172 -311.744366) (xy 166.311027 -311.750298) (xy 166.358298 -311.76399)
			(xy 166.40276 -311.785088) (xy 166.443263 -311.813044) (xy 166.478756 -311.847136) (xy 166.508321 -311.88648)
			(xy 166.531192 -311.930057) (xy 166.546776 -311.976738) (xy 166.554671 -312.025315) (xy 166.555166 -312.049922)
			(xy 166.554671 -312.074529) (xy 166.554492 -312.07563) (xy 166.873424 -312.07563) (xy 166.873424 -312.024214)
			(xy 166.881467 -311.973432) (xy 166.897355 -311.924533) (xy 166.920698 -311.878721) (xy 166.950919 -311.837125)
			(xy 166.987275 -311.800769) (xy 167.028871 -311.770548) (xy 167.074683 -311.747205) (xy 167.123582 -311.731317)
			(xy 167.174364 -311.723274) (xy 167.22578 -311.723274) (xy 167.276562 -311.731317) (xy 167.325461 -311.747205)
			(xy 167.371273 -311.770548) (xy 167.412869 -311.800769) (xy 167.449225 -311.837125) (xy 167.479446 -311.878721)
			(xy 167.502789 -311.924533) (xy 167.518677 -311.973432) (xy 167.52672 -312.024214) (xy 167.527224 -312.049922)
			(xy 167.844228 -312.049922) (xy 167.848188 -312.000868) (xy 167.859965 -311.953084) (xy 167.879256 -311.907808)
			(xy 167.905559 -311.866212) (xy 167.938194 -311.829375) (xy 167.976315 -311.79825) (xy 168.018936 -311.773643)
			(xy 168.064952 -311.756191) (xy 168.113171 -311.746347) (xy 168.162346 -311.744366) (xy 168.211201 -311.750298)
			(xy 168.258472 -311.76399) (xy 168.302934 -311.785088) (xy 168.343437 -311.813044) (xy 168.37893 -311.847136)
			(xy 168.408495 -311.88648) (xy 168.431366 -311.930057) (xy 168.44695 -311.976738) (xy 168.454845 -312.025315)
			(xy 168.45534 -312.049922) (xy 168.454845 -312.074529) (xy 168.454666 -312.07563) (xy 168.773344 -312.07563)
			(xy 168.773344 -312.024214) (xy 168.781387 -311.973432) (xy 168.797275 -311.924533) (xy 168.820618 -311.878721)
			(xy 168.850839 -311.837125) (xy 168.887195 -311.800769) (xy 168.928791 -311.770548) (xy 168.974603 -311.747205)
			(xy 169.023502 -311.731317) (xy 169.074284 -311.723274) (xy 169.1257 -311.723274) (xy 169.176482 -311.731317)
			(xy 169.225381 -311.747205) (xy 169.271193 -311.770548) (xy 169.312789 -311.800769) (xy 169.349145 -311.837125)
			(xy 169.379366 -311.878721) (xy 169.402709 -311.924533) (xy 169.418597 -311.973432) (xy 169.42664 -312.024214)
			(xy 169.427144 -312.049922) (xy 169.744148 -312.049922) (xy 169.748108 -312.000868) (xy 169.759885 -311.953084)
			(xy 169.779176 -311.907808) (xy 169.805479 -311.866212) (xy 169.838114 -311.829375) (xy 169.876235 -311.79825)
			(xy 169.918856 -311.773643) (xy 169.964872 -311.756191) (xy 170.013091 -311.746347) (xy 170.062266 -311.744366)
			(xy 170.111121 -311.750298) (xy 170.158392 -311.76399) (xy 170.202854 -311.785088) (xy 170.243357 -311.813044)
			(xy 170.27885 -311.847136) (xy 170.308415 -311.88648) (xy 170.331286 -311.930057) (xy 170.34687 -311.976738)
			(xy 170.354765 -312.025315) (xy 170.35526 -312.049922) (xy 170.354765 -312.074529) (xy 170.354586 -312.07563)
			(xy 170.673264 -312.07563) (xy 170.673264 -312.024214) (xy 170.681307 -311.973432) (xy 170.697195 -311.924533)
			(xy 170.720538 -311.878721) (xy 170.750759 -311.837125) (xy 170.787115 -311.800769) (xy 170.828711 -311.770548)
			(xy 170.874523 -311.747205) (xy 170.923422 -311.731317) (xy 170.974204 -311.723274) (xy 171.02562 -311.723274)
			(xy 171.076402 -311.731317) (xy 171.125301 -311.747205) (xy 171.171113 -311.770548) (xy 171.212709 -311.800769)
			(xy 171.249065 -311.837125) (xy 171.279286 -311.878721) (xy 171.302629 -311.924533) (xy 171.318517 -311.973432)
			(xy 171.32656 -312.024214) (xy 171.327064 -312.049922) (xy 171.644068 -312.049922) (xy 171.648028 -312.000868)
			(xy 171.659805 -311.953084) (xy 171.679096 -311.907808) (xy 171.705399 -311.866212) (xy 171.738034 -311.829375)
			(xy 171.776155 -311.79825) (xy 171.818776 -311.773643) (xy 171.864792 -311.756191) (xy 171.913011 -311.746347)
			(xy 171.962186 -311.744366) (xy 172.011041 -311.750298) (xy 172.058312 -311.76399) (xy 172.102774 -311.785088)
			(xy 172.143277 -311.813044) (xy 172.17877 -311.847136) (xy 172.208335 -311.88648) (xy 172.231206 -311.930057)
			(xy 172.24679 -311.976738) (xy 172.254685 -312.025315) (xy 172.25518 -312.049922) (xy 172.254685 -312.074529)
			(xy 172.254506 -312.07563) (xy 172.573438 -312.07563) (xy 172.573438 -312.024214) (xy 172.581481 -311.973432)
			(xy 172.597369 -311.924533) (xy 172.620712 -311.878721) (xy 172.650933 -311.837125) (xy 172.687289 -311.800769)
			(xy 172.728885 -311.770548) (xy 172.774697 -311.747205) (xy 172.823596 -311.731317) (xy 172.874378 -311.723274)
			(xy 172.925794 -311.723274) (xy 172.976576 -311.731317) (xy 173.025475 -311.747205) (xy 173.071287 -311.770548)
			(xy 173.112883 -311.800769) (xy 173.149239 -311.837125) (xy 173.17946 -311.878721) (xy 173.202803 -311.924533)
			(xy 173.218691 -311.973432) (xy 173.226734 -312.024214) (xy 173.227238 -312.049922) (xy 173.544242 -312.049922)
			(xy 173.548202 -312.000868) (xy 173.559979 -311.953084) (xy 173.57927 -311.907808) (xy 173.605573 -311.866212)
			(xy 173.638208 -311.829375) (xy 173.676329 -311.79825) (xy 173.71895 -311.773643) (xy 173.764966 -311.756191)
			(xy 173.813185 -311.746347) (xy 173.86236 -311.744366) (xy 173.911215 -311.750298) (xy 173.958486 -311.76399)
			(xy 174.002948 -311.785088) (xy 174.043451 -311.813044) (xy 174.078944 -311.847136) (xy 174.108509 -311.88648)
			(xy 174.13138 -311.930057) (xy 174.146964 -311.976738) (xy 174.154859 -312.025315) (xy 174.155354 -312.049922)
			(xy 174.154859 -312.074529) (xy 174.15468 -312.07563) (xy 174.473358 -312.07563) (xy 174.473358 -312.024214)
			(xy 174.481401 -311.973432) (xy 174.497289 -311.924533) (xy 174.520632 -311.878721) (xy 174.550853 -311.837125)
			(xy 174.587209 -311.800769) (xy 174.628805 -311.770548) (xy 174.674617 -311.747205) (xy 174.723516 -311.731317)
			(xy 174.774298 -311.723274) (xy 174.825714 -311.723274) (xy 174.876496 -311.731317) (xy 174.925395 -311.747205)
			(xy 174.971207 -311.770548) (xy 175.012803 -311.800769) (xy 175.049159 -311.837125) (xy 175.07938 -311.878721)
			(xy 175.102723 -311.924533) (xy 175.118611 -311.973432) (xy 175.126654 -312.024214) (xy 175.127158 -312.049922)
			(xy 175.444162 -312.049922) (xy 175.448122 -312.000868) (xy 175.459899 -311.953084) (xy 175.47919 -311.907808)
			(xy 175.505493 -311.866212) (xy 175.538128 -311.829375) (xy 175.576249 -311.79825) (xy 175.61887 -311.773643)
			(xy 175.664886 -311.756191) (xy 175.713105 -311.746347) (xy 175.76228 -311.744366) (xy 175.811135 -311.750298)
			(xy 175.858406 -311.76399) (xy 175.902868 -311.785088) (xy 175.943371 -311.813044) (xy 175.978864 -311.847136)
			(xy 176.008429 -311.88648) (xy 176.0313 -311.930057) (xy 176.046884 -311.976738) (xy 176.054779 -312.025315)
			(xy 176.055274 -312.049922) (xy 176.054779 -312.074529) (xy 176.0546 -312.07563) (xy 176.373278 -312.07563)
			(xy 176.373278 -312.024214) (xy 176.381321 -311.973432) (xy 176.397209 -311.924533) (xy 176.420552 -311.878721)
			(xy 176.450773 -311.837125) (xy 176.487129 -311.800769) (xy 176.528725 -311.770548) (xy 176.574537 -311.747205)
			(xy 176.623436 -311.731317) (xy 176.674218 -311.723274) (xy 176.725634 -311.723274) (xy 176.776416 -311.731317)
			(xy 176.825315 -311.747205) (xy 176.871127 -311.770548) (xy 176.912723 -311.800769) (xy 176.949079 -311.837125)
			(xy 176.9793 -311.878721) (xy 177.002643 -311.924533) (xy 177.018531 -311.973432) (xy 177.026574 -312.024214)
			(xy 177.027078 -312.049922) (xy 177.344082 -312.049922) (xy 177.348042 -312.000868) (xy 177.359819 -311.953084)
			(xy 177.37911 -311.907808) (xy 177.405413 -311.866212) (xy 177.438048 -311.829375) (xy 177.476169 -311.79825)
			(xy 177.51879 -311.773643) (xy 177.564806 -311.756191) (xy 177.613025 -311.746347) (xy 177.6622 -311.744366)
			(xy 177.711055 -311.750298) (xy 177.758326 -311.76399) (xy 177.802788 -311.785088) (xy 177.843291 -311.813044)
			(xy 177.878784 -311.847136) (xy 177.908349 -311.88648) (xy 177.93122 -311.930057) (xy 177.946804 -311.976738)
			(xy 177.954699 -312.025315) (xy 177.955194 -312.049922) (xy 177.954699 -312.074529) (xy 177.95452 -312.07563)
			(xy 178.273198 -312.07563) (xy 178.273198 -312.024214) (xy 178.281241 -311.973432) (xy 178.297129 -311.924533)
			(xy 178.320472 -311.878721) (xy 178.350693 -311.837125) (xy 178.387049 -311.800769) (xy 178.428645 -311.770548)
			(xy 178.474457 -311.747205) (xy 178.523356 -311.731317) (xy 178.574138 -311.723274) (xy 178.625554 -311.723274)
			(xy 178.676336 -311.731317) (xy 178.725235 -311.747205) (xy 178.771047 -311.770548) (xy 178.812643 -311.800769)
			(xy 178.848999 -311.837125) (xy 178.87922 -311.878721) (xy 178.902563 -311.924533) (xy 178.918451 -311.973432)
			(xy 178.926494 -312.024214) (xy 178.926998 -312.049922) (xy 179.244256 -312.049922) (xy 179.248216 -312.000868)
			(xy 179.259993 -311.953084) (xy 179.279284 -311.907808) (xy 179.305587 -311.866212) (xy 179.338222 -311.829375)
			(xy 179.376343 -311.79825) (xy 179.418964 -311.773643) (xy 179.46498 -311.756191) (xy 179.513199 -311.746347)
			(xy 179.562374 -311.744366) (xy 179.611229 -311.750298) (xy 179.6585 -311.76399) (xy 179.702962 -311.785088)
			(xy 179.743465 -311.813044) (xy 179.778958 -311.847136) (xy 179.808523 -311.88648) (xy 179.831394 -311.930057)
			(xy 179.846978 -311.976738) (xy 179.854873 -312.025315) (xy 179.855368 -312.049922) (xy 179.854873 -312.074529)
			(xy 179.854694 -312.07563) (xy 180.173372 -312.07563) (xy 180.173372 -312.024214) (xy 180.181415 -311.973432)
			(xy 180.197303 -311.924533) (xy 180.220646 -311.878721) (xy 180.250867 -311.837125) (xy 180.287223 -311.800769)
			(xy 180.328819 -311.770548) (xy 180.374631 -311.747205) (xy 180.42353 -311.731317) (xy 180.474312 -311.723274)
			(xy 180.525728 -311.723274) (xy 180.57651 -311.731317) (xy 180.625409 -311.747205) (xy 180.671221 -311.770548)
			(xy 180.712817 -311.800769) (xy 180.749173 -311.837125) (xy 180.779394 -311.878721) (xy 180.802737 -311.924533)
			(xy 180.818625 -311.973432) (xy 180.826668 -312.024214) (xy 180.827172 -312.049922) (xy 181.144176 -312.049922)
			(xy 181.148136 -312.000868) (xy 181.159913 -311.953084) (xy 181.179204 -311.907808) (xy 181.205507 -311.866212)
			(xy 181.238142 -311.829375) (xy 181.276263 -311.79825) (xy 181.318884 -311.773643) (xy 181.3649 -311.756191)
			(xy 181.413119 -311.746347) (xy 181.462294 -311.744366) (xy 181.511149 -311.750298) (xy 181.55842 -311.76399)
			(xy 181.602882 -311.785088) (xy 181.643385 -311.813044) (xy 181.678878 -311.847136) (xy 181.708443 -311.88648)
			(xy 181.731314 -311.930057) (xy 181.746898 -311.976738) (xy 181.754793 -312.025315) (xy 181.755288 -312.049922)
			(xy 182.094136 -312.049922) (xy 182.098096 -312.000868) (xy 182.109873 -311.953084) (xy 182.129164 -311.907808)
			(xy 182.155467 -311.866212) (xy 182.188102 -311.829375) (xy 182.226223 -311.79825) (xy 182.268844 -311.773643)
			(xy 182.31486 -311.756191) (xy 182.363079 -311.746347) (xy 182.412254 -311.744366) (xy 182.461109 -311.750298)
			(xy 182.50838 -311.76399) (xy 182.552842 -311.785088) (xy 182.593345 -311.813044) (xy 182.628838 -311.847136)
			(xy 182.658403 -311.88648) (xy 182.681274 -311.930057) (xy 182.696858 -311.976738) (xy 182.704753 -312.025315)
			(xy 182.705248 -312.049922) (xy 183.044096 -312.049922) (xy 183.048056 -312.000868) (xy 183.059833 -311.953084)
			(xy 183.079124 -311.907808) (xy 183.105427 -311.866212) (xy 183.138062 -311.829375) (xy 183.176183 -311.79825)
			(xy 183.218804 -311.773643) (xy 183.26482 -311.756191) (xy 183.313039 -311.746347) (xy 183.362214 -311.744366)
			(xy 183.411069 -311.750298) (xy 183.45834 -311.76399) (xy 183.502802 -311.785088) (xy 183.543305 -311.813044)
			(xy 183.578798 -311.847136) (xy 183.608363 -311.88648) (xy 183.631234 -311.930057) (xy 183.646818 -311.976738)
			(xy 183.654713 -312.025315) (xy 183.655208 -312.049922) (xy 183.994056 -312.049922) (xy 183.998016 -312.000868)
			(xy 184.009793 -311.953084) (xy 184.029084 -311.907808) (xy 184.055387 -311.866212) (xy 184.088022 -311.829375)
			(xy 184.126143 -311.79825) (xy 184.168764 -311.773643) (xy 184.21478 -311.756191) (xy 184.262999 -311.746347)
			(xy 184.312174 -311.744366) (xy 184.361029 -311.750298) (xy 184.4083 -311.76399) (xy 184.452762 -311.785088)
			(xy 184.493265 -311.813044) (xy 184.528758 -311.847136) (xy 184.558323 -311.88648) (xy 184.581194 -311.930057)
			(xy 184.596778 -311.976738) (xy 184.604673 -312.025315) (xy 184.605168 -312.049922) (xy 184.94427 -312.049922)
			(xy 184.94823 -312.000868) (xy 184.960007 -311.953084) (xy 184.979298 -311.907808) (xy 185.005601 -311.866212)
			(xy 185.038236 -311.829375) (xy 185.076357 -311.79825) (xy 185.118978 -311.773643) (xy 185.164994 -311.756191)
			(xy 185.213213 -311.746347) (xy 185.262388 -311.744366) (xy 185.311243 -311.750298) (xy 185.358514 -311.76399)
			(xy 185.402976 -311.785088) (xy 185.443479 -311.813044) (xy 185.478972 -311.847136) (xy 185.508537 -311.88648)
			(xy 185.531408 -311.930057) (xy 185.546992 -311.976738) (xy 185.554887 -312.025315) (xy 185.555382 -312.049922)
			(xy 185.89423 -312.049922) (xy 185.89819 -312.000868) (xy 185.909967 -311.953084) (xy 185.929258 -311.907808)
			(xy 185.955561 -311.866212) (xy 185.988196 -311.829375) (xy 186.026317 -311.79825) (xy 186.068938 -311.773643)
			(xy 186.114954 -311.756191) (xy 186.163173 -311.746347) (xy 186.212348 -311.744366) (xy 186.261203 -311.750298)
			(xy 186.308474 -311.76399) (xy 186.352936 -311.785088) (xy 186.393439 -311.813044) (xy 186.428932 -311.847136)
			(xy 186.458497 -311.88648) (xy 186.481368 -311.930057) (xy 186.496952 -311.976738) (xy 186.504847 -312.025315)
			(xy 186.505342 -312.049922) (xy 186.84419 -312.049922) (xy 186.84815 -312.000868) (xy 186.859927 -311.953084)
			(xy 186.879218 -311.907808) (xy 186.905521 -311.866212) (xy 186.938156 -311.829375) (xy 186.976277 -311.79825)
			(xy 187.018898 -311.773643) (xy 187.064914 -311.756191) (xy 187.113133 -311.746347) (xy 187.162308 -311.744366)
			(xy 187.211163 -311.750298) (xy 187.258434 -311.76399) (xy 187.302896 -311.785088) (xy 187.343399 -311.813044)
			(xy 187.378892 -311.847136) (xy 187.408457 -311.88648) (xy 187.431328 -311.930057) (xy 187.446912 -311.976738)
			(xy 187.454807 -312.025315) (xy 187.455302 -312.049922) (xy 187.79415 -312.049922) (xy 187.79811 -312.000868)
			(xy 187.809887 -311.953084) (xy 187.829178 -311.907808) (xy 187.855481 -311.866212) (xy 187.888116 -311.829375)
			(xy 187.926237 -311.79825) (xy 187.968858 -311.773643) (xy 188.014874 -311.756191) (xy 188.063093 -311.746347)
			(xy 188.112268 -311.744366) (xy 188.161123 -311.750298) (xy 188.208394 -311.76399) (xy 188.252856 -311.785088)
			(xy 188.293359 -311.813044) (xy 188.328852 -311.847136) (xy 188.358417 -311.88648) (xy 188.381288 -311.930057)
			(xy 188.396872 -311.976738) (xy 188.404767 -312.025315) (xy 188.405262 -312.049922) (xy 188.74411 -312.049922)
			(xy 188.74807 -312.000868) (xy 188.759847 -311.953084) (xy 188.779138 -311.907808) (xy 188.805441 -311.866212)
			(xy 188.838076 -311.829375) (xy 188.876197 -311.79825) (xy 188.918818 -311.773643) (xy 188.964834 -311.756191)
			(xy 189.013053 -311.746347) (xy 189.062228 -311.744366) (xy 189.111083 -311.750298) (xy 189.158354 -311.76399)
			(xy 189.202816 -311.785088) (xy 189.243319 -311.813044) (xy 189.278812 -311.847136) (xy 189.308377 -311.88648)
			(xy 189.331248 -311.930057) (xy 189.346832 -311.976738) (xy 189.354727 -312.025315) (xy 189.355222 -312.049922)
			(xy 189.354727 -312.074529) (xy 189.354548 -312.07563) (xy 189.673226 -312.07563) (xy 189.673226 -312.024214)
			(xy 189.681269 -311.973432) (xy 189.697157 -311.924533) (xy 189.7205 -311.878721) (xy 189.750721 -311.837125)
			(xy 189.787077 -311.800769) (xy 189.828673 -311.770548) (xy 189.874485 -311.747205) (xy 189.923384 -311.731317)
			(xy 189.974166 -311.723274) (xy 190.025582 -311.723274) (xy 190.076364 -311.731317) (xy 190.125263 -311.747205)
			(xy 190.171075 -311.770548) (xy 190.212671 -311.800769) (xy 190.249027 -311.837125) (xy 190.279248 -311.878721)
			(xy 190.302591 -311.924533) (xy 190.318479 -311.973432) (xy 190.326522 -312.024214) (xy 190.327026 -312.049922)
			(xy 190.644284 -312.049922) (xy 190.648244 -312.000868) (xy 190.660021 -311.953084) (xy 190.679312 -311.907808)
			(xy 190.705615 -311.866212) (xy 190.73825 -311.829375) (xy 190.776371 -311.79825) (xy 190.818992 -311.773643)
			(xy 190.865008 -311.756191) (xy 190.913227 -311.746347) (xy 190.962402 -311.744366) (xy 191.011257 -311.750298)
			(xy 191.058528 -311.76399) (xy 191.10299 -311.785088) (xy 191.143493 -311.813044) (xy 191.178986 -311.847136)
			(xy 191.208551 -311.88648) (xy 191.231422 -311.930057) (xy 191.247006 -311.976738) (xy 191.254901 -312.025315)
			(xy 191.255396 -312.049922) (xy 191.254901 -312.074529) (xy 191.254722 -312.07563) (xy 191.5734 -312.07563)
			(xy 191.5734 -312.024214) (xy 191.581443 -311.973432) (xy 191.597331 -311.924533) (xy 191.620674 -311.878721)
			(xy 191.650895 -311.837125) (xy 191.687251 -311.800769) (xy 191.728847 -311.770548) (xy 191.774659 -311.747205)
			(xy 191.823558 -311.731317) (xy 191.87434 -311.723274) (xy 191.925756 -311.723274) (xy 191.976538 -311.731317)
			(xy 192.025437 -311.747205) (xy 192.071249 -311.770548) (xy 192.112845 -311.800769) (xy 192.149201 -311.837125)
			(xy 192.179422 -311.878721) (xy 192.202765 -311.924533) (xy 192.218653 -311.973432) (xy 192.226696 -312.024214)
			(xy 192.2272 -312.049922) (xy 192.544204 -312.049922) (xy 192.548164 -312.000868) (xy 192.559941 -311.953084)
			(xy 192.579232 -311.907808) (xy 192.605535 -311.866212) (xy 192.63817 -311.829375) (xy 192.676291 -311.79825)
			(xy 192.718912 -311.773643) (xy 192.764928 -311.756191) (xy 192.813147 -311.746347) (xy 192.862322 -311.744366)
			(xy 192.911177 -311.750298) (xy 192.958448 -311.76399) (xy 193.00291 -311.785088) (xy 193.043413 -311.813044)
			(xy 193.078906 -311.847136) (xy 193.108471 -311.88648) (xy 193.131342 -311.930057) (xy 193.146926 -311.976738)
			(xy 193.154821 -312.025315) (xy 193.155316 -312.049922) (xy 193.154821 -312.074529) (xy 193.154642 -312.07563)
			(xy 193.47332 -312.07563) (xy 193.47332 -312.024214) (xy 193.481363 -311.973432) (xy 193.497251 -311.924533)
			(xy 193.520594 -311.878721) (xy 193.550815 -311.837125) (xy 193.587171 -311.800769) (xy 193.628767 -311.770548)
			(xy 193.674579 -311.747205) (xy 193.723478 -311.731317) (xy 193.77426 -311.723274) (xy 193.825676 -311.723274)
			(xy 193.876458 -311.731317) (xy 193.925357 -311.747205) (xy 193.971169 -311.770548) (xy 194.012765 -311.800769)
			(xy 194.049121 -311.837125) (xy 194.079342 -311.878721) (xy 194.102685 -311.924533) (xy 194.118573 -311.973432)
			(xy 194.126616 -312.024214) (xy 194.12712 -312.049922) (xy 194.444124 -312.049922) (xy 194.448084 -312.000868)
			(xy 194.459861 -311.953084) (xy 194.479152 -311.907808) (xy 194.505455 -311.866212) (xy 194.53809 -311.829375)
			(xy 194.576211 -311.79825) (xy 194.618832 -311.773643) (xy 194.664848 -311.756191) (xy 194.713067 -311.746347)
			(xy 194.762242 -311.744366) (xy 194.811097 -311.750298) (xy 194.858368 -311.76399) (xy 194.90283 -311.785088)
			(xy 194.943333 -311.813044) (xy 194.978826 -311.847136) (xy 195.008391 -311.88648) (xy 195.031262 -311.930057)
			(xy 195.046846 -311.976738) (xy 195.054741 -312.025315) (xy 195.055236 -312.049922) (xy 195.054741 -312.074529)
			(xy 195.054562 -312.07563) (xy 195.37324 -312.07563) (xy 195.37324 -312.024214) (xy 195.381283 -311.973432)
			(xy 195.397171 -311.924533) (xy 195.420514 -311.878721) (xy 195.450735 -311.837125) (xy 195.487091 -311.800769)
			(xy 195.528687 -311.770548) (xy 195.574499 -311.747205) (xy 195.623398 -311.731317) (xy 195.67418 -311.723274)
			(xy 195.725596 -311.723274) (xy 195.776378 -311.731317) (xy 195.825277 -311.747205) (xy 195.871089 -311.770548)
			(xy 195.912685 -311.800769) (xy 195.949041 -311.837125) (xy 195.979262 -311.878721) (xy 196.002605 -311.924533)
			(xy 196.018493 -311.973432) (xy 196.026536 -312.024214) (xy 196.02704 -312.049922) (xy 196.344044 -312.049922)
			(xy 196.348004 -312.000868) (xy 196.359781 -311.953084) (xy 196.379072 -311.907808) (xy 196.405375 -311.866212)
			(xy 196.43801 -311.829375) (xy 196.476131 -311.79825) (xy 196.518752 -311.773643) (xy 196.564768 -311.756191)
			(xy 196.612987 -311.746347) (xy 196.662162 -311.744366) (xy 196.711017 -311.750298) (xy 196.758288 -311.76399)
			(xy 196.80275 -311.785088) (xy 196.843253 -311.813044) (xy 196.878746 -311.847136) (xy 196.908311 -311.88648)
			(xy 196.931182 -311.930057) (xy 196.946766 -311.976738) (xy 196.954661 -312.025315) (xy 196.955156 -312.049922)
			(xy 196.954661 -312.074529) (xy 196.954482 -312.07563) (xy 197.273414 -312.07563) (xy 197.273414 -312.024214)
			(xy 197.281457 -311.973432) (xy 197.297345 -311.924533) (xy 197.320688 -311.878721) (xy 197.350909 -311.837125)
			(xy 197.387265 -311.800769) (xy 197.428861 -311.770548) (xy 197.474673 -311.747205) (xy 197.523572 -311.731317)
			(xy 197.574354 -311.723274) (xy 197.62577 -311.723274) (xy 197.676552 -311.731317) (xy 197.725451 -311.747205)
			(xy 197.771263 -311.770548) (xy 197.812859 -311.800769) (xy 197.849215 -311.837125) (xy 197.879436 -311.878721)
			(xy 197.902779 -311.924533) (xy 197.918667 -311.973432) (xy 197.92671 -312.024214) (xy 197.927214 -312.049922)
			(xy 197.92671 -312.07563) (xy 198.223374 -312.07563) (xy 198.223374 -312.024214) (xy 198.231417 -311.973432)
			(xy 198.247305 -311.924533) (xy 198.270648 -311.878721) (xy 198.300869 -311.837125) (xy 198.337225 -311.800769)
			(xy 198.378821 -311.770548) (xy 198.424633 -311.747205) (xy 198.473532 -311.731317) (xy 198.524314 -311.723274)
			(xy 198.57573 -311.723274) (xy 198.626512 -311.731317) (xy 198.675411 -311.747205) (xy 198.721223 -311.770548)
			(xy 198.762819 -311.800769) (xy 198.799175 -311.837125) (xy 198.829396 -311.878721) (xy 198.852739 -311.924533)
			(xy 198.868627 -311.973432) (xy 198.87667 -312.024214) (xy 198.877174 -312.049922) (xy 199.194432 -312.049922)
			(xy 199.198392 -312.000868) (xy 199.210169 -311.953084) (xy 199.22946 -311.907808) (xy 199.255763 -311.866212)
			(xy 199.288398 -311.829375) (xy 199.326519 -311.79825) (xy 199.36914 -311.773643) (xy 199.415156 -311.756191)
			(xy 199.463375 -311.746347) (xy 199.51255 -311.744366) (xy 199.561405 -311.750298) (xy 199.608676 -311.76399)
			(xy 199.653138 -311.785088) (xy 199.693641 -311.813044) (xy 199.729134 -311.847136) (xy 199.758699 -311.88648)
			(xy 199.78157 -311.930057) (xy 199.797154 -311.976738) (xy 199.805049 -312.025315) (xy 199.805544 -312.049922)
			(xy 199.805049 -312.074529) (xy 199.797154 -312.123106) (xy 199.78157 -312.169787) (xy 199.758699 -312.213364)
			(xy 199.729134 -312.252708) (xy 199.693641 -312.2868) (xy 199.653138 -312.314756) (xy 199.608676 -312.335854)
			(xy 199.561405 -312.349546) (xy 199.51255 -312.355478) (xy 199.463375 -312.353497) (xy 199.415156 -312.343653)
			(xy 199.36914 -312.326201) (xy 199.326519 -312.301594) (xy 199.288398 -312.270469) (xy 199.255763 -312.233632)
			(xy 199.22946 -312.192036) (xy 199.210169 -312.14676) (xy 199.198392 -312.098976) (xy 199.194432 -312.049922)
			(xy 198.877174 -312.049922) (xy 198.87667 -312.07563) (xy 198.868627 -312.126412) (xy 198.852739 -312.175311)
			(xy 198.829396 -312.221123) (xy 198.799175 -312.262719) (xy 198.762819 -312.299075) (xy 198.721223 -312.329296)
			(xy 198.675411 -312.352639) (xy 198.626512 -312.368527) (xy 198.57573 -312.37657) (xy 198.524314 -312.37657)
			(xy 198.473532 -312.368527) (xy 198.424633 -312.352639) (xy 198.378821 -312.329296) (xy 198.337225 -312.299075)
			(xy 198.300869 -312.262719) (xy 198.270648 -312.221123) (xy 198.247305 -312.175311) (xy 198.231417 -312.126412)
			(xy 198.223374 -312.07563) (xy 197.92671 -312.07563) (xy 197.918667 -312.126412) (xy 197.902779 -312.175311)
			(xy 197.879436 -312.221123) (xy 197.849215 -312.262719) (xy 197.812859 -312.299075) (xy 197.771263 -312.329296)
			(xy 197.725451 -312.352639) (xy 197.676552 -312.368527) (xy 197.62577 -312.37657) (xy 197.574354 -312.37657)
			(xy 197.523572 -312.368527) (xy 197.474673 -312.352639) (xy 197.428861 -312.329296) (xy 197.387265 -312.299075)
			(xy 197.350909 -312.262719) (xy 197.320688 -312.221123) (xy 197.297345 -312.175311) (xy 197.281457 -312.126412)
			(xy 197.273414 -312.07563) (xy 196.954482 -312.07563) (xy 196.946766 -312.123106) (xy 196.931182 -312.169787)
			(xy 196.908311 -312.213364) (xy 196.878746 -312.252708) (xy 196.843253 -312.2868) (xy 196.80275 -312.314756)
			(xy 196.758288 -312.335854) (xy 196.711017 -312.349546) (xy 196.662162 -312.355478) (xy 196.612987 -312.353497)
			(xy 196.564768 -312.343653) (xy 196.518752 -312.326201) (xy 196.476131 -312.301594) (xy 196.43801 -312.270469)
			(xy 196.405375 -312.233632) (xy 196.379072 -312.192036) (xy 196.359781 -312.14676) (xy 196.348004 -312.098976)
			(xy 196.344044 -312.049922) (xy 196.02704 -312.049922) (xy 196.026536 -312.07563) (xy 196.018493 -312.126412)
			(xy 196.002605 -312.175311) (xy 195.979262 -312.221123) (xy 195.949041 -312.262719) (xy 195.912685 -312.299075)
			(xy 195.871089 -312.329296) (xy 195.825277 -312.352639) (xy 195.776378 -312.368527) (xy 195.725596 -312.37657)
			(xy 195.67418 -312.37657) (xy 195.623398 -312.368527) (xy 195.574499 -312.352639) (xy 195.528687 -312.329296)
			(xy 195.487091 -312.299075) (xy 195.450735 -312.262719) (xy 195.420514 -312.221123) (xy 195.397171 -312.175311)
			(xy 195.381283 -312.126412) (xy 195.37324 -312.07563) (xy 195.054562 -312.07563) (xy 195.046846 -312.123106)
			(xy 195.031262 -312.169787) (xy 195.008391 -312.213364) (xy 194.978826 -312.252708) (xy 194.943333 -312.2868)
			(xy 194.90283 -312.314756) (xy 194.858368 -312.335854) (xy 194.811097 -312.349546) (xy 194.762242 -312.355478)
			(xy 194.713067 -312.353497) (xy 194.664848 -312.343653) (xy 194.618832 -312.326201) (xy 194.576211 -312.301594)
			(xy 194.53809 -312.270469) (xy 194.505455 -312.233632) (xy 194.479152 -312.192036) (xy 194.459861 -312.14676)
			(xy 194.448084 -312.098976) (xy 194.444124 -312.049922) (xy 194.12712 -312.049922) (xy 194.126616 -312.07563)
			(xy 194.118573 -312.126412) (xy 194.102685 -312.175311) (xy 194.079342 -312.221123) (xy 194.049121 -312.262719)
			(xy 194.012765 -312.299075) (xy 193.971169 -312.329296) (xy 193.925357 -312.352639) (xy 193.876458 -312.368527)
			(xy 193.825676 -312.37657) (xy 193.77426 -312.37657) (xy 193.723478 -312.368527) (xy 193.674579 -312.352639)
			(xy 193.628767 -312.329296) (xy 193.587171 -312.299075) (xy 193.550815 -312.262719) (xy 193.520594 -312.221123)
			(xy 193.497251 -312.175311) (xy 193.481363 -312.126412) (xy 193.47332 -312.07563) (xy 193.154642 -312.07563)
			(xy 193.146926 -312.123106) (xy 193.131342 -312.169787) (xy 193.108471 -312.213364) (xy 193.078906 -312.252708)
			(xy 193.043413 -312.2868) (xy 193.00291 -312.314756) (xy 192.958448 -312.335854) (xy 192.911177 -312.349546)
			(xy 192.862322 -312.355478) (xy 192.813147 -312.353497) (xy 192.764928 -312.343653) (xy 192.718912 -312.326201)
			(xy 192.676291 -312.301594) (xy 192.63817 -312.270469) (xy 192.605535 -312.233632) (xy 192.579232 -312.192036)
			(xy 192.559941 -312.14676) (xy 192.548164 -312.098976) (xy 192.544204 -312.049922) (xy 192.2272 -312.049922)
			(xy 192.226696 -312.07563) (xy 192.218653 -312.126412) (xy 192.202765 -312.175311) (xy 192.179422 -312.221123)
			(xy 192.149201 -312.262719) (xy 192.112845 -312.299075) (xy 192.071249 -312.329296) (xy 192.025437 -312.352639)
			(xy 191.976538 -312.368527) (xy 191.925756 -312.37657) (xy 191.87434 -312.37657) (xy 191.823558 -312.368527)
			(xy 191.774659 -312.352639) (xy 191.728847 -312.329296) (xy 191.687251 -312.299075) (xy 191.650895 -312.262719)
			(xy 191.620674 -312.221123) (xy 191.597331 -312.175311) (xy 191.581443 -312.126412) (xy 191.5734 -312.07563)
			(xy 191.254722 -312.07563) (xy 191.247006 -312.123106) (xy 191.231422 -312.169787) (xy 191.208551 -312.213364)
			(xy 191.178986 -312.252708) (xy 191.143493 -312.2868) (xy 191.10299 -312.314756) (xy 191.058528 -312.335854)
			(xy 191.011257 -312.349546) (xy 190.962402 -312.355478) (xy 190.913227 -312.353497) (xy 190.865008 -312.343653)
			(xy 190.818992 -312.326201) (xy 190.776371 -312.301594) (xy 190.73825 -312.270469) (xy 190.705615 -312.233632)
			(xy 190.679312 -312.192036) (xy 190.660021 -312.14676) (xy 190.648244 -312.098976) (xy 190.644284 -312.049922)
			(xy 190.327026 -312.049922) (xy 190.326522 -312.07563) (xy 190.318479 -312.126412) (xy 190.302591 -312.175311)
			(xy 190.279248 -312.221123) (xy 190.249027 -312.262719) (xy 190.212671 -312.299075) (xy 190.171075 -312.329296)
			(xy 190.125263 -312.352639) (xy 190.076364 -312.368527) (xy 190.025582 -312.37657) (xy 189.974166 -312.37657)
			(xy 189.923384 -312.368527) (xy 189.874485 -312.352639) (xy 189.828673 -312.329296) (xy 189.787077 -312.299075)
			(xy 189.750721 -312.262719) (xy 189.7205 -312.221123) (xy 189.697157 -312.175311) (xy 189.681269 -312.126412)
			(xy 189.673226 -312.07563) (xy 189.354548 -312.07563) (xy 189.346832 -312.123106) (xy 189.331248 -312.169787)
			(xy 189.308377 -312.213364) (xy 189.278812 -312.252708) (xy 189.243319 -312.2868) (xy 189.202816 -312.314756)
			(xy 189.158354 -312.335854) (xy 189.111083 -312.349546) (xy 189.062228 -312.355478) (xy 189.013053 -312.353497)
			(xy 188.964834 -312.343653) (xy 188.918818 -312.326201) (xy 188.876197 -312.301594) (xy 188.838076 -312.270469)
			(xy 188.805441 -312.233632) (xy 188.779138 -312.192036) (xy 188.759847 -312.14676) (xy 188.74807 -312.098976)
			(xy 188.74411 -312.049922) (xy 188.405262 -312.049922) (xy 188.404767 -312.074529) (xy 188.396872 -312.123106)
			(xy 188.381288 -312.169787) (xy 188.358417 -312.213364) (xy 188.328852 -312.252708) (xy 188.293359 -312.2868)
			(xy 188.252856 -312.314756) (xy 188.208394 -312.335854) (xy 188.161123 -312.349546) (xy 188.112268 -312.355478)
			(xy 188.063093 -312.353497) (xy 188.014874 -312.343653) (xy 187.968858 -312.326201) (xy 187.926237 -312.301594)
			(xy 187.888116 -312.270469) (xy 187.855481 -312.233632) (xy 187.829178 -312.192036) (xy 187.809887 -312.14676)
			(xy 187.79811 -312.098976) (xy 187.79415 -312.049922) (xy 187.455302 -312.049922) (xy 187.454807 -312.074529)
			(xy 187.446912 -312.123106) (xy 187.431328 -312.169787) (xy 187.408457 -312.213364) (xy 187.378892 -312.252708)
			(xy 187.343399 -312.2868) (xy 187.302896 -312.314756) (xy 187.258434 -312.335854) (xy 187.211163 -312.349546)
			(xy 187.162308 -312.355478) (xy 187.113133 -312.353497) (xy 187.064914 -312.343653) (xy 187.018898 -312.326201)
			(xy 186.976277 -312.301594) (xy 186.938156 -312.270469) (xy 186.905521 -312.233632) (xy 186.879218 -312.192036)
			(xy 186.859927 -312.14676) (xy 186.84815 -312.098976) (xy 186.84419 -312.049922) (xy 186.505342 -312.049922)
			(xy 186.504847 -312.074529) (xy 186.496952 -312.123106) (xy 186.481368 -312.169787) (xy 186.458497 -312.213364)
			(xy 186.428932 -312.252708) (xy 186.393439 -312.2868) (xy 186.352936 -312.314756) (xy 186.308474 -312.335854)
			(xy 186.261203 -312.349546) (xy 186.212348 -312.355478) (xy 186.163173 -312.353497) (xy 186.114954 -312.343653)
			(xy 186.068938 -312.326201) (xy 186.026317 -312.301594) (xy 185.988196 -312.270469) (xy 185.955561 -312.233632)
			(xy 185.929258 -312.192036) (xy 185.909967 -312.14676) (xy 185.89819 -312.098976) (xy 185.89423 -312.049922)
			(xy 185.555382 -312.049922) (xy 185.554887 -312.074529) (xy 185.546992 -312.123106) (xy 185.531408 -312.169787)
			(xy 185.508537 -312.213364) (xy 185.478972 -312.252708) (xy 185.443479 -312.2868) (xy 185.402976 -312.314756)
			(xy 185.358514 -312.335854) (xy 185.311243 -312.349546) (xy 185.262388 -312.355478) (xy 185.213213 -312.353497)
			(xy 185.164994 -312.343653) (xy 185.118978 -312.326201) (xy 185.076357 -312.301594) (xy 185.038236 -312.270469)
			(xy 185.005601 -312.233632) (xy 184.979298 -312.192036) (xy 184.960007 -312.14676) (xy 184.94823 -312.098976)
			(xy 184.94427 -312.049922) (xy 184.605168 -312.049922) (xy 184.604673 -312.074529) (xy 184.596778 -312.123106)
			(xy 184.581194 -312.169787) (xy 184.558323 -312.213364) (xy 184.528758 -312.252708) (xy 184.493265 -312.2868)
			(xy 184.452762 -312.314756) (xy 184.4083 -312.335854) (xy 184.361029 -312.349546) (xy 184.312174 -312.355478)
			(xy 184.262999 -312.353497) (xy 184.21478 -312.343653) (xy 184.168764 -312.326201) (xy 184.126143 -312.301594)
			(xy 184.088022 -312.270469) (xy 184.055387 -312.233632) (xy 184.029084 -312.192036) (xy 184.009793 -312.14676)
			(xy 183.998016 -312.098976) (xy 183.994056 -312.049922) (xy 183.655208 -312.049922) (xy 183.654713 -312.074529)
			(xy 183.646818 -312.123106) (xy 183.631234 -312.169787) (xy 183.608363 -312.213364) (xy 183.578798 -312.252708)
			(xy 183.543305 -312.2868) (xy 183.502802 -312.314756) (xy 183.45834 -312.335854) (xy 183.411069 -312.349546)
			(xy 183.362214 -312.355478) (xy 183.313039 -312.353497) (xy 183.26482 -312.343653) (xy 183.218804 -312.326201)
			(xy 183.176183 -312.301594) (xy 183.138062 -312.270469) (xy 183.105427 -312.233632) (xy 183.079124 -312.192036)
			(xy 183.059833 -312.14676) (xy 183.048056 -312.098976) (xy 183.044096 -312.049922) (xy 182.705248 -312.049922)
			(xy 182.704753 -312.074529) (xy 182.696858 -312.123106) (xy 182.681274 -312.169787) (xy 182.658403 -312.213364)
			(xy 182.628838 -312.252708) (xy 182.593345 -312.2868) (xy 182.552842 -312.314756) (xy 182.50838 -312.335854)
			(xy 182.461109 -312.349546) (xy 182.412254 -312.355478) (xy 182.363079 -312.353497) (xy 182.31486 -312.343653)
			(xy 182.268844 -312.326201) (xy 182.226223 -312.301594) (xy 182.188102 -312.270469) (xy 182.155467 -312.233632)
			(xy 182.129164 -312.192036) (xy 182.109873 -312.14676) (xy 182.098096 -312.098976) (xy 182.094136 -312.049922)
			(xy 181.755288 -312.049922) (xy 181.754793 -312.074529) (xy 181.746898 -312.123106) (xy 181.731314 -312.169787)
			(xy 181.708443 -312.213364) (xy 181.678878 -312.252708) (xy 181.643385 -312.2868) (xy 181.602882 -312.314756)
			(xy 181.55842 -312.335854) (xy 181.511149 -312.349546) (xy 181.462294 -312.355478) (xy 181.413119 -312.353497)
			(xy 181.3649 -312.343653) (xy 181.318884 -312.326201) (xy 181.276263 -312.301594) (xy 181.238142 -312.270469)
			(xy 181.205507 -312.233632) (xy 181.179204 -312.192036) (xy 181.159913 -312.14676) (xy 181.148136 -312.098976)
			(xy 181.144176 -312.049922) (xy 180.827172 -312.049922) (xy 180.826668 -312.07563) (xy 180.818625 -312.126412)
			(xy 180.802737 -312.175311) (xy 180.779394 -312.221123) (xy 180.749173 -312.262719) (xy 180.712817 -312.299075)
			(xy 180.671221 -312.329296) (xy 180.625409 -312.352639) (xy 180.57651 -312.368527) (xy 180.525728 -312.37657)
			(xy 180.474312 -312.37657) (xy 180.42353 -312.368527) (xy 180.374631 -312.352639) (xy 180.328819 -312.329296)
			(xy 180.287223 -312.299075) (xy 180.250867 -312.262719) (xy 180.220646 -312.221123) (xy 180.197303 -312.175311)
			(xy 180.181415 -312.126412) (xy 180.173372 -312.07563) (xy 179.854694 -312.07563) (xy 179.846978 -312.123106)
			(xy 179.831394 -312.169787) (xy 179.808523 -312.213364) (xy 179.778958 -312.252708) (xy 179.743465 -312.2868)
			(xy 179.702962 -312.314756) (xy 179.6585 -312.335854) (xy 179.611229 -312.349546) (xy 179.562374 -312.355478)
			(xy 179.513199 -312.353497) (xy 179.46498 -312.343653) (xy 179.418964 -312.326201) (xy 179.376343 -312.301594)
			(xy 179.338222 -312.270469) (xy 179.305587 -312.233632) (xy 179.279284 -312.192036) (xy 179.259993 -312.14676)
			(xy 179.248216 -312.098976) (xy 179.244256 -312.049922) (xy 178.926998 -312.049922) (xy 178.926494 -312.07563)
			(xy 178.918451 -312.126412) (xy 178.902563 -312.175311) (xy 178.87922 -312.221123) (xy 178.848999 -312.262719)
			(xy 178.812643 -312.299075) (xy 178.771047 -312.329296) (xy 178.725235 -312.352639) (xy 178.676336 -312.368527)
			(xy 178.625554 -312.37657) (xy 178.574138 -312.37657) (xy 178.523356 -312.368527) (xy 178.474457 -312.352639)
			(xy 178.428645 -312.329296) (xy 178.387049 -312.299075) (xy 178.350693 -312.262719) (xy 178.320472 -312.221123)
			(xy 178.297129 -312.175311) (xy 178.281241 -312.126412) (xy 178.273198 -312.07563) (xy 177.95452 -312.07563)
			(xy 177.946804 -312.123106) (xy 177.93122 -312.169787) (xy 177.908349 -312.213364) (xy 177.878784 -312.252708)
			(xy 177.843291 -312.2868) (xy 177.802788 -312.314756) (xy 177.758326 -312.335854) (xy 177.711055 -312.349546)
			(xy 177.6622 -312.355478) (xy 177.613025 -312.353497) (xy 177.564806 -312.343653) (xy 177.51879 -312.326201)
			(xy 177.476169 -312.301594) (xy 177.438048 -312.270469) (xy 177.405413 -312.233632) (xy 177.37911 -312.192036)
			(xy 177.359819 -312.14676) (xy 177.348042 -312.098976) (xy 177.344082 -312.049922) (xy 177.027078 -312.049922)
			(xy 177.026574 -312.07563) (xy 177.018531 -312.126412) (xy 177.002643 -312.175311) (xy 176.9793 -312.221123)
			(xy 176.949079 -312.262719) (xy 176.912723 -312.299075) (xy 176.871127 -312.329296) (xy 176.825315 -312.352639)
			(xy 176.776416 -312.368527) (xy 176.725634 -312.37657) (xy 176.674218 -312.37657) (xy 176.623436 -312.368527)
			(xy 176.574537 -312.352639) (xy 176.528725 -312.329296) (xy 176.487129 -312.299075) (xy 176.450773 -312.262719)
			(xy 176.420552 -312.221123) (xy 176.397209 -312.175311) (xy 176.381321 -312.126412) (xy 176.373278 -312.07563)
			(xy 176.0546 -312.07563) (xy 176.046884 -312.123106) (xy 176.0313 -312.169787) (xy 176.008429 -312.213364)
			(xy 175.978864 -312.252708) (xy 175.943371 -312.2868) (xy 175.902868 -312.314756) (xy 175.858406 -312.335854)
			(xy 175.811135 -312.349546) (xy 175.76228 -312.355478) (xy 175.713105 -312.353497) (xy 175.664886 -312.343653)
			(xy 175.61887 -312.326201) (xy 175.576249 -312.301594) (xy 175.538128 -312.270469) (xy 175.505493 -312.233632)
			(xy 175.47919 -312.192036) (xy 175.459899 -312.14676) (xy 175.448122 -312.098976) (xy 175.444162 -312.049922)
			(xy 175.127158 -312.049922) (xy 175.126654 -312.07563) (xy 175.118611 -312.126412) (xy 175.102723 -312.175311)
			(xy 175.07938 -312.221123) (xy 175.049159 -312.262719) (xy 175.012803 -312.299075) (xy 174.971207 -312.329296)
			(xy 174.925395 -312.352639) (xy 174.876496 -312.368527) (xy 174.825714 -312.37657) (xy 174.774298 -312.37657)
			(xy 174.723516 -312.368527) (xy 174.674617 -312.352639) (xy 174.628805 -312.329296) (xy 174.587209 -312.299075)
			(xy 174.550853 -312.262719) (xy 174.520632 -312.221123) (xy 174.497289 -312.175311) (xy 174.481401 -312.126412)
			(xy 174.473358 -312.07563) (xy 174.15468 -312.07563) (xy 174.146964 -312.123106) (xy 174.13138 -312.169787)
			(xy 174.108509 -312.213364) (xy 174.078944 -312.252708) (xy 174.043451 -312.2868) (xy 174.002948 -312.314756)
			(xy 173.958486 -312.335854) (xy 173.911215 -312.349546) (xy 173.86236 -312.355478) (xy 173.813185 -312.353497)
			(xy 173.764966 -312.343653) (xy 173.71895 -312.326201) (xy 173.676329 -312.301594) (xy 173.638208 -312.270469)
			(xy 173.605573 -312.233632) (xy 173.57927 -312.192036) (xy 173.559979 -312.14676) (xy 173.548202 -312.098976)
			(xy 173.544242 -312.049922) (xy 173.227238 -312.049922) (xy 173.226734 -312.07563) (xy 173.218691 -312.126412)
			(xy 173.202803 -312.175311) (xy 173.17946 -312.221123) (xy 173.149239 -312.262719) (xy 173.112883 -312.299075)
			(xy 173.071287 -312.329296) (xy 173.025475 -312.352639) (xy 172.976576 -312.368527) (xy 172.925794 -312.37657)
			(xy 172.874378 -312.37657) (xy 172.823596 -312.368527) (xy 172.774697 -312.352639) (xy 172.728885 -312.329296)
			(xy 172.687289 -312.299075) (xy 172.650933 -312.262719) (xy 172.620712 -312.221123) (xy 172.597369 -312.175311)
			(xy 172.581481 -312.126412) (xy 172.573438 -312.07563) (xy 172.254506 -312.07563) (xy 172.24679 -312.123106)
			(xy 172.231206 -312.169787) (xy 172.208335 -312.213364) (xy 172.17877 -312.252708) (xy 172.143277 -312.2868)
			(xy 172.102774 -312.314756) (xy 172.058312 -312.335854) (xy 172.011041 -312.349546) (xy 171.962186 -312.355478)
			(xy 171.913011 -312.353497) (xy 171.864792 -312.343653) (xy 171.818776 -312.326201) (xy 171.776155 -312.301594)
			(xy 171.738034 -312.270469) (xy 171.705399 -312.233632) (xy 171.679096 -312.192036) (xy 171.659805 -312.14676)
			(xy 171.648028 -312.098976) (xy 171.644068 -312.049922) (xy 171.327064 -312.049922) (xy 171.32656 -312.07563)
			(xy 171.318517 -312.126412) (xy 171.302629 -312.175311) (xy 171.279286 -312.221123) (xy 171.249065 -312.262719)
			(xy 171.212709 -312.299075) (xy 171.171113 -312.329296) (xy 171.125301 -312.352639) (xy 171.076402 -312.368527)
			(xy 171.02562 -312.37657) (xy 170.974204 -312.37657) (xy 170.923422 -312.368527) (xy 170.874523 -312.352639)
			(xy 170.828711 -312.329296) (xy 170.787115 -312.299075) (xy 170.750759 -312.262719) (xy 170.720538 -312.221123)
			(xy 170.697195 -312.175311) (xy 170.681307 -312.126412) (xy 170.673264 -312.07563) (xy 170.354586 -312.07563)
			(xy 170.34687 -312.123106) (xy 170.331286 -312.169787) (xy 170.308415 -312.213364) (xy 170.27885 -312.252708)
			(xy 170.243357 -312.2868) (xy 170.202854 -312.314756) (xy 170.158392 -312.335854) (xy 170.111121 -312.349546)
			(xy 170.062266 -312.355478) (xy 170.013091 -312.353497) (xy 169.964872 -312.343653) (xy 169.918856 -312.326201)
			(xy 169.876235 -312.301594) (xy 169.838114 -312.270469) (xy 169.805479 -312.233632) (xy 169.779176 -312.192036)
			(xy 169.759885 -312.14676) (xy 169.748108 -312.098976) (xy 169.744148 -312.049922) (xy 169.427144 -312.049922)
			(xy 169.42664 -312.07563) (xy 169.418597 -312.126412) (xy 169.402709 -312.175311) (xy 169.379366 -312.221123)
			(xy 169.349145 -312.262719) (xy 169.312789 -312.299075) (xy 169.271193 -312.329296) (xy 169.225381 -312.352639)
			(xy 169.176482 -312.368527) (xy 169.1257 -312.37657) (xy 169.074284 -312.37657) (xy 169.023502 -312.368527)
			(xy 168.974603 -312.352639) (xy 168.928791 -312.329296) (xy 168.887195 -312.299075) (xy 168.850839 -312.262719)
			(xy 168.820618 -312.221123) (xy 168.797275 -312.175311) (xy 168.781387 -312.126412) (xy 168.773344 -312.07563)
			(xy 168.454666 -312.07563) (xy 168.44695 -312.123106) (xy 168.431366 -312.169787) (xy 168.408495 -312.213364)
			(xy 168.37893 -312.252708) (xy 168.343437 -312.2868) (xy 168.302934 -312.314756) (xy 168.258472 -312.335854)
			(xy 168.211201 -312.349546) (xy 168.162346 -312.355478) (xy 168.113171 -312.353497) (xy 168.064952 -312.343653)
			(xy 168.018936 -312.326201) (xy 167.976315 -312.301594) (xy 167.938194 -312.270469) (xy 167.905559 -312.233632)
			(xy 167.879256 -312.192036) (xy 167.859965 -312.14676) (xy 167.848188 -312.098976) (xy 167.844228 -312.049922)
			(xy 167.527224 -312.049922) (xy 167.52672 -312.07563) (xy 167.518677 -312.126412) (xy 167.502789 -312.175311)
			(xy 167.479446 -312.221123) (xy 167.449225 -312.262719) (xy 167.412869 -312.299075) (xy 167.371273 -312.329296)
			(xy 167.325461 -312.352639) (xy 167.276562 -312.368527) (xy 167.22578 -312.37657) (xy 167.174364 -312.37657)
			(xy 167.123582 -312.368527) (xy 167.074683 -312.352639) (xy 167.028871 -312.329296) (xy 166.987275 -312.299075)
			(xy 166.950919 -312.262719) (xy 166.920698 -312.221123) (xy 166.897355 -312.175311) (xy 166.881467 -312.126412)
			(xy 166.873424 -312.07563) (xy 166.554492 -312.07563) (xy 166.546776 -312.123106) (xy 166.531192 -312.169787)
			(xy 166.508321 -312.213364) (xy 166.478756 -312.252708) (xy 166.443263 -312.2868) (xy 166.40276 -312.314756)
			(xy 166.358298 -312.335854) (xy 166.311027 -312.349546) (xy 166.262172 -312.355478) (xy 166.212997 -312.353497)
			(xy 166.164778 -312.343653) (xy 166.118762 -312.326201) (xy 166.076141 -312.301594) (xy 166.03802 -312.270469)
			(xy 166.005385 -312.233632) (xy 165.979082 -312.192036) (xy 165.959791 -312.14676) (xy 165.948014 -312.098976)
			(xy 165.944054 -312.049922) (xy 165.605736 -312.049922) (xy 165.601567 -312.100239) (xy 165.589167 -312.149206)
			(xy 165.568876 -312.195463) (xy 165.541249 -312.23775) (xy 165.507038 -312.274913) (xy 165.467176 -312.305938)
			(xy 165.422752 -312.329979) (xy 165.374977 -312.34638) (xy 165.325154 -312.354694) (xy 165.299898 -312.35523)
			(xy 165.29073 -312.355137) (xy 165.27243 -312.353994) (xy 165.263322 -312.352944) (xy 165.251384 -312.351674)
			(xy 165.240462 -312.355484) (xy 165.234885 -312.357651) (xy 165.224878 -312.364204) (xy 165.22065 -312.368438)
			(xy 165.164262 -312.427366) (xy 165.161468 -312.430414) (xy 165.158565 -312.434208) (xy 165.154085 -312.442645)
			(xy 165.152578 -312.447178) (xy 165.149022 -312.458608) (xy 165.151054 -312.470546) (xy 165.15499 -312.497584)
			(xy 165.15499 -312.55222) (xy 165.151054 -312.579258) (xy 165.149022 -312.591196) (xy 165.152578 -312.602626)
			(xy 165.154095 -312.607155) (xy 165.158574 -312.61559) (xy 165.161468 -312.61939) (xy 165.164262 -312.622438)
			(xy 165.22065 -312.681366) (xy 165.224879 -312.685598) (xy 165.234888 -312.692147) (xy 165.240462 -312.69432)
			(xy 165.251384 -312.69813) (xy 165.263322 -312.69686) (xy 165.27243 -312.695806) (xy 165.29073 -312.694664)
			(xy 165.299898 -312.694574) (xy 165.325157 -312.695067) (xy 165.374987 -312.703381) (xy 165.422768 -312.719784)
			(xy 165.467198 -312.743828) (xy 165.507065 -312.774858) (xy 165.54128 -312.812025) (xy 165.568911 -312.854318)
			(xy 165.589205 -312.900581) (xy 165.601606 -312.949554) (xy 165.605777 -312.999882) (xy 165.944054 -312.999882)
			(xy 165.948014 -312.950828) (xy 165.959791 -312.903044) (xy 165.979082 -312.857768) (xy 166.005385 -312.816172)
			(xy 166.03802 -312.779335) (xy 166.076141 -312.74821) (xy 166.118762 -312.723603) (xy 166.164778 -312.706151)
			(xy 166.212997 -312.696307) (xy 166.262172 -312.694326) (xy 166.311027 -312.700258) (xy 166.358298 -312.71395)
			(xy 166.40276 -312.735048) (xy 166.443263 -312.763004) (xy 166.478756 -312.797096) (xy 166.508321 -312.83644)
			(xy 166.531192 -312.880017) (xy 166.546776 -312.926698) (xy 166.554671 -312.975275) (xy 166.555166 -312.999882)
			(xy 166.894268 -312.999882) (xy 166.898228 -312.950828) (xy 166.910005 -312.903044) (xy 166.929296 -312.857768)
			(xy 166.955599 -312.816172) (xy 166.988234 -312.779335) (xy 167.026355 -312.74821) (xy 167.068976 -312.723603)
			(xy 167.114992 -312.706151) (xy 167.163211 -312.696307) (xy 167.212386 -312.694326) (xy 167.261241 -312.700258)
			(xy 167.308512 -312.71395) (xy 167.352974 -312.735048) (xy 167.393477 -312.763004) (xy 167.42897 -312.797096)
			(xy 167.458535 -312.83644) (xy 167.481406 -312.880017) (xy 167.49699 -312.926698) (xy 167.504885 -312.975275)
			(xy 167.50538 -312.999882) (xy 167.504885 -313.024489) (xy 167.504706 -313.02559) (xy 167.823384 -313.02559)
			(xy 167.823384 -312.974174) (xy 167.831427 -312.923392) (xy 167.847315 -312.874493) (xy 167.870658 -312.828681)
			(xy 167.900879 -312.787085) (xy 167.937235 -312.750729) (xy 167.978831 -312.720508) (xy 168.024643 -312.697165)
			(xy 168.073542 -312.681277) (xy 168.124324 -312.673234) (xy 168.17574 -312.673234) (xy 168.226522 -312.681277)
			(xy 168.275421 -312.697165) (xy 168.321233 -312.720508) (xy 168.362829 -312.750729) (xy 168.399185 -312.787085)
			(xy 168.429406 -312.828681) (xy 168.452749 -312.874493) (xy 168.468637 -312.923392) (xy 168.47668 -312.974174)
			(xy 168.477184 -312.999882) (xy 168.794188 -312.999882) (xy 168.798148 -312.950828) (xy 168.809925 -312.903044)
			(xy 168.829216 -312.857768) (xy 168.855519 -312.816172) (xy 168.888154 -312.779335) (xy 168.926275 -312.74821)
			(xy 168.968896 -312.723603) (xy 169.014912 -312.706151) (xy 169.063131 -312.696307) (xy 169.112306 -312.694326)
			(xy 169.161161 -312.700258) (xy 169.208432 -312.71395) (xy 169.252894 -312.735048) (xy 169.293397 -312.763004)
			(xy 169.32889 -312.797096) (xy 169.358455 -312.83644) (xy 169.381326 -312.880017) (xy 169.39691 -312.926698)
			(xy 169.404805 -312.975275) (xy 169.4053 -312.999882) (xy 169.404805 -313.024489) (xy 169.404626 -313.02559)
			(xy 169.723304 -313.02559) (xy 169.723304 -312.974174) (xy 169.731347 -312.923392) (xy 169.747235 -312.874493)
			(xy 169.770578 -312.828681) (xy 169.800799 -312.787085) (xy 169.837155 -312.750729) (xy 169.878751 -312.720508)
			(xy 169.924563 -312.697165) (xy 169.973462 -312.681277) (xy 170.024244 -312.673234) (xy 170.07566 -312.673234)
			(xy 170.126442 -312.681277) (xy 170.175341 -312.697165) (xy 170.221153 -312.720508) (xy 170.262749 -312.750729)
			(xy 170.299105 -312.787085) (xy 170.329326 -312.828681) (xy 170.352669 -312.874493) (xy 170.368557 -312.923392)
			(xy 170.3766 -312.974174) (xy 170.377104 -312.999882) (xy 170.694108 -312.999882) (xy 170.698068 -312.950828)
			(xy 170.709845 -312.903044) (xy 170.729136 -312.857768) (xy 170.755439 -312.816172) (xy 170.788074 -312.779335)
			(xy 170.826195 -312.74821) (xy 170.868816 -312.723603) (xy 170.914832 -312.706151) (xy 170.963051 -312.696307)
			(xy 171.012226 -312.694326) (xy 171.061081 -312.700258) (xy 171.108352 -312.71395) (xy 171.152814 -312.735048)
			(xy 171.193317 -312.763004) (xy 171.22881 -312.797096) (xy 171.258375 -312.83644) (xy 171.281246 -312.880017)
			(xy 171.29683 -312.926698) (xy 171.304725 -312.975275) (xy 171.30522 -312.999882) (xy 171.304725 -313.024489)
			(xy 171.304546 -313.02559) (xy 171.623224 -313.02559) (xy 171.623224 -312.974174) (xy 171.631267 -312.923392)
			(xy 171.647155 -312.874493) (xy 171.670498 -312.828681) (xy 171.700719 -312.787085) (xy 171.737075 -312.750729)
			(xy 171.778671 -312.720508) (xy 171.824483 -312.697165) (xy 171.873382 -312.681277) (xy 171.924164 -312.673234)
			(xy 171.97558 -312.673234) (xy 172.026362 -312.681277) (xy 172.075261 -312.697165) (xy 172.121073 -312.720508)
			(xy 172.162669 -312.750729) (xy 172.199025 -312.787085) (xy 172.229246 -312.828681) (xy 172.252589 -312.874493)
			(xy 172.268477 -312.923392) (xy 172.27652 -312.974174) (xy 172.277024 -312.999882) (xy 172.594282 -312.999882)
			(xy 172.598242 -312.950828) (xy 172.610019 -312.903044) (xy 172.62931 -312.857768) (xy 172.655613 -312.816172)
			(xy 172.688248 -312.779335) (xy 172.726369 -312.74821) (xy 172.76899 -312.723603) (xy 172.815006 -312.706151)
			(xy 172.863225 -312.696307) (xy 172.9124 -312.694326) (xy 172.961255 -312.700258) (xy 173.008526 -312.71395)
			(xy 173.052988 -312.735048) (xy 173.093491 -312.763004) (xy 173.128984 -312.797096) (xy 173.158549 -312.83644)
			(xy 173.18142 -312.880017) (xy 173.197004 -312.926698) (xy 173.204899 -312.975275) (xy 173.205394 -312.999882)
			(xy 173.204899 -313.024489) (xy 173.20472 -313.02559) (xy 173.523398 -313.02559) (xy 173.523398 -312.974174)
			(xy 173.531441 -312.923392) (xy 173.547329 -312.874493) (xy 173.570672 -312.828681) (xy 173.600893 -312.787085)
			(xy 173.637249 -312.750729) (xy 173.678845 -312.720508) (xy 173.724657 -312.697165) (xy 173.773556 -312.681277)
			(xy 173.824338 -312.673234) (xy 173.875754 -312.673234) (xy 173.926536 -312.681277) (xy 173.975435 -312.697165)
			(xy 174.021247 -312.720508) (xy 174.062843 -312.750729) (xy 174.099199 -312.787085) (xy 174.12942 -312.828681)
			(xy 174.152763 -312.874493) (xy 174.168651 -312.923392) (xy 174.176694 -312.974174) (xy 174.177198 -312.999882)
			(xy 174.494202 -312.999882) (xy 174.498162 -312.950828) (xy 174.509939 -312.903044) (xy 174.52923 -312.857768)
			(xy 174.555533 -312.816172) (xy 174.588168 -312.779335) (xy 174.626289 -312.74821) (xy 174.66891 -312.723603)
			(xy 174.714926 -312.706151) (xy 174.763145 -312.696307) (xy 174.81232 -312.694326) (xy 174.861175 -312.700258)
			(xy 174.908446 -312.71395) (xy 174.952908 -312.735048) (xy 174.993411 -312.763004) (xy 175.028904 -312.797096)
			(xy 175.058469 -312.83644) (xy 175.08134 -312.880017) (xy 175.096924 -312.926698) (xy 175.104819 -312.975275)
			(xy 175.105314 -312.999882) (xy 175.104819 -313.024489) (xy 175.10464 -313.02559) (xy 175.423318 -313.02559)
			(xy 175.423318 -312.974174) (xy 175.431361 -312.923392) (xy 175.447249 -312.874493) (xy 175.470592 -312.828681)
			(xy 175.500813 -312.787085) (xy 175.537169 -312.750729) (xy 175.578765 -312.720508) (xy 175.624577 -312.697165)
			(xy 175.673476 -312.681277) (xy 175.724258 -312.673234) (xy 175.775674 -312.673234) (xy 175.826456 -312.681277)
			(xy 175.875355 -312.697165) (xy 175.921167 -312.720508) (xy 175.962763 -312.750729) (xy 175.999119 -312.787085)
			(xy 176.02934 -312.828681) (xy 176.052683 -312.874493) (xy 176.068571 -312.923392) (xy 176.076614 -312.974174)
			(xy 176.077118 -312.999882) (xy 176.394122 -312.999882) (xy 176.398082 -312.950828) (xy 176.409859 -312.903044)
			(xy 176.42915 -312.857768) (xy 176.455453 -312.816172) (xy 176.488088 -312.779335) (xy 176.526209 -312.74821)
			(xy 176.56883 -312.723603) (xy 176.614846 -312.706151) (xy 176.663065 -312.696307) (xy 176.71224 -312.694326)
			(xy 176.761095 -312.700258) (xy 176.808366 -312.71395) (xy 176.852828 -312.735048) (xy 176.893331 -312.763004)
			(xy 176.928824 -312.797096) (xy 176.958389 -312.83644) (xy 176.98126 -312.880017) (xy 176.996844 -312.926698)
			(xy 177.004739 -312.975275) (xy 177.005234 -312.999882) (xy 177.004739 -313.024489) (xy 177.00456 -313.02559)
			(xy 177.323238 -313.02559) (xy 177.323238 -312.974174) (xy 177.331281 -312.923392) (xy 177.347169 -312.874493)
			(xy 177.370512 -312.828681) (xy 177.400733 -312.787085) (xy 177.437089 -312.750729) (xy 177.478685 -312.720508)
			(xy 177.524497 -312.697165) (xy 177.573396 -312.681277) (xy 177.624178 -312.673234) (xy 177.675594 -312.673234)
			(xy 177.726376 -312.681277) (xy 177.775275 -312.697165) (xy 177.821087 -312.720508) (xy 177.862683 -312.750729)
			(xy 177.899039 -312.787085) (xy 177.92926 -312.828681) (xy 177.952603 -312.874493) (xy 177.968491 -312.923392)
			(xy 177.976534 -312.974174) (xy 177.977038 -312.999882) (xy 178.294042 -312.999882) (xy 178.298002 -312.950828)
			(xy 178.309779 -312.903044) (xy 178.32907 -312.857768) (xy 178.355373 -312.816172) (xy 178.388008 -312.779335)
			(xy 178.426129 -312.74821) (xy 178.46875 -312.723603) (xy 178.514766 -312.706151) (xy 178.562985 -312.696307)
			(xy 178.61216 -312.694326) (xy 178.661015 -312.700258) (xy 178.708286 -312.71395) (xy 178.752748 -312.735048)
			(xy 178.793251 -312.763004) (xy 178.828744 -312.797096) (xy 178.858309 -312.83644) (xy 178.88118 -312.880017)
			(xy 178.896764 -312.926698) (xy 178.904659 -312.975275) (xy 178.905154 -312.999882) (xy 178.904659 -313.024489)
			(xy 178.90448 -313.02559) (xy 179.223412 -313.02559) (xy 179.223412 -312.974174) (xy 179.231455 -312.923392)
			(xy 179.247343 -312.874493) (xy 179.270686 -312.828681) (xy 179.300907 -312.787085) (xy 179.337263 -312.750729)
			(xy 179.378859 -312.720508) (xy 179.424671 -312.697165) (xy 179.47357 -312.681277) (xy 179.524352 -312.673234)
			(xy 179.575768 -312.673234) (xy 179.62655 -312.681277) (xy 179.675449 -312.697165) (xy 179.721261 -312.720508)
			(xy 179.762857 -312.750729) (xy 179.799213 -312.787085) (xy 179.829434 -312.828681) (xy 179.852777 -312.874493)
			(xy 179.868665 -312.923392) (xy 179.876708 -312.974174) (xy 179.877212 -312.999882) (xy 180.194216 -312.999882)
			(xy 180.198176 -312.950828) (xy 180.209953 -312.903044) (xy 180.229244 -312.857768) (xy 180.255547 -312.816172)
			(xy 180.288182 -312.779335) (xy 180.326303 -312.74821) (xy 180.368924 -312.723603) (xy 180.41494 -312.706151)
			(xy 180.463159 -312.696307) (xy 180.512334 -312.694326) (xy 180.561189 -312.700258) (xy 180.60846 -312.71395)
			(xy 180.652922 -312.735048) (xy 180.693425 -312.763004) (xy 180.728918 -312.797096) (xy 180.758483 -312.83644)
			(xy 180.781354 -312.880017) (xy 180.796938 -312.926698) (xy 180.804833 -312.975275) (xy 180.805328 -312.999882)
			(xy 180.804833 -313.024489) (xy 180.804654 -313.02559) (xy 181.123332 -313.02559) (xy 181.123332 -312.974174)
			(xy 181.131375 -312.923392) (xy 181.147263 -312.874493) (xy 181.170606 -312.828681) (xy 181.200827 -312.787085)
			(xy 181.237183 -312.750729) (xy 181.278779 -312.720508) (xy 181.324591 -312.697165) (xy 181.37349 -312.681277)
			(xy 181.424272 -312.673234) (xy 181.475688 -312.673234) (xy 181.52647 -312.681277) (xy 181.575369 -312.697165)
			(xy 181.621181 -312.720508) (xy 181.662777 -312.750729) (xy 181.699133 -312.787085) (xy 181.729354 -312.828681)
			(xy 181.752697 -312.874493) (xy 181.768585 -312.923392) (xy 181.776628 -312.974174) (xy 181.777132 -312.999882)
			(xy 182.094136 -312.999882) (xy 182.098096 -312.950828) (xy 182.109873 -312.903044) (xy 182.129164 -312.857768)
			(xy 182.155467 -312.816172) (xy 182.188102 -312.779335) (xy 182.226223 -312.74821) (xy 182.268844 -312.723603)
			(xy 182.31486 -312.706151) (xy 182.363079 -312.696307) (xy 182.412254 -312.694326) (xy 182.461109 -312.700258)
			(xy 182.50838 -312.71395) (xy 182.552842 -312.735048) (xy 182.593345 -312.763004) (xy 182.628838 -312.797096)
			(xy 182.658403 -312.83644) (xy 182.681274 -312.880017) (xy 182.696858 -312.926698) (xy 182.704753 -312.975275)
			(xy 182.705248 -312.999882) (xy 183.044096 -312.999882) (xy 183.048056 -312.950828) (xy 183.059833 -312.903044)
			(xy 183.079124 -312.857768) (xy 183.105427 -312.816172) (xy 183.138062 -312.779335) (xy 183.176183 -312.74821)
			(xy 183.218804 -312.723603) (xy 183.26482 -312.706151) (xy 183.313039 -312.696307) (xy 183.362214 -312.694326)
			(xy 183.411069 -312.700258) (xy 183.45834 -312.71395) (xy 183.502802 -312.735048) (xy 183.543305 -312.763004)
			(xy 183.578798 -312.797096) (xy 183.608363 -312.83644) (xy 183.631234 -312.880017) (xy 183.646818 -312.926698)
			(xy 183.654713 -312.975275) (xy 183.655208 -312.999882) (xy 183.994056 -312.999882) (xy 183.998016 -312.950828)
			(xy 184.009793 -312.903044) (xy 184.029084 -312.857768) (xy 184.055387 -312.816172) (xy 184.088022 -312.779335)
			(xy 184.126143 -312.74821) (xy 184.168764 -312.723603) (xy 184.21478 -312.706151) (xy 184.262999 -312.696307)
			(xy 184.312174 -312.694326) (xy 184.361029 -312.700258) (xy 184.4083 -312.71395) (xy 184.452762 -312.735048)
			(xy 184.493265 -312.763004) (xy 184.528758 -312.797096) (xy 184.558323 -312.83644) (xy 184.581194 -312.880017)
			(xy 184.596778 -312.926698) (xy 184.604673 -312.975275) (xy 184.605168 -312.999882) (xy 184.94427 -312.999882)
			(xy 184.94823 -312.950828) (xy 184.960007 -312.903044) (xy 184.979298 -312.857768) (xy 185.005601 -312.816172)
			(xy 185.038236 -312.779335) (xy 185.076357 -312.74821) (xy 185.118978 -312.723603) (xy 185.164994 -312.706151)
			(xy 185.213213 -312.696307) (xy 185.262388 -312.694326) (xy 185.311243 -312.700258) (xy 185.358514 -312.71395)
			(xy 185.402976 -312.735048) (xy 185.443479 -312.763004) (xy 185.478972 -312.797096) (xy 185.508537 -312.83644)
			(xy 185.531408 -312.880017) (xy 185.546992 -312.926698) (xy 185.554887 -312.975275) (xy 185.555382 -312.999882)
			(xy 185.89423 -312.999882) (xy 185.89819 -312.950828) (xy 185.909967 -312.903044) (xy 185.929258 -312.857768)
			(xy 185.955561 -312.816172) (xy 185.988196 -312.779335) (xy 186.026317 -312.74821) (xy 186.068938 -312.723603)
			(xy 186.114954 -312.706151) (xy 186.163173 -312.696307) (xy 186.212348 -312.694326) (xy 186.261203 -312.700258)
			(xy 186.308474 -312.71395) (xy 186.352936 -312.735048) (xy 186.393439 -312.763004) (xy 186.428932 -312.797096)
			(xy 186.458497 -312.83644) (xy 186.481368 -312.880017) (xy 186.496952 -312.926698) (xy 186.504847 -312.975275)
			(xy 186.505342 -312.999882) (xy 186.84419 -312.999882) (xy 186.84815 -312.950828) (xy 186.859927 -312.903044)
			(xy 186.879218 -312.857768) (xy 186.905521 -312.816172) (xy 186.938156 -312.779335) (xy 186.976277 -312.74821)
			(xy 187.018898 -312.723603) (xy 187.064914 -312.706151) (xy 187.113133 -312.696307) (xy 187.162308 -312.694326)
			(xy 187.211163 -312.700258) (xy 187.258434 -312.71395) (xy 187.302896 -312.735048) (xy 187.343399 -312.763004)
			(xy 187.378892 -312.797096) (xy 187.408457 -312.83644) (xy 187.431328 -312.880017) (xy 187.446912 -312.926698)
			(xy 187.454807 -312.975275) (xy 187.455302 -312.999882) (xy 187.79415 -312.999882) (xy 187.79811 -312.950828)
			(xy 187.809887 -312.903044) (xy 187.829178 -312.857768) (xy 187.855481 -312.816172) (xy 187.888116 -312.779335)
			(xy 187.926237 -312.74821) (xy 187.968858 -312.723603) (xy 188.014874 -312.706151) (xy 188.063093 -312.696307)
			(xy 188.112268 -312.694326) (xy 188.161123 -312.700258) (xy 188.208394 -312.71395) (xy 188.252856 -312.735048)
			(xy 188.293359 -312.763004) (xy 188.328852 -312.797096) (xy 188.358417 -312.83644) (xy 188.381288 -312.880017)
			(xy 188.396872 -312.926698) (xy 188.404767 -312.975275) (xy 188.405262 -312.999882) (xy 188.74411 -312.999882)
			(xy 188.74807 -312.950828) (xy 188.759847 -312.903044) (xy 188.779138 -312.857768) (xy 188.805441 -312.816172)
			(xy 188.838076 -312.779335) (xy 188.876197 -312.74821) (xy 188.918818 -312.723603) (xy 188.964834 -312.706151)
			(xy 189.013053 -312.696307) (xy 189.062228 -312.694326) (xy 189.111083 -312.700258) (xy 189.158354 -312.71395)
			(xy 189.202816 -312.735048) (xy 189.243319 -312.763004) (xy 189.278812 -312.797096) (xy 189.308377 -312.83644)
			(xy 189.331248 -312.880017) (xy 189.346832 -312.926698) (xy 189.354727 -312.975275) (xy 189.355222 -312.999882)
			(xy 189.69407 -312.999882) (xy 189.69803 -312.950828) (xy 189.709807 -312.903044) (xy 189.729098 -312.857768)
			(xy 189.755401 -312.816172) (xy 189.788036 -312.779335) (xy 189.826157 -312.74821) (xy 189.868778 -312.723603)
			(xy 189.914794 -312.706151) (xy 189.963013 -312.696307) (xy 190.012188 -312.694326) (xy 190.061043 -312.700258)
			(xy 190.108314 -312.71395) (xy 190.152776 -312.735048) (xy 190.193279 -312.763004) (xy 190.228772 -312.797096)
			(xy 190.258337 -312.83644) (xy 190.281208 -312.880017) (xy 190.296792 -312.926698) (xy 190.304687 -312.975275)
			(xy 190.305182 -312.999882) (xy 190.304687 -313.024489) (xy 190.304508 -313.02559) (xy 190.62344 -313.02559)
			(xy 190.62344 -312.974174) (xy 190.631483 -312.923392) (xy 190.647371 -312.874493) (xy 190.670714 -312.828681)
			(xy 190.700935 -312.787085) (xy 190.737291 -312.750729) (xy 190.778887 -312.720508) (xy 190.824699 -312.697165)
			(xy 190.873598 -312.681277) (xy 190.92438 -312.673234) (xy 190.975796 -312.673234) (xy 191.026578 -312.681277)
			(xy 191.075477 -312.697165) (xy 191.121289 -312.720508) (xy 191.162885 -312.750729) (xy 191.199241 -312.787085)
			(xy 191.229462 -312.828681) (xy 191.252805 -312.874493) (xy 191.268693 -312.923392) (xy 191.276736 -312.974174)
			(xy 191.27724 -312.999882) (xy 191.594244 -312.999882) (xy 191.598204 -312.950828) (xy 191.609981 -312.903044)
			(xy 191.629272 -312.857768) (xy 191.655575 -312.816172) (xy 191.68821 -312.779335) (xy 191.726331 -312.74821)
			(xy 191.768952 -312.723603) (xy 191.814968 -312.706151) (xy 191.863187 -312.696307) (xy 191.912362 -312.694326)
			(xy 191.961217 -312.700258) (xy 192.008488 -312.71395) (xy 192.05295 -312.735048) (xy 192.093453 -312.763004)
			(xy 192.128946 -312.797096) (xy 192.158511 -312.83644) (xy 192.181382 -312.880017) (xy 192.196966 -312.926698)
			(xy 192.204861 -312.975275) (xy 192.205356 -312.999882) (xy 192.204861 -313.024489) (xy 192.204682 -313.02559)
			(xy 192.52336 -313.02559) (xy 192.52336 -312.974174) (xy 192.531403 -312.923392) (xy 192.547291 -312.874493)
			(xy 192.570634 -312.828681) (xy 192.600855 -312.787085) (xy 192.637211 -312.750729) (xy 192.678807 -312.720508)
			(xy 192.724619 -312.697165) (xy 192.773518 -312.681277) (xy 192.8243 -312.673234) (xy 192.875716 -312.673234)
			(xy 192.926498 -312.681277) (xy 192.975397 -312.697165) (xy 193.021209 -312.720508) (xy 193.062805 -312.750729)
			(xy 193.099161 -312.787085) (xy 193.129382 -312.828681) (xy 193.152725 -312.874493) (xy 193.168613 -312.923392)
			(xy 193.176656 -312.974174) (xy 193.17716 -312.999882) (xy 193.494164 -312.999882) (xy 193.498124 -312.950828)
			(xy 193.509901 -312.903044) (xy 193.529192 -312.857768) (xy 193.555495 -312.816172) (xy 193.58813 -312.779335)
			(xy 193.626251 -312.74821) (xy 193.668872 -312.723603) (xy 193.714888 -312.706151) (xy 193.763107 -312.696307)
			(xy 193.812282 -312.694326) (xy 193.861137 -312.700258) (xy 193.908408 -312.71395) (xy 193.95287 -312.735048)
			(xy 193.993373 -312.763004) (xy 194.028866 -312.797096) (xy 194.058431 -312.83644) (xy 194.081302 -312.880017)
			(xy 194.096886 -312.926698) (xy 194.104781 -312.975275) (xy 194.105276 -312.999882) (xy 194.104781 -313.024489)
			(xy 194.104602 -313.02559) (xy 194.42328 -313.02559) (xy 194.42328 -312.974174) (xy 194.431323 -312.923392)
			(xy 194.447211 -312.874493) (xy 194.470554 -312.828681) (xy 194.500775 -312.787085) (xy 194.537131 -312.750729)
			(xy 194.578727 -312.720508) (xy 194.624539 -312.697165) (xy 194.673438 -312.681277) (xy 194.72422 -312.673234)
			(xy 194.775636 -312.673234) (xy 194.826418 -312.681277) (xy 194.875317 -312.697165) (xy 194.921129 -312.720508)
			(xy 194.962725 -312.750729) (xy 194.999081 -312.787085) (xy 195.029302 -312.828681) (xy 195.052645 -312.874493)
			(xy 195.068533 -312.923392) (xy 195.076576 -312.974174) (xy 195.07708 -312.999882) (xy 195.394084 -312.999882)
			(xy 195.398044 -312.950828) (xy 195.409821 -312.903044) (xy 195.429112 -312.857768) (xy 195.455415 -312.816172)
			(xy 195.48805 -312.779335) (xy 195.526171 -312.74821) (xy 195.568792 -312.723603) (xy 195.614808 -312.706151)
			(xy 195.663027 -312.696307) (xy 195.712202 -312.694326) (xy 195.761057 -312.700258) (xy 195.808328 -312.71395)
			(xy 195.85279 -312.735048) (xy 195.893293 -312.763004) (xy 195.928786 -312.797096) (xy 195.958351 -312.83644)
			(xy 195.981222 -312.880017) (xy 195.996806 -312.926698) (xy 196.004701 -312.975275) (xy 196.005196 -312.999882)
			(xy 196.004701 -313.024489) (xy 196.004522 -313.02559) (xy 196.3232 -313.02559) (xy 196.3232 -312.974174)
			(xy 196.331243 -312.923392) (xy 196.347131 -312.874493) (xy 196.370474 -312.828681) (xy 196.400695 -312.787085)
			(xy 196.437051 -312.750729) (xy 196.478647 -312.720508) (xy 196.524459 -312.697165) (xy 196.573358 -312.681277)
			(xy 196.62414 -312.673234) (xy 196.675556 -312.673234) (xy 196.726338 -312.681277) (xy 196.775237 -312.697165)
			(xy 196.821049 -312.720508) (xy 196.862645 -312.750729) (xy 196.899001 -312.787085) (xy 196.929222 -312.828681)
			(xy 196.952565 -312.874493) (xy 196.968453 -312.923392) (xy 196.976496 -312.974174) (xy 196.977 -312.999882)
			(xy 197.294258 -312.999882) (xy 197.298218 -312.950828) (xy 197.309995 -312.903044) (xy 197.329286 -312.857768)
			(xy 197.355589 -312.816172) (xy 197.388224 -312.779335) (xy 197.426345 -312.74821) (xy 197.468966 -312.723603)
			(xy 197.514982 -312.706151) (xy 197.563201 -312.696307) (xy 197.612376 -312.694326) (xy 197.661231 -312.700258)
			(xy 197.708502 -312.71395) (xy 197.752964 -312.735048) (xy 197.793467 -312.763004) (xy 197.82896 -312.797096)
			(xy 197.858525 -312.83644) (xy 197.881396 -312.880017) (xy 197.89698 -312.926698) (xy 197.904875 -312.975275)
			(xy 197.90537 -312.999882) (xy 198.244218 -312.999882) (xy 198.248178 -312.950828) (xy 198.259955 -312.903044)
			(xy 198.279246 -312.857768) (xy 198.305549 -312.816172) (xy 198.338184 -312.779335) (xy 198.376305 -312.74821)
			(xy 198.418926 -312.723603) (xy 198.464942 -312.706151) (xy 198.513161 -312.696307) (xy 198.562336 -312.694326)
			(xy 198.611191 -312.700258) (xy 198.658462 -312.71395) (xy 198.702924 -312.735048) (xy 198.743427 -312.763004)
			(xy 198.77892 -312.797096) (xy 198.808485 -312.83644) (xy 198.831356 -312.880017) (xy 198.84694 -312.926698)
			(xy 198.854835 -312.975275) (xy 198.85533 -312.999882) (xy 198.854835 -313.024489) (xy 198.84694 -313.073066)
			(xy 198.831356 -313.119747) (xy 198.808485 -313.163324) (xy 198.77892 -313.202668) (xy 198.743427 -313.23676)
			(xy 198.702924 -313.264716) (xy 198.658462 -313.285814) (xy 198.611191 -313.299506) (xy 198.562336 -313.305438)
			(xy 198.513161 -313.303457) (xy 198.464942 -313.293613) (xy 198.418926 -313.276161) (xy 198.376305 -313.251554)
			(xy 198.338184 -313.220429) (xy 198.305549 -313.183592) (xy 198.279246 -313.141996) (xy 198.259955 -313.09672)
			(xy 198.248178 -313.048936) (xy 198.244218 -312.999882) (xy 197.90537 -312.999882) (xy 197.904875 -313.024489)
			(xy 197.89698 -313.073066) (xy 197.881396 -313.119747) (xy 197.858525 -313.163324) (xy 197.82896 -313.202668)
			(xy 197.793467 -313.23676) (xy 197.752964 -313.264716) (xy 197.708502 -313.285814) (xy 197.661231 -313.299506)
			(xy 197.612376 -313.305438) (xy 197.563201 -313.303457) (xy 197.514982 -313.293613) (xy 197.468966 -313.276161)
			(xy 197.426345 -313.251554) (xy 197.388224 -313.220429) (xy 197.355589 -313.183592) (xy 197.329286 -313.141996)
			(xy 197.309995 -313.09672) (xy 197.298218 -313.048936) (xy 197.294258 -312.999882) (xy 196.977 -312.999882)
			(xy 196.976496 -313.02559) (xy 196.968453 -313.076372) (xy 196.952565 -313.125271) (xy 196.929222 -313.171083)
			(xy 196.899001 -313.212679) (xy 196.862645 -313.249035) (xy 196.821049 -313.279256) (xy 196.775237 -313.302599)
			(xy 196.726338 -313.318487) (xy 196.675556 -313.32653) (xy 196.62414 -313.32653) (xy 196.573358 -313.318487)
			(xy 196.524459 -313.302599) (xy 196.478647 -313.279256) (xy 196.437051 -313.249035) (xy 196.400695 -313.212679)
			(xy 196.370474 -313.171083) (xy 196.347131 -313.125271) (xy 196.331243 -313.076372) (xy 196.3232 -313.02559)
			(xy 196.004522 -313.02559) (xy 195.996806 -313.073066) (xy 195.981222 -313.119747) (xy 195.958351 -313.163324)
			(xy 195.928786 -313.202668) (xy 195.893293 -313.23676) (xy 195.85279 -313.264716) (xy 195.808328 -313.285814)
			(xy 195.761057 -313.299506) (xy 195.712202 -313.305438) (xy 195.663027 -313.303457) (xy 195.614808 -313.293613)
			(xy 195.568792 -313.276161) (xy 195.526171 -313.251554) (xy 195.48805 -313.220429) (xy 195.455415 -313.183592)
			(xy 195.429112 -313.141996) (xy 195.409821 -313.09672) (xy 195.398044 -313.048936) (xy 195.394084 -312.999882)
			(xy 195.07708 -312.999882) (xy 195.076576 -313.02559) (xy 195.068533 -313.076372) (xy 195.052645 -313.125271)
			(xy 195.029302 -313.171083) (xy 194.999081 -313.212679) (xy 194.962725 -313.249035) (xy 194.921129 -313.279256)
			(xy 194.875317 -313.302599) (xy 194.826418 -313.318487) (xy 194.775636 -313.32653) (xy 194.72422 -313.32653)
			(xy 194.673438 -313.318487) (xy 194.624539 -313.302599) (xy 194.578727 -313.279256) (xy 194.537131 -313.249035)
			(xy 194.500775 -313.212679) (xy 194.470554 -313.171083) (xy 194.447211 -313.125271) (xy 194.431323 -313.076372)
			(xy 194.42328 -313.02559) (xy 194.104602 -313.02559) (xy 194.096886 -313.073066) (xy 194.081302 -313.119747)
			(xy 194.058431 -313.163324) (xy 194.028866 -313.202668) (xy 193.993373 -313.23676) (xy 193.95287 -313.264716)
			(xy 193.908408 -313.285814) (xy 193.861137 -313.299506) (xy 193.812282 -313.305438) (xy 193.763107 -313.303457)
			(xy 193.714888 -313.293613) (xy 193.668872 -313.276161) (xy 193.626251 -313.251554) (xy 193.58813 -313.220429)
			(xy 193.555495 -313.183592) (xy 193.529192 -313.141996) (xy 193.509901 -313.09672) (xy 193.498124 -313.048936)
			(xy 193.494164 -312.999882) (xy 193.17716 -312.999882) (xy 193.176656 -313.02559) (xy 193.168613 -313.076372)
			(xy 193.152725 -313.125271) (xy 193.129382 -313.171083) (xy 193.099161 -313.212679) (xy 193.062805 -313.249035)
			(xy 193.021209 -313.279256) (xy 192.975397 -313.302599) (xy 192.926498 -313.318487) (xy 192.875716 -313.32653)
			(xy 192.8243 -313.32653) (xy 192.773518 -313.318487) (xy 192.724619 -313.302599) (xy 192.678807 -313.279256)
			(xy 192.637211 -313.249035) (xy 192.600855 -313.212679) (xy 192.570634 -313.171083) (xy 192.547291 -313.125271)
			(xy 192.531403 -313.076372) (xy 192.52336 -313.02559) (xy 192.204682 -313.02559) (xy 192.196966 -313.073066)
			(xy 192.181382 -313.119747) (xy 192.158511 -313.163324) (xy 192.128946 -313.202668) (xy 192.093453 -313.23676)
			(xy 192.05295 -313.264716) (xy 192.008488 -313.285814) (xy 191.961217 -313.299506) (xy 191.912362 -313.305438)
			(xy 191.863187 -313.303457) (xy 191.814968 -313.293613) (xy 191.768952 -313.276161) (xy 191.726331 -313.251554)
			(xy 191.68821 -313.220429) (xy 191.655575 -313.183592) (xy 191.629272 -313.141996) (xy 191.609981 -313.09672)
			(xy 191.598204 -313.048936) (xy 191.594244 -312.999882) (xy 191.27724 -312.999882) (xy 191.276736 -313.02559)
			(xy 191.268693 -313.076372) (xy 191.252805 -313.125271) (xy 191.229462 -313.171083) (xy 191.199241 -313.212679)
			(xy 191.162885 -313.249035) (xy 191.121289 -313.279256) (xy 191.075477 -313.302599) (xy 191.026578 -313.318487)
			(xy 190.975796 -313.32653) (xy 190.92438 -313.32653) (xy 190.873598 -313.318487) (xy 190.824699 -313.302599)
			(xy 190.778887 -313.279256) (xy 190.737291 -313.249035) (xy 190.700935 -313.212679) (xy 190.670714 -313.171083)
			(xy 190.647371 -313.125271) (xy 190.631483 -313.076372) (xy 190.62344 -313.02559) (xy 190.304508 -313.02559)
			(xy 190.296792 -313.073066) (xy 190.281208 -313.119747) (xy 190.258337 -313.163324) (xy 190.228772 -313.202668)
			(xy 190.193279 -313.23676) (xy 190.152776 -313.264716) (xy 190.108314 -313.285814) (xy 190.061043 -313.299506)
			(xy 190.012188 -313.305438) (xy 189.963013 -313.303457) (xy 189.914794 -313.293613) (xy 189.868778 -313.276161)
			(xy 189.826157 -313.251554) (xy 189.788036 -313.220429) (xy 189.755401 -313.183592) (xy 189.729098 -313.141996)
			(xy 189.709807 -313.09672) (xy 189.69803 -313.048936) (xy 189.69407 -312.999882) (xy 189.355222 -312.999882)
			(xy 189.354727 -313.024489) (xy 189.346832 -313.073066) (xy 189.331248 -313.119747) (xy 189.308377 -313.163324)
			(xy 189.278812 -313.202668) (xy 189.243319 -313.23676) (xy 189.202816 -313.264716) (xy 189.158354 -313.285814)
			(xy 189.111083 -313.299506) (xy 189.062228 -313.305438) (xy 189.013053 -313.303457) (xy 188.964834 -313.293613)
			(xy 188.918818 -313.276161) (xy 188.876197 -313.251554) (xy 188.838076 -313.220429) (xy 188.805441 -313.183592)
			(xy 188.779138 -313.141996) (xy 188.759847 -313.09672) (xy 188.74807 -313.048936) (xy 188.74411 -312.999882)
			(xy 188.405262 -312.999882) (xy 188.404767 -313.024489) (xy 188.396872 -313.073066) (xy 188.381288 -313.119747)
			(xy 188.358417 -313.163324) (xy 188.328852 -313.202668) (xy 188.293359 -313.23676) (xy 188.252856 -313.264716)
			(xy 188.208394 -313.285814) (xy 188.161123 -313.299506) (xy 188.112268 -313.305438) (xy 188.063093 -313.303457)
			(xy 188.014874 -313.293613) (xy 187.968858 -313.276161) (xy 187.926237 -313.251554) (xy 187.888116 -313.220429)
			(xy 187.855481 -313.183592) (xy 187.829178 -313.141996) (xy 187.809887 -313.09672) (xy 187.79811 -313.048936)
			(xy 187.79415 -312.999882) (xy 187.455302 -312.999882) (xy 187.454807 -313.024489) (xy 187.446912 -313.073066)
			(xy 187.431328 -313.119747) (xy 187.408457 -313.163324) (xy 187.378892 -313.202668) (xy 187.343399 -313.23676)
			(xy 187.302896 -313.264716) (xy 187.258434 -313.285814) (xy 187.211163 -313.299506) (xy 187.162308 -313.305438)
			(xy 187.113133 -313.303457) (xy 187.064914 -313.293613) (xy 187.018898 -313.276161) (xy 186.976277 -313.251554)
			(xy 186.938156 -313.220429) (xy 186.905521 -313.183592) (xy 186.879218 -313.141996) (xy 186.859927 -313.09672)
			(xy 186.84815 -313.048936) (xy 186.84419 -312.999882) (xy 186.505342 -312.999882) (xy 186.504847 -313.024489)
			(xy 186.496952 -313.073066) (xy 186.481368 -313.119747) (xy 186.458497 -313.163324) (xy 186.428932 -313.202668)
			(xy 186.393439 -313.23676) (xy 186.352936 -313.264716) (xy 186.308474 -313.285814) (xy 186.261203 -313.299506)
			(xy 186.212348 -313.305438) (xy 186.163173 -313.303457) (xy 186.114954 -313.293613) (xy 186.068938 -313.276161)
			(xy 186.026317 -313.251554) (xy 185.988196 -313.220429) (xy 185.955561 -313.183592) (xy 185.929258 -313.141996)
			(xy 185.909967 -313.09672) (xy 185.89819 -313.048936) (xy 185.89423 -312.999882) (xy 185.555382 -312.999882)
			(xy 185.554887 -313.024489) (xy 185.546992 -313.073066) (xy 185.531408 -313.119747) (xy 185.508537 -313.163324)
			(xy 185.478972 -313.202668) (xy 185.443479 -313.23676) (xy 185.402976 -313.264716) (xy 185.358514 -313.285814)
			(xy 185.311243 -313.299506) (xy 185.262388 -313.305438) (xy 185.213213 -313.303457) (xy 185.164994 -313.293613)
			(xy 185.118978 -313.276161) (xy 185.076357 -313.251554) (xy 185.038236 -313.220429) (xy 185.005601 -313.183592)
			(xy 184.979298 -313.141996) (xy 184.960007 -313.09672) (xy 184.94823 -313.048936) (xy 184.94427 -312.999882)
			(xy 184.605168 -312.999882) (xy 184.604673 -313.024489) (xy 184.596778 -313.073066) (xy 184.581194 -313.119747)
			(xy 184.558323 -313.163324) (xy 184.528758 -313.202668) (xy 184.493265 -313.23676) (xy 184.452762 -313.264716)
			(xy 184.4083 -313.285814) (xy 184.361029 -313.299506) (xy 184.312174 -313.305438) (xy 184.262999 -313.303457)
			(xy 184.21478 -313.293613) (xy 184.168764 -313.276161) (xy 184.126143 -313.251554) (xy 184.088022 -313.220429)
			(xy 184.055387 -313.183592) (xy 184.029084 -313.141996) (xy 184.009793 -313.09672) (xy 183.998016 -313.048936)
			(xy 183.994056 -312.999882) (xy 183.655208 -312.999882) (xy 183.654713 -313.024489) (xy 183.646818 -313.073066)
			(xy 183.631234 -313.119747) (xy 183.608363 -313.163324) (xy 183.578798 -313.202668) (xy 183.543305 -313.23676)
			(xy 183.502802 -313.264716) (xy 183.45834 -313.285814) (xy 183.411069 -313.299506) (xy 183.362214 -313.305438)
			(xy 183.313039 -313.303457) (xy 183.26482 -313.293613) (xy 183.218804 -313.276161) (xy 183.176183 -313.251554)
			(xy 183.138062 -313.220429) (xy 183.105427 -313.183592) (xy 183.079124 -313.141996) (xy 183.059833 -313.09672)
			(xy 183.048056 -313.048936) (xy 183.044096 -312.999882) (xy 182.705248 -312.999882) (xy 182.704753 -313.024489)
			(xy 182.696858 -313.073066) (xy 182.681274 -313.119747) (xy 182.658403 -313.163324) (xy 182.628838 -313.202668)
			(xy 182.593345 -313.23676) (xy 182.552842 -313.264716) (xy 182.50838 -313.285814) (xy 182.461109 -313.299506)
			(xy 182.412254 -313.305438) (xy 182.363079 -313.303457) (xy 182.31486 -313.293613) (xy 182.268844 -313.276161)
			(xy 182.226223 -313.251554) (xy 182.188102 -313.220429) (xy 182.155467 -313.183592) (xy 182.129164 -313.141996)
			(xy 182.109873 -313.09672) (xy 182.098096 -313.048936) (xy 182.094136 -312.999882) (xy 181.777132 -312.999882)
			(xy 181.776628 -313.02559) (xy 181.768585 -313.076372) (xy 181.752697 -313.125271) (xy 181.729354 -313.171083)
			(xy 181.699133 -313.212679) (xy 181.662777 -313.249035) (xy 181.621181 -313.279256) (xy 181.575369 -313.302599)
			(xy 181.52647 -313.318487) (xy 181.475688 -313.32653) (xy 181.424272 -313.32653) (xy 181.37349 -313.318487)
			(xy 181.324591 -313.302599) (xy 181.278779 -313.279256) (xy 181.237183 -313.249035) (xy 181.200827 -313.212679)
			(xy 181.170606 -313.171083) (xy 181.147263 -313.125271) (xy 181.131375 -313.076372) (xy 181.123332 -313.02559)
			(xy 180.804654 -313.02559) (xy 180.796938 -313.073066) (xy 180.781354 -313.119747) (xy 180.758483 -313.163324)
			(xy 180.728918 -313.202668) (xy 180.693425 -313.23676) (xy 180.652922 -313.264716) (xy 180.60846 -313.285814)
			(xy 180.561189 -313.299506) (xy 180.512334 -313.305438) (xy 180.463159 -313.303457) (xy 180.41494 -313.293613)
			(xy 180.368924 -313.276161) (xy 180.326303 -313.251554) (xy 180.288182 -313.220429) (xy 180.255547 -313.183592)
			(xy 180.229244 -313.141996) (xy 180.209953 -313.09672) (xy 180.198176 -313.048936) (xy 180.194216 -312.999882)
			(xy 179.877212 -312.999882) (xy 179.876708 -313.02559) (xy 179.868665 -313.076372) (xy 179.852777 -313.125271)
			(xy 179.829434 -313.171083) (xy 179.799213 -313.212679) (xy 179.762857 -313.249035) (xy 179.721261 -313.279256)
			(xy 179.675449 -313.302599) (xy 179.62655 -313.318487) (xy 179.575768 -313.32653) (xy 179.524352 -313.32653)
			(xy 179.47357 -313.318487) (xy 179.424671 -313.302599) (xy 179.378859 -313.279256) (xy 179.337263 -313.249035)
			(xy 179.300907 -313.212679) (xy 179.270686 -313.171083) (xy 179.247343 -313.125271) (xy 179.231455 -313.076372)
			(xy 179.223412 -313.02559) (xy 178.90448 -313.02559) (xy 178.896764 -313.073066) (xy 178.88118 -313.119747)
			(xy 178.858309 -313.163324) (xy 178.828744 -313.202668) (xy 178.793251 -313.23676) (xy 178.752748 -313.264716)
			(xy 178.708286 -313.285814) (xy 178.661015 -313.299506) (xy 178.61216 -313.305438) (xy 178.562985 -313.303457)
			(xy 178.514766 -313.293613) (xy 178.46875 -313.276161) (xy 178.426129 -313.251554) (xy 178.388008 -313.220429)
			(xy 178.355373 -313.183592) (xy 178.32907 -313.141996) (xy 178.309779 -313.09672) (xy 178.298002 -313.048936)
			(xy 178.294042 -312.999882) (xy 177.977038 -312.999882) (xy 177.976534 -313.02559) (xy 177.968491 -313.076372)
			(xy 177.952603 -313.125271) (xy 177.92926 -313.171083) (xy 177.899039 -313.212679) (xy 177.862683 -313.249035)
			(xy 177.821087 -313.279256) (xy 177.775275 -313.302599) (xy 177.726376 -313.318487) (xy 177.675594 -313.32653)
			(xy 177.624178 -313.32653) (xy 177.573396 -313.318487) (xy 177.524497 -313.302599) (xy 177.478685 -313.279256)
			(xy 177.437089 -313.249035) (xy 177.400733 -313.212679) (xy 177.370512 -313.171083) (xy 177.347169 -313.125271)
			(xy 177.331281 -313.076372) (xy 177.323238 -313.02559) (xy 177.00456 -313.02559) (xy 176.996844 -313.073066)
			(xy 176.98126 -313.119747) (xy 176.958389 -313.163324) (xy 176.928824 -313.202668) (xy 176.893331 -313.23676)
			(xy 176.852828 -313.264716) (xy 176.808366 -313.285814) (xy 176.761095 -313.299506) (xy 176.71224 -313.305438)
			(xy 176.663065 -313.303457) (xy 176.614846 -313.293613) (xy 176.56883 -313.276161) (xy 176.526209 -313.251554)
			(xy 176.488088 -313.220429) (xy 176.455453 -313.183592) (xy 176.42915 -313.141996) (xy 176.409859 -313.09672)
			(xy 176.398082 -313.048936) (xy 176.394122 -312.999882) (xy 176.077118 -312.999882) (xy 176.076614 -313.02559)
			(xy 176.068571 -313.076372) (xy 176.052683 -313.125271) (xy 176.02934 -313.171083) (xy 175.999119 -313.212679)
			(xy 175.962763 -313.249035) (xy 175.921167 -313.279256) (xy 175.875355 -313.302599) (xy 175.826456 -313.318487)
			(xy 175.775674 -313.32653) (xy 175.724258 -313.32653) (xy 175.673476 -313.318487) (xy 175.624577 -313.302599)
			(xy 175.578765 -313.279256) (xy 175.537169 -313.249035) (xy 175.500813 -313.212679) (xy 175.470592 -313.171083)
			(xy 175.447249 -313.125271) (xy 175.431361 -313.076372) (xy 175.423318 -313.02559) (xy 175.10464 -313.02559)
			(xy 175.096924 -313.073066) (xy 175.08134 -313.119747) (xy 175.058469 -313.163324) (xy 175.028904 -313.202668)
			(xy 174.993411 -313.23676) (xy 174.952908 -313.264716) (xy 174.908446 -313.285814) (xy 174.861175 -313.299506)
			(xy 174.81232 -313.305438) (xy 174.763145 -313.303457) (xy 174.714926 -313.293613) (xy 174.66891 -313.276161)
			(xy 174.626289 -313.251554) (xy 174.588168 -313.220429) (xy 174.555533 -313.183592) (xy 174.52923 -313.141996)
			(xy 174.509939 -313.09672) (xy 174.498162 -313.048936) (xy 174.494202 -312.999882) (xy 174.177198 -312.999882)
			(xy 174.176694 -313.02559) (xy 174.168651 -313.076372) (xy 174.152763 -313.125271) (xy 174.12942 -313.171083)
			(xy 174.099199 -313.212679) (xy 174.062843 -313.249035) (xy 174.021247 -313.279256) (xy 173.975435 -313.302599)
			(xy 173.926536 -313.318487) (xy 173.875754 -313.32653) (xy 173.824338 -313.32653) (xy 173.773556 -313.318487)
			(xy 173.724657 -313.302599) (xy 173.678845 -313.279256) (xy 173.637249 -313.249035) (xy 173.600893 -313.212679)
			(xy 173.570672 -313.171083) (xy 173.547329 -313.125271) (xy 173.531441 -313.076372) (xy 173.523398 -313.02559)
			(xy 173.20472 -313.02559) (xy 173.197004 -313.073066) (xy 173.18142 -313.119747) (xy 173.158549 -313.163324)
			(xy 173.128984 -313.202668) (xy 173.093491 -313.23676) (xy 173.052988 -313.264716) (xy 173.008526 -313.285814)
			(xy 172.961255 -313.299506) (xy 172.9124 -313.305438) (xy 172.863225 -313.303457) (xy 172.815006 -313.293613)
			(xy 172.76899 -313.276161) (xy 172.726369 -313.251554) (xy 172.688248 -313.220429) (xy 172.655613 -313.183592)
			(xy 172.62931 -313.141996) (xy 172.610019 -313.09672) (xy 172.598242 -313.048936) (xy 172.594282 -312.999882)
			(xy 172.277024 -312.999882) (xy 172.27652 -313.02559) (xy 172.268477 -313.076372) (xy 172.252589 -313.125271)
			(xy 172.229246 -313.171083) (xy 172.199025 -313.212679) (xy 172.162669 -313.249035) (xy 172.121073 -313.279256)
			(xy 172.075261 -313.302599) (xy 172.026362 -313.318487) (xy 171.97558 -313.32653) (xy 171.924164 -313.32653)
			(xy 171.873382 -313.318487) (xy 171.824483 -313.302599) (xy 171.778671 -313.279256) (xy 171.737075 -313.249035)
			(xy 171.700719 -313.212679) (xy 171.670498 -313.171083) (xy 171.647155 -313.125271) (xy 171.631267 -313.076372)
			(xy 171.623224 -313.02559) (xy 171.304546 -313.02559) (xy 171.29683 -313.073066) (xy 171.281246 -313.119747)
			(xy 171.258375 -313.163324) (xy 171.22881 -313.202668) (xy 171.193317 -313.23676) (xy 171.152814 -313.264716)
			(xy 171.108352 -313.285814) (xy 171.061081 -313.299506) (xy 171.012226 -313.305438) (xy 170.963051 -313.303457)
			(xy 170.914832 -313.293613) (xy 170.868816 -313.276161) (xy 170.826195 -313.251554) (xy 170.788074 -313.220429)
			(xy 170.755439 -313.183592) (xy 170.729136 -313.141996) (xy 170.709845 -313.09672) (xy 170.698068 -313.048936)
			(xy 170.694108 -312.999882) (xy 170.377104 -312.999882) (xy 170.3766 -313.02559) (xy 170.368557 -313.076372)
			(xy 170.352669 -313.125271) (xy 170.329326 -313.171083) (xy 170.299105 -313.212679) (xy 170.262749 -313.249035)
			(xy 170.221153 -313.279256) (xy 170.175341 -313.302599) (xy 170.126442 -313.318487) (xy 170.07566 -313.32653)
			(xy 170.024244 -313.32653) (xy 169.973462 -313.318487) (xy 169.924563 -313.302599) (xy 169.878751 -313.279256)
			(xy 169.837155 -313.249035) (xy 169.800799 -313.212679) (xy 169.770578 -313.171083) (xy 169.747235 -313.125271)
			(xy 169.731347 -313.076372) (xy 169.723304 -313.02559) (xy 169.404626 -313.02559) (xy 169.39691 -313.073066)
			(xy 169.381326 -313.119747) (xy 169.358455 -313.163324) (xy 169.32889 -313.202668) (xy 169.293397 -313.23676)
			(xy 169.252894 -313.264716) (xy 169.208432 -313.285814) (xy 169.161161 -313.299506) (xy 169.112306 -313.305438)
			(xy 169.063131 -313.303457) (xy 169.014912 -313.293613) (xy 168.968896 -313.276161) (xy 168.926275 -313.251554)
			(xy 168.888154 -313.220429) (xy 168.855519 -313.183592) (xy 168.829216 -313.141996) (xy 168.809925 -313.09672)
			(xy 168.798148 -313.048936) (xy 168.794188 -312.999882) (xy 168.477184 -312.999882) (xy 168.47668 -313.02559)
			(xy 168.468637 -313.076372) (xy 168.452749 -313.125271) (xy 168.429406 -313.171083) (xy 168.399185 -313.212679)
			(xy 168.362829 -313.249035) (xy 168.321233 -313.279256) (xy 168.275421 -313.302599) (xy 168.226522 -313.318487)
			(xy 168.17574 -313.32653) (xy 168.124324 -313.32653) (xy 168.073542 -313.318487) (xy 168.024643 -313.302599)
			(xy 167.978831 -313.279256) (xy 167.937235 -313.249035) (xy 167.900879 -313.212679) (xy 167.870658 -313.171083)
			(xy 167.847315 -313.125271) (xy 167.831427 -313.076372) (xy 167.823384 -313.02559) (xy 167.504706 -313.02559)
			(xy 167.49699 -313.073066) (xy 167.481406 -313.119747) (xy 167.458535 -313.163324) (xy 167.42897 -313.202668)
			(xy 167.393477 -313.23676) (xy 167.352974 -313.264716) (xy 167.308512 -313.285814) (xy 167.261241 -313.299506)
			(xy 167.212386 -313.305438) (xy 167.163211 -313.303457) (xy 167.114992 -313.293613) (xy 167.068976 -313.276161)
			(xy 167.026355 -313.251554) (xy 166.988234 -313.220429) (xy 166.955599 -313.183592) (xy 166.929296 -313.141996)
			(xy 166.910005 -313.09672) (xy 166.898228 -313.048936) (xy 166.894268 -312.999882) (xy 166.555166 -312.999882)
			(xy 166.554671 -313.024489) (xy 166.546776 -313.073066) (xy 166.531192 -313.119747) (xy 166.508321 -313.163324)
			(xy 166.478756 -313.202668) (xy 166.443263 -313.23676) (xy 166.40276 -313.264716) (xy 166.358298 -313.285814)
			(xy 166.311027 -313.299506) (xy 166.262172 -313.305438) (xy 166.212997 -313.303457) (xy 166.164778 -313.293613)
			(xy 166.118762 -313.276161) (xy 166.076141 -313.251554) (xy 166.03802 -313.220429) (xy 166.005385 -313.183592)
			(xy 165.979082 -313.141996) (xy 165.959791 -313.09672) (xy 165.948014 -313.048936) (xy 165.944054 -312.999882)
			(xy 165.605777 -312.999882) (xy 165.605778 -312.9999) (xy 165.601606 -313.050246) (xy 165.589205 -313.099219)
			(xy 165.568911 -313.145482) (xy 165.54128 -313.187775) (xy 165.507065 -313.224942) (xy 165.467198 -313.255972)
			(xy 165.422768 -313.280016) (xy 165.374987 -313.296419) (xy 165.325157 -313.304733) (xy 165.299898 -313.30519)
			(xy 165.29073 -313.305097) (xy 165.27243 -313.303954) (xy 165.263322 -313.302904) (xy 165.251384 -313.301634)
			(xy 165.240462 -313.305444) (xy 165.234884 -313.307609) (xy 165.224873 -313.314158) (xy 165.22065 -313.318398)
			(xy 165.164262 -313.377326) (xy 165.161468 -313.380374) (xy 165.158569 -313.38417) (xy 165.154099 -313.39261)
			(xy 165.152578 -313.397138) (xy 165.149022 -313.408568) (xy 165.151054 -313.420506) (xy 165.154994 -313.447544)
			(xy 165.155 -313.502181) (xy 165.151054 -313.529218) (xy 165.149022 -313.541156) (xy 165.152578 -313.552586)
			(xy 165.154092 -313.557117) (xy 165.158566 -313.565556) (xy 165.161468 -313.56935) (xy 165.164262 -313.572398)
			(xy 165.22065 -313.631326) (xy 165.224877 -313.635561) (xy 165.234885 -313.642114) (xy 165.240462 -313.64428)
			(xy 165.251384 -313.64809) (xy 165.263322 -313.64682) (xy 165.27243 -313.645767) (xy 165.29073 -313.644625)
			(xy 165.299898 -313.644534) (xy 165.325152 -313.645026) (xy 165.374972 -313.65334) (xy 165.422744 -313.669739)
			(xy 165.467166 -313.693779) (xy 165.507024 -313.724802) (xy 165.541233 -313.761962) (xy 165.568859 -313.804246)
			(xy 165.589148 -313.850501) (xy 165.601547 -313.899464) (xy 165.605718 -313.9498) (xy 165.605715 -313.949842)
			(xy 165.944054 -313.949842) (xy 165.948014 -313.900788) (xy 165.959791 -313.853004) (xy 165.979082 -313.807728)
			(xy 166.005385 -313.766132) (xy 166.03802 -313.729295) (xy 166.076141 -313.69817) (xy 166.118762 -313.673563)
			(xy 166.164778 -313.656111) (xy 166.212997 -313.646267) (xy 166.262172 -313.644286) (xy 166.311027 -313.650218)
			(xy 166.358298 -313.66391) (xy 166.40276 -313.685008) (xy 166.443263 -313.712964) (xy 166.478756 -313.747056)
			(xy 166.508321 -313.7864) (xy 166.531192 -313.829977) (xy 166.546776 -313.876658) (xy 166.554671 -313.925235)
			(xy 166.555166 -313.949842) (xy 166.894268 -313.949842) (xy 166.898228 -313.900788) (xy 166.910005 -313.853004)
			(xy 166.929296 -313.807728) (xy 166.955599 -313.766132) (xy 166.988234 -313.729295) (xy 167.026355 -313.69817)
			(xy 167.068976 -313.673563) (xy 167.114992 -313.656111) (xy 167.163211 -313.646267) (xy 167.212386 -313.644286)
			(xy 167.261241 -313.650218) (xy 167.308512 -313.66391) (xy 167.352974 -313.685008) (xy 167.393477 -313.712964)
			(xy 167.42897 -313.747056) (xy 167.458535 -313.7864) (xy 167.481406 -313.829977) (xy 167.49699 -313.876658)
			(xy 167.504885 -313.925235) (xy 167.50538 -313.949842) (xy 167.504885 -313.974449) (xy 167.504706 -313.97555)
			(xy 167.823384 -313.97555) (xy 167.823384 -313.924134) (xy 167.831427 -313.873352) (xy 167.847315 -313.824453)
			(xy 167.870658 -313.778641) (xy 167.900879 -313.737045) (xy 167.937235 -313.700689) (xy 167.978831 -313.670468)
			(xy 168.024643 -313.647125) (xy 168.073542 -313.631237) (xy 168.124324 -313.623194) (xy 168.17574 -313.623194)
			(xy 168.226522 -313.631237) (xy 168.275421 -313.647125) (xy 168.321233 -313.670468) (xy 168.362829 -313.700689)
			(xy 168.399185 -313.737045) (xy 168.429406 -313.778641) (xy 168.452749 -313.824453) (xy 168.468637 -313.873352)
			(xy 168.47668 -313.924134) (xy 168.477184 -313.949842) (xy 168.794188 -313.949842) (xy 168.798148 -313.900788)
			(xy 168.809925 -313.853004) (xy 168.829216 -313.807728) (xy 168.855519 -313.766132) (xy 168.888154 -313.729295)
			(xy 168.926275 -313.69817) (xy 168.968896 -313.673563) (xy 169.014912 -313.656111) (xy 169.063131 -313.646267)
			(xy 169.112306 -313.644286) (xy 169.161161 -313.650218) (xy 169.208432 -313.66391) (xy 169.252894 -313.685008)
			(xy 169.293397 -313.712964) (xy 169.32889 -313.747056) (xy 169.358455 -313.7864) (xy 169.381326 -313.829977)
			(xy 169.39691 -313.876658) (xy 169.404805 -313.925235) (xy 169.4053 -313.949842) (xy 169.404805 -313.974449)
			(xy 169.404626 -313.97555) (xy 169.723304 -313.97555) (xy 169.723304 -313.924134) (xy 169.731347 -313.873352)
			(xy 169.747235 -313.824453) (xy 169.770578 -313.778641) (xy 169.800799 -313.737045) (xy 169.837155 -313.700689)
			(xy 169.878751 -313.670468) (xy 169.924563 -313.647125) (xy 169.973462 -313.631237) (xy 170.024244 -313.623194)
			(xy 170.07566 -313.623194) (xy 170.126442 -313.631237) (xy 170.175341 -313.647125) (xy 170.221153 -313.670468)
			(xy 170.262749 -313.700689) (xy 170.299105 -313.737045) (xy 170.329326 -313.778641) (xy 170.352669 -313.824453)
			(xy 170.368557 -313.873352) (xy 170.3766 -313.924134) (xy 170.377104 -313.949842) (xy 170.694108 -313.949842)
			(xy 170.698068 -313.900788) (xy 170.709845 -313.853004) (xy 170.729136 -313.807728) (xy 170.755439 -313.766132)
			(xy 170.788074 -313.729295) (xy 170.826195 -313.69817) (xy 170.868816 -313.673563) (xy 170.914832 -313.656111)
			(xy 170.963051 -313.646267) (xy 171.012226 -313.644286) (xy 171.061081 -313.650218) (xy 171.108352 -313.66391)
			(xy 171.152814 -313.685008) (xy 171.193317 -313.712964) (xy 171.22881 -313.747056) (xy 171.258375 -313.7864)
			(xy 171.281246 -313.829977) (xy 171.29683 -313.876658) (xy 171.304725 -313.925235) (xy 171.30522 -313.949842)
			(xy 171.304725 -313.974449) (xy 171.304546 -313.97555) (xy 171.623224 -313.97555) (xy 171.623224 -313.924134)
			(xy 171.631267 -313.873352) (xy 171.647155 -313.824453) (xy 171.670498 -313.778641) (xy 171.700719 -313.737045)
			(xy 171.737075 -313.700689) (xy 171.778671 -313.670468) (xy 171.824483 -313.647125) (xy 171.873382 -313.631237)
			(xy 171.924164 -313.623194) (xy 171.97558 -313.623194) (xy 172.026362 -313.631237) (xy 172.075261 -313.647125)
			(xy 172.121073 -313.670468) (xy 172.162669 -313.700689) (xy 172.199025 -313.737045) (xy 172.229246 -313.778641)
			(xy 172.252589 -313.824453) (xy 172.268477 -313.873352) (xy 172.27652 -313.924134) (xy 172.277024 -313.949842)
			(xy 172.594282 -313.949842) (xy 172.598242 -313.900788) (xy 172.610019 -313.853004) (xy 172.62931 -313.807728)
			(xy 172.655613 -313.766132) (xy 172.688248 -313.729295) (xy 172.726369 -313.69817) (xy 172.76899 -313.673563)
			(xy 172.815006 -313.656111) (xy 172.863225 -313.646267) (xy 172.9124 -313.644286) (xy 172.961255 -313.650218)
			(xy 173.008526 -313.66391) (xy 173.052988 -313.685008) (xy 173.093491 -313.712964) (xy 173.128984 -313.747056)
			(xy 173.158549 -313.7864) (xy 173.18142 -313.829977) (xy 173.197004 -313.876658) (xy 173.204899 -313.925235)
			(xy 173.205394 -313.949842) (xy 173.204899 -313.974449) (xy 173.20472 -313.97555) (xy 173.523398 -313.97555)
			(xy 173.523398 -313.924134) (xy 173.531441 -313.873352) (xy 173.547329 -313.824453) (xy 173.570672 -313.778641)
			(xy 173.600893 -313.737045) (xy 173.637249 -313.700689) (xy 173.678845 -313.670468) (xy 173.724657 -313.647125)
			(xy 173.773556 -313.631237) (xy 173.824338 -313.623194) (xy 173.875754 -313.623194) (xy 173.926536 -313.631237)
			(xy 173.975435 -313.647125) (xy 174.021247 -313.670468) (xy 174.062843 -313.700689) (xy 174.099199 -313.737045)
			(xy 174.12942 -313.778641) (xy 174.152763 -313.824453) (xy 174.168651 -313.873352) (xy 174.176694 -313.924134)
			(xy 174.177198 -313.949842) (xy 174.494202 -313.949842) (xy 174.498162 -313.900788) (xy 174.509939 -313.853004)
			(xy 174.52923 -313.807728) (xy 174.555533 -313.766132) (xy 174.588168 -313.729295) (xy 174.626289 -313.69817)
			(xy 174.66891 -313.673563) (xy 174.714926 -313.656111) (xy 174.763145 -313.646267) (xy 174.81232 -313.644286)
			(xy 174.861175 -313.650218) (xy 174.908446 -313.66391) (xy 174.952908 -313.685008) (xy 174.993411 -313.712964)
			(xy 175.028904 -313.747056) (xy 175.058469 -313.7864) (xy 175.08134 -313.829977) (xy 175.096924 -313.876658)
			(xy 175.104819 -313.925235) (xy 175.105314 -313.949842) (xy 175.104819 -313.974449) (xy 175.10464 -313.97555)
			(xy 175.423318 -313.97555) (xy 175.423318 -313.924134) (xy 175.431361 -313.873352) (xy 175.447249 -313.824453)
			(xy 175.470592 -313.778641) (xy 175.500813 -313.737045) (xy 175.537169 -313.700689) (xy 175.578765 -313.670468)
			(xy 175.624577 -313.647125) (xy 175.673476 -313.631237) (xy 175.724258 -313.623194) (xy 175.775674 -313.623194)
			(xy 175.826456 -313.631237) (xy 175.875355 -313.647125) (xy 175.921167 -313.670468) (xy 175.962763 -313.700689)
			(xy 175.999119 -313.737045) (xy 176.02934 -313.778641) (xy 176.052683 -313.824453) (xy 176.068571 -313.873352)
			(xy 176.076614 -313.924134) (xy 176.077118 -313.949842) (xy 176.394122 -313.949842) (xy 176.398082 -313.900788)
			(xy 176.409859 -313.853004) (xy 176.42915 -313.807728) (xy 176.455453 -313.766132) (xy 176.488088 -313.729295)
			(xy 176.526209 -313.69817) (xy 176.56883 -313.673563) (xy 176.614846 -313.656111) (xy 176.663065 -313.646267)
			(xy 176.71224 -313.644286) (xy 176.761095 -313.650218) (xy 176.808366 -313.66391) (xy 176.852828 -313.685008)
			(xy 176.893331 -313.712964) (xy 176.928824 -313.747056) (xy 176.958389 -313.7864) (xy 176.98126 -313.829977)
			(xy 176.996844 -313.876658) (xy 177.004739 -313.925235) (xy 177.005234 -313.949842) (xy 177.004739 -313.974449)
			(xy 177.00456 -313.97555) (xy 177.323238 -313.97555) (xy 177.323238 -313.924134) (xy 177.331281 -313.873352)
			(xy 177.347169 -313.824453) (xy 177.370512 -313.778641) (xy 177.400733 -313.737045) (xy 177.437089 -313.700689)
			(xy 177.478685 -313.670468) (xy 177.524497 -313.647125) (xy 177.573396 -313.631237) (xy 177.624178 -313.623194)
			(xy 177.675594 -313.623194) (xy 177.726376 -313.631237) (xy 177.775275 -313.647125) (xy 177.821087 -313.670468)
			(xy 177.862683 -313.700689) (xy 177.899039 -313.737045) (xy 177.92926 -313.778641) (xy 177.952603 -313.824453)
			(xy 177.968491 -313.873352) (xy 177.976534 -313.924134) (xy 177.977038 -313.949842) (xy 178.294042 -313.949842)
			(xy 178.298002 -313.900788) (xy 178.309779 -313.853004) (xy 178.32907 -313.807728) (xy 178.355373 -313.766132)
			(xy 178.388008 -313.729295) (xy 178.426129 -313.69817) (xy 178.46875 -313.673563) (xy 178.514766 -313.656111)
			(xy 178.562985 -313.646267) (xy 178.61216 -313.644286) (xy 178.661015 -313.650218) (xy 178.708286 -313.66391)
			(xy 178.752748 -313.685008) (xy 178.793251 -313.712964) (xy 178.828744 -313.747056) (xy 178.858309 -313.7864)
			(xy 178.88118 -313.829977) (xy 178.896764 -313.876658) (xy 178.904659 -313.925235) (xy 178.905154 -313.949842)
			(xy 178.904659 -313.974449) (xy 178.90448 -313.97555) (xy 179.223412 -313.97555) (xy 179.223412 -313.924134)
			(xy 179.231455 -313.873352) (xy 179.247343 -313.824453) (xy 179.270686 -313.778641) (xy 179.300907 -313.737045)
			(xy 179.337263 -313.700689) (xy 179.378859 -313.670468) (xy 179.424671 -313.647125) (xy 179.47357 -313.631237)
			(xy 179.524352 -313.623194) (xy 179.575768 -313.623194) (xy 179.62655 -313.631237) (xy 179.675449 -313.647125)
			(xy 179.721261 -313.670468) (xy 179.762857 -313.700689) (xy 179.799213 -313.737045) (xy 179.829434 -313.778641)
			(xy 179.852777 -313.824453) (xy 179.868665 -313.873352) (xy 179.876708 -313.924134) (xy 179.877212 -313.949842)
			(xy 180.194216 -313.949842) (xy 180.198176 -313.900788) (xy 180.209953 -313.853004) (xy 180.229244 -313.807728)
			(xy 180.255547 -313.766132) (xy 180.288182 -313.729295) (xy 180.326303 -313.69817) (xy 180.368924 -313.673563)
			(xy 180.41494 -313.656111) (xy 180.463159 -313.646267) (xy 180.512334 -313.644286) (xy 180.561189 -313.650218)
			(xy 180.60846 -313.66391) (xy 180.652922 -313.685008) (xy 180.693425 -313.712964) (xy 180.728918 -313.747056)
			(xy 180.758483 -313.7864) (xy 180.781354 -313.829977) (xy 180.796938 -313.876658) (xy 180.804833 -313.925235)
			(xy 180.805328 -313.949842) (xy 180.804833 -313.974449) (xy 180.804654 -313.97555) (xy 181.123332 -313.97555)
			(xy 181.123332 -313.924134) (xy 181.131375 -313.873352) (xy 181.147263 -313.824453) (xy 181.170606 -313.778641)
			(xy 181.200827 -313.737045) (xy 181.237183 -313.700689) (xy 181.278779 -313.670468) (xy 181.324591 -313.647125)
			(xy 181.37349 -313.631237) (xy 181.424272 -313.623194) (xy 181.475688 -313.623194) (xy 181.52647 -313.631237)
			(xy 181.575369 -313.647125) (xy 181.621181 -313.670468) (xy 181.662777 -313.700689) (xy 181.699133 -313.737045)
			(xy 181.729354 -313.778641) (xy 181.752697 -313.824453) (xy 181.768585 -313.873352) (xy 181.776628 -313.924134)
			(xy 181.777132 -313.949842) (xy 182.094136 -313.949842) (xy 182.098096 -313.900788) (xy 182.109873 -313.853004)
			(xy 182.129164 -313.807728) (xy 182.155467 -313.766132) (xy 182.188102 -313.729295) (xy 182.226223 -313.69817)
			(xy 182.268844 -313.673563) (xy 182.31486 -313.656111) (xy 182.363079 -313.646267) (xy 182.412254 -313.644286)
			(xy 182.461109 -313.650218) (xy 182.50838 -313.66391) (xy 182.552842 -313.685008) (xy 182.593345 -313.712964)
			(xy 182.628838 -313.747056) (xy 182.658403 -313.7864) (xy 182.681274 -313.829977) (xy 182.696858 -313.876658)
			(xy 182.704753 -313.925235) (xy 182.705248 -313.949842) (xy 183.044096 -313.949842) (xy 183.048056 -313.900788)
			(xy 183.059833 -313.853004) (xy 183.079124 -313.807728) (xy 183.105427 -313.766132) (xy 183.138062 -313.729295)
			(xy 183.176183 -313.69817) (xy 183.218804 -313.673563) (xy 183.26482 -313.656111) (xy 183.313039 -313.646267)
			(xy 183.362214 -313.644286) (xy 183.411069 -313.650218) (xy 183.45834 -313.66391) (xy 183.502802 -313.685008)
			(xy 183.543305 -313.712964) (xy 183.578798 -313.747056) (xy 183.608363 -313.7864) (xy 183.631234 -313.829977)
			(xy 183.646818 -313.876658) (xy 183.654713 -313.925235) (xy 183.655208 -313.949842) (xy 183.994056 -313.949842)
			(xy 183.998016 -313.900788) (xy 184.009793 -313.853004) (xy 184.029084 -313.807728) (xy 184.055387 -313.766132)
			(xy 184.088022 -313.729295) (xy 184.126143 -313.69817) (xy 184.168764 -313.673563) (xy 184.21478 -313.656111)
			(xy 184.262999 -313.646267) (xy 184.312174 -313.644286) (xy 184.361029 -313.650218) (xy 184.4083 -313.66391)
			(xy 184.452762 -313.685008) (xy 184.493265 -313.712964) (xy 184.528758 -313.747056) (xy 184.558323 -313.7864)
			(xy 184.581194 -313.829977) (xy 184.596778 -313.876658) (xy 184.604673 -313.925235) (xy 184.605168 -313.949842)
			(xy 184.94427 -313.949842) (xy 184.94823 -313.900788) (xy 184.960007 -313.853004) (xy 184.979298 -313.807728)
			(xy 185.005601 -313.766132) (xy 185.038236 -313.729295) (xy 185.076357 -313.69817) (xy 185.118978 -313.673563)
			(xy 185.164994 -313.656111) (xy 185.213213 -313.646267) (xy 185.262388 -313.644286) (xy 185.311243 -313.650218)
			(xy 185.358514 -313.66391) (xy 185.402976 -313.685008) (xy 185.443479 -313.712964) (xy 185.478972 -313.747056)
			(xy 185.508537 -313.7864) (xy 185.531408 -313.829977) (xy 185.546992 -313.876658) (xy 185.554887 -313.925235)
			(xy 185.555382 -313.949842) (xy 185.89423 -313.949842) (xy 185.89819 -313.900788) (xy 185.909967 -313.853004)
			(xy 185.929258 -313.807728) (xy 185.955561 -313.766132) (xy 185.988196 -313.729295) (xy 186.026317 -313.69817)
			(xy 186.068938 -313.673563) (xy 186.114954 -313.656111) (xy 186.163173 -313.646267) (xy 186.212348 -313.644286)
			(xy 186.261203 -313.650218) (xy 186.308474 -313.66391) (xy 186.352936 -313.685008) (xy 186.393439 -313.712964)
			(xy 186.428932 -313.747056) (xy 186.458497 -313.7864) (xy 186.481368 -313.829977) (xy 186.496952 -313.876658)
			(xy 186.504847 -313.925235) (xy 186.505342 -313.949842) (xy 186.84419 -313.949842) (xy 186.84815 -313.900788)
			(xy 186.859927 -313.853004) (xy 186.879218 -313.807728) (xy 186.905521 -313.766132) (xy 186.938156 -313.729295)
			(xy 186.976277 -313.69817) (xy 187.018898 -313.673563) (xy 187.064914 -313.656111) (xy 187.113133 -313.646267)
			(xy 187.162308 -313.644286) (xy 187.211163 -313.650218) (xy 187.258434 -313.66391) (xy 187.302896 -313.685008)
			(xy 187.343399 -313.712964) (xy 187.378892 -313.747056) (xy 187.408457 -313.7864) (xy 187.431328 -313.829977)
			(xy 187.446912 -313.876658) (xy 187.454807 -313.925235) (xy 187.455302 -313.949842) (xy 187.79415 -313.949842)
			(xy 187.79811 -313.900788) (xy 187.809887 -313.853004) (xy 187.829178 -313.807728) (xy 187.855481 -313.766132)
			(xy 187.888116 -313.729295) (xy 187.926237 -313.69817) (xy 187.968858 -313.673563) (xy 188.014874 -313.656111)
			(xy 188.063093 -313.646267) (xy 188.112268 -313.644286) (xy 188.161123 -313.650218) (xy 188.208394 -313.66391)
			(xy 188.252856 -313.685008) (xy 188.293359 -313.712964) (xy 188.328852 -313.747056) (xy 188.358417 -313.7864)
			(xy 188.381288 -313.829977) (xy 188.396872 -313.876658) (xy 188.404767 -313.925235) (xy 188.405262 -313.949842)
			(xy 188.74411 -313.949842) (xy 188.74807 -313.900788) (xy 188.759847 -313.853004) (xy 188.779138 -313.807728)
			(xy 188.805441 -313.766132) (xy 188.838076 -313.729295) (xy 188.876197 -313.69817) (xy 188.918818 -313.673563)
			(xy 188.964834 -313.656111) (xy 189.013053 -313.646267) (xy 189.062228 -313.644286) (xy 189.111083 -313.650218)
			(xy 189.158354 -313.66391) (xy 189.202816 -313.685008) (xy 189.243319 -313.712964) (xy 189.278812 -313.747056)
			(xy 189.308377 -313.7864) (xy 189.331248 -313.829977) (xy 189.346832 -313.876658) (xy 189.354727 -313.925235)
			(xy 189.355222 -313.949842) (xy 189.69407 -313.949842) (xy 189.69803 -313.900788) (xy 189.709807 -313.853004)
			(xy 189.729098 -313.807728) (xy 189.755401 -313.766132) (xy 189.788036 -313.729295) (xy 189.826157 -313.69817)
			(xy 189.868778 -313.673563) (xy 189.914794 -313.656111) (xy 189.963013 -313.646267) (xy 190.012188 -313.644286)
			(xy 190.061043 -313.650218) (xy 190.108314 -313.66391) (xy 190.152776 -313.685008) (xy 190.193279 -313.712964)
			(xy 190.228772 -313.747056) (xy 190.258337 -313.7864) (xy 190.281208 -313.829977) (xy 190.296792 -313.876658)
			(xy 190.304687 -313.925235) (xy 190.305182 -313.949842) (xy 190.304687 -313.974449) (xy 190.304508 -313.97555)
			(xy 190.62344 -313.97555) (xy 190.62344 -313.924134) (xy 190.631483 -313.873352) (xy 190.647371 -313.824453)
			(xy 190.670714 -313.778641) (xy 190.700935 -313.737045) (xy 190.737291 -313.700689) (xy 190.778887 -313.670468)
			(xy 190.824699 -313.647125) (xy 190.873598 -313.631237) (xy 190.92438 -313.623194) (xy 190.975796 -313.623194)
			(xy 191.026578 -313.631237) (xy 191.075477 -313.647125) (xy 191.121289 -313.670468) (xy 191.162885 -313.700689)
			(xy 191.199241 -313.737045) (xy 191.229462 -313.778641) (xy 191.252805 -313.824453) (xy 191.268693 -313.873352)
			(xy 191.276736 -313.924134) (xy 191.27724 -313.949842) (xy 191.594244 -313.949842) (xy 191.598204 -313.900788)
			(xy 191.609981 -313.853004) (xy 191.629272 -313.807728) (xy 191.655575 -313.766132) (xy 191.68821 -313.729295)
			(xy 191.726331 -313.69817) (xy 191.768952 -313.673563) (xy 191.814968 -313.656111) (xy 191.863187 -313.646267)
			(xy 191.912362 -313.644286) (xy 191.961217 -313.650218) (xy 192.008488 -313.66391) (xy 192.05295 -313.685008)
			(xy 192.093453 -313.712964) (xy 192.128946 -313.747056) (xy 192.158511 -313.7864) (xy 192.181382 -313.829977)
			(xy 192.196966 -313.876658) (xy 192.204861 -313.925235) (xy 192.205356 -313.949842) (xy 192.204861 -313.974449)
			(xy 192.204682 -313.97555) (xy 192.52336 -313.97555) (xy 192.52336 -313.924134) (xy 192.531403 -313.873352)
			(xy 192.547291 -313.824453) (xy 192.570634 -313.778641) (xy 192.600855 -313.737045) (xy 192.637211 -313.700689)
			(xy 192.678807 -313.670468) (xy 192.724619 -313.647125) (xy 192.773518 -313.631237) (xy 192.8243 -313.623194)
			(xy 192.875716 -313.623194) (xy 192.926498 -313.631237) (xy 192.975397 -313.647125) (xy 193.021209 -313.670468)
			(xy 193.062805 -313.700689) (xy 193.099161 -313.737045) (xy 193.129382 -313.778641) (xy 193.152725 -313.824453)
			(xy 193.168613 -313.873352) (xy 193.176656 -313.924134) (xy 193.17716 -313.949842) (xy 193.494164 -313.949842)
			(xy 193.498124 -313.900788) (xy 193.509901 -313.853004) (xy 193.529192 -313.807728) (xy 193.555495 -313.766132)
			(xy 193.58813 -313.729295) (xy 193.626251 -313.69817) (xy 193.668872 -313.673563) (xy 193.714888 -313.656111)
			(xy 193.763107 -313.646267) (xy 193.812282 -313.644286) (xy 193.861137 -313.650218) (xy 193.908408 -313.66391)
			(xy 193.95287 -313.685008) (xy 193.993373 -313.712964) (xy 194.028866 -313.747056) (xy 194.058431 -313.7864)
			(xy 194.081302 -313.829977) (xy 194.096886 -313.876658) (xy 194.104781 -313.925235) (xy 194.105276 -313.949842)
			(xy 194.104781 -313.974449) (xy 194.104602 -313.97555) (xy 194.42328 -313.97555) (xy 194.42328 -313.924134)
			(xy 194.431323 -313.873352) (xy 194.447211 -313.824453) (xy 194.470554 -313.778641) (xy 194.500775 -313.737045)
			(xy 194.537131 -313.700689) (xy 194.578727 -313.670468) (xy 194.624539 -313.647125) (xy 194.673438 -313.631237)
			(xy 194.72422 -313.623194) (xy 194.775636 -313.623194) (xy 194.826418 -313.631237) (xy 194.875317 -313.647125)
			(xy 194.921129 -313.670468) (xy 194.962725 -313.700689) (xy 194.999081 -313.737045) (xy 195.029302 -313.778641)
			(xy 195.052645 -313.824453) (xy 195.068533 -313.873352) (xy 195.076576 -313.924134) (xy 195.07708 -313.949842)
			(xy 195.394084 -313.949842) (xy 195.398044 -313.900788) (xy 195.409821 -313.853004) (xy 195.429112 -313.807728)
			(xy 195.455415 -313.766132) (xy 195.48805 -313.729295) (xy 195.526171 -313.69817) (xy 195.568792 -313.673563)
			(xy 195.614808 -313.656111) (xy 195.663027 -313.646267) (xy 195.712202 -313.644286) (xy 195.761057 -313.650218)
			(xy 195.808328 -313.66391) (xy 195.85279 -313.685008) (xy 195.893293 -313.712964) (xy 195.928786 -313.747056)
			(xy 195.958351 -313.7864) (xy 195.981222 -313.829977) (xy 195.996806 -313.876658) (xy 196.004701 -313.925235)
			(xy 196.005196 -313.949842) (xy 196.004701 -313.974449) (xy 196.004522 -313.97555) (xy 196.3232 -313.97555)
			(xy 196.3232 -313.924134) (xy 196.331243 -313.873352) (xy 196.347131 -313.824453) (xy 196.370474 -313.778641)
			(xy 196.400695 -313.737045) (xy 196.437051 -313.700689) (xy 196.478647 -313.670468) (xy 196.524459 -313.647125)
			(xy 196.573358 -313.631237) (xy 196.62414 -313.623194) (xy 196.675556 -313.623194) (xy 196.726338 -313.631237)
			(xy 196.775237 -313.647125) (xy 196.821049 -313.670468) (xy 196.862645 -313.700689) (xy 196.899001 -313.737045)
			(xy 196.929222 -313.778641) (xy 196.952565 -313.824453) (xy 196.968453 -313.873352) (xy 196.976496 -313.924134)
			(xy 196.977 -313.949842) (xy 197.294258 -313.949842) (xy 197.298218 -313.900788) (xy 197.309995 -313.853004)
			(xy 197.329286 -313.807728) (xy 197.355589 -313.766132) (xy 197.388224 -313.729295) (xy 197.426345 -313.69817)
			(xy 197.468966 -313.673563) (xy 197.514982 -313.656111) (xy 197.563201 -313.646267) (xy 197.612376 -313.644286)
			(xy 197.661231 -313.650218) (xy 197.708502 -313.66391) (xy 197.752964 -313.685008) (xy 197.793467 -313.712964)
			(xy 197.82896 -313.747056) (xy 197.858525 -313.7864) (xy 197.881396 -313.829977) (xy 197.89698 -313.876658)
			(xy 197.904875 -313.925235) (xy 197.90537 -313.949842) (xy 198.244218 -313.949842) (xy 198.248178 -313.900788)
			(xy 198.259955 -313.853004) (xy 198.279246 -313.807728) (xy 198.305549 -313.766132) (xy 198.338184 -313.729295)
			(xy 198.376305 -313.69817) (xy 198.418926 -313.673563) (xy 198.464942 -313.656111) (xy 198.513161 -313.646267)
			(xy 198.562336 -313.644286) (xy 198.611191 -313.650218) (xy 198.658462 -313.66391) (xy 198.702924 -313.685008)
			(xy 198.743427 -313.712964) (xy 198.77892 -313.747056) (xy 198.808485 -313.7864) (xy 198.831356 -313.829977)
			(xy 198.84694 -313.876658) (xy 198.854835 -313.925235) (xy 198.85533 -313.949842) (xy 198.854835 -313.974449)
			(xy 198.84694 -314.023026) (xy 198.831356 -314.069707) (xy 198.808485 -314.113284) (xy 198.77892 -314.152628)
			(xy 198.743427 -314.18672) (xy 198.702924 -314.214676) (xy 198.658462 -314.235774) (xy 198.611191 -314.249466)
			(xy 198.562336 -314.255398) (xy 198.513161 -314.253417) (xy 198.464942 -314.243573) (xy 198.418926 -314.226121)
			(xy 198.376305 -314.201514) (xy 198.338184 -314.170389) (xy 198.305549 -314.133552) (xy 198.279246 -314.091956)
			(xy 198.259955 -314.04668) (xy 198.248178 -313.998896) (xy 198.244218 -313.949842) (xy 197.90537 -313.949842)
			(xy 197.904875 -313.974449) (xy 197.89698 -314.023026) (xy 197.881396 -314.069707) (xy 197.858525 -314.113284)
			(xy 197.82896 -314.152628) (xy 197.793467 -314.18672) (xy 197.752964 -314.214676) (xy 197.708502 -314.235774)
			(xy 197.661231 -314.249466) (xy 197.612376 -314.255398) (xy 197.563201 -314.253417) (xy 197.514982 -314.243573)
			(xy 197.468966 -314.226121) (xy 197.426345 -314.201514) (xy 197.388224 -314.170389) (xy 197.355589 -314.133552)
			(xy 197.329286 -314.091956) (xy 197.309995 -314.04668) (xy 197.298218 -313.998896) (xy 197.294258 -313.949842)
			(xy 196.977 -313.949842) (xy 196.976496 -313.97555) (xy 196.968453 -314.026332) (xy 196.952565 -314.075231)
			(xy 196.929222 -314.121043) (xy 196.899001 -314.162639) (xy 196.862645 -314.198995) (xy 196.821049 -314.229216)
			(xy 196.775237 -314.252559) (xy 196.726338 -314.268447) (xy 196.675556 -314.27649) (xy 196.62414 -314.27649)
			(xy 196.573358 -314.268447) (xy 196.524459 -314.252559) (xy 196.478647 -314.229216) (xy 196.437051 -314.198995)
			(xy 196.400695 -314.162639) (xy 196.370474 -314.121043) (xy 196.347131 -314.075231) (xy 196.331243 -314.026332)
			(xy 196.3232 -313.97555) (xy 196.004522 -313.97555) (xy 195.996806 -314.023026) (xy 195.981222 -314.069707)
			(xy 195.958351 -314.113284) (xy 195.928786 -314.152628) (xy 195.893293 -314.18672) (xy 195.85279 -314.214676)
			(xy 195.808328 -314.235774) (xy 195.761057 -314.249466) (xy 195.712202 -314.255398) (xy 195.663027 -314.253417)
			(xy 195.614808 -314.243573) (xy 195.568792 -314.226121) (xy 195.526171 -314.201514) (xy 195.48805 -314.170389)
			(xy 195.455415 -314.133552) (xy 195.429112 -314.091956) (xy 195.409821 -314.04668) (xy 195.398044 -313.998896)
			(xy 195.394084 -313.949842) (xy 195.07708 -313.949842) (xy 195.076576 -313.97555) (xy 195.068533 -314.026332)
			(xy 195.052645 -314.075231) (xy 195.029302 -314.121043) (xy 194.999081 -314.162639) (xy 194.962725 -314.198995)
			(xy 194.921129 -314.229216) (xy 194.875317 -314.252559) (xy 194.826418 -314.268447) (xy 194.775636 -314.27649)
			(xy 194.72422 -314.27649) (xy 194.673438 -314.268447) (xy 194.624539 -314.252559) (xy 194.578727 -314.229216)
			(xy 194.537131 -314.198995) (xy 194.500775 -314.162639) (xy 194.470554 -314.121043) (xy 194.447211 -314.075231)
			(xy 194.431323 -314.026332) (xy 194.42328 -313.97555) (xy 194.104602 -313.97555) (xy 194.096886 -314.023026)
			(xy 194.081302 -314.069707) (xy 194.058431 -314.113284) (xy 194.028866 -314.152628) (xy 193.993373 -314.18672)
			(xy 193.95287 -314.214676) (xy 193.908408 -314.235774) (xy 193.861137 -314.249466) (xy 193.812282 -314.255398)
			(xy 193.763107 -314.253417) (xy 193.714888 -314.243573) (xy 193.668872 -314.226121) (xy 193.626251 -314.201514)
			(xy 193.58813 -314.170389) (xy 193.555495 -314.133552) (xy 193.529192 -314.091956) (xy 193.509901 -314.04668)
			(xy 193.498124 -313.998896) (xy 193.494164 -313.949842) (xy 193.17716 -313.949842) (xy 193.176656 -313.97555)
			(xy 193.168613 -314.026332) (xy 193.152725 -314.075231) (xy 193.129382 -314.121043) (xy 193.099161 -314.162639)
			(xy 193.062805 -314.198995) (xy 193.021209 -314.229216) (xy 192.975397 -314.252559) (xy 192.926498 -314.268447)
			(xy 192.875716 -314.27649) (xy 192.8243 -314.27649) (xy 192.773518 -314.268447) (xy 192.724619 -314.252559)
			(xy 192.678807 -314.229216) (xy 192.637211 -314.198995) (xy 192.600855 -314.162639) (xy 192.570634 -314.121043)
			(xy 192.547291 -314.075231) (xy 192.531403 -314.026332) (xy 192.52336 -313.97555) (xy 192.204682 -313.97555)
			(xy 192.196966 -314.023026) (xy 192.181382 -314.069707) (xy 192.158511 -314.113284) (xy 192.128946 -314.152628)
			(xy 192.093453 -314.18672) (xy 192.05295 -314.214676) (xy 192.008488 -314.235774) (xy 191.961217 -314.249466)
			(xy 191.912362 -314.255398) (xy 191.863187 -314.253417) (xy 191.814968 -314.243573) (xy 191.768952 -314.226121)
			(xy 191.726331 -314.201514) (xy 191.68821 -314.170389) (xy 191.655575 -314.133552) (xy 191.629272 -314.091956)
			(xy 191.609981 -314.04668) (xy 191.598204 -313.998896) (xy 191.594244 -313.949842) (xy 191.27724 -313.949842)
			(xy 191.276736 -313.97555) (xy 191.268693 -314.026332) (xy 191.252805 -314.075231) (xy 191.229462 -314.121043)
			(xy 191.199241 -314.162639) (xy 191.162885 -314.198995) (xy 191.121289 -314.229216) (xy 191.075477 -314.252559)
			(xy 191.026578 -314.268447) (xy 190.975796 -314.27649) (xy 190.92438 -314.27649) (xy 190.873598 -314.268447)
			(xy 190.824699 -314.252559) (xy 190.778887 -314.229216) (xy 190.737291 -314.198995) (xy 190.700935 -314.162639)
			(xy 190.670714 -314.121043) (xy 190.647371 -314.075231) (xy 190.631483 -314.026332) (xy 190.62344 -313.97555)
			(xy 190.304508 -313.97555) (xy 190.296792 -314.023026) (xy 190.281208 -314.069707) (xy 190.258337 -314.113284)
			(xy 190.228772 -314.152628) (xy 190.193279 -314.18672) (xy 190.152776 -314.214676) (xy 190.108314 -314.235774)
			(xy 190.061043 -314.249466) (xy 190.012188 -314.255398) (xy 189.963013 -314.253417) (xy 189.914794 -314.243573)
			(xy 189.868778 -314.226121) (xy 189.826157 -314.201514) (xy 189.788036 -314.170389) (xy 189.755401 -314.133552)
			(xy 189.729098 -314.091956) (xy 189.709807 -314.04668) (xy 189.69803 -313.998896) (xy 189.69407 -313.949842)
			(xy 189.355222 -313.949842) (xy 189.354727 -313.974449) (xy 189.346832 -314.023026) (xy 189.331248 -314.069707)
			(xy 189.308377 -314.113284) (xy 189.278812 -314.152628) (xy 189.243319 -314.18672) (xy 189.202816 -314.214676)
			(xy 189.158354 -314.235774) (xy 189.111083 -314.249466) (xy 189.062228 -314.255398) (xy 189.013053 -314.253417)
			(xy 188.964834 -314.243573) (xy 188.918818 -314.226121) (xy 188.876197 -314.201514) (xy 188.838076 -314.170389)
			(xy 188.805441 -314.133552) (xy 188.779138 -314.091956) (xy 188.759847 -314.04668) (xy 188.74807 -313.998896)
			(xy 188.74411 -313.949842) (xy 188.405262 -313.949842) (xy 188.404767 -313.974449) (xy 188.396872 -314.023026)
			(xy 188.381288 -314.069707) (xy 188.358417 -314.113284) (xy 188.328852 -314.152628) (xy 188.293359 -314.18672)
			(xy 188.252856 -314.214676) (xy 188.208394 -314.235774) (xy 188.161123 -314.249466) (xy 188.112268 -314.255398)
			(xy 188.063093 -314.253417) (xy 188.014874 -314.243573) (xy 187.968858 -314.226121) (xy 187.926237 -314.201514)
			(xy 187.888116 -314.170389) (xy 187.855481 -314.133552) (xy 187.829178 -314.091956) (xy 187.809887 -314.04668)
			(xy 187.79811 -313.998896) (xy 187.79415 -313.949842) (xy 187.455302 -313.949842) (xy 187.454807 -313.974449)
			(xy 187.446912 -314.023026) (xy 187.431328 -314.069707) (xy 187.408457 -314.113284) (xy 187.378892 -314.152628)
			(xy 187.343399 -314.18672) (xy 187.302896 -314.214676) (xy 187.258434 -314.235774) (xy 187.211163 -314.249466)
			(xy 187.162308 -314.255398) (xy 187.113133 -314.253417) (xy 187.064914 -314.243573) (xy 187.018898 -314.226121)
			(xy 186.976277 -314.201514) (xy 186.938156 -314.170389) (xy 186.905521 -314.133552) (xy 186.879218 -314.091956)
			(xy 186.859927 -314.04668) (xy 186.84815 -313.998896) (xy 186.84419 -313.949842) (xy 186.505342 -313.949842)
			(xy 186.504847 -313.974449) (xy 186.496952 -314.023026) (xy 186.481368 -314.069707) (xy 186.458497 -314.113284)
			(xy 186.428932 -314.152628) (xy 186.393439 -314.18672) (xy 186.352936 -314.214676) (xy 186.308474 -314.235774)
			(xy 186.261203 -314.249466) (xy 186.212348 -314.255398) (xy 186.163173 -314.253417) (xy 186.114954 -314.243573)
			(xy 186.068938 -314.226121) (xy 186.026317 -314.201514) (xy 185.988196 -314.170389) (xy 185.955561 -314.133552)
			(xy 185.929258 -314.091956) (xy 185.909967 -314.04668) (xy 185.89819 -313.998896) (xy 185.89423 -313.949842)
			(xy 185.555382 -313.949842) (xy 185.554887 -313.974449) (xy 185.546992 -314.023026) (xy 185.531408 -314.069707)
			(xy 185.508537 -314.113284) (xy 185.478972 -314.152628) (xy 185.443479 -314.18672) (xy 185.402976 -314.214676)
			(xy 185.358514 -314.235774) (xy 185.311243 -314.249466) (xy 185.262388 -314.255398) (xy 185.213213 -314.253417)
			(xy 185.164994 -314.243573) (xy 185.118978 -314.226121) (xy 185.076357 -314.201514) (xy 185.038236 -314.170389)
			(xy 185.005601 -314.133552) (xy 184.979298 -314.091956) (xy 184.960007 -314.04668) (xy 184.94823 -313.998896)
			(xy 184.94427 -313.949842) (xy 184.605168 -313.949842) (xy 184.604673 -313.974449) (xy 184.596778 -314.023026)
			(xy 184.581194 -314.069707) (xy 184.558323 -314.113284) (xy 184.528758 -314.152628) (xy 184.493265 -314.18672)
			(xy 184.452762 -314.214676) (xy 184.4083 -314.235774) (xy 184.361029 -314.249466) (xy 184.312174 -314.255398)
			(xy 184.262999 -314.253417) (xy 184.21478 -314.243573) (xy 184.168764 -314.226121) (xy 184.126143 -314.201514)
			(xy 184.088022 -314.170389) (xy 184.055387 -314.133552) (xy 184.029084 -314.091956) (xy 184.009793 -314.04668)
			(xy 183.998016 -313.998896) (xy 183.994056 -313.949842) (xy 183.655208 -313.949842) (xy 183.654713 -313.974449)
			(xy 183.646818 -314.023026) (xy 183.631234 -314.069707) (xy 183.608363 -314.113284) (xy 183.578798 -314.152628)
			(xy 183.543305 -314.18672) (xy 183.502802 -314.214676) (xy 183.45834 -314.235774) (xy 183.411069 -314.249466)
			(xy 183.362214 -314.255398) (xy 183.313039 -314.253417) (xy 183.26482 -314.243573) (xy 183.218804 -314.226121)
			(xy 183.176183 -314.201514) (xy 183.138062 -314.170389) (xy 183.105427 -314.133552) (xy 183.079124 -314.091956)
			(xy 183.059833 -314.04668) (xy 183.048056 -313.998896) (xy 183.044096 -313.949842) (xy 182.705248 -313.949842)
			(xy 182.704753 -313.974449) (xy 182.696858 -314.023026) (xy 182.681274 -314.069707) (xy 182.658403 -314.113284)
			(xy 182.628838 -314.152628) (xy 182.593345 -314.18672) (xy 182.552842 -314.214676) (xy 182.50838 -314.235774)
			(xy 182.461109 -314.249466) (xy 182.412254 -314.255398) (xy 182.363079 -314.253417) (xy 182.31486 -314.243573)
			(xy 182.268844 -314.226121) (xy 182.226223 -314.201514) (xy 182.188102 -314.170389) (xy 182.155467 -314.133552)
			(xy 182.129164 -314.091956) (xy 182.109873 -314.04668) (xy 182.098096 -313.998896) (xy 182.094136 -313.949842)
			(xy 181.777132 -313.949842) (xy 181.776628 -313.97555) (xy 181.768585 -314.026332) (xy 181.752697 -314.075231)
			(xy 181.729354 -314.121043) (xy 181.699133 -314.162639) (xy 181.662777 -314.198995) (xy 181.621181 -314.229216)
			(xy 181.575369 -314.252559) (xy 181.52647 -314.268447) (xy 181.475688 -314.27649) (xy 181.424272 -314.27649)
			(xy 181.37349 -314.268447) (xy 181.324591 -314.252559) (xy 181.278779 -314.229216) (xy 181.237183 -314.198995)
			(xy 181.200827 -314.162639) (xy 181.170606 -314.121043) (xy 181.147263 -314.075231) (xy 181.131375 -314.026332)
			(xy 181.123332 -313.97555) (xy 180.804654 -313.97555) (xy 180.796938 -314.023026) (xy 180.781354 -314.069707)
			(xy 180.758483 -314.113284) (xy 180.728918 -314.152628) (xy 180.693425 -314.18672) (xy 180.652922 -314.214676)
			(xy 180.60846 -314.235774) (xy 180.561189 -314.249466) (xy 180.512334 -314.255398) (xy 180.463159 -314.253417)
			(xy 180.41494 -314.243573) (xy 180.368924 -314.226121) (xy 180.326303 -314.201514) (xy 180.288182 -314.170389)
			(xy 180.255547 -314.133552) (xy 180.229244 -314.091956) (xy 180.209953 -314.04668) (xy 180.198176 -313.998896)
			(xy 180.194216 -313.949842) (xy 179.877212 -313.949842) (xy 179.876708 -313.97555) (xy 179.868665 -314.026332)
			(xy 179.852777 -314.075231) (xy 179.829434 -314.121043) (xy 179.799213 -314.162639) (xy 179.762857 -314.198995)
			(xy 179.721261 -314.229216) (xy 179.675449 -314.252559) (xy 179.62655 -314.268447) (xy 179.575768 -314.27649)
			(xy 179.524352 -314.27649) (xy 179.47357 -314.268447) (xy 179.424671 -314.252559) (xy 179.378859 -314.229216)
			(xy 179.337263 -314.198995) (xy 179.300907 -314.162639) (xy 179.270686 -314.121043) (xy 179.247343 -314.075231)
			(xy 179.231455 -314.026332) (xy 179.223412 -313.97555) (xy 178.90448 -313.97555) (xy 178.896764 -314.023026)
			(xy 178.88118 -314.069707) (xy 178.858309 -314.113284) (xy 178.828744 -314.152628) (xy 178.793251 -314.18672)
			(xy 178.752748 -314.214676) (xy 178.708286 -314.235774) (xy 178.661015 -314.249466) (xy 178.61216 -314.255398)
			(xy 178.562985 -314.253417) (xy 178.514766 -314.243573) (xy 178.46875 -314.226121) (xy 178.426129 -314.201514)
			(xy 178.388008 -314.170389) (xy 178.355373 -314.133552) (xy 178.32907 -314.091956) (xy 178.309779 -314.04668)
			(xy 178.298002 -313.998896) (xy 178.294042 -313.949842) (xy 177.977038 -313.949842) (xy 177.976534 -313.97555)
			(xy 177.968491 -314.026332) (xy 177.952603 -314.075231) (xy 177.92926 -314.121043) (xy 177.899039 -314.162639)
			(xy 177.862683 -314.198995) (xy 177.821087 -314.229216) (xy 177.775275 -314.252559) (xy 177.726376 -314.268447)
			(xy 177.675594 -314.27649) (xy 177.624178 -314.27649) (xy 177.573396 -314.268447) (xy 177.524497 -314.252559)
			(xy 177.478685 -314.229216) (xy 177.437089 -314.198995) (xy 177.400733 -314.162639) (xy 177.370512 -314.121043)
			(xy 177.347169 -314.075231) (xy 177.331281 -314.026332) (xy 177.323238 -313.97555) (xy 177.00456 -313.97555)
			(xy 176.996844 -314.023026) (xy 176.98126 -314.069707) (xy 176.958389 -314.113284) (xy 176.928824 -314.152628)
			(xy 176.893331 -314.18672) (xy 176.852828 -314.214676) (xy 176.808366 -314.235774) (xy 176.761095 -314.249466)
			(xy 176.71224 -314.255398) (xy 176.663065 -314.253417) (xy 176.614846 -314.243573) (xy 176.56883 -314.226121)
			(xy 176.526209 -314.201514) (xy 176.488088 -314.170389) (xy 176.455453 -314.133552) (xy 176.42915 -314.091956)
			(xy 176.409859 -314.04668) (xy 176.398082 -313.998896) (xy 176.394122 -313.949842) (xy 176.077118 -313.949842)
			(xy 176.076614 -313.97555) (xy 176.068571 -314.026332) (xy 176.052683 -314.075231) (xy 176.02934 -314.121043)
			(xy 175.999119 -314.162639) (xy 175.962763 -314.198995) (xy 175.921167 -314.229216) (xy 175.875355 -314.252559)
			(xy 175.826456 -314.268447) (xy 175.775674 -314.27649) (xy 175.724258 -314.27649) (xy 175.673476 -314.268447)
			(xy 175.624577 -314.252559) (xy 175.578765 -314.229216) (xy 175.537169 -314.198995) (xy 175.500813 -314.162639)
			(xy 175.470592 -314.121043) (xy 175.447249 -314.075231) (xy 175.431361 -314.026332) (xy 175.423318 -313.97555)
			(xy 175.10464 -313.97555) (xy 175.096924 -314.023026) (xy 175.08134 -314.069707) (xy 175.058469 -314.113284)
			(xy 175.028904 -314.152628) (xy 174.993411 -314.18672) (xy 174.952908 -314.214676) (xy 174.908446 -314.235774)
			(xy 174.861175 -314.249466) (xy 174.81232 -314.255398) (xy 174.763145 -314.253417) (xy 174.714926 -314.243573)
			(xy 174.66891 -314.226121) (xy 174.626289 -314.201514) (xy 174.588168 -314.170389) (xy 174.555533 -314.133552)
			(xy 174.52923 -314.091956) (xy 174.509939 -314.04668) (xy 174.498162 -313.998896) (xy 174.494202 -313.949842)
			(xy 174.177198 -313.949842) (xy 174.176694 -313.97555) (xy 174.168651 -314.026332) (xy 174.152763 -314.075231)
			(xy 174.12942 -314.121043) (xy 174.099199 -314.162639) (xy 174.062843 -314.198995) (xy 174.021247 -314.229216)
			(xy 173.975435 -314.252559) (xy 173.926536 -314.268447) (xy 173.875754 -314.27649) (xy 173.824338 -314.27649)
			(xy 173.773556 -314.268447) (xy 173.724657 -314.252559) (xy 173.678845 -314.229216) (xy 173.637249 -314.198995)
			(xy 173.600893 -314.162639) (xy 173.570672 -314.121043) (xy 173.547329 -314.075231) (xy 173.531441 -314.026332)
			(xy 173.523398 -313.97555) (xy 173.20472 -313.97555) (xy 173.197004 -314.023026) (xy 173.18142 -314.069707)
			(xy 173.158549 -314.113284) (xy 173.128984 -314.152628) (xy 173.093491 -314.18672) (xy 173.052988 -314.214676)
			(xy 173.008526 -314.235774) (xy 172.961255 -314.249466) (xy 172.9124 -314.255398) (xy 172.863225 -314.253417)
			(xy 172.815006 -314.243573) (xy 172.76899 -314.226121) (xy 172.726369 -314.201514) (xy 172.688248 -314.170389)
			(xy 172.655613 -314.133552) (xy 172.62931 -314.091956) (xy 172.610019 -314.04668) (xy 172.598242 -313.998896)
			(xy 172.594282 -313.949842) (xy 172.277024 -313.949842) (xy 172.27652 -313.97555) (xy 172.268477 -314.026332)
			(xy 172.252589 -314.075231) (xy 172.229246 -314.121043) (xy 172.199025 -314.162639) (xy 172.162669 -314.198995)
			(xy 172.121073 -314.229216) (xy 172.075261 -314.252559) (xy 172.026362 -314.268447) (xy 171.97558 -314.27649)
			(xy 171.924164 -314.27649) (xy 171.873382 -314.268447) (xy 171.824483 -314.252559) (xy 171.778671 -314.229216)
			(xy 171.737075 -314.198995) (xy 171.700719 -314.162639) (xy 171.670498 -314.121043) (xy 171.647155 -314.075231)
			(xy 171.631267 -314.026332) (xy 171.623224 -313.97555) (xy 171.304546 -313.97555) (xy 171.29683 -314.023026)
			(xy 171.281246 -314.069707) (xy 171.258375 -314.113284) (xy 171.22881 -314.152628) (xy 171.193317 -314.18672)
			(xy 171.152814 -314.214676) (xy 171.108352 -314.235774) (xy 171.061081 -314.249466) (xy 171.012226 -314.255398)
			(xy 170.963051 -314.253417) (xy 170.914832 -314.243573) (xy 170.868816 -314.226121) (xy 170.826195 -314.201514)
			(xy 170.788074 -314.170389) (xy 170.755439 -314.133552) (xy 170.729136 -314.091956) (xy 170.709845 -314.04668)
			(xy 170.698068 -313.998896) (xy 170.694108 -313.949842) (xy 170.377104 -313.949842) (xy 170.3766 -313.97555)
			(xy 170.368557 -314.026332) (xy 170.352669 -314.075231) (xy 170.329326 -314.121043) (xy 170.299105 -314.162639)
			(xy 170.262749 -314.198995) (xy 170.221153 -314.229216) (xy 170.175341 -314.252559) (xy 170.126442 -314.268447)
			(xy 170.07566 -314.27649) (xy 170.024244 -314.27649) (xy 169.973462 -314.268447) (xy 169.924563 -314.252559)
			(xy 169.878751 -314.229216) (xy 169.837155 -314.198995) (xy 169.800799 -314.162639) (xy 169.770578 -314.121043)
			(xy 169.747235 -314.075231) (xy 169.731347 -314.026332) (xy 169.723304 -313.97555) (xy 169.404626 -313.97555)
			(xy 169.39691 -314.023026) (xy 169.381326 -314.069707) (xy 169.358455 -314.113284) (xy 169.32889 -314.152628)
			(xy 169.293397 -314.18672) (xy 169.252894 -314.214676) (xy 169.208432 -314.235774) (xy 169.161161 -314.249466)
			(xy 169.112306 -314.255398) (xy 169.063131 -314.253417) (xy 169.014912 -314.243573) (xy 168.968896 -314.226121)
			(xy 168.926275 -314.201514) (xy 168.888154 -314.170389) (xy 168.855519 -314.133552) (xy 168.829216 -314.091956)
			(xy 168.809925 -314.04668) (xy 168.798148 -313.998896) (xy 168.794188 -313.949842) (xy 168.477184 -313.949842)
			(xy 168.47668 -313.97555) (xy 168.468637 -314.026332) (xy 168.452749 -314.075231) (xy 168.429406 -314.121043)
			(xy 168.399185 -314.162639) (xy 168.362829 -314.198995) (xy 168.321233 -314.229216) (xy 168.275421 -314.252559)
			(xy 168.226522 -314.268447) (xy 168.17574 -314.27649) (xy 168.124324 -314.27649) (xy 168.073542 -314.268447)
			(xy 168.024643 -314.252559) (xy 167.978831 -314.229216) (xy 167.937235 -314.198995) (xy 167.900879 -314.162639)
			(xy 167.870658 -314.121043) (xy 167.847315 -314.075231) (xy 167.831427 -314.026332) (xy 167.823384 -313.97555)
			(xy 167.504706 -313.97555) (xy 167.49699 -314.023026) (xy 167.481406 -314.069707) (xy 167.458535 -314.113284)
			(xy 167.42897 -314.152628) (xy 167.393477 -314.18672) (xy 167.352974 -314.214676) (xy 167.308512 -314.235774)
			(xy 167.261241 -314.249466) (xy 167.212386 -314.255398) (xy 167.163211 -314.253417) (xy 167.114992 -314.243573)
			(xy 167.068976 -314.226121) (xy 167.026355 -314.201514) (xy 166.988234 -314.170389) (xy 166.955599 -314.133552)
			(xy 166.929296 -314.091956) (xy 166.910005 -314.04668) (xy 166.898228 -313.998896) (xy 166.894268 -313.949842)
			(xy 166.555166 -313.949842) (xy 166.554671 -313.974449) (xy 166.546776 -314.023026) (xy 166.531192 -314.069707)
			(xy 166.508321 -314.113284) (xy 166.478756 -314.152628) (xy 166.443263 -314.18672) (xy 166.40276 -314.214676)
			(xy 166.358298 -314.235774) (xy 166.311027 -314.249466) (xy 166.262172 -314.255398) (xy 166.212997 -314.253417)
			(xy 166.164778 -314.243573) (xy 166.118762 -314.226121) (xy 166.076141 -314.201514) (xy 166.03802 -314.170389)
			(xy 166.005385 -314.133552) (xy 165.979082 -314.091956) (xy 165.959791 -314.04668) (xy 165.948014 -313.998896)
			(xy 165.944054 -313.949842) (xy 165.605715 -313.949842) (xy 165.601547 -314.000136) (xy 165.589148 -314.049099)
			(xy 165.568859 -314.095354) (xy 165.541233 -314.137638) (xy 165.507024 -314.174798) (xy 165.467166 -314.205821)
			(xy 165.422744 -314.229861) (xy 165.374972 -314.24626) (xy 165.325152 -314.254574) (xy 165.299898 -314.25515)
			(xy 165.29073 -314.255057) (xy 165.27243 -314.253914) (xy 165.263322 -314.252864) (xy 165.251384 -314.251594)
			(xy 165.240462 -314.255404) (xy 165.234883 -314.257568) (xy 165.224868 -314.264113) (xy 165.22065 -314.268358)
			(xy 165.164262 -314.327286) (xy 165.161468 -314.330334) (xy 165.158566 -314.334129) (xy 165.15409 -314.342567)
			(xy 165.152578 -314.347098) (xy 165.149022 -314.358528) (xy 165.151054 -314.370466) (xy 165.154989 -314.397504)
			(xy 165.154985 -314.452139) (xy 165.151054 -314.479178) (xy 165.149022 -314.491116) (xy 165.152578 -314.502546)
			(xy 165.154088 -314.507079) (xy 165.158557 -314.515522) (xy 165.161468 -314.51931) (xy 165.164262 -314.522358)
			(xy 165.22065 -314.581286) (xy 165.22488 -314.585517) (xy 165.23489 -314.592063) (xy 165.240462 -314.59424)
			(xy 165.251384 -314.59805) (xy 165.263322 -314.59678) (xy 165.27243 -314.595726) (xy 165.29073 -314.594584)
			(xy 165.299898 -314.594494) (xy 165.325156 -314.594987) (xy 165.374982 -314.603301) (xy 165.42276 -314.619703)
			(xy 165.467187 -314.643745) (xy 165.507051 -314.674772) (xy 165.541264 -314.711937) (xy 165.568894 -314.754227)
			(xy 165.589186 -314.800488) (xy 165.601586 -314.849457) (xy 165.605758 -314.8998) (xy 165.605758 -314.899802)
			(xy 165.944054 -314.899802) (xy 165.948014 -314.850748) (xy 165.959791 -314.802964) (xy 165.979082 -314.757688)
			(xy 166.005385 -314.716092) (xy 166.03802 -314.679255) (xy 166.076141 -314.64813) (xy 166.118762 -314.623523)
			(xy 166.164778 -314.606071) (xy 166.212997 -314.596227) (xy 166.262172 -314.594246) (xy 166.311027 -314.600178)
			(xy 166.358298 -314.61387) (xy 166.40276 -314.634968) (xy 166.443263 -314.662924) (xy 166.478756 -314.697016)
			(xy 166.508321 -314.73636) (xy 166.531192 -314.779937) (xy 166.546776 -314.826618) (xy 166.554671 -314.875195)
			(xy 166.555166 -314.899802) (xy 166.894268 -314.899802) (xy 166.898228 -314.850748) (xy 166.910005 -314.802964)
			(xy 166.929296 -314.757688) (xy 166.955599 -314.716092) (xy 166.988234 -314.679255) (xy 167.026355 -314.64813)
			(xy 167.068976 -314.623523) (xy 167.114992 -314.606071) (xy 167.163211 -314.596227) (xy 167.212386 -314.594246)
			(xy 167.261241 -314.600178) (xy 167.308512 -314.61387) (xy 167.352974 -314.634968) (xy 167.393477 -314.662924)
			(xy 167.42897 -314.697016) (xy 167.458535 -314.73636) (xy 167.481406 -314.779937) (xy 167.49699 -314.826618)
			(xy 167.504885 -314.875195) (xy 167.50538 -314.899802) (xy 167.844228 -314.899802) (xy 167.848188 -314.850748)
			(xy 167.859965 -314.802964) (xy 167.879256 -314.757688) (xy 167.905559 -314.716092) (xy 167.938194 -314.679255)
			(xy 167.976315 -314.64813) (xy 168.018936 -314.623523) (xy 168.064952 -314.606071) (xy 168.113171 -314.596227)
			(xy 168.162346 -314.594246) (xy 168.211201 -314.600178) (xy 168.258472 -314.61387) (xy 168.302934 -314.634968)
			(xy 168.343437 -314.662924) (xy 168.37893 -314.697016) (xy 168.408495 -314.73636) (xy 168.431366 -314.779937)
			(xy 168.44695 -314.826618) (xy 168.454845 -314.875195) (xy 168.45534 -314.899802) (xy 168.794188 -314.899802)
			(xy 168.798148 -314.850748) (xy 168.809925 -314.802964) (xy 168.829216 -314.757688) (xy 168.855519 -314.716092)
			(xy 168.888154 -314.679255) (xy 168.926275 -314.64813) (xy 168.968896 -314.623523) (xy 169.014912 -314.606071)
			(xy 169.063131 -314.596227) (xy 169.112306 -314.594246) (xy 169.161161 -314.600178) (xy 169.208432 -314.61387)
			(xy 169.252894 -314.634968) (xy 169.293397 -314.662924) (xy 169.32889 -314.697016) (xy 169.358455 -314.73636)
			(xy 169.381326 -314.779937) (xy 169.39691 -314.826618) (xy 169.404805 -314.875195) (xy 169.4053 -314.899802)
			(xy 169.744148 -314.899802) (xy 169.748108 -314.850748) (xy 169.759885 -314.802964) (xy 169.779176 -314.757688)
			(xy 169.805479 -314.716092) (xy 169.838114 -314.679255) (xy 169.876235 -314.64813) (xy 169.918856 -314.623523)
			(xy 169.964872 -314.606071) (xy 170.013091 -314.596227) (xy 170.062266 -314.594246) (xy 170.111121 -314.600178)
			(xy 170.158392 -314.61387) (xy 170.202854 -314.634968) (xy 170.243357 -314.662924) (xy 170.27885 -314.697016)
			(xy 170.308415 -314.73636) (xy 170.331286 -314.779937) (xy 170.34687 -314.826618) (xy 170.354765 -314.875195)
			(xy 170.35526 -314.899802) (xy 170.694108 -314.899802) (xy 170.698068 -314.850748) (xy 170.709845 -314.802964)
			(xy 170.729136 -314.757688) (xy 170.755439 -314.716092) (xy 170.788074 -314.679255) (xy 170.826195 -314.64813)
			(xy 170.868816 -314.623523) (xy 170.914832 -314.606071) (xy 170.963051 -314.596227) (xy 171.012226 -314.594246)
			(xy 171.061081 -314.600178) (xy 171.108352 -314.61387) (xy 171.152814 -314.634968) (xy 171.193317 -314.662924)
			(xy 171.22881 -314.697016) (xy 171.258375 -314.73636) (xy 171.281246 -314.779937) (xy 171.29683 -314.826618)
			(xy 171.304725 -314.875195) (xy 171.30522 -314.899802) (xy 171.644068 -314.899802) (xy 171.648028 -314.850748)
			(xy 171.659805 -314.802964) (xy 171.679096 -314.757688) (xy 171.705399 -314.716092) (xy 171.738034 -314.679255)
			(xy 171.776155 -314.64813) (xy 171.818776 -314.623523) (xy 171.864792 -314.606071) (xy 171.913011 -314.596227)
			(xy 171.962186 -314.594246) (xy 172.011041 -314.600178) (xy 172.058312 -314.61387) (xy 172.102774 -314.634968)
			(xy 172.143277 -314.662924) (xy 172.17877 -314.697016) (xy 172.208335 -314.73636) (xy 172.231206 -314.779937)
			(xy 172.24679 -314.826618) (xy 172.254685 -314.875195) (xy 172.25518 -314.899802) (xy 172.594282 -314.899802)
			(xy 172.598242 -314.850748) (xy 172.610019 -314.802964) (xy 172.62931 -314.757688) (xy 172.655613 -314.716092)
			(xy 172.688248 -314.679255) (xy 172.726369 -314.64813) (xy 172.76899 -314.623523) (xy 172.815006 -314.606071)
			(xy 172.863225 -314.596227) (xy 172.9124 -314.594246) (xy 172.961255 -314.600178) (xy 173.008526 -314.61387)
			(xy 173.052988 -314.634968) (xy 173.093491 -314.662924) (xy 173.128984 -314.697016) (xy 173.158549 -314.73636)
			(xy 173.18142 -314.779937) (xy 173.197004 -314.826618) (xy 173.204899 -314.875195) (xy 173.205394 -314.899802)
			(xy 173.544242 -314.899802) (xy 173.548202 -314.850748) (xy 173.559979 -314.802964) (xy 173.57927 -314.757688)
			(xy 173.605573 -314.716092) (xy 173.638208 -314.679255) (xy 173.676329 -314.64813) (xy 173.71895 -314.623523)
			(xy 173.764966 -314.606071) (xy 173.813185 -314.596227) (xy 173.86236 -314.594246) (xy 173.911215 -314.600178)
			(xy 173.958486 -314.61387) (xy 174.002948 -314.634968) (xy 174.043451 -314.662924) (xy 174.078944 -314.697016)
			(xy 174.108509 -314.73636) (xy 174.13138 -314.779937) (xy 174.146964 -314.826618) (xy 174.154859 -314.875195)
			(xy 174.155354 -314.899802) (xy 174.494202 -314.899802) (xy 174.498162 -314.850748) (xy 174.509939 -314.802964)
			(xy 174.52923 -314.757688) (xy 174.555533 -314.716092) (xy 174.588168 -314.679255) (xy 174.626289 -314.64813)
			(xy 174.66891 -314.623523) (xy 174.714926 -314.606071) (xy 174.763145 -314.596227) (xy 174.81232 -314.594246)
			(xy 174.861175 -314.600178) (xy 174.908446 -314.61387) (xy 174.952908 -314.634968) (xy 174.993411 -314.662924)
			(xy 175.028904 -314.697016) (xy 175.058469 -314.73636) (xy 175.08134 -314.779937) (xy 175.096924 -314.826618)
			(xy 175.104819 -314.875195) (xy 175.105314 -314.899802) (xy 175.444162 -314.899802) (xy 175.448122 -314.850748)
			(xy 175.459899 -314.802964) (xy 175.47919 -314.757688) (xy 175.505493 -314.716092) (xy 175.538128 -314.679255)
			(xy 175.576249 -314.64813) (xy 175.61887 -314.623523) (xy 175.664886 -314.606071) (xy 175.713105 -314.596227)
			(xy 175.76228 -314.594246) (xy 175.811135 -314.600178) (xy 175.858406 -314.61387) (xy 175.902868 -314.634968)
			(xy 175.943371 -314.662924) (xy 175.978864 -314.697016) (xy 176.008429 -314.73636) (xy 176.0313 -314.779937)
			(xy 176.046884 -314.826618) (xy 176.054779 -314.875195) (xy 176.055274 -314.899802) (xy 176.394122 -314.899802)
			(xy 176.398082 -314.850748) (xy 176.409859 -314.802964) (xy 176.42915 -314.757688) (xy 176.455453 -314.716092)
			(xy 176.488088 -314.679255) (xy 176.526209 -314.64813) (xy 176.56883 -314.623523) (xy 176.614846 -314.606071)
			(xy 176.663065 -314.596227) (xy 176.71224 -314.594246) (xy 176.761095 -314.600178) (xy 176.808366 -314.61387)
			(xy 176.852828 -314.634968) (xy 176.893331 -314.662924) (xy 176.928824 -314.697016) (xy 176.958389 -314.73636)
			(xy 176.98126 -314.779937) (xy 176.996844 -314.826618) (xy 177.004739 -314.875195) (xy 177.005234 -314.899802)
			(xy 177.344082 -314.899802) (xy 177.348042 -314.850748) (xy 177.359819 -314.802964) (xy 177.37911 -314.757688)
			(xy 177.405413 -314.716092) (xy 177.438048 -314.679255) (xy 177.476169 -314.64813) (xy 177.51879 -314.623523)
			(xy 177.564806 -314.606071) (xy 177.613025 -314.596227) (xy 177.6622 -314.594246) (xy 177.711055 -314.600178)
			(xy 177.758326 -314.61387) (xy 177.802788 -314.634968) (xy 177.843291 -314.662924) (xy 177.878784 -314.697016)
			(xy 177.908349 -314.73636) (xy 177.93122 -314.779937) (xy 177.946804 -314.826618) (xy 177.954699 -314.875195)
			(xy 177.955194 -314.899802) (xy 178.294042 -314.899802) (xy 178.298002 -314.850748) (xy 178.309779 -314.802964)
			(xy 178.32907 -314.757688) (xy 178.355373 -314.716092) (xy 178.388008 -314.679255) (xy 178.426129 -314.64813)
			(xy 178.46875 -314.623523) (xy 178.514766 -314.606071) (xy 178.562985 -314.596227) (xy 178.61216 -314.594246)
			(xy 178.661015 -314.600178) (xy 178.708286 -314.61387) (xy 178.752748 -314.634968) (xy 178.793251 -314.662924)
			(xy 178.828744 -314.697016) (xy 178.858309 -314.73636) (xy 178.88118 -314.779937) (xy 178.896764 -314.826618)
			(xy 178.904659 -314.875195) (xy 178.905154 -314.899802) (xy 179.244256 -314.899802) (xy 179.248216 -314.850748)
			(xy 179.259993 -314.802964) (xy 179.279284 -314.757688) (xy 179.305587 -314.716092) (xy 179.338222 -314.679255)
			(xy 179.376343 -314.64813) (xy 179.418964 -314.623523) (xy 179.46498 -314.606071) (xy 179.513199 -314.596227)
			(xy 179.562374 -314.594246) (xy 179.611229 -314.600178) (xy 179.6585 -314.61387) (xy 179.702962 -314.634968)
			(xy 179.743465 -314.662924) (xy 179.778958 -314.697016) (xy 179.808523 -314.73636) (xy 179.831394 -314.779937)
			(xy 179.846978 -314.826618) (xy 179.854873 -314.875195) (xy 179.855368 -314.899802) (xy 180.194216 -314.899802)
			(xy 180.198176 -314.850748) (xy 180.209953 -314.802964) (xy 180.229244 -314.757688) (xy 180.255547 -314.716092)
			(xy 180.288182 -314.679255) (xy 180.326303 -314.64813) (xy 180.368924 -314.623523) (xy 180.41494 -314.606071)
			(xy 180.463159 -314.596227) (xy 180.512334 -314.594246) (xy 180.561189 -314.600178) (xy 180.60846 -314.61387)
			(xy 180.652922 -314.634968) (xy 180.693425 -314.662924) (xy 180.728918 -314.697016) (xy 180.758483 -314.73636)
			(xy 180.781354 -314.779937) (xy 180.796938 -314.826618) (xy 180.804833 -314.875195) (xy 180.805328 -314.899802)
			(xy 181.144176 -314.899802) (xy 181.148136 -314.850748) (xy 181.159913 -314.802964) (xy 181.179204 -314.757688)
			(xy 181.205507 -314.716092) (xy 181.238142 -314.679255) (xy 181.276263 -314.64813) (xy 181.318884 -314.623523)
			(xy 181.3649 -314.606071) (xy 181.413119 -314.596227) (xy 181.462294 -314.594246) (xy 181.511149 -314.600178)
			(xy 181.55842 -314.61387) (xy 181.602882 -314.634968) (xy 181.643385 -314.662924) (xy 181.678878 -314.697016)
			(xy 181.708443 -314.73636) (xy 181.731314 -314.779937) (xy 181.746898 -314.826618) (xy 181.754793 -314.875195)
			(xy 181.755288 -314.899802) (xy 182.094136 -314.899802) (xy 182.098096 -314.850748) (xy 182.109873 -314.802964)
			(xy 182.129164 -314.757688) (xy 182.155467 -314.716092) (xy 182.188102 -314.679255) (xy 182.226223 -314.64813)
			(xy 182.268844 -314.623523) (xy 182.31486 -314.606071) (xy 182.363079 -314.596227) (xy 182.412254 -314.594246)
			(xy 182.461109 -314.600178) (xy 182.50838 -314.61387) (xy 182.552842 -314.634968) (xy 182.593345 -314.662924)
			(xy 182.628838 -314.697016) (xy 182.658403 -314.73636) (xy 182.681274 -314.779937) (xy 182.696858 -314.826618)
			(xy 182.704753 -314.875195) (xy 182.705248 -314.899802) (xy 183.044096 -314.899802) (xy 183.048056 -314.850748)
			(xy 183.059833 -314.802964) (xy 183.079124 -314.757688) (xy 183.105427 -314.716092) (xy 183.138062 -314.679255)
			(xy 183.176183 -314.64813) (xy 183.218804 -314.623523) (xy 183.26482 -314.606071) (xy 183.313039 -314.596227)
			(xy 183.362214 -314.594246) (xy 183.411069 -314.600178) (xy 183.45834 -314.61387) (xy 183.502802 -314.634968)
			(xy 183.543305 -314.662924) (xy 183.578798 -314.697016) (xy 183.608363 -314.73636) (xy 183.631234 -314.779937)
			(xy 183.646818 -314.826618) (xy 183.654713 -314.875195) (xy 183.655208 -314.899802) (xy 183.994056 -314.899802)
			(xy 183.998016 -314.850748) (xy 184.009793 -314.802964) (xy 184.029084 -314.757688) (xy 184.055387 -314.716092)
			(xy 184.088022 -314.679255) (xy 184.126143 -314.64813) (xy 184.168764 -314.623523) (xy 184.21478 -314.606071)
			(xy 184.262999 -314.596227) (xy 184.312174 -314.594246) (xy 184.361029 -314.600178) (xy 184.4083 -314.61387)
			(xy 184.452762 -314.634968) (xy 184.493265 -314.662924) (xy 184.528758 -314.697016) (xy 184.558323 -314.73636)
			(xy 184.581194 -314.779937) (xy 184.596778 -314.826618) (xy 184.604673 -314.875195) (xy 184.605168 -314.899802)
			(xy 184.94427 -314.899802) (xy 184.94823 -314.850748) (xy 184.960007 -314.802964) (xy 184.979298 -314.757688)
			(xy 185.005601 -314.716092) (xy 185.038236 -314.679255) (xy 185.076357 -314.64813) (xy 185.118978 -314.623523)
			(xy 185.164994 -314.606071) (xy 185.213213 -314.596227) (xy 185.262388 -314.594246) (xy 185.311243 -314.600178)
			(xy 185.358514 -314.61387) (xy 185.402976 -314.634968) (xy 185.443479 -314.662924) (xy 185.478972 -314.697016)
			(xy 185.508537 -314.73636) (xy 185.531408 -314.779937) (xy 185.546992 -314.826618) (xy 185.554887 -314.875195)
			(xy 185.555382 -314.899802) (xy 185.89423 -314.899802) (xy 185.89819 -314.850748) (xy 185.909967 -314.802964)
			(xy 185.929258 -314.757688) (xy 185.955561 -314.716092) (xy 185.988196 -314.679255) (xy 186.026317 -314.64813)
			(xy 186.068938 -314.623523) (xy 186.114954 -314.606071) (xy 186.163173 -314.596227) (xy 186.212348 -314.594246)
			(xy 186.261203 -314.600178) (xy 186.308474 -314.61387) (xy 186.352936 -314.634968) (xy 186.393439 -314.662924)
			(xy 186.428932 -314.697016) (xy 186.458497 -314.73636) (xy 186.481368 -314.779937) (xy 186.496952 -314.826618)
			(xy 186.504847 -314.875195) (xy 186.505342 -314.899802) (xy 186.84419 -314.899802) (xy 186.84815 -314.850748)
			(xy 186.859927 -314.802964) (xy 186.879218 -314.757688) (xy 186.905521 -314.716092) (xy 186.938156 -314.679255)
			(xy 186.976277 -314.64813) (xy 187.018898 -314.623523) (xy 187.064914 -314.606071) (xy 187.113133 -314.596227)
			(xy 187.162308 -314.594246) (xy 187.211163 -314.600178) (xy 187.258434 -314.61387) (xy 187.302896 -314.634968)
			(xy 187.343399 -314.662924) (xy 187.378892 -314.697016) (xy 187.408457 -314.73636) (xy 187.431328 -314.779937)
			(xy 187.446912 -314.826618) (xy 187.454807 -314.875195) (xy 187.455302 -314.899802) (xy 187.79415 -314.899802)
			(xy 187.79811 -314.850748) (xy 187.809887 -314.802964) (xy 187.829178 -314.757688) (xy 187.855481 -314.716092)
			(xy 187.888116 -314.679255) (xy 187.926237 -314.64813) (xy 187.968858 -314.623523) (xy 188.014874 -314.606071)
			(xy 188.063093 -314.596227) (xy 188.112268 -314.594246) (xy 188.161123 -314.600178) (xy 188.208394 -314.61387)
			(xy 188.252856 -314.634968) (xy 188.293359 -314.662924) (xy 188.328852 -314.697016) (xy 188.358417 -314.73636)
			(xy 188.381288 -314.779937) (xy 188.396872 -314.826618) (xy 188.404767 -314.875195) (xy 188.405262 -314.899802)
			(xy 188.74411 -314.899802) (xy 188.74807 -314.850748) (xy 188.759847 -314.802964) (xy 188.779138 -314.757688)
			(xy 188.805441 -314.716092) (xy 188.838076 -314.679255) (xy 188.876197 -314.64813) (xy 188.918818 -314.623523)
			(xy 188.964834 -314.606071) (xy 189.013053 -314.596227) (xy 189.062228 -314.594246) (xy 189.111083 -314.600178)
			(xy 189.158354 -314.61387) (xy 189.202816 -314.634968) (xy 189.243319 -314.662924) (xy 189.278812 -314.697016)
			(xy 189.308377 -314.73636) (xy 189.331248 -314.779937) (xy 189.346832 -314.826618) (xy 189.354727 -314.875195)
			(xy 189.355222 -314.899802) (xy 189.69407 -314.899802) (xy 189.69803 -314.850748) (xy 189.709807 -314.802964)
			(xy 189.729098 -314.757688) (xy 189.755401 -314.716092) (xy 189.788036 -314.679255) (xy 189.826157 -314.64813)
			(xy 189.868778 -314.623523) (xy 189.914794 -314.606071) (xy 189.963013 -314.596227) (xy 190.012188 -314.594246)
			(xy 190.061043 -314.600178) (xy 190.108314 -314.61387) (xy 190.152776 -314.634968) (xy 190.193279 -314.662924)
			(xy 190.228772 -314.697016) (xy 190.258337 -314.73636) (xy 190.281208 -314.779937) (xy 190.296792 -314.826618)
			(xy 190.304687 -314.875195) (xy 190.305182 -314.899802) (xy 190.644284 -314.899802) (xy 190.648244 -314.850748)
			(xy 190.660021 -314.802964) (xy 190.679312 -314.757688) (xy 190.705615 -314.716092) (xy 190.73825 -314.679255)
			(xy 190.776371 -314.64813) (xy 190.818992 -314.623523) (xy 190.865008 -314.606071) (xy 190.913227 -314.596227)
			(xy 190.962402 -314.594246) (xy 191.011257 -314.600178) (xy 191.058528 -314.61387) (xy 191.10299 -314.634968)
			(xy 191.143493 -314.662924) (xy 191.178986 -314.697016) (xy 191.208551 -314.73636) (xy 191.231422 -314.779937)
			(xy 191.247006 -314.826618) (xy 191.254901 -314.875195) (xy 191.255396 -314.899802) (xy 191.594244 -314.899802)
			(xy 191.598204 -314.850748) (xy 191.609981 -314.802964) (xy 191.629272 -314.757688) (xy 191.655575 -314.716092)
			(xy 191.68821 -314.679255) (xy 191.726331 -314.64813) (xy 191.768952 -314.623523) (xy 191.814968 -314.606071)
			(xy 191.863187 -314.596227) (xy 191.912362 -314.594246) (xy 191.961217 -314.600178) (xy 192.008488 -314.61387)
			(xy 192.05295 -314.634968) (xy 192.093453 -314.662924) (xy 192.128946 -314.697016) (xy 192.158511 -314.73636)
			(xy 192.181382 -314.779937) (xy 192.196966 -314.826618) (xy 192.204861 -314.875195) (xy 192.205356 -314.899802)
			(xy 192.544204 -314.899802) (xy 192.548164 -314.850748) (xy 192.559941 -314.802964) (xy 192.579232 -314.757688)
			(xy 192.605535 -314.716092) (xy 192.63817 -314.679255) (xy 192.676291 -314.64813) (xy 192.718912 -314.623523)
			(xy 192.764928 -314.606071) (xy 192.813147 -314.596227) (xy 192.862322 -314.594246) (xy 192.911177 -314.600178)
			(xy 192.958448 -314.61387) (xy 193.00291 -314.634968) (xy 193.043413 -314.662924) (xy 193.078906 -314.697016)
			(xy 193.108471 -314.73636) (xy 193.131342 -314.779937) (xy 193.146926 -314.826618) (xy 193.154821 -314.875195)
			(xy 193.155316 -314.899802) (xy 193.494164 -314.899802) (xy 193.498124 -314.850748) (xy 193.509901 -314.802964)
			(xy 193.529192 -314.757688) (xy 193.555495 -314.716092) (xy 193.58813 -314.679255) (xy 193.626251 -314.64813)
			(xy 193.668872 -314.623523) (xy 193.714888 -314.606071) (xy 193.763107 -314.596227) (xy 193.812282 -314.594246)
			(xy 193.861137 -314.600178) (xy 193.908408 -314.61387) (xy 193.95287 -314.634968) (xy 193.993373 -314.662924)
			(xy 194.028866 -314.697016) (xy 194.058431 -314.73636) (xy 194.081302 -314.779937) (xy 194.096886 -314.826618)
			(xy 194.104781 -314.875195) (xy 194.105276 -314.899802) (xy 194.444124 -314.899802) (xy 194.448084 -314.850748)
			(xy 194.459861 -314.802964) (xy 194.479152 -314.757688) (xy 194.505455 -314.716092) (xy 194.53809 -314.679255)
			(xy 194.576211 -314.64813) (xy 194.618832 -314.623523) (xy 194.664848 -314.606071) (xy 194.713067 -314.596227)
			(xy 194.762242 -314.594246) (xy 194.811097 -314.600178) (xy 194.858368 -314.61387) (xy 194.90283 -314.634968)
			(xy 194.943333 -314.662924) (xy 194.978826 -314.697016) (xy 195.008391 -314.73636) (xy 195.031262 -314.779937)
			(xy 195.046846 -314.826618) (xy 195.054741 -314.875195) (xy 195.055236 -314.899802) (xy 195.394084 -314.899802)
			(xy 195.398044 -314.850748) (xy 195.409821 -314.802964) (xy 195.429112 -314.757688) (xy 195.455415 -314.716092)
			(xy 195.48805 -314.679255) (xy 195.526171 -314.64813) (xy 195.568792 -314.623523) (xy 195.614808 -314.606071)
			(xy 195.663027 -314.596227) (xy 195.712202 -314.594246) (xy 195.761057 -314.600178) (xy 195.808328 -314.61387)
			(xy 195.85279 -314.634968) (xy 195.893293 -314.662924) (xy 195.928786 -314.697016) (xy 195.958351 -314.73636)
			(xy 195.981222 -314.779937) (xy 195.996806 -314.826618) (xy 196.004701 -314.875195) (xy 196.005196 -314.899802)
			(xy 196.344044 -314.899802) (xy 196.348004 -314.850748) (xy 196.359781 -314.802964) (xy 196.379072 -314.757688)
			(xy 196.405375 -314.716092) (xy 196.43801 -314.679255) (xy 196.476131 -314.64813) (xy 196.518752 -314.623523)
			(xy 196.564768 -314.606071) (xy 196.612987 -314.596227) (xy 196.662162 -314.594246) (xy 196.711017 -314.600178)
			(xy 196.758288 -314.61387) (xy 196.80275 -314.634968) (xy 196.843253 -314.662924) (xy 196.878746 -314.697016)
			(xy 196.908311 -314.73636) (xy 196.931182 -314.779937) (xy 196.946766 -314.826618) (xy 196.954661 -314.875195)
			(xy 196.955156 -314.899802) (xy 196.954661 -314.924409) (xy 196.954482 -314.92551) (xy 197.273414 -314.92551)
			(xy 197.273414 -314.874094) (xy 197.281457 -314.823312) (xy 197.297345 -314.774413) (xy 197.320688 -314.728601)
			(xy 197.350909 -314.687005) (xy 197.387265 -314.650649) (xy 197.428861 -314.620428) (xy 197.474673 -314.597085)
			(xy 197.523572 -314.581197) (xy 197.574354 -314.573154) (xy 197.62577 -314.573154) (xy 197.676552 -314.581197)
			(xy 197.725451 -314.597085) (xy 197.771263 -314.620428) (xy 197.812859 -314.650649) (xy 197.849215 -314.687005)
			(xy 197.879436 -314.728601) (xy 197.902779 -314.774413) (xy 197.918667 -314.823312) (xy 197.92671 -314.874094)
			(xy 197.927214 -314.899802) (xy 197.92671 -314.92551) (xy 198.223374 -314.92551) (xy 198.223374 -314.874094)
			(xy 198.231417 -314.823312) (xy 198.247305 -314.774413) (xy 198.270648 -314.728601) (xy 198.300869 -314.687005)
			(xy 198.337225 -314.650649) (xy 198.378821 -314.620428) (xy 198.424633 -314.597085) (xy 198.473532 -314.581197)
			(xy 198.524314 -314.573154) (xy 198.57573 -314.573154) (xy 198.626512 -314.581197) (xy 198.675411 -314.597085)
			(xy 198.721223 -314.620428) (xy 198.762819 -314.650649) (xy 198.799175 -314.687005) (xy 198.829396 -314.728601)
			(xy 198.852739 -314.774413) (xy 198.868627 -314.823312) (xy 198.87667 -314.874094) (xy 198.877169 -314.899548)
			(xy 199.194432 -314.899548) (xy 199.198392 -314.850494) (xy 199.210169 -314.80271) (xy 199.22946 -314.757434)
			(xy 199.255763 -314.715838) (xy 199.288398 -314.679001) (xy 199.326519 -314.647876) (xy 199.36914 -314.623269)
			(xy 199.415156 -314.605817) (xy 199.463375 -314.595973) (xy 199.51255 -314.593992) (xy 199.561405 -314.599924)
			(xy 199.608676 -314.613616) (xy 199.653138 -314.634714) (xy 199.693641 -314.66267) (xy 199.729134 -314.696762)
			(xy 199.758699 -314.736106) (xy 199.78157 -314.779683) (xy 199.797154 -314.826364) (xy 199.805049 -314.874941)
			(xy 199.805544 -314.899548) (xy 199.805049 -314.924155) (xy 199.797154 -314.972732) (xy 199.78157 -315.019413)
			(xy 199.758699 -315.06299) (xy 199.729134 -315.102334) (xy 199.693641 -315.136426) (xy 199.653138 -315.164382)
			(xy 199.608676 -315.18548) (xy 199.561405 -315.199172) (xy 199.51255 -315.205104) (xy 199.463375 -315.203123)
			(xy 199.415156 -315.193279) (xy 199.36914 -315.175827) (xy 199.326519 -315.15122) (xy 199.288398 -315.120095)
			(xy 199.255763 -315.083258) (xy 199.22946 -315.041662) (xy 199.210169 -314.996386) (xy 199.198392 -314.948602)
			(xy 199.194432 -314.899548) (xy 198.877169 -314.899548) (xy 198.877174 -314.899802) (xy 198.87667 -314.92551)
			(xy 198.868627 -314.976292) (xy 198.852739 -315.025191) (xy 198.829396 -315.071003) (xy 198.799175 -315.112599)
			(xy 198.762819 -315.148955) (xy 198.721223 -315.179176) (xy 198.675411 -315.202519) (xy 198.626512 -315.218407)
			(xy 198.57573 -315.22645) (xy 198.524314 -315.22645) (xy 198.473532 -315.218407) (xy 198.424633 -315.202519)
			(xy 198.378821 -315.179176) (xy 198.337225 -315.148955) (xy 198.300869 -315.112599) (xy 198.270648 -315.071003)
			(xy 198.247305 -315.025191) (xy 198.231417 -314.976292) (xy 198.223374 -314.92551) (xy 197.92671 -314.92551)
			(xy 197.918667 -314.976292) (xy 197.902779 -315.025191) (xy 197.879436 -315.071003) (xy 197.849215 -315.112599)
			(xy 197.812859 -315.148955) (xy 197.771263 -315.179176) (xy 197.725451 -315.202519) (xy 197.676552 -315.218407)
			(xy 197.62577 -315.22645) (xy 197.574354 -315.22645) (xy 197.523572 -315.218407) (xy 197.474673 -315.202519)
			(xy 197.428861 -315.179176) (xy 197.387265 -315.148955) (xy 197.350909 -315.112599) (xy 197.320688 -315.071003)
			(xy 197.297345 -315.025191) (xy 197.281457 -314.976292) (xy 197.273414 -314.92551) (xy 196.954482 -314.92551)
			(xy 196.946766 -314.972986) (xy 196.931182 -315.019667) (xy 196.908311 -315.063244) (xy 196.878746 -315.102588)
			(xy 196.843253 -315.13668) (xy 196.80275 -315.164636) (xy 196.758288 -315.185734) (xy 196.711017 -315.199426)
			(xy 196.662162 -315.205358) (xy 196.612987 -315.203377) (xy 196.564768 -315.193533) (xy 196.518752 -315.176081)
			(xy 196.476131 -315.151474) (xy 196.43801 -315.120349) (xy 196.405375 -315.083512) (xy 196.379072 -315.041916)
			(xy 196.359781 -314.99664) (xy 196.348004 -314.948856) (xy 196.344044 -314.899802) (xy 196.005196 -314.899802)
			(xy 196.004701 -314.924409) (xy 195.996806 -314.972986) (xy 195.981222 -315.019667) (xy 195.958351 -315.063244)
			(xy 195.928786 -315.102588) (xy 195.893293 -315.13668) (xy 195.85279 -315.164636) (xy 195.808328 -315.185734)
			(xy 195.761057 -315.199426) (xy 195.712202 -315.205358) (xy 195.663027 -315.203377) (xy 195.614808 -315.193533)
			(xy 195.568792 -315.176081) (xy 195.526171 -315.151474) (xy 195.48805 -315.120349) (xy 195.455415 -315.083512)
			(xy 195.429112 -315.041916) (xy 195.409821 -314.99664) (xy 195.398044 -314.948856) (xy 195.394084 -314.899802)
			(xy 195.055236 -314.899802) (xy 195.054741 -314.924409) (xy 195.046846 -314.972986) (xy 195.031262 -315.019667)
			(xy 195.008391 -315.063244) (xy 194.978826 -315.102588) (xy 194.943333 -315.13668) (xy 194.90283 -315.164636)
			(xy 194.858368 -315.185734) (xy 194.811097 -315.199426) (xy 194.762242 -315.205358) (xy 194.713067 -315.203377)
			(xy 194.664848 -315.193533) (xy 194.618832 -315.176081) (xy 194.576211 -315.151474) (xy 194.53809 -315.120349)
			(xy 194.505455 -315.083512) (xy 194.479152 -315.041916) (xy 194.459861 -314.99664) (xy 194.448084 -314.948856)
			(xy 194.444124 -314.899802) (xy 194.105276 -314.899802) (xy 194.104781 -314.924409) (xy 194.096886 -314.972986)
			(xy 194.081302 -315.019667) (xy 194.058431 -315.063244) (xy 194.028866 -315.102588) (xy 193.993373 -315.13668)
			(xy 193.95287 -315.164636) (xy 193.908408 -315.185734) (xy 193.861137 -315.199426) (xy 193.812282 -315.205358)
			(xy 193.763107 -315.203377) (xy 193.714888 -315.193533) (xy 193.668872 -315.176081) (xy 193.626251 -315.151474)
			(xy 193.58813 -315.120349) (xy 193.555495 -315.083512) (xy 193.529192 -315.041916) (xy 193.509901 -314.99664)
			(xy 193.498124 -314.948856) (xy 193.494164 -314.899802) (xy 193.155316 -314.899802) (xy 193.154821 -314.924409)
			(xy 193.146926 -314.972986) (xy 193.131342 -315.019667) (xy 193.108471 -315.063244) (xy 193.078906 -315.102588)
			(xy 193.043413 -315.13668) (xy 193.00291 -315.164636) (xy 192.958448 -315.185734) (xy 192.911177 -315.199426)
			(xy 192.862322 -315.205358) (xy 192.813147 -315.203377) (xy 192.764928 -315.193533) (xy 192.718912 -315.176081)
			(xy 192.676291 -315.151474) (xy 192.63817 -315.120349) (xy 192.605535 -315.083512) (xy 192.579232 -315.041916)
			(xy 192.559941 -314.99664) (xy 192.548164 -314.948856) (xy 192.544204 -314.899802) (xy 192.205356 -314.899802)
			(xy 192.204861 -314.924409) (xy 192.196966 -314.972986) (xy 192.181382 -315.019667) (xy 192.158511 -315.063244)
			(xy 192.128946 -315.102588) (xy 192.093453 -315.13668) (xy 192.05295 -315.164636) (xy 192.008488 -315.185734)
			(xy 191.961217 -315.199426) (xy 191.912362 -315.205358) (xy 191.863187 -315.203377) (xy 191.814968 -315.193533)
			(xy 191.768952 -315.176081) (xy 191.726331 -315.151474) (xy 191.68821 -315.120349) (xy 191.655575 -315.083512)
			(xy 191.629272 -315.041916) (xy 191.609981 -314.99664) (xy 191.598204 -314.948856) (xy 191.594244 -314.899802)
			(xy 191.255396 -314.899802) (xy 191.254901 -314.924409) (xy 191.247006 -314.972986) (xy 191.231422 -315.019667)
			(xy 191.208551 -315.063244) (xy 191.178986 -315.102588) (xy 191.143493 -315.13668) (xy 191.10299 -315.164636)
			(xy 191.058528 -315.185734) (xy 191.011257 -315.199426) (xy 190.962402 -315.205358) (xy 190.913227 -315.203377)
			(xy 190.865008 -315.193533) (xy 190.818992 -315.176081) (xy 190.776371 -315.151474) (xy 190.73825 -315.120349)
			(xy 190.705615 -315.083512) (xy 190.679312 -315.041916) (xy 190.660021 -314.99664) (xy 190.648244 -314.948856)
			(xy 190.644284 -314.899802) (xy 190.305182 -314.899802) (xy 190.304687 -314.924409) (xy 190.296792 -314.972986)
			(xy 190.281208 -315.019667) (xy 190.258337 -315.063244) (xy 190.228772 -315.102588) (xy 190.193279 -315.13668)
			(xy 190.152776 -315.164636) (xy 190.108314 -315.185734) (xy 190.061043 -315.199426) (xy 190.012188 -315.205358)
			(xy 189.963013 -315.203377) (xy 189.914794 -315.193533) (xy 189.868778 -315.176081) (xy 189.826157 -315.151474)
			(xy 189.788036 -315.120349) (xy 189.755401 -315.083512) (xy 189.729098 -315.041916) (xy 189.709807 -314.99664)
			(xy 189.69803 -314.948856) (xy 189.69407 -314.899802) (xy 189.355222 -314.899802) (xy 189.354727 -314.924409)
			(xy 189.346832 -314.972986) (xy 189.331248 -315.019667) (xy 189.308377 -315.063244) (xy 189.278812 -315.102588)
			(xy 189.243319 -315.13668) (xy 189.202816 -315.164636) (xy 189.158354 -315.185734) (xy 189.111083 -315.199426)
			(xy 189.062228 -315.205358) (xy 189.013053 -315.203377) (xy 188.964834 -315.193533) (xy 188.918818 -315.176081)
			(xy 188.876197 -315.151474) (xy 188.838076 -315.120349) (xy 188.805441 -315.083512) (xy 188.779138 -315.041916)
			(xy 188.759847 -314.99664) (xy 188.74807 -314.948856) (xy 188.74411 -314.899802) (xy 188.405262 -314.899802)
			(xy 188.404767 -314.924409) (xy 188.396872 -314.972986) (xy 188.381288 -315.019667) (xy 188.358417 -315.063244)
			(xy 188.328852 -315.102588) (xy 188.293359 -315.13668) (xy 188.252856 -315.164636) (xy 188.208394 -315.185734)
			(xy 188.161123 -315.199426) (xy 188.112268 -315.205358) (xy 188.063093 -315.203377) (xy 188.014874 -315.193533)
			(xy 187.968858 -315.176081) (xy 187.926237 -315.151474) (xy 187.888116 -315.120349) (xy 187.855481 -315.083512)
			(xy 187.829178 -315.041916) (xy 187.809887 -314.99664) (xy 187.79811 -314.948856) (xy 187.79415 -314.899802)
			(xy 187.455302 -314.899802) (xy 187.454807 -314.924409) (xy 187.446912 -314.972986) (xy 187.431328 -315.019667)
			(xy 187.408457 -315.063244) (xy 187.378892 -315.102588) (xy 187.343399 -315.13668) (xy 187.302896 -315.164636)
			(xy 187.258434 -315.185734) (xy 187.211163 -315.199426) (xy 187.162308 -315.205358) (xy 187.113133 -315.203377)
			(xy 187.064914 -315.193533) (xy 187.018898 -315.176081) (xy 186.976277 -315.151474) (xy 186.938156 -315.120349)
			(xy 186.905521 -315.083512) (xy 186.879218 -315.041916) (xy 186.859927 -314.99664) (xy 186.84815 -314.948856)
			(xy 186.84419 -314.899802) (xy 186.505342 -314.899802) (xy 186.504847 -314.924409) (xy 186.496952 -314.972986)
			(xy 186.481368 -315.019667) (xy 186.458497 -315.063244) (xy 186.428932 -315.102588) (xy 186.393439 -315.13668)
			(xy 186.352936 -315.164636) (xy 186.308474 -315.185734) (xy 186.261203 -315.199426) (xy 186.212348 -315.205358)
			(xy 186.163173 -315.203377) (xy 186.114954 -315.193533) (xy 186.068938 -315.176081) (xy 186.026317 -315.151474)
			(xy 185.988196 -315.120349) (xy 185.955561 -315.083512) (xy 185.929258 -315.041916) (xy 185.909967 -314.99664)
			(xy 185.89819 -314.948856) (xy 185.89423 -314.899802) (xy 185.555382 -314.899802) (xy 185.554887 -314.924409)
			(xy 185.546992 -314.972986) (xy 185.531408 -315.019667) (xy 185.508537 -315.063244) (xy 185.478972 -315.102588)
			(xy 185.443479 -315.13668) (xy 185.402976 -315.164636) (xy 185.358514 -315.185734) (xy 185.311243 -315.199426)
			(xy 185.262388 -315.205358) (xy 185.213213 -315.203377) (xy 185.164994 -315.193533) (xy 185.118978 -315.176081)
			(xy 185.076357 -315.151474) (xy 185.038236 -315.120349) (xy 185.005601 -315.083512) (xy 184.979298 -315.041916)
			(xy 184.960007 -314.99664) (xy 184.94823 -314.948856) (xy 184.94427 -314.899802) (xy 184.605168 -314.899802)
			(xy 184.604673 -314.924409) (xy 184.596778 -314.972986) (xy 184.581194 -315.019667) (xy 184.558323 -315.063244)
			(xy 184.528758 -315.102588) (xy 184.493265 -315.13668) (xy 184.452762 -315.164636) (xy 184.4083 -315.185734)
			(xy 184.361029 -315.199426) (xy 184.312174 -315.205358) (xy 184.262999 -315.203377) (xy 184.21478 -315.193533)
			(xy 184.168764 -315.176081) (xy 184.126143 -315.151474) (xy 184.088022 -315.120349) (xy 184.055387 -315.083512)
			(xy 184.029084 -315.041916) (xy 184.009793 -314.99664) (xy 183.998016 -314.948856) (xy 183.994056 -314.899802)
			(xy 183.655208 -314.899802) (xy 183.654713 -314.924409) (xy 183.646818 -314.972986) (xy 183.631234 -315.019667)
			(xy 183.608363 -315.063244) (xy 183.578798 -315.102588) (xy 183.543305 -315.13668) (xy 183.502802 -315.164636)
			(xy 183.45834 -315.185734) (xy 183.411069 -315.199426) (xy 183.362214 -315.205358) (xy 183.313039 -315.203377)
			(xy 183.26482 -315.193533) (xy 183.218804 -315.176081) (xy 183.176183 -315.151474) (xy 183.138062 -315.120349)
			(xy 183.105427 -315.083512) (xy 183.079124 -315.041916) (xy 183.059833 -314.99664) (xy 183.048056 -314.948856)
			(xy 183.044096 -314.899802) (xy 182.705248 -314.899802) (xy 182.704753 -314.924409) (xy 182.696858 -314.972986)
			(xy 182.681274 -315.019667) (xy 182.658403 -315.063244) (xy 182.628838 -315.102588) (xy 182.593345 -315.13668)
			(xy 182.552842 -315.164636) (xy 182.50838 -315.185734) (xy 182.461109 -315.199426) (xy 182.412254 -315.205358)
			(xy 182.363079 -315.203377) (xy 182.31486 -315.193533) (xy 182.268844 -315.176081) (xy 182.226223 -315.151474)
			(xy 182.188102 -315.120349) (xy 182.155467 -315.083512) (xy 182.129164 -315.041916) (xy 182.109873 -314.99664)
			(xy 182.098096 -314.948856) (xy 182.094136 -314.899802) (xy 181.755288 -314.899802) (xy 181.754793 -314.924409)
			(xy 181.746898 -314.972986) (xy 181.731314 -315.019667) (xy 181.708443 -315.063244) (xy 181.678878 -315.102588)
			(xy 181.643385 -315.13668) (xy 181.602882 -315.164636) (xy 181.55842 -315.185734) (xy 181.511149 -315.199426)
			(xy 181.462294 -315.205358) (xy 181.413119 -315.203377) (xy 181.3649 -315.193533) (xy 181.318884 -315.176081)
			(xy 181.276263 -315.151474) (xy 181.238142 -315.120349) (xy 181.205507 -315.083512) (xy 181.179204 -315.041916)
			(xy 181.159913 -314.99664) (xy 181.148136 -314.948856) (xy 181.144176 -314.899802) (xy 180.805328 -314.899802)
			(xy 180.804833 -314.924409) (xy 180.796938 -314.972986) (xy 180.781354 -315.019667) (xy 180.758483 -315.063244)
			(xy 180.728918 -315.102588) (xy 180.693425 -315.13668) (xy 180.652922 -315.164636) (xy 180.60846 -315.185734)
			(xy 180.561189 -315.199426) (xy 180.512334 -315.205358) (xy 180.463159 -315.203377) (xy 180.41494 -315.193533)
			(xy 180.368924 -315.176081) (xy 180.326303 -315.151474) (xy 180.288182 -315.120349) (xy 180.255547 -315.083512)
			(xy 180.229244 -315.041916) (xy 180.209953 -314.99664) (xy 180.198176 -314.948856) (xy 180.194216 -314.899802)
			(xy 179.855368 -314.899802) (xy 179.854873 -314.924409) (xy 179.846978 -314.972986) (xy 179.831394 -315.019667)
			(xy 179.808523 -315.063244) (xy 179.778958 -315.102588) (xy 179.743465 -315.13668) (xy 179.702962 -315.164636)
			(xy 179.6585 -315.185734) (xy 179.611229 -315.199426) (xy 179.562374 -315.205358) (xy 179.513199 -315.203377)
			(xy 179.46498 -315.193533) (xy 179.418964 -315.176081) (xy 179.376343 -315.151474) (xy 179.338222 -315.120349)
			(xy 179.305587 -315.083512) (xy 179.279284 -315.041916) (xy 179.259993 -314.99664) (xy 179.248216 -314.948856)
			(xy 179.244256 -314.899802) (xy 178.905154 -314.899802) (xy 178.904659 -314.924409) (xy 178.896764 -314.972986)
			(xy 178.88118 -315.019667) (xy 178.858309 -315.063244) (xy 178.828744 -315.102588) (xy 178.793251 -315.13668)
			(xy 178.752748 -315.164636) (xy 178.708286 -315.185734) (xy 178.661015 -315.199426) (xy 178.61216 -315.205358)
			(xy 178.562985 -315.203377) (xy 178.514766 -315.193533) (xy 178.46875 -315.176081) (xy 178.426129 -315.151474)
			(xy 178.388008 -315.120349) (xy 178.355373 -315.083512) (xy 178.32907 -315.041916) (xy 178.309779 -314.99664)
			(xy 178.298002 -314.948856) (xy 178.294042 -314.899802) (xy 177.955194 -314.899802) (xy 177.954699 -314.924409)
			(xy 177.946804 -314.972986) (xy 177.93122 -315.019667) (xy 177.908349 -315.063244) (xy 177.878784 -315.102588)
			(xy 177.843291 -315.13668) (xy 177.802788 -315.164636) (xy 177.758326 -315.185734) (xy 177.711055 -315.199426)
			(xy 177.6622 -315.205358) (xy 177.613025 -315.203377) (xy 177.564806 -315.193533) (xy 177.51879 -315.176081)
			(xy 177.476169 -315.151474) (xy 177.438048 -315.120349) (xy 177.405413 -315.083512) (xy 177.37911 -315.041916)
			(xy 177.359819 -314.99664) (xy 177.348042 -314.948856) (xy 177.344082 -314.899802) (xy 177.005234 -314.899802)
			(xy 177.004739 -314.924409) (xy 176.996844 -314.972986) (xy 176.98126 -315.019667) (xy 176.958389 -315.063244)
			(xy 176.928824 -315.102588) (xy 176.893331 -315.13668) (xy 176.852828 -315.164636) (xy 176.808366 -315.185734)
			(xy 176.761095 -315.199426) (xy 176.71224 -315.205358) (xy 176.663065 -315.203377) (xy 176.614846 -315.193533)
			(xy 176.56883 -315.176081) (xy 176.526209 -315.151474) (xy 176.488088 -315.120349) (xy 176.455453 -315.083512)
			(xy 176.42915 -315.041916) (xy 176.409859 -314.99664) (xy 176.398082 -314.948856) (xy 176.394122 -314.899802)
			(xy 176.055274 -314.899802) (xy 176.054779 -314.924409) (xy 176.046884 -314.972986) (xy 176.0313 -315.019667)
			(xy 176.008429 -315.063244) (xy 175.978864 -315.102588) (xy 175.943371 -315.13668) (xy 175.902868 -315.164636)
			(xy 175.858406 -315.185734) (xy 175.811135 -315.199426) (xy 175.76228 -315.205358) (xy 175.713105 -315.203377)
			(xy 175.664886 -315.193533) (xy 175.61887 -315.176081) (xy 175.576249 -315.151474) (xy 175.538128 -315.120349)
			(xy 175.505493 -315.083512) (xy 175.47919 -315.041916) (xy 175.459899 -314.99664) (xy 175.448122 -314.948856)
			(xy 175.444162 -314.899802) (xy 175.105314 -314.899802) (xy 175.104819 -314.924409) (xy 175.096924 -314.972986)
			(xy 175.08134 -315.019667) (xy 175.058469 -315.063244) (xy 175.028904 -315.102588) (xy 174.993411 -315.13668)
			(xy 174.952908 -315.164636) (xy 174.908446 -315.185734) (xy 174.861175 -315.199426) (xy 174.81232 -315.205358)
			(xy 174.763145 -315.203377) (xy 174.714926 -315.193533) (xy 174.66891 -315.176081) (xy 174.626289 -315.151474)
			(xy 174.588168 -315.120349) (xy 174.555533 -315.083512) (xy 174.52923 -315.041916) (xy 174.509939 -314.99664)
			(xy 174.498162 -314.948856) (xy 174.494202 -314.899802) (xy 174.155354 -314.899802) (xy 174.154859 -314.924409)
			(xy 174.146964 -314.972986) (xy 174.13138 -315.019667) (xy 174.108509 -315.063244) (xy 174.078944 -315.102588)
			(xy 174.043451 -315.13668) (xy 174.002948 -315.164636) (xy 173.958486 -315.185734) (xy 173.911215 -315.199426)
			(xy 173.86236 -315.205358) (xy 173.813185 -315.203377) (xy 173.764966 -315.193533) (xy 173.71895 -315.176081)
			(xy 173.676329 -315.151474) (xy 173.638208 -315.120349) (xy 173.605573 -315.083512) (xy 173.57927 -315.041916)
			(xy 173.559979 -314.99664) (xy 173.548202 -314.948856) (xy 173.544242 -314.899802) (xy 173.205394 -314.899802)
			(xy 173.204899 -314.924409) (xy 173.197004 -314.972986) (xy 173.18142 -315.019667) (xy 173.158549 -315.063244)
			(xy 173.128984 -315.102588) (xy 173.093491 -315.13668) (xy 173.052988 -315.164636) (xy 173.008526 -315.185734)
			(xy 172.961255 -315.199426) (xy 172.9124 -315.205358) (xy 172.863225 -315.203377) (xy 172.815006 -315.193533)
			(xy 172.76899 -315.176081) (xy 172.726369 -315.151474) (xy 172.688248 -315.120349) (xy 172.655613 -315.083512)
			(xy 172.62931 -315.041916) (xy 172.610019 -314.99664) (xy 172.598242 -314.948856) (xy 172.594282 -314.899802)
			(xy 172.25518 -314.899802) (xy 172.254685 -314.924409) (xy 172.24679 -314.972986) (xy 172.231206 -315.019667)
			(xy 172.208335 -315.063244) (xy 172.17877 -315.102588) (xy 172.143277 -315.13668) (xy 172.102774 -315.164636)
			(xy 172.058312 -315.185734) (xy 172.011041 -315.199426) (xy 171.962186 -315.205358) (xy 171.913011 -315.203377)
			(xy 171.864792 -315.193533) (xy 171.818776 -315.176081) (xy 171.776155 -315.151474) (xy 171.738034 -315.120349)
			(xy 171.705399 -315.083512) (xy 171.679096 -315.041916) (xy 171.659805 -314.99664) (xy 171.648028 -314.948856)
			(xy 171.644068 -314.899802) (xy 171.30522 -314.899802) (xy 171.304725 -314.924409) (xy 171.29683 -314.972986)
			(xy 171.281246 -315.019667) (xy 171.258375 -315.063244) (xy 171.22881 -315.102588) (xy 171.193317 -315.13668)
			(xy 171.152814 -315.164636) (xy 171.108352 -315.185734) (xy 171.061081 -315.199426) (xy 171.012226 -315.205358)
			(xy 170.963051 -315.203377) (xy 170.914832 -315.193533) (xy 170.868816 -315.176081) (xy 170.826195 -315.151474)
			(xy 170.788074 -315.120349) (xy 170.755439 -315.083512) (xy 170.729136 -315.041916) (xy 170.709845 -314.99664)
			(xy 170.698068 -314.948856) (xy 170.694108 -314.899802) (xy 170.35526 -314.899802) (xy 170.354765 -314.924409)
			(xy 170.34687 -314.972986) (xy 170.331286 -315.019667) (xy 170.308415 -315.063244) (xy 170.27885 -315.102588)
			(xy 170.243357 -315.13668) (xy 170.202854 -315.164636) (xy 170.158392 -315.185734) (xy 170.111121 -315.199426)
			(xy 170.062266 -315.205358) (xy 170.013091 -315.203377) (xy 169.964872 -315.193533) (xy 169.918856 -315.176081)
			(xy 169.876235 -315.151474) (xy 169.838114 -315.120349) (xy 169.805479 -315.083512) (xy 169.779176 -315.041916)
			(xy 169.759885 -314.99664) (xy 169.748108 -314.948856) (xy 169.744148 -314.899802) (xy 169.4053 -314.899802)
			(xy 169.404805 -314.924409) (xy 169.39691 -314.972986) (xy 169.381326 -315.019667) (xy 169.358455 -315.063244)
			(xy 169.32889 -315.102588) (xy 169.293397 -315.13668) (xy 169.252894 -315.164636) (xy 169.208432 -315.185734)
			(xy 169.161161 -315.199426) (xy 169.112306 -315.205358) (xy 169.063131 -315.203377) (xy 169.014912 -315.193533)
			(xy 168.968896 -315.176081) (xy 168.926275 -315.151474) (xy 168.888154 -315.120349) (xy 168.855519 -315.083512)
			(xy 168.829216 -315.041916) (xy 168.809925 -314.99664) (xy 168.798148 -314.948856) (xy 168.794188 -314.899802)
			(xy 168.45534 -314.899802) (xy 168.454845 -314.924409) (xy 168.44695 -314.972986) (xy 168.431366 -315.019667)
			(xy 168.408495 -315.063244) (xy 168.37893 -315.102588) (xy 168.343437 -315.13668) (xy 168.302934 -315.164636)
			(xy 168.258472 -315.185734) (xy 168.211201 -315.199426) (xy 168.162346 -315.205358) (xy 168.113171 -315.203377)
			(xy 168.064952 -315.193533) (xy 168.018936 -315.176081) (xy 167.976315 -315.151474) (xy 167.938194 -315.120349)
			(xy 167.905559 -315.083512) (xy 167.879256 -315.041916) (xy 167.859965 -314.99664) (xy 167.848188 -314.948856)
			(xy 167.844228 -314.899802) (xy 167.50538 -314.899802) (xy 167.504885 -314.924409) (xy 167.49699 -314.972986)
			(xy 167.481406 -315.019667) (xy 167.458535 -315.063244) (xy 167.42897 -315.102588) (xy 167.393477 -315.13668)
			(xy 167.352974 -315.164636) (xy 167.308512 -315.185734) (xy 167.261241 -315.199426) (xy 167.212386 -315.205358)
			(xy 167.163211 -315.203377) (xy 167.114992 -315.193533) (xy 167.068976 -315.176081) (xy 167.026355 -315.151474)
			(xy 166.988234 -315.120349) (xy 166.955599 -315.083512) (xy 166.929296 -315.041916) (xy 166.910005 -314.99664)
			(xy 166.898228 -314.948856) (xy 166.894268 -314.899802) (xy 166.555166 -314.899802) (xy 166.554671 -314.924409)
			(xy 166.546776 -314.972986) (xy 166.531192 -315.019667) (xy 166.508321 -315.063244) (xy 166.478756 -315.102588)
			(xy 166.443263 -315.13668) (xy 166.40276 -315.164636) (xy 166.358298 -315.185734) (xy 166.311027 -315.199426)
			(xy 166.262172 -315.205358) (xy 166.212997 -315.203377) (xy 166.164778 -315.193533) (xy 166.118762 -315.176081)
			(xy 166.076141 -315.151474) (xy 166.03802 -315.120349) (xy 166.005385 -315.083512) (xy 165.979082 -315.041916)
			(xy 165.959791 -314.99664) (xy 165.948014 -314.948856) (xy 165.944054 -314.899802) (xy 165.605758 -314.899802)
			(xy 165.601586 -314.950143) (xy 165.589186 -314.999112) (xy 165.568894 -315.045373) (xy 165.541264 -315.087663)
			(xy 165.507051 -315.124828) (xy 165.467187 -315.155855) (xy 165.42276 -315.179897) (xy 165.374982 -315.196299)
			(xy 165.325156 -315.204613) (xy 165.299898 -315.20511) (xy 165.290794 -315.205013) (xy 165.27262 -315.203872)
			(xy 165.263576 -315.202824) (xy 165.251384 -315.201554) (xy 165.240462 -315.205364) (xy 165.234884 -315.20753)
			(xy 165.224875 -315.214081) (xy 165.22065 -315.218318) (xy 165.164262 -315.277246) (xy 165.161468 -315.280294)
			(xy 165.15857 -315.284091) (xy 165.154103 -315.292532) (xy 165.152578 -315.297058) (xy 165.149022 -315.308488)
			(xy 165.151054 -315.320426) (xy 165.153185 -315.333914) (xy 165.155475 -315.361127) (xy 165.155626 -315.374782)
			(xy 165.155464 -315.388436) (xy 165.153175 -315.415649) (xy 165.151054 -315.429138) (xy 165.149022 -315.441076)
			(xy 165.152578 -315.452506) (xy 165.154093 -315.457036) (xy 165.15857 -315.465473) (xy 165.161468 -315.46927)
			(xy 165.164262 -315.472318) (xy 165.22065 -315.531246) (xy 165.224878 -315.53548) (xy 165.234886 -315.54203)
			(xy 165.240462 -315.5442) (xy 165.251384 -315.54801) (xy 165.263576 -315.54674) (xy 165.27262 -315.545692)
			(xy 165.290794 -315.544548) (xy 165.299898 -315.544454) (xy 165.325159 -315.544947) (xy 165.374992 -315.553262)
			(xy 165.422776 -315.569666) (xy 165.467209 -315.593712) (xy 165.507078 -315.624743) (xy 165.541296 -315.661913)
			(xy 165.568929 -315.704208) (xy 165.589223 -315.750475) (xy 165.601626 -315.799451) (xy 165.605795 -315.849762)
			(xy 165.944054 -315.849762) (xy 165.948014 -315.800708) (xy 165.959791 -315.752924) (xy 165.979082 -315.707648)
			(xy 166.005385 -315.666052) (xy 166.03802 -315.629215) (xy 166.076141 -315.59809) (xy 166.118762 -315.573483)
			(xy 166.164778 -315.556031) (xy 166.212997 -315.546187) (xy 166.262172 -315.544206) (xy 166.311027 -315.550138)
			(xy 166.358298 -315.56383) (xy 166.40276 -315.584928) (xy 166.443263 -315.612884) (xy 166.478756 -315.646976)
			(xy 166.508321 -315.68632) (xy 166.531192 -315.729897) (xy 166.546776 -315.776578) (xy 166.554671 -315.825155)
			(xy 166.555166 -315.849762) (xy 166.554671 -315.874369) (xy 166.554492 -315.87547) (xy 166.873424 -315.87547)
			(xy 166.873424 -315.824054) (xy 166.881467 -315.773272) (xy 166.897355 -315.724373) (xy 166.920698 -315.678561)
			(xy 166.950919 -315.636965) (xy 166.987275 -315.600609) (xy 167.028871 -315.570388) (xy 167.074683 -315.547045)
			(xy 167.123582 -315.531157) (xy 167.174364 -315.523114) (xy 167.22578 -315.523114) (xy 167.276562 -315.531157)
			(xy 167.325461 -315.547045) (xy 167.371273 -315.570388) (xy 167.412869 -315.600609) (xy 167.449225 -315.636965)
			(xy 167.479446 -315.678561) (xy 167.502789 -315.724373) (xy 167.518677 -315.773272) (xy 167.52672 -315.824054)
			(xy 167.527224 -315.849762) (xy 167.844228 -315.849762) (xy 167.848188 -315.800708) (xy 167.859965 -315.752924)
			(xy 167.879256 -315.707648) (xy 167.905559 -315.666052) (xy 167.938194 -315.629215) (xy 167.976315 -315.59809)
			(xy 168.018936 -315.573483) (xy 168.064952 -315.556031) (xy 168.113171 -315.546187) (xy 168.162346 -315.544206)
			(xy 168.211201 -315.550138) (xy 168.258472 -315.56383) (xy 168.302934 -315.584928) (xy 168.343437 -315.612884)
			(xy 168.37893 -315.646976) (xy 168.408495 -315.68632) (xy 168.431366 -315.729897) (xy 168.44695 -315.776578)
			(xy 168.454845 -315.825155) (xy 168.45534 -315.849762) (xy 168.454845 -315.874369) (xy 168.454666 -315.87547)
			(xy 168.773344 -315.87547) (xy 168.773344 -315.824054) (xy 168.781387 -315.773272) (xy 168.797275 -315.724373)
			(xy 168.820618 -315.678561) (xy 168.850839 -315.636965) (xy 168.887195 -315.600609) (xy 168.928791 -315.570388)
			(xy 168.974603 -315.547045) (xy 169.023502 -315.531157) (xy 169.074284 -315.523114) (xy 169.1257 -315.523114)
			(xy 169.176482 -315.531157) (xy 169.225381 -315.547045) (xy 169.271193 -315.570388) (xy 169.312789 -315.600609)
			(xy 169.349145 -315.636965) (xy 169.379366 -315.678561) (xy 169.402709 -315.724373) (xy 169.418597 -315.773272)
			(xy 169.42664 -315.824054) (xy 169.427144 -315.849762) (xy 169.744148 -315.849762) (xy 169.748108 -315.800708)
			(xy 169.759885 -315.752924) (xy 169.779176 -315.707648) (xy 169.805479 -315.666052) (xy 169.838114 -315.629215)
			(xy 169.876235 -315.59809) (xy 169.918856 -315.573483) (xy 169.964872 -315.556031) (xy 170.013091 -315.546187)
			(xy 170.062266 -315.544206) (xy 170.111121 -315.550138) (xy 170.158392 -315.56383) (xy 170.202854 -315.584928)
			(xy 170.243357 -315.612884) (xy 170.27885 -315.646976) (xy 170.308415 -315.68632) (xy 170.331286 -315.729897)
			(xy 170.34687 -315.776578) (xy 170.354765 -315.825155) (xy 170.35526 -315.849762) (xy 170.354765 -315.874369)
			(xy 170.354586 -315.87547) (xy 170.673264 -315.87547) (xy 170.673264 -315.824054) (xy 170.681307 -315.773272)
			(xy 170.697195 -315.724373) (xy 170.720538 -315.678561) (xy 170.750759 -315.636965) (xy 170.787115 -315.600609)
			(xy 170.828711 -315.570388) (xy 170.874523 -315.547045) (xy 170.923422 -315.531157) (xy 170.974204 -315.523114)
			(xy 171.02562 -315.523114) (xy 171.076402 -315.531157) (xy 171.125301 -315.547045) (xy 171.171113 -315.570388)
			(xy 171.212709 -315.600609) (xy 171.249065 -315.636965) (xy 171.279286 -315.678561) (xy 171.302629 -315.724373)
			(xy 171.318517 -315.773272) (xy 171.32656 -315.824054) (xy 171.327064 -315.849762) (xy 171.644068 -315.849762)
			(xy 171.648028 -315.800708) (xy 171.659805 -315.752924) (xy 171.679096 -315.707648) (xy 171.705399 -315.666052)
			(xy 171.738034 -315.629215) (xy 171.776155 -315.59809) (xy 171.818776 -315.573483) (xy 171.864792 -315.556031)
			(xy 171.913011 -315.546187) (xy 171.962186 -315.544206) (xy 172.011041 -315.550138) (xy 172.058312 -315.56383)
			(xy 172.102774 -315.584928) (xy 172.143277 -315.612884) (xy 172.17877 -315.646976) (xy 172.208335 -315.68632)
			(xy 172.231206 -315.729897) (xy 172.24679 -315.776578) (xy 172.254685 -315.825155) (xy 172.25518 -315.849762)
			(xy 172.254685 -315.874369) (xy 172.254506 -315.87547) (xy 172.573438 -315.87547) (xy 172.573438 -315.824054)
			(xy 172.581481 -315.773272) (xy 172.597369 -315.724373) (xy 172.620712 -315.678561) (xy 172.650933 -315.636965)
			(xy 172.687289 -315.600609) (xy 172.728885 -315.570388) (xy 172.774697 -315.547045) (xy 172.823596 -315.531157)
			(xy 172.874378 -315.523114) (xy 172.925794 -315.523114) (xy 172.976576 -315.531157) (xy 173.025475 -315.547045)
			(xy 173.071287 -315.570388) (xy 173.112883 -315.600609) (xy 173.149239 -315.636965) (xy 173.17946 -315.678561)
			(xy 173.202803 -315.724373) (xy 173.218691 -315.773272) (xy 173.226734 -315.824054) (xy 173.227238 -315.849762)
			(xy 173.544242 -315.849762) (xy 173.548202 -315.800708) (xy 173.559979 -315.752924) (xy 173.57927 -315.707648)
			(xy 173.605573 -315.666052) (xy 173.638208 -315.629215) (xy 173.676329 -315.59809) (xy 173.71895 -315.573483)
			(xy 173.764966 -315.556031) (xy 173.813185 -315.546187) (xy 173.86236 -315.544206) (xy 173.911215 -315.550138)
			(xy 173.958486 -315.56383) (xy 174.002948 -315.584928) (xy 174.043451 -315.612884) (xy 174.078944 -315.646976)
			(xy 174.108509 -315.68632) (xy 174.13138 -315.729897) (xy 174.146964 -315.776578) (xy 174.154859 -315.825155)
			(xy 174.155354 -315.849762) (xy 174.154859 -315.874369) (xy 174.15468 -315.87547) (xy 174.473358 -315.87547)
			(xy 174.473358 -315.824054) (xy 174.481401 -315.773272) (xy 174.497289 -315.724373) (xy 174.520632 -315.678561)
			(xy 174.550853 -315.636965) (xy 174.587209 -315.600609) (xy 174.628805 -315.570388) (xy 174.674617 -315.547045)
			(xy 174.723516 -315.531157) (xy 174.774298 -315.523114) (xy 174.825714 -315.523114) (xy 174.876496 -315.531157)
			(xy 174.925395 -315.547045) (xy 174.971207 -315.570388) (xy 175.012803 -315.600609) (xy 175.049159 -315.636965)
			(xy 175.07938 -315.678561) (xy 175.102723 -315.724373) (xy 175.118611 -315.773272) (xy 175.126654 -315.824054)
			(xy 175.127158 -315.849762) (xy 175.444162 -315.849762) (xy 175.448122 -315.800708) (xy 175.459899 -315.752924)
			(xy 175.47919 -315.707648) (xy 175.505493 -315.666052) (xy 175.538128 -315.629215) (xy 175.576249 -315.59809)
			(xy 175.61887 -315.573483) (xy 175.664886 -315.556031) (xy 175.713105 -315.546187) (xy 175.76228 -315.544206)
			(xy 175.811135 -315.550138) (xy 175.858406 -315.56383) (xy 175.902868 -315.584928) (xy 175.943371 -315.612884)
			(xy 175.978864 -315.646976) (xy 176.008429 -315.68632) (xy 176.0313 -315.729897) (xy 176.046884 -315.776578)
			(xy 176.054779 -315.825155) (xy 176.055274 -315.849762) (xy 176.054779 -315.874369) (xy 176.0546 -315.87547)
			(xy 176.373278 -315.87547) (xy 176.373278 -315.824054) (xy 176.381321 -315.773272) (xy 176.397209 -315.724373)
			(xy 176.420552 -315.678561) (xy 176.450773 -315.636965) (xy 176.487129 -315.600609) (xy 176.528725 -315.570388)
			(xy 176.574537 -315.547045) (xy 176.623436 -315.531157) (xy 176.674218 -315.523114) (xy 176.725634 -315.523114)
			(xy 176.776416 -315.531157) (xy 176.825315 -315.547045) (xy 176.871127 -315.570388) (xy 176.912723 -315.600609)
			(xy 176.949079 -315.636965) (xy 176.9793 -315.678561) (xy 177.002643 -315.724373) (xy 177.018531 -315.773272)
			(xy 177.026574 -315.824054) (xy 177.027078 -315.849762) (xy 177.344082 -315.849762) (xy 177.348042 -315.800708)
			(xy 177.359819 -315.752924) (xy 177.37911 -315.707648) (xy 177.405413 -315.666052) (xy 177.438048 -315.629215)
			(xy 177.476169 -315.59809) (xy 177.51879 -315.573483) (xy 177.564806 -315.556031) (xy 177.613025 -315.546187)
			(xy 177.6622 -315.544206) (xy 177.711055 -315.550138) (xy 177.758326 -315.56383) (xy 177.802788 -315.584928)
			(xy 177.843291 -315.612884) (xy 177.878784 -315.646976) (xy 177.908349 -315.68632) (xy 177.93122 -315.729897)
			(xy 177.946804 -315.776578) (xy 177.954699 -315.825155) (xy 177.955194 -315.849762) (xy 177.954699 -315.874369)
			(xy 177.95452 -315.87547) (xy 178.273198 -315.87547) (xy 178.273198 -315.824054) (xy 178.281241 -315.773272)
			(xy 178.297129 -315.724373) (xy 178.320472 -315.678561) (xy 178.350693 -315.636965) (xy 178.387049 -315.600609)
			(xy 178.428645 -315.570388) (xy 178.474457 -315.547045) (xy 178.523356 -315.531157) (xy 178.574138 -315.523114)
			(xy 178.625554 -315.523114) (xy 178.676336 -315.531157) (xy 178.725235 -315.547045) (xy 178.771047 -315.570388)
			(xy 178.812643 -315.600609) (xy 178.848999 -315.636965) (xy 178.87922 -315.678561) (xy 178.902563 -315.724373)
			(xy 178.918451 -315.773272) (xy 178.926494 -315.824054) (xy 178.926998 -315.849762) (xy 179.244256 -315.849762)
			(xy 179.248216 -315.800708) (xy 179.259993 -315.752924) (xy 179.279284 -315.707648) (xy 179.305587 -315.666052)
			(xy 179.338222 -315.629215) (xy 179.376343 -315.59809) (xy 179.418964 -315.573483) (xy 179.46498 -315.556031)
			(xy 179.513199 -315.546187) (xy 179.562374 -315.544206) (xy 179.611229 -315.550138) (xy 179.6585 -315.56383)
			(xy 179.702962 -315.584928) (xy 179.743465 -315.612884) (xy 179.778958 -315.646976) (xy 179.808523 -315.68632)
			(xy 179.831394 -315.729897) (xy 179.846978 -315.776578) (xy 179.854873 -315.825155) (xy 179.855368 -315.849762)
			(xy 179.854873 -315.874369) (xy 179.854694 -315.87547) (xy 180.173372 -315.87547) (xy 180.173372 -315.824054)
			(xy 180.181415 -315.773272) (xy 180.197303 -315.724373) (xy 180.220646 -315.678561) (xy 180.250867 -315.636965)
			(xy 180.287223 -315.600609) (xy 180.328819 -315.570388) (xy 180.374631 -315.547045) (xy 180.42353 -315.531157)
			(xy 180.474312 -315.523114) (xy 180.525728 -315.523114) (xy 180.57651 -315.531157) (xy 180.625409 -315.547045)
			(xy 180.671221 -315.570388) (xy 180.712817 -315.600609) (xy 180.749173 -315.636965) (xy 180.779394 -315.678561)
			(xy 180.802737 -315.724373) (xy 180.818625 -315.773272) (xy 180.826668 -315.824054) (xy 180.827172 -315.849762)
			(xy 181.144176 -315.849762) (xy 181.148136 -315.800708) (xy 181.159913 -315.752924) (xy 181.179204 -315.707648)
			(xy 181.205507 -315.666052) (xy 181.238142 -315.629215) (xy 181.276263 -315.59809) (xy 181.318884 -315.573483)
			(xy 181.3649 -315.556031) (xy 181.413119 -315.546187) (xy 181.462294 -315.544206) (xy 181.511149 -315.550138)
			(xy 181.55842 -315.56383) (xy 181.602882 -315.584928) (xy 181.643385 -315.612884) (xy 181.678878 -315.646976)
			(xy 181.708443 -315.68632) (xy 181.731314 -315.729897) (xy 181.746898 -315.776578) (xy 181.754793 -315.825155)
			(xy 181.755288 -315.849762) (xy 182.094136 -315.849762) (xy 182.098096 -315.800708) (xy 182.109873 -315.752924)
			(xy 182.129164 -315.707648) (xy 182.155467 -315.666052) (xy 182.188102 -315.629215) (xy 182.226223 -315.59809)
			(xy 182.268844 -315.573483) (xy 182.31486 -315.556031) (xy 182.363079 -315.546187) (xy 182.412254 -315.544206)
			(xy 182.461109 -315.550138) (xy 182.50838 -315.56383) (xy 182.552842 -315.584928) (xy 182.593345 -315.612884)
			(xy 182.628838 -315.646976) (xy 182.658403 -315.68632) (xy 182.681274 -315.729897) (xy 182.696858 -315.776578)
			(xy 182.704753 -315.825155) (xy 182.705248 -315.849762) (xy 183.044096 -315.849762) (xy 183.048056 -315.800708)
			(xy 183.059833 -315.752924) (xy 183.079124 -315.707648) (xy 183.105427 -315.666052) (xy 183.138062 -315.629215)
			(xy 183.176183 -315.59809) (xy 183.218804 -315.573483) (xy 183.26482 -315.556031) (xy 183.313039 -315.546187)
			(xy 183.362214 -315.544206) (xy 183.411069 -315.550138) (xy 183.45834 -315.56383) (xy 183.502802 -315.584928)
			(xy 183.543305 -315.612884) (xy 183.578798 -315.646976) (xy 183.608363 -315.68632) (xy 183.631234 -315.729897)
			(xy 183.646818 -315.776578) (xy 183.654713 -315.825155) (xy 183.655208 -315.849762) (xy 183.994056 -315.849762)
			(xy 183.998016 -315.800708) (xy 184.009793 -315.752924) (xy 184.029084 -315.707648) (xy 184.055387 -315.666052)
			(xy 184.088022 -315.629215) (xy 184.126143 -315.59809) (xy 184.168764 -315.573483) (xy 184.21478 -315.556031)
			(xy 184.262999 -315.546187) (xy 184.312174 -315.544206) (xy 184.361029 -315.550138) (xy 184.4083 -315.56383)
			(xy 184.452762 -315.584928) (xy 184.493265 -315.612884) (xy 184.528758 -315.646976) (xy 184.558323 -315.68632)
			(xy 184.581194 -315.729897) (xy 184.596778 -315.776578) (xy 184.604673 -315.825155) (xy 184.605168 -315.849762)
			(xy 184.94427 -315.849762) (xy 184.94823 -315.800708) (xy 184.960007 -315.752924) (xy 184.979298 -315.707648)
			(xy 185.005601 -315.666052) (xy 185.038236 -315.629215) (xy 185.076357 -315.59809) (xy 185.118978 -315.573483)
			(xy 185.164994 -315.556031) (xy 185.213213 -315.546187) (xy 185.262388 -315.544206) (xy 185.311243 -315.550138)
			(xy 185.358514 -315.56383) (xy 185.402976 -315.584928) (xy 185.443479 -315.612884) (xy 185.478972 -315.646976)
			(xy 185.508537 -315.68632) (xy 185.531408 -315.729897) (xy 185.546992 -315.776578) (xy 185.554887 -315.825155)
			(xy 185.555382 -315.849762) (xy 185.89423 -315.849762) (xy 185.89819 -315.800708) (xy 185.909967 -315.752924)
			(xy 185.929258 -315.707648) (xy 185.955561 -315.666052) (xy 185.988196 -315.629215) (xy 186.026317 -315.59809)
			(xy 186.068938 -315.573483) (xy 186.114954 -315.556031) (xy 186.163173 -315.546187) (xy 186.212348 -315.544206)
			(xy 186.261203 -315.550138) (xy 186.308474 -315.56383) (xy 186.352936 -315.584928) (xy 186.393439 -315.612884)
			(xy 186.428932 -315.646976) (xy 186.458497 -315.68632) (xy 186.481368 -315.729897) (xy 186.496952 -315.776578)
			(xy 186.504847 -315.825155) (xy 186.505342 -315.849762) (xy 186.84419 -315.849762) (xy 186.84815 -315.800708)
			(xy 186.859927 -315.752924) (xy 186.879218 -315.707648) (xy 186.905521 -315.666052) (xy 186.938156 -315.629215)
			(xy 186.976277 -315.59809) (xy 187.018898 -315.573483) (xy 187.064914 -315.556031) (xy 187.113133 -315.546187)
			(xy 187.162308 -315.544206) (xy 187.211163 -315.550138) (xy 187.258434 -315.56383) (xy 187.302896 -315.584928)
			(xy 187.343399 -315.612884) (xy 187.378892 -315.646976) (xy 187.408457 -315.68632) (xy 187.431328 -315.729897)
			(xy 187.446912 -315.776578) (xy 187.454807 -315.825155) (xy 187.455302 -315.849762) (xy 187.79415 -315.849762)
			(xy 187.79811 -315.800708) (xy 187.809887 -315.752924) (xy 187.829178 -315.707648) (xy 187.855481 -315.666052)
			(xy 187.888116 -315.629215) (xy 187.926237 -315.59809) (xy 187.968858 -315.573483) (xy 188.014874 -315.556031)
			(xy 188.063093 -315.546187) (xy 188.112268 -315.544206) (xy 188.161123 -315.550138) (xy 188.208394 -315.56383)
			(xy 188.252856 -315.584928) (xy 188.293359 -315.612884) (xy 188.328852 -315.646976) (xy 188.358417 -315.68632)
			(xy 188.381288 -315.729897) (xy 188.396872 -315.776578) (xy 188.404767 -315.825155) (xy 188.405262 -315.849762)
			(xy 188.74411 -315.849762) (xy 188.74807 -315.800708) (xy 188.759847 -315.752924) (xy 188.779138 -315.707648)
			(xy 188.805441 -315.666052) (xy 188.838076 -315.629215) (xy 188.876197 -315.59809) (xy 188.918818 -315.573483)
			(xy 188.964834 -315.556031) (xy 189.013053 -315.546187) (xy 189.062228 -315.544206) (xy 189.111083 -315.550138)
			(xy 189.158354 -315.56383) (xy 189.202816 -315.584928) (xy 189.243319 -315.612884) (xy 189.278812 -315.646976)
			(xy 189.308377 -315.68632) (xy 189.331248 -315.729897) (xy 189.346832 -315.776578) (xy 189.354727 -315.825155)
			(xy 189.355222 -315.849762) (xy 189.354727 -315.874369) (xy 189.354548 -315.87547) (xy 189.673226 -315.87547)
			(xy 189.673226 -315.824054) (xy 189.681269 -315.773272) (xy 189.697157 -315.724373) (xy 189.7205 -315.678561)
			(xy 189.750721 -315.636965) (xy 189.787077 -315.600609) (xy 189.828673 -315.570388) (xy 189.874485 -315.547045)
			(xy 189.923384 -315.531157) (xy 189.974166 -315.523114) (xy 190.025582 -315.523114) (xy 190.076364 -315.531157)
			(xy 190.125263 -315.547045) (xy 190.171075 -315.570388) (xy 190.212671 -315.600609) (xy 190.249027 -315.636965)
			(xy 190.279248 -315.678561) (xy 190.302591 -315.724373) (xy 190.318479 -315.773272) (xy 190.326522 -315.824054)
			(xy 190.327026 -315.849762) (xy 190.644284 -315.849762) (xy 190.648244 -315.800708) (xy 190.660021 -315.752924)
			(xy 190.679312 -315.707648) (xy 190.705615 -315.666052) (xy 190.73825 -315.629215) (xy 190.776371 -315.59809)
			(xy 190.818992 -315.573483) (xy 190.865008 -315.556031) (xy 190.913227 -315.546187) (xy 190.962402 -315.544206)
			(xy 191.011257 -315.550138) (xy 191.058528 -315.56383) (xy 191.10299 -315.584928) (xy 191.143493 -315.612884)
			(xy 191.178986 -315.646976) (xy 191.208551 -315.68632) (xy 191.231422 -315.729897) (xy 191.247006 -315.776578)
			(xy 191.254901 -315.825155) (xy 191.255396 -315.849762) (xy 191.254901 -315.874369) (xy 191.254722 -315.87547)
			(xy 191.5734 -315.87547) (xy 191.5734 -315.824054) (xy 191.581443 -315.773272) (xy 191.597331 -315.724373)
			(xy 191.620674 -315.678561) (xy 191.650895 -315.636965) (xy 191.687251 -315.600609) (xy 191.728847 -315.570388)
			(xy 191.774659 -315.547045) (xy 191.823558 -315.531157) (xy 191.87434 -315.523114) (xy 191.925756 -315.523114)
			(xy 191.976538 -315.531157) (xy 192.025437 -315.547045) (xy 192.071249 -315.570388) (xy 192.112845 -315.600609)
			(xy 192.149201 -315.636965) (xy 192.179422 -315.678561) (xy 192.202765 -315.724373) (xy 192.218653 -315.773272)
			(xy 192.226696 -315.824054) (xy 192.2272 -315.849762) (xy 192.544204 -315.849762) (xy 192.548164 -315.800708)
			(xy 192.559941 -315.752924) (xy 192.579232 -315.707648) (xy 192.605535 -315.666052) (xy 192.63817 -315.629215)
			(xy 192.676291 -315.59809) (xy 192.718912 -315.573483) (xy 192.764928 -315.556031) (xy 192.813147 -315.546187)
			(xy 192.862322 -315.544206) (xy 192.911177 -315.550138) (xy 192.958448 -315.56383) (xy 193.00291 -315.584928)
			(xy 193.043413 -315.612884) (xy 193.078906 -315.646976) (xy 193.108471 -315.68632) (xy 193.131342 -315.729897)
			(xy 193.146926 -315.776578) (xy 193.154821 -315.825155) (xy 193.155316 -315.849762) (xy 193.154821 -315.874369)
			(xy 193.154642 -315.87547) (xy 193.47332 -315.87547) (xy 193.47332 -315.824054) (xy 193.481363 -315.773272)
			(xy 193.497251 -315.724373) (xy 193.520594 -315.678561) (xy 193.550815 -315.636965) (xy 193.587171 -315.600609)
			(xy 193.628767 -315.570388) (xy 193.674579 -315.547045) (xy 193.723478 -315.531157) (xy 193.77426 -315.523114)
			(xy 193.825676 -315.523114) (xy 193.876458 -315.531157) (xy 193.925357 -315.547045) (xy 193.971169 -315.570388)
			(xy 194.012765 -315.600609) (xy 194.049121 -315.636965) (xy 194.079342 -315.678561) (xy 194.102685 -315.724373)
			(xy 194.118573 -315.773272) (xy 194.126616 -315.824054) (xy 194.12712 -315.849762) (xy 194.444124 -315.849762)
			(xy 194.448084 -315.800708) (xy 194.459861 -315.752924) (xy 194.479152 -315.707648) (xy 194.505455 -315.666052)
			(xy 194.53809 -315.629215) (xy 194.576211 -315.59809) (xy 194.618832 -315.573483) (xy 194.664848 -315.556031)
			(xy 194.713067 -315.546187) (xy 194.762242 -315.544206) (xy 194.811097 -315.550138) (xy 194.858368 -315.56383)
			(xy 194.90283 -315.584928) (xy 194.943333 -315.612884) (xy 194.978826 -315.646976) (xy 195.008391 -315.68632)
			(xy 195.031262 -315.729897) (xy 195.046846 -315.776578) (xy 195.054741 -315.825155) (xy 195.055236 -315.849762)
			(xy 195.054741 -315.874369) (xy 195.054562 -315.87547) (xy 195.37324 -315.87547) (xy 195.37324 -315.824054)
			(xy 195.381283 -315.773272) (xy 195.397171 -315.724373) (xy 195.420514 -315.678561) (xy 195.450735 -315.636965)
			(xy 195.487091 -315.600609) (xy 195.528687 -315.570388) (xy 195.574499 -315.547045) (xy 195.623398 -315.531157)
			(xy 195.67418 -315.523114) (xy 195.725596 -315.523114) (xy 195.776378 -315.531157) (xy 195.825277 -315.547045)
			(xy 195.871089 -315.570388) (xy 195.912685 -315.600609) (xy 195.949041 -315.636965) (xy 195.979262 -315.678561)
			(xy 196.002605 -315.724373) (xy 196.018493 -315.773272) (xy 196.026536 -315.824054) (xy 196.02704 -315.849762)
			(xy 196.344044 -315.849762) (xy 196.348004 -315.800708) (xy 196.359781 -315.752924) (xy 196.379072 -315.707648)
			(xy 196.405375 -315.666052) (xy 196.43801 -315.629215) (xy 196.476131 -315.59809) (xy 196.518752 -315.573483)
			(xy 196.564768 -315.556031) (xy 196.612987 -315.546187) (xy 196.662162 -315.544206) (xy 196.711017 -315.550138)
			(xy 196.758288 -315.56383) (xy 196.80275 -315.584928) (xy 196.843253 -315.612884) (xy 196.878746 -315.646976)
			(xy 196.908311 -315.68632) (xy 196.931182 -315.729897) (xy 196.946766 -315.776578) (xy 196.954661 -315.825155)
			(xy 196.955156 -315.849762) (xy 197.294258 -315.849762) (xy 197.298218 -315.800708) (xy 197.309995 -315.752924)
			(xy 197.329286 -315.707648) (xy 197.355589 -315.666052) (xy 197.388224 -315.629215) (xy 197.426345 -315.59809)
			(xy 197.468966 -315.573483) (xy 197.514982 -315.556031) (xy 197.563201 -315.546187) (xy 197.612376 -315.544206)
			(xy 197.661231 -315.550138) (xy 197.708502 -315.56383) (xy 197.752964 -315.584928) (xy 197.793467 -315.612884)
			(xy 197.82896 -315.646976) (xy 197.858525 -315.68632) (xy 197.881396 -315.729897) (xy 197.89698 -315.776578)
			(xy 197.904875 -315.825155) (xy 197.90537 -315.849762) (xy 198.244218 -315.849762) (xy 198.248178 -315.800708)
			(xy 198.259955 -315.752924) (xy 198.279246 -315.707648) (xy 198.305549 -315.666052) (xy 198.338184 -315.629215)
			(xy 198.376305 -315.59809) (xy 198.418926 -315.573483) (xy 198.464942 -315.556031) (xy 198.513161 -315.546187)
			(xy 198.562336 -315.544206) (xy 198.611191 -315.550138) (xy 198.658462 -315.56383) (xy 198.702924 -315.584928)
			(xy 198.743427 -315.612884) (xy 198.77892 -315.646976) (xy 198.808485 -315.68632) (xy 198.831356 -315.729897)
			(xy 198.84694 -315.776578) (xy 198.854835 -315.825155) (xy 198.85533 -315.849762) (xy 198.854835 -315.874369)
			(xy 198.84694 -315.922946) (xy 198.831356 -315.969627) (xy 198.808485 -316.013204) (xy 198.77892 -316.052548)
			(xy 198.743427 -316.08664) (xy 198.702924 -316.114596) (xy 198.658462 -316.135694) (xy 198.611191 -316.149386)
			(xy 198.562336 -316.155318) (xy 198.513161 -316.153337) (xy 198.464942 -316.143493) (xy 198.418926 -316.126041)
			(xy 198.376305 -316.101434) (xy 198.338184 -316.070309) (xy 198.305549 -316.033472) (xy 198.279246 -315.991876)
			(xy 198.259955 -315.9466) (xy 198.248178 -315.898816) (xy 198.244218 -315.849762) (xy 197.90537 -315.849762)
			(xy 197.904875 -315.874369) (xy 197.89698 -315.922946) (xy 197.881396 -315.969627) (xy 197.858525 -316.013204)
			(xy 197.82896 -316.052548) (xy 197.793467 -316.08664) (xy 197.752964 -316.114596) (xy 197.708502 -316.135694)
			(xy 197.661231 -316.149386) (xy 197.612376 -316.155318) (xy 197.563201 -316.153337) (xy 197.514982 -316.143493)
			(xy 197.468966 -316.126041) (xy 197.426345 -316.101434) (xy 197.388224 -316.070309) (xy 197.355589 -316.033472)
			(xy 197.329286 -315.991876) (xy 197.309995 -315.9466) (xy 197.298218 -315.898816) (xy 197.294258 -315.849762)
			(xy 196.955156 -315.849762) (xy 196.954661 -315.874369) (xy 196.946766 -315.922946) (xy 196.931182 -315.969627)
			(xy 196.908311 -316.013204) (xy 196.878746 -316.052548) (xy 196.843253 -316.08664) (xy 196.80275 -316.114596)
			(xy 196.758288 -316.135694) (xy 196.711017 -316.149386) (xy 196.662162 -316.155318) (xy 196.612987 -316.153337)
			(xy 196.564768 -316.143493) (xy 196.518752 -316.126041) (xy 196.476131 -316.101434) (xy 196.43801 -316.070309)
			(xy 196.405375 -316.033472) (xy 196.379072 -315.991876) (xy 196.359781 -315.9466) (xy 196.348004 -315.898816)
			(xy 196.344044 -315.849762) (xy 196.02704 -315.849762) (xy 196.026536 -315.87547) (xy 196.018493 -315.926252)
			(xy 196.002605 -315.975151) (xy 195.979262 -316.020963) (xy 195.949041 -316.062559) (xy 195.912685 -316.098915)
			(xy 195.871089 -316.129136) (xy 195.825277 -316.152479) (xy 195.776378 -316.168367) (xy 195.725596 -316.17641)
			(xy 195.67418 -316.17641) (xy 195.623398 -316.168367) (xy 195.574499 -316.152479) (xy 195.528687 -316.129136)
			(xy 195.487091 -316.098915) (xy 195.450735 -316.062559) (xy 195.420514 -316.020963) (xy 195.397171 -315.975151)
			(xy 195.381283 -315.926252) (xy 195.37324 -315.87547) (xy 195.054562 -315.87547) (xy 195.046846 -315.922946)
			(xy 195.031262 -315.969627) (xy 195.008391 -316.013204) (xy 194.978826 -316.052548) (xy 194.943333 -316.08664)
			(xy 194.90283 -316.114596) (xy 194.858368 -316.135694) (xy 194.811097 -316.149386) (xy 194.762242 -316.155318)
			(xy 194.713067 -316.153337) (xy 194.664848 -316.143493) (xy 194.618832 -316.126041) (xy 194.576211 -316.101434)
			(xy 194.53809 -316.070309) (xy 194.505455 -316.033472) (xy 194.479152 -315.991876) (xy 194.459861 -315.9466)
			(xy 194.448084 -315.898816) (xy 194.444124 -315.849762) (xy 194.12712 -315.849762) (xy 194.126616 -315.87547)
			(xy 194.118573 -315.926252) (xy 194.102685 -315.975151) (xy 194.079342 -316.020963) (xy 194.049121 -316.062559)
			(xy 194.012765 -316.098915) (xy 193.971169 -316.129136) (xy 193.925357 -316.152479) (xy 193.876458 -316.168367)
			(xy 193.825676 -316.17641) (xy 193.77426 -316.17641) (xy 193.723478 -316.168367) (xy 193.674579 -316.152479)
			(xy 193.628767 -316.129136) (xy 193.587171 -316.098915) (xy 193.550815 -316.062559) (xy 193.520594 -316.020963)
			(xy 193.497251 -315.975151) (xy 193.481363 -315.926252) (xy 193.47332 -315.87547) (xy 193.154642 -315.87547)
			(xy 193.146926 -315.922946) (xy 193.131342 -315.969627) (xy 193.108471 -316.013204) (xy 193.078906 -316.052548)
			(xy 193.043413 -316.08664) (xy 193.00291 -316.114596) (xy 192.958448 -316.135694) (xy 192.911177 -316.149386)
			(xy 192.862322 -316.155318) (xy 192.813147 -316.153337) (xy 192.764928 -316.143493) (xy 192.718912 -316.126041)
			(xy 192.676291 -316.101434) (xy 192.63817 -316.070309) (xy 192.605535 -316.033472) (xy 192.579232 -315.991876)
			(xy 192.559941 -315.9466) (xy 192.548164 -315.898816) (xy 192.544204 -315.849762) (xy 192.2272 -315.849762)
			(xy 192.226696 -315.87547) (xy 192.218653 -315.926252) (xy 192.202765 -315.975151) (xy 192.179422 -316.020963)
			(xy 192.149201 -316.062559) (xy 192.112845 -316.098915) (xy 192.071249 -316.129136) (xy 192.025437 -316.152479)
			(xy 191.976538 -316.168367) (xy 191.925756 -316.17641) (xy 191.87434 -316.17641) (xy 191.823558 -316.168367)
			(xy 191.774659 -316.152479) (xy 191.728847 -316.129136) (xy 191.687251 -316.098915) (xy 191.650895 -316.062559)
			(xy 191.620674 -316.020963) (xy 191.597331 -315.975151) (xy 191.581443 -315.926252) (xy 191.5734 -315.87547)
			(xy 191.254722 -315.87547) (xy 191.247006 -315.922946) (xy 191.231422 -315.969627) (xy 191.208551 -316.013204)
			(xy 191.178986 -316.052548) (xy 191.143493 -316.08664) (xy 191.10299 -316.114596) (xy 191.058528 -316.135694)
			(xy 191.011257 -316.149386) (xy 190.962402 -316.155318) (xy 190.913227 -316.153337) (xy 190.865008 -316.143493)
			(xy 190.818992 -316.126041) (xy 190.776371 -316.101434) (xy 190.73825 -316.070309) (xy 190.705615 -316.033472)
			(xy 190.679312 -315.991876) (xy 190.660021 -315.9466) (xy 190.648244 -315.898816) (xy 190.644284 -315.849762)
			(xy 190.327026 -315.849762) (xy 190.326522 -315.87547) (xy 190.318479 -315.926252) (xy 190.302591 -315.975151)
			(xy 190.279248 -316.020963) (xy 190.249027 -316.062559) (xy 190.212671 -316.098915) (xy 190.171075 -316.129136)
			(xy 190.125263 -316.152479) (xy 190.076364 -316.168367) (xy 190.025582 -316.17641) (xy 189.974166 -316.17641)
			(xy 189.923384 -316.168367) (xy 189.874485 -316.152479) (xy 189.828673 -316.129136) (xy 189.787077 -316.098915)
			(xy 189.750721 -316.062559) (xy 189.7205 -316.020963) (xy 189.697157 -315.975151) (xy 189.681269 -315.926252)
			(xy 189.673226 -315.87547) (xy 189.354548 -315.87547) (xy 189.346832 -315.922946) (xy 189.331248 -315.969627)
			(xy 189.308377 -316.013204) (xy 189.278812 -316.052548) (xy 189.243319 -316.08664) (xy 189.202816 -316.114596)
			(xy 189.158354 -316.135694) (xy 189.111083 -316.149386) (xy 189.062228 -316.155318) (xy 189.013053 -316.153337)
			(xy 188.964834 -316.143493) (xy 188.918818 -316.126041) (xy 188.876197 -316.101434) (xy 188.838076 -316.070309)
			(xy 188.805441 -316.033472) (xy 188.779138 -315.991876) (xy 188.759847 -315.9466) (xy 188.74807 -315.898816)
			(xy 188.74411 -315.849762) (xy 188.405262 -315.849762) (xy 188.404767 -315.874369) (xy 188.396872 -315.922946)
			(xy 188.381288 -315.969627) (xy 188.358417 -316.013204) (xy 188.328852 -316.052548) (xy 188.293359 -316.08664)
			(xy 188.252856 -316.114596) (xy 188.208394 -316.135694) (xy 188.161123 -316.149386) (xy 188.112268 -316.155318)
			(xy 188.063093 -316.153337) (xy 188.014874 -316.143493) (xy 187.968858 -316.126041) (xy 187.926237 -316.101434)
			(xy 187.888116 -316.070309) (xy 187.855481 -316.033472) (xy 187.829178 -315.991876) (xy 187.809887 -315.9466)
			(xy 187.79811 -315.898816) (xy 187.79415 -315.849762) (xy 187.455302 -315.849762) (xy 187.454807 -315.874369)
			(xy 187.446912 -315.922946) (xy 187.431328 -315.969627) (xy 187.408457 -316.013204) (xy 187.378892 -316.052548)
			(xy 187.343399 -316.08664) (xy 187.302896 -316.114596) (xy 187.258434 -316.135694) (xy 187.211163 -316.149386)
			(xy 187.162308 -316.155318) (xy 187.113133 -316.153337) (xy 187.064914 -316.143493) (xy 187.018898 -316.126041)
			(xy 186.976277 -316.101434) (xy 186.938156 -316.070309) (xy 186.905521 -316.033472) (xy 186.879218 -315.991876)
			(xy 186.859927 -315.9466) (xy 186.84815 -315.898816) (xy 186.84419 -315.849762) (xy 186.505342 -315.849762)
			(xy 186.504847 -315.874369) (xy 186.496952 -315.922946) (xy 186.481368 -315.969627) (xy 186.458497 -316.013204)
			(xy 186.428932 -316.052548) (xy 186.393439 -316.08664) (xy 186.352936 -316.114596) (xy 186.308474 -316.135694)
			(xy 186.261203 -316.149386) (xy 186.212348 -316.155318) (xy 186.163173 -316.153337) (xy 186.114954 -316.143493)
			(xy 186.068938 -316.126041) (xy 186.026317 -316.101434) (xy 185.988196 -316.070309) (xy 185.955561 -316.033472)
			(xy 185.929258 -315.991876) (xy 185.909967 -315.9466) (xy 185.89819 -315.898816) (xy 185.89423 -315.849762)
			(xy 185.555382 -315.849762) (xy 185.554887 -315.874369) (xy 185.546992 -315.922946) (xy 185.531408 -315.969627)
			(xy 185.508537 -316.013204) (xy 185.478972 -316.052548) (xy 185.443479 -316.08664) (xy 185.402976 -316.114596)
			(xy 185.358514 -316.135694) (xy 185.311243 -316.149386) (xy 185.262388 -316.155318) (xy 185.213213 -316.153337)
			(xy 185.164994 -316.143493) (xy 185.118978 -316.126041) (xy 185.076357 -316.101434) (xy 185.038236 -316.070309)
			(xy 185.005601 -316.033472) (xy 184.979298 -315.991876) (xy 184.960007 -315.9466) (xy 184.94823 -315.898816)
			(xy 184.94427 -315.849762) (xy 184.605168 -315.849762) (xy 184.604673 -315.874369) (xy 184.596778 -315.922946)
			(xy 184.581194 -315.969627) (xy 184.558323 -316.013204) (xy 184.528758 -316.052548) (xy 184.493265 -316.08664)
			(xy 184.452762 -316.114596) (xy 184.4083 -316.135694) (xy 184.361029 -316.149386) (xy 184.312174 -316.155318)
			(xy 184.262999 -316.153337) (xy 184.21478 -316.143493) (xy 184.168764 -316.126041) (xy 184.126143 -316.101434)
			(xy 184.088022 -316.070309) (xy 184.055387 -316.033472) (xy 184.029084 -315.991876) (xy 184.009793 -315.9466)
			(xy 183.998016 -315.898816) (xy 183.994056 -315.849762) (xy 183.655208 -315.849762) (xy 183.654713 -315.874369)
			(xy 183.646818 -315.922946) (xy 183.631234 -315.969627) (xy 183.608363 -316.013204) (xy 183.578798 -316.052548)
			(xy 183.543305 -316.08664) (xy 183.502802 -316.114596) (xy 183.45834 -316.135694) (xy 183.411069 -316.149386)
			(xy 183.362214 -316.155318) (xy 183.313039 -316.153337) (xy 183.26482 -316.143493) (xy 183.218804 -316.126041)
			(xy 183.176183 -316.101434) (xy 183.138062 -316.070309) (xy 183.105427 -316.033472) (xy 183.079124 -315.991876)
			(xy 183.059833 -315.9466) (xy 183.048056 -315.898816) (xy 183.044096 -315.849762) (xy 182.705248 -315.849762)
			(xy 182.704753 -315.874369) (xy 182.696858 -315.922946) (xy 182.681274 -315.969627) (xy 182.658403 -316.013204)
			(xy 182.628838 -316.052548) (xy 182.593345 -316.08664) (xy 182.552842 -316.114596) (xy 182.50838 -316.135694)
			(xy 182.461109 -316.149386) (xy 182.412254 -316.155318) (xy 182.363079 -316.153337) (xy 182.31486 -316.143493)
			(xy 182.268844 -316.126041) (xy 182.226223 -316.101434) (xy 182.188102 -316.070309) (xy 182.155467 -316.033472)
			(xy 182.129164 -315.991876) (xy 182.109873 -315.9466) (xy 182.098096 -315.898816) (xy 182.094136 -315.849762)
			(xy 181.755288 -315.849762) (xy 181.754793 -315.874369) (xy 181.746898 -315.922946) (xy 181.731314 -315.969627)
			(xy 181.708443 -316.013204) (xy 181.678878 -316.052548) (xy 181.643385 -316.08664) (xy 181.602882 -316.114596)
			(xy 181.55842 -316.135694) (xy 181.511149 -316.149386) (xy 181.462294 -316.155318) (xy 181.413119 -316.153337)
			(xy 181.3649 -316.143493) (xy 181.318884 -316.126041) (xy 181.276263 -316.101434) (xy 181.238142 -316.070309)
			(xy 181.205507 -316.033472) (xy 181.179204 -315.991876) (xy 181.159913 -315.9466) (xy 181.148136 -315.898816)
			(xy 181.144176 -315.849762) (xy 180.827172 -315.849762) (xy 180.826668 -315.87547) (xy 180.818625 -315.926252)
			(xy 180.802737 -315.975151) (xy 180.779394 -316.020963) (xy 180.749173 -316.062559) (xy 180.712817 -316.098915)
			(xy 180.671221 -316.129136) (xy 180.625409 -316.152479) (xy 180.57651 -316.168367) (xy 180.525728 -316.17641)
			(xy 180.474312 -316.17641) (xy 180.42353 -316.168367) (xy 180.374631 -316.152479) (xy 180.328819 -316.129136)
			(xy 180.287223 -316.098915) (xy 180.250867 -316.062559) (xy 180.220646 -316.020963) (xy 180.197303 -315.975151)
			(xy 180.181415 -315.926252) (xy 180.173372 -315.87547) (xy 179.854694 -315.87547) (xy 179.846978 -315.922946)
			(xy 179.831394 -315.969627) (xy 179.808523 -316.013204) (xy 179.778958 -316.052548) (xy 179.743465 -316.08664)
			(xy 179.702962 -316.114596) (xy 179.6585 -316.135694) (xy 179.611229 -316.149386) (xy 179.562374 -316.155318)
			(xy 179.513199 -316.153337) (xy 179.46498 -316.143493) (xy 179.418964 -316.126041) (xy 179.376343 -316.101434)
			(xy 179.338222 -316.070309) (xy 179.305587 -316.033472) (xy 179.279284 -315.991876) (xy 179.259993 -315.9466)
			(xy 179.248216 -315.898816) (xy 179.244256 -315.849762) (xy 178.926998 -315.849762) (xy 178.926494 -315.87547)
			(xy 178.918451 -315.926252) (xy 178.902563 -315.975151) (xy 178.87922 -316.020963) (xy 178.848999 -316.062559)
			(xy 178.812643 -316.098915) (xy 178.771047 -316.129136) (xy 178.725235 -316.152479) (xy 178.676336 -316.168367)
			(xy 178.625554 -316.17641) (xy 178.574138 -316.17641) (xy 178.523356 -316.168367) (xy 178.474457 -316.152479)
			(xy 178.428645 -316.129136) (xy 178.387049 -316.098915) (xy 178.350693 -316.062559) (xy 178.320472 -316.020963)
			(xy 178.297129 -315.975151) (xy 178.281241 -315.926252) (xy 178.273198 -315.87547) (xy 177.95452 -315.87547)
			(xy 177.946804 -315.922946) (xy 177.93122 -315.969627) (xy 177.908349 -316.013204) (xy 177.878784 -316.052548)
			(xy 177.843291 -316.08664) (xy 177.802788 -316.114596) (xy 177.758326 -316.135694) (xy 177.711055 -316.149386)
			(xy 177.6622 -316.155318) (xy 177.613025 -316.153337) (xy 177.564806 -316.143493) (xy 177.51879 -316.126041)
			(xy 177.476169 -316.101434) (xy 177.438048 -316.070309) (xy 177.405413 -316.033472) (xy 177.37911 -315.991876)
			(xy 177.359819 -315.9466) (xy 177.348042 -315.898816) (xy 177.344082 -315.849762) (xy 177.027078 -315.849762)
			(xy 177.026574 -315.87547) (xy 177.018531 -315.926252) (xy 177.002643 -315.975151) (xy 176.9793 -316.020963)
			(xy 176.949079 -316.062559) (xy 176.912723 -316.098915) (xy 176.871127 -316.129136) (xy 176.825315 -316.152479)
			(xy 176.776416 -316.168367) (xy 176.725634 -316.17641) (xy 176.674218 -316.17641) (xy 176.623436 -316.168367)
			(xy 176.574537 -316.152479) (xy 176.528725 -316.129136) (xy 176.487129 -316.098915) (xy 176.450773 -316.062559)
			(xy 176.420552 -316.020963) (xy 176.397209 -315.975151) (xy 176.381321 -315.926252) (xy 176.373278 -315.87547)
			(xy 176.0546 -315.87547) (xy 176.046884 -315.922946) (xy 176.0313 -315.969627) (xy 176.008429 -316.013204)
			(xy 175.978864 -316.052548) (xy 175.943371 -316.08664) (xy 175.902868 -316.114596) (xy 175.858406 -316.135694)
			(xy 175.811135 -316.149386) (xy 175.76228 -316.155318) (xy 175.713105 -316.153337) (xy 175.664886 -316.143493)
			(xy 175.61887 -316.126041) (xy 175.576249 -316.101434) (xy 175.538128 -316.070309) (xy 175.505493 -316.033472)
			(xy 175.47919 -315.991876) (xy 175.459899 -315.9466) (xy 175.448122 -315.898816) (xy 175.444162 -315.849762)
			(xy 175.127158 -315.849762) (xy 175.126654 -315.87547) (xy 175.118611 -315.926252) (xy 175.102723 -315.975151)
			(xy 175.07938 -316.020963) (xy 175.049159 -316.062559) (xy 175.012803 -316.098915) (xy 174.971207 -316.129136)
			(xy 174.925395 -316.152479) (xy 174.876496 -316.168367) (xy 174.825714 -316.17641) (xy 174.774298 -316.17641)
			(xy 174.723516 -316.168367) (xy 174.674617 -316.152479) (xy 174.628805 -316.129136) (xy 174.587209 -316.098915)
			(xy 174.550853 -316.062559) (xy 174.520632 -316.020963) (xy 174.497289 -315.975151) (xy 174.481401 -315.926252)
			(xy 174.473358 -315.87547) (xy 174.15468 -315.87547) (xy 174.146964 -315.922946) (xy 174.13138 -315.969627)
			(xy 174.108509 -316.013204) (xy 174.078944 -316.052548) (xy 174.043451 -316.08664) (xy 174.002948 -316.114596)
			(xy 173.958486 -316.135694) (xy 173.911215 -316.149386) (xy 173.86236 -316.155318) (xy 173.813185 -316.153337)
			(xy 173.764966 -316.143493) (xy 173.71895 -316.126041) (xy 173.676329 -316.101434) (xy 173.638208 -316.070309)
			(xy 173.605573 -316.033472) (xy 173.57927 -315.991876) (xy 173.559979 -315.9466) (xy 173.548202 -315.898816)
			(xy 173.544242 -315.849762) (xy 173.227238 -315.849762) (xy 173.226734 -315.87547) (xy 173.218691 -315.926252)
			(xy 173.202803 -315.975151) (xy 173.17946 -316.020963) (xy 173.149239 -316.062559) (xy 173.112883 -316.098915)
			(xy 173.071287 -316.129136) (xy 173.025475 -316.152479) (xy 172.976576 -316.168367) (xy 172.925794 -316.17641)
			(xy 172.874378 -316.17641) (xy 172.823596 -316.168367) (xy 172.774697 -316.152479) (xy 172.728885 -316.129136)
			(xy 172.687289 -316.098915) (xy 172.650933 -316.062559) (xy 172.620712 -316.020963) (xy 172.597369 -315.975151)
			(xy 172.581481 -315.926252) (xy 172.573438 -315.87547) (xy 172.254506 -315.87547) (xy 172.24679 -315.922946)
			(xy 172.231206 -315.969627) (xy 172.208335 -316.013204) (xy 172.17877 -316.052548) (xy 172.143277 -316.08664)
			(xy 172.102774 -316.114596) (xy 172.058312 -316.135694) (xy 172.011041 -316.149386) (xy 171.962186 -316.155318)
			(xy 171.913011 -316.153337) (xy 171.864792 -316.143493) (xy 171.818776 -316.126041) (xy 171.776155 -316.101434)
			(xy 171.738034 -316.070309) (xy 171.705399 -316.033472) (xy 171.679096 -315.991876) (xy 171.659805 -315.9466)
			(xy 171.648028 -315.898816) (xy 171.644068 -315.849762) (xy 171.327064 -315.849762) (xy 171.32656 -315.87547)
			(xy 171.318517 -315.926252) (xy 171.302629 -315.975151) (xy 171.279286 -316.020963) (xy 171.249065 -316.062559)
			(xy 171.212709 -316.098915) (xy 171.171113 -316.129136) (xy 171.125301 -316.152479) (xy 171.076402 -316.168367)
			(xy 171.02562 -316.17641) (xy 170.974204 -316.17641) (xy 170.923422 -316.168367) (xy 170.874523 -316.152479)
			(xy 170.828711 -316.129136) (xy 170.787115 -316.098915) (xy 170.750759 -316.062559) (xy 170.720538 -316.020963)
			(xy 170.697195 -315.975151) (xy 170.681307 -315.926252) (xy 170.673264 -315.87547) (xy 170.354586 -315.87547)
			(xy 170.34687 -315.922946) (xy 170.331286 -315.969627) (xy 170.308415 -316.013204) (xy 170.27885 -316.052548)
			(xy 170.243357 -316.08664) (xy 170.202854 -316.114596) (xy 170.158392 -316.135694) (xy 170.111121 -316.149386)
			(xy 170.062266 -316.155318) (xy 170.013091 -316.153337) (xy 169.964872 -316.143493) (xy 169.918856 -316.126041)
			(xy 169.876235 -316.101434) (xy 169.838114 -316.070309) (xy 169.805479 -316.033472) (xy 169.779176 -315.991876)
			(xy 169.759885 -315.9466) (xy 169.748108 -315.898816) (xy 169.744148 -315.849762) (xy 169.427144 -315.849762)
			(xy 169.42664 -315.87547) (xy 169.418597 -315.926252) (xy 169.402709 -315.975151) (xy 169.379366 -316.020963)
			(xy 169.349145 -316.062559) (xy 169.312789 -316.098915) (xy 169.271193 -316.129136) (xy 169.225381 -316.152479)
			(xy 169.176482 -316.168367) (xy 169.1257 -316.17641) (xy 169.074284 -316.17641) (xy 169.023502 -316.168367)
			(xy 168.974603 -316.152479) (xy 168.928791 -316.129136) (xy 168.887195 -316.098915) (xy 168.850839 -316.062559)
			(xy 168.820618 -316.020963) (xy 168.797275 -315.975151) (xy 168.781387 -315.926252) (xy 168.773344 -315.87547)
			(xy 168.454666 -315.87547) (xy 168.44695 -315.922946) (xy 168.431366 -315.969627) (xy 168.408495 -316.013204)
			(xy 168.37893 -316.052548) (xy 168.343437 -316.08664) (xy 168.302934 -316.114596) (xy 168.258472 -316.135694)
			(xy 168.211201 -316.149386) (xy 168.162346 -316.155318) (xy 168.113171 -316.153337) (xy 168.064952 -316.143493)
			(xy 168.018936 -316.126041) (xy 167.976315 -316.101434) (xy 167.938194 -316.070309) (xy 167.905559 -316.033472)
			(xy 167.879256 -315.991876) (xy 167.859965 -315.9466) (xy 167.848188 -315.898816) (xy 167.844228 -315.849762)
			(xy 167.527224 -315.849762) (xy 167.52672 -315.87547) (xy 167.518677 -315.926252) (xy 167.502789 -315.975151)
			(xy 167.479446 -316.020963) (xy 167.449225 -316.062559) (xy 167.412869 -316.098915) (xy 167.371273 -316.129136)
			(xy 167.325461 -316.152479) (xy 167.276562 -316.168367) (xy 167.22578 -316.17641) (xy 167.174364 -316.17641)
			(xy 167.123582 -316.168367) (xy 167.074683 -316.152479) (xy 167.028871 -316.129136) (xy 166.987275 -316.098915)
			(xy 166.950919 -316.062559) (xy 166.920698 -316.020963) (xy 166.897355 -315.975151) (xy 166.881467 -315.926252)
			(xy 166.873424 -315.87547) (xy 166.554492 -315.87547) (xy 166.546776 -315.922946) (xy 166.531192 -315.969627)
			(xy 166.508321 -316.013204) (xy 166.478756 -316.052548) (xy 166.443263 -316.08664) (xy 166.40276 -316.114596)
			(xy 166.358298 -316.135694) (xy 166.311027 -316.149386) (xy 166.262172 -316.155318) (xy 166.212997 -316.153337)
			(xy 166.164778 -316.143493) (xy 166.118762 -316.126041) (xy 166.076141 -316.101434) (xy 166.03802 -316.070309)
			(xy 166.005385 -316.033472) (xy 165.979082 -315.991876) (xy 165.959791 -315.9466) (xy 165.948014 -315.898816)
			(xy 165.944054 -315.849762) (xy 165.605795 -315.849762) (xy 165.605798 -315.8498) (xy 165.601626 -315.900149)
			(xy 165.589223 -315.949125) (xy 165.568929 -315.995392) (xy 165.541296 -316.037687) (xy 165.507078 -316.074857)
			(xy 165.467209 -316.105888) (xy 165.422776 -316.129934) (xy 165.374992 -316.146338) (xy 165.325159 -316.154653)
			(xy 165.299898 -316.15507) (xy 165.290794 -316.154973) (xy 165.27262 -316.153832) (xy 165.263576 -316.152784)
			(xy 165.251384 -316.151514) (xy 165.240462 -316.155324) (xy 165.234883 -316.157489) (xy 165.224871 -316.164036)
			(xy 165.22065 -316.168278) (xy 165.164262 -316.227206) (xy 165.161468 -316.230254) (xy 165.158568 -316.234049)
			(xy 165.154094 -316.242488) (xy 165.152578 -316.247018) (xy 165.149022 -316.258448) (xy 165.151054 -316.270386)
			(xy 165.153179 -316.283811) (xy 165.155468 -316.310897) (xy 165.155626 -316.324488) (xy 165.155626 -316.324996)
			(xy 165.155372 -316.334394) (xy 165.155372 -316.3951) (xy 165.155626 -316.399418) (xy 165.155626 -316.399926)
			(xy 165.156645 -316.407806) (xy 165.162854 -316.422423) (xy 165.167818 -316.428628) (xy 165.172136 -316.432946)
			(xy 165.228524 -316.483492) (xy 165.232527 -316.486889) (xy 165.241614 -316.492141) (xy 165.246558 -316.493906)
			(xy 165.256718 -316.497208) (xy 165.26764 -316.496192) (xy 165.299898 -316.494414) (xy 165.325154 -316.494906)
			(xy 165.374977 -316.50322) (xy 165.422752 -316.519621) (xy 165.467176 -316.543662) (xy 165.507038 -316.574687)
			(xy 165.541249 -316.61185) (xy 165.568876 -316.654137) (xy 165.589167 -316.700394) (xy 165.601567 -316.749361)
			(xy 165.605738 -316.7997) (xy 165.605736 -316.799722) (xy 165.944054 -316.799722) (xy 165.948014 -316.750668)
			(xy 165.959791 -316.702884) (xy 165.979082 -316.657608) (xy 166.005385 -316.616012) (xy 166.03802 -316.579175)
			(xy 166.076141 -316.54805) (xy 166.118762 -316.523443) (xy 166.164778 -316.505991) (xy 166.212997 -316.496147)
			(xy 166.262172 -316.494166) (xy 166.311027 -316.500098) (xy 166.358298 -316.51379) (xy 166.40276 -316.534888)
			(xy 166.443263 -316.562844) (xy 166.478756 -316.596936) (xy 166.508321 -316.63628) (xy 166.531192 -316.679857)
			(xy 166.546776 -316.726538) (xy 166.554671 -316.775115) (xy 166.555166 -316.799722) (xy 166.554671 -316.824329)
			(xy 166.554492 -316.82543) (xy 166.873424 -316.82543) (xy 166.873424 -316.774014) (xy 166.881467 -316.723232)
			(xy 166.897355 -316.674333) (xy 166.920698 -316.628521) (xy 166.950919 -316.586925) (xy 166.987275 -316.550569)
			(xy 167.028871 -316.520348) (xy 167.074683 -316.497005) (xy 167.123582 -316.481117) (xy 167.174364 -316.473074)
			(xy 167.22578 -316.473074) (xy 167.276562 -316.481117) (xy 167.325461 -316.497005) (xy 167.371273 -316.520348)
			(xy 167.412869 -316.550569) (xy 167.449225 -316.586925) (xy 167.479446 -316.628521) (xy 167.502789 -316.674333)
			(xy 167.518677 -316.723232) (xy 167.52672 -316.774014) (xy 167.527224 -316.799722) (xy 167.844228 -316.799722)
			(xy 167.848188 -316.750668) (xy 167.859965 -316.702884) (xy 167.879256 -316.657608) (xy 167.905559 -316.616012)
			(xy 167.938194 -316.579175) (xy 167.976315 -316.54805) (xy 168.018936 -316.523443) (xy 168.064952 -316.505991)
			(xy 168.113171 -316.496147) (xy 168.162346 -316.494166) (xy 168.211201 -316.500098) (xy 168.258472 -316.51379)
			(xy 168.302934 -316.534888) (xy 168.343437 -316.562844) (xy 168.37893 -316.596936) (xy 168.408495 -316.63628)
			(xy 168.431366 -316.679857) (xy 168.44695 -316.726538) (xy 168.454845 -316.775115) (xy 168.45534 -316.799722)
			(xy 168.454845 -316.824329) (xy 168.454666 -316.82543) (xy 168.773344 -316.82543) (xy 168.773344 -316.774014)
			(xy 168.781387 -316.723232) (xy 168.797275 -316.674333) (xy 168.820618 -316.628521) (xy 168.850839 -316.586925)
			(xy 168.887195 -316.550569) (xy 168.928791 -316.520348) (xy 168.974603 -316.497005) (xy 169.023502 -316.481117)
			(xy 169.074284 -316.473074) (xy 169.1257 -316.473074) (xy 169.176482 -316.481117) (xy 169.225381 -316.497005)
			(xy 169.271193 -316.520348) (xy 169.312789 -316.550569) (xy 169.349145 -316.586925) (xy 169.379366 -316.628521)
			(xy 169.402709 -316.674333) (xy 169.418597 -316.723232) (xy 169.42664 -316.774014) (xy 169.427144 -316.799722)
			(xy 169.744148 -316.799722) (xy 169.748108 -316.750668) (xy 169.759885 -316.702884) (xy 169.779176 -316.657608)
			(xy 169.805479 -316.616012) (xy 169.838114 -316.579175) (xy 169.876235 -316.54805) (xy 169.918856 -316.523443)
			(xy 169.964872 -316.505991) (xy 170.013091 -316.496147) (xy 170.062266 -316.494166) (xy 170.111121 -316.500098)
			(xy 170.158392 -316.51379) (xy 170.202854 -316.534888) (xy 170.243357 -316.562844) (xy 170.27885 -316.596936)
			(xy 170.308415 -316.63628) (xy 170.331286 -316.679857) (xy 170.34687 -316.726538) (xy 170.354765 -316.775115)
			(xy 170.35526 -316.799722) (xy 170.354765 -316.824329) (xy 170.354586 -316.82543) (xy 170.673264 -316.82543)
			(xy 170.673264 -316.774014) (xy 170.681307 -316.723232) (xy 170.697195 -316.674333) (xy 170.720538 -316.628521)
			(xy 170.750759 -316.586925) (xy 170.787115 -316.550569) (xy 170.828711 -316.520348) (xy 170.874523 -316.497005)
			(xy 170.923422 -316.481117) (xy 170.974204 -316.473074) (xy 171.02562 -316.473074) (xy 171.076402 -316.481117)
			(xy 171.125301 -316.497005) (xy 171.171113 -316.520348) (xy 171.212709 -316.550569) (xy 171.249065 -316.586925)
			(xy 171.279286 -316.628521) (xy 171.302629 -316.674333) (xy 171.318517 -316.723232) (xy 171.32656 -316.774014)
			(xy 171.327064 -316.799722) (xy 171.644068 -316.799722) (xy 171.648028 -316.750668) (xy 171.659805 -316.702884)
			(xy 171.679096 -316.657608) (xy 171.705399 -316.616012) (xy 171.738034 -316.579175) (xy 171.776155 -316.54805)
			(xy 171.818776 -316.523443) (xy 171.864792 -316.505991) (xy 171.913011 -316.496147) (xy 171.962186 -316.494166)
			(xy 172.011041 -316.500098) (xy 172.058312 -316.51379) (xy 172.102774 -316.534888) (xy 172.143277 -316.562844)
			(xy 172.17877 -316.596936) (xy 172.208335 -316.63628) (xy 172.231206 -316.679857) (xy 172.24679 -316.726538)
			(xy 172.254685 -316.775115) (xy 172.25518 -316.799722) (xy 172.254685 -316.824329) (xy 172.254506 -316.82543)
			(xy 172.573438 -316.82543) (xy 172.573438 -316.774014) (xy 172.581481 -316.723232) (xy 172.597369 -316.674333)
			(xy 172.620712 -316.628521) (xy 172.650933 -316.586925) (xy 172.687289 -316.550569) (xy 172.728885 -316.520348)
			(xy 172.774697 -316.497005) (xy 172.823596 -316.481117) (xy 172.874378 -316.473074) (xy 172.925794 -316.473074)
			(xy 172.976576 -316.481117) (xy 173.025475 -316.497005) (xy 173.071287 -316.520348) (xy 173.112883 -316.550569)
			(xy 173.149239 -316.586925) (xy 173.17946 -316.628521) (xy 173.202803 -316.674333) (xy 173.218691 -316.723232)
			(xy 173.226734 -316.774014) (xy 173.227238 -316.799722) (xy 173.544242 -316.799722) (xy 173.548202 -316.750668)
			(xy 173.559979 -316.702884) (xy 173.57927 -316.657608) (xy 173.605573 -316.616012) (xy 173.638208 -316.579175)
			(xy 173.676329 -316.54805) (xy 173.71895 -316.523443) (xy 173.764966 -316.505991) (xy 173.813185 -316.496147)
			(xy 173.86236 -316.494166) (xy 173.911215 -316.500098) (xy 173.958486 -316.51379) (xy 174.002948 -316.534888)
			(xy 174.043451 -316.562844) (xy 174.078944 -316.596936) (xy 174.108509 -316.63628) (xy 174.13138 -316.679857)
			(xy 174.146964 -316.726538) (xy 174.154859 -316.775115) (xy 174.155354 -316.799722) (xy 174.154859 -316.824329)
			(xy 174.15468 -316.82543) (xy 174.473358 -316.82543) (xy 174.473358 -316.774014) (xy 174.481401 -316.723232)
			(xy 174.497289 -316.674333) (xy 174.520632 -316.628521) (xy 174.550853 -316.586925) (xy 174.587209 -316.550569)
			(xy 174.628805 -316.520348) (xy 174.674617 -316.497005) (xy 174.723516 -316.481117) (xy 174.774298 -316.473074)
			(xy 174.825714 -316.473074) (xy 174.876496 -316.481117) (xy 174.925395 -316.497005) (xy 174.971207 -316.520348)
			(xy 175.012803 -316.550569) (xy 175.049159 -316.586925) (xy 175.07938 -316.628521) (xy 175.102723 -316.674333)
			(xy 175.118611 -316.723232) (xy 175.126654 -316.774014) (xy 175.127158 -316.799722) (xy 175.444162 -316.799722)
			(xy 175.448122 -316.750668) (xy 175.459899 -316.702884) (xy 175.47919 -316.657608) (xy 175.505493 -316.616012)
			(xy 175.538128 -316.579175) (xy 175.576249 -316.54805) (xy 175.61887 -316.523443) (xy 175.664886 -316.505991)
			(xy 175.713105 -316.496147) (xy 175.76228 -316.494166) (xy 175.811135 -316.500098) (xy 175.858406 -316.51379)
			(xy 175.902868 -316.534888) (xy 175.943371 -316.562844) (xy 175.978864 -316.596936) (xy 176.008429 -316.63628)
			(xy 176.0313 -316.679857) (xy 176.046884 -316.726538) (xy 176.054779 -316.775115) (xy 176.055274 -316.799722)
			(xy 176.054779 -316.824329) (xy 176.0546 -316.82543) (xy 176.373278 -316.82543) (xy 176.373278 -316.774014)
			(xy 176.381321 -316.723232) (xy 176.397209 -316.674333) (xy 176.420552 -316.628521) (xy 176.450773 -316.586925)
			(xy 176.487129 -316.550569) (xy 176.528725 -316.520348) (xy 176.574537 -316.497005) (xy 176.623436 -316.481117)
			(xy 176.674218 -316.473074) (xy 176.725634 -316.473074) (xy 176.776416 -316.481117) (xy 176.825315 -316.497005)
			(xy 176.871127 -316.520348) (xy 176.912723 -316.550569) (xy 176.949079 -316.586925) (xy 176.9793 -316.628521)
			(xy 177.002643 -316.674333) (xy 177.018531 -316.723232) (xy 177.026574 -316.774014) (xy 177.027078 -316.799722)
			(xy 177.344082 -316.799722) (xy 177.348042 -316.750668) (xy 177.359819 -316.702884) (xy 177.37911 -316.657608)
			(xy 177.405413 -316.616012) (xy 177.438048 -316.579175) (xy 177.476169 -316.54805) (xy 177.51879 -316.523443)
			(xy 177.564806 -316.505991) (xy 177.613025 -316.496147) (xy 177.6622 -316.494166) (xy 177.711055 -316.500098)
			(xy 177.758326 -316.51379) (xy 177.802788 -316.534888) (xy 177.843291 -316.562844) (xy 177.878784 -316.596936)
			(xy 177.908349 -316.63628) (xy 177.93122 -316.679857) (xy 177.946804 -316.726538) (xy 177.954699 -316.775115)
			(xy 177.955194 -316.799722) (xy 177.954699 -316.824329) (xy 177.95452 -316.82543) (xy 178.273198 -316.82543)
			(xy 178.273198 -316.774014) (xy 178.281241 -316.723232) (xy 178.297129 -316.674333) (xy 178.320472 -316.628521)
			(xy 178.350693 -316.586925) (xy 178.387049 -316.550569) (xy 178.428645 -316.520348) (xy 178.474457 -316.497005)
			(xy 178.523356 -316.481117) (xy 178.574138 -316.473074) (xy 178.625554 -316.473074) (xy 178.676336 -316.481117)
			(xy 178.725235 -316.497005) (xy 178.771047 -316.520348) (xy 178.812643 -316.550569) (xy 178.848999 -316.586925)
			(xy 178.87922 -316.628521) (xy 178.902563 -316.674333) (xy 178.918451 -316.723232) (xy 178.926494 -316.774014)
			(xy 178.926998 -316.799722) (xy 179.244256 -316.799722) (xy 179.248216 -316.750668) (xy 179.259993 -316.702884)
			(xy 179.279284 -316.657608) (xy 179.305587 -316.616012) (xy 179.338222 -316.579175) (xy 179.376343 -316.54805)
			(xy 179.418964 -316.523443) (xy 179.46498 -316.505991) (xy 179.513199 -316.496147) (xy 179.562374 -316.494166)
			(xy 179.611229 -316.500098) (xy 179.6585 -316.51379) (xy 179.702962 -316.534888) (xy 179.743465 -316.562844)
			(xy 179.778958 -316.596936) (xy 179.808523 -316.63628) (xy 179.831394 -316.679857) (xy 179.846978 -316.726538)
			(xy 179.854873 -316.775115) (xy 179.855368 -316.799722) (xy 179.854873 -316.824329) (xy 179.854694 -316.82543)
			(xy 180.173372 -316.82543) (xy 180.173372 -316.774014) (xy 180.181415 -316.723232) (xy 180.197303 -316.674333)
			(xy 180.220646 -316.628521) (xy 180.250867 -316.586925) (xy 180.287223 -316.550569) (xy 180.328819 -316.520348)
			(xy 180.374631 -316.497005) (xy 180.42353 -316.481117) (xy 180.474312 -316.473074) (xy 180.525728 -316.473074)
			(xy 180.57651 -316.481117) (xy 180.625409 -316.497005) (xy 180.671221 -316.520348) (xy 180.712817 -316.550569)
			(xy 180.749173 -316.586925) (xy 180.779394 -316.628521) (xy 180.802737 -316.674333) (xy 180.818625 -316.723232)
			(xy 180.826668 -316.774014) (xy 180.827172 -316.799722) (xy 181.144176 -316.799722) (xy 181.148136 -316.750668)
			(xy 181.159913 -316.702884) (xy 181.179204 -316.657608) (xy 181.205507 -316.616012) (xy 181.238142 -316.579175)
			(xy 181.276263 -316.54805) (xy 181.318884 -316.523443) (xy 181.3649 -316.505991) (xy 181.413119 -316.496147)
			(xy 181.462294 -316.494166) (xy 181.511149 -316.500098) (xy 181.55842 -316.51379) (xy 181.602882 -316.534888)
			(xy 181.643385 -316.562844) (xy 181.678878 -316.596936) (xy 181.708443 -316.63628) (xy 181.731314 -316.679857)
			(xy 181.746898 -316.726538) (xy 181.754793 -316.775115) (xy 181.755288 -316.799722) (xy 182.094136 -316.799722)
			(xy 182.098096 -316.750668) (xy 182.109873 -316.702884) (xy 182.129164 -316.657608) (xy 182.155467 -316.616012)
			(xy 182.188102 -316.579175) (xy 182.226223 -316.54805) (xy 182.268844 -316.523443) (xy 182.31486 -316.505991)
			(xy 182.363079 -316.496147) (xy 182.412254 -316.494166) (xy 182.461109 -316.500098) (xy 182.50838 -316.51379)
			(xy 182.552842 -316.534888) (xy 182.593345 -316.562844) (xy 182.628838 -316.596936) (xy 182.658403 -316.63628)
			(xy 182.681274 -316.679857) (xy 182.696858 -316.726538) (xy 182.704753 -316.775115) (xy 182.705248 -316.799722)
			(xy 183.044096 -316.799722) (xy 183.048056 -316.750668) (xy 183.059833 -316.702884) (xy 183.079124 -316.657608)
			(xy 183.105427 -316.616012) (xy 183.138062 -316.579175) (xy 183.176183 -316.54805) (xy 183.218804 -316.523443)
			(xy 183.26482 -316.505991) (xy 183.313039 -316.496147) (xy 183.362214 -316.494166) (xy 183.411069 -316.500098)
			(xy 183.45834 -316.51379) (xy 183.502802 -316.534888) (xy 183.543305 -316.562844) (xy 183.578798 -316.596936)
			(xy 183.608363 -316.63628) (xy 183.631234 -316.679857) (xy 183.646818 -316.726538) (xy 183.654713 -316.775115)
			(xy 183.655208 -316.799722) (xy 183.994056 -316.799722) (xy 183.998016 -316.750668) (xy 184.009793 -316.702884)
			(xy 184.029084 -316.657608) (xy 184.055387 -316.616012) (xy 184.088022 -316.579175) (xy 184.126143 -316.54805)
			(xy 184.168764 -316.523443) (xy 184.21478 -316.505991) (xy 184.262999 -316.496147) (xy 184.312174 -316.494166)
			(xy 184.361029 -316.500098) (xy 184.4083 -316.51379) (xy 184.452762 -316.534888) (xy 184.493265 -316.562844)
			(xy 184.528758 -316.596936) (xy 184.558323 -316.63628) (xy 184.581194 -316.679857) (xy 184.596778 -316.726538)
			(xy 184.604673 -316.775115) (xy 184.605168 -316.799722) (xy 184.94427 -316.799722) (xy 184.94823 -316.750668)
			(xy 184.960007 -316.702884) (xy 184.979298 -316.657608) (xy 185.005601 -316.616012) (xy 185.038236 -316.579175)
			(xy 185.076357 -316.54805) (xy 185.118978 -316.523443) (xy 185.164994 -316.505991) (xy 185.213213 -316.496147)
			(xy 185.262388 -316.494166) (xy 185.311243 -316.500098) (xy 185.358514 -316.51379) (xy 185.402976 -316.534888)
			(xy 185.443479 -316.562844) (xy 185.478972 -316.596936) (xy 185.508537 -316.63628) (xy 185.531408 -316.679857)
			(xy 185.546992 -316.726538) (xy 185.554887 -316.775115) (xy 185.555382 -316.799722) (xy 185.89423 -316.799722)
			(xy 185.89819 -316.750668) (xy 185.909967 -316.702884) (xy 185.929258 -316.657608) (xy 185.955561 -316.616012)
			(xy 185.988196 -316.579175) (xy 186.026317 -316.54805) (xy 186.068938 -316.523443) (xy 186.114954 -316.505991)
			(xy 186.163173 -316.496147) (xy 186.212348 -316.494166) (xy 186.261203 -316.500098) (xy 186.308474 -316.51379)
			(xy 186.352936 -316.534888) (xy 186.393439 -316.562844) (xy 186.428932 -316.596936) (xy 186.458497 -316.63628)
			(xy 186.481368 -316.679857) (xy 186.496952 -316.726538) (xy 186.504847 -316.775115) (xy 186.505342 -316.799722)
			(xy 186.84419 -316.799722) (xy 186.84815 -316.750668) (xy 186.859927 -316.702884) (xy 186.879218 -316.657608)
			(xy 186.905521 -316.616012) (xy 186.938156 -316.579175) (xy 186.976277 -316.54805) (xy 187.018898 -316.523443)
			(xy 187.064914 -316.505991) (xy 187.113133 -316.496147) (xy 187.162308 -316.494166) (xy 187.211163 -316.500098)
			(xy 187.258434 -316.51379) (xy 187.302896 -316.534888) (xy 187.343399 -316.562844) (xy 187.378892 -316.596936)
			(xy 187.408457 -316.63628) (xy 187.431328 -316.679857) (xy 187.446912 -316.726538) (xy 187.454807 -316.775115)
			(xy 187.455302 -316.799722) (xy 187.79415 -316.799722) (xy 187.79811 -316.750668) (xy 187.809887 -316.702884)
			(xy 187.829178 -316.657608) (xy 187.855481 -316.616012) (xy 187.888116 -316.579175) (xy 187.926237 -316.54805)
			(xy 187.968858 -316.523443) (xy 188.014874 -316.505991) (xy 188.063093 -316.496147) (xy 188.112268 -316.494166)
			(xy 188.161123 -316.500098) (xy 188.208394 -316.51379) (xy 188.252856 -316.534888) (xy 188.293359 -316.562844)
			(xy 188.328852 -316.596936) (xy 188.358417 -316.63628) (xy 188.381288 -316.679857) (xy 188.396872 -316.726538)
			(xy 188.404767 -316.775115) (xy 188.405262 -316.799722) (xy 188.74411 -316.799722) (xy 188.74807 -316.750668)
			(xy 188.759847 -316.702884) (xy 188.779138 -316.657608) (xy 188.805441 -316.616012) (xy 188.838076 -316.579175)
			(xy 188.876197 -316.54805) (xy 188.918818 -316.523443) (xy 188.964834 -316.505991) (xy 189.013053 -316.496147)
			(xy 189.062228 -316.494166) (xy 189.111083 -316.500098) (xy 189.158354 -316.51379) (xy 189.202816 -316.534888)
			(xy 189.243319 -316.562844) (xy 189.278812 -316.596936) (xy 189.308377 -316.63628) (xy 189.331248 -316.679857)
			(xy 189.346832 -316.726538) (xy 189.354727 -316.775115) (xy 189.355222 -316.799722) (xy 189.354727 -316.824329)
			(xy 189.354548 -316.82543) (xy 189.673226 -316.82543) (xy 189.673226 -316.774014) (xy 189.681269 -316.723232)
			(xy 189.697157 -316.674333) (xy 189.7205 -316.628521) (xy 189.750721 -316.586925) (xy 189.787077 -316.550569)
			(xy 189.828673 -316.520348) (xy 189.874485 -316.497005) (xy 189.923384 -316.481117) (xy 189.974166 -316.473074)
			(xy 190.025582 -316.473074) (xy 190.076364 -316.481117) (xy 190.125263 -316.497005) (xy 190.171075 -316.520348)
			(xy 190.212671 -316.550569) (xy 190.249027 -316.586925) (xy 190.279248 -316.628521) (xy 190.302591 -316.674333)
			(xy 190.318479 -316.723232) (xy 190.326522 -316.774014) (xy 190.327026 -316.799722) (xy 190.644284 -316.799722)
			(xy 190.648244 -316.750668) (xy 190.660021 -316.702884) (xy 190.679312 -316.657608) (xy 190.705615 -316.616012)
			(xy 190.73825 -316.579175) (xy 190.776371 -316.54805) (xy 190.818992 -316.523443) (xy 190.865008 -316.505991)
			(xy 190.913227 -316.496147) (xy 190.962402 -316.494166) (xy 191.011257 -316.500098) (xy 191.058528 -316.51379)
			(xy 191.10299 -316.534888) (xy 191.143493 -316.562844) (xy 191.178986 -316.596936) (xy 191.208551 -316.63628)
			(xy 191.231422 -316.679857) (xy 191.247006 -316.726538) (xy 191.254901 -316.775115) (xy 191.255396 -316.799722)
			(xy 191.254901 -316.824329) (xy 191.254722 -316.82543) (xy 191.5734 -316.82543) (xy 191.5734 -316.774014)
			(xy 191.581443 -316.723232) (xy 191.597331 -316.674333) (xy 191.620674 -316.628521) (xy 191.650895 -316.586925)
			(xy 191.687251 -316.550569) (xy 191.728847 -316.520348) (xy 191.774659 -316.497005) (xy 191.823558 -316.481117)
			(xy 191.87434 -316.473074) (xy 191.925756 -316.473074) (xy 191.976538 -316.481117) (xy 192.025437 -316.497005)
			(xy 192.071249 -316.520348) (xy 192.112845 -316.550569) (xy 192.149201 -316.586925) (xy 192.179422 -316.628521)
			(xy 192.202765 -316.674333) (xy 192.218653 -316.723232) (xy 192.226696 -316.774014) (xy 192.2272 -316.799722)
			(xy 192.544204 -316.799722) (xy 192.548164 -316.750668) (xy 192.559941 -316.702884) (xy 192.579232 -316.657608)
			(xy 192.605535 -316.616012) (xy 192.63817 -316.579175) (xy 192.676291 -316.54805) (xy 192.718912 -316.523443)
			(xy 192.764928 -316.505991) (xy 192.813147 -316.496147) (xy 192.862322 -316.494166) (xy 192.911177 -316.500098)
			(xy 192.958448 -316.51379) (xy 193.00291 -316.534888) (xy 193.043413 -316.562844) (xy 193.078906 -316.596936)
			(xy 193.108471 -316.63628) (xy 193.131342 -316.679857) (xy 193.146926 -316.726538) (xy 193.154821 -316.775115)
			(xy 193.155316 -316.799722) (xy 193.154821 -316.824329) (xy 193.154642 -316.82543) (xy 193.47332 -316.82543)
			(xy 193.47332 -316.774014) (xy 193.481363 -316.723232) (xy 193.497251 -316.674333) (xy 193.520594 -316.628521)
			(xy 193.550815 -316.586925) (xy 193.587171 -316.550569) (xy 193.628767 -316.520348) (xy 193.674579 -316.497005)
			(xy 193.723478 -316.481117) (xy 193.77426 -316.473074) (xy 193.825676 -316.473074) (xy 193.876458 -316.481117)
			(xy 193.925357 -316.497005) (xy 193.971169 -316.520348) (xy 194.012765 -316.550569) (xy 194.049121 -316.586925)
			(xy 194.079342 -316.628521) (xy 194.102685 -316.674333) (xy 194.118573 -316.723232) (xy 194.126616 -316.774014)
			(xy 194.12712 -316.799722) (xy 194.444124 -316.799722) (xy 194.448084 -316.750668) (xy 194.459861 -316.702884)
			(xy 194.479152 -316.657608) (xy 194.505455 -316.616012) (xy 194.53809 -316.579175) (xy 194.576211 -316.54805)
			(xy 194.618832 -316.523443) (xy 194.664848 -316.505991) (xy 194.713067 -316.496147) (xy 194.762242 -316.494166)
			(xy 194.811097 -316.500098) (xy 194.858368 -316.51379) (xy 194.90283 -316.534888) (xy 194.943333 -316.562844)
			(xy 194.978826 -316.596936) (xy 195.008391 -316.63628) (xy 195.031262 -316.679857) (xy 195.046846 -316.726538)
			(xy 195.054741 -316.775115) (xy 195.055236 -316.799722) (xy 195.054741 -316.824329) (xy 195.054562 -316.82543)
			(xy 195.37324 -316.82543) (xy 195.37324 -316.774014) (xy 195.381283 -316.723232) (xy 195.397171 -316.674333)
			(xy 195.420514 -316.628521) (xy 195.450735 -316.586925) (xy 195.487091 -316.550569) (xy 195.528687 -316.520348)
			(xy 195.574499 -316.497005) (xy 195.623398 -316.481117) (xy 195.67418 -316.473074) (xy 195.725596 -316.473074)
			(xy 195.776378 -316.481117) (xy 195.825277 -316.497005) (xy 195.871089 -316.520348) (xy 195.912685 -316.550569)
			(xy 195.949041 -316.586925) (xy 195.979262 -316.628521) (xy 196.002605 -316.674333) (xy 196.018493 -316.723232)
			(xy 196.026536 -316.774014) (xy 196.02704 -316.799722) (xy 196.344044 -316.799722) (xy 196.348004 -316.750668)
			(xy 196.359781 -316.702884) (xy 196.379072 -316.657608) (xy 196.405375 -316.616012) (xy 196.43801 -316.579175)
			(xy 196.476131 -316.54805) (xy 196.518752 -316.523443) (xy 196.564768 -316.505991) (xy 196.612987 -316.496147)
			(xy 196.662162 -316.494166) (xy 196.711017 -316.500098) (xy 196.758288 -316.51379) (xy 196.80275 -316.534888)
			(xy 196.843253 -316.562844) (xy 196.878746 -316.596936) (xy 196.908311 -316.63628) (xy 196.931182 -316.679857)
			(xy 196.946766 -316.726538) (xy 196.954661 -316.775115) (xy 196.955156 -316.799722) (xy 196.954661 -316.824329)
			(xy 196.954482 -316.82543) (xy 197.273414 -316.82543) (xy 197.273414 -316.774014) (xy 197.281457 -316.723232)
			(xy 197.297345 -316.674333) (xy 197.320688 -316.628521) (xy 197.350909 -316.586925) (xy 197.387265 -316.550569)
			(xy 197.428861 -316.520348) (xy 197.474673 -316.497005) (xy 197.523572 -316.481117) (xy 197.574354 -316.473074)
			(xy 197.62577 -316.473074) (xy 197.676552 -316.481117) (xy 197.725451 -316.497005) (xy 197.771263 -316.520348)
			(xy 197.812859 -316.550569) (xy 197.849215 -316.586925) (xy 197.879436 -316.628521) (xy 197.902779 -316.674333)
			(xy 197.918667 -316.723232) (xy 197.92671 -316.774014) (xy 197.927214 -316.799722) (xy 197.92671 -316.82543)
			(xy 198.223374 -316.82543) (xy 198.223374 -316.774014) (xy 198.231417 -316.723232) (xy 198.247305 -316.674333)
			(xy 198.270648 -316.628521) (xy 198.300869 -316.586925) (xy 198.337225 -316.550569) (xy 198.378821 -316.520348)
			(xy 198.424633 -316.497005) (xy 198.473532 -316.481117) (xy 198.524314 -316.473074) (xy 198.57573 -316.473074)
			(xy 198.626512 -316.481117) (xy 198.675411 -316.497005) (xy 198.721223 -316.520348) (xy 198.762819 -316.550569)
			(xy 198.799175 -316.586925) (xy 198.829396 -316.628521) (xy 198.852739 -316.674333) (xy 198.868627 -316.723232)
			(xy 198.87667 -316.774014) (xy 198.877174 -316.799722) (xy 199.194432 -316.799722) (xy 199.198392 -316.750668)
			(xy 199.210169 -316.702884) (xy 199.22946 -316.657608) (xy 199.255763 -316.616012) (xy 199.288398 -316.579175)
			(xy 199.326519 -316.54805) (xy 199.36914 -316.523443) (xy 199.415156 -316.505991) (xy 199.463375 -316.496147)
			(xy 199.51255 -316.494166) (xy 199.561405 -316.500098) (xy 199.608676 -316.51379) (xy 199.653138 -316.534888)
			(xy 199.693641 -316.562844) (xy 199.729134 -316.596936) (xy 199.758699 -316.63628) (xy 199.78157 -316.679857)
			(xy 199.797154 -316.726538) (xy 199.805049 -316.775115) (xy 199.805544 -316.799722) (xy 199.805049 -316.824329)
			(xy 199.797154 -316.872906) (xy 199.78157 -316.919587) (xy 199.758699 -316.963164) (xy 199.729134 -317.002508)
			(xy 199.693641 -317.0366) (xy 199.653138 -317.064556) (xy 199.608676 -317.085654) (xy 199.561405 -317.099346)
			(xy 199.51255 -317.105278) (xy 199.463375 -317.103297) (xy 199.415156 -317.093453) (xy 199.36914 -317.076001)
			(xy 199.326519 -317.051394) (xy 199.288398 -317.020269) (xy 199.255763 -316.983432) (xy 199.22946 -316.941836)
			(xy 199.210169 -316.89656) (xy 199.198392 -316.848776) (xy 199.194432 -316.799722) (xy 198.877174 -316.799722)
			(xy 198.87667 -316.82543) (xy 198.868627 -316.876212) (xy 198.852739 -316.925111) (xy 198.829396 -316.970923)
			(xy 198.799175 -317.012519) (xy 198.762819 -317.048875) (xy 198.721223 -317.079096) (xy 198.675411 -317.102439)
			(xy 198.626512 -317.118327) (xy 198.57573 -317.12637) (xy 198.524314 -317.12637) (xy 198.473532 -317.118327)
			(xy 198.424633 -317.102439) (xy 198.378821 -317.079096) (xy 198.337225 -317.048875) (xy 198.300869 -317.012519)
			(xy 198.270648 -316.970923) (xy 198.247305 -316.925111) (xy 198.231417 -316.876212) (xy 198.223374 -316.82543)
			(xy 197.92671 -316.82543) (xy 197.918667 -316.876212) (xy 197.902779 -316.925111) (xy 197.879436 -316.970923)
			(xy 197.849215 -317.012519) (xy 197.812859 -317.048875) (xy 197.771263 -317.079096) (xy 197.725451 -317.102439)
			(xy 197.676552 -317.118327) (xy 197.62577 -317.12637) (xy 197.574354 -317.12637) (xy 197.523572 -317.118327)
			(xy 197.474673 -317.102439) (xy 197.428861 -317.079096) (xy 197.387265 -317.048875) (xy 197.350909 -317.012519)
			(xy 197.320688 -316.970923) (xy 197.297345 -316.925111) (xy 197.281457 -316.876212) (xy 197.273414 -316.82543)
			(xy 196.954482 -316.82543) (xy 196.946766 -316.872906) (xy 196.931182 -316.919587) (xy 196.908311 -316.963164)
			(xy 196.878746 -317.002508) (xy 196.843253 -317.0366) (xy 196.80275 -317.064556) (xy 196.758288 -317.085654)
			(xy 196.711017 -317.099346) (xy 196.662162 -317.105278) (xy 196.612987 -317.103297) (xy 196.564768 -317.093453)
			(xy 196.518752 -317.076001) (xy 196.476131 -317.051394) (xy 196.43801 -317.020269) (xy 196.405375 -316.983432)
			(xy 196.379072 -316.941836) (xy 196.359781 -316.89656) (xy 196.348004 -316.848776) (xy 196.344044 -316.799722)
			(xy 196.02704 -316.799722) (xy 196.026536 -316.82543) (xy 196.018493 -316.876212) (xy 196.002605 -316.925111)
			(xy 195.979262 -316.970923) (xy 195.949041 -317.012519) (xy 195.912685 -317.048875) (xy 195.871089 -317.079096)
			(xy 195.825277 -317.102439) (xy 195.776378 -317.118327) (xy 195.725596 -317.12637) (xy 195.67418 -317.12637)
			(xy 195.623398 -317.118327) (xy 195.574499 -317.102439) (xy 195.528687 -317.079096) (xy 195.487091 -317.048875)
			(xy 195.450735 -317.012519) (xy 195.420514 -316.970923) (xy 195.397171 -316.925111) (xy 195.381283 -316.876212)
			(xy 195.37324 -316.82543) (xy 195.054562 -316.82543) (xy 195.046846 -316.872906) (xy 195.031262 -316.919587)
			(xy 195.008391 -316.963164) (xy 194.978826 -317.002508) (xy 194.943333 -317.0366) (xy 194.90283 -317.064556)
			(xy 194.858368 -317.085654) (xy 194.811097 -317.099346) (xy 194.762242 -317.105278) (xy 194.713067 -317.103297)
			(xy 194.664848 -317.093453) (xy 194.618832 -317.076001) (xy 194.576211 -317.051394) (xy 194.53809 -317.020269)
			(xy 194.505455 -316.983432) (xy 194.479152 -316.941836) (xy 194.459861 -316.89656) (xy 194.448084 -316.848776)
			(xy 194.444124 -316.799722) (xy 194.12712 -316.799722) (xy 194.126616 -316.82543) (xy 194.118573 -316.876212)
			(xy 194.102685 -316.925111) (xy 194.079342 -316.970923) (xy 194.049121 -317.012519) (xy 194.012765 -317.048875)
			(xy 193.971169 -317.079096) (xy 193.925357 -317.102439) (xy 193.876458 -317.118327) (xy 193.825676 -317.12637)
			(xy 193.77426 -317.12637) (xy 193.723478 -317.118327) (xy 193.674579 -317.102439) (xy 193.628767 -317.079096)
			(xy 193.587171 -317.048875) (xy 193.550815 -317.012519) (xy 193.520594 -316.970923) (xy 193.497251 -316.925111)
			(xy 193.481363 -316.876212) (xy 193.47332 -316.82543) (xy 193.154642 -316.82543) (xy 193.146926 -316.872906)
			(xy 193.131342 -316.919587) (xy 193.108471 -316.963164) (xy 193.078906 -317.002508) (xy 193.043413 -317.0366)
			(xy 193.00291 -317.064556) (xy 192.958448 -317.085654) (xy 192.911177 -317.099346) (xy 192.862322 -317.105278)
			(xy 192.813147 -317.103297) (xy 192.764928 -317.093453) (xy 192.718912 -317.076001) (xy 192.676291 -317.051394)
			(xy 192.63817 -317.020269) (xy 192.605535 -316.983432) (xy 192.579232 -316.941836) (xy 192.559941 -316.89656)
			(xy 192.548164 -316.848776) (xy 192.544204 -316.799722) (xy 192.2272 -316.799722) (xy 192.226696 -316.82543)
			(xy 192.218653 -316.876212) (xy 192.202765 -316.925111) (xy 192.179422 -316.970923) (xy 192.149201 -317.012519)
			(xy 192.112845 -317.048875) (xy 192.071249 -317.079096) (xy 192.025437 -317.102439) (xy 191.976538 -317.118327)
			(xy 191.925756 -317.12637) (xy 191.87434 -317.12637) (xy 191.823558 -317.118327) (xy 191.774659 -317.102439)
			(xy 191.728847 -317.079096) (xy 191.687251 -317.048875) (xy 191.650895 -317.012519) (xy 191.620674 -316.970923)
			(xy 191.597331 -316.925111) (xy 191.581443 -316.876212) (xy 191.5734 -316.82543) (xy 191.254722 -316.82543)
			(xy 191.247006 -316.872906) (xy 191.231422 -316.919587) (xy 191.208551 -316.963164) (xy 191.178986 -317.002508)
			(xy 191.143493 -317.0366) (xy 191.10299 -317.064556) (xy 191.058528 -317.085654) (xy 191.011257 -317.099346)
			(xy 190.962402 -317.105278) (xy 190.913227 -317.103297) (xy 190.865008 -317.093453) (xy 190.818992 -317.076001)
			(xy 190.776371 -317.051394) (xy 190.73825 -317.020269) (xy 190.705615 -316.983432) (xy 190.679312 -316.941836)
			(xy 190.660021 -316.89656) (xy 190.648244 -316.848776) (xy 190.644284 -316.799722) (xy 190.327026 -316.799722)
			(xy 190.326522 -316.82543) (xy 190.318479 -316.876212) (xy 190.302591 -316.925111) (xy 190.279248 -316.970923)
			(xy 190.249027 -317.012519) (xy 190.212671 -317.048875) (xy 190.171075 -317.079096) (xy 190.125263 -317.102439)
			(xy 190.076364 -317.118327) (xy 190.025582 -317.12637) (xy 189.974166 -317.12637) (xy 189.923384 -317.118327)
			(xy 189.874485 -317.102439) (xy 189.828673 -317.079096) (xy 189.787077 -317.048875) (xy 189.750721 -317.012519)
			(xy 189.7205 -316.970923) (xy 189.697157 -316.925111) (xy 189.681269 -316.876212) (xy 189.673226 -316.82543)
			(xy 189.354548 -316.82543) (xy 189.346832 -316.872906) (xy 189.331248 -316.919587) (xy 189.308377 -316.963164)
			(xy 189.278812 -317.002508) (xy 189.243319 -317.0366) (xy 189.202816 -317.064556) (xy 189.158354 -317.085654)
			(xy 189.111083 -317.099346) (xy 189.062228 -317.105278) (xy 189.013053 -317.103297) (xy 188.964834 -317.093453)
			(xy 188.918818 -317.076001) (xy 188.876197 -317.051394) (xy 188.838076 -317.020269) (xy 188.805441 -316.983432)
			(xy 188.779138 -316.941836) (xy 188.759847 -316.89656) (xy 188.74807 -316.848776) (xy 188.74411 -316.799722)
			(xy 188.405262 -316.799722) (xy 188.404767 -316.824329) (xy 188.396872 -316.872906) (xy 188.381288 -316.919587)
			(xy 188.358417 -316.963164) (xy 188.328852 -317.002508) (xy 188.293359 -317.0366) (xy 188.252856 -317.064556)
			(xy 188.208394 -317.085654) (xy 188.161123 -317.099346) (xy 188.112268 -317.105278) (xy 188.063093 -317.103297)
			(xy 188.014874 -317.093453) (xy 187.968858 -317.076001) (xy 187.926237 -317.051394) (xy 187.888116 -317.020269)
			(xy 187.855481 -316.983432) (xy 187.829178 -316.941836) (xy 187.809887 -316.89656) (xy 187.79811 -316.848776)
			(xy 187.79415 -316.799722) (xy 187.455302 -316.799722) (xy 187.454807 -316.824329) (xy 187.446912 -316.872906)
			(xy 187.431328 -316.919587) (xy 187.408457 -316.963164) (xy 187.378892 -317.002508) (xy 187.343399 -317.0366)
			(xy 187.302896 -317.064556) (xy 187.258434 -317.085654) (xy 187.211163 -317.099346) (xy 187.162308 -317.105278)
			(xy 187.113133 -317.103297) (xy 187.064914 -317.093453) (xy 187.018898 -317.076001) (xy 186.976277 -317.051394)
			(xy 186.938156 -317.020269) (xy 186.905521 -316.983432) (xy 186.879218 -316.941836) (xy 186.859927 -316.89656)
			(xy 186.84815 -316.848776) (xy 186.84419 -316.799722) (xy 186.505342 -316.799722) (xy 186.504847 -316.824329)
			(xy 186.496952 -316.872906) (xy 186.481368 -316.919587) (xy 186.458497 -316.963164) (xy 186.428932 -317.002508)
			(xy 186.393439 -317.0366) (xy 186.352936 -317.064556) (xy 186.308474 -317.085654) (xy 186.261203 -317.099346)
			(xy 186.212348 -317.105278) (xy 186.163173 -317.103297) (xy 186.114954 -317.093453) (xy 186.068938 -317.076001)
			(xy 186.026317 -317.051394) (xy 185.988196 -317.020269) (xy 185.955561 -316.983432) (xy 185.929258 -316.941836)
			(xy 185.909967 -316.89656) (xy 185.89819 -316.848776) (xy 185.89423 -316.799722) (xy 185.555382 -316.799722)
			(xy 185.554887 -316.824329) (xy 185.546992 -316.872906) (xy 185.531408 -316.919587) (xy 185.508537 -316.963164)
			(xy 185.478972 -317.002508) (xy 185.443479 -317.0366) (xy 185.402976 -317.064556) (xy 185.358514 -317.085654)
			(xy 185.311243 -317.099346) (xy 185.262388 -317.105278) (xy 185.213213 -317.103297) (xy 185.164994 -317.093453)
			(xy 185.118978 -317.076001) (xy 185.076357 -317.051394) (xy 185.038236 -317.020269) (xy 185.005601 -316.983432)
			(xy 184.979298 -316.941836) (xy 184.960007 -316.89656) (xy 184.94823 -316.848776) (xy 184.94427 -316.799722)
			(xy 184.605168 -316.799722) (xy 184.604673 -316.824329) (xy 184.596778 -316.872906) (xy 184.581194 -316.919587)
			(xy 184.558323 -316.963164) (xy 184.528758 -317.002508) (xy 184.493265 -317.0366) (xy 184.452762 -317.064556)
			(xy 184.4083 -317.085654) (xy 184.361029 -317.099346) (xy 184.312174 -317.105278) (xy 184.262999 -317.103297)
			(xy 184.21478 -317.093453) (xy 184.168764 -317.076001) (xy 184.126143 -317.051394) (xy 184.088022 -317.020269)
			(xy 184.055387 -316.983432) (xy 184.029084 -316.941836) (xy 184.009793 -316.89656) (xy 183.998016 -316.848776)
			(xy 183.994056 -316.799722) (xy 183.655208 -316.799722) (xy 183.654713 -316.824329) (xy 183.646818 -316.872906)
			(xy 183.631234 -316.919587) (xy 183.608363 -316.963164) (xy 183.578798 -317.002508) (xy 183.543305 -317.0366)
			(xy 183.502802 -317.064556) (xy 183.45834 -317.085654) (xy 183.411069 -317.099346) (xy 183.362214 -317.105278)
			(xy 183.313039 -317.103297) (xy 183.26482 -317.093453) (xy 183.218804 -317.076001) (xy 183.176183 -317.051394)
			(xy 183.138062 -317.020269) (xy 183.105427 -316.983432) (xy 183.079124 -316.941836) (xy 183.059833 -316.89656)
			(xy 183.048056 -316.848776) (xy 183.044096 -316.799722) (xy 182.705248 -316.799722) (xy 182.704753 -316.824329)
			(xy 182.696858 -316.872906) (xy 182.681274 -316.919587) (xy 182.658403 -316.963164) (xy 182.628838 -317.002508)
			(xy 182.593345 -317.0366) (xy 182.552842 -317.064556) (xy 182.50838 -317.085654) (xy 182.461109 -317.099346)
			(xy 182.412254 -317.105278) (xy 182.363079 -317.103297) (xy 182.31486 -317.093453) (xy 182.268844 -317.076001)
			(xy 182.226223 -317.051394) (xy 182.188102 -317.020269) (xy 182.155467 -316.983432) (xy 182.129164 -316.941836)
			(xy 182.109873 -316.89656) (xy 182.098096 -316.848776) (xy 182.094136 -316.799722) (xy 181.755288 -316.799722)
			(xy 181.754793 -316.824329) (xy 181.746898 -316.872906) (xy 181.731314 -316.919587) (xy 181.708443 -316.963164)
			(xy 181.678878 -317.002508) (xy 181.643385 -317.0366) (xy 181.602882 -317.064556) (xy 181.55842 -317.085654)
			(xy 181.511149 -317.099346) (xy 181.462294 -317.105278) (xy 181.413119 -317.103297) (xy 181.3649 -317.093453)
			(xy 181.318884 -317.076001) (xy 181.276263 -317.051394) (xy 181.238142 -317.020269) (xy 181.205507 -316.983432)
			(xy 181.179204 -316.941836) (xy 181.159913 -316.89656) (xy 181.148136 -316.848776) (xy 181.144176 -316.799722)
			(xy 180.827172 -316.799722) (xy 180.826668 -316.82543) (xy 180.818625 -316.876212) (xy 180.802737 -316.925111)
			(xy 180.779394 -316.970923) (xy 180.749173 -317.012519) (xy 180.712817 -317.048875) (xy 180.671221 -317.079096)
			(xy 180.625409 -317.102439) (xy 180.57651 -317.118327) (xy 180.525728 -317.12637) (xy 180.474312 -317.12637)
			(xy 180.42353 -317.118327) (xy 180.374631 -317.102439) (xy 180.328819 -317.079096) (xy 180.287223 -317.048875)
			(xy 180.250867 -317.012519) (xy 180.220646 -316.970923) (xy 180.197303 -316.925111) (xy 180.181415 -316.876212)
			(xy 180.173372 -316.82543) (xy 179.854694 -316.82543) (xy 179.846978 -316.872906) (xy 179.831394 -316.919587)
			(xy 179.808523 -316.963164) (xy 179.778958 -317.002508) (xy 179.743465 -317.0366) (xy 179.702962 -317.064556)
			(xy 179.6585 -317.085654) (xy 179.611229 -317.099346) (xy 179.562374 -317.105278) (xy 179.513199 -317.103297)
			(xy 179.46498 -317.093453) (xy 179.418964 -317.076001) (xy 179.376343 -317.051394) (xy 179.338222 -317.020269)
			(xy 179.305587 -316.983432) (xy 179.279284 -316.941836) (xy 179.259993 -316.89656) (xy 179.248216 -316.848776)
			(xy 179.244256 -316.799722) (xy 178.926998 -316.799722) (xy 178.926494 -316.82543) (xy 178.918451 -316.876212)
			(xy 178.902563 -316.925111) (xy 178.87922 -316.970923) (xy 178.848999 -317.012519) (xy 178.812643 -317.048875)
			(xy 178.771047 -317.079096) (xy 178.725235 -317.102439) (xy 178.676336 -317.118327) (xy 178.625554 -317.12637)
			(xy 178.574138 -317.12637) (xy 178.523356 -317.118327) (xy 178.474457 -317.102439) (xy 178.428645 -317.079096)
			(xy 178.387049 -317.048875) (xy 178.350693 -317.012519) (xy 178.320472 -316.970923) (xy 178.297129 -316.925111)
			(xy 178.281241 -316.876212) (xy 178.273198 -316.82543) (xy 177.95452 -316.82543) (xy 177.946804 -316.872906)
			(xy 177.93122 -316.919587) (xy 177.908349 -316.963164) (xy 177.878784 -317.002508) (xy 177.843291 -317.0366)
			(xy 177.802788 -317.064556) (xy 177.758326 -317.085654) (xy 177.711055 -317.099346) (xy 177.6622 -317.105278)
			(xy 177.613025 -317.103297) (xy 177.564806 -317.093453) (xy 177.51879 -317.076001) (xy 177.476169 -317.051394)
			(xy 177.438048 -317.020269) (xy 177.405413 -316.983432) (xy 177.37911 -316.941836) (xy 177.359819 -316.89656)
			(xy 177.348042 -316.848776) (xy 177.344082 -316.799722) (xy 177.027078 -316.799722) (xy 177.026574 -316.82543)
			(xy 177.018531 -316.876212) (xy 177.002643 -316.925111) (xy 176.9793 -316.970923) (xy 176.949079 -317.012519)
			(xy 176.912723 -317.048875) (xy 176.871127 -317.079096) (xy 176.825315 -317.102439) (xy 176.776416 -317.118327)
			(xy 176.725634 -317.12637) (xy 176.674218 -317.12637) (xy 176.623436 -317.118327) (xy 176.574537 -317.102439)
			(xy 176.528725 -317.079096) (xy 176.487129 -317.048875) (xy 176.450773 -317.012519) (xy 176.420552 -316.970923)
			(xy 176.397209 -316.925111) (xy 176.381321 -316.876212) (xy 176.373278 -316.82543) (xy 176.0546 -316.82543)
			(xy 176.046884 -316.872906) (xy 176.0313 -316.919587) (xy 176.008429 -316.963164) (xy 175.978864 -317.002508)
			(xy 175.943371 -317.0366) (xy 175.902868 -317.064556) (xy 175.858406 -317.085654) (xy 175.811135 -317.099346)
			(xy 175.76228 -317.105278) (xy 175.713105 -317.103297) (xy 175.664886 -317.093453) (xy 175.61887 -317.076001)
			(xy 175.576249 -317.051394) (xy 175.538128 -317.020269) (xy 175.505493 -316.983432) (xy 175.47919 -316.941836)
			(xy 175.459899 -316.89656) (xy 175.448122 -316.848776) (xy 175.444162 -316.799722) (xy 175.127158 -316.799722)
			(xy 175.126654 -316.82543) (xy 175.118611 -316.876212) (xy 175.102723 -316.925111) (xy 175.07938 -316.970923)
			(xy 175.049159 -317.012519) (xy 175.012803 -317.048875) (xy 174.971207 -317.079096) (xy 174.925395 -317.102439)
			(xy 174.876496 -317.118327) (xy 174.825714 -317.12637) (xy 174.774298 -317.12637) (xy 174.723516 -317.118327)
			(xy 174.674617 -317.102439) (xy 174.628805 -317.079096) (xy 174.587209 -317.048875) (xy 174.550853 -317.012519)
			(xy 174.520632 -316.970923) (xy 174.497289 -316.925111) (xy 174.481401 -316.876212) (xy 174.473358 -316.82543)
			(xy 174.15468 -316.82543) (xy 174.146964 -316.872906) (xy 174.13138 -316.919587) (xy 174.108509 -316.963164)
			(xy 174.078944 -317.002508) (xy 174.043451 -317.0366) (xy 174.002948 -317.064556) (xy 173.958486 -317.085654)
			(xy 173.911215 -317.099346) (xy 173.86236 -317.105278) (xy 173.813185 -317.103297) (xy 173.764966 -317.093453)
			(xy 173.71895 -317.076001) (xy 173.676329 -317.051394) (xy 173.638208 -317.020269) (xy 173.605573 -316.983432)
			(xy 173.57927 -316.941836) (xy 173.559979 -316.89656) (xy 173.548202 -316.848776) (xy 173.544242 -316.799722)
			(xy 173.227238 -316.799722) (xy 173.226734 -316.82543) (xy 173.218691 -316.876212) (xy 173.202803 -316.925111)
			(xy 173.17946 -316.970923) (xy 173.149239 -317.012519) (xy 173.112883 -317.048875) (xy 173.071287 -317.079096)
			(xy 173.025475 -317.102439) (xy 172.976576 -317.118327) (xy 172.925794 -317.12637) (xy 172.874378 -317.12637)
			(xy 172.823596 -317.118327) (xy 172.774697 -317.102439) (xy 172.728885 -317.079096) (xy 172.687289 -317.048875)
			(xy 172.650933 -317.012519) (xy 172.620712 -316.970923) (xy 172.597369 -316.925111) (xy 172.581481 -316.876212)
			(xy 172.573438 -316.82543) (xy 172.254506 -316.82543) (xy 172.24679 -316.872906) (xy 172.231206 -316.919587)
			(xy 172.208335 -316.963164) (xy 172.17877 -317.002508) (xy 172.143277 -317.0366) (xy 172.102774 -317.064556)
			(xy 172.058312 -317.085654) (xy 172.011041 -317.099346) (xy 171.962186 -317.105278) (xy 171.913011 -317.103297)
			(xy 171.864792 -317.093453) (xy 171.818776 -317.076001) (xy 171.776155 -317.051394) (xy 171.738034 -317.020269)
			(xy 171.705399 -316.983432) (xy 171.679096 -316.941836) (xy 171.659805 -316.89656) (xy 171.648028 -316.848776)
			(xy 171.644068 -316.799722) (xy 171.327064 -316.799722) (xy 171.32656 -316.82543) (xy 171.318517 -316.876212)
			(xy 171.302629 -316.925111) (xy 171.279286 -316.970923) (xy 171.249065 -317.012519) (xy 171.212709 -317.048875)
			(xy 171.171113 -317.079096) (xy 171.125301 -317.102439) (xy 171.076402 -317.118327) (xy 171.02562 -317.12637)
			(xy 170.974204 -317.12637) (xy 170.923422 -317.118327) (xy 170.874523 -317.102439) (xy 170.828711 -317.079096)
			(xy 170.787115 -317.048875) (xy 170.750759 -317.012519) (xy 170.720538 -316.970923) (xy 170.697195 -316.925111)
			(xy 170.681307 -316.876212) (xy 170.673264 -316.82543) (xy 170.354586 -316.82543) (xy 170.34687 -316.872906)
			(xy 170.331286 -316.919587) (xy 170.308415 -316.963164) (xy 170.27885 -317.002508) (xy 170.243357 -317.0366)
			(xy 170.202854 -317.064556) (xy 170.158392 -317.085654) (xy 170.111121 -317.099346) (xy 170.062266 -317.105278)
			(xy 170.013091 -317.103297) (xy 169.964872 -317.093453) (xy 169.918856 -317.076001) (xy 169.876235 -317.051394)
			(xy 169.838114 -317.020269) (xy 169.805479 -316.983432) (xy 169.779176 -316.941836) (xy 169.759885 -316.89656)
			(xy 169.748108 -316.848776) (xy 169.744148 -316.799722) (xy 169.427144 -316.799722) (xy 169.42664 -316.82543)
			(xy 169.418597 -316.876212) (xy 169.402709 -316.925111) (xy 169.379366 -316.970923) (xy 169.349145 -317.012519)
			(xy 169.312789 -317.048875) (xy 169.271193 -317.079096) (xy 169.225381 -317.102439) (xy 169.176482 -317.118327)
			(xy 169.1257 -317.12637) (xy 169.074284 -317.12637) (xy 169.023502 -317.118327) (xy 168.974603 -317.102439)
			(xy 168.928791 -317.079096) (xy 168.887195 -317.048875) (xy 168.850839 -317.012519) (xy 168.820618 -316.970923)
			(xy 168.797275 -316.925111) (xy 168.781387 -316.876212) (xy 168.773344 -316.82543) (xy 168.454666 -316.82543)
			(xy 168.44695 -316.872906) (xy 168.431366 -316.919587) (xy 168.408495 -316.963164) (xy 168.37893 -317.002508)
			(xy 168.343437 -317.0366) (xy 168.302934 -317.064556) (xy 168.258472 -317.085654) (xy 168.211201 -317.099346)
			(xy 168.162346 -317.105278) (xy 168.113171 -317.103297) (xy 168.064952 -317.093453) (xy 168.018936 -317.076001)
			(xy 167.976315 -317.051394) (xy 167.938194 -317.020269) (xy 167.905559 -316.983432) (xy 167.879256 -316.941836)
			(xy 167.859965 -316.89656) (xy 167.848188 -316.848776) (xy 167.844228 -316.799722) (xy 167.527224 -316.799722)
			(xy 167.52672 -316.82543) (xy 167.518677 -316.876212) (xy 167.502789 -316.925111) (xy 167.479446 -316.970923)
			(xy 167.449225 -317.012519) (xy 167.412869 -317.048875) (xy 167.371273 -317.079096) (xy 167.325461 -317.102439)
			(xy 167.276562 -317.118327) (xy 167.22578 -317.12637) (xy 167.174364 -317.12637) (xy 167.123582 -317.118327)
			(xy 167.074683 -317.102439) (xy 167.028871 -317.079096) (xy 166.987275 -317.048875) (xy 166.950919 -317.012519)
			(xy 166.920698 -316.970923) (xy 166.897355 -316.925111) (xy 166.881467 -316.876212) (xy 166.873424 -316.82543)
			(xy 166.554492 -316.82543) (xy 166.546776 -316.872906) (xy 166.531192 -316.919587) (xy 166.508321 -316.963164)
			(xy 166.478756 -317.002508) (xy 166.443263 -317.0366) (xy 166.40276 -317.064556) (xy 166.358298 -317.085654)
			(xy 166.311027 -317.099346) (xy 166.262172 -317.105278) (xy 166.212997 -317.103297) (xy 166.164778 -317.093453)
			(xy 166.118762 -317.076001) (xy 166.076141 -317.051394) (xy 166.03802 -317.020269) (xy 166.005385 -316.983432)
			(xy 165.979082 -316.941836) (xy 165.959791 -316.89656) (xy 165.948014 -316.848776) (xy 165.944054 -316.799722)
			(xy 165.605736 -316.799722) (xy 165.601567 -316.850039) (xy 165.589167 -316.899006) (xy 165.568876 -316.945263)
			(xy 165.541249 -316.98755) (xy 165.507038 -317.024713) (xy 165.467176 -317.055738) (xy 165.422752 -317.079779)
			(xy 165.374977 -317.09618) (xy 165.325154 -317.104494) (xy 165.299898 -317.10503) (xy 165.26764 -317.103252)
			(xy 165.256718 -317.102236) (xy 165.246558 -317.105538) (xy 165.241604 -317.107281) (xy 165.23251 -317.112532)
			(xy 165.228524 -317.115952) (xy 165.172136 -317.166498) (xy 165.167818 -317.170816) (xy 165.16284 -317.177013)
			(xy 165.156623 -317.191632) (xy 165.155626 -317.199518) (xy 165.155626 -317.200026) (xy 165.155372 -317.204344)
			(xy 165.155372 -317.266574) (xy 165.155372 -317.26759) (xy 165.155562 -317.283084) (xy 165.153403 -317.313996)
			(xy 165.151054 -317.329312) (xy 165.149022 -317.34125) (xy 165.152324 -317.352172) (xy 165.154001 -317.357231)
			(xy 165.159126 -317.366575) (xy 165.162484 -317.370714) (xy 165.164262 -317.372746) (xy 165.220396 -317.43142)
			(xy 165.226746 -317.437008) (xy 165.229907 -317.43931) (xy 165.236797 -317.443008) (xy 165.240462 -317.444374)
			(xy 165.25113 -317.448184) (xy 165.263322 -317.446914) (xy 165.27243 -317.445861) (xy 165.29073 -317.444719)
			(xy 165.299898 -317.444628) (xy 165.32389 -317.445074) (xy 165.371284 -317.452581) (xy 165.416919 -317.46741)
			(xy 165.459673 -317.489195) (xy 165.498492 -317.517402) (xy 165.53242 -317.551334) (xy 165.560622 -317.590156)
			(xy 165.582403 -317.632912) (xy 165.597227 -317.678549) (xy 165.604729 -317.725944) (xy 165.605206 -317.749936)
			(xy 165.605166 -317.759037) (xy 165.604147 -317.777209) (xy 165.603174 -317.786258) (xy 165.60165 -317.798196)
			(xy 165.60546 -317.809118) (xy 165.607624 -317.814697) (xy 165.614172 -317.824709) (xy 165.618414 -317.82893)
			(xy 165.677342 -317.885318) (xy 165.68039 -317.888112) (xy 165.684186 -317.891011) (xy 165.692626 -317.89548)
			(xy 165.697154 -317.897002) (xy 165.708584 -317.900558) (xy 165.720522 -317.898526) (xy 165.73401 -317.896395)
			(xy 165.761223 -317.894104) (xy 165.774878 -317.893954) (xy 165.788532 -317.894117) (xy 165.815744 -317.896407)
			(xy 165.829234 -317.898526) (xy 165.841172 -317.900558) (xy 165.852602 -317.897002) (xy 165.857132 -317.895487)
			(xy 165.865568 -317.891009) (xy 165.869366 -317.888112) (xy 165.872414 -317.885318) (xy 165.931342 -317.82893)
			(xy 165.935574 -317.824701) (xy 165.942122 -317.814691) (xy 165.944296 -317.809118) (xy 165.948106 -317.798196)
			(xy 165.946582 -317.786258) (xy 165.945593 -317.777211) (xy 165.944576 -317.759037) (xy 165.94455 -317.749936)
			(xy 165.945033 -317.72511) (xy 165.953061 -317.676112) (xy 165.96891 -317.629059) (xy 165.992163 -317.585189)
			(xy 166.022207 -317.54566) (xy 166.058251 -317.511512) (xy 166.099345 -317.483646) (xy 166.144406 -317.462795)
			(xy 166.192247 -317.44951) (xy 166.241607 -317.444139) (xy 166.291185 -317.446826) (xy 166.339676 -317.457499)
			(xy 166.385801 -317.475876) (xy 166.428345 -317.501474) (xy 166.466187 -317.533617) (xy 166.49833 -317.57146)
			(xy 166.523927 -317.614005) (xy 166.542303 -317.66013) (xy 166.552975 -317.708621) (xy 166.55566 -317.758199)
			(xy 166.550289 -317.807559) (xy 166.537003 -317.8554) (xy 166.516152 -317.90046) (xy 166.488284 -317.941554)
			(xy 166.454136 -317.977597) (xy 166.414606 -318.007641) (xy 166.370736 -318.030893) (xy 166.323682 -318.046741)
			(xy 166.274684 -318.054767) (xy 166.249858 -318.055244) (xy 166.240757 -318.055203) (xy 166.222585 -318.054184)
			(xy 166.213536 -318.053212) (xy 166.201598 -318.051688) (xy 166.190676 -318.055498) (xy 166.185096 -318.05766)
			(xy 166.175078 -318.064203) (xy 166.170864 -318.068452) (xy 166.114476 -318.12738) (xy 166.111682 -318.130428)
			(xy 166.108779 -318.134222) (xy 166.104301 -318.142659) (xy 166.102792 -318.147192) (xy 166.099236 -318.158622)
			(xy 166.101268 -318.17056) (xy 166.103397 -318.184048) (xy 166.105686 -318.211262) (xy 166.10584 -318.224916)
			(xy 166.10584 -318.295274) (xy 166.106295 -318.305934) (xy 166.114976 -318.325405) (xy 166.122604 -318.332866)
			(xy 166.178484 -318.383412) (xy 166.188644 -318.390524) (xy 166.197026 -318.39408) (xy 166.207186 -318.397382)
			(xy 166.218108 -318.396366) (xy 166.249858 -318.394588) (xy 166.275585 -318.395117) (xy 166.326311 -318.403737)
			(xy 166.374873 -318.420742) (xy 166.419896 -318.445649) (xy 166.460106 -318.477753) (xy 166.494363 -318.516144)
			(xy 166.521697 -318.559736) (xy 166.541335 -318.607295) (xy 166.55272 -318.657473) (xy 166.554658 -318.683132)
			(xy 166.555166 -318.693038) (xy 166.55923 -318.701674) (xy 166.561351 -318.705992) (xy 166.566979 -318.713792)
			(xy 166.570406 -318.717168) (xy 166.621206 -318.765174) (xy 166.628473 -318.771522) (xy 166.646365 -318.778707)
			(xy 166.656004 -318.779144)
		)
		(stroke
			(width 0)
			(type solid)
		)
		(fill yes)
		(layer "In11.Cu")
		(net "P1V25_PEX1")
	)
	(gr_poly
		(pts
			(xy 257.655822 -323.491098) (xy 257.664721 -323.490659) (xy 257.681416 -323.484479) (xy 257.695002 -323.472975)
			(xy 257.699764 -323.465444) (xy 257.720592 -323.429376) (xy 257.720592 -323.428868) (xy 257.743452 -323.38899)
			(xy 257.743706 -323.388482) (xy 257.749119 -323.377281) (xy 257.749792 -323.352453) (xy 257.744976 -323.340984)
			(xy 257.695042 -323.256024) (xy 257.601376 -323.082611) (xy 257.514944 -322.905482) (xy 257.435892 -322.724937)
			(xy 257.364356 -322.541286) (xy 257.300456 -322.35484) (xy 257.244302 -322.165916) (xy 257.195989 -321.974837)
			(xy 257.155599 -321.781928) (xy 257.123202 -321.587517) (xy 257.098852 -321.391934) (xy 257.082591 -321.195514)
			(xy 257.074446 -320.99859) (xy 257.073908 -320.900044) (xy 257.074405 -320.802611) (xy 257.082353 -320.607908)
			(xy 257.098236 -320.413691) (xy 257.122028 -320.220283) (xy 257.153689 -320.028007) (xy 257.193167 -319.837182)
			(xy 257.240395 -319.648126) (xy 257.295295 -319.461154) (xy 257.357775 -319.276577) (xy 257.427733 -319.094702)
			(xy 257.50505 -318.915831) (xy 257.589599 -318.740263) (xy 257.681239 -318.56829) (xy 257.779817 -318.400198)
			(xy 257.885169 -318.236267) (xy 257.99712 -318.076769) (xy 258.115484 -317.921971) (xy 258.240063 -317.772129)
			(xy 258.37065 -317.627493) (xy 258.507029 -317.488304) (xy 258.648971 -317.354793) (xy 258.79624 -317.227183)
			(xy 258.948592 -317.105687) (xy 259.105773 -316.990505) (xy 259.267521 -316.881831) (xy 259.433568 -316.779845)
			(xy 259.603636 -316.684716) (xy 259.777442 -316.596603) (xy 259.954698 -316.515653) (xy 260.135108 -316.442)
			(xy 260.318373 -316.375768) (xy 260.504186 -316.317065) (xy 260.692239 -316.265991) (xy 260.882219 -316.222629)
			(xy 261.073809 -316.187052) (xy 261.266692 -316.15932) (xy 261.460544 -316.139478) (xy 261.655045 -316.12756)
			(xy 261.84987 -316.123585) (xy 262.044695 -316.12756) (xy 262.239196 -316.139478) (xy 262.433048 -316.15932)
			(xy 262.625931 -316.187052) (xy 262.817521 -316.222629) (xy 263.007501 -316.265991) (xy 263.195554 -316.317065)
			(xy 263.381367 -316.375768) (xy 263.564632 -316.442) (xy 263.745042 -316.515653) (xy 263.922298 -316.596603)
			(xy 264.096104 -316.684716) (xy 264.266172 -316.779845) (xy 264.298121 -316.799468) (xy 267.793482 -316.799468)
			(xy 267.797442 -316.750414) (xy 267.809219 -316.70263) (xy 267.82851 -316.657354) (xy 267.854813 -316.615758)
			(xy 267.887448 -316.578921) (xy 267.925569 -316.547796) (xy 267.96819 -316.523189) (xy 268.014206 -316.505737)
			(xy 268.062425 -316.495893) (xy 268.1116 -316.493912) (xy 268.160455 -316.499844) (xy 268.207726 -316.513536)
			(xy 268.252188 -316.534634) (xy 268.292691 -316.56259) (xy 268.328184 -316.596682) (xy 268.357749 -316.636026)
			(xy 268.38062 -316.679603) (xy 268.396204 -316.726284) (xy 268.404099 -316.774861) (xy 268.404594 -316.799468)
			(xy 268.404099 -316.824075) (xy 268.403879 -316.82543) (xy 268.723106 -316.82543) (xy 268.723106 -316.774014)
			(xy 268.731149 -316.723232) (xy 268.747037 -316.674333) (xy 268.77038 -316.628521) (xy 268.800601 -316.586925)
			(xy 268.836957 -316.550569) (xy 268.878553 -316.520348) (xy 268.924365 -316.497005) (xy 268.973264 -316.481117)
			(xy 269.024046 -316.473074) (xy 269.075462 -316.473074) (xy 269.126244 -316.481117) (xy 269.175143 -316.497005)
			(xy 269.220955 -316.520348) (xy 269.262551 -316.550569) (xy 269.298907 -316.586925) (xy 269.329128 -316.628521)
			(xy 269.352471 -316.674333) (xy 269.368359 -316.723232) (xy 269.376402 -316.774014) (xy 269.376906 -316.799722)
			(xy 269.376402 -316.82543) (xy 269.673066 -316.82543) (xy 269.673066 -316.774014) (xy 269.681109 -316.723232)
			(xy 269.696997 -316.674333) (xy 269.72034 -316.628521) (xy 269.750561 -316.586925) (xy 269.786917 -316.550569)
			(xy 269.828513 -316.520348) (xy 269.874325 -316.497005) (xy 269.923224 -316.481117) (xy 269.974006 -316.473074)
			(xy 270.025422 -316.473074) (xy 270.076204 -316.481117) (xy 270.125103 -316.497005) (xy 270.170915 -316.520348)
			(xy 270.212511 -316.550569) (xy 270.248867 -316.586925) (xy 270.279088 -316.628521) (xy 270.302431 -316.674333)
			(xy 270.318319 -316.723232) (xy 270.326362 -316.774014) (xy 270.326866 -316.799722) (xy 270.644124 -316.799722)
			(xy 270.648084 -316.750668) (xy 270.659861 -316.702884) (xy 270.679152 -316.657608) (xy 270.705455 -316.616012)
			(xy 270.73809 -316.579175) (xy 270.776211 -316.54805) (xy 270.818832 -316.523443) (xy 270.864848 -316.505991)
			(xy 270.913067 -316.496147) (xy 270.962242 -316.494166) (xy 271.011097 -316.500098) (xy 271.058368 -316.51379)
			(xy 271.10283 -316.534888) (xy 271.143333 -316.562844) (xy 271.178826 -316.596936) (xy 271.208391 -316.63628)
			(xy 271.231262 -316.679857) (xy 271.246846 -316.726538) (xy 271.254741 -316.775115) (xy 271.255236 -316.799722)
			(xy 271.254741 -316.824329) (xy 271.254562 -316.82543) (xy 271.57324 -316.82543) (xy 271.57324 -316.774014)
			(xy 271.581283 -316.723232) (xy 271.597171 -316.674333) (xy 271.620514 -316.628521) (xy 271.650735 -316.586925)
			(xy 271.687091 -316.550569) (xy 271.728687 -316.520348) (xy 271.774499 -316.497005) (xy 271.823398 -316.481117)
			(xy 271.87418 -316.473074) (xy 271.925596 -316.473074) (xy 271.976378 -316.481117) (xy 272.025277 -316.497005)
			(xy 272.071089 -316.520348) (xy 272.112685 -316.550569) (xy 272.149041 -316.586925) (xy 272.179262 -316.628521)
			(xy 272.202605 -316.674333) (xy 272.218493 -316.723232) (xy 272.226536 -316.774014) (xy 272.22704 -316.799722)
			(xy 272.544044 -316.799722) (xy 272.548004 -316.750668) (xy 272.559781 -316.702884) (xy 272.579072 -316.657608)
			(xy 272.605375 -316.616012) (xy 272.63801 -316.579175) (xy 272.676131 -316.54805) (xy 272.718752 -316.523443)
			(xy 272.764768 -316.505991) (xy 272.812987 -316.496147) (xy 272.862162 -316.494166) (xy 272.911017 -316.500098)
			(xy 272.958288 -316.51379) (xy 273.00275 -316.534888) (xy 273.043253 -316.562844) (xy 273.078746 -316.596936)
			(xy 273.108311 -316.63628) (xy 273.131182 -316.679857) (xy 273.146766 -316.726538) (xy 273.154661 -316.775115)
			(xy 273.155156 -316.799722) (xy 273.154661 -316.824329) (xy 273.154482 -316.82543) (xy 273.47316 -316.82543)
			(xy 273.47316 -316.774014) (xy 273.481203 -316.723232) (xy 273.497091 -316.674333) (xy 273.520434 -316.628521)
			(xy 273.550655 -316.586925) (xy 273.587011 -316.550569) (xy 273.628607 -316.520348) (xy 273.674419 -316.497005)
			(xy 273.723318 -316.481117) (xy 273.7741 -316.473074) (xy 273.825516 -316.473074) (xy 273.876298 -316.481117)
			(xy 273.925197 -316.497005) (xy 273.971009 -316.520348) (xy 274.012605 -316.550569) (xy 274.048961 -316.586925)
			(xy 274.079182 -316.628521) (xy 274.102525 -316.674333) (xy 274.118413 -316.723232) (xy 274.126456 -316.774014)
			(xy 274.12696 -316.799722) (xy 274.443964 -316.799722) (xy 274.447924 -316.750668) (xy 274.459701 -316.702884)
			(xy 274.478992 -316.657608) (xy 274.505295 -316.616012) (xy 274.53793 -316.579175) (xy 274.576051 -316.54805)
			(xy 274.618672 -316.523443) (xy 274.664688 -316.505991) (xy 274.712907 -316.496147) (xy 274.762082 -316.494166)
			(xy 274.810937 -316.500098) (xy 274.858208 -316.51379) (xy 274.90267 -316.534888) (xy 274.943173 -316.562844)
			(xy 274.978666 -316.596936) (xy 275.008231 -316.63628) (xy 275.031102 -316.679857) (xy 275.046686 -316.726538)
			(xy 275.054581 -316.775115) (xy 275.055076 -316.799722) (xy 275.054581 -316.824329) (xy 275.054402 -316.82543)
			(xy 275.37308 -316.82543) (xy 275.37308 -316.774014) (xy 275.381123 -316.723232) (xy 275.397011 -316.674333)
			(xy 275.420354 -316.628521) (xy 275.450575 -316.586925) (xy 275.486931 -316.550569) (xy 275.528527 -316.520348)
			(xy 275.574339 -316.497005) (xy 275.623238 -316.481117) (xy 275.67402 -316.473074) (xy 275.725436 -316.473074)
			(xy 275.776218 -316.481117) (xy 275.825117 -316.497005) (xy 275.870929 -316.520348) (xy 275.912525 -316.550569)
			(xy 275.948881 -316.586925) (xy 275.979102 -316.628521) (xy 276.002445 -316.674333) (xy 276.018333 -316.723232)
			(xy 276.026376 -316.774014) (xy 276.02688 -316.799722) (xy 276.343884 -316.799722) (xy 276.347844 -316.750668)
			(xy 276.359621 -316.702884) (xy 276.378912 -316.657608) (xy 276.405215 -316.616012) (xy 276.43785 -316.579175)
			(xy 276.475971 -316.54805) (xy 276.518592 -316.523443) (xy 276.564608 -316.505991) (xy 276.612827 -316.496147)
			(xy 276.662002 -316.494166) (xy 276.710857 -316.500098) (xy 276.758128 -316.51379) (xy 276.80259 -316.534888)
			(xy 276.843093 -316.562844) (xy 276.878586 -316.596936) (xy 276.908151 -316.63628) (xy 276.931022 -316.679857)
			(xy 276.946606 -316.726538) (xy 276.954501 -316.775115) (xy 276.954996 -316.799722) (xy 276.954501 -316.824329)
			(xy 276.954322 -316.82543) (xy 277.273254 -316.82543) (xy 277.273254 -316.774014) (xy 277.281297 -316.723232)
			(xy 277.297185 -316.674333) (xy 277.320528 -316.628521) (xy 277.350749 -316.586925) (xy 277.387105 -316.550569)
			(xy 277.428701 -316.520348) (xy 277.474513 -316.497005) (xy 277.523412 -316.481117) (xy 277.574194 -316.473074)
			(xy 277.62561 -316.473074) (xy 277.676392 -316.481117) (xy 277.725291 -316.497005) (xy 277.771103 -316.520348)
			(xy 277.812699 -316.550569) (xy 277.849055 -316.586925) (xy 277.879276 -316.628521) (xy 277.902619 -316.674333)
			(xy 277.918507 -316.723232) (xy 277.92655 -316.774014) (xy 277.927054 -316.799722) (xy 278.244058 -316.799722)
			(xy 278.248018 -316.750668) (xy 278.259795 -316.702884) (xy 278.279086 -316.657608) (xy 278.305389 -316.616012)
			(xy 278.338024 -316.579175) (xy 278.376145 -316.54805) (xy 278.418766 -316.523443) (xy 278.464782 -316.505991)
			(xy 278.513001 -316.496147) (xy 278.562176 -316.494166) (xy 278.611031 -316.500098) (xy 278.658302 -316.51379)
			(xy 278.702764 -316.534888) (xy 278.743267 -316.562844) (xy 278.77876 -316.596936) (xy 278.808325 -316.63628)
			(xy 278.831196 -316.679857) (xy 278.84678 -316.726538) (xy 278.854675 -316.775115) (xy 278.85517 -316.799722)
			(xy 278.854675 -316.824329) (xy 278.854496 -316.82543) (xy 279.173174 -316.82543) (xy 279.173174 -316.774014)
			(xy 279.181217 -316.723232) (xy 279.197105 -316.674333) (xy 279.220448 -316.628521) (xy 279.250669 -316.586925)
			(xy 279.287025 -316.550569) (xy 279.328621 -316.520348) (xy 279.374433 -316.497005) (xy 279.423332 -316.481117)
			(xy 279.474114 -316.473074) (xy 279.52553 -316.473074) (xy 279.576312 -316.481117) (xy 279.625211 -316.497005)
			(xy 279.671023 -316.520348) (xy 279.712619 -316.550569) (xy 279.748975 -316.586925) (xy 279.779196 -316.628521)
			(xy 279.802539 -316.674333) (xy 279.818427 -316.723232) (xy 279.82647 -316.774014) (xy 279.826974 -316.799722)
			(xy 280.143978 -316.799722) (xy 280.147938 -316.750668) (xy 280.159715 -316.702884) (xy 280.179006 -316.657608)
			(xy 280.205309 -316.616012) (xy 280.237944 -316.579175) (xy 280.276065 -316.54805) (xy 280.318686 -316.523443)
			(xy 280.364702 -316.505991) (xy 280.412921 -316.496147) (xy 280.462096 -316.494166) (xy 280.510951 -316.500098)
			(xy 280.558222 -316.51379) (xy 280.602684 -316.534888) (xy 280.643187 -316.562844) (xy 280.67868 -316.596936)
			(xy 280.708245 -316.63628) (xy 280.731116 -316.679857) (xy 280.7467 -316.726538) (xy 280.754595 -316.775115)
			(xy 280.75509 -316.799722) (xy 280.754595 -316.824329) (xy 280.754416 -316.82543) (xy 281.073094 -316.82543)
			(xy 281.073094 -316.774014) (xy 281.081137 -316.723232) (xy 281.097025 -316.674333) (xy 281.120368 -316.628521)
			(xy 281.150589 -316.586925) (xy 281.186945 -316.550569) (xy 281.228541 -316.520348) (xy 281.274353 -316.497005)
			(xy 281.323252 -316.481117) (xy 281.374034 -316.473074) (xy 281.42545 -316.473074) (xy 281.476232 -316.481117)
			(xy 281.525131 -316.497005) (xy 281.570943 -316.520348) (xy 281.612539 -316.550569) (xy 281.648895 -316.586925)
			(xy 281.679116 -316.628521) (xy 281.702459 -316.674333) (xy 281.718347 -316.723232) (xy 281.72639 -316.774014)
			(xy 281.726894 -316.799722) (xy 282.043898 -316.799722) (xy 282.047858 -316.750668) (xy 282.059635 -316.702884)
			(xy 282.078926 -316.657608) (xy 282.105229 -316.616012) (xy 282.137864 -316.579175) (xy 282.175985 -316.54805)
			(xy 282.218606 -316.523443) (xy 282.264622 -316.505991) (xy 282.312841 -316.496147) (xy 282.362016 -316.494166)
			(xy 282.410871 -316.500098) (xy 282.458142 -316.51379) (xy 282.502604 -316.534888) (xy 282.543107 -316.562844)
			(xy 282.5786 -316.596936) (xy 282.608165 -316.63628) (xy 282.631036 -316.679857) (xy 282.64662 -316.726538)
			(xy 282.654515 -316.775115) (xy 282.65501 -316.799722) (xy 282.654515 -316.824329) (xy 282.654336 -316.82543)
			(xy 282.973268 -316.82543) (xy 282.973268 -316.774014) (xy 282.981311 -316.723232) (xy 282.997199 -316.674333)
			(xy 283.020542 -316.628521) (xy 283.050763 -316.586925) (xy 283.087119 -316.550569) (xy 283.128715 -316.520348)
			(xy 283.174527 -316.497005) (xy 283.223426 -316.481117) (xy 283.274208 -316.473074) (xy 283.325624 -316.473074)
			(xy 283.376406 -316.481117) (xy 283.425305 -316.497005) (xy 283.471117 -316.520348) (xy 283.512713 -316.550569)
			(xy 283.549069 -316.586925) (xy 283.57929 -316.628521) (xy 283.602633 -316.674333) (xy 283.618521 -316.723232)
			(xy 283.626564 -316.774014) (xy 283.627068 -316.799722) (xy 283.944072 -316.799722) (xy 283.948032 -316.750668)
			(xy 283.959809 -316.702884) (xy 283.9791 -316.657608) (xy 284.005403 -316.616012) (xy 284.038038 -316.579175)
			(xy 284.076159 -316.54805) (xy 284.11878 -316.523443) (xy 284.164796 -316.505991) (xy 284.213015 -316.496147)
			(xy 284.26219 -316.494166) (xy 284.311045 -316.500098) (xy 284.358316 -316.51379) (xy 284.402778 -316.534888)
			(xy 284.443281 -316.562844) (xy 284.478774 -316.596936) (xy 284.508339 -316.63628) (xy 284.53121 -316.679857)
			(xy 284.546794 -316.726538) (xy 284.554689 -316.775115) (xy 284.555184 -316.799722) (xy 284.554689 -316.824329)
			(xy 284.55451 -316.82543) (xy 284.873188 -316.82543) (xy 284.873188 -316.774014) (xy 284.881231 -316.723232)
			(xy 284.897119 -316.674333) (xy 284.920462 -316.628521) (xy 284.950683 -316.586925) (xy 284.987039 -316.550569)
			(xy 285.028635 -316.520348) (xy 285.074447 -316.497005) (xy 285.123346 -316.481117) (xy 285.174128 -316.473074)
			(xy 285.225544 -316.473074) (xy 285.276326 -316.481117) (xy 285.325225 -316.497005) (xy 285.371037 -316.520348)
			(xy 285.412633 -316.550569) (xy 285.448989 -316.586925) (xy 285.47921 -316.628521) (xy 285.502553 -316.674333)
			(xy 285.518441 -316.723232) (xy 285.526484 -316.774014) (xy 285.526988 -316.799722) (xy 285.843992 -316.799722)
			(xy 285.847952 -316.750668) (xy 285.859729 -316.702884) (xy 285.87902 -316.657608) (xy 285.905323 -316.616012)
			(xy 285.937958 -316.579175) (xy 285.976079 -316.54805) (xy 286.0187 -316.523443) (xy 286.064716 -316.505991)
			(xy 286.112935 -316.496147) (xy 286.16211 -316.494166) (xy 286.210965 -316.500098) (xy 286.258236 -316.51379)
			(xy 286.302698 -316.534888) (xy 286.343201 -316.562844) (xy 286.378694 -316.596936) (xy 286.408259 -316.63628)
			(xy 286.43113 -316.679857) (xy 286.446714 -316.726538) (xy 286.454609 -316.775115) (xy 286.455104 -316.799722)
			(xy 286.454609 -316.824329) (xy 286.45443 -316.82543) (xy 286.773108 -316.82543) (xy 286.773108 -316.774014)
			(xy 286.781151 -316.723232) (xy 286.797039 -316.674333) (xy 286.820382 -316.628521) (xy 286.850603 -316.586925)
			(xy 286.886959 -316.550569) (xy 286.928555 -316.520348) (xy 286.974367 -316.497005) (xy 287.023266 -316.481117)
			(xy 287.074048 -316.473074) (xy 287.125464 -316.473074) (xy 287.176246 -316.481117) (xy 287.225145 -316.497005)
			(xy 287.270957 -316.520348) (xy 287.312553 -316.550569) (xy 287.348909 -316.586925) (xy 287.37913 -316.628521)
			(xy 287.402473 -316.674333) (xy 287.418361 -316.723232) (xy 287.426404 -316.774014) (xy 287.426908 -316.799722)
			(xy 287.743912 -316.799722) (xy 287.747872 -316.750668) (xy 287.759649 -316.702884) (xy 287.77894 -316.657608)
			(xy 287.805243 -316.616012) (xy 287.837878 -316.579175) (xy 287.875999 -316.54805) (xy 287.91862 -316.523443)
			(xy 287.964636 -316.505991) (xy 288.012855 -316.496147) (xy 288.06203 -316.494166) (xy 288.110885 -316.500098)
			(xy 288.158156 -316.51379) (xy 288.202618 -316.534888) (xy 288.243121 -316.562844) (xy 288.278614 -316.596936)
			(xy 288.308179 -316.63628) (xy 288.33105 -316.679857) (xy 288.346634 -316.726538) (xy 288.354529 -316.775115)
			(xy 288.355024 -316.799722) (xy 288.354529 -316.824329) (xy 288.35435 -316.82543) (xy 288.673282 -316.82543)
			(xy 288.673282 -316.774014) (xy 288.681325 -316.723232) (xy 288.697213 -316.674333) (xy 288.720556 -316.628521)
			(xy 288.750777 -316.586925) (xy 288.787133 -316.550569) (xy 288.828729 -316.520348) (xy 288.874541 -316.497005)
			(xy 288.92344 -316.481117) (xy 288.974222 -316.473074) (xy 289.025638 -316.473074) (xy 289.07642 -316.481117)
			(xy 289.125319 -316.497005) (xy 289.171131 -316.520348) (xy 289.212727 -316.550569) (xy 289.249083 -316.586925)
			(xy 289.279304 -316.628521) (xy 289.302647 -316.674333) (xy 289.318535 -316.723232) (xy 289.326578 -316.774014)
			(xy 289.327082 -316.799722) (xy 289.644086 -316.799722) (xy 289.648046 -316.750668) (xy 289.659823 -316.702884)
			(xy 289.679114 -316.657608) (xy 289.705417 -316.616012) (xy 289.738052 -316.579175) (xy 289.776173 -316.54805)
			(xy 289.818794 -316.523443) (xy 289.86481 -316.505991) (xy 289.913029 -316.496147) (xy 289.962204 -316.494166)
			(xy 290.011059 -316.500098) (xy 290.05833 -316.51379) (xy 290.102792 -316.534888) (xy 290.143295 -316.562844)
			(xy 290.178788 -316.596936) (xy 290.208353 -316.63628) (xy 290.231224 -316.679857) (xy 290.246808 -316.726538)
			(xy 290.254703 -316.775115) (xy 290.255198 -316.799722) (xy 290.254703 -316.824329) (xy 290.254524 -316.82543)
			(xy 290.573202 -316.82543) (xy 290.573202 -316.774014) (xy 290.581245 -316.723232) (xy 290.597133 -316.674333)
			(xy 290.620476 -316.628521) (xy 290.650697 -316.586925) (xy 290.687053 -316.550569) (xy 290.728649 -316.520348)
			(xy 290.774461 -316.497005) (xy 290.82336 -316.481117) (xy 290.874142 -316.473074) (xy 290.925558 -316.473074)
			(xy 290.97634 -316.481117) (xy 291.025239 -316.497005) (xy 291.071051 -316.520348) (xy 291.112647 -316.550569)
			(xy 291.149003 -316.586925) (xy 291.179224 -316.628521) (xy 291.202567 -316.674333) (xy 291.218455 -316.723232)
			(xy 291.226498 -316.774014) (xy 291.227002 -316.799722) (xy 291.544006 -316.799722) (xy 291.547966 -316.750668)
			(xy 291.559743 -316.702884) (xy 291.579034 -316.657608) (xy 291.605337 -316.616012) (xy 291.637972 -316.579175)
			(xy 291.676093 -316.54805) (xy 291.718714 -316.523443) (xy 291.76473 -316.505991) (xy 291.812949 -316.496147)
			(xy 291.862124 -316.494166) (xy 291.910979 -316.500098) (xy 291.95825 -316.51379) (xy 292.002712 -316.534888)
			(xy 292.043215 -316.562844) (xy 292.078708 -316.596936) (xy 292.108273 -316.63628) (xy 292.131144 -316.679857)
			(xy 292.146728 -316.726538) (xy 292.154623 -316.775115) (xy 292.155118 -316.799722) (xy 292.154623 -316.824329)
			(xy 292.154444 -316.82543) (xy 292.473122 -316.82543) (xy 292.473122 -316.774014) (xy 292.481165 -316.723232)
			(xy 292.497053 -316.674333) (xy 292.520396 -316.628521) (xy 292.550617 -316.586925) (xy 292.586973 -316.550569)
			(xy 292.628569 -316.520348) (xy 292.674381 -316.497005) (xy 292.72328 -316.481117) (xy 292.774062 -316.473074)
			(xy 292.825478 -316.473074) (xy 292.87626 -316.481117) (xy 292.925159 -316.497005) (xy 292.970971 -316.520348)
			(xy 293.012567 -316.550569) (xy 293.048923 -316.586925) (xy 293.079144 -316.628521) (xy 293.102487 -316.674333)
			(xy 293.118375 -316.723232) (xy 293.126418 -316.774014) (xy 293.126922 -316.799722) (xy 293.443926 -316.799722)
			(xy 293.447886 -316.750668) (xy 293.459663 -316.702884) (xy 293.478954 -316.657608) (xy 293.505257 -316.616012)
			(xy 293.537892 -316.579175) (xy 293.576013 -316.54805) (xy 293.618634 -316.523443) (xy 293.66465 -316.505991)
			(xy 293.712869 -316.496147) (xy 293.762044 -316.494166) (xy 293.810899 -316.500098) (xy 293.85817 -316.51379)
			(xy 293.902632 -316.534888) (xy 293.943135 -316.562844) (xy 293.978628 -316.596936) (xy 294.008193 -316.63628)
			(xy 294.031064 -316.679857) (xy 294.046648 -316.726538) (xy 294.054543 -316.775115) (xy 294.055038 -316.799722)
			(xy 294.054543 -316.824329) (xy 294.054364 -316.82543) (xy 294.373042 -316.82543) (xy 294.373042 -316.774014)
			(xy 294.381085 -316.723232) (xy 294.396973 -316.674333) (xy 294.420316 -316.628521) (xy 294.450537 -316.586925)
			(xy 294.486893 -316.550569) (xy 294.528489 -316.520348) (xy 294.574301 -316.497005) (xy 294.6232 -316.481117)
			(xy 294.673982 -316.473074) (xy 294.725398 -316.473074) (xy 294.77618 -316.481117) (xy 294.825079 -316.497005)
			(xy 294.870891 -316.520348) (xy 294.912487 -316.550569) (xy 294.948843 -316.586925) (xy 294.979064 -316.628521)
			(xy 295.002407 -316.674333) (xy 295.018295 -316.723232) (xy 295.026338 -316.774014) (xy 295.026842 -316.799722)
			(xy 295.3441 -316.799722) (xy 295.34806 -316.750668) (xy 295.359837 -316.702884) (xy 295.379128 -316.657608)
			(xy 295.405431 -316.616012) (xy 295.438066 -316.579175) (xy 295.476187 -316.54805) (xy 295.518808 -316.523443)
			(xy 295.564824 -316.505991) (xy 295.613043 -316.496147) (xy 295.662218 -316.494166) (xy 295.711073 -316.500098)
			(xy 295.758344 -316.51379) (xy 295.802806 -316.534888) (xy 295.843309 -316.562844) (xy 295.878802 -316.596936)
			(xy 295.908367 -316.63628) (xy 295.931238 -316.679857) (xy 295.946822 -316.726538) (xy 295.954717 -316.775115)
			(xy 295.955212 -316.799722) (xy 295.954717 -316.824329) (xy 295.954538 -316.82543) (xy 296.273216 -316.82543)
			(xy 296.273216 -316.774014) (xy 296.281259 -316.723232) (xy 296.297147 -316.674333) (xy 296.32049 -316.628521)
			(xy 296.350711 -316.586925) (xy 296.387067 -316.550569) (xy 296.428663 -316.520348) (xy 296.474475 -316.497005)
			(xy 296.523374 -316.481117) (xy 296.574156 -316.473074) (xy 296.625572 -316.473074) (xy 296.676354 -316.481117)
			(xy 296.725253 -316.497005) (xy 296.771065 -316.520348) (xy 296.812661 -316.550569) (xy 296.849017 -316.586925)
			(xy 296.879238 -316.628521) (xy 296.902581 -316.674333) (xy 296.918469 -316.723232) (xy 296.926512 -316.774014)
			(xy 296.927016 -316.799722) (xy 297.24402 -316.799722) (xy 297.24798 -316.750668) (xy 297.259757 -316.702884)
			(xy 297.279048 -316.657608) (xy 297.305351 -316.616012) (xy 297.337986 -316.579175) (xy 297.376107 -316.54805)
			(xy 297.418728 -316.523443) (xy 297.464744 -316.505991) (xy 297.512963 -316.496147) (xy 297.562138 -316.494166)
			(xy 297.610993 -316.500098) (xy 297.658264 -316.51379) (xy 297.702726 -316.534888) (xy 297.743229 -316.562844)
			(xy 297.778722 -316.596936) (xy 297.808287 -316.63628) (xy 297.831158 -316.679857) (xy 297.846742 -316.726538)
			(xy 297.854637 -316.775115) (xy 297.855132 -316.799722) (xy 297.854637 -316.824329) (xy 297.854458 -316.82543)
			(xy 298.173136 -316.82543) (xy 298.173136 -316.774014) (xy 298.181179 -316.723232) (xy 298.197067 -316.674333)
			(xy 298.22041 -316.628521) (xy 298.250631 -316.586925) (xy 298.286987 -316.550569) (xy 298.328583 -316.520348)
			(xy 298.374395 -316.497005) (xy 298.423294 -316.481117) (xy 298.474076 -316.473074) (xy 298.525492 -316.473074)
			(xy 298.576274 -316.481117) (xy 298.625173 -316.497005) (xy 298.670985 -316.520348) (xy 298.712581 -316.550569)
			(xy 298.748937 -316.586925) (xy 298.779158 -316.628521) (xy 298.802501 -316.674333) (xy 298.818389 -316.723232)
			(xy 298.826432 -316.774014) (xy 298.826936 -316.799722) (xy 299.14394 -316.799722) (xy 299.1479 -316.750668)
			(xy 299.159677 -316.702884) (xy 299.178968 -316.657608) (xy 299.205271 -316.616012) (xy 299.237906 -316.579175)
			(xy 299.276027 -316.54805) (xy 299.318648 -316.523443) (xy 299.364664 -316.505991) (xy 299.412883 -316.496147)
			(xy 299.462058 -316.494166) (xy 299.510913 -316.500098) (xy 299.558184 -316.51379) (xy 299.602646 -316.534888)
			(xy 299.643149 -316.562844) (xy 299.678642 -316.596936) (xy 299.708207 -316.63628) (xy 299.731078 -316.679857)
			(xy 299.746662 -316.726538) (xy 299.754557 -316.775115) (xy 299.755052 -316.799722) (xy 299.754557 -316.824329)
			(xy 299.754378 -316.82543) (xy 300.073056 -316.82543) (xy 300.073056 -316.774014) (xy 300.081099 -316.723232)
			(xy 300.096987 -316.674333) (xy 300.12033 -316.628521) (xy 300.150551 -316.586925) (xy 300.186907 -316.550569)
			(xy 300.228503 -316.520348) (xy 300.274315 -316.497005) (xy 300.323214 -316.481117) (xy 300.373996 -316.473074)
			(xy 300.425412 -316.473074) (xy 300.476194 -316.481117) (xy 300.525093 -316.497005) (xy 300.570905 -316.520348)
			(xy 300.612501 -316.550569) (xy 300.648857 -316.586925) (xy 300.679078 -316.628521) (xy 300.702421 -316.674333)
			(xy 300.718309 -316.723232) (xy 300.726352 -316.774014) (xy 300.726856 -316.799722) (xy 301.044114 -316.799722)
			(xy 301.048074 -316.750668) (xy 301.059851 -316.702884) (xy 301.079142 -316.657608) (xy 301.105445 -316.616012)
			(xy 301.13808 -316.579175) (xy 301.176201 -316.54805) (xy 301.218822 -316.523443) (xy 301.264838 -316.505991)
			(xy 301.313057 -316.496147) (xy 301.362232 -316.494166) (xy 301.411087 -316.500098) (xy 301.458358 -316.51379)
			(xy 301.50282 -316.534888) (xy 301.543323 -316.562844) (xy 301.578816 -316.596936) (xy 301.608381 -316.63628)
			(xy 301.631252 -316.679857) (xy 301.646836 -316.726538) (xy 301.654731 -316.775115) (xy 301.655226 -316.799722)
			(xy 301.654731 -316.824329) (xy 301.654552 -316.82543) (xy 301.97323 -316.82543) (xy 301.97323 -316.774014)
			(xy 301.981273 -316.723232) (xy 301.997161 -316.674333) (xy 302.020504 -316.628521) (xy 302.050725 -316.586925)
			(xy 302.087081 -316.550569) (xy 302.128677 -316.520348) (xy 302.174489 -316.497005) (xy 302.223388 -316.481117)
			(xy 302.27417 -316.473074) (xy 302.325586 -316.473074) (xy 302.376368 -316.481117) (xy 302.425267 -316.497005)
			(xy 302.471079 -316.520348) (xy 302.512675 -316.550569) (xy 302.549031 -316.586925) (xy 302.579252 -316.628521)
			(xy 302.602595 -316.674333) (xy 302.618483 -316.723232) (xy 302.626526 -316.774014) (xy 302.62703 -316.799722)
			(xy 302.944034 -316.799722) (xy 302.947994 -316.750668) (xy 302.959771 -316.702884) (xy 302.979062 -316.657608)
			(xy 303.005365 -316.616012) (xy 303.038 -316.579175) (xy 303.076121 -316.54805) (xy 303.118742 -316.523443)
			(xy 303.164758 -316.505991) (xy 303.212977 -316.496147) (xy 303.262152 -316.494166) (xy 303.311007 -316.500098)
			(xy 303.358278 -316.51379) (xy 303.40274 -316.534888) (xy 303.443243 -316.562844) (xy 303.478736 -316.596936)
			(xy 303.508301 -316.63628) (xy 303.531172 -316.679857) (xy 303.546756 -316.726538) (xy 303.554651 -316.775115)
			(xy 303.555146 -316.799722) (xy 303.554651 -316.824329) (xy 303.546756 -316.872906) (xy 303.531172 -316.919587)
			(xy 303.508301 -316.963164) (xy 303.478736 -317.002508) (xy 303.443243 -317.0366) (xy 303.40274 -317.064556)
			(xy 303.358278 -317.085654) (xy 303.311007 -317.099346) (xy 303.262152 -317.105278) (xy 303.212977 -317.103297)
			(xy 303.164758 -317.093453) (xy 303.118742 -317.076001) (xy 303.076121 -317.051394) (xy 303.038 -317.020269)
			(xy 303.005365 -316.983432) (xy 302.979062 -316.941836) (xy 302.959771 -316.89656) (xy 302.947994 -316.848776)
			(xy 302.944034 -316.799722) (xy 302.62703 -316.799722) (xy 302.626526 -316.82543) (xy 302.618483 -316.876212)
			(xy 302.602595 -316.925111) (xy 302.579252 -316.970923) (xy 302.549031 -317.012519) (xy 302.512675 -317.048875)
			(xy 302.471079 -317.079096) (xy 302.425267 -317.102439) (xy 302.376368 -317.118327) (xy 302.325586 -317.12637)
			(xy 302.27417 -317.12637) (xy 302.223388 -317.118327) (xy 302.174489 -317.102439) (xy 302.128677 -317.079096)
			(xy 302.087081 -317.048875) (xy 302.050725 -317.012519) (xy 302.020504 -316.970923) (xy 301.997161 -316.925111)
			(xy 301.981273 -316.876212) (xy 301.97323 -316.82543) (xy 301.654552 -316.82543) (xy 301.646836 -316.872906)
			(xy 301.631252 -316.919587) (xy 301.608381 -316.963164) (xy 301.578816 -317.002508) (xy 301.543323 -317.0366)
			(xy 301.50282 -317.064556) (xy 301.458358 -317.085654) (xy 301.411087 -317.099346) (xy 301.362232 -317.105278)
			(xy 301.313057 -317.103297) (xy 301.264838 -317.093453) (xy 301.218822 -317.076001) (xy 301.176201 -317.051394)
			(xy 301.13808 -317.020269) (xy 301.105445 -316.983432) (xy 301.079142 -316.941836) (xy 301.059851 -316.89656)
			(xy 301.048074 -316.848776) (xy 301.044114 -316.799722) (xy 300.726856 -316.799722) (xy 300.726352 -316.82543)
			(xy 300.718309 -316.876212) (xy 300.702421 -316.925111) (xy 300.679078 -316.970923) (xy 300.648857 -317.012519)
			(xy 300.612501 -317.048875) (xy 300.570905 -317.079096) (xy 300.525093 -317.102439) (xy 300.476194 -317.118327)
			(xy 300.425412 -317.12637) (xy 300.373996 -317.12637) (xy 300.323214 -317.118327) (xy 300.274315 -317.102439)
			(xy 300.228503 -317.079096) (xy 300.186907 -317.048875) (xy 300.150551 -317.012519) (xy 300.12033 -316.970923)
			(xy 300.096987 -316.925111) (xy 300.081099 -316.876212) (xy 300.073056 -316.82543) (xy 299.754378 -316.82543)
			(xy 299.746662 -316.872906) (xy 299.731078 -316.919587) (xy 299.708207 -316.963164) (xy 299.678642 -317.002508)
			(xy 299.643149 -317.0366) (xy 299.602646 -317.064556) (xy 299.558184 -317.085654) (xy 299.510913 -317.099346)
			(xy 299.462058 -317.105278) (xy 299.412883 -317.103297) (xy 299.364664 -317.093453) (xy 299.318648 -317.076001)
			(xy 299.276027 -317.051394) (xy 299.237906 -317.020269) (xy 299.205271 -316.983432) (xy 299.178968 -316.941836)
			(xy 299.159677 -316.89656) (xy 299.1479 -316.848776) (xy 299.14394 -316.799722) (xy 298.826936 -316.799722)
			(xy 298.826432 -316.82543) (xy 298.818389 -316.876212) (xy 298.802501 -316.925111) (xy 298.779158 -316.970923)
			(xy 298.748937 -317.012519) (xy 298.712581 -317.048875) (xy 298.670985 -317.079096) (xy 298.625173 -317.102439)
			(xy 298.576274 -317.118327) (xy 298.525492 -317.12637) (xy 298.474076 -317.12637) (xy 298.423294 -317.118327)
			(xy 298.374395 -317.102439) (xy 298.328583 -317.079096) (xy 298.286987 -317.048875) (xy 298.250631 -317.012519)
			(xy 298.22041 -316.970923) (xy 298.197067 -316.925111) (xy 298.181179 -316.876212) (xy 298.173136 -316.82543)
			(xy 297.854458 -316.82543) (xy 297.846742 -316.872906) (xy 297.831158 -316.919587) (xy 297.808287 -316.963164)
			(xy 297.778722 -317.002508) (xy 297.743229 -317.0366) (xy 297.702726 -317.064556) (xy 297.658264 -317.085654)
			(xy 297.610993 -317.099346) (xy 297.562138 -317.105278) (xy 297.512963 -317.103297) (xy 297.464744 -317.093453)
			(xy 297.418728 -317.076001) (xy 297.376107 -317.051394) (xy 297.337986 -317.020269) (xy 297.305351 -316.983432)
			(xy 297.279048 -316.941836) (xy 297.259757 -316.89656) (xy 297.24798 -316.848776) (xy 297.24402 -316.799722)
			(xy 296.927016 -316.799722) (xy 296.926512 -316.82543) (xy 296.918469 -316.876212) (xy 296.902581 -316.925111)
			(xy 296.879238 -316.970923) (xy 296.849017 -317.012519) (xy 296.812661 -317.048875) (xy 296.771065 -317.079096)
			(xy 296.725253 -317.102439) (xy 296.676354 -317.118327) (xy 296.625572 -317.12637) (xy 296.574156 -317.12637)
			(xy 296.523374 -317.118327) (xy 296.474475 -317.102439) (xy 296.428663 -317.079096) (xy 296.387067 -317.048875)
			(xy 296.350711 -317.012519) (xy 296.32049 -316.970923) (xy 296.297147 -316.925111) (xy 296.281259 -316.876212)
			(xy 296.273216 -316.82543) (xy 295.954538 -316.82543) (xy 295.946822 -316.872906) (xy 295.931238 -316.919587)
			(xy 295.908367 -316.963164) (xy 295.878802 -317.002508) (xy 295.843309 -317.0366) (xy 295.802806 -317.064556)
			(xy 295.758344 -317.085654) (xy 295.711073 -317.099346) (xy 295.662218 -317.105278) (xy 295.613043 -317.103297)
			(xy 295.564824 -317.093453) (xy 295.518808 -317.076001) (xy 295.476187 -317.051394) (xy 295.438066 -317.020269)
			(xy 295.405431 -316.983432) (xy 295.379128 -316.941836) (xy 295.359837 -316.89656) (xy 295.34806 -316.848776)
			(xy 295.3441 -316.799722) (xy 295.026842 -316.799722) (xy 295.026338 -316.82543) (xy 295.018295 -316.876212)
			(xy 295.002407 -316.925111) (xy 294.979064 -316.970923) (xy 294.948843 -317.012519) (xy 294.912487 -317.048875)
			(xy 294.870891 -317.079096) (xy 294.825079 -317.102439) (xy 294.77618 -317.118327) (xy 294.725398 -317.12637)
			(xy 294.673982 -317.12637) (xy 294.6232 -317.118327) (xy 294.574301 -317.102439) (xy 294.528489 -317.079096)
			(xy 294.486893 -317.048875) (xy 294.450537 -317.012519) (xy 294.420316 -316.970923) (xy 294.396973 -316.925111)
			(xy 294.381085 -316.876212) (xy 294.373042 -316.82543) (xy 294.054364 -316.82543) (xy 294.046648 -316.872906)
			(xy 294.031064 -316.919587) (xy 294.008193 -316.963164) (xy 293.978628 -317.002508) (xy 293.943135 -317.0366)
			(xy 293.902632 -317.064556) (xy 293.85817 -317.085654) (xy 293.810899 -317.099346) (xy 293.762044 -317.105278)
			(xy 293.712869 -317.103297) (xy 293.66465 -317.093453) (xy 293.618634 -317.076001) (xy 293.576013 -317.051394)
			(xy 293.537892 -317.020269) (xy 293.505257 -316.983432) (xy 293.478954 -316.941836) (xy 293.459663 -316.89656)
			(xy 293.447886 -316.848776) (xy 293.443926 -316.799722) (xy 293.126922 -316.799722) (xy 293.126418 -316.82543)
			(xy 293.118375 -316.876212) (xy 293.102487 -316.925111) (xy 293.079144 -316.970923) (xy 293.048923 -317.012519)
			(xy 293.012567 -317.048875) (xy 292.970971 -317.079096) (xy 292.925159 -317.102439) (xy 292.87626 -317.118327)
			(xy 292.825478 -317.12637) (xy 292.774062 -317.12637) (xy 292.72328 -317.118327) (xy 292.674381 -317.102439)
			(xy 292.628569 -317.079096) (xy 292.586973 -317.048875) (xy 292.550617 -317.012519) (xy 292.520396 -316.970923)
			(xy 292.497053 -316.925111) (xy 292.481165 -316.876212) (xy 292.473122 -316.82543) (xy 292.154444 -316.82543)
			(xy 292.146728 -316.872906) (xy 292.131144 -316.919587) (xy 292.108273 -316.963164) (xy 292.078708 -317.002508)
			(xy 292.043215 -317.0366) (xy 292.002712 -317.064556) (xy 291.95825 -317.085654) (xy 291.910979 -317.099346)
			(xy 291.862124 -317.105278) (xy 291.812949 -317.103297) (xy 291.76473 -317.093453) (xy 291.718714 -317.076001)
			(xy 291.676093 -317.051394) (xy 291.637972 -317.020269) (xy 291.605337 -316.983432) (xy 291.579034 -316.941836)
			(xy 291.559743 -316.89656) (xy 291.547966 -316.848776) (xy 291.544006 -316.799722) (xy 291.227002 -316.799722)
			(xy 291.226498 -316.82543) (xy 291.218455 -316.876212) (xy 291.202567 -316.925111) (xy 291.179224 -316.970923)
			(xy 291.149003 -317.012519) (xy 291.112647 -317.048875) (xy 291.071051 -317.079096) (xy 291.025239 -317.102439)
			(xy 290.97634 -317.118327) (xy 290.925558 -317.12637) (xy 290.874142 -317.12637) (xy 290.82336 -317.118327)
			(xy 290.774461 -317.102439) (xy 290.728649 -317.079096) (xy 290.687053 -317.048875) (xy 290.650697 -317.012519)
			(xy 290.620476 -316.970923) (xy 290.597133 -316.925111) (xy 290.581245 -316.876212) (xy 290.573202 -316.82543)
			(xy 290.254524 -316.82543) (xy 290.246808 -316.872906) (xy 290.231224 -316.919587) (xy 290.208353 -316.963164)
			(xy 290.178788 -317.002508) (xy 290.143295 -317.0366) (xy 290.102792 -317.064556) (xy 290.05833 -317.085654)
			(xy 290.011059 -317.099346) (xy 289.962204 -317.105278) (xy 289.913029 -317.103297) (xy 289.86481 -317.093453)
			(xy 289.818794 -317.076001) (xy 289.776173 -317.051394) (xy 289.738052 -317.020269) (xy 289.705417 -316.983432)
			(xy 289.679114 -316.941836) (xy 289.659823 -316.89656) (xy 289.648046 -316.848776) (xy 289.644086 -316.799722)
			(xy 289.327082 -316.799722) (xy 289.326578 -316.82543) (xy 289.318535 -316.876212) (xy 289.302647 -316.925111)
			(xy 289.279304 -316.970923) (xy 289.249083 -317.012519) (xy 289.212727 -317.048875) (xy 289.171131 -317.079096)
			(xy 289.125319 -317.102439) (xy 289.07642 -317.118327) (xy 289.025638 -317.12637) (xy 288.974222 -317.12637)
			(xy 288.92344 -317.118327) (xy 288.874541 -317.102439) (xy 288.828729 -317.079096) (xy 288.787133 -317.048875)
			(xy 288.750777 -317.012519) (xy 288.720556 -316.970923) (xy 288.697213 -316.925111) (xy 288.681325 -316.876212)
			(xy 288.673282 -316.82543) (xy 288.35435 -316.82543) (xy 288.346634 -316.872906) (xy 288.33105 -316.919587)
			(xy 288.308179 -316.963164) (xy 288.278614 -317.002508) (xy 288.243121 -317.0366) (xy 288.202618 -317.064556)
			(xy 288.158156 -317.085654) (xy 288.110885 -317.099346) (xy 288.06203 -317.105278) (xy 288.012855 -317.103297)
			(xy 287.964636 -317.093453) (xy 287.91862 -317.076001) (xy 287.875999 -317.051394) (xy 287.837878 -317.020269)
			(xy 287.805243 -316.983432) (xy 287.77894 -316.941836) (xy 287.759649 -316.89656) (xy 287.747872 -316.848776)
			(xy 287.743912 -316.799722) (xy 287.426908 -316.799722) (xy 287.426404 -316.82543) (xy 287.418361 -316.876212)
			(xy 287.402473 -316.925111) (xy 287.37913 -316.970923) (xy 287.348909 -317.012519) (xy 287.312553 -317.048875)
			(xy 287.270957 -317.079096) (xy 287.225145 -317.102439) (xy 287.176246 -317.118327) (xy 287.125464 -317.12637)
			(xy 287.074048 -317.12637) (xy 287.023266 -317.118327) (xy 286.974367 -317.102439) (xy 286.928555 -317.079096)
			(xy 286.886959 -317.048875) (xy 286.850603 -317.012519) (xy 286.820382 -316.970923) (xy 286.797039 -316.925111)
			(xy 286.781151 -316.876212) (xy 286.773108 -316.82543) (xy 286.45443 -316.82543) (xy 286.446714 -316.872906)
			(xy 286.43113 -316.919587) (xy 286.408259 -316.963164) (xy 286.378694 -317.002508) (xy 286.343201 -317.0366)
			(xy 286.302698 -317.064556) (xy 286.258236 -317.085654) (xy 286.210965 -317.099346) (xy 286.16211 -317.105278)
			(xy 286.112935 -317.103297) (xy 286.064716 -317.093453) (xy 286.0187 -317.076001) (xy 285.976079 -317.051394)
			(xy 285.937958 -317.020269) (xy 285.905323 -316.983432) (xy 285.87902 -316.941836) (xy 285.859729 -316.89656)
			(xy 285.847952 -316.848776) (xy 285.843992 -316.799722) (xy 285.526988 -316.799722) (xy 285.526484 -316.82543)
			(xy 285.518441 -316.876212) (xy 285.502553 -316.925111) (xy 285.47921 -316.970923) (xy 285.448989 -317.012519)
			(xy 285.412633 -317.048875) (xy 285.371037 -317.079096) (xy 285.325225 -317.102439) (xy 285.276326 -317.118327)
			(xy 285.225544 -317.12637) (xy 285.174128 -317.12637) (xy 285.123346 -317.118327) (xy 285.074447 -317.102439)
			(xy 285.028635 -317.079096) (xy 284.987039 -317.048875) (xy 284.950683 -317.012519) (xy 284.920462 -316.970923)
			(xy 284.897119 -316.925111) (xy 284.881231 -316.876212) (xy 284.873188 -316.82543) (xy 284.55451 -316.82543)
			(xy 284.546794 -316.872906) (xy 284.53121 -316.919587) (xy 284.508339 -316.963164) (xy 284.478774 -317.002508)
			(xy 284.443281 -317.0366) (xy 284.402778 -317.064556) (xy 284.358316 -317.085654) (xy 284.311045 -317.099346)
			(xy 284.26219 -317.105278) (xy 284.213015 -317.103297) (xy 284.164796 -317.093453) (xy 284.11878 -317.076001)
			(xy 284.076159 -317.051394) (xy 284.038038 -317.020269) (xy 284.005403 -316.983432) (xy 283.9791 -316.941836)
			(xy 283.959809 -316.89656) (xy 283.948032 -316.848776) (xy 283.944072 -316.799722) (xy 283.627068 -316.799722)
			(xy 283.626564 -316.82543) (xy 283.618521 -316.876212) (xy 283.602633 -316.925111) (xy 283.57929 -316.970923)
			(xy 283.549069 -317.012519) (xy 283.512713 -317.048875) (xy 283.471117 -317.079096) (xy 283.425305 -317.102439)
			(xy 283.376406 -317.118327) (xy 283.325624 -317.12637) (xy 283.274208 -317.12637) (xy 283.223426 -317.118327)
			(xy 283.174527 -317.102439) (xy 283.128715 -317.079096) (xy 283.087119 -317.048875) (xy 283.050763 -317.012519)
			(xy 283.020542 -316.970923) (xy 282.997199 -316.925111) (xy 282.981311 -316.876212) (xy 282.973268 -316.82543)
			(xy 282.654336 -316.82543) (xy 282.64662 -316.872906) (xy 282.631036 -316.919587) (xy 282.608165 -316.963164)
			(xy 282.5786 -317.002508) (xy 282.543107 -317.0366) (xy 282.502604 -317.064556) (xy 282.458142 -317.085654)
			(xy 282.410871 -317.099346) (xy 282.362016 -317.105278) (xy 282.312841 -317.103297) (xy 282.264622 -317.093453)
			(xy 282.218606 -317.076001) (xy 282.175985 -317.051394) (xy 282.137864 -317.020269) (xy 282.105229 -316.983432)
			(xy 282.078926 -316.941836) (xy 282.059635 -316.89656) (xy 282.047858 -316.848776) (xy 282.043898 -316.799722)
			(xy 281.726894 -316.799722) (xy 281.72639 -316.82543) (xy 281.718347 -316.876212) (xy 281.702459 -316.925111)
			(xy 281.679116 -316.970923) (xy 281.648895 -317.012519) (xy 281.612539 -317.048875) (xy 281.570943 -317.079096)
			(xy 281.525131 -317.102439) (xy 281.476232 -317.118327) (xy 281.42545 -317.12637) (xy 281.374034 -317.12637)
			(xy 281.323252 -317.118327) (xy 281.274353 -317.102439) (xy 281.228541 -317.079096) (xy 281.186945 -317.048875)
			(xy 281.150589 -317.012519) (xy 281.120368 -316.970923) (xy 281.097025 -316.925111) (xy 281.081137 -316.876212)
			(xy 281.073094 -316.82543) (xy 280.754416 -316.82543) (xy 280.7467 -316.872906) (xy 280.731116 -316.919587)
			(xy 280.708245 -316.963164) (xy 280.67868 -317.002508) (xy 280.643187 -317.0366) (xy 280.602684 -317.064556)
			(xy 280.558222 -317.085654) (xy 280.510951 -317.099346) (xy 280.462096 -317.105278) (xy 280.412921 -317.103297)
			(xy 280.364702 -317.093453) (xy 280.318686 -317.076001) (xy 280.276065 -317.051394) (xy 280.237944 -317.020269)
			(xy 280.205309 -316.983432) (xy 280.179006 -316.941836) (xy 280.159715 -316.89656) (xy 280.147938 -316.848776)
			(xy 280.143978 -316.799722) (xy 279.826974 -316.799722) (xy 279.82647 -316.82543) (xy 279.818427 -316.876212)
			(xy 279.802539 -316.925111) (xy 279.779196 -316.970923) (xy 279.748975 -317.012519) (xy 279.712619 -317.048875)
			(xy 279.671023 -317.079096) (xy 279.625211 -317.102439) (xy 279.576312 -317.118327) (xy 279.52553 -317.12637)
			(xy 279.474114 -317.12637) (xy 279.423332 -317.118327) (xy 279.374433 -317.102439) (xy 279.328621 -317.079096)
			(xy 279.287025 -317.048875) (xy 279.250669 -317.012519) (xy 279.220448 -316.970923) (xy 279.197105 -316.925111)
			(xy 279.181217 -316.876212) (xy 279.173174 -316.82543) (xy 278.854496 -316.82543) (xy 278.84678 -316.872906)
			(xy 278.831196 -316.919587) (xy 278.808325 -316.963164) (xy 278.77876 -317.002508) (xy 278.743267 -317.0366)
			(xy 278.702764 -317.064556) (xy 278.658302 -317.085654) (xy 278.611031 -317.099346) (xy 278.562176 -317.105278)
			(xy 278.513001 -317.103297) (xy 278.464782 -317.093453) (xy 278.418766 -317.076001) (xy 278.376145 -317.051394)
			(xy 278.338024 -317.020269) (xy 278.305389 -316.983432) (xy 278.279086 -316.941836) (xy 278.259795 -316.89656)
			(xy 278.248018 -316.848776) (xy 278.244058 -316.799722) (xy 277.927054 -316.799722) (xy 277.92655 -316.82543)
			(xy 277.918507 -316.876212) (xy 277.902619 -316.925111) (xy 277.879276 -316.970923) (xy 277.849055 -317.012519)
			(xy 277.812699 -317.048875) (xy 277.771103 -317.079096) (xy 277.725291 -317.102439) (xy 277.676392 -317.118327)
			(xy 277.62561 -317.12637) (xy 277.574194 -317.12637) (xy 277.523412 -317.118327) (xy 277.474513 -317.102439)
			(xy 277.428701 -317.079096) (xy 277.387105 -317.048875) (xy 277.350749 -317.012519) (xy 277.320528 -316.970923)
			(xy 277.297185 -316.925111) (xy 277.281297 -316.876212) (xy 277.273254 -316.82543) (xy 276.954322 -316.82543)
			(xy 276.946606 -316.872906) (xy 276.931022 -316.919587) (xy 276.908151 -316.963164) (xy 276.878586 -317.002508)
			(xy 276.843093 -317.0366) (xy 276.80259 -317.064556) (xy 276.758128 -317.085654) (xy 276.710857 -317.099346)
			(xy 276.662002 -317.105278) (xy 276.612827 -317.103297) (xy 276.564608 -317.093453) (xy 276.518592 -317.076001)
			(xy 276.475971 -317.051394) (xy 276.43785 -317.020269) (xy 276.405215 -316.983432) (xy 276.378912 -316.941836)
			(xy 276.359621 -316.89656) (xy 276.347844 -316.848776) (xy 276.343884 -316.799722) (xy 276.02688 -316.799722)
			(xy 276.026376 -316.82543) (xy 276.018333 -316.876212) (xy 276.002445 -316.925111) (xy 275.979102 -316.970923)
			(xy 275.948881 -317.012519) (xy 275.912525 -317.048875) (xy 275.870929 -317.079096) (xy 275.825117 -317.102439)
			(xy 275.776218 -317.118327) (xy 275.725436 -317.12637) (xy 275.67402 -317.12637) (xy 275.623238 -317.118327)
			(xy 275.574339 -317.102439) (xy 275.528527 -317.079096) (xy 275.486931 -317.048875) (xy 275.450575 -317.012519)
			(xy 275.420354 -316.970923) (xy 275.397011 -316.925111) (xy 275.381123 -316.876212) (xy 275.37308 -316.82543)
			(xy 275.054402 -316.82543) (xy 275.046686 -316.872906) (xy 275.031102 -316.919587) (xy 275.008231 -316.963164)
			(xy 274.978666 -317.002508) (xy 274.943173 -317.0366) (xy 274.90267 -317.064556) (xy 274.858208 -317.085654)
			(xy 274.810937 -317.099346) (xy 274.762082 -317.105278) (xy 274.712907 -317.103297) (xy 274.664688 -317.093453)
			(xy 274.618672 -317.076001) (xy 274.576051 -317.051394) (xy 274.53793 -317.020269) (xy 274.505295 -316.983432)
			(xy 274.478992 -316.941836) (xy 274.459701 -316.89656) (xy 274.447924 -316.848776) (xy 274.443964 -316.799722)
			(xy 274.12696 -316.799722) (xy 274.126456 -316.82543) (xy 274.118413 -316.876212) (xy 274.102525 -316.925111)
			(xy 274.079182 -316.970923) (xy 274.048961 -317.012519) (xy 274.012605 -317.048875) (xy 273.971009 -317.079096)
			(xy 273.925197 -317.102439) (xy 273.876298 -317.118327) (xy 273.825516 -317.12637) (xy 273.7741 -317.12637)
			(xy 273.723318 -317.118327) (xy 273.674419 -317.102439) (xy 273.628607 -317.079096) (xy 273.587011 -317.048875)
			(xy 273.550655 -317.012519) (xy 273.520434 -316.970923) (xy 273.497091 -316.925111) (xy 273.481203 -316.876212)
			(xy 273.47316 -316.82543) (xy 273.154482 -316.82543) (xy 273.146766 -316.872906) (xy 273.131182 -316.919587)
			(xy 273.108311 -316.963164) (xy 273.078746 -317.002508) (xy 273.043253 -317.0366) (xy 273.00275 -317.064556)
			(xy 272.958288 -317.085654) (xy 272.911017 -317.099346) (xy 272.862162 -317.105278) (xy 272.812987 -317.103297)
			(xy 272.764768 -317.093453) (xy 272.718752 -317.076001) (xy 272.676131 -317.051394) (xy 272.63801 -317.020269)
			(xy 272.605375 -316.983432) (xy 272.579072 -316.941836) (xy 272.559781 -316.89656) (xy 272.548004 -316.848776)
			(xy 272.544044 -316.799722) (xy 272.22704 -316.799722) (xy 272.226536 -316.82543) (xy 272.218493 -316.876212)
			(xy 272.202605 -316.925111) (xy 272.179262 -316.970923) (xy 272.149041 -317.012519) (xy 272.112685 -317.048875)
			(xy 272.071089 -317.079096) (xy 272.025277 -317.102439) (xy 271.976378 -317.118327) (xy 271.925596 -317.12637)
			(xy 271.87418 -317.12637) (xy 271.823398 -317.118327) (xy 271.774499 -317.102439) (xy 271.728687 -317.079096)
			(xy 271.687091 -317.048875) (xy 271.650735 -317.012519) (xy 271.620514 -316.970923) (xy 271.597171 -316.925111)
			(xy 271.581283 -316.876212) (xy 271.57324 -316.82543) (xy 271.254562 -316.82543) (xy 271.246846 -316.872906)
			(xy 271.231262 -316.919587) (xy 271.208391 -316.963164) (xy 271.178826 -317.002508) (xy 271.143333 -317.0366)
			(xy 271.10283 -317.064556) (xy 271.058368 -317.085654) (xy 271.011097 -317.099346) (xy 270.962242 -317.105278)
			(xy 270.913067 -317.103297) (xy 270.864848 -317.093453) (xy 270.818832 -317.076001) (xy 270.776211 -317.051394)
			(xy 270.73809 -317.020269) (xy 270.705455 -316.983432) (xy 270.679152 -316.941836) (xy 270.659861 -316.89656)
			(xy 270.648084 -316.848776) (xy 270.644124 -316.799722) (xy 270.326866 -316.799722) (xy 270.326362 -316.82543)
			(xy 270.318319 -316.876212) (xy 270.302431 -316.925111) (xy 270.279088 -316.970923) (xy 270.248867 -317.012519)
			(xy 270.212511 -317.048875) (xy 270.170915 -317.079096) (xy 270.125103 -317.102439) (xy 270.076204 -317.118327)
			(xy 270.025422 -317.12637) (xy 269.974006 -317.12637) (xy 269.923224 -317.118327) (xy 269.874325 -317.102439)
			(xy 269.828513 -317.079096) (xy 269.786917 -317.048875) (xy 269.750561 -317.012519) (xy 269.72034 -316.970923)
			(xy 269.696997 -316.925111) (xy 269.681109 -316.876212) (xy 269.673066 -316.82543) (xy 269.376402 -316.82543)
			(xy 269.368359 -316.876212) (xy 269.352471 -316.925111) (xy 269.329128 -316.970923) (xy 269.298907 -317.012519)
			(xy 269.262551 -317.048875) (xy 269.220955 -317.079096) (xy 269.175143 -317.102439) (xy 269.126244 -317.118327)
			(xy 269.075462 -317.12637) (xy 269.024046 -317.12637) (xy 268.973264 -317.118327) (xy 268.924365 -317.102439)
			(xy 268.878553 -317.079096) (xy 268.836957 -317.048875) (xy 268.800601 -317.012519) (xy 268.77038 -316.970923)
			(xy 268.747037 -316.925111) (xy 268.731149 -316.876212) (xy 268.723106 -316.82543) (xy 268.403879 -316.82543)
			(xy 268.396204 -316.872652) (xy 268.38062 -316.919333) (xy 268.357749 -316.96291) (xy 268.328184 -317.002254)
			(xy 268.292691 -317.036346) (xy 268.252188 -317.064302) (xy 268.207726 -317.0854) (xy 268.160455 -317.099092)
			(xy 268.1116 -317.105024) (xy 268.062425 -317.103043) (xy 268.014206 -317.093199) (xy 267.96819 -317.075747)
			(xy 267.925569 -317.05114) (xy 267.887448 -317.020015) (xy 267.854813 -316.983178) (xy 267.82851 -316.941582)
			(xy 267.809219 -316.896306) (xy 267.797442 -316.848522) (xy 267.793482 -316.799468) (xy 264.298121 -316.799468)
			(xy 264.432219 -316.881831) (xy 264.593967 -316.990505) (xy 264.751148 -317.105687) (xy 264.9035 -317.227183)
			(xy 265.050769 -317.354793) (xy 265.192711 -317.488304) (xy 265.32909 -317.627493) (xy 265.43964 -317.749936)
			(xy 268.74395 -317.749936) (xy 268.74791 -317.700882) (xy 268.759687 -317.653098) (xy 268.778978 -317.607822)
			(xy 268.805281 -317.566226) (xy 268.837916 -317.529389) (xy 268.876037 -317.498264) (xy 268.918658 -317.473657)
			(xy 268.964674 -317.456205) (xy 269.012893 -317.446361) (xy 269.062068 -317.44438) (xy 269.110923 -317.450312)
			(xy 269.158194 -317.464004) (xy 269.202656 -317.485102) (xy 269.243159 -317.513058) (xy 269.278652 -317.54715)
			(xy 269.308217 -317.586494) (xy 269.331088 -317.630071) (xy 269.346672 -317.676752) (xy 269.354567 -317.725329)
			(xy 269.355062 -317.749936) (xy 269.69391 -317.749936) (xy 269.69787 -317.700882) (xy 269.709647 -317.653098)
			(xy 269.728938 -317.607822) (xy 269.755241 -317.566226) (xy 269.787876 -317.529389) (xy 269.825997 -317.498264)
			(xy 269.868618 -317.473657) (xy 269.914634 -317.456205) (xy 269.962853 -317.446361) (xy 270.012028 -317.44438)
			(xy 270.060883 -317.450312) (xy 270.108154 -317.464004) (xy 270.152616 -317.485102) (xy 270.193119 -317.513058)
			(xy 270.228612 -317.54715) (xy 270.258177 -317.586494) (xy 270.281048 -317.630071) (xy 270.296632 -317.676752)
			(xy 270.304527 -317.725329) (xy 270.305022 -317.749936) (xy 270.304527 -317.774543) (xy 270.304348 -317.775644)
			(xy 270.62328 -317.775644) (xy 270.62328 -317.724228) (xy 270.631323 -317.673446) (xy 270.647211 -317.624547)
			(xy 270.670554 -317.578735) (xy 270.700775 -317.537139) (xy 270.737131 -317.500783) (xy 270.778727 -317.470562)
			(xy 270.824539 -317.447219) (xy 270.873438 -317.431331) (xy 270.92422 -317.423288) (xy 270.975636 -317.423288)
			(xy 271.026418 -317.431331) (xy 271.075317 -317.447219) (xy 271.121129 -317.470562) (xy 271.162725 -317.500783)
			(xy 271.199081 -317.537139) (xy 271.229302 -317.578735) (xy 271.252645 -317.624547) (xy 271.268533 -317.673446)
			(xy 271.276576 -317.724228) (xy 271.27708 -317.749936) (xy 271.594084 -317.749936) (xy 271.598044 -317.700882)
			(xy 271.609821 -317.653098) (xy 271.629112 -317.607822) (xy 271.655415 -317.566226) (xy 271.68805 -317.529389)
			(xy 271.726171 -317.498264) (xy 271.768792 -317.473657) (xy 271.814808 -317.456205) (xy 271.863027 -317.446361)
			(xy 271.912202 -317.44438) (xy 271.961057 -317.450312) (xy 272.008328 -317.464004) (xy 272.05279 -317.485102)
			(xy 272.093293 -317.513058) (xy 272.128786 -317.54715) (xy 272.158351 -317.586494) (xy 272.181222 -317.630071)
			(xy 272.196806 -317.676752) (xy 272.204701 -317.725329) (xy 272.205196 -317.749936) (xy 272.204701 -317.774543)
			(xy 272.204522 -317.775644) (xy 272.5232 -317.775644) (xy 272.5232 -317.724228) (xy 272.531243 -317.673446)
			(xy 272.547131 -317.624547) (xy 272.570474 -317.578735) (xy 272.600695 -317.537139) (xy 272.637051 -317.500783)
			(xy 272.678647 -317.470562) (xy 272.724459 -317.447219) (xy 272.773358 -317.431331) (xy 272.82414 -317.423288)
			(xy 272.875556 -317.423288) (xy 272.926338 -317.431331) (xy 272.975237 -317.447219) (xy 273.021049 -317.470562)
			(xy 273.062645 -317.500783) (xy 273.099001 -317.537139) (xy 273.129222 -317.578735) (xy 273.152565 -317.624547)
			(xy 273.168453 -317.673446) (xy 273.176496 -317.724228) (xy 273.177 -317.749936) (xy 273.494004 -317.749936)
			(xy 273.497964 -317.700882) (xy 273.509741 -317.653098) (xy 273.529032 -317.607822) (xy 273.555335 -317.566226)
			(xy 273.58797 -317.529389) (xy 273.626091 -317.498264) (xy 273.668712 -317.473657) (xy 273.714728 -317.456205)
			(xy 273.762947 -317.446361) (xy 273.812122 -317.44438) (xy 273.860977 -317.450312) (xy 273.908248 -317.464004)
			(xy 273.95271 -317.485102) (xy 273.993213 -317.513058) (xy 274.028706 -317.54715) (xy 274.058271 -317.586494)
			(xy 274.081142 -317.630071) (xy 274.096726 -317.676752) (xy 274.104621 -317.725329) (xy 274.105116 -317.749936)
			(xy 274.104621 -317.774543) (xy 274.104442 -317.775644) (xy 274.42312 -317.775644) (xy 274.42312 -317.724228)
			(xy 274.431163 -317.673446) (xy 274.447051 -317.624547) (xy 274.470394 -317.578735) (xy 274.500615 -317.537139)
			(xy 274.536971 -317.500783) (xy 274.578567 -317.470562) (xy 274.624379 -317.447219) (xy 274.673278 -317.431331)
			(xy 274.72406 -317.423288) (xy 274.775476 -317.423288) (xy 274.826258 -317.431331) (xy 274.875157 -317.447219)
			(xy 274.920969 -317.470562) (xy 274.962565 -317.500783) (xy 274.998921 -317.537139) (xy 275.029142 -317.578735)
			(xy 275.052485 -317.624547) (xy 275.068373 -317.673446) (xy 275.076416 -317.724228) (xy 275.07692 -317.749936)
			(xy 275.393924 -317.749936) (xy 275.397884 -317.700882) (xy 275.409661 -317.653098) (xy 275.428952 -317.607822)
			(xy 275.455255 -317.566226) (xy 275.48789 -317.529389) (xy 275.526011 -317.498264) (xy 275.568632 -317.473657)
			(xy 275.614648 -317.456205) (xy 275.662867 -317.446361) (xy 275.712042 -317.44438) (xy 275.760897 -317.450312)
			(xy 275.808168 -317.464004) (xy 275.85263 -317.485102) (xy 275.893133 -317.513058) (xy 275.928626 -317.54715)
			(xy 275.958191 -317.586494) (xy 275.981062 -317.630071) (xy 275.996646 -317.676752) (xy 276.004541 -317.725329)
			(xy 276.005036 -317.749936) (xy 276.004541 -317.774543) (xy 276.004362 -317.775644) (xy 276.32304 -317.775644)
			(xy 276.32304 -317.724228) (xy 276.331083 -317.673446) (xy 276.346971 -317.624547) (xy 276.370314 -317.578735)
			(xy 276.400535 -317.537139) (xy 276.436891 -317.500783) (xy 276.478487 -317.470562) (xy 276.524299 -317.447219)
			(xy 276.573198 -317.431331) (xy 276.62398 -317.423288) (xy 276.675396 -317.423288) (xy 276.726178 -317.431331)
			(xy 276.775077 -317.447219) (xy 276.820889 -317.470562) (xy 276.862485 -317.500783) (xy 276.898841 -317.537139)
			(xy 276.929062 -317.578735) (xy 276.952405 -317.624547) (xy 276.968293 -317.673446) (xy 276.976336 -317.724228)
			(xy 276.97684 -317.749936) (xy 277.294098 -317.749936) (xy 277.298058 -317.700882) (xy 277.309835 -317.653098)
			(xy 277.329126 -317.607822) (xy 277.355429 -317.566226) (xy 277.388064 -317.529389) (xy 277.426185 -317.498264)
			(xy 277.468806 -317.473657) (xy 277.514822 -317.456205) (xy 277.563041 -317.446361) (xy 277.612216 -317.44438)
			(xy 277.661071 -317.450312) (xy 277.708342 -317.464004) (xy 277.752804 -317.485102) (xy 277.793307 -317.513058)
			(xy 277.8288 -317.54715) (xy 277.858365 -317.586494) (xy 277.881236 -317.630071) (xy 277.89682 -317.676752)
			(xy 277.904715 -317.725329) (xy 277.90521 -317.749936) (xy 277.904715 -317.774543) (xy 277.904536 -317.775644)
			(xy 278.223214 -317.775644) (xy 278.223214 -317.724228) (xy 278.231257 -317.673446) (xy 278.247145 -317.624547)
			(xy 278.270488 -317.578735) (xy 278.300709 -317.537139) (xy 278.337065 -317.500783) (xy 278.378661 -317.470562)
			(xy 278.424473 -317.447219) (xy 278.473372 -317.431331) (xy 278.524154 -317.423288) (xy 278.57557 -317.423288)
			(xy 278.626352 -317.431331) (xy 278.675251 -317.447219) (xy 278.721063 -317.470562) (xy 278.762659 -317.500783)
			(xy 278.799015 -317.537139) (xy 278.829236 -317.578735) (xy 278.852579 -317.624547) (xy 278.868467 -317.673446)
			(xy 278.87651 -317.724228) (xy 278.877014 -317.749936) (xy 279.194018 -317.749936) (xy 279.197978 -317.700882)
			(xy 279.209755 -317.653098) (xy 279.229046 -317.607822) (xy 279.255349 -317.566226) (xy 279.287984 -317.529389)
			(xy 279.326105 -317.498264) (xy 279.368726 -317.473657) (xy 279.414742 -317.456205) (xy 279.462961 -317.446361)
			(xy 279.512136 -317.44438) (xy 279.560991 -317.450312) (xy 279.608262 -317.464004) (xy 279.652724 -317.485102)
			(xy 279.693227 -317.513058) (xy 279.72872 -317.54715) (xy 279.758285 -317.586494) (xy 279.781156 -317.630071)
			(xy 279.79674 -317.676752) (xy 279.804635 -317.725329) (xy 279.80513 -317.749936) (xy 279.804635 -317.774543)
			(xy 279.804456 -317.775644) (xy 280.123134 -317.775644) (xy 280.123134 -317.724228) (xy 280.131177 -317.673446)
			(xy 280.147065 -317.624547) (xy 280.170408 -317.578735) (xy 280.200629 -317.537139) (xy 280.236985 -317.500783)
			(xy 280.278581 -317.470562) (xy 280.324393 -317.447219) (xy 280.373292 -317.431331) (xy 280.424074 -317.423288)
			(xy 280.47549 -317.423288) (xy 280.526272 -317.431331) (xy 280.575171 -317.447219) (xy 280.620983 -317.470562)
			(xy 280.662579 -317.500783) (xy 280.698935 -317.537139) (xy 280.729156 -317.578735) (xy 280.752499 -317.624547)
			(xy 280.768387 -317.673446) (xy 280.77643 -317.724228) (xy 280.776934 -317.749936) (xy 281.093938 -317.749936)
			(xy 281.097898 -317.700882) (xy 281.109675 -317.653098) (xy 281.128966 -317.607822) (xy 281.155269 -317.566226)
			(xy 281.187904 -317.529389) (xy 281.226025 -317.498264) (xy 281.268646 -317.473657) (xy 281.314662 -317.456205)
			(xy 281.362881 -317.446361) (xy 281.412056 -317.44438) (xy 281.460911 -317.450312) (xy 281.508182 -317.464004)
			(xy 281.552644 -317.485102) (xy 281.593147 -317.513058) (xy 281.62864 -317.54715) (xy 281.658205 -317.586494)
			(xy 281.681076 -317.630071) (xy 281.69666 -317.676752) (xy 281.704555 -317.725329) (xy 281.70505 -317.749936)
			(xy 281.704555 -317.774543) (xy 281.704376 -317.775644) (xy 282.023054 -317.775644) (xy 282.023054 -317.724228)
			(xy 282.031097 -317.673446) (xy 282.046985 -317.624547) (xy 282.070328 -317.578735) (xy 282.100549 -317.537139)
			(xy 282.136905 -317.500783) (xy 282.178501 -317.470562) (xy 282.224313 -317.447219) (xy 282.273212 -317.431331)
			(xy 282.323994 -317.423288) (xy 282.37541 -317.423288) (xy 282.426192 -317.431331) (xy 282.475091 -317.447219)
			(xy 282.520903 -317.470562) (xy 282.562499 -317.500783) (xy 282.598855 -317.537139) (xy 282.629076 -317.578735)
			(xy 282.652419 -317.624547) (xy 282.668307 -317.673446) (xy 282.67635 -317.724228) (xy 282.676854 -317.749936)
			(xy 282.994112 -317.749936) (xy 282.998072 -317.700882) (xy 283.009849 -317.653098) (xy 283.02914 -317.607822)
			(xy 283.055443 -317.566226) (xy 283.088078 -317.529389) (xy 283.126199 -317.498264) (xy 283.16882 -317.473657)
			(xy 283.214836 -317.456205) (xy 283.263055 -317.446361) (xy 283.31223 -317.44438) (xy 283.361085 -317.450312)
			(xy 283.408356 -317.464004) (xy 283.452818 -317.485102) (xy 283.493321 -317.513058) (xy 283.528814 -317.54715)
			(xy 283.558379 -317.586494) (xy 283.58125 -317.630071) (xy 283.596834 -317.676752) (xy 283.604729 -317.725329)
			(xy 283.605224 -317.749936) (xy 283.604729 -317.774543) (xy 283.60455 -317.775644) (xy 283.923228 -317.775644)
			(xy 283.923228 -317.724228) (xy 283.931271 -317.673446) (xy 283.947159 -317.624547) (xy 283.970502 -317.578735)
			(xy 284.000723 -317.537139) (xy 284.037079 -317.500783) (xy 284.078675 -317.470562) (xy 284.124487 -317.447219)
			(xy 284.173386 -317.431331) (xy 284.224168 -317.423288) (xy 284.275584 -317.423288) (xy 284.326366 -317.431331)
			(xy 284.375265 -317.447219) (xy 284.421077 -317.470562) (xy 284.462673 -317.500783) (xy 284.499029 -317.537139)
			(xy 284.52925 -317.578735) (xy 284.552593 -317.624547) (xy 284.568481 -317.673446) (xy 284.576524 -317.724228)
			(xy 284.577028 -317.749936) (xy 284.894032 -317.749936) (xy 284.897992 -317.700882) (xy 284.909769 -317.653098)
			(xy 284.92906 -317.607822) (xy 284.955363 -317.566226) (xy 284.987998 -317.529389) (xy 285.026119 -317.498264)
			(xy 285.06874 -317.473657) (xy 285.114756 -317.456205) (xy 285.162975 -317.446361) (xy 285.21215 -317.44438)
			(xy 285.261005 -317.450312) (xy 285.308276 -317.464004) (xy 285.352738 -317.485102) (xy 285.393241 -317.513058)
			(xy 285.428734 -317.54715) (xy 285.458299 -317.586494) (xy 285.48117 -317.630071) (xy 285.496754 -317.676752)
			(xy 285.504649 -317.725329) (xy 285.505144 -317.749936) (xy 285.504649 -317.774543) (xy 285.50447 -317.775644)
			(xy 285.823148 -317.775644) (xy 285.823148 -317.724228) (xy 285.831191 -317.673446) (xy 285.847079 -317.624547)
			(xy 285.870422 -317.578735) (xy 285.900643 -317.537139) (xy 285.936999 -317.500783) (xy 285.978595 -317.470562)
			(xy 286.024407 -317.447219) (xy 286.073306 -317.431331) (xy 286.124088 -317.423288) (xy 286.175504 -317.423288)
			(xy 286.226286 -317.431331) (xy 286.275185 -317.447219) (xy 286.320997 -317.470562) (xy 286.362593 -317.500783)
			(xy 286.398949 -317.537139) (xy 286.42917 -317.578735) (xy 286.452513 -317.624547) (xy 286.468401 -317.673446)
			(xy 286.476444 -317.724228) (xy 286.476948 -317.749936) (xy 286.793952 -317.749936) (xy 286.797912 -317.700882)
			(xy 286.809689 -317.653098) (xy 286.82898 -317.607822) (xy 286.855283 -317.566226) (xy 286.887918 -317.529389)
			(xy 286.926039 -317.498264) (xy 286.96866 -317.473657) (xy 287.014676 -317.456205) (xy 287.062895 -317.446361)
			(xy 287.11207 -317.44438) (xy 287.160925 -317.450312) (xy 287.208196 -317.464004) (xy 287.252658 -317.485102)
			(xy 287.293161 -317.513058) (xy 287.328654 -317.54715) (xy 287.358219 -317.586494) (xy 287.38109 -317.630071)
			(xy 287.396674 -317.676752) (xy 287.404569 -317.725329) (xy 287.405064 -317.749936) (xy 287.404569 -317.774543)
			(xy 287.40439 -317.775644) (xy 287.723068 -317.775644) (xy 287.723068 -317.724228) (xy 287.731111 -317.673446)
			(xy 287.746999 -317.624547) (xy 287.770342 -317.578735) (xy 287.800563 -317.537139) (xy 287.836919 -317.500783)
			(xy 287.878515 -317.470562) (xy 287.924327 -317.447219) (xy 287.973226 -317.431331) (xy 288.024008 -317.423288)
			(xy 288.075424 -317.423288) (xy 288.126206 -317.431331) (xy 288.175105 -317.447219) (xy 288.220917 -317.470562)
			(xy 288.262513 -317.500783) (xy 288.298869 -317.537139) (xy 288.32909 -317.578735) (xy 288.352433 -317.624547)
			(xy 288.368321 -317.673446) (xy 288.376364 -317.724228) (xy 288.376868 -317.749936) (xy 288.694126 -317.749936)
			(xy 288.698086 -317.700882) (xy 288.709863 -317.653098) (xy 288.729154 -317.607822) (xy 288.755457 -317.566226)
			(xy 288.788092 -317.529389) (xy 288.826213 -317.498264) (xy 288.868834 -317.473657) (xy 288.91485 -317.456205)
			(xy 288.963069 -317.446361) (xy 289.012244 -317.44438) (xy 289.061099 -317.450312) (xy 289.10837 -317.464004)
			(xy 289.152832 -317.485102) (xy 289.193335 -317.513058) (xy 289.228828 -317.54715) (xy 289.258393 -317.586494)
			(xy 289.281264 -317.630071) (xy 289.296848 -317.676752) (xy 289.304743 -317.725329) (xy 289.305238 -317.749936)
			(xy 289.304743 -317.774543) (xy 289.304564 -317.775644) (xy 289.623242 -317.775644) (xy 289.623242 -317.724228)
			(xy 289.631285 -317.673446) (xy 289.647173 -317.624547) (xy 289.670516 -317.578735) (xy 289.700737 -317.537139)
			(xy 289.737093 -317.500783) (xy 289.778689 -317.470562) (xy 289.824501 -317.447219) (xy 289.8734 -317.431331)
			(xy 289.924182 -317.423288) (xy 289.975598 -317.423288) (xy 290.02638 -317.431331) (xy 290.075279 -317.447219)
			(xy 290.121091 -317.470562) (xy 290.162687 -317.500783) (xy 290.199043 -317.537139) (xy 290.229264 -317.578735)
			(xy 290.252607 -317.624547) (xy 290.268495 -317.673446) (xy 290.276538 -317.724228) (xy 290.277042 -317.749936)
			(xy 290.594046 -317.749936) (xy 290.598006 -317.700882) (xy 290.609783 -317.653098) (xy 290.629074 -317.607822)
			(xy 290.655377 -317.566226) (xy 290.688012 -317.529389) (xy 290.726133 -317.498264) (xy 290.768754 -317.473657)
			(xy 290.81477 -317.456205) (xy 290.862989 -317.446361) (xy 290.912164 -317.44438) (xy 290.961019 -317.450312)
			(xy 291.00829 -317.464004) (xy 291.052752 -317.485102) (xy 291.093255 -317.513058) (xy 291.128748 -317.54715)
			(xy 291.158313 -317.586494) (xy 291.181184 -317.630071) (xy 291.196768 -317.676752) (xy 291.204663 -317.725329)
			(xy 291.205158 -317.749936) (xy 291.204663 -317.774543) (xy 291.204484 -317.775644) (xy 291.523162 -317.775644)
			(xy 291.523162 -317.724228) (xy 291.531205 -317.673446) (xy 291.547093 -317.624547) (xy 291.570436 -317.578735)
			(xy 291.600657 -317.537139) (xy 291.637013 -317.500783) (xy 291.678609 -317.470562) (xy 291.724421 -317.447219)
			(xy 291.77332 -317.431331) (xy 291.824102 -317.423288) (xy 291.875518 -317.423288) (xy 291.9263 -317.431331)
			(xy 291.975199 -317.447219) (xy 292.021011 -317.470562) (xy 292.062607 -317.500783) (xy 292.098963 -317.537139)
			(xy 292.129184 -317.578735) (xy 292.152527 -317.624547) (xy 292.168415 -317.673446) (xy 292.176458 -317.724228)
			(xy 292.176962 -317.749936) (xy 292.493966 -317.749936) (xy 292.497926 -317.700882) (xy 292.509703 -317.653098)
			(xy 292.528994 -317.607822) (xy 292.555297 -317.566226) (xy 292.587932 -317.529389) (xy 292.626053 -317.498264)
			(xy 292.668674 -317.473657) (xy 292.71469 -317.456205) (xy 292.762909 -317.446361) (xy 292.812084 -317.44438)
			(xy 292.860939 -317.450312) (xy 292.90821 -317.464004) (xy 292.952672 -317.485102) (xy 292.993175 -317.513058)
			(xy 293.028668 -317.54715) (xy 293.058233 -317.586494) (xy 293.081104 -317.630071) (xy 293.096688 -317.676752)
			(xy 293.104583 -317.725329) (xy 293.105078 -317.749936) (xy 293.104583 -317.774543) (xy 293.104404 -317.775644)
			(xy 293.423082 -317.775644) (xy 293.423082 -317.724228) (xy 293.431125 -317.673446) (xy 293.447013 -317.624547)
			(xy 293.470356 -317.578735) (xy 293.500577 -317.537139) (xy 293.536933 -317.500783) (xy 293.578529 -317.470562)
			(xy 293.624341 -317.447219) (xy 293.67324 -317.431331) (xy 293.724022 -317.423288) (xy 293.775438 -317.423288)
			(xy 293.82622 -317.431331) (xy 293.875119 -317.447219) (xy 293.920931 -317.470562) (xy 293.962527 -317.500783)
			(xy 293.998883 -317.537139) (xy 294.029104 -317.578735) (xy 294.052447 -317.624547) (xy 294.068335 -317.673446)
			(xy 294.076378 -317.724228) (xy 294.076882 -317.749936) (xy 294.393886 -317.749936) (xy 294.397846 -317.700882)
			(xy 294.409623 -317.653098) (xy 294.428914 -317.607822) (xy 294.455217 -317.566226) (xy 294.487852 -317.529389)
			(xy 294.525973 -317.498264) (xy 294.568594 -317.473657) (xy 294.61461 -317.456205) (xy 294.662829 -317.446361)
			(xy 294.712004 -317.44438) (xy 294.760859 -317.450312) (xy 294.80813 -317.464004) (xy 294.852592 -317.485102)
			(xy 294.893095 -317.513058) (xy 294.928588 -317.54715) (xy 294.958153 -317.586494) (xy 294.981024 -317.630071)
			(xy 294.996608 -317.676752) (xy 295.004503 -317.725329) (xy 295.004998 -317.749936) (xy 295.004503 -317.774543)
			(xy 295.004324 -317.775644) (xy 295.323256 -317.775644) (xy 295.323256 -317.724228) (xy 295.331299 -317.673446)
			(xy 295.347187 -317.624547) (xy 295.37053 -317.578735) (xy 295.400751 -317.537139) (xy 295.437107 -317.500783)
			(xy 295.478703 -317.470562) (xy 295.524515 -317.447219) (xy 295.573414 -317.431331) (xy 295.624196 -317.423288)
			(xy 295.675612 -317.423288) (xy 295.726394 -317.431331) (xy 295.775293 -317.447219) (xy 295.821105 -317.470562)
			(xy 295.862701 -317.500783) (xy 295.899057 -317.537139) (xy 295.929278 -317.578735) (xy 295.952621 -317.624547)
			(xy 295.968509 -317.673446) (xy 295.976552 -317.724228) (xy 295.977056 -317.749936) (xy 296.29406 -317.749936)
			(xy 296.29802 -317.700882) (xy 296.309797 -317.653098) (xy 296.329088 -317.607822) (xy 296.355391 -317.566226)
			(xy 296.388026 -317.529389) (xy 296.426147 -317.498264) (xy 296.468768 -317.473657) (xy 296.514784 -317.456205)
			(xy 296.563003 -317.446361) (xy 296.612178 -317.44438) (xy 296.661033 -317.450312) (xy 296.708304 -317.464004)
			(xy 296.752766 -317.485102) (xy 296.793269 -317.513058) (xy 296.828762 -317.54715) (xy 296.858327 -317.586494)
			(xy 296.881198 -317.630071) (xy 296.896782 -317.676752) (xy 296.904677 -317.725329) (xy 296.905172 -317.749936)
			(xy 296.904677 -317.774543) (xy 296.904498 -317.775644) (xy 297.223176 -317.775644) (xy 297.223176 -317.724228)
			(xy 297.231219 -317.673446) (xy 297.247107 -317.624547) (xy 297.27045 -317.578735) (xy 297.300671 -317.537139)
			(xy 297.337027 -317.500783) (xy 297.378623 -317.470562) (xy 297.424435 -317.447219) (xy 297.473334 -317.431331)
			(xy 297.524116 -317.423288) (xy 297.575532 -317.423288) (xy 297.626314 -317.431331) (xy 297.675213 -317.447219)
			(xy 297.721025 -317.470562) (xy 297.762621 -317.500783) (xy 297.798977 -317.537139) (xy 297.829198 -317.578735)
			(xy 297.852541 -317.624547) (xy 297.868429 -317.673446) (xy 297.876472 -317.724228) (xy 297.876976 -317.749936)
			(xy 298.19398 -317.749936) (xy 298.19794 -317.700882) (xy 298.209717 -317.653098) (xy 298.229008 -317.607822)
			(xy 298.255311 -317.566226) (xy 298.287946 -317.529389) (xy 298.326067 -317.498264) (xy 298.368688 -317.473657)
			(xy 298.414704 -317.456205) (xy 298.462923 -317.446361) (xy 298.512098 -317.44438) (xy 298.560953 -317.450312)
			(xy 298.608224 -317.464004) (xy 298.652686 -317.485102) (xy 298.693189 -317.513058) (xy 298.728682 -317.54715)
			(xy 298.758247 -317.586494) (xy 298.781118 -317.630071) (xy 298.796702 -317.676752) (xy 298.804597 -317.725329)
			(xy 298.805092 -317.749936) (xy 298.804597 -317.774543) (xy 298.804418 -317.775644) (xy 299.123096 -317.775644)
			(xy 299.123096 -317.724228) (xy 299.131139 -317.673446) (xy 299.147027 -317.624547) (xy 299.17037 -317.578735)
			(xy 299.200591 -317.537139) (xy 299.236947 -317.500783) (xy 299.278543 -317.470562) (xy 299.324355 -317.447219)
			(xy 299.373254 -317.431331) (xy 299.424036 -317.423288) (xy 299.475452 -317.423288) (xy 299.526234 -317.431331)
			(xy 299.575133 -317.447219) (xy 299.620945 -317.470562) (xy 299.662541 -317.500783) (xy 299.698897 -317.537139)
			(xy 299.729118 -317.578735) (xy 299.752461 -317.624547) (xy 299.768349 -317.673446) (xy 299.776392 -317.724228)
			(xy 299.776896 -317.749936) (xy 300.0939 -317.749936) (xy 300.09786 -317.700882) (xy 300.109637 -317.653098)
			(xy 300.128928 -317.607822) (xy 300.155231 -317.566226) (xy 300.187866 -317.529389) (xy 300.225987 -317.498264)
			(xy 300.268608 -317.473657) (xy 300.314624 -317.456205) (xy 300.362843 -317.446361) (xy 300.412018 -317.44438)
			(xy 300.460873 -317.450312) (xy 300.508144 -317.464004) (xy 300.552606 -317.485102) (xy 300.593109 -317.513058)
			(xy 300.628602 -317.54715) (xy 300.658167 -317.586494) (xy 300.681038 -317.630071) (xy 300.696622 -317.676752)
			(xy 300.704517 -317.725329) (xy 300.705012 -317.749936) (xy 300.704517 -317.774543) (xy 300.704338 -317.775644)
			(xy 301.02327 -317.775644) (xy 301.02327 -317.724228) (xy 301.031313 -317.673446) (xy 301.047201 -317.624547)
			(xy 301.070544 -317.578735) (xy 301.100765 -317.537139) (xy 301.137121 -317.500783) (xy 301.178717 -317.470562)
			(xy 301.224529 -317.447219) (xy 301.273428 -317.431331) (xy 301.32421 -317.423288) (xy 301.375626 -317.423288)
			(xy 301.426408 -317.431331) (xy 301.475307 -317.447219) (xy 301.521119 -317.470562) (xy 301.562715 -317.500783)
			(xy 301.599071 -317.537139) (xy 301.629292 -317.578735) (xy 301.652635 -317.624547) (xy 301.668523 -317.673446)
			(xy 301.676566 -317.724228) (xy 301.67707 -317.749936) (xy 301.994074 -317.749936) (xy 301.998034 -317.700882)
			(xy 302.009811 -317.653098) (xy 302.029102 -317.607822) (xy 302.055405 -317.566226) (xy 302.08804 -317.529389)
			(xy 302.126161 -317.498264) (xy 302.168782 -317.473657) (xy 302.214798 -317.456205) (xy 302.263017 -317.446361)
			(xy 302.312192 -317.44438) (xy 302.361047 -317.450312) (xy 302.408318 -317.464004) (xy 302.45278 -317.485102)
			(xy 302.493283 -317.513058) (xy 302.528776 -317.54715) (xy 302.558341 -317.586494) (xy 302.581212 -317.630071)
			(xy 302.596796 -317.676752) (xy 302.604691 -317.725329) (xy 302.605186 -317.749936) (xy 302.604691 -317.774543)
			(xy 302.604512 -317.775644) (xy 302.92319 -317.775644) (xy 302.92319 -317.724228) (xy 302.931233 -317.673446)
			(xy 302.947121 -317.624547) (xy 302.970464 -317.578735) (xy 303.000685 -317.537139) (xy 303.037041 -317.500783)
			(xy 303.078637 -317.470562) (xy 303.124449 -317.447219) (xy 303.173348 -317.431331) (xy 303.22413 -317.423288)
			(xy 303.275546 -317.423288) (xy 303.326328 -317.431331) (xy 303.375227 -317.447219) (xy 303.421039 -317.470562)
			(xy 303.462635 -317.500783) (xy 303.498991 -317.537139) (xy 303.529212 -317.578735) (xy 303.552555 -317.624547)
			(xy 303.568443 -317.673446) (xy 303.576486 -317.724228) (xy 303.57699 -317.749936) (xy 303.576486 -317.775644)
			(xy 303.568443 -317.826426) (xy 303.552555 -317.875325) (xy 303.529212 -317.921137) (xy 303.498991 -317.962733)
			(xy 303.462635 -317.999089) (xy 303.421039 -318.02931) (xy 303.375227 -318.052653) (xy 303.326328 -318.068541)
			(xy 303.275546 -318.076584) (xy 303.22413 -318.076584) (xy 303.173348 -318.068541) (xy 303.124449 -318.052653)
			(xy 303.078637 -318.02931) (xy 303.037041 -317.999089) (xy 303.000685 -317.962733) (xy 302.970464 -317.921137)
			(xy 302.947121 -317.875325) (xy 302.931233 -317.826426) (xy 302.92319 -317.775644) (xy 302.604512 -317.775644)
			(xy 302.596796 -317.82312) (xy 302.581212 -317.869801) (xy 302.558341 -317.913378) (xy 302.528776 -317.952722)
			(xy 302.493283 -317.986814) (xy 302.45278 -318.01477) (xy 302.408318 -318.035868) (xy 302.361047 -318.04956)
			(xy 302.312192 -318.055492) (xy 302.263017 -318.053511) (xy 302.214798 -318.043667) (xy 302.168782 -318.026215)
			(xy 302.126161 -318.001608) (xy 302.08804 -317.970483) (xy 302.055405 -317.933646) (xy 302.029102 -317.89205)
			(xy 302.009811 -317.846774) (xy 301.998034 -317.79899) (xy 301.994074 -317.749936) (xy 301.67707 -317.749936)
			(xy 301.676566 -317.775644) (xy 301.668523 -317.826426) (xy 301.652635 -317.875325) (xy 301.629292 -317.921137)
			(xy 301.599071 -317.962733) (xy 301.562715 -317.999089) (xy 301.521119 -318.02931) (xy 301.475307 -318.052653)
			(xy 301.426408 -318.068541) (xy 301.375626 -318.076584) (xy 301.32421 -318.076584) (xy 301.273428 -318.068541)
			(xy 301.224529 -318.052653) (xy 301.178717 -318.02931) (xy 301.137121 -317.999089) (xy 301.100765 -317.962733)
			(xy 301.070544 -317.921137) (xy 301.047201 -317.875325) (xy 301.031313 -317.826426) (xy 301.02327 -317.775644)
			(xy 300.704338 -317.775644) (xy 300.696622 -317.82312) (xy 300.681038 -317.869801) (xy 300.658167 -317.913378)
			(xy 300.628602 -317.952722) (xy 300.593109 -317.986814) (xy 300.552606 -318.01477) (xy 300.508144 -318.035868)
			(xy 300.460873 -318.04956) (xy 300.412018 -318.055492) (xy 300.362843 -318.053511) (xy 300.314624 -318.043667)
			(xy 300.268608 -318.026215) (xy 300.225987 -318.001608) (xy 300.187866 -317.970483) (xy 300.155231 -317.933646)
			(xy 300.128928 -317.89205) (xy 300.109637 -317.846774) (xy 300.09786 -317.79899) (xy 300.0939 -317.749936)
			(xy 299.776896 -317.749936) (xy 299.776392 -317.775644) (xy 299.768349 -317.826426) (xy 299.752461 -317.875325)
			(xy 299.729118 -317.921137) (xy 299.698897 -317.962733) (xy 299.662541 -317.999089) (xy 299.620945 -318.02931)
			(xy 299.575133 -318.052653) (xy 299.526234 -318.068541) (xy 299.475452 -318.076584) (xy 299.424036 -318.076584)
			(xy 299.373254 -318.068541) (xy 299.324355 -318.052653) (xy 299.278543 -318.02931) (xy 299.236947 -317.999089)
			(xy 299.200591 -317.962733) (xy 299.17037 -317.921137) (xy 299.147027 -317.875325) (xy 299.131139 -317.826426)
			(xy 299.123096 -317.775644) (xy 298.804418 -317.775644) (xy 298.796702 -317.82312) (xy 298.781118 -317.869801)
			(xy 298.758247 -317.913378) (xy 298.728682 -317.952722) (xy 298.693189 -317.986814) (xy 298.652686 -318.01477)
			(xy 298.608224 -318.035868) (xy 298.560953 -318.04956) (xy 298.512098 -318.055492) (xy 298.462923 -318.053511)
			(xy 298.414704 -318.043667) (xy 298.368688 -318.026215) (xy 298.326067 -318.001608) (xy 298.287946 -317.970483)
			(xy 298.255311 -317.933646) (xy 298.229008 -317.89205) (xy 298.209717 -317.846774) (xy 298.19794 -317.79899)
			(xy 298.19398 -317.749936) (xy 297.876976 -317.749936) (xy 297.876472 -317.775644) (xy 297.868429 -317.826426)
			(xy 297.852541 -317.875325) (xy 297.829198 -317.921137) (xy 297.798977 -317.962733) (xy 297.762621 -317.999089)
			(xy 297.721025 -318.02931) (xy 297.675213 -318.052653) (xy 297.626314 -318.068541) (xy 297.575532 -318.076584)
			(xy 297.524116 -318.076584) (xy 297.473334 -318.068541) (xy 297.424435 -318.052653) (xy 297.378623 -318.02931)
			(xy 297.337027 -317.999089) (xy 297.300671 -317.962733) (xy 297.27045 -317.921137) (xy 297.247107 -317.875325)
			(xy 297.231219 -317.826426) (xy 297.223176 -317.775644) (xy 296.904498 -317.775644) (xy 296.896782 -317.82312)
			(xy 296.881198 -317.869801) (xy 296.858327 -317.913378) (xy 296.828762 -317.952722) (xy 296.793269 -317.986814)
			(xy 296.752766 -318.01477) (xy 296.708304 -318.035868) (xy 296.661033 -318.04956) (xy 296.612178 -318.055492)
			(xy 296.563003 -318.053511) (xy 296.514784 -318.043667) (xy 296.468768 -318.026215) (xy 296.426147 -318.001608)
			(xy 296.388026 -317.970483) (xy 296.355391 -317.933646) (xy 296.329088 -317.89205) (xy 296.309797 -317.846774)
			(xy 296.29802 -317.79899) (xy 296.29406 -317.749936) (xy 295.977056 -317.749936) (xy 295.976552 -317.775644)
			(xy 295.968509 -317.826426) (xy 295.952621 -317.875325) (xy 295.929278 -317.921137) (xy 295.899057 -317.962733)
			(xy 295.862701 -317.999089) (xy 295.821105 -318.02931) (xy 295.775293 -318.052653) (xy 295.726394 -318.068541)
			(xy 295.675612 -318.076584) (xy 295.624196 -318.076584) (xy 295.573414 -318.068541) (xy 295.524515 -318.052653)
			(xy 295.478703 -318.02931) (xy 295.437107 -317.999089) (xy 295.400751 -317.962733) (xy 295.37053 -317.921137)
			(xy 295.347187 -317.875325) (xy 295.331299 -317.826426) (xy 295.323256 -317.775644) (xy 295.004324 -317.775644)
			(xy 294.996608 -317.82312) (xy 294.981024 -317.869801) (xy 294.958153 -317.913378) (xy 294.928588 -317.952722)
			(xy 294.893095 -317.986814) (xy 294.852592 -318.01477) (xy 294.80813 -318.035868) (xy 294.760859 -318.04956)
			(xy 294.712004 -318.055492) (xy 294.662829 -318.053511) (xy 294.61461 -318.043667) (xy 294.568594 -318.026215)
			(xy 294.525973 -318.001608) (xy 294.487852 -317.970483) (xy 294.455217 -317.933646) (xy 294.428914 -317.89205)
			(xy 294.409623 -317.846774) (xy 294.397846 -317.79899) (xy 294.393886 -317.749936) (xy 294.076882 -317.749936)
			(xy 294.076378 -317.775644) (xy 294.068335 -317.826426) (xy 294.052447 -317.875325) (xy 294.029104 -317.921137)
			(xy 293.998883 -317.962733) (xy 293.962527 -317.999089) (xy 293.920931 -318.02931) (xy 293.875119 -318.052653)
			(xy 293.82622 -318.068541) (xy 293.775438 -318.076584) (xy 293.724022 -318.076584) (xy 293.67324 -318.068541)
			(xy 293.624341 -318.052653) (xy 293.578529 -318.02931) (xy 293.536933 -317.999089) (xy 293.500577 -317.962733)
			(xy 293.470356 -317.921137) (xy 293.447013 -317.875325) (xy 293.431125 -317.826426) (xy 293.423082 -317.775644)
			(xy 293.104404 -317.775644) (xy 293.096688 -317.82312) (xy 293.081104 -317.869801) (xy 293.058233 -317.913378)
			(xy 293.028668 -317.952722) (xy 292.993175 -317.986814) (xy 292.952672 -318.01477) (xy 292.90821 -318.035868)
			(xy 292.860939 -318.04956) (xy 292.812084 -318.055492) (xy 292.762909 -318.053511) (xy 292.71469 -318.043667)
			(xy 292.668674 -318.026215) (xy 292.626053 -318.001608) (xy 292.587932 -317.970483) (xy 292.555297 -317.933646)
			(xy 292.528994 -317.89205) (xy 292.509703 -317.846774) (xy 292.497926 -317.79899) (xy 292.493966 -317.749936)
			(xy 292.176962 -317.749936) (xy 292.176458 -317.775644) (xy 292.168415 -317.826426) (xy 292.152527 -317.875325)
			(xy 292.129184 -317.921137) (xy 292.098963 -317.962733) (xy 292.062607 -317.999089) (xy 292.021011 -318.02931)
			(xy 291.975199 -318.052653) (xy 291.9263 -318.068541) (xy 291.875518 -318.076584) (xy 291.824102 -318.076584)
			(xy 291.77332 -318.068541) (xy 291.724421 -318.052653) (xy 291.678609 -318.02931) (xy 291.637013 -317.999089)
			(xy 291.600657 -317.962733) (xy 291.570436 -317.921137) (xy 291.547093 -317.875325) (xy 291.531205 -317.826426)
			(xy 291.523162 -317.775644) (xy 291.204484 -317.775644) (xy 291.196768 -317.82312) (xy 291.181184 -317.869801)
			(xy 291.158313 -317.913378) (xy 291.128748 -317.952722) (xy 291.093255 -317.986814) (xy 291.052752 -318.01477)
			(xy 291.00829 -318.035868) (xy 290.961019 -318.04956) (xy 290.912164 -318.055492) (xy 290.862989 -318.053511)
			(xy 290.81477 -318.043667) (xy 290.768754 -318.026215) (xy 290.726133 -318.001608) (xy 290.688012 -317.970483)
			(xy 290.655377 -317.933646) (xy 290.629074 -317.89205) (xy 290.609783 -317.846774) (xy 290.598006 -317.79899)
			(xy 290.594046 -317.749936) (xy 290.277042 -317.749936) (xy 290.276538 -317.775644) (xy 290.268495 -317.826426)
			(xy 290.252607 -317.875325) (xy 290.229264 -317.921137) (xy 290.199043 -317.962733) (xy 290.162687 -317.999089)
			(xy 290.121091 -318.02931) (xy 290.075279 -318.052653) (xy 290.02638 -318.068541) (xy 289.975598 -318.076584)
			(xy 289.924182 -318.076584) (xy 289.8734 -318.068541) (xy 289.824501 -318.052653) (xy 289.778689 -318.02931)
			(xy 289.737093 -317.999089) (xy 289.700737 -317.962733) (xy 289.670516 -317.921137) (xy 289.647173 -317.875325)
			(xy 289.631285 -317.826426) (xy 289.623242 -317.775644) (xy 289.304564 -317.775644) (xy 289.296848 -317.82312)
			(xy 289.281264 -317.869801) (xy 289.258393 -317.913378) (xy 289.228828 -317.952722) (xy 289.193335 -317.986814)
			(xy 289.152832 -318.01477) (xy 289.10837 -318.035868) (xy 289.061099 -318.04956) (xy 289.012244 -318.055492)
			(xy 288.963069 -318.053511) (xy 288.91485 -318.043667) (xy 288.868834 -318.026215) (xy 288.826213 -318.001608)
			(xy 288.788092 -317.970483) (xy 288.755457 -317.933646) (xy 288.729154 -317.89205) (xy 288.709863 -317.846774)
			(xy 288.698086 -317.79899) (xy 288.694126 -317.749936) (xy 288.376868 -317.749936) (xy 288.376364 -317.775644)
			(xy 288.368321 -317.826426) (xy 288.352433 -317.875325) (xy 288.32909 -317.921137) (xy 288.298869 -317.962733)
			(xy 288.262513 -317.999089) (xy 288.220917 -318.02931) (xy 288.175105 -318.052653) (xy 288.126206 -318.068541)
			(xy 288.075424 -318.076584) (xy 288.024008 -318.076584) (xy 287.973226 -318.068541) (xy 287.924327 -318.052653)
			(xy 287.878515 -318.02931) (xy 287.836919 -317.999089) (xy 287.800563 -317.962733) (xy 287.770342 -317.921137)
			(xy 287.746999 -317.875325) (xy 287.731111 -317.826426) (xy 287.723068 -317.775644) (xy 287.40439 -317.775644)
			(xy 287.396674 -317.82312) (xy 287.38109 -317.869801) (xy 287.358219 -317.913378) (xy 287.328654 -317.952722)
			(xy 287.293161 -317.986814) (xy 287.252658 -318.01477) (xy 287.208196 -318.035868) (xy 287.160925 -318.04956)
			(xy 287.11207 -318.055492) (xy 287.062895 -318.053511) (xy 287.014676 -318.043667) (xy 286.96866 -318.026215)
			(xy 286.926039 -318.001608) (xy 286.887918 -317.970483) (xy 286.855283 -317.933646) (xy 286.82898 -317.89205)
			(xy 286.809689 -317.846774) (xy 286.797912 -317.79899) (xy 286.793952 -317.749936) (xy 286.476948 -317.749936)
			(xy 286.476444 -317.775644) (xy 286.468401 -317.826426) (xy 286.452513 -317.875325) (xy 286.42917 -317.921137)
			(xy 286.398949 -317.962733) (xy 286.362593 -317.999089) (xy 286.320997 -318.02931) (xy 286.275185 -318.052653)
			(xy 286.226286 -318.068541) (xy 286.175504 -318.076584) (xy 286.124088 -318.076584) (xy 286.073306 -318.068541)
			(xy 286.024407 -318.052653) (xy 285.978595 -318.02931) (xy 285.936999 -317.999089) (xy 285.900643 -317.962733)
			(xy 285.870422 -317.921137) (xy 285.847079 -317.875325) (xy 285.831191 -317.826426) (xy 285.823148 -317.775644)
			(xy 285.50447 -317.775644) (xy 285.496754 -317.82312) (xy 285.48117 -317.869801) (xy 285.458299 -317.913378)
			(xy 285.428734 -317.952722) (xy 285.393241 -317.986814) (xy 285.352738 -318.01477) (xy 285.308276 -318.035868)
			(xy 285.261005 -318.04956) (xy 285.21215 -318.055492) (xy 285.162975 -318.053511) (xy 285.114756 -318.043667)
			(xy 285.06874 -318.026215) (xy 285.026119 -318.001608) (xy 284.987998 -317.970483) (xy 284.955363 -317.933646)
			(xy 284.92906 -317.89205) (xy 284.909769 -317.846774) (xy 284.897992 -317.79899) (xy 284.894032 -317.749936)
			(xy 284.577028 -317.749936) (xy 284.576524 -317.775644) (xy 284.568481 -317.826426) (xy 284.552593 -317.875325)
			(xy 284.52925 -317.921137) (xy 284.499029 -317.962733) (xy 284.462673 -317.999089) (xy 284.421077 -318.02931)
			(xy 284.375265 -318.052653) (xy 284.326366 -318.068541) (xy 284.275584 -318.076584) (xy 284.224168 -318.076584)
			(xy 284.173386 -318.068541) (xy 284.124487 -318.052653) (xy 284.078675 -318.02931) (xy 284.037079 -317.999089)
			(xy 284.000723 -317.962733) (xy 283.970502 -317.921137) (xy 283.947159 -317.875325) (xy 283.931271 -317.826426)
			(xy 283.923228 -317.775644) (xy 283.60455 -317.775644) (xy 283.596834 -317.82312) (xy 283.58125 -317.869801)
			(xy 283.558379 -317.913378) (xy 283.528814 -317.952722) (xy 283.493321 -317.986814) (xy 283.452818 -318.01477)
			(xy 283.408356 -318.035868) (xy 283.361085 -318.04956) (xy 283.31223 -318.055492) (xy 283.263055 -318.053511)
			(xy 283.214836 -318.043667) (xy 283.16882 -318.026215) (xy 283.126199 -318.001608) (xy 283.088078 -317.970483)
			(xy 283.055443 -317.933646) (xy 283.02914 -317.89205) (xy 283.009849 -317.846774) (xy 282.998072 -317.79899)
			(xy 282.994112 -317.749936) (xy 282.676854 -317.749936) (xy 282.67635 -317.775644) (xy 282.668307 -317.826426)
			(xy 282.652419 -317.875325) (xy 282.629076 -317.921137) (xy 282.598855 -317.962733) (xy 282.562499 -317.999089)
			(xy 282.520903 -318.02931) (xy 282.475091 -318.052653) (xy 282.426192 -318.068541) (xy 282.37541 -318.076584)
			(xy 282.323994 -318.076584) (xy 282.273212 -318.068541) (xy 282.224313 -318.052653) (xy 282.178501 -318.02931)
			(xy 282.136905 -317.999089) (xy 282.100549 -317.962733) (xy 282.070328 -317.921137) (xy 282.046985 -317.875325)
			(xy 282.031097 -317.826426) (xy 282.023054 -317.775644) (xy 281.704376 -317.775644) (xy 281.69666 -317.82312)
			(xy 281.681076 -317.869801) (xy 281.658205 -317.913378) (xy 281.62864 -317.952722) (xy 281.593147 -317.986814)
			(xy 281.552644 -318.01477) (xy 281.508182 -318.035868) (xy 281.460911 -318.04956) (xy 281.412056 -318.055492)
			(xy 281.362881 -318.053511) (xy 281.314662 -318.043667) (xy 281.268646 -318.026215) (xy 281.226025 -318.001608)
			(xy 281.187904 -317.970483) (xy 281.155269 -317.933646) (xy 281.128966 -317.89205) (xy 281.109675 -317.846774)
			(xy 281.097898 -317.79899) (xy 281.093938 -317.749936) (xy 280.776934 -317.749936) (xy 280.77643 -317.775644)
			(xy 280.768387 -317.826426) (xy 280.752499 -317.875325) (xy 280.729156 -317.921137) (xy 280.698935 -317.962733)
			(xy 280.662579 -317.999089) (xy 280.620983 -318.02931) (xy 280.575171 -318.052653) (xy 280.526272 -318.068541)
			(xy 280.47549 -318.076584) (xy 280.424074 -318.076584) (xy 280.373292 -318.068541) (xy 280.324393 -318.052653)
			(xy 280.278581 -318.02931) (xy 280.236985 -317.999089) (xy 280.200629 -317.962733) (xy 280.170408 -317.921137)
			(xy 280.147065 -317.875325) (xy 280.131177 -317.826426) (xy 280.123134 -317.775644) (xy 279.804456 -317.775644)
			(xy 279.79674 -317.82312) (xy 279.781156 -317.869801) (xy 279.758285 -317.913378) (xy 279.72872 -317.952722)
			(xy 279.693227 -317.986814) (xy 279.652724 -318.01477) (xy 279.608262 -318.035868) (xy 279.560991 -318.04956)
			(xy 279.512136 -318.055492) (xy 279.462961 -318.053511) (xy 279.414742 -318.043667) (xy 279.368726 -318.026215)
			(xy 279.326105 -318.001608) (xy 279.287984 -317.970483) (xy 279.255349 -317.933646) (xy 279.229046 -317.89205)
			(xy 279.209755 -317.846774) (xy 279.197978 -317.79899) (xy 279.194018 -317.749936) (xy 278.877014 -317.749936)
			(xy 278.87651 -317.775644) (xy 278.868467 -317.826426) (xy 278.852579 -317.875325) (xy 278.829236 -317.921137)
			(xy 278.799015 -317.962733) (xy 278.762659 -317.999089) (xy 278.721063 -318.02931) (xy 278.675251 -318.052653)
			(xy 278.626352 -318.068541) (xy 278.57557 -318.076584) (xy 278.524154 -318.076584) (xy 278.473372 -318.068541)
			(xy 278.424473 -318.052653) (xy 278.378661 -318.02931) (xy 278.337065 -317.999089) (xy 278.300709 -317.962733)
			(xy 278.270488 -317.921137) (xy 278.247145 -317.875325) (xy 278.231257 -317.826426) (xy 278.223214 -317.775644)
			(xy 277.904536 -317.775644) (xy 277.89682 -317.82312) (xy 277.881236 -317.869801) (xy 277.858365 -317.913378)
			(xy 277.8288 -317.952722) (xy 277.793307 -317.986814) (xy 277.752804 -318.01477) (xy 277.708342 -318.035868)
			(xy 277.661071 -318.04956) (xy 277.612216 -318.055492) (xy 277.563041 -318.053511) (xy 277.514822 -318.043667)
			(xy 277.468806 -318.026215) (xy 277.426185 -318.001608) (xy 277.388064 -317.970483) (xy 277.355429 -317.933646)
			(xy 277.329126 -317.89205) (xy 277.309835 -317.846774) (xy 277.298058 -317.79899) (xy 277.294098 -317.749936)
			(xy 276.97684 -317.749936) (xy 276.976336 -317.775644) (xy 276.968293 -317.826426) (xy 276.952405 -317.875325)
			(xy 276.929062 -317.921137) (xy 276.898841 -317.962733) (xy 276.862485 -317.999089) (xy 276.820889 -318.02931)
			(xy 276.775077 -318.052653) (xy 276.726178 -318.068541) (xy 276.675396 -318.076584) (xy 276.62398 -318.076584)
			(xy 276.573198 -318.068541) (xy 276.524299 -318.052653) (xy 276.478487 -318.02931) (xy 276.436891 -317.999089)
			(xy 276.400535 -317.962733) (xy 276.370314 -317.921137) (xy 276.346971 -317.875325) (xy 276.331083 -317.826426)
			(xy 276.32304 -317.775644) (xy 276.004362 -317.775644) (xy 275.996646 -317.82312) (xy 275.981062 -317.869801)
			(xy 275.958191 -317.913378) (xy 275.928626 -317.952722) (xy 275.893133 -317.986814) (xy 275.85263 -318.01477)
			(xy 275.808168 -318.035868) (xy 275.760897 -318.04956) (xy 275.712042 -318.055492) (xy 275.662867 -318.053511)
			(xy 275.614648 -318.043667) (xy 275.568632 -318.026215) (xy 275.526011 -318.001608) (xy 275.48789 -317.970483)
			(xy 275.455255 -317.933646) (xy 275.428952 -317.89205) (xy 275.409661 -317.846774) (xy 275.397884 -317.79899)
			(xy 275.393924 -317.749936) (xy 275.07692 -317.749936) (xy 275.076416 -317.775644) (xy 275.068373 -317.826426)
			(xy 275.052485 -317.875325) (xy 275.029142 -317.921137) (xy 274.998921 -317.962733) (xy 274.962565 -317.999089)
			(xy 274.920969 -318.02931) (xy 274.875157 -318.052653) (xy 274.826258 -318.068541) (xy 274.775476 -318.076584)
			(xy 274.72406 -318.076584) (xy 274.673278 -318.068541) (xy 274.624379 -318.052653) (xy 274.578567 -318.02931)
			(xy 274.536971 -317.999089) (xy 274.500615 -317.962733) (xy 274.470394 -317.921137) (xy 274.447051 -317.875325)
			(xy 274.431163 -317.826426) (xy 274.42312 -317.775644) (xy 274.104442 -317.775644) (xy 274.096726 -317.82312)
			(xy 274.081142 -317.869801) (xy 274.058271 -317.913378) (xy 274.028706 -317.952722) (xy 273.993213 -317.986814)
			(xy 273.95271 -318.01477) (xy 273.908248 -318.035868) (xy 273.860977 -318.04956) (xy 273.812122 -318.055492)
			(xy 273.762947 -318.053511) (xy 273.714728 -318.043667) (xy 273.668712 -318.026215) (xy 273.626091 -318.001608)
			(xy 273.58797 -317.970483) (xy 273.555335 -317.933646) (xy 273.529032 -317.89205) (xy 273.509741 -317.846774)
			(xy 273.497964 -317.79899) (xy 273.494004 -317.749936) (xy 273.177 -317.749936) (xy 273.176496 -317.775644)
			(xy 273.168453 -317.826426) (xy 273.152565 -317.875325) (xy 273.129222 -317.921137) (xy 273.099001 -317.962733)
			(xy 273.062645 -317.999089) (xy 273.021049 -318.02931) (xy 272.975237 -318.052653) (xy 272.926338 -318.068541)
			(xy 272.875556 -318.076584) (xy 272.82414 -318.076584) (xy 272.773358 -318.068541) (xy 272.724459 -318.052653)
			(xy 272.678647 -318.02931) (xy 272.637051 -317.999089) (xy 272.600695 -317.962733) (xy 272.570474 -317.921137)
			(xy 272.547131 -317.875325) (xy 272.531243 -317.826426) (xy 272.5232 -317.775644) (xy 272.204522 -317.775644)
			(xy 272.196806 -317.82312) (xy 272.181222 -317.869801) (xy 272.158351 -317.913378) (xy 272.128786 -317.952722)
			(xy 272.093293 -317.986814) (xy 272.05279 -318.01477) (xy 272.008328 -318.035868) (xy 271.961057 -318.04956)
			(xy 271.912202 -318.055492) (xy 271.863027 -318.053511) (xy 271.814808 -318.043667) (xy 271.768792 -318.026215)
			(xy 271.726171 -318.001608) (xy 271.68805 -317.970483) (xy 271.655415 -317.933646) (xy 271.629112 -317.89205)
			(xy 271.609821 -317.846774) (xy 271.598044 -317.79899) (xy 271.594084 -317.749936) (xy 271.27708 -317.749936)
			(xy 271.276576 -317.775644) (xy 271.268533 -317.826426) (xy 271.252645 -317.875325) (xy 271.229302 -317.921137)
			(xy 271.199081 -317.962733) (xy 271.162725 -317.999089) (xy 271.121129 -318.02931) (xy 271.075317 -318.052653)
			(xy 271.026418 -318.068541) (xy 270.975636 -318.076584) (xy 270.92422 -318.076584) (xy 270.873438 -318.068541)
			(xy 270.824539 -318.052653) (xy 270.778727 -318.02931) (xy 270.737131 -317.999089) (xy 270.700775 -317.962733)
			(xy 270.670554 -317.921137) (xy 270.647211 -317.875325) (xy 270.631323 -317.826426) (xy 270.62328 -317.775644)
			(xy 270.304348 -317.775644) (xy 270.296632 -317.82312) (xy 270.281048 -317.869801) (xy 270.258177 -317.913378)
			(xy 270.228612 -317.952722) (xy 270.193119 -317.986814) (xy 270.152616 -318.01477) (xy 270.108154 -318.035868)
			(xy 270.060883 -318.04956) (xy 270.012028 -318.055492) (xy 269.962853 -318.053511) (xy 269.914634 -318.043667)
			(xy 269.868618 -318.026215) (xy 269.825997 -318.001608) (xy 269.787876 -317.970483) (xy 269.755241 -317.933646)
			(xy 269.728938 -317.89205) (xy 269.709647 -317.846774) (xy 269.69787 -317.79899) (xy 269.69391 -317.749936)
			(xy 269.355062 -317.749936) (xy 269.354567 -317.774543) (xy 269.346672 -317.82312) (xy 269.331088 -317.869801)
			(xy 269.308217 -317.913378) (xy 269.278652 -317.952722) (xy 269.243159 -317.986814) (xy 269.202656 -318.01477)
			(xy 269.158194 -318.035868) (xy 269.110923 -318.04956) (xy 269.062068 -318.055492) (xy 269.012893 -318.053511)
			(xy 268.964674 -318.043667) (xy 268.918658 -318.026215) (xy 268.876037 -318.001608) (xy 268.837916 -317.970483)
			(xy 268.805281 -317.933646) (xy 268.778978 -317.89205) (xy 268.759687 -317.846774) (xy 268.74791 -317.79899)
			(xy 268.74395 -317.749936) (xy 265.43964 -317.749936) (xy 265.459677 -317.772129) (xy 265.584256 -317.921971)
			(xy 265.70262 -318.076769) (xy 265.814571 -318.236267) (xy 265.919923 -318.400198) (xy 266.018501 -318.56829)
			(xy 266.08863 -318.699896) (xy 269.69391 -318.699896) (xy 269.69787 -318.650842) (xy 269.709647 -318.603058)
			(xy 269.728938 -318.557782) (xy 269.755241 -318.516186) (xy 269.787876 -318.479349) (xy 269.825997 -318.448224)
			(xy 269.868618 -318.423617) (xy 269.914634 -318.406165) (xy 269.962853 -318.396321) (xy 270.012028 -318.39434)
			(xy 270.060883 -318.400272) (xy 270.108154 -318.413964) (xy 270.152616 -318.435062) (xy 270.193119 -318.463018)
			(xy 270.228612 -318.49711) (xy 270.258177 -318.536454) (xy 270.281048 -318.580031) (xy 270.296632 -318.626712)
			(xy 270.304527 -318.675289) (xy 270.305022 -318.699896) (xy 270.304527 -318.724503) (xy 270.304348 -318.725604)
			(xy 270.62328 -318.725604) (xy 270.62328 -318.674188) (xy 270.631323 -318.623406) (xy 270.647211 -318.574507)
			(xy 270.670554 -318.528695) (xy 270.700775 -318.487099) (xy 270.737131 -318.450743) (xy 270.778727 -318.420522)
			(xy 270.824539 -318.397179) (xy 270.873438 -318.381291) (xy 270.92422 -318.373248) (xy 270.975636 -318.373248)
			(xy 271.026418 -318.381291) (xy 271.075317 -318.397179) (xy 271.121129 -318.420522) (xy 271.162725 -318.450743)
			(xy 271.199081 -318.487099) (xy 271.229302 -318.528695) (xy 271.252645 -318.574507) (xy 271.268533 -318.623406)
			(xy 271.276576 -318.674188) (xy 271.27708 -318.699896) (xy 271.594084 -318.699896) (xy 271.598044 -318.650842)
			(xy 271.609821 -318.603058) (xy 271.629112 -318.557782) (xy 271.655415 -318.516186) (xy 271.68805 -318.479349)
			(xy 271.726171 -318.448224) (xy 271.768792 -318.423617) (xy 271.814808 -318.406165) (xy 271.863027 -318.396321)
			(xy 271.912202 -318.39434) (xy 271.961057 -318.400272) (xy 272.008328 -318.413964) (xy 272.05279 -318.435062)
			(xy 272.093293 -318.463018) (xy 272.128786 -318.49711) (xy 272.158351 -318.536454) (xy 272.181222 -318.580031)
			(xy 272.196806 -318.626712) (xy 272.204701 -318.675289) (xy 272.205196 -318.699896) (xy 272.204701 -318.724503)
			(xy 272.204522 -318.725604) (xy 272.5232 -318.725604) (xy 272.5232 -318.674188) (xy 272.531243 -318.623406)
			(xy 272.547131 -318.574507) (xy 272.570474 -318.528695) (xy 272.600695 -318.487099) (xy 272.637051 -318.450743)
			(xy 272.678647 -318.420522) (xy 272.724459 -318.397179) (xy 272.773358 -318.381291) (xy 272.82414 -318.373248)
			(xy 272.875556 -318.373248) (xy 272.926338 -318.381291) (xy 272.975237 -318.397179) (xy 273.021049 -318.420522)
			(xy 273.062645 -318.450743) (xy 273.099001 -318.487099) (xy 273.129222 -318.528695) (xy 273.152565 -318.574507)
			(xy 273.168453 -318.623406) (xy 273.176496 -318.674188) (xy 273.177 -318.699896) (xy 273.494004 -318.699896)
			(xy 273.497964 -318.650842) (xy 273.509741 -318.603058) (xy 273.529032 -318.557782) (xy 273.555335 -318.516186)
			(xy 273.58797 -318.479349) (xy 273.626091 -318.448224) (xy 273.668712 -318.423617) (xy 273.714728 -318.406165)
			(xy 273.762947 -318.396321) (xy 273.812122 -318.39434) (xy 273.860977 -318.400272) (xy 273.908248 -318.413964)
			(xy 273.95271 -318.435062) (xy 273.993213 -318.463018) (xy 274.028706 -318.49711) (xy 274.058271 -318.536454)
			(xy 274.081142 -318.580031) (xy 274.096726 -318.626712) (xy 274.104621 -318.675289) (xy 274.105116 -318.699896)
			(xy 274.104621 -318.724503) (xy 274.104442 -318.725604) (xy 274.42312 -318.725604) (xy 274.42312 -318.674188)
			(xy 274.431163 -318.623406) (xy 274.447051 -318.574507) (xy 274.470394 -318.528695) (xy 274.500615 -318.487099)
			(xy 274.536971 -318.450743) (xy 274.578567 -318.420522) (xy 274.624379 -318.397179) (xy 274.673278 -318.381291)
			(xy 274.72406 -318.373248) (xy 274.775476 -318.373248) (xy 274.826258 -318.381291) (xy 274.875157 -318.397179)
			(xy 274.920969 -318.420522) (xy 274.962565 -318.450743) (xy 274.998921 -318.487099) (xy 275.029142 -318.528695)
			(xy 275.052485 -318.574507) (xy 275.068373 -318.623406) (xy 275.076416 -318.674188) (xy 275.07692 -318.699896)
			(xy 275.393924 -318.699896) (xy 275.397884 -318.650842) (xy 275.409661 -318.603058) (xy 275.428952 -318.557782)
			(xy 275.455255 -318.516186) (xy 275.48789 -318.479349) (xy 275.526011 -318.448224) (xy 275.568632 -318.423617)
			(xy 275.614648 -318.406165) (xy 275.662867 -318.396321) (xy 275.712042 -318.39434) (xy 275.760897 -318.400272)
			(xy 275.808168 -318.413964) (xy 275.85263 -318.435062) (xy 275.893133 -318.463018) (xy 275.928626 -318.49711)
			(xy 275.958191 -318.536454) (xy 275.981062 -318.580031) (xy 275.996646 -318.626712) (xy 276.004541 -318.675289)
			(xy 276.005036 -318.699896) (xy 276.004541 -318.724503) (xy 276.004362 -318.725604) (xy 276.32304 -318.725604)
			(xy 276.32304 -318.674188) (xy 276.331083 -318.623406) (xy 276.346971 -318.574507) (xy 276.370314 -318.528695)
			(xy 276.400535 -318.487099) (xy 276.436891 -318.450743) (xy 276.478487 -318.420522) (xy 276.524299 -318.397179)
			(xy 276.573198 -318.381291) (xy 276.62398 -318.373248) (xy 276.675396 -318.373248) (xy 276.726178 -318.381291)
			(xy 276.775077 -318.397179) (xy 276.820889 -318.420522) (xy 276.862485 -318.450743) (xy 276.898841 -318.487099)
			(xy 276.929062 -318.528695) (xy 276.952405 -318.574507) (xy 276.968293 -318.623406) (xy 276.976336 -318.674188)
			(xy 276.97684 -318.699896) (xy 277.294098 -318.699896) (xy 277.298058 -318.650842) (xy 277.309835 -318.603058)
			(xy 277.329126 -318.557782) (xy 277.355429 -318.516186) (xy 277.388064 -318.479349) (xy 277.426185 -318.448224)
			(xy 277.468806 -318.423617) (xy 277.514822 -318.406165) (xy 277.563041 -318.396321) (xy 277.612216 -318.39434)
			(xy 277.661071 -318.400272) (xy 277.708342 -318.413964) (xy 277.752804 -318.435062) (xy 277.793307 -318.463018)
			(xy 277.8288 -318.49711) (xy 277.858365 -318.536454) (xy 277.881236 -318.580031) (xy 277.89682 -318.626712)
			(xy 277.904715 -318.675289) (xy 277.90521 -318.699896) (xy 277.904715 -318.724503) (xy 277.904536 -318.725604)
			(xy 278.223214 -318.725604) (xy 278.223214 -318.674188) (xy 278.231257 -318.623406) (xy 278.247145 -318.574507)
			(xy 278.270488 -318.528695) (xy 278.300709 -318.487099) (xy 278.337065 -318.450743) (xy 278.378661 -318.420522)
			(xy 278.424473 -318.397179) (xy 278.473372 -318.381291) (xy 278.524154 -318.373248) (xy 278.57557 -318.373248)
			(xy 278.626352 -318.381291) (xy 278.675251 -318.397179) (xy 278.721063 -318.420522) (xy 278.762659 -318.450743)
			(xy 278.799015 -318.487099) (xy 278.829236 -318.528695) (xy 278.852579 -318.574507) (xy 278.868467 -318.623406)
			(xy 278.87651 -318.674188) (xy 278.877014 -318.699896) (xy 279.194018 -318.699896) (xy 279.197978 -318.650842)
			(xy 279.209755 -318.603058) (xy 279.229046 -318.557782) (xy 279.255349 -318.516186) (xy 279.287984 -318.479349)
			(xy 279.326105 -318.448224) (xy 279.368726 -318.423617) (xy 279.414742 -318.406165) (xy 279.462961 -318.396321)
			(xy 279.512136 -318.39434) (xy 279.560991 -318.400272) (xy 279.608262 -318.413964) (xy 279.652724 -318.435062)
			(xy 279.693227 -318.463018) (xy 279.72872 -318.49711) (xy 279.758285 -318.536454) (xy 279.781156 -318.580031)
			(xy 279.79674 -318.626712) (xy 279.804635 -318.675289) (xy 279.80513 -318.699896) (xy 279.804635 -318.724503)
			(xy 279.804456 -318.725604) (xy 280.123134 -318.725604) (xy 280.123134 -318.674188) (xy 280.131177 -318.623406)
			(xy 280.147065 -318.574507) (xy 280.170408 -318.528695) (xy 280.200629 -318.487099) (xy 280.236985 -318.450743)
			(xy 280.278581 -318.420522) (xy 280.324393 -318.397179) (xy 280.373292 -318.381291) (xy 280.424074 -318.373248)
			(xy 280.47549 -318.373248) (xy 280.526272 -318.381291) (xy 280.575171 -318.397179) (xy 280.620983 -318.420522)
			(xy 280.662579 -318.450743) (xy 280.698935 -318.487099) (xy 280.729156 -318.528695) (xy 280.752499 -318.574507)
			(xy 280.768387 -318.623406) (xy 280.77643 -318.674188) (xy 280.776934 -318.699896) (xy 281.093938 -318.699896)
			(xy 281.097898 -318.650842) (xy 281.109675 -318.603058) (xy 281.128966 -318.557782) (xy 281.155269 -318.516186)
			(xy 281.187904 -318.479349) (xy 281.226025 -318.448224) (xy 281.268646 -318.423617) (xy 281.314662 -318.406165)
			(xy 281.362881 -318.396321) (xy 281.412056 -318.39434) (xy 281.460911 -318.400272) (xy 281.508182 -318.413964)
			(xy 281.552644 -318.435062) (xy 281.593147 -318.463018) (xy 281.62864 -318.49711) (xy 281.658205 -318.536454)
			(xy 281.681076 -318.580031) (xy 281.69666 -318.626712) (xy 281.704555 -318.675289) (xy 281.70505 -318.699896)
			(xy 281.704555 -318.724503) (xy 281.704376 -318.725604) (xy 282.023054 -318.725604) (xy 282.023054 -318.674188)
			(xy 282.031097 -318.623406) (xy 282.046985 -318.574507) (xy 282.070328 -318.528695) (xy 282.100549 -318.487099)
			(xy 282.136905 -318.450743) (xy 282.178501 -318.420522) (xy 282.224313 -318.397179) (xy 282.273212 -318.381291)
			(xy 282.323994 -318.373248) (xy 282.37541 -318.373248) (xy 282.426192 -318.381291) (xy 282.475091 -318.397179)
			(xy 282.520903 -318.420522) (xy 282.562499 -318.450743) (xy 282.598855 -318.487099) (xy 282.629076 -318.528695)
			(xy 282.652419 -318.574507) (xy 282.668307 -318.623406) (xy 282.67635 -318.674188) (xy 282.676854 -318.699896)
			(xy 282.994112 -318.699896) (xy 282.998072 -318.650842) (xy 283.009849 -318.603058) (xy 283.02914 -318.557782)
			(xy 283.055443 -318.516186) (xy 283.088078 -318.479349) (xy 283.126199 -318.448224) (xy 283.16882 -318.423617)
			(xy 283.214836 -318.406165) (xy 283.263055 -318.396321) (xy 283.31223 -318.39434) (xy 283.361085 -318.400272)
			(xy 283.408356 -318.413964) (xy 283.452818 -318.435062) (xy 283.493321 -318.463018) (xy 283.528814 -318.49711)
			(xy 283.558379 -318.536454) (xy 283.58125 -318.580031) (xy 283.596834 -318.626712) (xy 283.604729 -318.675289)
			(xy 283.605224 -318.699896) (xy 283.604729 -318.724503) (xy 283.60455 -318.725604) (xy 283.923228 -318.725604)
			(xy 283.923228 -318.674188) (xy 283.931271 -318.623406) (xy 283.947159 -318.574507) (xy 283.970502 -318.528695)
			(xy 284.000723 -318.487099) (xy 284.037079 -318.450743) (xy 284.078675 -318.420522) (xy 284.124487 -318.397179)
			(xy 284.173386 -318.381291) (xy 284.224168 -318.373248) (xy 284.275584 -318.373248) (xy 284.326366 -318.381291)
			(xy 284.375265 -318.397179) (xy 284.421077 -318.420522) (xy 284.462673 -318.450743) (xy 284.499029 -318.487099)
			(xy 284.52925 -318.528695) (xy 284.552593 -318.574507) (xy 284.568481 -318.623406) (xy 284.576524 -318.674188)
			(xy 284.577028 -318.699896) (xy 284.894032 -318.699896) (xy 284.897992 -318.650842) (xy 284.909769 -318.603058)
			(xy 284.92906 -318.557782) (xy 284.955363 -318.516186) (xy 284.987998 -318.479349) (xy 285.026119 -318.448224)
			(xy 285.06874 -318.423617) (xy 285.114756 -318.406165) (xy 285.162975 -318.396321) (xy 285.21215 -318.39434)
			(xy 285.261005 -318.400272) (xy 285.308276 -318.413964) (xy 285.352738 -318.435062) (xy 285.393241 -318.463018)
			(xy 285.428734 -318.49711) (xy 285.458299 -318.536454) (xy 285.48117 -318.580031) (xy 285.496754 -318.626712)
			(xy 285.504649 -318.675289) (xy 285.505144 -318.699896) (xy 285.504649 -318.724503) (xy 285.50447 -318.725604)
			(xy 285.823148 -318.725604) (xy 285.823148 -318.674188) (xy 285.831191 -318.623406) (xy 285.847079 -318.574507)
			(xy 285.870422 -318.528695) (xy 285.900643 -318.487099) (xy 285.936999 -318.450743) (xy 285.978595 -318.420522)
			(xy 286.024407 -318.397179) (xy 286.073306 -318.381291) (xy 286.124088 -318.373248) (xy 286.175504 -318.373248)
			(xy 286.226286 -318.381291) (xy 286.275185 -318.397179) (xy 286.320997 -318.420522) (xy 286.362593 -318.450743)
			(xy 286.398949 -318.487099) (xy 286.42917 -318.528695) (xy 286.452513 -318.574507) (xy 286.468401 -318.623406)
			(xy 286.476444 -318.674188) (xy 286.476948 -318.699896) (xy 286.793952 -318.699896) (xy 286.797912 -318.650842)
			(xy 286.809689 -318.603058) (xy 286.82898 -318.557782) (xy 286.855283 -318.516186) (xy 286.887918 -318.479349)
			(xy 286.926039 -318.448224) (xy 286.96866 -318.423617) (xy 287.014676 -318.406165) (xy 287.062895 -318.396321)
			(xy 287.11207 -318.39434) (xy 287.160925 -318.400272) (xy 287.208196 -318.413964) (xy 287.252658 -318.435062)
			(xy 287.293161 -318.463018) (xy 287.328654 -318.49711) (xy 287.358219 -318.536454) (xy 287.38109 -318.580031)
			(xy 287.396674 -318.626712) (xy 287.404569 -318.675289) (xy 287.405064 -318.699896) (xy 287.404569 -318.724503)
			(xy 287.40439 -318.725604) (xy 287.723068 -318.725604) (xy 287.723068 -318.674188) (xy 287.731111 -318.623406)
			(xy 287.746999 -318.574507) (xy 287.770342 -318.528695) (xy 287.800563 -318.487099) (xy 287.836919 -318.450743)
			(xy 287.878515 -318.420522) (xy 287.924327 -318.397179) (xy 287.973226 -318.381291) (xy 288.024008 -318.373248)
			(xy 288.075424 -318.373248) (xy 288.126206 -318.381291) (xy 288.175105 -318.397179) (xy 288.220917 -318.420522)
			(xy 288.262513 -318.450743) (xy 288.298869 -318.487099) (xy 288.32909 -318.528695) (xy 288.352433 -318.574507)
			(xy 288.368321 -318.623406) (xy 288.376364 -318.674188) (xy 288.376868 -318.699896) (xy 288.694126 -318.699896)
			(xy 288.698086 -318.650842) (xy 288.709863 -318.603058) (xy 288.729154 -318.557782) (xy 288.755457 -318.516186)
			(xy 288.788092 -318.479349) (xy 288.826213 -318.448224) (xy 288.868834 -318.423617) (xy 288.91485 -318.406165)
			(xy 288.963069 -318.396321) (xy 289.012244 -318.39434) (xy 289.061099 -318.400272) (xy 289.10837 -318.413964)
			(xy 289.152832 -318.435062) (xy 289.193335 -318.463018) (xy 289.228828 -318.49711) (xy 289.258393 -318.536454)
			(xy 289.281264 -318.580031) (xy 289.296848 -318.626712) (xy 289.304743 -318.675289) (xy 289.305238 -318.699896)
			(xy 289.304743 -318.724503) (xy 289.304564 -318.725604) (xy 289.623242 -318.725604) (xy 289.623242 -318.674188)
			(xy 289.631285 -318.623406) (xy 289.647173 -318.574507) (xy 289.670516 -318.528695) (xy 289.700737 -318.487099)
			(xy 289.737093 -318.450743) (xy 289.778689 -318.420522) (xy 289.824501 -318.397179) (xy 289.8734 -318.381291)
			(xy 289.924182 -318.373248) (xy 289.975598 -318.373248) (xy 290.02638 -318.381291) (xy 290.075279 -318.397179)
			(xy 290.121091 -318.420522) (xy 290.162687 -318.450743) (xy 290.199043 -318.487099) (xy 290.229264 -318.528695)
			(xy 290.252607 -318.574507) (xy 290.268495 -318.623406) (xy 290.276538 -318.674188) (xy 290.277042 -318.699896)
			(xy 290.594046 -318.699896) (xy 290.598006 -318.650842) (xy 290.609783 -318.603058) (xy 290.629074 -318.557782)
			(xy 290.655377 -318.516186) (xy 290.688012 -318.479349) (xy 290.726133 -318.448224) (xy 290.768754 -318.423617)
			(xy 290.81477 -318.406165) (xy 290.862989 -318.396321) (xy 290.912164 -318.39434) (xy 290.961019 -318.400272)
			(xy 291.00829 -318.413964) (xy 291.052752 -318.435062) (xy 291.093255 -318.463018) (xy 291.128748 -318.49711)
			(xy 291.158313 -318.536454) (xy 291.181184 -318.580031) (xy 291.196768 -318.626712) (xy 291.204663 -318.675289)
			(xy 291.205158 -318.699896) (xy 291.204663 -318.724503) (xy 291.204484 -318.725604) (xy 291.523162 -318.725604)
			(xy 291.523162 -318.674188) (xy 291.531205 -318.623406) (xy 291.547093 -318.574507) (xy 291.570436 -318.528695)
			(xy 291.600657 -318.487099) (xy 291.637013 -318.450743) (xy 291.678609 -318.420522) (xy 291.724421 -318.397179)
			(xy 291.77332 -318.381291) (xy 291.824102 -318.373248) (xy 291.875518 -318.373248) (xy 291.9263 -318.381291)
			(xy 291.975199 -318.397179) (xy 292.021011 -318.420522) (xy 292.062607 -318.450743) (xy 292.098963 -318.487099)
			(xy 292.129184 -318.528695) (xy 292.152527 -318.574507) (xy 292.168415 -318.623406) (xy 292.176458 -318.674188)
			(xy 292.176962 -318.699896) (xy 292.493966 -318.699896) (xy 292.497926 -318.650842) (xy 292.509703 -318.603058)
			(xy 292.528994 -318.557782) (xy 292.555297 -318.516186) (xy 292.587932 -318.479349) (xy 292.626053 -318.448224)
			(xy 292.668674 -318.423617) (xy 292.71469 -318.406165) (xy 292.762909 -318.396321) (xy 292.812084 -318.39434)
			(xy 292.860939 -318.400272) (xy 292.90821 -318.413964) (xy 292.952672 -318.435062) (xy 292.993175 -318.463018)
			(xy 293.028668 -318.49711) (xy 293.058233 -318.536454) (xy 293.081104 -318.580031) (xy 293.096688 -318.626712)
			(xy 293.104583 -318.675289) (xy 293.105078 -318.699896) (xy 293.104583 -318.724503) (xy 293.104404 -318.725604)
			(xy 293.423082 -318.725604) (xy 293.423082 -318.674188) (xy 293.431125 -318.623406) (xy 293.447013 -318.574507)
			(xy 293.470356 -318.528695) (xy 293.500577 -318.487099) (xy 293.536933 -318.450743) (xy 293.578529 -318.420522)
			(xy 293.624341 -318.397179) (xy 293.67324 -318.381291) (xy 293.724022 -318.373248) (xy 293.775438 -318.373248)
			(xy 293.82622 -318.381291) (xy 293.875119 -318.397179) (xy 293.920931 -318.420522) (xy 293.962527 -318.450743)
			(xy 293.998883 -318.487099) (xy 294.029104 -318.528695) (xy 294.052447 -318.574507) (xy 294.068335 -318.623406)
			(xy 294.076378 -318.674188) (xy 294.076882 -318.699896) (xy 294.393886 -318.699896) (xy 294.397846 -318.650842)
			(xy 294.409623 -318.603058) (xy 294.428914 -318.557782) (xy 294.455217 -318.516186) (xy 294.487852 -318.479349)
			(xy 294.525973 -318.448224) (xy 294.568594 -318.423617) (xy 294.61461 -318.406165) (xy 294.662829 -318.396321)
			(xy 294.712004 -318.39434) (xy 294.760859 -318.400272) (xy 294.80813 -318.413964) (xy 294.852592 -318.435062)
			(xy 294.893095 -318.463018) (xy 294.928588 -318.49711) (xy 294.958153 -318.536454) (xy 294.981024 -318.580031)
			(xy 294.996608 -318.626712) (xy 295.004503 -318.675289) (xy 295.004998 -318.699896) (xy 295.004503 -318.724503)
			(xy 295.004324 -318.725604) (xy 295.323256 -318.725604) (xy 295.323256 -318.674188) (xy 295.331299 -318.623406)
			(xy 295.347187 -318.574507) (xy 295.37053 -318.528695) (xy 295.400751 -318.487099) (xy 295.437107 -318.450743)
			(xy 295.478703 -318.420522) (xy 295.524515 -318.397179) (xy 295.573414 -318.381291) (xy 295.624196 -318.373248)
			(xy 295.675612 -318.373248) (xy 295.726394 -318.381291) (xy 295.775293 -318.397179) (xy 295.821105 -318.420522)
			(xy 295.862701 -318.450743) (xy 295.899057 -318.487099) (xy 295.929278 -318.528695) (xy 295.952621 -318.574507)
			(xy 295.968509 -318.623406) (xy 295.976552 -318.674188) (xy 295.977056 -318.699896) (xy 296.29406 -318.699896)
			(xy 296.29802 -318.650842) (xy 296.309797 -318.603058) (xy 296.329088 -318.557782) (xy 296.355391 -318.516186)
			(xy 296.388026 -318.479349) (xy 296.426147 -318.448224) (xy 296.468768 -318.423617) (xy 296.514784 -318.406165)
			(xy 296.563003 -318.396321) (xy 296.612178 -318.39434) (xy 296.661033 -318.400272) (xy 296.708304 -318.413964)
			(xy 296.752766 -318.435062) (xy 296.793269 -318.463018) (xy 296.828762 -318.49711) (xy 296.858327 -318.536454)
			(xy 296.881198 -318.580031) (xy 296.896782 -318.626712) (xy 296.904677 -318.675289) (xy 296.905172 -318.699896)
			(xy 296.904677 -318.724503) (xy 296.904498 -318.725604) (xy 297.223176 -318.725604) (xy 297.223176 -318.674188)
			(xy 297.231219 -318.623406) (xy 297.247107 -318.574507) (xy 297.27045 -318.528695) (xy 297.300671 -318.487099)
			(xy 297.337027 -318.450743) (xy 297.378623 -318.420522) (xy 297.424435 -318.397179) (xy 297.473334 -318.381291)
			(xy 297.524116 -318.373248) (xy 297.575532 -318.373248) (xy 297.626314 -318.381291) (xy 297.675213 -318.397179)
			(xy 297.721025 -318.420522) (xy 297.762621 -318.450743) (xy 297.798977 -318.487099) (xy 297.829198 -318.528695)
			(xy 297.852541 -318.574507) (xy 297.868429 -318.623406) (xy 297.876472 -318.674188) (xy 297.876976 -318.699896)
			(xy 298.19398 -318.699896) (xy 298.19794 -318.650842) (xy 298.209717 -318.603058) (xy 298.229008 -318.557782)
			(xy 298.255311 -318.516186) (xy 298.287946 -318.479349) (xy 298.326067 -318.448224) (xy 298.368688 -318.423617)
			(xy 298.414704 -318.406165) (xy 298.462923 -318.396321) (xy 298.512098 -318.39434) (xy 298.560953 -318.400272)
			(xy 298.608224 -318.413964) (xy 298.652686 -318.435062) (xy 298.693189 -318.463018) (xy 298.728682 -318.49711)
			(xy 298.758247 -318.536454) (xy 298.781118 -318.580031) (xy 298.796702 -318.626712) (xy 298.804597 -318.675289)
			(xy 298.805092 -318.699896) (xy 298.804597 -318.724503) (xy 298.804418 -318.725604) (xy 299.123096 -318.725604)
			(xy 299.123096 -318.674188) (xy 299.131139 -318.623406) (xy 299.147027 -318.574507) (xy 299.17037 -318.528695)
			(xy 299.200591 -318.487099) (xy 299.236947 -318.450743) (xy 299.278543 -318.420522) (xy 299.324355 -318.397179)
			(xy 299.373254 -318.381291) (xy 299.424036 -318.373248) (xy 299.475452 -318.373248) (xy 299.526234 -318.381291)
			(xy 299.575133 -318.397179) (xy 299.620945 -318.420522) (xy 299.662541 -318.450743) (xy 299.698897 -318.487099)
			(xy 299.729118 -318.528695) (xy 299.752461 -318.574507) (xy 299.768349 -318.623406) (xy 299.776392 -318.674188)
			(xy 299.776896 -318.699896) (xy 300.0939 -318.699896) (xy 300.09786 -318.650842) (xy 300.109637 -318.603058)
			(xy 300.128928 -318.557782) (xy 300.155231 -318.516186) (xy 300.187866 -318.479349) (xy 300.225987 -318.448224)
			(xy 300.268608 -318.423617) (xy 300.314624 -318.406165) (xy 300.362843 -318.396321) (xy 300.412018 -318.39434)
			(xy 300.460873 -318.400272) (xy 300.508144 -318.413964) (xy 300.552606 -318.435062) (xy 300.593109 -318.463018)
			(xy 300.628602 -318.49711) (xy 300.658167 -318.536454) (xy 300.681038 -318.580031) (xy 300.696622 -318.626712)
			(xy 300.704517 -318.675289) (xy 300.705012 -318.699896) (xy 300.704517 -318.724503) (xy 300.704338 -318.725604)
			(xy 301.02327 -318.725604) (xy 301.02327 -318.674188) (xy 301.031313 -318.623406) (xy 301.047201 -318.574507)
			(xy 301.070544 -318.528695) (xy 301.100765 -318.487099) (xy 301.137121 -318.450743) (xy 301.178717 -318.420522)
			(xy 301.224529 -318.397179) (xy 301.273428 -318.381291) (xy 301.32421 -318.373248) (xy 301.375626 -318.373248)
			(xy 301.426408 -318.381291) (xy 301.475307 -318.397179) (xy 301.521119 -318.420522) (xy 301.562715 -318.450743)
			(xy 301.599071 -318.487099) (xy 301.629292 -318.528695) (xy 301.652635 -318.574507) (xy 301.668523 -318.623406)
			(xy 301.676566 -318.674188) (xy 301.67707 -318.699896) (xy 301.994074 -318.699896) (xy 301.998034 -318.650842)
			(xy 302.009811 -318.603058) (xy 302.029102 -318.557782) (xy 302.055405 -318.516186) (xy 302.08804 -318.479349)
			(xy 302.126161 -318.448224) (xy 302.168782 -318.423617) (xy 302.214798 -318.406165) (xy 302.263017 -318.396321)
			(xy 302.312192 -318.39434) (xy 302.361047 -318.400272) (xy 302.408318 -318.413964) (xy 302.45278 -318.435062)
			(xy 302.493283 -318.463018) (xy 302.528776 -318.49711) (xy 302.558341 -318.536454) (xy 302.581212 -318.580031)
			(xy 302.596796 -318.626712) (xy 302.604691 -318.675289) (xy 302.605186 -318.699896) (xy 302.604691 -318.724503)
			(xy 302.604512 -318.725604) (xy 302.92319 -318.725604) (xy 302.92319 -318.674188) (xy 302.931233 -318.623406)
			(xy 302.947121 -318.574507) (xy 302.970464 -318.528695) (xy 303.000685 -318.487099) (xy 303.037041 -318.450743)
			(xy 303.078637 -318.420522) (xy 303.124449 -318.397179) (xy 303.173348 -318.381291) (xy 303.22413 -318.373248)
			(xy 303.275546 -318.373248) (xy 303.326328 -318.381291) (xy 303.375227 -318.397179) (xy 303.421039 -318.420522)
			(xy 303.462635 -318.450743) (xy 303.498991 -318.487099) (xy 303.529212 -318.528695) (xy 303.552555 -318.574507)
			(xy 303.568443 -318.623406) (xy 303.576486 -318.674188) (xy 303.57699 -318.699896) (xy 303.576486 -318.725604)
			(xy 303.568443 -318.776386) (xy 303.552555 -318.825285) (xy 303.529212 -318.871097) (xy 303.498991 -318.912693)
			(xy 303.462635 -318.949049) (xy 303.421039 -318.97927) (xy 303.375227 -319.002613) (xy 303.326328 -319.018501)
			(xy 303.275546 -319.026544) (xy 303.22413 -319.026544) (xy 303.173348 -319.018501) (xy 303.124449 -319.002613)
			(xy 303.078637 -318.97927) (xy 303.037041 -318.949049) (xy 303.000685 -318.912693) (xy 302.970464 -318.871097)
			(xy 302.947121 -318.825285) (xy 302.931233 -318.776386) (xy 302.92319 -318.725604) (xy 302.604512 -318.725604)
			(xy 302.596796 -318.77308) (xy 302.581212 -318.819761) (xy 302.558341 -318.863338) (xy 302.528776 -318.902682)
			(xy 302.493283 -318.936774) (xy 302.45278 -318.96473) (xy 302.408318 -318.985828) (xy 302.361047 -318.99952)
			(xy 302.312192 -319.005452) (xy 302.263017 -319.003471) (xy 302.214798 -318.993627) (xy 302.168782 -318.976175)
			(xy 302.126161 -318.951568) (xy 302.08804 -318.920443) (xy 302.055405 -318.883606) (xy 302.029102 -318.84201)
			(xy 302.009811 -318.796734) (xy 301.998034 -318.74895) (xy 301.994074 -318.699896) (xy 301.67707 -318.699896)
			(xy 301.676566 -318.725604) (xy 301.668523 -318.776386) (xy 301.652635 -318.825285) (xy 301.629292 -318.871097)
			(xy 301.599071 -318.912693) (xy 301.562715 -318.949049) (xy 301.521119 -318.97927) (xy 301.475307 -319.002613)
			(xy 301.426408 -319.018501) (xy 301.375626 -319.026544) (xy 301.32421 -319.026544) (xy 301.273428 -319.018501)
			(xy 301.224529 -319.002613) (xy 301.178717 -318.97927) (xy 301.137121 -318.949049) (xy 301.100765 -318.912693)
			(xy 301.070544 -318.871097) (xy 301.047201 -318.825285) (xy 301.031313 -318.776386) (xy 301.02327 -318.725604)
			(xy 300.704338 -318.725604) (xy 300.696622 -318.77308) (xy 300.681038 -318.819761) (xy 300.658167 -318.863338)
			(xy 300.628602 -318.902682) (xy 300.593109 -318.936774) (xy 300.552606 -318.96473) (xy 300.508144 -318.985828)
			(xy 300.460873 -318.99952) (xy 300.412018 -319.005452) (xy 300.362843 -319.003471) (xy 300.314624 -318.993627)
			(xy 300.268608 -318.976175) (xy 300.225987 -318.951568) (xy 300.187866 -318.920443) (xy 300.155231 -318.883606)
			(xy 300.128928 -318.84201) (xy 300.109637 -318.796734) (xy 300.09786 -318.74895) (xy 300.0939 -318.699896)
			(xy 299.776896 -318.699896) (xy 299.776392 -318.725604) (xy 299.768349 -318.776386) (xy 299.752461 -318.825285)
			(xy 299.729118 -318.871097) (xy 299.698897 -318.912693) (xy 299.662541 -318.949049) (xy 299.620945 -318.97927)
			(xy 299.575133 -319.002613) (xy 299.526234 -319.018501) (xy 299.475452 -319.026544) (xy 299.424036 -319.026544)
			(xy 299.373254 -319.018501) (xy 299.324355 -319.002613) (xy 299.278543 -318.97927) (xy 299.236947 -318.949049)
			(xy 299.200591 -318.912693) (xy 299.17037 -318.871097) (xy 299.147027 -318.825285) (xy 299.131139 -318.776386)
			(xy 299.123096 -318.725604) (xy 298.804418 -318.725604) (xy 298.796702 -318.77308) (xy 298.781118 -318.819761)
			(xy 298.758247 -318.863338) (xy 298.728682 -318.902682) (xy 298.693189 -318.936774) (xy 298.652686 -318.96473)
			(xy 298.608224 -318.985828) (xy 298.560953 -318.99952) (xy 298.512098 -319.005452) (xy 298.462923 -319.003471)
			(xy 298.414704 -318.993627) (xy 298.368688 -318.976175) (xy 298.326067 -318.951568) (xy 298.287946 -318.920443)
			(xy 298.255311 -318.883606) (xy 298.229008 -318.84201) (xy 298.209717 -318.796734) (xy 298.19794 -318.74895)
			(xy 298.19398 -318.699896) (xy 297.876976 -318.699896) (xy 297.876472 -318.725604) (xy 297.868429 -318.776386)
			(xy 297.852541 -318.825285) (xy 297.829198 -318.871097) (xy 297.798977 -318.912693) (xy 297.762621 -318.949049)
			(xy 297.721025 -318.97927) (xy 297.675213 -319.002613) (xy 297.626314 -319.018501) (xy 297.575532 -319.026544)
			(xy 297.524116 -319.026544) (xy 297.473334 -319.018501) (xy 297.424435 -319.002613) (xy 297.378623 -318.97927)
			(xy 297.337027 -318.949049) (xy 297.300671 -318.912693) (xy 297.27045 -318.871097) (xy 297.247107 -318.825285)
			(xy 297.231219 -318.776386) (xy 297.223176 -318.725604) (xy 296.904498 -318.725604) (xy 296.896782 -318.77308)
			(xy 296.881198 -318.819761) (xy 296.858327 -318.863338) (xy 296.828762 -318.902682) (xy 296.793269 -318.936774)
			(xy 296.752766 -318.96473) (xy 296.708304 -318.985828) (xy 296.661033 -318.99952) (xy 296.612178 -319.005452)
			(xy 296.563003 -319.003471) (xy 296.514784 -318.993627) (xy 296.468768 -318.976175) (xy 296.426147 -318.951568)
			(xy 296.388026 -318.920443) (xy 296.355391 -318.883606) (xy 296.329088 -318.84201) (xy 296.309797 -318.796734)
			(xy 296.29802 -318.74895) (xy 296.29406 -318.699896) (xy 295.977056 -318.699896) (xy 295.976552 -318.725604)
			(xy 295.968509 -318.776386) (xy 295.952621 -318.825285) (xy 295.929278 -318.871097) (xy 295.899057 -318.912693)
			(xy 295.862701 -318.949049) (xy 295.821105 -318.97927) (xy 295.775293 -319.002613) (xy 295.726394 -319.018501)
			(xy 295.675612 -319.026544) (xy 295.624196 -319.026544) (xy 295.573414 -319.018501) (xy 295.524515 -319.002613)
			(xy 295.478703 -318.97927) (xy 295.437107 -318.949049) (xy 295.400751 -318.912693) (xy 295.37053 -318.871097)
			(xy 295.347187 -318.825285) (xy 295.331299 -318.776386) (xy 295.323256 -318.725604) (xy 295.004324 -318.725604)
			(xy 294.996608 -318.77308) (xy 294.981024 -318.819761) (xy 294.958153 -318.863338) (xy 294.928588 -318.902682)
			(xy 294.893095 -318.936774) (xy 294.852592 -318.96473) (xy 294.80813 -318.985828) (xy 294.760859 -318.99952)
			(xy 294.712004 -319.005452) (xy 294.662829 -319.003471) (xy 294.61461 -318.993627) (xy 294.568594 -318.976175)
			(xy 294.525973 -318.951568) (xy 294.487852 -318.920443) (xy 294.455217 -318.883606) (xy 294.428914 -318.84201)
			(xy 294.409623 -318.796734) (xy 294.397846 -318.74895) (xy 294.393886 -318.699896) (xy 294.076882 -318.699896)
			(xy 294.076378 -318.725604) (xy 294.068335 -318.776386) (xy 294.052447 -318.825285) (xy 294.029104 -318.871097)
			(xy 293.998883 -318.912693) (xy 293.962527 -318.949049) (xy 293.920931 -318.97927) (xy 293.875119 -319.002613)
			(xy 293.82622 -319.018501) (xy 293.775438 -319.026544) (xy 293.724022 -319.026544) (xy 293.67324 -319.018501)
			(xy 293.624341 -319.002613) (xy 293.578529 -318.97927) (xy 293.536933 -318.949049) (xy 293.500577 -318.912693)
			(xy 293.470356 -318.871097) (xy 293.447013 -318.825285) (xy 293.431125 -318.776386) (xy 293.423082 -318.725604)
			(xy 293.104404 -318.725604) (xy 293.096688 -318.77308) (xy 293.081104 -318.819761) (xy 293.058233 -318.863338)
			(xy 293.028668 -318.902682) (xy 292.993175 -318.936774) (xy 292.952672 -318.96473) (xy 292.90821 -318.985828)
			(xy 292.860939 -318.99952) (xy 292.812084 -319.005452) (xy 292.762909 -319.003471) (xy 292.71469 -318.993627)
			(xy 292.668674 -318.976175) (xy 292.626053 -318.951568) (xy 292.587932 -318.920443) (xy 292.555297 -318.883606)
			(xy 292.528994 -318.84201) (xy 292.509703 -318.796734) (xy 292.497926 -318.74895) (xy 292.493966 -318.699896)
			(xy 292.176962 -318.699896) (xy 292.176458 -318.725604) (xy 292.168415 -318.776386) (xy 292.152527 -318.825285)
			(xy 292.129184 -318.871097) (xy 292.098963 -318.912693) (xy 292.062607 -318.949049) (xy 292.021011 -318.97927)
			(xy 291.975199 -319.002613) (xy 291.9263 -319.018501) (xy 291.875518 -319.026544) (xy 291.824102 -319.026544)
			(xy 291.77332 -319.018501) (xy 291.724421 -319.002613) (xy 291.678609 -318.97927) (xy 291.637013 -318.949049)
			(xy 291.600657 -318.912693) (xy 291.570436 -318.871097) (xy 291.547093 -318.825285) (xy 291.531205 -318.776386)
			(xy 291.523162 -318.725604) (xy 291.204484 -318.725604) (xy 291.196768 -318.77308) (xy 291.181184 -318.819761)
			(xy 291.158313 -318.863338) (xy 291.128748 -318.902682) (xy 291.093255 -318.936774) (xy 291.052752 -318.96473)
			(xy 291.00829 -318.985828) (xy 290.961019 -318.99952) (xy 290.912164 -319.005452) (xy 290.862989 -319.003471)
			(xy 290.81477 -318.993627) (xy 290.768754 -318.976175) (xy 290.726133 -318.951568) (xy 290.688012 -318.920443)
			(xy 290.655377 -318.883606) (xy 290.629074 -318.84201) (xy 290.609783 -318.796734) (xy 290.598006 -318.74895)
			(xy 290.594046 -318.699896) (xy 290.277042 -318.699896) (xy 290.276538 -318.725604) (xy 290.268495 -318.776386)
			(xy 290.252607 -318.825285) (xy 290.229264 -318.871097) (xy 290.199043 -318.912693) (xy 290.162687 -318.949049)
			(xy 290.121091 -318.97927) (xy 290.075279 -319.002613) (xy 290.02638 -319.018501) (xy 289.975598 -319.026544)
			(xy 289.924182 -319.026544) (xy 289.8734 -319.018501) (xy 289.824501 -319.002613) (xy 289.778689 -318.97927)
			(xy 289.737093 -318.949049) (xy 289.700737 -318.912693) (xy 289.670516 -318.871097) (xy 289.647173 -318.825285)
			(xy 289.631285 -318.776386) (xy 289.623242 -318.725604) (xy 289.304564 -318.725604) (xy 289.296848 -318.77308)
			(xy 289.281264 -318.819761) (xy 289.258393 -318.863338) (xy 289.228828 -318.902682) (xy 289.193335 -318.936774)
			(xy 289.152832 -318.96473) (xy 289.10837 -318.985828) (xy 289.061099 -318.99952) (xy 289.012244 -319.005452)
			(xy 288.963069 -319.003471) (xy 288.91485 -318.993627) (xy 288.868834 -318.976175) (xy 288.826213 -318.951568)
			(xy 288.788092 -318.920443) (xy 288.755457 -318.883606) (xy 288.729154 -318.84201) (xy 288.709863 -318.796734)
			(xy 288.698086 -318.74895) (xy 288.694126 -318.699896) (xy 288.376868 -318.699896) (xy 288.376364 -318.725604)
			(xy 288.368321 -318.776386) (xy 288.352433 -318.825285) (xy 288.32909 -318.871097) (xy 288.298869 -318.912693)
			(xy 288.262513 -318.949049) (xy 288.220917 -318.97927) (xy 288.175105 -319.002613) (xy 288.126206 -319.018501)
			(xy 288.075424 -319.026544) (xy 288.024008 -319.026544) (xy 287.973226 -319.018501) (xy 287.924327 -319.002613)
			(xy 287.878515 -318.97927) (xy 287.836919 -318.949049) (xy 287.800563 -318.912693) (xy 287.770342 -318.871097)
			(xy 287.746999 -318.825285) (xy 287.731111 -318.776386) (xy 287.723068 -318.725604) (xy 287.40439 -318.725604)
			(xy 287.396674 -318.77308) (xy 287.38109 -318.819761) (xy 287.358219 -318.863338) (xy 287.328654 -318.902682)
			(xy 287.293161 -318.936774) (xy 287.252658 -318.96473) (xy 287.208196 -318.985828) (xy 287.160925 -318.99952)
			(xy 287.11207 -319.005452) (xy 287.062895 -319.003471) (xy 287.014676 -318.993627) (xy 286.96866 -318.976175)
			(xy 286.926039 -318.951568) (xy 286.887918 -318.920443) (xy 286.855283 -318.883606) (xy 286.82898 -318.84201)
			(xy 286.809689 -318.796734) (xy 286.797912 -318.74895) (xy 286.793952 -318.699896) (xy 286.476948 -318.699896)
			(xy 286.476444 -318.725604) (xy 286.468401 -318.776386) (xy 286.452513 -318.825285) (xy 286.42917 -318.871097)
			(xy 286.398949 -318.912693) (xy 286.362593 -318.949049) (xy 286.320997 -318.97927) (xy 286.275185 -319.002613)
			(xy 286.226286 -319.018501) (xy 286.175504 -319.026544) (xy 286.124088 -319.026544) (xy 286.073306 -319.018501)
			(xy 286.024407 -319.002613) (xy 285.978595 -318.97927) (xy 285.936999 -318.949049) (xy 285.900643 -318.912693)
			(xy 285.870422 -318.871097) (xy 285.847079 -318.825285) (xy 285.831191 -318.776386) (xy 285.823148 -318.725604)
			(xy 285.50447 -318.725604) (xy 285.496754 -318.77308) (xy 285.48117 -318.819761) (xy 285.458299 -318.863338)
			(xy 285.428734 -318.902682) (xy 285.393241 -318.936774) (xy 285.352738 -318.96473) (xy 285.308276 -318.985828)
			(xy 285.261005 -318.99952) (xy 285.21215 -319.005452) (xy 285.162975 -319.003471) (xy 285.114756 -318.993627)
			(xy 285.06874 -318.976175) (xy 285.026119 -318.951568) (xy 284.987998 -318.920443) (xy 284.955363 -318.883606)
			(xy 284.92906 -318.84201) (xy 284.909769 -318.796734) (xy 284.897992 -318.74895) (xy 284.894032 -318.699896)
			(xy 284.577028 -318.699896) (xy 284.576524 -318.725604) (xy 284.568481 -318.776386) (xy 284.552593 -318.825285)
			(xy 284.52925 -318.871097) (xy 284.499029 -318.912693) (xy 284.462673 -318.949049) (xy 284.421077 -318.97927)
			(xy 284.375265 -319.002613) (xy 284.326366 -319.018501) (xy 284.275584 -319.026544) (xy 284.224168 -319.026544)
			(xy 284.173386 -319.018501) (xy 284.124487 -319.002613) (xy 284.078675 -318.97927) (xy 284.037079 -318.949049)
			(xy 284.000723 -318.912693) (xy 283.970502 -318.871097) (xy 283.947159 -318.825285) (xy 283.931271 -318.776386)
			(xy 283.923228 -318.725604) (xy 283.60455 -318.725604) (xy 283.596834 -318.77308) (xy 283.58125 -318.819761)
			(xy 283.558379 -318.863338) (xy 283.528814 -318.902682) (xy 283.493321 -318.936774) (xy 283.452818 -318.96473)
			(xy 283.408356 -318.985828) (xy 283.361085 -318.99952) (xy 283.31223 -319.005452) (xy 283.263055 -319.003471)
			(xy 283.214836 -318.993627) (xy 283.16882 -318.976175) (xy 283.126199 -318.951568) (xy 283.088078 -318.920443)
			(xy 283.055443 -318.883606) (xy 283.02914 -318.84201) (xy 283.009849 -318.796734) (xy 282.998072 -318.74895)
			(xy 282.994112 -318.699896) (xy 282.676854 -318.699896) (xy 282.67635 -318.725604) (xy 282.668307 -318.776386)
			(xy 282.652419 -318.825285) (xy 282.629076 -318.871097) (xy 282.598855 -318.912693) (xy 282.562499 -318.949049)
			(xy 282.520903 -318.97927) (xy 282.475091 -319.002613) (xy 282.426192 -319.018501) (xy 282.37541 -319.026544)
			(xy 282.323994 -319.026544) (xy 282.273212 -319.018501) (xy 282.224313 -319.002613) (xy 282.178501 -318.97927)
			(xy 282.136905 -318.949049) (xy 282.100549 -318.912693) (xy 282.070328 -318.871097) (xy 282.046985 -318.825285)
			(xy 282.031097 -318.776386) (xy 282.023054 -318.725604) (xy 281.704376 -318.725604) (xy 281.69666 -318.77308)
			(xy 281.681076 -318.819761) (xy 281.658205 -318.863338) (xy 281.62864 -318.902682) (xy 281.593147 -318.936774)
			(xy 281.552644 -318.96473) (xy 281.508182 -318.985828) (xy 281.460911 -318.99952) (xy 281.412056 -319.005452)
			(xy 281.362881 -319.003471) (xy 281.314662 -318.993627) (xy 281.268646 -318.976175) (xy 281.226025 -318.951568)
			(xy 281.187904 -318.920443) (xy 281.155269 -318.883606) (xy 281.128966 -318.84201) (xy 281.109675 -318.796734)
			(xy 281.097898 -318.74895) (xy 281.093938 -318.699896) (xy 280.776934 -318.699896) (xy 280.77643 -318.725604)
			(xy 280.768387 -318.776386) (xy 280.752499 -318.825285) (xy 280.729156 -318.871097) (xy 280.698935 -318.912693)
			(xy 280.662579 -318.949049) (xy 280.620983 -318.97927) (xy 280.575171 -319.002613) (xy 280.526272 -319.018501)
			(xy 280.47549 -319.026544) (xy 280.424074 -319.026544) (xy 280.373292 -319.018501) (xy 280.324393 -319.002613)
			(xy 280.278581 -318.97927) (xy 280.236985 -318.949049) (xy 280.200629 -318.912693) (xy 280.170408 -318.871097)
			(xy 280.147065 -318.825285) (xy 280.131177 -318.776386) (xy 280.123134 -318.725604) (xy 279.804456 -318.725604)
			(xy 279.79674 -318.77308) (xy 279.781156 -318.819761) (xy 279.758285 -318.863338) (xy 279.72872 -318.902682)
			(xy 279.693227 -318.936774) (xy 279.652724 -318.96473) (xy 279.608262 -318.985828) (xy 279.560991 -318.99952)
			(xy 279.512136 -319.005452) (xy 279.462961 -319.003471) (xy 279.414742 -318.993627) (xy 279.368726 -318.976175)
			(xy 279.326105 -318.951568) (xy 279.287984 -318.920443) (xy 279.255349 -318.883606) (xy 279.229046 -318.84201)
			(xy 279.209755 -318.796734) (xy 279.197978 -318.74895) (xy 279.194018 -318.699896) (xy 278.877014 -318.699896)
			(xy 278.87651 -318.725604) (xy 278.868467 -318.776386) (xy 278.852579 -318.825285) (xy 278.829236 -318.871097)
			(xy 278.799015 -318.912693) (xy 278.762659 -318.949049) (xy 278.721063 -318.97927) (xy 278.675251 -319.002613)
			(xy 278.626352 -319.018501) (xy 278.57557 -319.026544) (xy 278.524154 -319.026544) (xy 278.473372 -319.018501)
			(xy 278.424473 -319.002613) (xy 278.378661 -318.97927) (xy 278.337065 -318.949049) (xy 278.300709 -318.912693)
			(xy 278.270488 -318.871097) (xy 278.247145 -318.825285) (xy 278.231257 -318.776386) (xy 278.223214 -318.725604)
			(xy 277.904536 -318.725604) (xy 277.89682 -318.77308) (xy 277.881236 -318.819761) (xy 277.858365 -318.863338)
			(xy 277.8288 -318.902682) (xy 277.793307 -318.936774) (xy 277.752804 -318.96473) (xy 277.708342 -318.985828)
			(xy 277.661071 -318.99952) (xy 277.612216 -319.005452) (xy 277.563041 -319.003471) (xy 277.514822 -318.993627)
			(xy 277.468806 -318.976175) (xy 277.426185 -318.951568) (xy 277.388064 -318.920443) (xy 277.355429 -318.883606)
			(xy 277.329126 -318.84201) (xy 277.309835 -318.796734) (xy 277.298058 -318.74895) (xy 277.294098 -318.699896)
			(xy 276.97684 -318.699896) (xy 276.976336 -318.725604) (xy 276.968293 -318.776386) (xy 276.952405 -318.825285)
			(xy 276.929062 -318.871097) (xy 276.898841 -318.912693) (xy 276.862485 -318.949049) (xy 276.820889 -318.97927)
			(xy 276.775077 -319.002613) (xy 276.726178 -319.018501) (xy 276.675396 -319.026544) (xy 276.62398 -319.026544)
			(xy 276.573198 -319.018501) (xy 276.524299 -319.002613) (xy 276.478487 -318.97927) (xy 276.436891 -318.949049)
			(xy 276.400535 -318.912693) (xy 276.370314 -318.871097) (xy 276.346971 -318.825285) (xy 276.331083 -318.776386)
			(xy 276.32304 -318.725604) (xy 276.004362 -318.725604) (xy 275.996646 -318.77308) (xy 275.981062 -318.819761)
			(xy 275.958191 -318.863338) (xy 275.928626 -318.902682) (xy 275.893133 -318.936774) (xy 275.85263 -318.96473)
			(xy 275.808168 -318.985828) (xy 275.760897 -318.99952) (xy 275.712042 -319.005452) (xy 275.662867 -319.003471)
			(xy 275.614648 -318.993627) (xy 275.568632 -318.976175) (xy 275.526011 -318.951568) (xy 275.48789 -318.920443)
			(xy 275.455255 -318.883606) (xy 275.428952 -318.84201) (xy 275.409661 -318.796734) (xy 275.397884 -318.74895)
			(xy 275.393924 -318.699896) (xy 275.07692 -318.699896) (xy 275.076416 -318.725604) (xy 275.068373 -318.776386)
			(xy 275.052485 -318.825285) (xy 275.029142 -318.871097) (xy 274.998921 -318.912693) (xy 274.962565 -318.949049)
			(xy 274.920969 -318.97927) (xy 274.875157 -319.002613) (xy 274.826258 -319.018501) (xy 274.775476 -319.026544)
			(xy 274.72406 -319.026544) (xy 274.673278 -319.018501) (xy 274.624379 -319.002613) (xy 274.578567 -318.97927)
			(xy 274.536971 -318.949049) (xy 274.500615 -318.912693) (xy 274.470394 -318.871097) (xy 274.447051 -318.825285)
			(xy 274.431163 -318.776386) (xy 274.42312 -318.725604) (xy 274.104442 -318.725604) (xy 274.096726 -318.77308)
			(xy 274.081142 -318.819761) (xy 274.058271 -318.863338) (xy 274.028706 -318.902682) (xy 273.993213 -318.936774)
			(xy 273.95271 -318.96473) (xy 273.908248 -318.985828) (xy 273.860977 -318.99952) (xy 273.812122 -319.005452)
			(xy 273.762947 -319.003471) (xy 273.714728 -318.993627) (xy 273.668712 -318.976175) (xy 273.626091 -318.951568)
			(xy 273.58797 -318.920443) (xy 273.555335 -318.883606) (xy 273.529032 -318.84201) (xy 273.509741 -318.796734)
			(xy 273.497964 -318.74895) (xy 273.494004 -318.699896) (xy 273.177 -318.699896) (xy 273.176496 -318.725604)
			(xy 273.168453 -318.776386) (xy 273.152565 -318.825285) (xy 273.129222 -318.871097) (xy 273.099001 -318.912693)
			(xy 273.062645 -318.949049) (xy 273.021049 -318.97927) (xy 272.975237 -319.002613) (xy 272.926338 -319.018501)
			(xy 272.875556 -319.026544) (xy 272.82414 -319.026544) (xy 272.773358 -319.018501) (xy 272.724459 -319.002613)
			(xy 272.678647 -318.97927) (xy 272.637051 -318.949049) (xy 272.600695 -318.912693) (xy 272.570474 -318.871097)
			(xy 272.547131 -318.825285) (xy 272.531243 -318.776386) (xy 272.5232 -318.725604) (xy 272.204522 -318.725604)
			(xy 272.196806 -318.77308) (xy 272.181222 -318.819761) (xy 272.158351 -318.863338) (xy 272.128786 -318.902682)
			(xy 272.093293 -318.936774) (xy 272.05279 -318.96473) (xy 272.008328 -318.985828) (xy 271.961057 -318.99952)
			(xy 271.912202 -319.005452) (xy 271.863027 -319.003471) (xy 271.814808 -318.993627) (xy 271.768792 -318.976175)
			(xy 271.726171 -318.951568) (xy 271.68805 -318.920443) (xy 271.655415 -318.883606) (xy 271.629112 -318.84201)
			(xy 271.609821 -318.796734) (xy 271.598044 -318.74895) (xy 271.594084 -318.699896) (xy 271.27708 -318.699896)
			(xy 271.276576 -318.725604) (xy 271.268533 -318.776386) (xy 271.252645 -318.825285) (xy 271.229302 -318.871097)
			(xy 271.199081 -318.912693) (xy 271.162725 -318.949049) (xy 271.121129 -318.97927) (xy 271.075317 -319.002613)
			(xy 271.026418 -319.018501) (xy 270.975636 -319.026544) (xy 270.92422 -319.026544) (xy 270.873438 -319.018501)
			(xy 270.824539 -319.002613) (xy 270.778727 -318.97927) (xy 270.737131 -318.949049) (xy 270.700775 -318.912693)
			(xy 270.670554 -318.871097) (xy 270.647211 -318.825285) (xy 270.631323 -318.776386) (xy 270.62328 -318.725604)
			(xy 270.304348 -318.725604) (xy 270.296632 -318.77308) (xy 270.281048 -318.819761) (xy 270.258177 -318.863338)
			(xy 270.228612 -318.902682) (xy 270.193119 -318.936774) (xy 270.152616 -318.96473) (xy 270.108154 -318.985828)
			(xy 270.060883 -318.99952) (xy 270.012028 -319.005452) (xy 269.962853 -319.003471) (xy 269.914634 -318.993627)
			(xy 269.868618 -318.976175) (xy 269.825997 -318.951568) (xy 269.787876 -318.920443) (xy 269.755241 -318.883606)
			(xy 269.728938 -318.84201) (xy 269.709647 -318.796734) (xy 269.69787 -318.74895) (xy 269.69391 -318.699896)
			(xy 266.08863 -318.699896) (xy 266.110141 -318.740263) (xy 266.19469 -318.915831) (xy 266.272007 -319.094702)
			(xy 266.341965 -319.276577) (xy 266.404445 -319.461154) (xy 266.459345 -319.648126) (xy 266.459841 -319.65011)
			(xy 270.644124 -319.65011) (xy 270.648084 -319.601056) (xy 270.659861 -319.553272) (xy 270.679152 -319.507996)
			(xy 270.705455 -319.4664) (xy 270.73809 -319.429563) (xy 270.776211 -319.398438) (xy 270.818832 -319.373831)
			(xy 270.864848 -319.356379) (xy 270.913067 -319.346535) (xy 270.962242 -319.344554) (xy 271.011097 -319.350486)
			(xy 271.058368 -319.364178) (xy 271.10283 -319.385276) (xy 271.143333 -319.413232) (xy 271.178826 -319.447324)
			(xy 271.208391 -319.486668) (xy 271.231262 -319.530245) (xy 271.246846 -319.576926) (xy 271.254741 -319.625503)
			(xy 271.255236 -319.65011) (xy 272.544044 -319.65011) (xy 272.548004 -319.601056) (xy 272.559781 -319.553272)
			(xy 272.579072 -319.507996) (xy 272.605375 -319.4664) (xy 272.63801 -319.429563) (xy 272.676131 -319.398438)
			(xy 272.718752 -319.373831) (xy 272.764768 -319.356379) (xy 272.812987 -319.346535) (xy 272.862162 -319.344554)
			(xy 272.911017 -319.350486) (xy 272.958288 -319.364178) (xy 273.00275 -319.385276) (xy 273.043253 -319.413232)
			(xy 273.078746 -319.447324) (xy 273.108311 -319.486668) (xy 273.131182 -319.530245) (xy 273.146766 -319.576926)
			(xy 273.154661 -319.625503) (xy 273.155156 -319.65011) (xy 274.443964 -319.65011) (xy 274.447924 -319.601056)
			(xy 274.459701 -319.553272) (xy 274.478992 -319.507996) (xy 274.505295 -319.4664) (xy 274.53793 -319.429563)
			(xy 274.576051 -319.398438) (xy 274.618672 -319.373831) (xy 274.664688 -319.356379) (xy 274.712907 -319.346535)
			(xy 274.762082 -319.344554) (xy 274.810937 -319.350486) (xy 274.858208 -319.364178) (xy 274.90267 -319.385276)
			(xy 274.943173 -319.413232) (xy 274.978666 -319.447324) (xy 275.008231 -319.486668) (xy 275.031102 -319.530245)
			(xy 275.046686 -319.576926) (xy 275.054581 -319.625503) (xy 275.055076 -319.65011) (xy 276.344138 -319.65011)
			(xy 276.348098 -319.601056) (xy 276.359875 -319.553272) (xy 276.379166 -319.507996) (xy 276.405469 -319.4664)
			(xy 276.438104 -319.429563) (xy 276.476225 -319.398438) (xy 276.518846 -319.373831) (xy 276.564862 -319.356379)
			(xy 276.613081 -319.346535) (xy 276.662256 -319.344554) (xy 276.711111 -319.350486) (xy 276.758382 -319.364178)
			(xy 276.802844 -319.385276) (xy 276.843347 -319.413232) (xy 276.87884 -319.447324) (xy 276.908405 -319.486668)
			(xy 276.931276 -319.530245) (xy 276.94686 -319.576926) (xy 276.954755 -319.625503) (xy 276.95525 -319.65011)
			(xy 278.244058 -319.65011) (xy 278.248018 -319.601056) (xy 278.259795 -319.553272) (xy 278.279086 -319.507996)
			(xy 278.305389 -319.4664) (xy 278.338024 -319.429563) (xy 278.376145 -319.398438) (xy 278.418766 -319.373831)
			(xy 278.464782 -319.356379) (xy 278.513001 -319.346535) (xy 278.562176 -319.344554) (xy 278.611031 -319.350486)
			(xy 278.658302 -319.364178) (xy 278.702764 -319.385276) (xy 278.743267 -319.413232) (xy 278.77876 -319.447324)
			(xy 278.808325 -319.486668) (xy 278.831196 -319.530245) (xy 278.84678 -319.576926) (xy 278.854675 -319.625503)
			(xy 278.85517 -319.65011) (xy 280.143978 -319.65011) (xy 280.147938 -319.601056) (xy 280.159715 -319.553272)
			(xy 280.179006 -319.507996) (xy 280.205309 -319.4664) (xy 280.237944 -319.429563) (xy 280.276065 -319.398438)
			(xy 280.318686 -319.373831) (xy 280.364702 -319.356379) (xy 280.412921 -319.346535) (xy 280.462096 -319.344554)
			(xy 280.510951 -319.350486) (xy 280.558222 -319.364178) (xy 280.602684 -319.385276) (xy 280.643187 -319.413232)
			(xy 280.67868 -319.447324) (xy 280.708245 -319.486668) (xy 280.731116 -319.530245) (xy 280.7467 -319.576926)
			(xy 280.754595 -319.625503) (xy 280.75509 -319.65011) (xy 282.044152 -319.65011) (xy 282.048112 -319.601056)
			(xy 282.059889 -319.553272) (xy 282.07918 -319.507996) (xy 282.105483 -319.4664) (xy 282.138118 -319.429563)
			(xy 282.176239 -319.398438) (xy 282.21886 -319.373831) (xy 282.264876 -319.356379) (xy 282.313095 -319.346535)
			(xy 282.36227 -319.344554) (xy 282.411125 -319.350486) (xy 282.458396 -319.364178) (xy 282.502858 -319.385276)
			(xy 282.543361 -319.413232) (xy 282.578854 -319.447324) (xy 282.608419 -319.486668) (xy 282.63129 -319.530245)
			(xy 282.646874 -319.576926) (xy 282.654769 -319.625503) (xy 282.655264 -319.65011) (xy 283.944072 -319.65011)
			(xy 283.948032 -319.601056) (xy 283.959809 -319.553272) (xy 283.9791 -319.507996) (xy 284.005403 -319.4664)
			(xy 284.038038 -319.429563) (xy 284.076159 -319.398438) (xy 284.11878 -319.373831) (xy 284.164796 -319.356379)
			(xy 284.213015 -319.346535) (xy 284.26219 -319.344554) (xy 284.311045 -319.350486) (xy 284.358316 -319.364178)
			(xy 284.402778 -319.385276) (xy 284.443281 -319.413232) (xy 284.478774 -319.447324) (xy 284.508339 -319.486668)
			(xy 284.53121 -319.530245) (xy 284.546794 -319.576926) (xy 284.554689 -319.625503) (xy 284.555184 -319.65011)
			(xy 285.843992 -319.65011) (xy 285.847952 -319.601056) (xy 285.859729 -319.553272) (xy 285.87902 -319.507996)
			(xy 285.905323 -319.4664) (xy 285.937958 -319.429563) (xy 285.976079 -319.398438) (xy 286.0187 -319.373831)
			(xy 286.064716 -319.356379) (xy 286.112935 -319.346535) (xy 286.16211 -319.344554) (xy 286.210965 -319.350486)
			(xy 286.258236 -319.364178) (xy 286.302698 -319.385276) (xy 286.343201 -319.413232) (xy 286.378694 -319.447324)
			(xy 286.408259 -319.486668) (xy 286.43113 -319.530245) (xy 286.446714 -319.576926) (xy 286.454609 -319.625503)
			(xy 286.455104 -319.65011) (xy 287.744166 -319.65011) (xy 287.748126 -319.601056) (xy 287.759903 -319.553272)
			(xy 287.779194 -319.507996) (xy 287.805497 -319.4664) (xy 287.838132 -319.429563) (xy 287.876253 -319.398438)
			(xy 287.918874 -319.373831) (xy 287.96489 -319.356379) (xy 288.013109 -319.346535) (xy 288.062284 -319.344554)
			(xy 288.111139 -319.350486) (xy 288.15841 -319.364178) (xy 288.202872 -319.385276) (xy 288.243375 -319.413232)
			(xy 288.278868 -319.447324) (xy 288.308433 -319.486668) (xy 288.331304 -319.530245) (xy 288.346888 -319.576926)
			(xy 288.354783 -319.625503) (xy 288.355278 -319.65011) (xy 289.64434 -319.65011) (xy 289.6483 -319.601056)
			(xy 289.660077 -319.553272) (xy 289.679368 -319.507996) (xy 289.705671 -319.4664) (xy 289.738306 -319.429563)
			(xy 289.776427 -319.398438) (xy 289.819048 -319.373831) (xy 289.865064 -319.356379) (xy 289.913283 -319.346535)
			(xy 289.962458 -319.344554) (xy 290.011313 -319.350486) (xy 290.058584 -319.364178) (xy 290.103046 -319.385276)
			(xy 290.143549 -319.413232) (xy 290.179042 -319.447324) (xy 290.208607 -319.486668) (xy 290.231478 -319.530245)
			(xy 290.247062 -319.576926) (xy 290.254957 -319.625503) (xy 290.255452 -319.65011) (xy 291.544006 -319.65011)
			(xy 291.547966 -319.601056) (xy 291.559743 -319.553272) (xy 291.579034 -319.507996) (xy 291.605337 -319.4664)
			(xy 291.637972 -319.429563) (xy 291.676093 -319.398438) (xy 291.718714 -319.373831) (xy 291.76473 -319.356379)
			(xy 291.812949 -319.346535) (xy 291.862124 -319.344554) (xy 291.910979 -319.350486) (xy 291.95825 -319.364178)
			(xy 292.002712 -319.385276) (xy 292.043215 -319.413232) (xy 292.078708 -319.447324) (xy 292.108273 -319.486668)
			(xy 292.131144 -319.530245) (xy 292.146728 -319.576926) (xy 292.154623 -319.625503) (xy 292.155118 -319.65011)
			(xy 293.443926 -319.65011) (xy 293.447886 -319.601056) (xy 293.459663 -319.553272) (xy 293.478954 -319.507996)
			(xy 293.505257 -319.4664) (xy 293.537892 -319.429563) (xy 293.576013 -319.398438) (xy 293.618634 -319.373831)
			(xy 293.66465 -319.356379) (xy 293.712869 -319.346535) (xy 293.762044 -319.344554) (xy 293.810899 -319.350486)
			(xy 293.85817 -319.364178) (xy 293.902632 -319.385276) (xy 293.943135 -319.413232) (xy 293.978628 -319.447324)
			(xy 294.008193 -319.486668) (xy 294.031064 -319.530245) (xy 294.046648 -319.576926) (xy 294.054543 -319.625503)
			(xy 294.055038 -319.65011) (xy 295.3441 -319.65011) (xy 295.34806 -319.601056) (xy 295.359837 -319.553272)
			(xy 295.379128 -319.507996) (xy 295.405431 -319.4664) (xy 295.438066 -319.429563) (xy 295.476187 -319.398438)
			(xy 295.518808 -319.373831) (xy 295.564824 -319.356379) (xy 295.613043 -319.346535) (xy 295.662218 -319.344554)
			(xy 295.711073 -319.350486) (xy 295.758344 -319.364178) (xy 295.802806 -319.385276) (xy 295.843309 -319.413232)
			(xy 295.878802 -319.447324) (xy 295.908367 -319.486668) (xy 295.931238 -319.530245) (xy 295.946822 -319.576926)
			(xy 295.954717 -319.625503) (xy 295.955212 -319.65011) (xy 297.24402 -319.65011) (xy 297.24798 -319.601056)
			(xy 297.259757 -319.553272) (xy 297.279048 -319.507996) (xy 297.305351 -319.4664) (xy 297.337986 -319.429563)
			(xy 297.376107 -319.398438) (xy 297.418728 -319.373831) (xy 297.464744 -319.356379) (xy 297.512963 -319.346535)
			(xy 297.562138 -319.344554) (xy 297.610993 -319.350486) (xy 297.658264 -319.364178) (xy 297.702726 -319.385276)
			(xy 297.743229 -319.413232) (xy 297.778722 -319.447324) (xy 297.808287 -319.486668) (xy 297.831158 -319.530245)
			(xy 297.846742 -319.576926) (xy 297.854637 -319.625503) (xy 297.855132 -319.65011) (xy 299.14394 -319.65011)
			(xy 299.1479 -319.601056) (xy 299.159677 -319.553272) (xy 299.178968 -319.507996) (xy 299.205271 -319.4664)
			(xy 299.237906 -319.429563) (xy 299.276027 -319.398438) (xy 299.318648 -319.373831) (xy 299.364664 -319.356379)
			(xy 299.412883 -319.346535) (xy 299.462058 -319.344554) (xy 299.510913 -319.350486) (xy 299.558184 -319.364178)
			(xy 299.602646 -319.385276) (xy 299.643149 -319.413232) (xy 299.678642 -319.447324) (xy 299.708207 -319.486668)
			(xy 299.731078 -319.530245) (xy 299.746662 -319.576926) (xy 299.754557 -319.625503) (xy 299.755052 -319.65011)
			(xy 301.044114 -319.65011) (xy 301.048074 -319.601056) (xy 301.059851 -319.553272) (xy 301.079142 -319.507996)
			(xy 301.105445 -319.4664) (xy 301.13808 -319.429563) (xy 301.176201 -319.398438) (xy 301.218822 -319.373831)
			(xy 301.264838 -319.356379) (xy 301.313057 -319.346535) (xy 301.362232 -319.344554) (xy 301.411087 -319.350486)
			(xy 301.458358 -319.364178) (xy 301.50282 -319.385276) (xy 301.543323 -319.413232) (xy 301.578816 -319.447324)
			(xy 301.608381 -319.486668) (xy 301.631252 -319.530245) (xy 301.646836 -319.576926) (xy 301.654731 -319.625503)
			(xy 301.655226 -319.65011) (xy 302.944034 -319.65011) (xy 302.947994 -319.601056) (xy 302.959771 -319.553272)
			(xy 302.979062 -319.507996) (xy 303.005365 -319.4664) (xy 303.038 -319.429563) (xy 303.076121 -319.398438)
			(xy 303.118742 -319.373831) (xy 303.164758 -319.356379) (xy 303.212977 -319.346535) (xy 303.262152 -319.344554)
			(xy 303.311007 -319.350486) (xy 303.358278 -319.364178) (xy 303.40274 -319.385276) (xy 303.443243 -319.413232)
			(xy 303.478736 -319.447324) (xy 303.508301 -319.486668) (xy 303.531172 -319.530245) (xy 303.546756 -319.576926)
			(xy 303.554651 -319.625503) (xy 303.555146 -319.65011) (xy 303.554651 -319.674717) (xy 303.546756 -319.723294)
			(xy 303.531172 -319.769975) (xy 303.508301 -319.813552) (xy 303.478736 -319.852896) (xy 303.443243 -319.886988)
			(xy 303.40274 -319.914944) (xy 303.358278 -319.936042) (xy 303.311007 -319.949734) (xy 303.262152 -319.955666)
			(xy 303.212977 -319.953685) (xy 303.164758 -319.943841) (xy 303.118742 -319.926389) (xy 303.076121 -319.901782)
			(xy 303.038 -319.870657) (xy 303.005365 -319.83382) (xy 302.979062 -319.792224) (xy 302.959771 -319.746948)
			(xy 302.947994 -319.699164) (xy 302.944034 -319.65011) (xy 301.655226 -319.65011) (xy 301.654731 -319.674717)
			(xy 301.646836 -319.723294) (xy 301.631252 -319.769975) (xy 301.608381 -319.813552) (xy 301.578816 -319.852896)
			(xy 301.543323 -319.886988) (xy 301.50282 -319.914944) (xy 301.458358 -319.936042) (xy 301.411087 -319.949734)
			(xy 301.362232 -319.955666) (xy 301.313057 -319.953685) (xy 301.264838 -319.943841) (xy 301.218822 -319.926389)
			(xy 301.176201 -319.901782) (xy 301.13808 -319.870657) (xy 301.105445 -319.83382) (xy 301.079142 -319.792224)
			(xy 301.059851 -319.746948) (xy 301.048074 -319.699164) (xy 301.044114 -319.65011) (xy 299.755052 -319.65011)
			(xy 299.754557 -319.674717) (xy 299.746662 -319.723294) (xy 299.731078 -319.769975) (xy 299.708207 -319.813552)
			(xy 299.678642 -319.852896) (xy 299.643149 -319.886988) (xy 299.602646 -319.914944) (xy 299.558184 -319.936042)
			(xy 299.510913 -319.949734) (xy 299.462058 -319.955666) (xy 299.412883 -319.953685) (xy 299.364664 -319.943841)
			(xy 299.318648 -319.926389) (xy 299.276027 -319.901782) (xy 299.237906 -319.870657) (xy 299.205271 -319.83382)
			(xy 299.178968 -319.792224) (xy 299.159677 -319.746948) (xy 299.1479 -319.699164) (xy 299.14394 -319.65011)
			(xy 297.855132 -319.65011) (xy 297.854637 -319.674717) (xy 297.846742 -319.723294) (xy 297.831158 -319.769975)
			(xy 297.808287 -319.813552) (xy 297.778722 -319.852896) (xy 297.743229 -319.886988) (xy 297.702726 -319.914944)
			(xy 297.658264 -319.936042) (xy 297.610993 -319.949734) (xy 297.562138 -319.955666) (xy 297.512963 -319.953685)
			(xy 297.464744 -319.943841) (xy 297.418728 -319.926389) (xy 297.376107 -319.901782) (xy 297.337986 -319.870657)
			(xy 297.305351 -319.83382) (xy 297.279048 -319.792224) (xy 297.259757 -319.746948) (xy 297.24798 -319.699164)
			(xy 297.24402 -319.65011) (xy 295.955212 -319.65011) (xy 295.954717 -319.674717) (xy 295.946822 -319.723294)
			(xy 295.931238 -319.769975) (xy 295.908367 -319.813552) (xy 295.878802 -319.852896) (xy 295.843309 -319.886988)
			(xy 295.802806 -319.914944) (xy 295.758344 -319.936042) (xy 295.711073 -319.949734) (xy 295.662218 -319.955666)
			(xy 295.613043 -319.953685) (xy 295.564824 -319.943841) (xy 295.518808 -319.926389) (xy 295.476187 -319.901782)
			(xy 295.438066 -319.870657) (xy 295.405431 -319.83382) (xy 295.379128 -319.792224) (xy 295.359837 -319.746948)
			(xy 295.34806 -319.699164) (xy 295.3441 -319.65011) (xy 294.055038 -319.65011) (xy 294.054543 -319.674717)
			(xy 294.046648 -319.723294) (xy 294.031064 -319.769975) (xy 294.008193 -319.813552) (xy 293.978628 -319.852896)
			(xy 293.943135 -319.886988) (xy 293.902632 -319.914944) (xy 293.85817 -319.936042) (xy 293.810899 -319.949734)
			(xy 293.762044 -319.955666) (xy 293.712869 -319.953685) (xy 293.66465 -319.943841) (xy 293.618634 -319.926389)
			(xy 293.576013 -319.901782) (xy 293.537892 -319.870657) (xy 293.505257 -319.83382) (xy 293.478954 -319.792224)
			(xy 293.459663 -319.746948) (xy 293.447886 -319.699164) (xy 293.443926 -319.65011) (xy 292.155118 -319.65011)
			(xy 292.154623 -319.674717) (xy 292.146728 -319.723294) (xy 292.131144 -319.769975) (xy 292.108273 -319.813552)
			(xy 292.078708 -319.852896) (xy 292.043215 -319.886988) (xy 292.002712 -319.914944) (xy 291.95825 -319.936042)
			(xy 291.910979 -319.949734) (xy 291.862124 -319.955666) (xy 291.812949 -319.953685) (xy 291.76473 -319.943841)
			(xy 291.718714 -319.926389) (xy 291.676093 -319.901782) (xy 291.637972 -319.870657) (xy 291.605337 -319.83382)
			(xy 291.579034 -319.792224) (xy 291.559743 -319.746948) (xy 291.547966 -319.699164) (xy 291.544006 -319.65011)
			(xy 290.255452 -319.65011) (xy 290.254957 -319.674717) (xy 290.247062 -319.723294) (xy 290.231478 -319.769975)
			(xy 290.208607 -319.813552) (xy 290.179042 -319.852896) (xy 290.143549 -319.886988) (xy 290.103046 -319.914944)
			(xy 290.058584 -319.936042) (xy 290.011313 -319.949734) (xy 289.962458 -319.955666) (xy 289.913283 -319.953685)
			(xy 289.865064 -319.943841) (xy 289.819048 -319.926389) (xy 289.776427 -319.901782) (xy 289.738306 -319.870657)
			(xy 289.705671 -319.83382) (xy 289.679368 -319.792224) (xy 289.660077 -319.746948) (xy 289.6483 -319.699164)
			(xy 289.64434 -319.65011) (xy 288.355278 -319.65011) (xy 288.354783 -319.674717) (xy 288.346888 -319.723294)
			(xy 288.331304 -319.769975) (xy 288.308433 -319.813552) (xy 288.278868 -319.852896) (xy 288.243375 -319.886988)
			(xy 288.202872 -319.914944) (xy 288.15841 -319.936042) (xy 288.111139 -319.949734) (xy 288.062284 -319.955666)
			(xy 288.013109 -319.953685) (xy 287.96489 -319.943841) (xy 287.918874 -319.926389) (xy 287.876253 -319.901782)
			(xy 287.838132 -319.870657) (xy 287.805497 -319.83382) (xy 287.779194 -319.792224) (xy 287.759903 -319.746948)
			(xy 287.748126 -319.699164) (xy 287.744166 -319.65011) (xy 286.455104 -319.65011) (xy 286.454609 -319.674717)
			(xy 286.446714 -319.723294) (xy 286.43113 -319.769975) (xy 286.408259 -319.813552) (xy 286.378694 -319.852896)
			(xy 286.343201 -319.886988) (xy 286.302698 -319.914944) (xy 286.258236 -319.936042) (xy 286.210965 -319.949734)
			(xy 286.16211 -319.955666) (xy 286.112935 -319.953685) (xy 286.064716 -319.943841) (xy 286.0187 -319.926389)
			(xy 285.976079 -319.901782) (xy 285.937958 -319.870657) (xy 285.905323 -319.83382) (xy 285.87902 -319.792224)
			(xy 285.859729 -319.746948) (xy 285.847952 -319.699164) (xy 285.843992 -319.65011) (xy 284.555184 -319.65011)
			(xy 284.554689 -319.674717) (xy 284.546794 -319.723294) (xy 284.53121 -319.769975) (xy 284.508339 -319.813552)
			(xy 284.478774 -319.852896) (xy 284.443281 -319.886988) (xy 284.402778 -319.914944) (xy 284.358316 -319.936042)
			(xy 284.311045 -319.949734) (xy 284.26219 -319.955666) (xy 284.213015 -319.953685) (xy 284.164796 -319.943841)
			(xy 284.11878 -319.926389) (xy 284.076159 -319.901782) (xy 284.038038 -319.870657) (xy 284.005403 -319.83382)
			(xy 283.9791 -319.792224) (xy 283.959809 -319.746948) (xy 283.948032 -319.699164) (xy 283.944072 -319.65011)
			(xy 282.655264 -319.65011) (xy 282.654769 -319.674717) (xy 282.646874 -319.723294) (xy 282.63129 -319.769975)
			(xy 282.608419 -319.813552) (xy 282.578854 -319.852896) (xy 282.543361 -319.886988) (xy 282.502858 -319.914944)
			(xy 282.458396 -319.936042) (xy 282.411125 -319.949734) (xy 282.36227 -319.955666) (xy 282.313095 -319.953685)
			(xy 282.264876 -319.943841) (xy 282.21886 -319.926389) (xy 282.176239 -319.901782) (xy 282.138118 -319.870657)
			(xy 282.105483 -319.83382) (xy 282.07918 -319.792224) (xy 282.059889 -319.746948) (xy 282.048112 -319.699164)
			(xy 282.044152 -319.65011) (xy 280.75509 -319.65011) (xy 280.754595 -319.674717) (xy 280.7467 -319.723294)
			(xy 280.731116 -319.769975) (xy 280.708245 -319.813552) (xy 280.67868 -319.852896) (xy 280.643187 -319.886988)
			(xy 280.602684 -319.914944) (xy 280.558222 -319.936042) (xy 280.510951 -319.949734) (xy 280.462096 -319.955666)
			(xy 280.412921 -319.953685) (xy 280.364702 -319.943841) (xy 280.318686 -319.926389) (xy 280.276065 -319.901782)
			(xy 280.237944 -319.870657) (xy 280.205309 -319.83382) (xy 280.179006 -319.792224) (xy 280.159715 -319.746948)
			(xy 280.147938 -319.699164) (xy 280.143978 -319.65011) (xy 278.85517 -319.65011) (xy 278.854675 -319.674717)
			(xy 278.84678 -319.723294) (xy 278.831196 -319.769975) (xy 278.808325 -319.813552) (xy 278.77876 -319.852896)
			(xy 278.743267 -319.886988) (xy 278.702764 -319.914944) (xy 278.658302 -319.936042) (xy 278.611031 -319.949734)
			(xy 278.562176 -319.955666) (xy 278.513001 -319.953685) (xy 278.464782 -319.943841) (xy 278.418766 -319.926389)
			(xy 278.376145 -319.901782) (xy 278.338024 -319.870657) (xy 278.305389 -319.83382) (xy 278.279086 -319.792224)
			(xy 278.259795 -319.746948) (xy 278.248018 -319.699164) (xy 278.244058 -319.65011) (xy 276.95525 -319.65011)
			(xy 276.954755 -319.674717) (xy 276.94686 -319.723294) (xy 276.931276 -319.769975) (xy 276.908405 -319.813552)
			(xy 276.87884 -319.852896) (xy 276.843347 -319.886988) (xy 276.802844 -319.914944) (xy 276.758382 -319.936042)
			(xy 276.711111 -319.949734) (xy 276.662256 -319.955666) (xy 276.613081 -319.953685) (xy 276.564862 -319.943841)
			(xy 276.518846 -319.926389) (xy 276.476225 -319.901782) (xy 276.438104 -319.870657) (xy 276.405469 -319.83382)
			(xy 276.379166 -319.792224) (xy 276.359875 -319.746948) (xy 276.348098 -319.699164) (xy 276.344138 -319.65011)
			(xy 275.055076 -319.65011) (xy 275.054581 -319.674717) (xy 275.046686 -319.723294) (xy 275.031102 -319.769975)
			(xy 275.008231 -319.813552) (xy 274.978666 -319.852896) (xy 274.943173 -319.886988) (xy 274.90267 -319.914944)
			(xy 274.858208 -319.936042) (xy 274.810937 -319.949734) (xy 274.762082 -319.955666) (xy 274.712907 -319.953685)
			(xy 274.664688 -319.943841) (xy 274.618672 -319.926389) (xy 274.576051 -319.901782) (xy 274.53793 -319.870657)
			(xy 274.505295 -319.83382) (xy 274.478992 -319.792224) (xy 274.459701 -319.746948) (xy 274.447924 -319.699164)
			(xy 274.443964 -319.65011) (xy 273.155156 -319.65011) (xy 273.154661 -319.674717) (xy 273.146766 -319.723294)
			(xy 273.131182 -319.769975) (xy 273.108311 -319.813552) (xy 273.078746 -319.852896) (xy 273.043253 -319.886988)
			(xy 273.00275 -319.914944) (xy 272.958288 -319.936042) (xy 272.911017 -319.949734) (xy 272.862162 -319.955666)
			(xy 272.812987 -319.953685) (xy 272.764768 -319.943841) (xy 272.718752 -319.926389) (xy 272.676131 -319.901782)
			(xy 272.63801 -319.870657) (xy 272.605375 -319.83382) (xy 272.579072 -319.792224) (xy 272.559781 -319.746948)
			(xy 272.548004 -319.699164) (xy 272.544044 -319.65011) (xy 271.255236 -319.65011) (xy 271.254741 -319.674717)
			(xy 271.246846 -319.723294) (xy 271.231262 -319.769975) (xy 271.208391 -319.813552) (xy 271.178826 -319.852896)
			(xy 271.143333 -319.886988) (xy 271.10283 -319.914944) (xy 271.058368 -319.936042) (xy 271.011097 -319.949734)
			(xy 270.962242 -319.955666) (xy 270.913067 -319.953685) (xy 270.864848 -319.943841) (xy 270.818832 -319.926389)
			(xy 270.776211 -319.901782) (xy 270.73809 -319.870657) (xy 270.705455 -319.83382) (xy 270.679152 -319.792224)
			(xy 270.659861 -319.746948) (xy 270.648084 -319.699164) (xy 270.644124 -319.65011) (xy 266.459841 -319.65011)
			(xy 266.506573 -319.837182) (xy 266.546051 -320.028007) (xy 266.577712 -320.220283) (xy 266.601504 -320.413691)
			(xy 266.617387 -320.607908) (xy 266.625335 -320.802611) (xy 266.625832 -320.900044) (xy 266.62533 -320.99843)
			(xy 266.617228 -321.195035) (xy 266.601034 -321.39114) (xy 266.576778 -321.586411) (xy 266.544499 -321.780517)
			(xy 266.504253 -321.973129) (xy 266.456108 -322.16392) (xy 266.400146 -322.352567) (xy 266.336461 -322.538748)
			(xy 266.265162 -322.722148) (xy 266.18637 -322.902456) (xy 266.100218 -323.079365) (xy 266.006852 -323.252577)
			(xy 265.95705 -323.337428) (xy 265.953494 -323.34327) (xy 265.949938 -323.35597) (xy 265.949684 -323.363082)
			(xy 265.949844 -323.369791) (xy 265.953188 -323.382784) (xy 265.956288 -323.388736) (xy 265.988292 -323.445124)
			(xy 265.9888 -323.445632) (xy 266.000484 -323.465952) (xy 266.005238 -323.473445) (xy 266.018868 -323.484791)
			(xy 266.035557 -323.490786) (xy 266.044426 -323.491098) (xy 298.158154 -323.491098) (xy 298.164592 -323.490906)
			(xy 298.17706 -323.487687) (xy 298.182792 -323.484748) (xy 304.476658 -320.02349) (xy 304.49012 -320.002662)
			(xy 304.49139 -319.990216) (xy 304.496394 -319.94555) (xy 304.513423 -319.857292) (xy 304.538315 -319.770922)
			(xy 304.554128 -319.72885) (xy 304.557684 -319.71996) (xy 304.557684 -319.47485) (xy 304.543206 -319.450974)
			(xy 304.53076 -319.444116) (xy 304.509658 -319.432327) (xy 304.471142 -319.403126) (xy 304.43771 -319.368219)
			(xy 304.410198 -319.328478) (xy 304.389294 -319.284897) (xy 304.375521 -319.238567) (xy 304.369223 -319.190644)
			(xy 304.370558 -319.142328) (xy 304.37455 -319.118488) (xy 304.376836 -319.106042) (xy 304.36947 -319.08242)
			(xy 304.292254 -319.00495) (xy 304.268632 -318.997584) (xy 304.255932 -319.000124) (xy 304.242023 -319.00252)
			(xy 304.213911 -319.005061) (xy 304.199798 -319.005204) (xy 304.174543 -319.004682) (xy 304.124722 -318.996368)
			(xy 304.076949 -318.979968) (xy 304.032527 -318.955927) (xy 303.992668 -318.924904) (xy 303.958459 -318.887742)
			(xy 303.930833 -318.845457) (xy 303.910543 -318.799201) (xy 303.898144 -318.750237) (xy 303.893973 -318.6999)
			(xy 303.898144 -318.649563) (xy 303.910543 -318.600599) (xy 303.930833 -318.554343) (xy 303.958459 -318.512058)
			(xy 303.992668 -318.474896) (xy 304.032527 -318.443873) (xy 304.076949 -318.419832) (xy 304.124722 -318.403432)
			(xy 304.174543 -318.395118) (xy 304.199798 -318.394588) (xy 304.213913 -318.394708) (xy 304.242026 -318.397248)
			(xy 304.255932 -318.399668) (xy 304.268632 -318.402208) (xy 304.292254 -318.394842) (xy 304.36947 -318.317372)
			(xy 304.376836 -318.29375) (xy 304.37455 -318.281304) (xy 304.36992 -318.253296) (xy 304.369917 -318.196535)
			(xy 304.37455 -318.168528) (xy 304.376836 -318.156082) (xy 304.36947 -318.13246) (xy 304.292254 -318.05499)
			(xy 304.268632 -318.047624) (xy 304.255932 -318.050164) (xy 304.242023 -318.052561) (xy 304.213911 -318.055102)
			(xy 304.199798 -318.055244) (xy 304.17454 -318.054722) (xy 304.124712 -318.046407) (xy 304.076933 -318.030004)
			(xy 304.032506 -318.005961) (xy 303.992641 -317.974933) (xy 303.958427 -317.937767) (xy 303.930798 -317.895476)
			(xy 303.910506 -317.849214) (xy 303.898105 -317.800244) (xy 303.893933 -317.7499) (xy 303.898105 -317.699556)
			(xy 303.910506 -317.650586) (xy 303.930798 -317.604324) (xy 303.958427 -317.562033) (xy 303.992641 -317.524867)
			(xy 304.032506 -317.493839) (xy 304.076933 -317.469796) (xy 304.124712 -317.453393) (xy 304.17454 -317.445078)
			(xy 304.199798 -317.444628) (xy 304.208902 -317.444724) (xy 304.227076 -317.445866) (xy 304.23612 -317.446914)
			(xy 304.248058 -317.448184) (xy 304.27041 -317.44031) (xy 304.343308 -317.363856) (xy 304.35042 -317.34125)
			(xy 304.348388 -317.329058) (xy 304.346257 -317.31557) (xy 304.343969 -317.288357) (xy 304.343816 -317.274702)
			(xy 304.343816 -317.226188) (xy 304.343355 -317.21553) (xy 304.334671 -317.196064) (xy 304.327052 -317.188596)
			(xy 304.263298 -317.130684) (xy 304.242978 -317.12408) (xy 304.232056 -317.125096) (xy 304.199798 -317.12662)
			(xy 304.174109 -317.126116) (xy 304.123362 -317.118078) (xy 304.074498 -317.102201) (xy 304.02872 -317.078875)
			(xy 303.987153 -317.048676) (xy 303.950823 -317.012345) (xy 303.920624 -316.970779) (xy 303.897298 -316.925)
			(xy 303.881421 -316.876136) (xy 303.873384 -316.825389) (xy 303.873384 -316.774011) (xy 303.881421 -316.723264)
			(xy 303.897298 -316.6744) (xy 303.920624 -316.628621) (xy 303.950823 -316.587055) (xy 303.987153 -316.550724)
			(xy 304.02872 -316.520525) (xy 304.074498 -316.497199) (xy 304.123362 -316.481322) (xy 304.174109 -316.473284)
			(xy 304.199798 -316.472824) (xy 304.232056 -316.474348) (xy 304.242978 -316.475364) (xy 304.263298 -316.46876)
			(xy 304.327052 -316.410848) (xy 304.33457 -316.403307) (xy 304.343249 -316.383887) (xy 304.343816 -316.373256)
			(xy 304.343816 -316.324742) (xy 304.343858 -316.315388) (xy 304.344874 -316.296707) (xy 304.345848 -316.287404)
			(xy 304.347372 -316.275974) (xy 304.339752 -316.25413) (xy 304.267362 -316.181486) (xy 304.245772 -316.173612)
			(xy 304.234342 -316.174882) (xy 304.199798 -316.17666) (xy 304.174113 -316.176156) (xy 304.123376 -316.16812)
			(xy 304.074521 -316.152246) (xy 304.028751 -316.128924) (xy 303.987192 -316.09873) (xy 303.950869 -316.062406)
			(xy 303.920675 -316.020847) (xy 303.897354 -315.975077) (xy 303.88148 -315.926222) (xy 303.873444 -315.875485)
			(xy 303.873444 -315.824115) (xy 303.88148 -315.773378) (xy 303.897354 -315.724523) (xy 303.920675 -315.678753)
			(xy 303.950869 -315.637194) (xy 303.987192 -315.60087) (xy 304.028751 -315.570676) (xy 304.074521 -315.547354)
			(xy 304.123376 -315.53148) (xy 304.174113 -315.523444) (xy 304.199798 -315.522864) (xy 304.213448 -315.522952)
			(xy 304.240662 -315.525111) (xy 304.254154 -315.527182) (xy 304.266346 -315.529214) (xy 304.289206 -315.522356)
			(xy 304.365406 -315.448696) (xy 304.373534 -315.42609) (xy 304.37201 -315.414152) (xy 304.370348 -315.400439)
			(xy 304.369199 -315.372837) (xy 304.369724 -315.359034) (xy 304.370337 -315.348812) (xy 304.372749 -315.328475)
			(xy 304.37455 -315.318394) (xy 304.376836 -315.305694) (xy 304.369724 -315.282326) (xy 304.292254 -315.204856)
			(xy 304.268632 -315.19749) (xy 304.255932 -315.199776) (xy 304.24203 -315.202254) (xy 304.213918 -315.20493)
			(xy 304.199798 -315.20511) (xy 304.174543 -315.204588) (xy 304.124721 -315.196274) (xy 304.076947 -315.179873)
			(xy 304.032524 -315.155832) (xy 303.992664 -315.124808) (xy 303.958454 -315.087646) (xy 303.930828 -315.04536)
			(xy 303.910538 -314.999103) (xy 303.898138 -314.950138) (xy 303.893967 -314.8998) (xy 303.898138 -314.849462)
			(xy 303.910538 -314.800497) (xy 303.930828 -314.75424) (xy 303.958454 -314.711954) (xy 303.992664 -314.674792)
			(xy 304.032524 -314.643768) (xy 304.076947 -314.619727) (xy 304.124721 -314.603326) (xy 304.174543 -314.595012)
			(xy 304.199798 -314.594494) (xy 304.213913 -314.594614) (xy 304.242026 -314.597154) (xy 304.255932 -314.599574)
			(xy 304.268632 -314.602114) (xy 304.292254 -314.594748) (xy 304.36947 -314.517278) (xy 304.376836 -314.493656)
			(xy 304.37455 -314.48121) (xy 304.369919 -314.453202) (xy 304.369915 -314.396441) (xy 304.37455 -314.368434)
			(xy 304.376836 -314.355988) (xy 304.36947 -314.332366) (xy 304.292254 -314.254896) (xy 304.268632 -314.24753)
			(xy 304.255932 -314.25007) (xy 304.242023 -314.252466) (xy 304.213911 -314.255008) (xy 304.199798 -314.25515)
			(xy 304.174539 -314.254628) (xy 304.124711 -314.246313) (xy 304.076931 -314.22991) (xy 304.032502 -314.205866)
			(xy 303.992637 -314.174837) (xy 303.958423 -314.13767) (xy 303.930792 -314.095379) (xy 303.9105 -314.049116)
			(xy 303.898099 -314.000145) (xy 303.893927 -313.9498) (xy 303.898099 -313.899455) (xy 303.9105 -313.850484)
			(xy 303.930792 -313.804221) (xy 303.958423 -313.76193) (xy 303.992637 -313.724763) (xy 304.032502 -313.693734)
			(xy 304.076931 -313.66969) (xy 304.124711 -313.653287) (xy 304.174539 -313.644972) (xy 304.199798 -313.644534)
			(xy 304.213913 -313.644653) (xy 304.242026 -313.647193) (xy 304.255932 -313.649614) (xy 304.268632 -313.652154)
			(xy 304.292254 -313.644788) (xy 304.36947 -313.567318) (xy 304.376836 -313.543696) (xy 304.37455 -313.53125)
			(xy 304.369925 -313.503243) (xy 304.369932 -313.446483) (xy 304.37455 -313.418474) (xy 304.376836 -313.406028)
			(xy 304.36947 -313.382406) (xy 304.292254 -313.304936) (xy 304.268632 -313.29757) (xy 304.255932 -313.30011)
			(xy 304.242023 -313.302506) (xy 304.213911 -313.305047) (xy 304.199798 -313.30519) (xy 304.174544 -313.304668)
			(xy 304.124726 -313.296355) (xy 304.076955 -313.279955) (xy 304.032535 -313.255916) (xy 303.992678 -313.224893)
			(xy 303.95847 -313.187734) (xy 303.930845 -313.14545) (xy 303.910557 -313.099197) (xy 303.898158 -313.050235)
			(xy 303.893987 -312.9999) (xy 303.898158 -312.949565) (xy 303.910557 -312.900603) (xy 303.930845 -312.85435)
			(xy 303.95847 -312.812066) (xy 303.992678 -312.774907) (xy 304.032535 -312.743884) (xy 304.076955 -312.719845)
			(xy 304.124726 -312.703445) (xy 304.174544 -312.695132) (xy 304.199798 -312.694574) (xy 304.213913 -312.694693)
			(xy 304.242026 -312.697233) (xy 304.255932 -312.699654) (xy 304.268632 -312.702194) (xy 304.292254 -312.694828)
			(xy 304.36947 -312.617358) (xy 304.376836 -312.593736) (xy 304.37455 -312.58129) (xy 304.370529 -312.557561)
			(xy 304.369125 -312.509455) (xy 304.371756 -312.485532) (xy 304.37328 -312.473594) (xy 304.365406 -312.450988)
			(xy 304.288952 -312.377582) (xy 304.266092 -312.37047) (xy 304.254154 -312.372502) (xy 304.240663 -312.374584)
			(xy 304.213449 -312.376746) (xy 304.199798 -312.37682) (xy 304.174109 -312.376316) (xy 304.123362 -312.368278)
			(xy 304.074498 -312.352401) (xy 304.02872 -312.329075) (xy 303.987153 -312.298876) (xy 303.950823 -312.262545)
			(xy 303.920624 -312.220979) (xy 303.897298 -312.1752) (xy 303.881421 -312.126336) (xy 303.873384 -312.075589)
			(xy 303.873384 -312.024211) (xy 303.881421 -311.973464) (xy 303.897298 -311.9246) (xy 303.920624 -311.878821)
			(xy 303.950823 -311.837255) (xy 303.987153 -311.800924) (xy 304.02872 -311.770725) (xy 304.074498 -311.747399)
			(xy 304.123362 -311.731522) (xy 304.174109 -311.723484) (xy 304.199798 -311.723024) (xy 304.234342 -311.724802)
			(xy 304.246026 -311.726072) (xy 304.267362 -311.718198) (xy 304.339752 -311.6453) (xy 304.347372 -311.62371)
			(xy 304.345848 -311.61228) (xy 304.344876 -311.602913) (xy 304.343863 -311.584105) (xy 304.343816 -311.574688)
			(xy 304.343816 -311.526428) (xy 304.343363 -311.515766) (xy 304.334689 -311.496288) (xy 304.327052 -311.488836)
			(xy 304.263298 -311.430924) (xy 304.242978 -311.42432) (xy 304.232056 -311.425336) (xy 304.199798 -311.42686)
			(xy 304.174113 -311.426356) (xy 304.123376 -311.41832) (xy 304.074521 -311.402446) (xy 304.028751 -311.379124)
			(xy 303.987192 -311.34893) (xy 303.950869 -311.312606) (xy 303.920675 -311.271047) (xy 303.897354 -311.225277)
			(xy 303.88148 -311.176422) (xy 303.873444 -311.125685) (xy 303.873444 -311.074315) (xy 303.88148 -311.023578)
			(xy 303.897354 -310.974723) (xy 303.920675 -310.928953) (xy 303.950869 -310.887394) (xy 303.987192 -310.85107)
			(xy 304.028751 -310.820876) (xy 304.074521 -310.797554) (xy 304.123376 -310.78168) (xy 304.174113 -310.773644)
			(xy 304.199798 -310.773064) (xy 304.232056 -310.774588) (xy 304.242978 -310.775604) (xy 304.263298 -310.769)
			(xy 304.327052 -310.711088) (xy 304.33456 -310.703543) (xy 304.343216 -310.684124) (xy 304.343816 -310.673496)
			(xy 304.343816 -310.624728) (xy 304.343978 -310.611074) (xy 304.346268 -310.583861) (xy 304.348388 -310.570372)
			(xy 304.35042 -310.558434) (xy 304.343308 -310.535828) (xy 304.27041 -310.459374) (xy 304.248058 -310.4515)
			(xy 304.23612 -310.453024) (xy 304.227073 -310.454012) (xy 304.208899 -310.455027) (xy 304.199798 -310.455056)
			(xy 304.174539 -310.454535) (xy 304.124709 -310.446219) (xy 304.076928 -310.429816) (xy 304.032499 -310.405771)
			(xy 303.992633 -310.374742) (xy 303.958418 -310.337574) (xy 303.930787 -310.295282) (xy 303.910494 -310.249019)
			(xy 303.898092 -310.200046) (xy 303.89392 -310.1497) (xy 303.898092 -310.099354) (xy 303.910494 -310.050381)
			(xy 303.930787 -310.004118) (xy 303.958418 -309.961826) (xy 303.992633 -309.924658) (xy 304.032499 -309.893629)
			(xy 304.076928 -309.869584) (xy 304.124709 -309.853181) (xy 304.174539 -309.844865) (xy 304.199798 -309.84444)
			(xy 304.213913 -309.844559) (xy 304.242026 -309.847099) (xy 304.255932 -309.84952) (xy 304.268632 -309.85206)
			(xy 304.292254 -309.844694) (xy 304.36947 -309.767224) (xy 304.376836 -309.743602) (xy 304.37455 -309.731156)
			(xy 304.370264 -309.705486) (xy 304.369467 -309.653452) (xy 304.3775 -309.602036) (xy 304.394129 -309.552724)
			(xy 304.418874 -309.506944) (xy 304.451019 -309.466019) (xy 304.489634 -309.431133) (xy 304.533603 -309.403296)
			(xy 304.55743 -309.392828) (xy 304.571908 -309.386986) (xy 304.588672 -309.361586) (xy 304.588672 -309.03799)
			(xy 304.571908 -309.01259) (xy 304.55743 -309.006748) (xy 304.535471 -308.997122) (xy 304.49461 -308.972041)
			(xy 304.458173 -308.940881) (xy 304.427055 -308.904409) (xy 304.40202 -308.86352) (xy 304.383685 -308.81922)
			(xy 304.372501 -308.772599) (xy 304.368741 -308.724803) (xy 304.3725 -308.677007) (xy 304.383683 -308.630386)
			(xy 304.402017 -308.586086) (xy 304.427051 -308.545196) (xy 304.458169 -308.508723) (xy 304.494605 -308.477562)
			(xy 304.535465 -308.452481) (xy 304.55743 -308.442868) (xy 304.571908 -308.437026) (xy 304.588672 -308.411626)
			(xy 304.588672 -308.08803) (xy 304.571908 -308.06263) (xy 304.55743 -308.056788) (xy 304.535467 -308.047162)
			(xy 304.494601 -308.02208) (xy 304.458158 -307.990918) (xy 304.427034 -307.954443) (xy 304.401994 -307.91355)
			(xy 304.383655 -307.869246) (xy 304.372466 -307.82262) (xy 304.368704 -307.774818) (xy 304.372461 -307.727016)
			(xy 304.383643 -307.680389) (xy 304.401977 -307.636083) (xy 304.427012 -307.595187) (xy 304.458132 -307.558708)
			(xy 304.494571 -307.527542) (xy 304.535435 -307.502455) (xy 304.55743 -307.492908) (xy 304.571908 -307.487066)
			(xy 304.588672 -307.461666) (xy 304.588672 -307.13807) (xy 304.571908 -307.11267) (xy 304.55743 -307.106828)
			(xy 304.535472 -307.097202) (xy 304.494615 -307.072122) (xy 304.458181 -307.040963) (xy 304.427065 -307.004492)
			(xy 304.402033 -306.963605) (xy 304.3837 -306.919307) (xy 304.372518 -306.872689) (xy 304.36876 -306.824895)
			(xy 304.372519 -306.777102) (xy 304.383703 -306.730484) (xy 304.402037 -306.686187) (xy 304.42707 -306.645301)
			(xy 304.458187 -306.608831) (xy 304.494622 -306.577673) (xy 304.53548 -306.552594) (xy 304.55743 -306.542948)
			(xy 304.571908 -306.537106) (xy 304.588672 -306.511706) (xy 304.588672 -306.203858) (xy 304.588238 -306.19388)
			(xy 304.580702 -306.175407) (xy 304.566675 -306.16122) (xy 304.557684 -306.156868) (xy 304.55743 -306.156868)
			(xy 304.533942 -306.146496) (xy 304.490531 -306.119085) (xy 304.452307 -306.084808) (xy 304.420346 -306.044629)
			(xy 304.395544 -305.999676) (xy 304.378598 -305.951212) (xy 304.369985 -305.900598) (xy 304.36947 -305.874928)
			(xy 304.369914 -305.850933) (xy 304.377417 -305.803533) (xy 304.392243 -305.75789) (xy 304.414026 -305.715128)
			(xy 304.442231 -305.676301) (xy 304.476163 -305.642364) (xy 304.514986 -305.614153) (xy 304.557744 -305.592362)
			(xy 304.603384 -305.577529) (xy 304.650783 -305.570018) (xy 304.674778 -305.56962) (xy 304.700971 -305.570157)
			(xy 304.75259 -305.579084) (xy 304.801932 -305.59668) (xy 304.847552 -305.622429) (xy 304.888114 -305.655579)
			(xy 304.905664 -305.67503) (xy 304.912522 -305.682904) (xy 304.92192 -305.68773) (xy 304.926718 -305.689944)
			(xy 304.936965 -305.692511) (xy 304.94224 -305.69281) (xy 305.013868 -305.69535) (xy 305.016916 -305.69535)
			(xy 305.038506 -305.691286) (xy 305.048666 -305.686968) (xy 305.055524 -305.679602) (xy 305.057302 -305.67757)
			(xy 305.430682 -305.30419) (xy 305.437665 -305.296439) (xy 305.445259 -305.277031) (xy 305.445414 -305.266598)
			(xy 305.442874 -305.19243) (xy 305.438048 -305.182778) (xy 305.425348 -305.156108) (xy 305.417982 -305.14925)
			(xy 305.39973 -305.131793) (xy 305.368695 -305.091951) (xy 305.344645 -305.047542) (xy 305.328236 -304.999779)
			(xy 305.319917 -304.949966) (xy 305.31943 -304.924714) (xy 305.319875 -304.900721) (xy 305.32738 -304.853326)
			(xy 305.342208 -304.807689) (xy 305.363993 -304.764934) (xy 305.392199 -304.726113) (xy 305.426132 -304.692184)
			(xy 305.464954 -304.663981) (xy 305.507711 -304.642199) (xy 305.55335 -304.627375) (xy 305.600745 -304.619873)
			(xy 305.624738 -304.619406) (xy 305.659282 -304.621438) (xy 305.676348 -304.572191) (xy 305.719619 -304.477367)
			(xy 305.745642 -304.432208) (xy 305.750019 -304.424011) (xy 305.753189 -304.405715) (xy 305.749676 -304.387482)
			(xy 305.745134 -304.379376) (xy 305.711606 -304.325782) (xy 305.711606 -304.325274) (xy 305.701192 -304.309018)
			(xy 305.69916 -304.305462) (xy 305.691794 -304.292) (xy 305.665124 -304.277776) (xy 305.647852 -304.2793)
			(xy 305.626262 -304.280062) (xy 305.623722 -304.280062) (xy 305.599782 -304.279518) (xy 305.552511 -304.271891)
			(xy 305.507011 -304.256976) (xy 305.464397 -304.235141) (xy 305.425716 -304.206919) (xy 305.391914 -304.173005)
			(xy 305.363823 -304.134228) (xy 305.34213 -304.091542) (xy 305.327369 -304.045992) (xy 305.3199 -303.998695)
			(xy 305.31943 -303.974754) (xy 305.319904 -303.950766) (xy 305.327416 -303.903382) (xy 305.342248 -303.857757)
			(xy 305.364035 -303.815013) (xy 305.39224 -303.776204) (xy 305.426168 -303.742285) (xy 305.464985 -303.714091)
			(xy 305.507735 -303.692316) (xy 305.553364 -303.677497) (xy 305.60075 -303.669997) (xy 305.624738 -303.669446)
			(xy 305.648678 -303.669915) (xy 305.69597 -303.677394) (xy 305.741515 -303.692163) (xy 305.784197 -303.713859)
			(xy 305.82297 -303.741951) (xy 305.856883 -303.77575) (xy 305.885105 -303.814429) (xy 305.906944 -303.857038)
			(xy 305.921865 -303.902533) (xy 305.929502 -303.9498) (xy 305.930046 -303.973738) (xy 305.930046 -303.975008)
			(xy 305.92903 -304.000154) (xy 305.928014 -304.014632) (xy 305.940714 -304.039778) (xy 306.015644 -304.086514)
			(xy 306.015898 -304.086514) (xy 306.028852 -304.094896) (xy 306.036442 -304.099264) (xy 306.053516 -304.103101)
			(xy 306.070888 -304.100996) (xy 306.07889 -304.097436) (xy 306.0827 -304.095404) (xy 306.084224 -304.094388)
			(xy 306.09957 -304.085444) (xy 306.13082 -304.068549) (xy 306.146708 -304.060606) (xy 306.154206 -304.056514)
			(xy 306.166148 -304.044315) (xy 306.170076 -304.03673) (xy 306.189312 -303.996984) (xy 306.233978 -303.920806)
			(xy 306.285372 -303.848996) (xy 306.31384 -303.815242) (xy 306.317904 -303.8094) (xy 306.329986 -303.791338)
			(xy 306.358447 -303.758502) (xy 306.391276 -303.730032) (xy 306.409344 -303.71796) (xy 306.414932 -303.713896)
			(xy 306.448036 -303.68597) (xy 306.518397 -303.635457) (xy 306.592972 -303.591402) (xy 306.67117 -303.554155)
			(xy 306.711604 -303.538636) (xy 306.720927 -303.534656) (xy 306.735666 -303.520763) (xy 306.74392 -303.502267)
			(xy 306.744624 -303.492154) (xy 306.745649 -303.468554) (xy 306.754077 -303.422076) (xy 306.769563 -303.377451)
			(xy 306.791738 -303.335743) (xy 306.820073 -303.29795) (xy 306.853891 -303.264971) (xy 306.892386 -303.237596)
			(xy 306.934638 -303.216477) (xy 306.979638 -303.202118) (xy 307.026314 -303.194862) (xy 307.049932 -303.194466)
			(xy 307.076184 -303.195014) (xy 307.127913 -303.203997) (xy 307.177344 -303.221694) (xy 307.223021 -303.247582)
			(xy 307.263599 -303.280899) (xy 307.297883 -303.320664) (xy 307.324862 -303.365705) (xy 307.343741 -303.414697)
			(xy 307.349398 -303.440338) (xy 307.352067 -303.451027) (xy 307.364991 -303.468841) (xy 307.384188 -303.479603)
			(xy 307.395118 -303.480978) (xy 307.425179 -303.483735) (xy 307.484913 -303.492503) (xy 307.514498 -303.498504)
			(xy 307.519663 -303.499451) (xy 307.530161 -303.499451) (xy 307.535326 -303.498504) (xy 307.56491 -303.492494)
			(xy 307.624643 -303.483722) (xy 307.654706 -303.480978) (xy 307.665624 -303.479558) (xy 307.684805 -303.468798)
			(xy 307.697748 -303.451016) (xy 307.700426 -303.440338) (xy 307.706074 -303.414695) (xy 307.724954 -303.365704)
			(xy 307.751935 -303.320663) (xy 307.78622 -303.280899) (xy 307.826799 -303.247584) (xy 307.872478 -303.221699)
			(xy 307.92191 -303.204006) (xy 307.97364 -303.195026) (xy 307.999892 -303.194466) (xy 308.014074 -303.194652)
			(xy 308.042314 -303.197325) (xy 308.05628 -303.1998) (xy 308.068726 -303.202086) (xy 308.092348 -303.19472)
			(xy 308.169818 -303.11725) (xy 308.177184 -303.093628) (xy 308.174898 -303.081182) (xy 308.172413 -303.067217)
			(xy 308.169742 -303.038977) (xy 308.169564 -303.024794) (xy 308.17005 -302.999971) (xy 308.178084 -302.950978)
			(xy 308.193937 -302.90393) (xy 308.217193 -302.860067) (xy 308.24724 -302.820544) (xy 308.283284 -302.786403)
			(xy 308.324377 -302.758543) (xy 308.369437 -302.737699) (xy 308.417275 -302.724419) (xy 308.466631 -302.719053)
			(xy 308.516205 -302.721743) (xy 308.564691 -302.732418) (xy 308.610811 -302.750796) (xy 308.65335 -302.776394)
			(xy 308.691187 -302.808537) (xy 308.723326 -302.846378) (xy 308.748919 -302.88892) (xy 308.767292 -302.935042)
			(xy 308.777962 -302.983529) (xy 308.780196 -303.024794) (xy 309.119028 -303.024794) (xy 309.122988 -302.97574)
			(xy 309.134765 -302.927956) (xy 309.154056 -302.88268) (xy 309.180359 -302.841084) (xy 309.212994 -302.804247)
			(xy 309.251115 -302.773122) (xy 309.293736 -302.748515) (xy 309.339752 -302.731063) (xy 309.387971 -302.721219)
			(xy 309.437146 -302.719238) (xy 309.486001 -302.72517) (xy 309.533272 -302.738862) (xy 309.577734 -302.75996)
			(xy 309.618237 -302.787916) (xy 309.65373 -302.822008) (xy 309.683295 -302.861352) (xy 309.706166 -302.904929)
			(xy 309.72175 -302.95161) (xy 309.729645 -303.000187) (xy 309.73014 -303.024794) (xy 309.729645 -303.049401)
			(xy 309.72175 -303.097978) (xy 309.706166 -303.144659) (xy 309.683295 -303.188236) (xy 309.65373 -303.22758)
			(xy 309.618237 -303.261672) (xy 309.577734 -303.289628) (xy 309.533272 -303.310726) (xy 309.486001 -303.324418)
			(xy 309.437146 -303.33035) (xy 309.387971 -303.328369) (xy 309.339752 -303.318525) (xy 309.293736 -303.301073)
			(xy 309.251115 -303.276466) (xy 309.212994 -303.245341) (xy 309.180359 -303.208504) (xy 309.154056 -303.166908)
			(xy 309.134765 -303.121632) (xy 309.122988 -303.073848) (xy 309.119028 -303.024794) (xy 308.780196 -303.024794)
			(xy 308.780646 -303.033103) (xy 308.775275 -303.082459) (xy 308.76199 -303.130295) (xy 308.74114 -303.175352)
			(xy 308.713276 -303.216442) (xy 308.679131 -303.252483) (xy 308.639604 -303.282525) (xy 308.595739 -303.305776)
			(xy 308.548689 -303.321625) (xy 308.499696 -303.329652) (xy 308.474872 -303.330102) (xy 308.460689 -303.329919)
			(xy 308.432449 -303.327252) (xy 308.418484 -303.324768) (xy 308.406038 -303.322482) (xy 308.382416 -303.329848)
			(xy 308.304946 -303.407318) (xy 308.29758 -303.43094) (xy 308.299866 -303.443386) (xy 308.302052 -303.45547)
			(xy 308.304723 -303.479883) (xy 308.3052 -303.492154) (xy 308.305844 -303.502281) (xy 308.314083 -303.520805)
			(xy 308.32888 -303.534664) (xy 308.33822 -303.538636) (xy 308.378771 -303.554176) (xy 308.457189 -303.591506)
			(xy 308.531959 -303.635689) (xy 308.602485 -303.686373) (xy 308.635654 -303.714404) (xy 308.641242 -303.718722)
			(xy 308.658898 -303.730637) (xy 308.69104 -303.758585) (xy 308.718985 -303.790731) (xy 308.730904 -303.808384)
			(xy 308.735222 -303.813972) (xy 308.746652 -303.827688) (xy 308.754208 -303.8359) (xy 308.774371 -303.845396)
			(xy 308.785514 -303.845976) (xy 309.130954 -303.845976) (xy 309.154322 -303.832514) (xy 309.16118 -303.820576)
			(xy 309.17397 -303.799698) (xy 309.205135 -303.761939) (xy 309.241921 -303.729632) (xy 309.283389 -303.703606)
			(xy 309.328477 -303.684524) (xy 309.37603 -303.672876) (xy 309.424832 -303.66896) (xy 309.473634 -303.672876)
			(xy 309.521187 -303.684524) (xy 309.566275 -303.703606) (xy 309.607743 -303.729632) (xy 309.644529 -303.761939)
			(xy 309.675694 -303.799698) (xy 309.688484 -303.820576) (xy 309.695342 -303.832514) (xy 309.71871 -303.845976)
			(xy 310.080914 -303.845976) (xy 310.104282 -303.832514) (xy 310.11114 -303.820576) (xy 310.125034 -303.797977)
			(xy 310.159341 -303.757519) (xy 310.200117 -303.723592) (xy 310.246138 -303.697212) (xy 310.296021 -303.679172)
			(xy 310.348269 -303.670014) (xy 310.374792 -303.669446) (xy 310.388974 -303.669632) (xy 310.417214 -303.672304)
			(xy 310.43118 -303.67478) (xy 310.443626 -303.677066) (xy 310.467248 -303.6697) (xy 310.544718 -303.59223)
			(xy 310.552084 -303.568608) (xy 310.549798 -303.556162) (xy 310.547314 -303.542197) (xy 310.544645 -303.513957)
			(xy 310.544464 -303.499774) (xy 310.544652 -303.485592) (xy 310.547327 -303.457353) (xy 310.549798 -303.443386)
			(xy 310.552084 -303.43094) (xy 310.544718 -303.407318) (xy 310.467248 -303.329848) (xy 310.443626 -303.322482)
			(xy 310.43118 -303.324768) (xy 310.417215 -303.327253) (xy 310.388975 -303.329924) (xy 310.374792 -303.330102)
			(xy 310.349972 -303.329616) (xy 310.300986 -303.321583) (xy 310.253944 -303.305732) (xy 310.210087 -303.282479)
			(xy 310.170569 -303.252437) (xy 310.136433 -303.216398) (xy 310.108576 -303.175311) (xy 310.087733 -303.130259)
			(xy 310.074454 -303.082427) (xy 310.069087 -303.033078) (xy 310.071775 -302.983511) (xy 310.082447 -302.935031)
			(xy 310.100821 -302.888917) (xy 310.126413 -302.846382) (xy 310.15855 -302.808548) (xy 310.196384 -302.776412)
			(xy 310.238918 -302.75082) (xy 310.285033 -302.732446) (xy 310.333513 -302.721775) (xy 310.38308 -302.719087)
			(xy 310.432429 -302.724454) (xy 310.48026 -302.737734) (xy 310.525313 -302.758577) (xy 310.5664 -302.786434)
			(xy 310.602439 -302.820571) (xy 310.63248 -302.860089) (xy 310.655733 -302.903946) (xy 310.671584 -302.950988)
			(xy 310.679616 -302.999974) (xy 310.6801 -303.024794) (xy 310.679914 -303.038976) (xy 310.677241 -303.067216)
			(xy 310.674766 -303.081182) (xy 310.67248 -303.093628) (xy 310.679846 -303.11725) (xy 310.757316 -303.19472)
			(xy 310.780938 -303.202086) (xy 310.793384 -303.1998) (xy 310.807349 -303.197314) (xy 310.835589 -303.194639)
			(xy 310.849772 -303.194466) (xy 310.863955 -303.194651) (xy 310.892194 -303.197322) (xy 310.90616 -303.1998)
			(xy 310.918606 -303.202086) (xy 310.942228 -303.19472) (xy 311.019698 -303.11725) (xy 311.027064 -303.093628)
			(xy 311.024778 -303.081182) (xy 311.022293 -303.067217) (xy 311.019621 -303.038977) (xy 311.019444 -303.024794)
			(xy 311.01993 -302.999968) (xy 311.027964 -302.950972) (xy 311.043819 -302.90392) (xy 311.067077 -302.860054)
			(xy 311.097126 -302.820528) (xy 311.133174 -302.786385) (xy 311.174271 -302.758523) (xy 311.219334 -302.737678)
			(xy 311.267176 -302.724397) (xy 311.316537 -302.719032) (xy 311.366115 -302.721724) (xy 311.414604 -302.7324)
			(xy 311.460727 -302.750782) (xy 311.503269 -302.776383) (xy 311.541109 -302.80853) (xy 311.573249 -302.846375)
			(xy 311.598842 -302.888921) (xy 311.617215 -302.935047) (xy 311.627884 -302.983539) (xy 311.630116 -303.024794)
			(xy 311.968908 -303.024794) (xy 311.972868 -302.97574) (xy 311.984645 -302.927956) (xy 312.003936 -302.88268)
			(xy 312.030239 -302.841084) (xy 312.062874 -302.804247) (xy 312.100995 -302.773122) (xy 312.143616 -302.748515)
			(xy 312.189632 -302.731063) (xy 312.237851 -302.721219) (xy 312.287026 -302.719238) (xy 312.335881 -302.72517)
			(xy 312.383152 -302.738862) (xy 312.427614 -302.75996) (xy 312.468117 -302.787916) (xy 312.50361 -302.822008)
			(xy 312.533175 -302.861352) (xy 312.556046 -302.904929) (xy 312.57163 -302.95161) (xy 312.579525 -303.000187)
			(xy 312.58002 -303.024794) (xy 312.919122 -303.024794) (xy 312.923082 -302.97574) (xy 312.934859 -302.927956)
			(xy 312.95415 -302.88268) (xy 312.980453 -302.841084) (xy 313.013088 -302.804247) (xy 313.051209 -302.773122)
			(xy 313.09383 -302.748515) (xy 313.139846 -302.731063) (xy 313.188065 -302.721219) (xy 313.23724 -302.719238)
			(xy 313.286095 -302.72517) (xy 313.333366 -302.738862) (xy 313.377828 -302.75996) (xy 313.418331 -302.787916)
			(xy 313.453824 -302.822008) (xy 313.483389 -302.861352) (xy 313.50626 -302.904929) (xy 313.521844 -302.95161)
			(xy 313.529739 -303.000187) (xy 313.530234 -303.024794) (xy 313.869082 -303.024794) (xy 313.873042 -302.97574)
			(xy 313.884819 -302.927956) (xy 313.90411 -302.88268) (xy 313.930413 -302.841084) (xy 313.963048 -302.804247)
			(xy 314.001169 -302.773122) (xy 314.04379 -302.748515) (xy 314.089806 -302.731063) (xy 314.138025 -302.721219)
			(xy 314.1872 -302.719238) (xy 314.236055 -302.72517) (xy 314.283326 -302.738862) (xy 314.327788 -302.75996)
			(xy 314.368291 -302.787916) (xy 314.403784 -302.822008) (xy 314.433349 -302.861352) (xy 314.45622 -302.904929)
			(xy 314.471804 -302.95161) (xy 314.479699 -303.000187) (xy 314.480194 -303.024794) (xy 314.803802 -303.024794)
			(xy 314.807762 -302.97574) (xy 314.819539 -302.927956) (xy 314.83883 -302.88268) (xy 314.865133 -302.841084)
			(xy 314.897768 -302.804247) (xy 314.935889 -302.773122) (xy 314.97851 -302.748515) (xy 315.024526 -302.731063)
			(xy 315.072745 -302.721219) (xy 315.12192 -302.719238) (xy 315.170775 -302.72517) (xy 315.218046 -302.738862)
			(xy 315.262508 -302.75996) (xy 315.303011 -302.787916) (xy 315.338504 -302.822008) (xy 315.368069 -302.861352)
			(xy 315.39094 -302.904929) (xy 315.406524 -302.95161) (xy 315.414419 -303.000187) (xy 315.414914 -303.024794)
			(xy 315.414419 -303.049401) (xy 315.406524 -303.097978) (xy 315.39094 -303.144659) (xy 315.368069 -303.188236)
			(xy 315.338504 -303.22758) (xy 315.303011 -303.261672) (xy 315.262508 -303.289628) (xy 315.218046 -303.310726)
			(xy 315.170775 -303.324418) (xy 315.12192 -303.33035) (xy 315.072745 -303.328369) (xy 315.024526 -303.318525)
			(xy 314.97851 -303.301073) (xy 314.935889 -303.276466) (xy 314.897768 -303.245341) (xy 314.865133 -303.208504)
			(xy 314.83883 -303.166908) (xy 314.819539 -303.121632) (xy 314.807762 -303.073848) (xy 314.803802 -303.024794)
			(xy 314.480194 -303.024794) (xy 314.479699 -303.049401) (xy 314.471804 -303.097978) (xy 314.45622 -303.144659)
			(xy 314.433349 -303.188236) (xy 314.403784 -303.22758) (xy 314.368291 -303.261672) (xy 314.327788 -303.289628)
			(xy 314.283326 -303.310726) (xy 314.236055 -303.324418) (xy 314.1872 -303.33035) (xy 314.138025 -303.328369)
			(xy 314.089806 -303.318525) (xy 314.04379 -303.301073) (xy 314.001169 -303.276466) (xy 313.963048 -303.245341)
			(xy 313.930413 -303.208504) (xy 313.90411 -303.166908) (xy 313.884819 -303.121632) (xy 313.873042 -303.073848)
			(xy 313.869082 -303.024794) (xy 313.530234 -303.024794) (xy 313.529739 -303.049401) (xy 313.521844 -303.097978)
			(xy 313.50626 -303.144659) (xy 313.483389 -303.188236) (xy 313.453824 -303.22758) (xy 313.418331 -303.261672)
			(xy 313.377828 -303.289628) (xy 313.333366 -303.310726) (xy 313.286095 -303.324418) (xy 313.23724 -303.33035)
			(xy 313.188065 -303.328369) (xy 313.139846 -303.318525) (xy 313.09383 -303.301073) (xy 313.051209 -303.276466)
			(xy 313.013088 -303.245341) (xy 312.980453 -303.208504) (xy 312.95415 -303.166908) (xy 312.934859 -303.121632)
			(xy 312.923082 -303.073848) (xy 312.919122 -303.024794) (xy 312.58002 -303.024794) (xy 312.579525 -303.049401)
			(xy 312.57163 -303.097978) (xy 312.556046 -303.144659) (xy 312.533175 -303.188236) (xy 312.50361 -303.22758)
			(xy 312.468117 -303.261672) (xy 312.427614 -303.289628) (xy 312.383152 -303.310726) (xy 312.335881 -303.324418)
			(xy 312.287026 -303.33035) (xy 312.237851 -303.328369) (xy 312.189632 -303.318525) (xy 312.143616 -303.301073)
			(xy 312.100995 -303.276466) (xy 312.062874 -303.245341) (xy 312.030239 -303.208504) (xy 312.003936 -303.166908)
			(xy 311.984645 -303.121632) (xy 311.972868 -303.073848) (xy 311.968908 -303.024794) (xy 311.630116 -303.024794)
			(xy 311.630566 -303.033117) (xy 311.625193 -303.082477) (xy 311.611904 -303.130316) (xy 311.59105 -303.175376)
			(xy 311.563181 -303.216468) (xy 311.529032 -303.25251) (xy 311.489501 -303.282552) (xy 311.44563 -303.305802)
			(xy 311.398576 -303.321649) (xy 311.349578 -303.329674) (xy 311.324752 -303.330102) (xy 311.310569 -303.329918)
			(xy 311.282329 -303.327249) (xy 311.268364 -303.324768) (xy 311.255918 -303.322482) (xy 311.232296 -303.329848)
			(xy 311.154826 -303.407318) (xy 311.14746 -303.43094) (xy 311.149746 -303.443386) (xy 311.152233 -303.457351)
			(xy 311.154907 -303.485591) (xy 311.15508 -303.499774) (xy 311.154895 -303.513957) (xy 311.152223 -303.542196)
			(xy 311.149746 -303.556162) (xy 311.14746 -303.568608) (xy 311.154826 -303.59223) (xy 311.232296 -303.6697)
			(xy 311.255918 -303.677066) (xy 311.268364 -303.67478) (xy 311.282329 -303.672297) (xy 311.310569 -303.669631)
			(xy 311.324752 -303.669446) (xy 311.351277 -303.67001) (xy 311.403531 -303.67916) (xy 311.453422 -303.697193)
			(xy 311.49945 -303.723569) (xy 311.540234 -303.757495) (xy 311.574548 -303.797952) (xy 311.588404 -303.820576)
			(xy 311.595262 -303.832514) (xy 311.61863 -303.845976) (xy 311.980834 -303.845976) (xy 312.004202 -303.832514)
			(xy 312.01106 -303.820576) (xy 312.02385 -303.799698) (xy 312.055015 -303.761939) (xy 312.091801 -303.729632)
			(xy 312.133269 -303.703606) (xy 312.178357 -303.684524) (xy 312.22591 -303.672876) (xy 312.274712 -303.66896)
			(xy 312.323514 -303.672876) (xy 312.371067 -303.684524) (xy 312.416155 -303.703606) (xy 312.457623 -303.729632)
			(xy 312.494409 -303.761939) (xy 312.525574 -303.799698) (xy 312.538364 -303.820576) (xy 312.545222 -303.832514)
			(xy 312.56859 -303.845976) (xy 312.931048 -303.845976) (xy 312.954416 -303.832514) (xy 312.961274 -303.820576)
			(xy 312.974064 -303.799698) (xy 313.005229 -303.761939) (xy 313.042015 -303.729632) (xy 313.083483 -303.703606)
			(xy 313.128571 -303.684524) (xy 313.176124 -303.672876) (xy 313.224926 -303.66896) (xy 313.273728 -303.672876)
			(xy 313.321281 -303.684524) (xy 313.366369 -303.703606) (xy 313.407837 -303.729632) (xy 313.444623 -303.761939)
			(xy 313.475788 -303.799698) (xy 313.488578 -303.820576) (xy 313.495436 -303.832514) (xy 313.518804 -303.845976)
			(xy 313.852306 -303.845976) (xy 313.876182 -303.831498) (xy 313.882786 -303.819052) (xy 313.895231 -303.796703)
			(xy 313.92594 -303.755797) (xy 313.962579 -303.720103) (xy 314.004275 -303.690474) (xy 314.050035 -303.667615)
			(xy 314.098767 -303.652071) (xy 314.14931 -303.644212) (xy 314.174886 -303.643792) (xy 315.124846 -303.643792)
			(xy 315.149383 -303.644241) (xy 315.197918 -303.65149) (xy 315.244851 -303.665825) (xy 315.289155 -303.686929)
			(xy 315.329859 -303.714341) (xy 315.366071 -303.747461) (xy 315.381894 -303.76622) (xy 315.383418 -303.768252)
			(xy 315.383672 -303.768506) (xy 315.386974 -303.77257) (xy 315.389006 -303.775364) (xy 315.391868 -303.779156)
			(xy 315.398767 -303.785686) (xy 315.402722 -303.788318) (xy 315.412628 -303.794668) (xy 315.418851 -303.798435)
			(xy 315.43279 -303.80257) (xy 315.44006 -303.802796) (xy 315.470286 -303.802796) (xy 315.475933 -303.802676)
			(xy 315.486962 -303.800248) (xy 315.49213 -303.79797) (xy 315.510926 -303.78908) (xy 315.521594 -303.782222)
			(xy 315.52769 -303.776126) (xy 315.532008 -303.7713) (xy 315.549562 -303.752492) (xy 315.589808 -303.720451)
			(xy 315.634846 -303.695593) (xy 315.683408 -303.678619) (xy 315.734125 -303.670005) (xy 315.759846 -303.669446)
			(xy 315.783947 -303.669903) (xy 315.831548 -303.677481) (xy 315.877369 -303.69244) (xy 315.920272 -303.714411)
			(xy 315.959192 -303.742847) (xy 315.976508 -303.759616) (xy 315.983882 -303.766523) (xy 316.002483 -303.774373)
			(xy 316.012576 -303.774856) (xy 317.110618 -303.774856) (xy 317.120603 -303.774314) (xy 317.139026 -303.766591)
			(xy 317.146432 -303.75987) (xy 317.170308 -303.735994) (xy 317.170816 -303.735486) (xy 317.177408 -303.728109)
			(xy 317.184878 -303.709809) (xy 317.185294 -303.699926) (xy 317.185294 -298.353734) (xy 317.185024 -298.346849)
			(xy 317.181281 -298.333593) (xy 317.177928 -298.327572) (xy 317.161926 -298.301156) (xy 317.152782 -298.292266)
			(xy 317.147194 -298.288964) (xy 317.122742 -298.274216) (xy 317.078113 -298.238595) (xy 317.039289 -298.196724)
			(xy 317.007136 -298.149536) (xy 316.982371 -298.098085) (xy 316.965547 -298.043519) (xy 316.95704 -297.987055)
			(xy 316.957039 -297.929955) (xy 316.965545 -297.873491) (xy 316.982367 -297.818924) (xy 317.007131 -297.767472)
			(xy 317.039283 -297.720284) (xy 317.078106 -297.678411) (xy 317.122734 -297.64279) (xy 317.147194 -297.628056)
			(xy 317.152782 -297.624754) (xy 317.161926 -297.615864) (xy 317.185294 -297.577256) (xy 317.185294 -296.575734)
			(xy 317.185024 -296.568849) (xy 317.181281 -296.555593) (xy 317.177928 -296.549572) (xy 317.161926 -296.523156)
			(xy 317.152782 -296.514266) (xy 317.147194 -296.510964) (xy 317.122742 -296.496216) (xy 317.078113 -296.460595)
			(xy 317.039289 -296.418724) (xy 317.007136 -296.371536) (xy 316.982371 -296.320085) (xy 316.965547 -296.265519)
			(xy 316.95704 -296.209055) (xy 316.957039 -296.151955) (xy 316.965545 -296.095491) (xy 316.982367 -296.040924)
			(xy 317.007131 -295.989472) (xy 317.039283 -295.942284) (xy 317.078106 -295.900411) (xy 317.122734 -295.86479)
			(xy 317.147194 -295.850056) (xy 317.153036 -295.846754) (xy 317.16218 -295.837864) (xy 317.172086 -295.820846)
			(xy 317.176756 -295.812008) (xy 317.179613 -295.792244) (xy 317.174735 -295.77288) (xy 317.162855 -295.756829)
			(xy 317.15456 -295.75125) (xy 317.148972 -295.748202) (xy 317.142876 -295.74617) (xy 317.131817 -295.742808)
			(xy 317.110086 -295.734928) (xy 317.099442 -295.730422) (xy 317.074251 -295.718911) (xy 317.027204 -295.68969)
			(xy 316.984872 -295.653978) (xy 316.948145 -295.612525) (xy 316.917793 -295.566199) (xy 316.894453 -295.515974)
			(xy 316.878615 -295.462904) (xy 316.870611 -295.408102) (xy 316.87008 -295.38041) (xy 316.870559 -295.352917)
			(xy 316.878449 -295.2985) (xy 316.894068 -295.245778) (xy 316.917091 -295.195844) (xy 316.947043 -295.149732)
			(xy 316.983303 -295.108395) (xy 317.02512 -295.07269) (xy 317.071629 -295.043357) (xy 317.121866 -295.021002)
			(xy 317.14821 -295.013126) (xy 317.158715 -295.009623) (xy 317.175547 -294.995269) (xy 317.184776 -294.975166)
			(xy 317.185294 -294.964104) (xy 317.185294 -282.115514) (xy 317.184855 -282.105451) (xy 317.177118 -282.08687)
			(xy 317.170308 -282.079446) (xy 316.667896 -281.577034) (xy 316.660552 -281.57022) (xy 316.642089 -281.562484)
			(xy 316.632082 -281.562048) (xy 316.006734 -281.562048) (xy 315.996921 -281.562542) (xy 315.978751 -281.569976)
			(xy 315.971428 -281.576526) (xy 315.913516 -281.63266) (xy 315.905642 -281.650186) (xy 315.905134 -281.660346)
			(xy 315.903834 -281.685031) (xy 315.89425 -281.733521) (xy 315.876977 -281.779834) (xy 315.852468 -281.822758)
			(xy 315.821362 -281.861172) (xy 315.784473 -281.894071) (xy 315.742764 -281.920597) (xy 315.697326 -281.940055)
			(xy 315.649347 -281.951937) (xy 315.60008 -281.955932) (xy 315.550813 -281.951937) (xy 315.502834 -281.940055)
			(xy 315.457396 -281.920597) (xy 315.415687 -281.894071) (xy 315.378798 -281.861172) (xy 315.347692 -281.822758)
			(xy 315.323183 -281.779834) (xy 315.30591 -281.733521) (xy 315.296326 -281.685031) (xy 315.295026 -281.660346)
			(xy 315.294518 -281.650186) (xy 315.286898 -281.632406) (xy 315.228732 -281.576272) (xy 315.22138 -281.569792)
			(xy 315.203217 -281.562482) (xy 315.193426 -281.562048) (xy 315.078364 -281.562048) (xy 315.068515 -281.562466)
			(xy 315.050234 -281.569792) (xy 315.042804 -281.576272) (xy 314.985146 -281.632406) (xy 314.977018 -281.65044)
			(xy 314.976764 -281.660346) (xy 314.975499 -281.685499) (xy 314.966198 -281.734995) (xy 314.94942 -281.782479)
			(xy 314.925562 -281.826831) (xy 314.895187 -281.867001) (xy 314.859014 -281.902041) (xy 314.817897 -281.931121)
			(xy 314.772808 -281.953555) (xy 314.724813 -281.968812) (xy 314.675047 -281.976532) (xy 314.624685 -281.976532)
			(xy 314.574919 -281.968812) (xy 314.526924 -281.953555) (xy 314.481835 -281.931121) (xy 314.440718 -281.902041)
			(xy 314.404545 -281.867001) (xy 314.37417 -281.826831) (xy 314.350312 -281.782479) (xy 314.333534 -281.734995)
			(xy 314.324233 -281.685499) (xy 314.322968 -281.660346) (xy 314.322714 -281.65044) (xy 314.314586 -281.632406)
			(xy 314.256928 -281.576272) (xy 314.249522 -281.569758) (xy 314.231224 -281.562449) (xy 314.221368 -281.562048)
			(xy 314.128404 -281.562048) (xy 314.118552 -281.562458) (xy 314.100261 -281.569775) (xy 314.092844 -281.576272)
			(xy 314.035186 -281.632406) (xy 314.027058 -281.65044) (xy 314.026804 -281.660346) (xy 314.025537 -281.685501)
			(xy 314.016234 -281.734999) (xy 313.999455 -281.782486) (xy 313.975597 -281.826841) (xy 313.945223 -281.867016)
			(xy 313.909052 -281.902062) (xy 313.867937 -281.931151) (xy 313.822849 -281.953595) (xy 313.774855 -281.968865)
			(xy 313.725088 -281.9766) (xy 313.699906 -281.977084) (xy 313.67473 -281.976629) (xy 313.624972 -281.968926)
			(xy 313.576983 -281.953687) (xy 313.531896 -281.931272) (xy 313.490779 -281.90221) (xy 313.454603 -281.867189)
			(xy 313.424222 -281.827036) (xy 313.400356 -281.782701) (xy 313.383569 -281.735231) (xy 313.374256 -281.685748)
			(xy 313.373008 -281.6606) (xy 313.372754 -281.650694) (xy 313.364626 -281.632406) (xy 313.306968 -281.576526)
			(xy 313.299587 -281.569942) (xy 313.281288 -281.562488) (xy 313.271408 -281.562048) (xy 313.156346 -281.562048)
			(xy 313.146532 -281.56254) (xy 313.128359 -281.569971) (xy 313.12104 -281.576526) (xy 313.063128 -281.63266)
			(xy 313.055254 -281.650186) (xy 313.054746 -281.660346) (xy 313.053427 -281.685017) (xy 313.043812 -281.733476)
			(xy 313.026518 -281.779753) (xy 313.001996 -281.822641) (xy 312.970888 -281.861021) (xy 312.934004 -281.893889)
			(xy 312.892309 -281.920388) (xy 312.84689 -281.939826) (xy 312.798934 -281.951695) (xy 312.749692 -281.955687)
			(xy 312.70045 -281.951695) (xy 312.652494 -281.939826) (xy 312.607075 -281.920388) (xy 312.56538 -281.893889)
			(xy 312.528496 -281.861021) (xy 312.497388 -281.822641) (xy 312.472866 -281.779753) (xy 312.455572 -281.733476)
			(xy 312.445957 -281.685017) (xy 312.444638 -281.660346) (xy 312.44413 -281.650186) (xy 312.436256 -281.63266)
			(xy 312.378344 -281.576526) (xy 312.371015 -281.569982) (xy 312.352852 -281.562537) (xy 312.343038 -281.562048)
			(xy 312.206386 -281.562048) (xy 312.196576 -281.562551) (xy 312.178419 -281.569997) (xy 312.17108 -281.576526)
			(xy 312.113168 -281.63266) (xy 312.105294 -281.650186) (xy 312.104786 -281.660346) (xy 312.103467 -281.685017)
			(xy 312.093852 -281.733476) (xy 312.076558 -281.779753) (xy 312.052036 -281.822641) (xy 312.020928 -281.861021)
			(xy 311.984044 -281.893889) (xy 311.942349 -281.920388) (xy 311.89693 -281.939826) (xy 311.848974 -281.951695)
			(xy 311.799732 -281.955687) (xy 311.75049 -281.951695) (xy 311.702534 -281.939826) (xy 311.657115 -281.920388)
			(xy 311.61542 -281.893889) (xy 311.578536 -281.861021) (xy 311.547428 -281.822641) (xy 311.522906 -281.779753)
			(xy 311.505612 -281.733476) (xy 311.495997 -281.685017) (xy 311.494678 -281.660346) (xy 311.49417 -281.650186)
			(xy 311.486296 -281.63266) (xy 311.428384 -281.576526) (xy 311.421057 -281.569975) (xy 311.402894 -281.562517)
			(xy 311.393078 -281.562048) (xy 311.256172 -281.562048) (xy 311.246363 -281.562553) (xy 311.228209 -281.570003)
			(xy 311.220866 -281.576526) (xy 311.162954 -281.63266) (xy 311.15508 -281.650186) (xy 311.154572 -281.660346)
			(xy 311.153253 -281.685017) (xy 311.143638 -281.733476) (xy 311.126344 -281.779753) (xy 311.101822 -281.822641)
			(xy 311.070714 -281.861021) (xy 311.03383 -281.893889) (xy 310.992135 -281.920388) (xy 310.946716 -281.939826)
			(xy 310.89876 -281.951695) (xy 310.849518 -281.955687) (xy 310.800276 -281.951695) (xy 310.75232 -281.939826)
			(xy 310.706901 -281.920388) (xy 310.665206 -281.893889) (xy 310.628322 -281.861021) (xy 310.597214 -281.822641)
			(xy 310.572692 -281.779753) (xy 310.555398 -281.733476) (xy 310.545783 -281.685017) (xy 310.544464 -281.660346)
			(xy 310.543956 -281.650186) (xy 310.536082 -281.63266) (xy 310.47817 -281.576526) (xy 310.470843 -281.569977)
			(xy 310.452679 -281.562524) (xy 310.442864 -281.562048) (xy 310.306212 -281.562048) (xy 310.2964 -281.562546)
			(xy 310.278236 -281.569986) (xy 310.270906 -281.576526) (xy 310.212994 -281.632406) (xy 310.20512 -281.650186)
			(xy 310.204612 -281.660346) (xy 310.203167 -281.686375) (xy 310.192517 -281.737402) (xy 310.17336 -281.785882)
			(xy 310.146252 -281.830406) (xy 310.11198 -281.869682) (xy 310.071539 -281.902572) (xy 310.026102 -281.92812)
			(xy 309.976987 -281.945584) (xy 309.925621 -281.954459) (xy 309.899558 -281.954986) (xy 309.873476 -281.95446)
			(xy 309.82207 -281.945603) (xy 309.772917 -281.928137) (xy 309.727448 -281.90257) (xy 309.686987 -281.869647)
			(xy 309.65271 -281.830326) (xy 309.625616 -281.78575) (xy 309.606494 -281.737218) (xy 309.595898 -281.686142)
			(xy 309.594504 -281.660092) (xy 309.593996 -281.649932) (xy 309.586122 -281.632406) (xy 309.52821 -281.576272)
			(xy 309.520862 -281.56978) (xy 309.502699 -281.562443) (xy 309.492904 -281.562048) (xy 309.356506 -281.562048)
			(xy 309.346723 -281.562503) (xy 309.328578 -281.569829) (xy 309.3212 -281.576272) (xy 309.263288 -281.632406)
			(xy 309.255414 -281.650186) (xy 309.254906 -281.660092) (xy 309.253504 -281.686152) (xy 309.242924 -281.737253)
			(xy 309.223814 -281.785813) (xy 309.19673 -281.830419) (xy 309.16246 -281.869773) (xy 309.122 -281.902732)
			(xy 309.076527 -281.928335) (xy 309.027365 -281.945838) (xy 308.975944 -281.954731) (xy 308.949852 -281.95524)
			(xy 308.923772 -281.954713) (xy 308.872369 -281.945855) (xy 308.82322 -281.928388) (xy 308.777756 -281.90282)
			(xy 308.7373 -281.869896) (xy 308.703029 -281.830574) (xy 308.675942 -281.785998) (xy 308.656826 -281.737467)
			(xy 308.646239 -281.686392) (xy 308.644798 -281.660346) (xy 308.64429 -281.650186) (xy 308.636416 -281.63266)
			(xy 308.578504 -281.576526) (xy 308.571173 -281.569988) (xy 308.553009 -281.562558) (xy 308.543198 -281.562048)
			(xy 308.406546 -281.562048) (xy 308.396732 -281.56254) (xy 308.378559 -281.569971) (xy 308.37124 -281.576526)
			(xy 308.313328 -281.63266) (xy 308.305454 -281.650186) (xy 308.304946 -281.660346) (xy 308.303524 -281.68639)
			(xy 308.292911 -281.737453) (xy 308.273779 -281.785971) (xy 308.246682 -281.830534) (xy 308.21241 -281.869847)
			(xy 308.171958 -281.902766) (xy 308.126502 -281.928335) (xy 308.077363 -281.945811) (xy 308.025969 -281.954686)
			(xy 307.999892 -281.95524) (xy 307.973795 -281.954715) (xy 307.922361 -281.945853) (xy 307.873183 -281.928371)
			(xy 307.827695 -281.902779) (xy 307.787223 -281.869822) (xy 307.752947 -281.830462) (xy 307.725866 -281.785845)
			(xy 307.706768 -281.737271) (xy 307.696211 -281.686157) (xy 307.694838 -281.660092) (xy 307.69433 -281.650186)
			(xy 307.686456 -281.632406) (xy 307.628544 -281.576272) (xy 307.621193 -281.56979) (xy 307.60303 -281.562476)
			(xy 307.593238 -281.562048) (xy 307.456586 -281.562048) (xy 307.446797 -281.562489) (xy 307.428632 -281.569794)
			(xy 307.42128 -281.576272) (xy 307.363368 -281.632406) (xy 307.355494 -281.650186) (xy 307.354986 -281.660092)
			(xy 307.353584 -281.686151) (xy 307.343004 -281.737251) (xy 307.323894 -281.78581) (xy 307.296809 -281.830414)
			(xy 307.262538 -281.869766) (xy 307.222078 -281.902722) (xy 307.176606 -281.928322) (xy 307.127444 -281.945823)
			(xy 307.076024 -281.954713) (xy 307.049932 -281.95524) (xy 307.023853 -281.954711) (xy 306.972453 -281.945851)
			(xy 306.923307 -281.928382) (xy 306.877846 -281.902813) (xy 306.837392 -281.869889) (xy 306.803125 -281.830567)
			(xy 306.776039 -281.785993) (xy 306.756925 -281.737463) (xy 306.746339 -281.686391) (xy 306.744878 -281.660346)
			(xy 306.74437 -281.650186) (xy 306.736496 -281.63266) (xy 306.678584 -281.576526) (xy 306.671257 -281.569975)
			(xy 306.653094 -281.562517) (xy 306.643278 -281.562048) (xy 306.506372 -281.562048) (xy 306.496563 -281.562553)
			(xy 306.478409 -281.570003) (xy 306.471066 -281.576526) (xy 306.413154 -281.63266) (xy 306.40528 -281.650186)
			(xy 306.404772 -281.660346) (xy 306.40335 -281.686391) (xy 306.392737 -281.737455) (xy 306.373605 -281.785975)
			(xy 306.34651 -281.830541) (xy 306.312238 -281.869856) (xy 306.271786 -281.902778) (xy 306.22633 -281.928351)
			(xy 306.17719 -281.945831) (xy 306.125796 -281.95471) (xy 306.099718 -281.95524) (xy 306.073626 -281.954709)
			(xy 306.0222 -281.945837) (xy 305.973033 -281.928348) (xy 305.927557 -281.902752) (xy 305.887096 -281.869795)
			(xy 305.852829 -281.830437) (xy 305.825756 -281.785825) (xy 305.806664 -281.737258) (xy 305.79611 -281.686151)
			(xy 305.794664 -281.660092) (xy 305.794156 -281.650186) (xy 305.786282 -281.632406) (xy 305.72837 -281.576272)
			(xy 305.72102 -281.569786) (xy 305.702857 -281.562463) (xy 305.693064 -281.562048) (xy 305.556412 -281.562048)
			(xy 305.546628 -281.562502) (xy 305.528482 -281.569826) (xy 305.521106 -281.576272) (xy 305.463194 -281.632406)
			(xy 305.45532 -281.650186) (xy 305.454812 -281.660092) (xy 305.45341 -281.686152) (xy 305.442831 -281.737254)
			(xy 305.423721 -281.785814) (xy 305.396637 -281.830421) (xy 305.362366 -281.869776) (xy 305.321906 -281.902735)
			(xy 305.276434 -281.928339) (xy 305.227272 -281.945843) (xy 305.17585 -281.954737) (xy 305.149758 -281.95524)
			(xy 305.123677 -281.954713) (xy 305.072274 -281.945856) (xy 305.023124 -281.92839) (xy 304.977659 -281.902822)
			(xy 304.937202 -281.869898) (xy 304.902931 -281.830576) (xy 304.875843 -281.786) (xy 304.856727 -281.737468)
			(xy 304.846139 -281.686393) (xy 304.844704 -281.660346) (xy 304.844196 -281.650186) (xy 304.836322 -281.63266)
			(xy 304.77841 -281.576526) (xy 304.77108 -281.569987) (xy 304.752916 -281.562555) (xy 304.743104 -281.562048)
			(xy 304.606452 -281.562048) (xy 304.596637 -281.562539) (xy 304.578463 -281.569969) (xy 304.571146 -281.576526)
			(xy 304.513234 -281.63266) (xy 304.50536 -281.650186) (xy 304.504852 -281.660346) (xy 304.50343 -281.68639)
			(xy 304.492817 -281.737453) (xy 304.473685 -281.785972) (xy 304.446589 -281.830536) (xy 304.412317 -281.869849)
			(xy 304.371864 -281.902769) (xy 304.326408 -281.928339) (xy 304.277269 -281.945816) (xy 304.225875 -281.954692)
			(xy 304.199798 -281.95524) (xy 304.173701 -281.954716) (xy 304.122265 -281.945854) (xy 304.073087 -281.928373)
			(xy 304.027598 -281.902781) (xy 303.987126 -281.869824) (xy 303.952849 -281.830464) (xy 303.925767 -281.785846)
			(xy 303.906668 -281.737272) (xy 303.896111 -281.686158) (xy 303.894744 -281.660092) (xy 303.894236 -281.650186)
			(xy 303.886362 -281.632406) (xy 303.82845 -281.576272) (xy 303.821099 -281.569789) (xy 303.802936 -281.562473)
			(xy 303.793144 -281.562048) (xy 303.656492 -281.562048) (xy 303.646702 -281.562488) (xy 303.628536 -281.569792)
			(xy 303.621186 -281.576272) (xy 303.563274 -281.632406) (xy 303.5554 -281.650186) (xy 303.554892 -281.660092)
			(xy 303.55349 -281.686152) (xy 303.54291 -281.737252) (xy 303.5238 -281.785811) (xy 303.496715 -281.830415)
			(xy 303.462445 -281.869768) (xy 303.421985 -281.902725) (xy 303.376512 -281.928326) (xy 303.32735 -281.945827)
			(xy 303.27593 -281.954719) (xy 303.249838 -281.95524) (xy 303.223759 -281.954712) (xy 303.172358 -281.945852)
			(xy 303.123211 -281.928384) (xy 303.077749 -281.902815) (xy 303.037295 -281.869891) (xy 303.003026 -281.830569)
			(xy 302.97594 -281.785995) (xy 302.956826 -281.737464) (xy 302.946239 -281.686391) (xy 302.944784 -281.660346)
			(xy 302.944276 -281.650186) (xy 302.936402 -281.63266) (xy 302.87849 -281.576526) (xy 302.871164 -281.569974)
			(xy 302.853 -281.562514) (xy 302.843184 -281.562048) (xy 302.706532 -281.562048) (xy 302.696719 -281.562543)
			(xy 302.678549 -281.569977) (xy 302.671226 -281.576526) (xy 302.613314 -281.63266) (xy 302.60544 -281.650186)
			(xy 302.604932 -281.660346) (xy 302.60351 -281.686393) (xy 302.592899 -281.737461) (xy 302.573768 -281.785986)
			(xy 302.546673 -281.830557) (xy 302.512402 -281.869878) (xy 302.471951 -281.902807) (xy 302.426495 -281.928388)
			(xy 302.377354 -281.945877) (xy 302.325958 -281.954766) (xy 302.299878 -281.95524) (xy 302.273782 -281.954714)
			(xy 302.222349 -281.94585) (xy 302.173173 -281.928366) (xy 302.127688 -281.902774) (xy 302.087218 -281.869817)
			(xy 302.052944 -281.830457) (xy 302.025864 -281.785841) (xy 302.006767 -281.737269) (xy 301.996211 -281.686156)
			(xy 301.994824 -281.660092) (xy 301.994316 -281.650186) (xy 301.986442 -281.632406) (xy 301.92853 -281.576272)
			(xy 301.921178 -281.569792) (xy 301.903015 -281.562483) (xy 301.893224 -281.562048) (xy 301.756572 -281.562048)
			(xy 301.746784 -281.562491) (xy 301.728622 -281.5698) (xy 301.721266 -281.576272) (xy 301.663354 -281.632406)
			(xy 301.65548 -281.650186) (xy 301.654972 -281.660092) (xy 301.65357 -281.686151) (xy 301.64299 -281.73725)
			(xy 301.623879 -281.785807) (xy 301.596794 -281.83041) (xy 301.562523 -281.869761) (xy 301.522063 -281.902716)
			(xy 301.476591 -281.928314) (xy 301.427429 -281.945812) (xy 301.376009 -281.9547) (xy 301.349918 -281.95524)
			(xy 301.32384 -281.95471) (xy 301.272441 -281.945848) (xy 301.223298 -281.928378) (xy 301.177839 -281.902808)
			(xy 301.137387 -281.869884) (xy 301.103121 -281.830563) (xy 301.076037 -281.785989) (xy 301.056924 -281.737461)
			(xy 301.046338 -281.68639) (xy 301.044864 -281.660346) (xy 301.044356 -281.650186) (xy 301.036482 -281.63266)
			(xy 300.97857 -281.576526) (xy 300.971243 -281.569977) (xy 300.953079 -281.562524) (xy 300.943264 -281.562048)
			(xy 300.806358 -281.562048) (xy 300.796551 -281.562556) (xy 300.7784 -281.570009) (xy 300.771052 -281.576526)
			(xy 300.71314 -281.63266) (xy 300.705266 -281.650186) (xy 300.704758 -281.660346) (xy 300.703336 -281.68639)
			(xy 300.692723 -281.737454) (xy 300.673591 -281.785973) (xy 300.646495 -281.830537) (xy 300.612223 -281.869851)
			(xy 300.571771 -281.902772) (xy 300.526315 -281.928343) (xy 300.477175 -281.945821) (xy 300.425781 -281.954697)
			(xy 300.399704 -281.95524) (xy 300.373607 -281.954716) (xy 300.32217 -281.945855) (xy 300.272991 -281.928374)
			(xy 300.227501 -281.902783) (xy 300.187028 -281.869826) (xy 300.15275 -281.830466) (xy 300.125667 -281.785848)
			(xy 300.106569 -281.737274) (xy 300.096011 -281.686158) (xy 300.09465 -281.660092) (xy 300.094142 -281.650186)
			(xy 300.086268 -281.632406) (xy 300.028356 -281.576272) (xy 300.021005 -281.569788) (xy 300.002842 -281.56247)
			(xy 299.99305 -281.562048) (xy 299.856398 -281.562048) (xy 299.846608 -281.562487) (xy 299.82844 -281.569789)
			(xy 299.821092 -281.576272) (xy 299.76318 -281.632406) (xy 299.755306 -281.650186) (xy 299.754798 -281.660092)
			(xy 299.753396 -281.686152) (xy 299.742816 -281.737252) (xy 299.723706 -281.785812) (xy 299.696622 -281.830417)
			(xy 299.662351 -281.869771) (xy 299.621891 -281.902728) (xy 299.576419 -281.92833) (xy 299.527257 -281.945832)
			(xy 299.475836 -281.954724) (xy 299.449744 -281.95524) (xy 299.423664 -281.954712) (xy 299.372263 -281.945853)
			(xy 299.323115 -281.928385) (xy 299.277652 -281.902817) (xy 299.237197 -281.869893) (xy 299.202927 -281.830571)
			(xy 299.175841 -281.785996) (xy 299.156726 -281.737465) (xy 299.146139 -281.686392) (xy 299.14469 -281.660346)
			(xy 299.144182 -281.650186) (xy 299.136308 -281.63266) (xy 299.078396 -281.576526) (xy 299.071065 -281.569989)
			(xy 299.052901 -281.562562) (xy 299.04309 -281.562048) (xy 298.906438 -281.562048) (xy 298.896624 -281.562542)
			(xy 298.878453 -281.569975) (xy 298.871132 -281.576526) (xy 298.81322 -281.63266) (xy 298.805346 -281.650186)
			(xy 298.804838 -281.660346) (xy 298.803416 -281.686389) (xy 298.792803 -281.737452) (xy 298.77367 -281.78597)
			(xy 298.746574 -281.830532) (xy 298.712302 -281.869844) (xy 298.671849 -281.902762) (xy 298.626393 -281.92833)
			(xy 298.577254 -281.945805) (xy 298.525861 -281.954679) (xy 298.499784 -281.95524) (xy 298.473688 -281.954714)
			(xy 298.422254 -281.945851) (xy 298.373077 -281.928368) (xy 298.327591 -281.902776) (xy 298.28712 -281.869819)
			(xy 298.252845 -281.830459) (xy 298.225765 -281.785842) (xy 298.206668 -281.73727) (xy 298.196111 -281.686157)
			(xy 298.19473 -281.660092) (xy 298.194222 -281.650186) (xy 298.186348 -281.632406) (xy 298.128436 -281.576272)
			(xy 298.121084 -281.569791) (xy 298.102921 -281.56248) (xy 298.09313 -281.562048) (xy 297.956478 -281.562048)
			(xy 297.946689 -281.56249) (xy 297.928526 -281.569798) (xy 297.921172 -281.576272) (xy 297.86326 -281.632406)
			(xy 297.855386 -281.650186) (xy 297.854878 -281.660092) (xy 297.853476 -281.686151) (xy 297.842896 -281.73725)
			(xy 297.823785 -281.785808) (xy 297.796701 -281.830412) (xy 297.76243 -281.869763) (xy 297.721969 -281.902718)
			(xy 297.676497 -281.928318) (xy 297.627336 -281.945817) (xy 297.575915 -281.954706) (xy 297.549824 -281.95524)
			(xy 297.523745 -281.954711) (xy 297.472346 -281.945849) (xy 297.423202 -281.928379) (xy 297.377742 -281.90281)
			(xy 297.33729 -281.869886) (xy 297.303023 -281.830565) (xy 297.275938 -281.785991) (xy 297.256825 -281.737462)
			(xy 297.246238 -281.68639) (xy 297.24477 -281.660346) (xy 297.244262 -281.650186) (xy 297.236388 -281.63266)
			(xy 297.178476 -281.576526) (xy 297.171149 -281.569976) (xy 297.152986 -281.562521) (xy 297.14317 -281.562048)
			(xy 297.006518 -281.562048) (xy 296.996706 -281.562545) (xy 296.97854 -281.569983) (xy 296.971212 -281.576526)
			(xy 296.9133 -281.63266) (xy 296.905426 -281.650186) (xy 296.904918 -281.660346) (xy 296.903496 -281.686392)
			(xy 296.892884 -281.73746) (xy 296.873753 -281.785984) (xy 296.846658 -281.830553) (xy 296.812387 -281.869873)
			(xy 296.771936 -281.902801) (xy 296.72648 -281.928379) (xy 296.677339 -281.945866) (xy 296.625943 -281.954753)
			(xy 296.599864 -281.95524) (xy 296.573769 -281.954713) (xy 296.522338 -281.945847) (xy 296.473164 -281.928362)
			(xy 296.427681 -281.902769) (xy 296.387213 -281.869812) (xy 296.352941 -281.830452) (xy 296.325862 -281.785837)
			(xy 296.306767 -281.737266) (xy 296.29621 -281.686155) (xy 296.29481 -281.660092) (xy 296.294302 -281.650186)
			(xy 296.286428 -281.632406) (xy 296.228516 -281.576272) (xy 296.221163 -281.569794) (xy 296.203 -281.562491)
			(xy 296.19321 -281.562048) (xy 296.056558 -281.562048) (xy 296.046771 -281.562494) (xy 296.028613 -281.569806)
			(xy 296.021252 -281.576272) (xy 295.96334 -281.632406) (xy 295.955466 -281.650186) (xy 295.954958 -281.660092)
			(xy 295.953556 -281.686151) (xy 295.942976 -281.737248) (xy 295.923865 -281.785805) (xy 295.89678 -281.830407)
			(xy 295.862508 -281.869756) (xy 295.822048 -281.902709) (xy 295.776575 -281.928306) (xy 295.727414 -281.945801)
			(xy 295.675995 -281.954688) (xy 295.649904 -281.95524) (xy 295.623821 -281.954717) (xy 295.572411 -281.945866)
			(xy 295.523255 -281.928404) (xy 295.477783 -281.902838) (xy 295.437319 -281.869915) (xy 295.403042 -281.830591)
			(xy 295.375949 -281.786012) (xy 295.356829 -281.737477) (xy 295.346239 -281.686397) (xy 295.34485 -281.660346)
			(xy 295.344342 -281.650186) (xy 295.336468 -281.63266) (xy 295.278556 -281.576526) (xy 295.271228 -281.56998)
			(xy 295.253064 -281.562531) (xy 295.24325 -281.562048) (xy 295.106344 -281.562048) (xy 295.09653 -281.56254)
			(xy 295.078357 -281.569972) (xy 295.071038 -281.576526) (xy 295.013126 -281.63266) (xy 295.005252 -281.650186)
			(xy 295.004744 -281.660346) (xy 295.003322 -281.68639) (xy 294.992709 -281.737453) (xy 294.973576 -281.785971)
			(xy 294.94648 -281.830533) (xy 294.912208 -281.869846) (xy 294.871756 -281.902765) (xy 294.826299 -281.928334)
			(xy 294.77716 -281.94581) (xy 294.725767 -281.954685) (xy 294.69969 -281.95524) (xy 294.673594 -281.954715)
			(xy 294.622159 -281.945852) (xy 294.572981 -281.92837) (xy 294.527494 -281.902778) (xy 294.487023 -281.869821)
			(xy 294.452747 -281.830461) (xy 294.425666 -281.785844) (xy 294.406568 -281.737271) (xy 294.396011 -281.686157)
			(xy 294.394636 -281.660092) (xy 294.394128 -281.650186) (xy 294.386254 -281.632406) (xy 294.328342 -281.576272)
			(xy 294.320991 -281.569791) (xy 294.302828 -281.562477) (xy 294.293036 -281.562048) (xy 294.156384 -281.562048)
			(xy 294.146595 -281.562489) (xy 294.12843 -281.569795) (xy 294.121078 -281.576272) (xy 294.063166 -281.632406)
			(xy 294.055292 -281.650186) (xy 294.054784 -281.660092) (xy 294.053382 -281.686151) (xy 294.042802 -281.737251)
			(xy 294.023692 -281.785809) (xy 293.996607 -281.830413) (xy 293.962336 -281.869766) (xy 293.921876 -281.902721)
			(xy 293.876403 -281.928321) (xy 293.827242 -281.945821) (xy 293.775821 -281.954711) (xy 293.74973 -281.95524)
			(xy 293.723651 -281.954711) (xy 293.672251 -281.94585) (xy 293.623106 -281.928381) (xy 293.577645 -281.902812)
			(xy 293.537192 -281.869888) (xy 293.502924 -281.830567) (xy 293.475839 -281.785992) (xy 293.456725 -281.737463)
			(xy 293.446139 -281.686391) (xy 293.444676 -281.660346) (xy 293.444168 -281.650186) (xy 293.436294 -281.63266)
			(xy 293.378382 -281.576526) (xy 293.371055 -281.569976) (xy 293.352892 -281.562518) (xy 293.343076 -281.562048)
			(xy 293.206424 -281.562048) (xy 293.196611 -281.562544) (xy 293.178444 -281.569981) (xy 293.171118 -281.576526)
			(xy 293.113206 -281.63266) (xy 293.105332 -281.650186) (xy 293.104824 -281.660346) (xy 293.103402 -281.686392)
			(xy 293.092791 -281.737461) (xy 293.073659 -281.785985) (xy 293.046565 -281.830554) (xy 293.012294 -281.869875)
			(xy 292.971842 -281.902803) (xy 292.926386 -281.928383) (xy 292.877246 -281.945871) (xy 292.825849 -281.954758)
			(xy 292.79977 -281.95524) (xy 292.773675 -281.954713) (xy 292.722243 -281.945848) (xy 292.673068 -281.928364)
			(xy 292.627584 -281.902771) (xy 292.587115 -281.869814) (xy 292.552842 -281.830454) (xy 292.525763 -281.785839)
			(xy 292.506667 -281.737267) (xy 292.496111 -281.686156) (xy 292.494716 -281.660092) (xy 292.494208 -281.650186)
			(xy 292.486334 -281.632406) (xy 292.428422 -281.576272) (xy 292.42107 -281.569794) (xy 292.402906 -281.562487)
			(xy 292.393116 -281.562048) (xy 292.256464 -281.562048) (xy 292.246676 -281.562493) (xy 292.228517 -281.569804)
			(xy 292.221158 -281.576272) (xy 292.163246 -281.632406) (xy 292.155372 -281.650186) (xy 292.154864 -281.660092)
			(xy 292.153564 -281.684777) (xy 292.14398 -281.733267) (xy 292.126707 -281.77958) (xy 292.102198 -281.822504)
			(xy 292.071092 -281.860918) (xy 292.034203 -281.893817) (xy 291.992494 -281.920343) (xy 291.947056 -281.939801)
			(xy 291.899077 -281.951683) (xy 291.84981 -281.955678) (xy 291.800543 -281.951683) (xy 291.752564 -281.939801)
			(xy 291.707126 -281.920343) (xy 291.665417 -281.893817) (xy 291.628528 -281.860918) (xy 291.597422 -281.822504)
			(xy 291.572913 -281.77958) (xy 291.55564 -281.733267) (xy 291.546056 -281.684777) (xy 291.544756 -281.660092)
			(xy 291.544248 -281.650186) (xy 291.536374 -281.632406) (xy 291.478462 -281.576272) (xy 291.471112 -281.569788)
			(xy 291.452949 -281.562467) (xy 291.443156 -281.562048) (xy 291.424868 -281.562048) (xy 291.419142 -281.561902)
			(xy 291.407981 -281.559344) (xy 291.40277 -281.556968) (xy 291.391641 -281.552253) (xy 291.367509 -281.55265)
			(xy 291.356542 -281.55773) (xy 291.312854 -281.579574) (xy 291.305271 -281.583502) (xy 291.293084 -281.595452)
			(xy 291.288978 -281.602942) (xy 291.265773 -281.648242) (xy 291.211172 -281.734146) (xy 291.180012 -281.774392)
			(xy 291.17417 -281.78379) (xy 291.162621 -281.806313) (xy 291.13322 -281.847509) (xy 291.097425 -281.883291)
			(xy 291.056218 -281.912678) (xy 291.033708 -281.924252) (xy 291.02431 -281.930094) (xy 290.98458 -281.960826)
			(xy 290.899859 -282.014791) (xy 290.809991 -282.059664) (xy 290.763198 -282.077922) (xy 290.753722 -282.081983)
			(xy 290.738819 -282.096202) (xy 290.73068 -282.115123) (xy 290.730178 -282.12542) (xy 290.729617 -282.150648)
			(xy 290.721238 -282.200405) (xy 290.704791 -282.248106) (xy 290.680726 -282.292455) (xy 290.649696 -282.332243)
			(xy 290.612546 -282.366388) (xy 290.570288 -282.393959) (xy 290.524072 -282.414207) (xy 290.475155 -282.426581)
			(xy 290.42487 -282.430743) (xy 290.374585 -282.426581) (xy 290.325668 -282.414207) (xy 290.279452 -282.393959)
			(xy 290.237194 -282.366388) (xy 290.200044 -282.332243) (xy 290.169014 -282.292455) (xy 290.144949 -282.248106)
			(xy 290.128502 -282.200405) (xy 290.120123 -282.150648) (xy 290.119562 -282.12542) (xy 290.119101 -282.115106)
			(xy 290.110997 -282.096141) (xy 290.096058 -282.08192) (xy 290.086542 -282.077922) (xy 290.046613 -282.062479)
			(xy 289.969407 -282.025471) (xy 289.932364 -282.004008) (xy 289.924168 -281.999636) (xy 289.905877 -281.996478)
			(xy 289.887655 -282.000006) (xy 289.879532 -282.004516) (xy 289.825938 -282.038044) (xy 289.82543 -282.038044)
			(xy 289.809174 -282.048458) (xy 289.805618 -282.05049) (xy 289.792156 -282.057856) (xy 289.777932 -282.084526)
			(xy 289.779456 -282.101798) (xy 289.780218 -282.123388) (xy 289.780218 -282.125928) (xy 289.779671 -282.149867)
			(xy 289.772038 -282.197135) (xy 289.757119 -282.242632) (xy 289.735282 -282.285243) (xy 289.707061 -282.323923)
			(xy 289.673148 -282.357723) (xy 289.634374 -282.385815) (xy 289.591691 -282.40751) (xy 289.546144 -282.422277)
			(xy 289.49885 -282.429752) (xy 289.47491 -282.43022) (xy 289.450918 -282.42975) (xy 289.403524 -282.422245)
			(xy 289.357888 -282.407419) (xy 289.315133 -282.385636) (xy 289.276312 -282.357433) (xy 289.242381 -282.323504)
			(xy 289.214175 -282.284686) (xy 289.192389 -282.241932) (xy 289.17756 -282.196297) (xy 289.170052 -282.148904)
			(xy 289.169602 -282.124912) (xy 289.169602 -282.124404) (xy 289.170618 -282.099766) (xy 289.171888 -282.085288)
			(xy 289.159188 -282.060142) (xy 289.07232 -282.005786) (xy 289.063035 -282.000642) (xy 289.042044 -281.997642)
			(xy 289.03168 -281.999944) (xy 289.017964 -282.003754) (xy 289.012376 -282.007056) (xy 288.988086 -282.021024)
			(xy 288.938143 -282.046441) (xy 288.912554 -282.057856) (xy 288.863024 -282.077922) (xy 288.853559 -282.081992)
			(xy 288.838678 -282.096216) (xy 288.830552 -282.115129) (xy 288.830004 -282.12542) (xy 288.829443 -282.150648)
			(xy 288.821064 -282.200405) (xy 288.804617 -282.248106) (xy 288.780552 -282.292455) (xy 288.749522 -282.332243)
			(xy 288.712372 -282.366388) (xy 288.670114 -282.393959) (xy 288.623898 -282.414207) (xy 288.574981 -282.426581)
			(xy 288.524696 -282.430743) (xy 288.474411 -282.426581) (xy 288.425494 -282.414207) (xy 288.379278 -282.393959)
			(xy 288.33702 -282.366388) (xy 288.29987 -282.332243) (xy 288.26884 -282.292455) (xy 288.244775 -282.248106)
			(xy 288.228328 -282.200405) (xy 288.219949 -282.150648) (xy 288.219388 -282.12542) (xy 288.218927 -282.115105)
			(xy 288.210825 -282.096136) (xy 288.19589 -282.081909) (xy 288.186368 -282.077922) (xy 288.14644 -282.062476)
			(xy 288.069237 -282.025463) (xy 288.03219 -282.004008) (xy 288.023994 -281.999631) (xy 288.0057 -281.996464)
			(xy 287.987471 -281.999985) (xy 287.979358 -282.004516) (xy 287.925764 -282.038044) (xy 287.925256 -282.038044)
			(xy 287.909 -282.048458) (xy 287.905444 -282.05049) (xy 287.891982 -282.057856) (xy 287.877758 -282.084526)
			(xy 287.879282 -282.101798) (xy 287.880044 -282.123388) (xy 287.880044 -282.125928) (xy 287.879495 -282.150274)
			(xy 287.871618 -282.198328) (xy 287.856212 -282.244522) (xy 287.833667 -282.287684) (xy 287.804555 -282.32672)
			(xy 287.769615 -282.360638) (xy 287.729733 -282.388579) (xy 287.685922 -282.409833) (xy 287.639291 -282.423863)
			(xy 287.591024 -282.430311) (xy 287.542346 -282.429015) (xy 287.518348 -282.424886) (xy 287.505902 -282.4226)
			(xy 287.48228 -282.429966) (xy 287.40481 -282.507436) (xy 287.397444 -282.531058) (xy 287.39973 -282.543504)
			(xy 287.402216 -282.557469) (xy 287.404889 -282.585709) (xy 287.405064 -282.599892) (xy 306.743874 -282.599892)
			(xy 306.747834 -282.550838) (xy 306.759611 -282.503054) (xy 306.778902 -282.457778) (xy 306.805205 -282.416182)
			(xy 306.83784 -282.379345) (xy 306.875961 -282.34822) (xy 306.918582 -282.323613) (xy 306.964598 -282.306161)
			(xy 307.012817 -282.296317) (xy 307.061992 -282.294336) (xy 307.110847 -282.300268) (xy 307.158118 -282.31396)
			(xy 307.20258 -282.335058) (xy 307.243083 -282.363014) (xy 307.278576 -282.397106) (xy 307.308141 -282.43645)
			(xy 307.331012 -282.480027) (xy 307.346596 -282.526708) (xy 307.354491 -282.575285) (xy 307.354986 -282.599892)
			(xy 307.354491 -282.624499) (xy 307.354312 -282.6256) (xy 308.623204 -282.6256) (xy 308.623204 -282.574184)
			(xy 308.631247 -282.523402) (xy 308.647135 -282.474503) (xy 308.670478 -282.428691) (xy 308.700699 -282.387095)
			(xy 308.737055 -282.350739) (xy 308.778651 -282.320518) (xy 308.824463 -282.297175) (xy 308.873362 -282.281287)
			(xy 308.924144 -282.273244) (xy 308.97556 -282.273244) (xy 309.026342 -282.281287) (xy 309.075241 -282.297175)
			(xy 309.121053 -282.320518) (xy 309.162649 -282.350739) (xy 309.199005 -282.387095) (xy 309.229226 -282.428691)
			(xy 309.252569 -282.474503) (xy 309.268457 -282.523402) (xy 309.2765 -282.574184) (xy 309.277004 -282.599892)
			(xy 309.2765 -282.6256) (xy 309.573164 -282.6256) (xy 309.573164 -282.574184) (xy 309.581207 -282.523402)
			(xy 309.597095 -282.474503) (xy 309.620438 -282.428691) (xy 309.650659 -282.387095) (xy 309.687015 -282.350739)
			(xy 309.728611 -282.320518) (xy 309.774423 -282.297175) (xy 309.823322 -282.281287) (xy 309.874104 -282.273244)
			(xy 309.92552 -282.273244) (xy 309.976302 -282.281287) (xy 310.025201 -282.297175) (xy 310.071013 -282.320518)
			(xy 310.112609 -282.350739) (xy 310.148965 -282.387095) (xy 310.179186 -282.428691) (xy 310.202529 -282.474503)
			(xy 310.218417 -282.523402) (xy 310.22646 -282.574184) (xy 310.226964 -282.599892) (xy 310.543968 -282.599892)
			(xy 310.547928 -282.550838) (xy 310.559705 -282.503054) (xy 310.578996 -282.457778) (xy 310.605299 -282.416182)
			(xy 310.637934 -282.379345) (xy 310.676055 -282.34822) (xy 310.718676 -282.323613) (xy 310.764692 -282.306161)
			(xy 310.812911 -282.296317) (xy 310.862086 -282.294336) (xy 310.910941 -282.300268) (xy 310.958212 -282.31396)
			(xy 311.002674 -282.335058) (xy 311.043177 -282.363014) (xy 311.07867 -282.397106) (xy 311.108235 -282.43645)
			(xy 311.131106 -282.480027) (xy 311.14669 -282.526708) (xy 311.154585 -282.575285) (xy 311.15508 -282.599892)
			(xy 311.154585 -282.624499) (xy 311.154406 -282.6256) (xy 311.473084 -282.6256) (xy 311.473084 -282.574184)
			(xy 311.481127 -282.523402) (xy 311.497015 -282.474503) (xy 311.520358 -282.428691) (xy 311.550579 -282.387095)
			(xy 311.586935 -282.350739) (xy 311.628531 -282.320518) (xy 311.674343 -282.297175) (xy 311.723242 -282.281287)
			(xy 311.774024 -282.273244) (xy 311.82544 -282.273244) (xy 311.876222 -282.281287) (xy 311.925121 -282.297175)
			(xy 311.970933 -282.320518) (xy 312.012529 -282.350739) (xy 312.048885 -282.387095) (xy 312.079106 -282.428691)
			(xy 312.102449 -282.474503) (xy 312.118337 -282.523402) (xy 312.12638 -282.574184) (xy 312.126884 -282.599892)
			(xy 312.12638 -282.6256) (xy 312.423044 -282.6256) (xy 312.423044 -282.574184) (xy 312.431087 -282.523402)
			(xy 312.446975 -282.474503) (xy 312.470318 -282.428691) (xy 312.500539 -282.387095) (xy 312.536895 -282.350739)
			(xy 312.578491 -282.320518) (xy 312.624303 -282.297175) (xy 312.673202 -282.281287) (xy 312.723984 -282.273244)
			(xy 312.7754 -282.273244) (xy 312.826182 -282.281287) (xy 312.875081 -282.297175) (xy 312.920893 -282.320518)
			(xy 312.962489 -282.350739) (xy 312.998845 -282.387095) (xy 313.029066 -282.428691) (xy 313.052409 -282.474503)
			(xy 313.068297 -282.523402) (xy 313.07634 -282.574184) (xy 313.076844 -282.599892) (xy 313.394102 -282.599892)
			(xy 313.398062 -282.550838) (xy 313.409839 -282.503054) (xy 313.42913 -282.457778) (xy 313.455433 -282.416182)
			(xy 313.488068 -282.379345) (xy 313.526189 -282.34822) (xy 313.56881 -282.323613) (xy 313.614826 -282.306161)
			(xy 313.663045 -282.296317) (xy 313.71222 -282.294336) (xy 313.761075 -282.300268) (xy 313.808346 -282.31396)
			(xy 313.852808 -282.335058) (xy 313.893311 -282.363014) (xy 313.928804 -282.397106) (xy 313.958369 -282.43645)
			(xy 313.98124 -282.480027) (xy 313.996824 -282.526708) (xy 314.004719 -282.575285) (xy 314.005214 -282.599892)
			(xy 314.344062 -282.599892) (xy 314.348022 -282.550838) (xy 314.359799 -282.503054) (xy 314.37909 -282.457778)
			(xy 314.405393 -282.416182) (xy 314.438028 -282.379345) (xy 314.476149 -282.34822) (xy 314.51877 -282.323613)
			(xy 314.564786 -282.306161) (xy 314.613005 -282.296317) (xy 314.66218 -282.294336) (xy 314.711035 -282.300268)
			(xy 314.758306 -282.31396) (xy 314.802768 -282.335058) (xy 314.843271 -282.363014) (xy 314.878764 -282.397106)
			(xy 314.908329 -282.43645) (xy 314.9312 -282.480027) (xy 314.946784 -282.526708) (xy 314.954679 -282.575285)
			(xy 314.955174 -282.599892) (xy 314.954679 -282.624499) (xy 314.946784 -282.673076) (xy 314.9312 -282.719757)
			(xy 314.908329 -282.763334) (xy 314.878764 -282.802678) (xy 314.843271 -282.83677) (xy 314.802768 -282.864726)
			(xy 314.758306 -282.885824) (xy 314.711035 -282.899516) (xy 314.66218 -282.905448) (xy 314.613005 -282.903467)
			(xy 314.564786 -282.893623) (xy 314.51877 -282.876171) (xy 314.476149 -282.851564) (xy 314.438028 -282.820439)
			(xy 314.405393 -282.783602) (xy 314.37909 -282.742006) (xy 314.359799 -282.69673) (xy 314.348022 -282.648946)
			(xy 314.344062 -282.599892) (xy 314.005214 -282.599892) (xy 314.004719 -282.624499) (xy 313.996824 -282.673076)
			(xy 313.98124 -282.719757) (xy 313.958369 -282.763334) (xy 313.928804 -282.802678) (xy 313.893311 -282.83677)
			(xy 313.852808 -282.864726) (xy 313.808346 -282.885824) (xy 313.761075 -282.899516) (xy 313.71222 -282.905448)
			(xy 313.663045 -282.903467) (xy 313.614826 -282.893623) (xy 313.56881 -282.876171) (xy 313.526189 -282.851564)
			(xy 313.488068 -282.820439) (xy 313.455433 -282.783602) (xy 313.42913 -282.742006) (xy 313.409839 -282.69673)
			(xy 313.398062 -282.648946) (xy 313.394102 -282.599892) (xy 313.076844 -282.599892) (xy 313.07634 -282.6256)
			(xy 313.068297 -282.676382) (xy 313.052409 -282.725281) (xy 313.029066 -282.771093) (xy 312.998845 -282.812689)
			(xy 312.962489 -282.849045) (xy 312.920893 -282.879266) (xy 312.875081 -282.902609) (xy 312.826182 -282.918497)
			(xy 312.7754 -282.92654) (xy 312.723984 -282.92654) (xy 312.673202 -282.918497) (xy 312.624303 -282.902609)
			(xy 312.578491 -282.879266) (xy 312.536895 -282.849045) (xy 312.500539 -282.812689) (xy 312.470318 -282.771093)
			(xy 312.446975 -282.725281) (xy 312.431087 -282.676382) (xy 312.423044 -282.6256) (xy 312.12638 -282.6256)
			(xy 312.118337 -282.676382) (xy 312.102449 -282.725281) (xy 312.079106 -282.771093) (xy 312.048885 -282.812689)
			(xy 312.012529 -282.849045) (xy 311.970933 -282.879266) (xy 311.925121 -282.902609) (xy 311.876222 -282.918497)
			(xy 311.82544 -282.92654) (xy 311.774024 -282.92654) (xy 311.723242 -282.918497) (xy 311.674343 -282.902609)
			(xy 311.628531 -282.879266) (xy 311.586935 -282.849045) (xy 311.550579 -282.812689) (xy 311.520358 -282.771093)
			(xy 311.497015 -282.725281) (xy 311.481127 -282.676382) (xy 311.473084 -282.6256) (xy 311.154406 -282.6256)
			(xy 311.14669 -282.673076) (xy 311.131106 -282.719757) (xy 311.108235 -282.763334) (xy 311.07867 -282.802678)
			(xy 311.043177 -282.83677) (xy 311.002674 -282.864726) (xy 310.958212 -282.885824) (xy 310.910941 -282.899516)
			(xy 310.862086 -282.905448) (xy 310.812911 -282.903467) (xy 310.764692 -282.893623) (xy 310.718676 -282.876171)
			(xy 310.676055 -282.851564) (xy 310.637934 -282.820439) (xy 310.605299 -282.783602) (xy 310.578996 -282.742006)
			(xy 310.559705 -282.69673) (xy 310.547928 -282.648946) (xy 310.543968 -282.599892) (xy 310.226964 -282.599892)
			(xy 310.22646 -282.6256) (xy 310.218417 -282.676382) (xy 310.202529 -282.725281) (xy 310.179186 -282.771093)
			(xy 310.148965 -282.812689) (xy 310.112609 -282.849045) (xy 310.071013 -282.879266) (xy 310.025201 -282.902609)
			(xy 309.976302 -282.918497) (xy 309.92552 -282.92654) (xy 309.874104 -282.92654) (xy 309.823322 -282.918497)
			(xy 309.774423 -282.902609) (xy 309.728611 -282.879266) (xy 309.687015 -282.849045) (xy 309.650659 -282.812689)
			(xy 309.620438 -282.771093) (xy 309.597095 -282.725281) (xy 309.581207 -282.676382) (xy 309.573164 -282.6256)
			(xy 309.2765 -282.6256) (xy 309.268457 -282.676382) (xy 309.252569 -282.725281) (xy 309.229226 -282.771093)
			(xy 309.199005 -282.812689) (xy 309.162649 -282.849045) (xy 309.121053 -282.879266) (xy 309.075241 -282.902609)
			(xy 309.026342 -282.918497) (xy 308.97556 -282.92654) (xy 308.924144 -282.92654) (xy 308.873362 -282.918497)
			(xy 308.824463 -282.902609) (xy 308.778651 -282.879266) (xy 308.737055 -282.849045) (xy 308.700699 -282.812689)
			(xy 308.670478 -282.771093) (xy 308.647135 -282.725281) (xy 308.631247 -282.676382) (xy 308.623204 -282.6256)
			(xy 307.354312 -282.6256) (xy 307.346596 -282.673076) (xy 307.331012 -282.719757) (xy 307.308141 -282.763334)
			(xy 307.278576 -282.802678) (xy 307.243083 -282.83677) (xy 307.20258 -282.864726) (xy 307.158118 -282.885824)
			(xy 307.110847 -282.899516) (xy 307.061992 -282.905448) (xy 307.012817 -282.903467) (xy 306.964598 -282.893623)
			(xy 306.918582 -282.876171) (xy 306.875961 -282.851564) (xy 306.83784 -282.820439) (xy 306.805205 -282.783602)
			(xy 306.778902 -282.742006) (xy 306.759611 -282.69673) (xy 306.747834 -282.648946) (xy 306.743874 -282.599892)
			(xy 287.405064 -282.599892) (xy 287.404878 -282.614074) (xy 287.402206 -282.642314) (xy 287.39973 -282.65628)
			(xy 287.397444 -282.668726) (xy 287.40481 -282.692348) (xy 287.48228 -282.769818) (xy 287.505902 -282.777184)
			(xy 287.518348 -282.774898) (xy 287.532313 -282.772415) (xy 287.560553 -282.769746) (xy 287.574736 -282.769564)
			(xy 287.599559 -282.770053) (xy 287.64855 -282.77809) (xy 287.695595 -282.793948) (xy 287.739455 -282.817208)
			(xy 287.778975 -282.847257) (xy 287.813112 -282.883303) (xy 287.840968 -282.924398) (xy 287.861809 -282.969458)
			(xy 287.875085 -283.017295) (xy 287.880448 -283.066651) (xy 287.880001 -283.074872) (xy 288.219146 -283.074872)
			(xy 288.223106 -283.025818) (xy 288.234883 -282.978034) (xy 288.254174 -282.932758) (xy 288.280477 -282.891162)
			(xy 288.313112 -282.854325) (xy 288.351233 -282.8232) (xy 288.393854 -282.798593) (xy 288.43987 -282.781141)
			(xy 288.488089 -282.771297) (xy 288.537264 -282.769316) (xy 288.586119 -282.775248) (xy 288.63339 -282.78894)
			(xy 288.677852 -282.810038) (xy 288.718355 -282.837994) (xy 288.753848 -282.872086) (xy 288.783413 -282.91143)
			(xy 288.806284 -282.955007) (xy 288.821868 -283.001688) (xy 288.829763 -283.050265) (xy 288.830258 -283.074872)
			(xy 289.169106 -283.074872) (xy 289.173066 -283.025818) (xy 289.184843 -282.978034) (xy 289.204134 -282.932758)
			(xy 289.230437 -282.891162) (xy 289.263072 -282.854325) (xy 289.301193 -282.8232) (xy 289.343814 -282.798593)
			(xy 289.38983 -282.781141) (xy 289.438049 -282.771297) (xy 289.487224 -282.769316) (xy 289.536079 -282.775248)
			(xy 289.58335 -282.78894) (xy 289.627812 -282.810038) (xy 289.668315 -282.837994) (xy 289.703808 -282.872086)
			(xy 289.733373 -282.91143) (xy 289.756244 -282.955007) (xy 289.771828 -283.001688) (xy 289.779723 -283.050265)
			(xy 289.780218 -283.074872) (xy 290.119066 -283.074872) (xy 290.123026 -283.025818) (xy 290.134803 -282.978034)
			(xy 290.154094 -282.932758) (xy 290.180397 -282.891162) (xy 290.213032 -282.854325) (xy 290.251153 -282.8232)
			(xy 290.293774 -282.798593) (xy 290.33979 -282.781141) (xy 290.388009 -282.771297) (xy 290.437184 -282.769316)
			(xy 290.486039 -282.775248) (xy 290.53331 -282.78894) (xy 290.577772 -282.810038) (xy 290.618275 -282.837994)
			(xy 290.653768 -282.872086) (xy 290.683333 -282.91143) (xy 290.706204 -282.955007) (xy 290.721788 -283.001688)
			(xy 290.729683 -283.050265) (xy 290.730178 -283.074872) (xy 292.018986 -283.074872) (xy 292.022946 -283.025818)
			(xy 292.034723 -282.978034) (xy 292.054014 -282.932758) (xy 292.080317 -282.891162) (xy 292.112952 -282.854325)
			(xy 292.151073 -282.8232) (xy 292.193694 -282.798593) (xy 292.23971 -282.781141) (xy 292.287929 -282.771297)
			(xy 292.337104 -282.769316) (xy 292.385959 -282.775248) (xy 292.43323 -282.78894) (xy 292.477692 -282.810038)
			(xy 292.518195 -282.837994) (xy 292.553688 -282.872086) (xy 292.583253 -282.91143) (xy 292.606124 -282.955007)
			(xy 292.621708 -283.001688) (xy 292.629603 -283.050265) (xy 292.630098 -283.074872) (xy 292.968946 -283.074872)
			(xy 292.972906 -283.025818) (xy 292.984683 -282.978034) (xy 293.003974 -282.932758) (xy 293.030277 -282.891162)
			(xy 293.062912 -282.854325) (xy 293.101033 -282.8232) (xy 293.143654 -282.798593) (xy 293.18967 -282.781141)
			(xy 293.237889 -282.771297) (xy 293.287064 -282.769316) (xy 293.335919 -282.775248) (xy 293.38319 -282.78894)
			(xy 293.427652 -282.810038) (xy 293.468155 -282.837994) (xy 293.503648 -282.872086) (xy 293.533213 -282.91143)
			(xy 293.556084 -282.955007) (xy 293.571668 -283.001688) (xy 293.579563 -283.050265) (xy 293.580058 -283.074872)
			(xy 293.918906 -283.074872) (xy 293.922866 -283.025818) (xy 293.934643 -282.978034) (xy 293.953934 -282.932758)
			(xy 293.980237 -282.891162) (xy 294.012872 -282.854325) (xy 294.050993 -282.8232) (xy 294.093614 -282.798593)
			(xy 294.13963 -282.781141) (xy 294.187849 -282.771297) (xy 294.237024 -282.769316) (xy 294.285879 -282.775248)
			(xy 294.33315 -282.78894) (xy 294.377612 -282.810038) (xy 294.418115 -282.837994) (xy 294.453608 -282.872086)
			(xy 294.483173 -282.91143) (xy 294.506044 -282.955007) (xy 294.521628 -283.001688) (xy 294.529523 -283.050265)
			(xy 294.530018 -283.074872) (xy 294.86912 -283.074872) (xy 294.87308 -283.025818) (xy 294.884857 -282.978034)
			(xy 294.904148 -282.932758) (xy 294.930451 -282.891162) (xy 294.963086 -282.854325) (xy 295.001207 -282.8232)
			(xy 295.043828 -282.798593) (xy 295.089844 -282.781141) (xy 295.138063 -282.771297) (xy 295.187238 -282.769316)
			(xy 295.236093 -282.775248) (xy 295.283364 -282.78894) (xy 295.327826 -282.810038) (xy 295.368329 -282.837994)
			(xy 295.403822 -282.872086) (xy 295.433387 -282.91143) (xy 295.456258 -282.955007) (xy 295.471842 -283.001688)
			(xy 295.479737 -283.050265) (xy 295.480232 -283.074872) (xy 295.81908 -283.074872) (xy 295.82304 -283.025818)
			(xy 295.834817 -282.978034) (xy 295.854108 -282.932758) (xy 295.880411 -282.891162) (xy 295.913046 -282.854325)
			(xy 295.951167 -282.8232) (xy 295.993788 -282.798593) (xy 296.039804 -282.781141) (xy 296.088023 -282.771297)
			(xy 296.137198 -282.769316) (xy 296.186053 -282.775248) (xy 296.233324 -282.78894) (xy 296.277786 -282.810038)
			(xy 296.318289 -282.837994) (xy 296.353782 -282.872086) (xy 296.383347 -282.91143) (xy 296.406218 -282.955007)
			(xy 296.421802 -283.001688) (xy 296.429697 -283.050265) (xy 296.430192 -283.074872) (xy 296.76904 -283.074872)
			(xy 296.773 -283.025818) (xy 296.784777 -282.978034) (xy 296.804068 -282.932758) (xy 296.830371 -282.891162)
			(xy 296.863006 -282.854325) (xy 296.901127 -282.8232) (xy 296.943748 -282.798593) (xy 296.989764 -282.781141)
			(xy 297.037983 -282.771297) (xy 297.087158 -282.769316) (xy 297.136013 -282.775248) (xy 297.183284 -282.78894)
			(xy 297.227746 -282.810038) (xy 297.268249 -282.837994) (xy 297.303742 -282.872086) (xy 297.333307 -282.91143)
			(xy 297.356178 -282.955007) (xy 297.371762 -283.001688) (xy 297.379657 -283.050265) (xy 297.380152 -283.074872)
			(xy 297.719 -283.074872) (xy 297.72296 -283.025818) (xy 297.734737 -282.978034) (xy 297.754028 -282.932758)
			(xy 297.780331 -282.891162) (xy 297.812966 -282.854325) (xy 297.851087 -282.8232) (xy 297.893708 -282.798593)
			(xy 297.939724 -282.781141) (xy 297.987943 -282.771297) (xy 298.037118 -282.769316) (xy 298.085973 -282.775248)
			(xy 298.133244 -282.78894) (xy 298.177706 -282.810038) (xy 298.218209 -282.837994) (xy 298.253702 -282.872086)
			(xy 298.283267 -282.91143) (xy 298.306138 -282.955007) (xy 298.321722 -283.001688) (xy 298.329617 -283.050265)
			(xy 298.330112 -283.074872) (xy 298.66896 -283.074872) (xy 298.67292 -283.025818) (xy 298.684697 -282.978034)
			(xy 298.703988 -282.932758) (xy 298.730291 -282.891162) (xy 298.762926 -282.854325) (xy 298.801047 -282.8232)
			(xy 298.843668 -282.798593) (xy 298.889684 -282.781141) (xy 298.937903 -282.771297) (xy 298.987078 -282.769316)
			(xy 299.035933 -282.775248) (xy 299.083204 -282.78894) (xy 299.127666 -282.810038) (xy 299.168169 -282.837994)
			(xy 299.203662 -282.872086) (xy 299.233227 -282.91143) (xy 299.256098 -282.955007) (xy 299.271682 -283.001688)
			(xy 299.279577 -283.050265) (xy 299.280072 -283.074872) (xy 300.56888 -283.074872) (xy 300.57284 -283.025818)
			(xy 300.584617 -282.978034) (xy 300.603908 -282.932758) (xy 300.630211 -282.891162) (xy 300.662846 -282.854325)
			(xy 300.700967 -282.8232) (xy 300.743588 -282.798593) (xy 300.789604 -282.781141) (xy 300.837823 -282.771297)
			(xy 300.886998 -282.769316) (xy 300.935853 -282.775248) (xy 300.983124 -282.78894) (xy 301.027586 -282.810038)
			(xy 301.068089 -282.837994) (xy 301.103582 -282.872086) (xy 301.133147 -282.91143) (xy 301.156018 -282.955007)
			(xy 301.171602 -283.001688) (xy 301.179497 -283.050265) (xy 301.179992 -283.074872) (xy 301.519094 -283.074872)
			(xy 301.523054 -283.025818) (xy 301.534831 -282.978034) (xy 301.554122 -282.932758) (xy 301.580425 -282.891162)
			(xy 301.61306 -282.854325) (xy 301.651181 -282.8232) (xy 301.693802 -282.798593) (xy 301.739818 -282.781141)
			(xy 301.788037 -282.771297) (xy 301.837212 -282.769316) (xy 301.886067 -282.775248) (xy 301.933338 -282.78894)
			(xy 301.9778 -282.810038) (xy 302.018303 -282.837994) (xy 302.053796 -282.872086) (xy 302.083361 -282.91143)
			(xy 302.106232 -282.955007) (xy 302.121816 -283.001688) (xy 302.129711 -283.050265) (xy 302.130206 -283.074872)
			(xy 302.469054 -283.074872) (xy 302.473014 -283.025818) (xy 302.484791 -282.978034) (xy 302.504082 -282.932758)
			(xy 302.530385 -282.891162) (xy 302.56302 -282.854325) (xy 302.601141 -282.8232) (xy 302.643762 -282.798593)
			(xy 302.689778 -282.781141) (xy 302.737997 -282.771297) (xy 302.787172 -282.769316) (xy 302.836027 -282.775248)
			(xy 302.883298 -282.78894) (xy 302.92776 -282.810038) (xy 302.968263 -282.837994) (xy 303.003756 -282.872086)
			(xy 303.033321 -282.91143) (xy 303.056192 -282.955007) (xy 303.071776 -283.001688) (xy 303.079671 -283.050265)
			(xy 303.080166 -283.074872) (xy 303.419014 -283.074872) (xy 303.422974 -283.025818) (xy 303.434751 -282.978034)
			(xy 303.454042 -282.932758) (xy 303.480345 -282.891162) (xy 303.51298 -282.854325) (xy 303.551101 -282.8232)
			(xy 303.593722 -282.798593) (xy 303.639738 -282.781141) (xy 303.687957 -282.771297) (xy 303.737132 -282.769316)
			(xy 303.785987 -282.775248) (xy 303.833258 -282.78894) (xy 303.87772 -282.810038) (xy 303.918223 -282.837994)
			(xy 303.953716 -282.872086) (xy 303.983281 -282.91143) (xy 304.006152 -282.955007) (xy 304.021736 -283.001688)
			(xy 304.029631 -283.050265) (xy 304.030126 -283.074872) (xy 304.368974 -283.074872) (xy 304.372934 -283.025818)
			(xy 304.384711 -282.978034) (xy 304.404002 -282.932758) (xy 304.430305 -282.891162) (xy 304.46294 -282.854325)
			(xy 304.501061 -282.8232) (xy 304.543682 -282.798593) (xy 304.589698 -282.781141) (xy 304.637917 -282.771297)
			(xy 304.687092 -282.769316) (xy 304.735947 -282.775248) (xy 304.783218 -282.78894) (xy 304.82768 -282.810038)
			(xy 304.868183 -282.837994) (xy 304.903676 -282.872086) (xy 304.933241 -282.91143) (xy 304.956112 -282.955007)
			(xy 304.971696 -283.001688) (xy 304.979591 -283.050265) (xy 304.980086 -283.074872) (xy 304.979591 -283.099479)
			(xy 304.971696 -283.148056) (xy 304.956112 -283.194737) (xy 304.933241 -283.238314) (xy 304.903676 -283.277658)
			(xy 304.868183 -283.31175) (xy 304.82768 -283.339706) (xy 304.783218 -283.360804) (xy 304.735947 -283.374496)
			(xy 304.687092 -283.380428) (xy 304.637917 -283.378447) (xy 304.589698 -283.368603) (xy 304.543682 -283.351151)
			(xy 304.501061 -283.326544) (xy 304.46294 -283.295419) (xy 304.430305 -283.258582) (xy 304.404002 -283.216986)
			(xy 304.384711 -283.17171) (xy 304.372934 -283.123926) (xy 304.368974 -283.074872) (xy 304.030126 -283.074872)
			(xy 304.029631 -283.099479) (xy 304.021736 -283.148056) (xy 304.006152 -283.194737) (xy 303.983281 -283.238314)
			(xy 303.953716 -283.277658) (xy 303.918223 -283.31175) (xy 303.87772 -283.339706) (xy 303.833258 -283.360804)
			(xy 303.785987 -283.374496) (xy 303.737132 -283.380428) (xy 303.687957 -283.378447) (xy 303.639738 -283.368603)
			(xy 303.593722 -283.351151) (xy 303.551101 -283.326544) (xy 303.51298 -283.295419) (xy 303.480345 -283.258582)
			(xy 303.454042 -283.216986) (xy 303.434751 -283.17171) (xy 303.422974 -283.123926) (xy 303.419014 -283.074872)
			(xy 303.080166 -283.074872) (xy 303.079671 -283.099479) (xy 303.071776 -283.148056) (xy 303.056192 -283.194737)
			(xy 303.033321 -283.238314) (xy 303.003756 -283.277658) (xy 302.968263 -283.31175) (xy 302.92776 -283.339706)
			(xy 302.883298 -283.360804) (xy 302.836027 -283.374496) (xy 302.787172 -283.380428) (xy 302.737997 -283.378447)
			(xy 302.689778 -283.368603) (xy 302.643762 -283.351151) (xy 302.601141 -283.326544) (xy 302.56302 -283.295419)
			(xy 302.530385 -283.258582) (xy 302.504082 -283.216986) (xy 302.484791 -283.17171) (xy 302.473014 -283.123926)
			(xy 302.469054 -283.074872) (xy 302.130206 -283.074872) (xy 302.129711 -283.099479) (xy 302.121816 -283.148056)
			(xy 302.106232 -283.194737) (xy 302.083361 -283.238314) (xy 302.053796 -283.277658) (xy 302.018303 -283.31175)
			(xy 301.9778 -283.339706) (xy 301.933338 -283.360804) (xy 301.886067 -283.374496) (xy 301.837212 -283.380428)
			(xy 301.788037 -283.378447) (xy 301.739818 -283.368603) (xy 301.693802 -283.351151) (xy 301.651181 -283.326544)
			(xy 301.61306 -283.295419) (xy 301.580425 -283.258582) (xy 301.554122 -283.216986) (xy 301.534831 -283.17171)
			(xy 301.523054 -283.123926) (xy 301.519094 -283.074872) (xy 301.179992 -283.074872) (xy 301.179497 -283.099479)
			(xy 301.171602 -283.148056) (xy 301.156018 -283.194737) (xy 301.133147 -283.238314) (xy 301.103582 -283.277658)
			(xy 301.068089 -283.31175) (xy 301.027586 -283.339706) (xy 300.983124 -283.360804) (xy 300.935853 -283.374496)
			(xy 300.886998 -283.380428) (xy 300.837823 -283.378447) (xy 300.789604 -283.368603) (xy 300.743588 -283.351151)
			(xy 300.700967 -283.326544) (xy 300.662846 -283.295419) (xy 300.630211 -283.258582) (xy 300.603908 -283.216986)
			(xy 300.584617 -283.17171) (xy 300.57284 -283.123926) (xy 300.56888 -283.074872) (xy 299.280072 -283.074872)
			(xy 299.279577 -283.099479) (xy 299.271682 -283.148056) (xy 299.256098 -283.194737) (xy 299.233227 -283.238314)
			(xy 299.203662 -283.277658) (xy 299.168169 -283.31175) (xy 299.127666 -283.339706) (xy 299.083204 -283.360804)
			(xy 299.035933 -283.374496) (xy 298.987078 -283.380428) (xy 298.937903 -283.378447) (xy 298.889684 -283.368603)
			(xy 298.843668 -283.351151) (xy 298.801047 -283.326544) (xy 298.762926 -283.295419) (xy 298.730291 -283.258582)
			(xy 298.703988 -283.216986) (xy 298.684697 -283.17171) (xy 298.67292 -283.123926) (xy 298.66896 -283.074872)
			(xy 298.330112 -283.074872) (xy 298.329617 -283.099479) (xy 298.321722 -283.148056) (xy 298.306138 -283.194737)
			(xy 298.283267 -283.238314) (xy 298.253702 -283.277658) (xy 298.218209 -283.31175) (xy 298.177706 -283.339706)
			(xy 298.133244 -283.360804) (xy 298.085973 -283.374496) (xy 298.037118 -283.380428) (xy 297.987943 -283.378447)
			(xy 297.939724 -283.368603) (xy 297.893708 -283.351151) (xy 297.851087 -283.326544) (xy 297.812966 -283.295419)
			(xy 297.780331 -283.258582) (xy 297.754028 -283.216986) (xy 297.734737 -283.17171) (xy 297.72296 -283.123926)
			(xy 297.719 -283.074872) (xy 297.380152 -283.074872) (xy 297.379657 -283.099479) (xy 297.371762 -283.148056)
			(xy 297.356178 -283.194737) (xy 297.333307 -283.238314) (xy 297.303742 -283.277658) (xy 297.268249 -283.31175)
			(xy 297.227746 -283.339706) (xy 297.183284 -283.360804) (xy 297.136013 -283.374496) (xy 297.087158 -283.380428)
			(xy 297.037983 -283.378447) (xy 296.989764 -283.368603) (xy 296.943748 -283.351151) (xy 296.901127 -283.326544)
			(xy 296.863006 -283.295419) (xy 296.830371 -283.258582) (xy 296.804068 -283.216986) (xy 296.784777 -283.17171)
			(xy 296.773 -283.123926) (xy 296.76904 -283.074872) (xy 296.430192 -283.074872) (xy 296.429697 -283.099479)
			(xy 296.421802 -283.148056) (xy 296.406218 -283.194737) (xy 296.383347 -283.238314) (xy 296.353782 -283.277658)
			(xy 296.318289 -283.31175) (xy 296.277786 -283.339706) (xy 296.233324 -283.360804) (xy 296.186053 -283.374496)
			(xy 296.137198 -283.380428) (xy 296.088023 -283.378447) (xy 296.039804 -283.368603) (xy 295.993788 -283.351151)
			(xy 295.951167 -283.326544) (xy 295.913046 -283.295419) (xy 295.880411 -283.258582) (xy 295.854108 -283.216986)
			(xy 295.834817 -283.17171) (xy 295.82304 -283.123926) (xy 295.81908 -283.074872) (xy 295.480232 -283.074872)
			(xy 295.479737 -283.099479) (xy 295.471842 -283.148056) (xy 295.456258 -283.194737) (xy 295.433387 -283.238314)
			(xy 295.403822 -283.277658) (xy 295.368329 -283.31175) (xy 295.327826 -283.339706) (xy 295.283364 -283.360804)
			(xy 295.236093 -283.374496) (xy 295.187238 -283.380428) (xy 295.138063 -283.378447) (xy 295.089844 -283.368603)
			(xy 295.043828 -283.351151) (xy 295.001207 -283.326544) (xy 294.963086 -283.295419) (xy 294.930451 -283.258582)
			(xy 294.904148 -283.216986) (xy 294.884857 -283.17171) (xy 294.87308 -283.123926) (xy 294.86912 -283.074872)
			(xy 294.530018 -283.074872) (xy 294.529523 -283.099479) (xy 294.521628 -283.148056) (xy 294.506044 -283.194737)
			(xy 294.483173 -283.238314) (xy 294.453608 -283.277658) (xy 294.418115 -283.31175) (xy 294.377612 -283.339706)
			(xy 294.33315 -283.360804) (xy 294.285879 -283.374496) (xy 294.237024 -283.380428) (xy 294.187849 -283.378447)
			(xy 294.13963 -283.368603) (xy 294.093614 -283.351151) (xy 294.050993 -283.326544) (xy 294.012872 -283.295419)
			(xy 293.980237 -283.258582) (xy 293.953934 -283.216986) (xy 293.934643 -283.17171) (xy 293.922866 -283.123926)
			(xy 293.918906 -283.074872) (xy 293.580058 -283.074872) (xy 293.579563 -283.099479) (xy 293.571668 -283.148056)
			(xy 293.556084 -283.194737) (xy 293.533213 -283.238314) (xy 293.503648 -283.277658) (xy 293.468155 -283.31175)
			(xy 293.427652 -283.339706) (xy 293.38319 -283.360804) (xy 293.335919 -283.374496) (xy 293.287064 -283.380428)
			(xy 293.237889 -283.378447) (xy 293.18967 -283.368603) (xy 293.143654 -283.351151) (xy 293.101033 -283.326544)
			(xy 293.062912 -283.295419) (xy 293.030277 -283.258582) (xy 293.003974 -283.216986) (xy 292.984683 -283.17171)
			(xy 292.972906 -283.123926) (xy 292.968946 -283.074872) (xy 292.630098 -283.074872) (xy 292.629603 -283.099479)
			(xy 292.621708 -283.148056) (xy 292.606124 -283.194737) (xy 292.583253 -283.238314) (xy 292.553688 -283.277658)
			(xy 292.518195 -283.31175) (xy 292.477692 -283.339706) (xy 292.43323 -283.360804) (xy 292.385959 -283.374496)
			(xy 292.337104 -283.380428) (xy 292.287929 -283.378447) (xy 292.23971 -283.368603) (xy 292.193694 -283.351151)
			(xy 292.151073 -283.326544) (xy 292.112952 -283.295419) (xy 292.080317 -283.258582) (xy 292.054014 -283.216986)
			(xy 292.034723 -283.17171) (xy 292.022946 -283.123926) (xy 292.018986 -283.074872) (xy 290.730178 -283.074872)
			(xy 290.729683 -283.099479) (xy 290.721788 -283.148056) (xy 290.706204 -283.194737) (xy 290.683333 -283.238314)
			(xy 290.653768 -283.277658) (xy 290.618275 -283.31175) (xy 290.577772 -283.339706) (xy 290.53331 -283.360804)
			(xy 290.486039 -283.374496) (xy 290.437184 -283.380428) (xy 290.388009 -283.378447) (xy 290.33979 -283.368603)
			(xy 290.293774 -283.351151) (xy 290.251153 -283.326544) (xy 290.213032 -283.295419) (xy 290.180397 -283.258582)
			(xy 290.154094 -283.216986) (xy 290.134803 -283.17171) (xy 290.123026 -283.123926) (xy 290.119066 -283.074872)
			(xy 289.780218 -283.074872) (xy 289.779723 -283.099479) (xy 289.771828 -283.148056) (xy 289.756244 -283.194737)
			(xy 289.733373 -283.238314) (xy 289.703808 -283.277658) (xy 289.668315 -283.31175) (xy 289.627812 -283.339706)
			(xy 289.58335 -283.360804) (xy 289.536079 -283.374496) (xy 289.487224 -283.380428) (xy 289.438049 -283.378447)
			(xy 289.38983 -283.368603) (xy 289.343814 -283.351151) (xy 289.301193 -283.326544) (xy 289.263072 -283.295419)
			(xy 289.230437 -283.258582) (xy 289.204134 -283.216986) (xy 289.184843 -283.17171) (xy 289.173066 -283.123926)
			(xy 289.169106 -283.074872) (xy 288.830258 -283.074872) (xy 288.829763 -283.099479) (xy 288.821868 -283.148056)
			(xy 288.806284 -283.194737) (xy 288.783413 -283.238314) (xy 288.753848 -283.277658) (xy 288.718355 -283.31175)
			(xy 288.677852 -283.339706) (xy 288.63339 -283.360804) (xy 288.586119 -283.374496) (xy 288.537264 -283.380428)
			(xy 288.488089 -283.378447) (xy 288.43987 -283.368603) (xy 288.393854 -283.351151) (xy 288.351233 -283.326544)
			(xy 288.313112 -283.295419) (xy 288.280477 -283.258582) (xy 288.254174 -283.216986) (xy 288.234883 -283.17171)
			(xy 288.223106 -283.123926) (xy 288.219146 -283.074872) (xy 287.880001 -283.074872) (xy 287.877755 -283.116224)
			(xy 287.867077 -283.164708) (xy 287.848696 -283.210826) (xy 287.823096 -283.253363) (xy 287.790952 -283.291198)
			(xy 287.753111 -283.323334) (xy 287.710569 -283.348925) (xy 287.664447 -283.367296) (xy 287.61596 -283.377963)
			(xy 287.566387 -283.380646) (xy 287.517032 -283.375273) (xy 287.469197 -283.361987) (xy 287.424142 -283.341137)
			(xy 287.383053 -283.313272) (xy 287.347014 -283.279127) (xy 287.316973 -283.239601) (xy 287.293723 -283.195736)
			(xy 287.277875 -283.148688) (xy 287.269848 -283.099695) (xy 287.269428 -283.074872) (xy 287.269611 -283.060689)
			(xy 287.272279 -283.032449) (xy 287.274762 -283.018484) (xy 287.277048 -283.006038) (xy 287.269682 -282.982416)
			(xy 287.192212 -282.904946) (xy 287.16859 -282.89758) (xy 287.156144 -282.899866) (xy 287.142179 -282.902349)
			(xy 287.113939 -282.905017) (xy 287.099756 -282.9052) (xy 287.085573 -282.905016) (xy 287.057333 -282.902348)
			(xy 287.043368 -282.899866) (xy 287.030922 -282.89758) (xy 287.0073 -282.904946) (xy 286.92983 -282.982416)
			(xy 286.922464 -283.006038) (xy 286.92475 -283.018484) (xy 286.927237 -283.032449) (xy 286.929912 -283.060689)
			(xy 286.930084 -283.074872) (xy 286.9296 -283.099691) (xy 286.921574 -283.148676) (xy 286.905729 -283.195717)
			(xy 286.882482 -283.239575) (xy 286.852446 -283.279094) (xy 286.816412 -283.313233) (xy 286.77533 -283.341093)
			(xy 286.730282 -283.361939) (xy 286.682454 -283.375223) (xy 286.633108 -283.380594) (xy 286.583542 -283.377911)
			(xy 286.535064 -283.367245) (xy 286.48895 -283.348876) (xy 286.446415 -283.323288) (xy 286.40858 -283.291157)
			(xy 286.376442 -283.253327) (xy 286.350847 -283.210797) (xy 286.332471 -283.164686) (xy 286.321796 -283.116209)
			(xy 286.319104 -283.066644) (xy 286.324467 -283.017297) (xy 286.337743 -282.969467) (xy 286.358582 -282.924415)
			(xy 286.386434 -282.883328) (xy 286.420567 -282.847288) (xy 286.460081 -282.817246) (xy 286.503935 -282.793991)
			(xy 286.550974 -282.778138) (xy 286.599957 -282.770104) (xy 286.624776 -282.769564) (xy 286.638959 -282.769749)
			(xy 286.667198 -282.77242) (xy 286.681164 -282.774898) (xy 286.69361 -282.777184) (xy 286.717232 -282.769818)
			(xy 286.794702 -282.692348) (xy 286.802068 -282.668726) (xy 286.799782 -282.65628) (xy 286.797297 -282.642315)
			(xy 286.794626 -282.614075) (xy 286.794448 -282.599892) (xy 286.794635 -282.58571) (xy 286.797309 -282.55747)
			(xy 286.799782 -282.543504) (xy 286.802068 -282.531058) (xy 286.794702 -282.507436) (xy 286.717232 -282.429966)
			(xy 286.69361 -282.4226) (xy 286.681164 -282.424886) (xy 286.657132 -282.428916) (xy 286.608422 -282.430191)
			(xy 286.560129 -282.423714) (xy 286.513476 -282.409649) (xy 286.46965 -282.388354) (xy 286.429762 -282.360368)
			(xy 286.394825 -282.326402) (xy 286.365726 -282.287319) (xy 286.343203 -282.244111) (xy 286.327828 -282.197874)
			(xy 286.319992 -282.149782) (xy 286.319468 -282.12542) (xy 286.319007 -282.115106) (xy 286.310903 -282.09614)
			(xy 286.295966 -282.081917) (xy 286.286448 -282.077922) (xy 286.246519 -282.062479) (xy 286.169312 -282.025471)
			(xy 286.13227 -282.004008) (xy 286.124074 -281.999634) (xy 286.105783 -281.996475) (xy 286.087558 -282.000001)
			(xy 286.079438 -282.004516) (xy 286.025844 -282.038044) (xy 286.025336 -282.038044) (xy 286.00908 -282.048458)
			(xy 286.005524 -282.05049) (xy 285.992062 -282.057856) (xy 285.977838 -282.084526) (xy 285.979362 -282.101798)
			(xy 285.980124 -282.123388) (xy 285.980124 -282.125928) (xy 285.979523 -282.151128) (xy 285.971079 -282.20082)
			(xy 285.954587 -282.24845) (xy 285.930497 -282.292724) (xy 285.899461 -282.332441) (xy 285.862324 -282.36652)
			(xy 285.820094 -282.394037) (xy 285.773917 -282.414243) (xy 285.725049 -282.426591) (xy 285.674816 -282.430745)
			(xy 285.624583 -282.426591) (xy 285.575715 -282.414243) (xy 285.529538 -282.394037) (xy 285.487308 -282.36652)
			(xy 285.450171 -282.332441) (xy 285.419135 -282.292724) (xy 285.395045 -282.24845) (xy 285.378553 -282.20082)
			(xy 285.370109 -282.151128) (xy 285.369508 -282.125928) (xy 285.369508 -282.124658) (xy 285.37027 -282.103068)
			(xy 285.37027 -282.101036) (xy 285.37094 -282.091106) (xy 285.365544 -282.071971) (xy 285.353278 -282.056324)
			(xy 285.34487 -282.050998) (xy 285.343092 -282.049982) (xy 285.270194 -282.004516) (xy 285.262096 -281.999946)
			(xy 285.243859 -281.996398) (xy 285.225561 -281.999617) (xy 285.217362 -282.004008) (xy 285.202081 -282.013014)
			(xy 285.170958 -282.030036) (xy 285.155132 -282.038044) (xy 285.132612 -282.049058) (xy 285.086614 -282.069006)
			(xy 285.063184 -282.077922) (xy 285.05371 -282.081985) (xy 285.038811 -282.096204) (xy 285.030675 -282.115124)
			(xy 285.030164 -282.12542) (xy 285.029603 -282.150648) (xy 285.021224 -282.200405) (xy 285.004777 -282.248106)
			(xy 284.980712 -282.292455) (xy 284.949682 -282.332243) (xy 284.912532 -282.366388) (xy 284.870274 -282.393959)
			(xy 284.824058 -282.414207) (xy 284.775141 -282.426581) (xy 284.724856 -282.430743) (xy 284.674571 -282.426581)
			(xy 284.625654 -282.414207) (xy 284.579438 -282.393959) (xy 284.53718 -282.366388) (xy 284.50003 -282.332243)
			(xy 284.469 -282.292455) (xy 284.444935 -282.248106) (xy 284.428488 -282.200405) (xy 284.420109 -282.150648)
			(xy 284.419548 -282.12542) (xy 284.419086 -282.115107) (xy 284.410981 -282.096143) (xy 284.396041 -282.081926)
			(xy 284.386528 -282.077922) (xy 284.346599 -282.062479) (xy 284.269393 -282.025469) (xy 284.23235 -282.004008)
			(xy 284.224154 -281.999638) (xy 284.205865 -281.996485) (xy 284.187646 -282.000017) (xy 284.179518 -282.004516)
			(xy 284.125924 -282.038044) (xy 284.125416 -282.038044) (xy 284.10916 -282.048458) (xy 284.105604 -282.05049)
			(xy 284.092142 -282.057856) (xy 284.077918 -282.084526) (xy 284.079442 -282.101798) (xy 284.080204 -282.123388)
			(xy 284.080204 -282.125928) (xy 284.079603 -282.151128) (xy 284.071159 -282.20082) (xy 284.054667 -282.24845)
			(xy 284.030577 -282.292724) (xy 283.999541 -282.332441) (xy 283.962404 -282.36652) (xy 283.920174 -282.394037)
			(xy 283.873997 -282.414243) (xy 283.825129 -282.426591) (xy 283.774896 -282.430745) (xy 283.724663 -282.426591)
			(xy 283.675795 -282.414243) (xy 283.629618 -282.394037) (xy 283.587388 -282.36652) (xy 283.550251 -282.332441)
			(xy 283.519215 -282.292724) (xy 283.495125 -282.24845) (xy 283.478633 -282.20082) (xy 283.470189 -282.151128)
			(xy 283.469588 -282.125928) (xy 283.469588 -282.124658) (xy 283.47035 -282.103068) (xy 283.47035 -282.101036)
			(xy 283.47102 -282.091107) (xy 283.465623 -282.071973) (xy 283.453354 -282.05633) (xy 283.44495 -282.050998)
			(xy 283.443172 -282.049982) (xy 283.370274 -282.004516) (xy 283.362175 -281.999931) (xy 283.343928 -281.996355)
			(xy 283.325611 -281.999553) (xy 283.317442 -282.004008) (xy 283.302161 -282.013014) (xy 283.271038 -282.030035)
			(xy 283.255212 -282.038044) (xy 283.232693 -282.04906) (xy 283.186696 -282.069011) (xy 283.163264 -282.077922)
			(xy 283.153793 -282.081988) (xy 283.1389 -282.096208) (xy 283.130767 -282.115126) (xy 283.130244 -282.12542)
			(xy 283.129683 -282.150648) (xy 283.121304 -282.200405) (xy 283.104857 -282.248106) (xy 283.080792 -282.292455)
			(xy 283.049762 -282.332243) (xy 283.012612 -282.366388) (xy 282.970354 -282.393959) (xy 282.924138 -282.414207)
			(xy 282.875221 -282.426581) (xy 282.824936 -282.430743) (xy 282.774651 -282.426581) (xy 282.725734 -282.414207)
			(xy 282.679518 -282.393959) (xy 282.63726 -282.366388) (xy 282.60011 -282.332243) (xy 282.56908 -282.292455)
			(xy 282.545015 -282.248106) (xy 282.528568 -282.200405) (xy 282.520189 -282.150648) (xy 282.519628 -282.12542)
			(xy 282.519166 -282.115108) (xy 282.511059 -282.096147) (xy 282.496117 -282.081935) (xy 282.486608 -282.077922)
			(xy 282.446746 -282.062466) (xy 282.369669 -282.025455) (xy 282.332684 -282.004008) (xy 282.33243 -282.003754)
			(xy 282.331922 -282.0035) (xy 282.323721 -281.999231) (xy 282.305487 -281.996266) (xy 282.287383 -281.999948)
			(xy 282.279344 -282.004516) (xy 282.241244 -282.028392) (xy 282.240736 -282.028392) (xy 282.190698 -282.060142)
			(xy 282.178252 -282.08478) (xy 282.179014 -282.09875) (xy 282.179014 -282.100274) (xy 282.179268 -282.102052)
			(xy 282.18003 -282.122626) (xy 282.18003 -282.125928) (xy 282.179429 -282.151128) (xy 282.170985 -282.20082)
			(xy 282.154493 -282.24845) (xy 282.130403 -282.292724) (xy 282.099367 -282.332441) (xy 282.06223 -282.36652)
			(xy 282.02 -282.394037) (xy 281.973823 -282.414243) (xy 281.924955 -282.426591) (xy 281.874722 -282.430745)
			(xy 281.824489 -282.426591) (xy 281.775621 -282.414243) (xy 281.729444 -282.394037) (xy 281.687214 -282.36652)
			(xy 281.650077 -282.332441) (xy 281.619041 -282.292724) (xy 281.594951 -282.24845) (xy 281.578459 -282.20082)
			(xy 281.570015 -282.151128) (xy 281.569414 -282.125928) (xy 281.569414 -282.124658) (xy 281.570176 -282.103068)
			(xy 281.570176 -282.101036) (xy 281.570846 -282.091106) (xy 281.56545 -282.07197) (xy 281.553185 -282.056322)
			(xy 281.544776 -282.050998) (xy 281.542998 -282.049982) (xy 281.4701 -282.004516) (xy 281.462002 -281.999945)
			(xy 281.443764 -281.996395) (xy 281.425465 -281.999612) (xy 281.417268 -282.004008) (xy 281.401987 -282.013014)
			(xy 281.370864 -282.030036) (xy 281.355038 -282.038044) (xy 281.332518 -282.049058) (xy 281.28652 -282.069006)
			(xy 281.26309 -282.077922) (xy 281.253615 -282.081984) (xy 281.238714 -282.096203) (xy 281.230577 -282.115124)
			(xy 281.23007 -282.12542) (xy 281.229509 -282.150648) (xy 281.22113 -282.200405) (xy 281.204683 -282.248106)
			(xy 281.180618 -282.292455) (xy 281.149588 -282.332243) (xy 281.112438 -282.366388) (xy 281.07018 -282.393959)
			(xy 281.023964 -282.414207) (xy 280.975047 -282.426581) (xy 280.924762 -282.430743) (xy 280.874477 -282.426581)
			(xy 280.82556 -282.414207) (xy 280.779344 -282.393959) (xy 280.737086 -282.366388) (xy 280.699936 -282.332243)
			(xy 280.668906 -282.292455) (xy 280.644841 -282.248106) (xy 280.628394 -282.200405) (xy 280.620015 -282.150648)
			(xy 280.619454 -282.12542) (xy 280.618992 -282.115107) (xy 280.610887 -282.096142) (xy 280.595948 -282.081924)
			(xy 280.586434 -282.077922) (xy 280.546505 -282.062479) (xy 280.469299 -282.02547) (xy 280.432256 -282.004008)
			(xy 280.42406 -281.999637) (xy 280.405771 -281.996482) (xy 280.38755 -282.000012) (xy 280.379424 -282.004516)
			(xy 280.32583 -282.038044) (xy 280.325322 -282.038044) (xy 280.309066 -282.048458) (xy 280.30551 -282.05049)
			(xy 280.292048 -282.057856) (xy 280.277824 -282.084526) (xy 280.279348 -282.101798) (xy 280.28011 -282.123388)
			(xy 280.28011 -282.125928) (xy 280.279509 -282.151128) (xy 280.271065 -282.20082) (xy 280.254573 -282.24845)
			(xy 280.230483 -282.292724) (xy 280.199447 -282.332441) (xy 280.16231 -282.36652) (xy 280.12008 -282.394037)
			(xy 280.073903 -282.414243) (xy 280.025035 -282.426591) (xy 279.974802 -282.430745) (xy 279.924569 -282.426591)
			(xy 279.875701 -282.414243) (xy 279.829524 -282.394037) (xy 279.787294 -282.36652) (xy 279.750157 -282.332441)
			(xy 279.719121 -282.292724) (xy 279.695031 -282.24845) (xy 279.678539 -282.20082) (xy 279.670095 -282.151128)
			(xy 279.669494 -282.125928) (xy 279.669494 -282.124658) (xy 279.670256 -282.103068) (xy 279.670256 -282.101036)
			(xy 279.670926 -282.091107) (xy 279.665529 -282.071973) (xy 279.653261 -282.056328) (xy 279.644856 -282.050998)
			(xy 279.643078 -282.049982) (xy 279.57018 -282.004516) (xy 279.562081 -281.99993) (xy 279.543833 -281.996352)
			(xy 279.525514 -281.999548) (xy 279.517348 -282.004008) (xy 279.502067 -282.013014) (xy 279.470944 -282.030035)
			(xy 279.455118 -282.038044) (xy 279.432599 -282.04906) (xy 279.386602 -282.069011) (xy 279.36317 -282.077922)
			(xy 279.353698 -282.081987) (xy 279.338803 -282.096207) (xy 279.330669 -282.115125) (xy 279.33015 -282.12542)
			(xy 279.329589 -282.150648) (xy 279.32121 -282.200405) (xy 279.304763 -282.248106) (xy 279.280698 -282.292455)
			(xy 279.249668 -282.332243) (xy 279.212518 -282.366388) (xy 279.17026 -282.393959) (xy 279.124044 -282.414207)
			(xy 279.075127 -282.426581) (xy 279.024842 -282.430743) (xy 278.974557 -282.426581) (xy 278.92564 -282.414207)
			(xy 278.879424 -282.393959) (xy 278.837166 -282.366388) (xy 278.800016 -282.332243) (xy 278.768986 -282.292455)
			(xy 278.744921 -282.248106) (xy 278.728474 -282.200405) (xy 278.720095 -282.150648) (xy 278.719534 -282.12542)
			(xy 278.719072 -282.115108) (xy 278.710966 -282.096146) (xy 278.696024 -282.081932) (xy 278.686514 -282.077922)
			(xy 278.646585 -282.062478) (xy 278.56938 -282.025468) (xy 278.532336 -282.004008) (xy 278.524139 -281.999623)
			(xy 278.505839 -281.99644) (xy 278.487599 -281.999949) (xy 278.479504 -282.004516) (xy 278.42591 -282.038044)
			(xy 278.425402 -282.038044) (xy 278.409146 -282.048458) (xy 278.40559 -282.05049) (xy 278.392128 -282.057856)
			(xy 278.377904 -282.084526) (xy 278.379428 -282.101798) (xy 278.38019 -282.123388) (xy 278.38019 -282.125928)
			(xy 278.379589 -282.151128) (xy 278.371145 -282.20082) (xy 278.354653 -282.24845) (xy 278.330563 -282.292724)
			(xy 278.299527 -282.332441) (xy 278.26239 -282.36652) (xy 278.22016 -282.394037) (xy 278.173983 -282.414243)
			(xy 278.125115 -282.426591) (xy 278.074882 -282.430745) (xy 278.024649 -282.426591) (xy 277.975781 -282.414243)
			(xy 277.929604 -282.394037) (xy 277.887374 -282.36652) (xy 277.850237 -282.332441) (xy 277.819201 -282.292724)
			(xy 277.795111 -282.24845) (xy 277.778619 -282.20082) (xy 277.770175 -282.151128) (xy 277.769574 -282.125928)
			(xy 277.769574 -282.124658) (xy 277.770336 -282.103068) (xy 277.770336 -282.101036) (xy 277.771006 -282.091107)
			(xy 277.765608 -282.071975) (xy 277.753337 -282.056334) (xy 277.744936 -282.050998) (xy 277.743158 -282.049982)
			(xy 277.67026 -282.004516) (xy 277.662161 -281.999933) (xy 277.643916 -281.996363) (xy 277.625602 -281.999564)
			(xy 277.617428 -282.004008) (xy 277.602147 -282.013013) (xy 277.571024 -282.030034) (xy 277.555198 -282.038044)
			(xy 277.532679 -282.04906) (xy 277.486682 -282.06901) (xy 277.46325 -282.077922) (xy 277.453781 -282.081989)
			(xy 277.438892 -282.096211) (xy 277.430762 -282.115127) (xy 277.43023 -282.12542) (xy 277.429669 -282.150648)
			(xy 277.42129 -282.200405) (xy 277.404843 -282.248106) (xy 277.380778 -282.292455) (xy 277.349748 -282.332243)
			(xy 277.312598 -282.366388) (xy 277.27034 -282.393959) (xy 277.224124 -282.414207) (xy 277.175207 -282.426581)
			(xy 277.124922 -282.430743) (xy 277.074637 -282.426581) (xy 277.02572 -282.414207) (xy 276.979504 -282.393959)
			(xy 276.937246 -282.366388) (xy 276.900096 -282.332243) (xy 276.869066 -282.292455) (xy 276.845001 -282.248106)
			(xy 276.828554 -282.200405) (xy 276.820175 -282.150648) (xy 276.819614 -282.12542) (xy 276.819154 -282.115104)
			(xy 276.811054 -282.096131) (xy 276.796121 -282.081897) (xy 276.786594 -282.077922) (xy 276.771354 -282.07208)
			(xy 276.75967 -282.067508) (xy 276.734524 -282.070048) (xy 276.654768 -282.124404) (xy 276.644743 -282.13193)
			(xy 276.633008 -282.154047) (xy 276.632416 -282.166568) (xy 276.632416 -282.726384) (xy 276.6314 -282.7274)
			(xy 276.6314 -283.074872) (xy 276.819118 -283.074872) (xy 276.823078 -283.025818) (xy 276.834855 -282.978034)
			(xy 276.854146 -282.932758) (xy 276.880449 -282.891162) (xy 276.913084 -282.854325) (xy 276.951205 -282.8232)
			(xy 276.993826 -282.798593) (xy 277.039842 -282.781141) (xy 277.088061 -282.771297) (xy 277.137236 -282.769316)
			(xy 277.186091 -282.775248) (xy 277.233362 -282.78894) (xy 277.277824 -282.810038) (xy 277.318327 -282.837994)
			(xy 277.35382 -282.872086) (xy 277.383385 -282.91143) (xy 277.406256 -282.955007) (xy 277.42184 -283.001688)
			(xy 277.429735 -283.050265) (xy 277.43023 -283.074872) (xy 277.769078 -283.074872) (xy 277.773038 -283.025818)
			(xy 277.784815 -282.978034) (xy 277.804106 -282.932758) (xy 277.830409 -282.891162) (xy 277.863044 -282.854325)
			(xy 277.901165 -282.8232) (xy 277.943786 -282.798593) (xy 277.989802 -282.781141) (xy 278.038021 -282.771297)
			(xy 278.087196 -282.769316) (xy 278.136051 -282.775248) (xy 278.183322 -282.78894) (xy 278.227784 -282.810038)
			(xy 278.268287 -282.837994) (xy 278.30378 -282.872086) (xy 278.333345 -282.91143) (xy 278.356216 -282.955007)
			(xy 278.3718 -283.001688) (xy 278.379695 -283.050265) (xy 278.38019 -283.074872) (xy 278.719038 -283.074872)
			(xy 278.722998 -283.025818) (xy 278.734775 -282.978034) (xy 278.754066 -282.932758) (xy 278.780369 -282.891162)
			(xy 278.813004 -282.854325) (xy 278.851125 -282.8232) (xy 278.893746 -282.798593) (xy 278.939762 -282.781141)
			(xy 278.987981 -282.771297) (xy 279.037156 -282.769316) (xy 279.086011 -282.775248) (xy 279.133282 -282.78894)
			(xy 279.177744 -282.810038) (xy 279.218247 -282.837994) (xy 279.25374 -282.872086) (xy 279.283305 -282.91143)
			(xy 279.306176 -282.955007) (xy 279.32176 -283.001688) (xy 279.329655 -283.050265) (xy 279.33015 -283.074872)
			(xy 279.668998 -283.074872) (xy 279.672958 -283.025818) (xy 279.684735 -282.978034) (xy 279.704026 -282.932758)
			(xy 279.730329 -282.891162) (xy 279.762964 -282.854325) (xy 279.801085 -282.8232) (xy 279.843706 -282.798593)
			(xy 279.889722 -282.781141) (xy 279.937941 -282.771297) (xy 279.987116 -282.769316) (xy 280.035971 -282.775248)
			(xy 280.083242 -282.78894) (xy 280.127704 -282.810038) (xy 280.168207 -282.837994) (xy 280.2037 -282.872086)
			(xy 280.233265 -282.91143) (xy 280.256136 -282.955007) (xy 280.27172 -283.001688) (xy 280.279615 -283.050265)
			(xy 280.28011 -283.074872) (xy 280.618958 -283.074872) (xy 280.622918 -283.025818) (xy 280.634695 -282.978034)
			(xy 280.653986 -282.932758) (xy 280.680289 -282.891162) (xy 280.712924 -282.854325) (xy 280.751045 -282.8232)
			(xy 280.793666 -282.798593) (xy 280.839682 -282.781141) (xy 280.887901 -282.771297) (xy 280.937076 -282.769316)
			(xy 280.985931 -282.775248) (xy 281.033202 -282.78894) (xy 281.077664 -282.810038) (xy 281.118167 -282.837994)
			(xy 281.15366 -282.872086) (xy 281.183225 -282.91143) (xy 281.206096 -282.955007) (xy 281.22168 -283.001688)
			(xy 281.229575 -283.050265) (xy 281.23007 -283.074872) (xy 281.568918 -283.074872) (xy 281.572878 -283.025818)
			(xy 281.584655 -282.978034) (xy 281.603946 -282.932758) (xy 281.630249 -282.891162) (xy 281.662884 -282.854325)
			(xy 281.701005 -282.8232) (xy 281.743626 -282.798593) (xy 281.789642 -282.781141) (xy 281.837861 -282.771297)
			(xy 281.887036 -282.769316) (xy 281.935891 -282.775248) (xy 281.983162 -282.78894) (xy 282.027624 -282.810038)
			(xy 282.068127 -282.837994) (xy 282.10362 -282.872086) (xy 282.133185 -282.91143) (xy 282.156056 -282.955007)
			(xy 282.17164 -283.001688) (xy 282.179535 -283.050265) (xy 282.18003 -283.074872) (xy 282.519132 -283.074872)
			(xy 282.523092 -283.025818) (xy 282.534869 -282.978034) (xy 282.55416 -282.932758) (xy 282.580463 -282.891162)
			(xy 282.613098 -282.854325) (xy 282.651219 -282.8232) (xy 282.69384 -282.798593) (xy 282.739856 -282.781141)
			(xy 282.788075 -282.771297) (xy 282.83725 -282.769316) (xy 282.886105 -282.775248) (xy 282.933376 -282.78894)
			(xy 282.977838 -282.810038) (xy 283.018341 -282.837994) (xy 283.053834 -282.872086) (xy 283.083399 -282.91143)
			(xy 283.10627 -282.955007) (xy 283.121854 -283.001688) (xy 283.129749 -283.050265) (xy 283.130244 -283.074872)
			(xy 283.469092 -283.074872) (xy 283.473052 -283.025818) (xy 283.484829 -282.978034) (xy 283.50412 -282.932758)
			(xy 283.530423 -282.891162) (xy 283.563058 -282.854325) (xy 283.601179 -282.8232) (xy 283.6438 -282.798593)
			(xy 283.689816 -282.781141) (xy 283.738035 -282.771297) (xy 283.78721 -282.769316) (xy 283.836065 -282.775248)
			(xy 283.883336 -282.78894) (xy 283.927798 -282.810038) (xy 283.968301 -282.837994) (xy 284.003794 -282.872086)
			(xy 284.033359 -282.91143) (xy 284.05623 -282.955007) (xy 284.071814 -283.001688) (xy 284.079709 -283.050265)
			(xy 284.080204 -283.074872) (xy 284.419052 -283.074872) (xy 284.423012 -283.025818) (xy 284.434789 -282.978034)
			(xy 284.45408 -282.932758) (xy 284.480383 -282.891162) (xy 284.513018 -282.854325) (xy 284.551139 -282.8232)
			(xy 284.59376 -282.798593) (xy 284.639776 -282.781141) (xy 284.687995 -282.771297) (xy 284.73717 -282.769316)
			(xy 284.786025 -282.775248) (xy 284.833296 -282.78894) (xy 284.877758 -282.810038) (xy 284.918261 -282.837994)
			(xy 284.953754 -282.872086) (xy 284.983319 -282.91143) (xy 285.00619 -282.955007) (xy 285.021774 -283.001688)
			(xy 285.029669 -283.050265) (xy 285.030164 -283.074872) (xy 285.369012 -283.074872) (xy 285.372972 -283.025818)
			(xy 285.384749 -282.978034) (xy 285.40404 -282.932758) (xy 285.430343 -282.891162) (xy 285.462978 -282.854325)
			(xy 285.501099 -282.8232) (xy 285.54372 -282.798593) (xy 285.589736 -282.781141) (xy 285.637955 -282.771297)
			(xy 285.68713 -282.769316) (xy 285.735985 -282.775248) (xy 285.783256 -282.78894) (xy 285.827718 -282.810038)
			(xy 285.868221 -282.837994) (xy 285.903714 -282.872086) (xy 285.933279 -282.91143) (xy 285.95615 -282.955007)
			(xy 285.971734 -283.001688) (xy 285.979629 -283.050265) (xy 285.980124 -283.074872) (xy 285.979629 -283.099479)
			(xy 285.971734 -283.148056) (xy 285.95615 -283.194737) (xy 285.933279 -283.238314) (xy 285.903714 -283.277658)
			(xy 285.868221 -283.31175) (xy 285.827718 -283.339706) (xy 285.783256 -283.360804) (xy 285.735985 -283.374496)
			(xy 285.68713 -283.380428) (xy 285.637955 -283.378447) (xy 285.589736 -283.368603) (xy 285.54372 -283.351151)
			(xy 285.501099 -283.326544) (xy 285.462978 -283.295419) (xy 285.430343 -283.258582) (xy 285.40404 -283.216986)
			(xy 285.384749 -283.17171) (xy 285.372972 -283.123926) (xy 285.369012 -283.074872) (xy 285.030164 -283.074872)
			(xy 285.029669 -283.099479) (xy 285.021774 -283.148056) (xy 285.00619 -283.194737) (xy 284.983319 -283.238314)
			(xy 284.953754 -283.277658) (xy 284.918261 -283.31175) (xy 284.877758 -283.339706) (xy 284.833296 -283.360804)
			(xy 284.786025 -283.374496) (xy 284.73717 -283.380428) (xy 284.687995 -283.378447) (xy 284.639776 -283.368603)
			(xy 284.59376 -283.351151) (xy 284.551139 -283.326544) (xy 284.513018 -283.295419) (xy 284.480383 -283.258582)
			(xy 284.45408 -283.216986) (xy 284.434789 -283.17171) (xy 284.423012 -283.123926) (xy 284.419052 -283.074872)
			(xy 284.080204 -283.074872) (xy 284.079709 -283.099479) (xy 284.071814 -283.148056) (xy 284.05623 -283.194737)
			(xy 284.033359 -283.238314) (xy 284.003794 -283.277658) (xy 283.968301 -283.31175) (xy 283.927798 -283.339706)
			(xy 283.883336 -283.360804) (xy 283.836065 -283.374496) (xy 283.78721 -283.380428) (xy 283.738035 -283.378447)
			(xy 283.689816 -283.368603) (xy 283.6438 -283.351151) (xy 283.601179 -283.326544) (xy 283.563058 -283.295419)
			(xy 283.530423 -283.258582) (xy 283.50412 -283.216986) (xy 283.484829 -283.17171) (xy 283.473052 -283.123926)
			(xy 283.469092 -283.074872) (xy 283.130244 -283.074872) (xy 283.129749 -283.099479) (xy 283.121854 -283.148056)
			(xy 283.10627 -283.194737) (xy 283.083399 -283.238314) (xy 283.053834 -283.277658) (xy 283.018341 -283.31175)
			(xy 282.977838 -283.339706) (xy 282.933376 -283.360804) (xy 282.886105 -283.374496) (xy 282.83725 -283.380428)
			(xy 282.788075 -283.378447) (xy 282.739856 -283.368603) (xy 282.69384 -283.351151) (xy 282.651219 -283.326544)
			(xy 282.613098 -283.295419) (xy 282.580463 -283.258582) (xy 282.55416 -283.216986) (xy 282.534869 -283.17171)
			(xy 282.523092 -283.123926) (xy 282.519132 -283.074872) (xy 282.18003 -283.074872) (xy 282.179535 -283.099479)
			(xy 282.17164 -283.148056) (xy 282.156056 -283.194737) (xy 282.133185 -283.238314) (xy 282.10362 -283.277658)
			(xy 282.068127 -283.31175) (xy 282.027624 -283.339706) (xy 281.983162 -283.360804) (xy 281.935891 -283.374496)
			(xy 281.887036 -283.380428) (xy 281.837861 -283.378447) (xy 281.789642 -283.368603) (xy 281.743626 -283.351151)
			(xy 281.701005 -283.326544) (xy 281.662884 -283.295419) (xy 281.630249 -283.258582) (xy 281.603946 -283.216986)
			(xy 281.584655 -283.17171) (xy 281.572878 -283.123926) (xy 281.568918 -283.074872) (xy 281.23007 -283.074872)
			(xy 281.229575 -283.099479) (xy 281.22168 -283.148056) (xy 281.206096 -283.194737) (xy 281.183225 -283.238314)
			(xy 281.15366 -283.277658) (xy 281.118167 -283.31175) (xy 281.077664 -283.339706) (xy 281.033202 -283.360804)
			(xy 280.985931 -283.374496) (xy 280.937076 -283.380428) (xy 280.887901 -283.378447) (xy 280.839682 -283.368603)
			(xy 280.793666 -283.351151) (xy 280.751045 -283.326544) (xy 280.712924 -283.295419) (xy 280.680289 -283.258582)
			(xy 280.653986 -283.216986) (xy 280.634695 -283.17171) (xy 280.622918 -283.123926) (xy 280.618958 -283.074872)
			(xy 280.28011 -283.074872) (xy 280.279615 -283.099479) (xy 280.27172 -283.148056) (xy 280.256136 -283.194737)
			(xy 280.233265 -283.238314) (xy 280.2037 -283.277658) (xy 280.168207 -283.31175) (xy 280.127704 -283.339706)
			(xy 280.083242 -283.360804) (xy 280.035971 -283.374496) (xy 279.987116 -283.380428) (xy 279.937941 -283.378447)
			(xy 279.889722 -283.368603) (xy 279.843706 -283.351151) (xy 279.801085 -283.326544) (xy 279.762964 -283.295419)
			(xy 279.730329 -283.258582) (xy 279.704026 -283.216986) (xy 279.684735 -283.17171) (xy 279.672958 -283.123926)
			(xy 279.668998 -283.074872) (xy 279.33015 -283.074872) (xy 279.329655 -283.099479) (xy 279.32176 -283.148056)
			(xy 279.306176 -283.194737) (xy 279.283305 -283.238314) (xy 279.25374 -283.277658) (xy 279.218247 -283.31175)
			(xy 279.177744 -283.339706) (xy 279.133282 -283.360804) (xy 279.086011 -283.374496) (xy 279.037156 -283.380428)
			(xy 278.987981 -283.378447) (xy 278.939762 -283.368603) (xy 278.893746 -283.351151) (xy 278.851125 -283.326544)
			(xy 278.813004 -283.295419) (xy 278.780369 -283.258582) (xy 278.754066 -283.216986) (xy 278.734775 -283.17171)
			(xy 278.722998 -283.123926) (xy 278.719038 -283.074872) (xy 278.38019 -283.074872) (xy 278.379695 -283.099479)
			(xy 278.3718 -283.148056) (xy 278.356216 -283.194737) (xy 278.333345 -283.238314) (xy 278.30378 -283.277658)
			(xy 278.268287 -283.31175) (xy 278.227784 -283.339706) (xy 278.183322 -283.360804) (xy 278.136051 -283.374496)
			(xy 278.087196 -283.380428) (xy 278.038021 -283.378447) (xy 277.989802 -283.368603) (xy 277.943786 -283.351151)
			(xy 277.901165 -283.326544) (xy 277.863044 -283.295419) (xy 277.830409 -283.258582) (xy 277.804106 -283.216986)
			(xy 277.784815 -283.17171) (xy 277.773038 -283.123926) (xy 277.769078 -283.074872) (xy 277.43023 -283.074872)
			(xy 277.429735 -283.099479) (xy 277.42184 -283.148056) (xy 277.406256 -283.194737) (xy 277.383385 -283.238314)
			(xy 277.35382 -283.277658) (xy 277.318327 -283.31175) (xy 277.277824 -283.339706) (xy 277.233362 -283.360804)
			(xy 277.186091 -283.374496) (xy 277.137236 -283.380428) (xy 277.088061 -283.378447) (xy 277.039842 -283.368603)
			(xy 276.993826 -283.351151) (xy 276.951205 -283.326544) (xy 276.913084 -283.295419) (xy 276.880449 -283.258582)
			(xy 276.854146 -283.216986) (xy 276.834855 -283.17171) (xy 276.823078 -283.123926) (xy 276.819118 -283.074872)
			(xy 276.6314 -283.074872) (xy 276.6314 -283.549852) (xy 305.793914 -283.549852) (xy 305.797874 -283.500798)
			(xy 305.809651 -283.453014) (xy 305.828942 -283.407738) (xy 305.855245 -283.366142) (xy 305.88788 -283.329305)
			(xy 305.926001 -283.29818) (xy 305.968622 -283.273573) (xy 306.014638 -283.256121) (xy 306.062857 -283.246277)
			(xy 306.112032 -283.244296) (xy 306.160887 -283.250228) (xy 306.208158 -283.26392) (xy 306.25262 -283.285018)
			(xy 306.293123 -283.312974) (xy 306.328616 -283.347066) (xy 306.358181 -283.38641) (xy 306.381052 -283.429987)
			(xy 306.396636 -283.476668) (xy 306.404531 -283.525245) (xy 306.405026 -283.549852) (xy 306.404531 -283.574459)
			(xy 306.404352 -283.57556) (xy 306.72303 -283.57556) (xy 306.72303 -283.524144) (xy 306.731073 -283.473362)
			(xy 306.746961 -283.424463) (xy 306.770304 -283.378651) (xy 306.800525 -283.337055) (xy 306.836881 -283.300699)
			(xy 306.878477 -283.270478) (xy 306.924289 -283.247135) (xy 306.973188 -283.231247) (xy 307.02397 -283.223204)
			(xy 307.075386 -283.223204) (xy 307.126168 -283.231247) (xy 307.175067 -283.247135) (xy 307.220879 -283.270478)
			(xy 307.262475 -283.300699) (xy 307.298831 -283.337055) (xy 307.329052 -283.378651) (xy 307.352395 -283.424463)
			(xy 307.368283 -283.473362) (xy 307.376326 -283.524144) (xy 307.37683 -283.549852) (xy 307.376326 -283.57556)
			(xy 307.673244 -283.57556) (xy 307.673244 -283.524144) (xy 307.681287 -283.473362) (xy 307.697175 -283.424463)
			(xy 307.720518 -283.378651) (xy 307.750739 -283.337055) (xy 307.787095 -283.300699) (xy 307.828691 -283.270478)
			(xy 307.874503 -283.247135) (xy 307.923402 -283.231247) (xy 307.974184 -283.223204) (xy 308.0256 -283.223204)
			(xy 308.076382 -283.231247) (xy 308.125281 -283.247135) (xy 308.171093 -283.270478) (xy 308.212689 -283.300699)
			(xy 308.249045 -283.337055) (xy 308.279266 -283.378651) (xy 308.302609 -283.424463) (xy 308.318497 -283.473362)
			(xy 308.32654 -283.524144) (xy 308.327044 -283.549852) (xy 308.644048 -283.549852) (xy 308.648008 -283.500798)
			(xy 308.659785 -283.453014) (xy 308.679076 -283.407738) (xy 308.705379 -283.366142) (xy 308.738014 -283.329305)
			(xy 308.776135 -283.29818) (xy 308.818756 -283.273573) (xy 308.864772 -283.256121) (xy 308.912991 -283.246277)
			(xy 308.962166 -283.244296) (xy 309.011021 -283.250228) (xy 309.058292 -283.26392) (xy 309.102754 -283.285018)
			(xy 309.143257 -283.312974) (xy 309.17875 -283.347066) (xy 309.208315 -283.38641) (xy 309.231186 -283.429987)
			(xy 309.24677 -283.476668) (xy 309.254665 -283.525245) (xy 309.25516 -283.549852) (xy 309.594008 -283.549852)
			(xy 309.597968 -283.500798) (xy 309.609745 -283.453014) (xy 309.629036 -283.407738) (xy 309.655339 -283.366142)
			(xy 309.687974 -283.329305) (xy 309.726095 -283.29818) (xy 309.768716 -283.273573) (xy 309.814732 -283.256121)
			(xy 309.862951 -283.246277) (xy 309.912126 -283.244296) (xy 309.960981 -283.250228) (xy 310.008252 -283.26392)
			(xy 310.052714 -283.285018) (xy 310.093217 -283.312974) (xy 310.12871 -283.347066) (xy 310.158275 -283.38641)
			(xy 310.181146 -283.429987) (xy 310.19673 -283.476668) (xy 310.204625 -283.525245) (xy 310.20512 -283.549852)
			(xy 310.543968 -283.549852) (xy 310.547928 -283.500798) (xy 310.559705 -283.453014) (xy 310.578996 -283.407738)
			(xy 310.605299 -283.366142) (xy 310.637934 -283.329305) (xy 310.676055 -283.29818) (xy 310.718676 -283.273573)
			(xy 310.764692 -283.256121) (xy 310.812911 -283.246277) (xy 310.862086 -283.244296) (xy 310.910941 -283.250228)
			(xy 310.958212 -283.26392) (xy 311.002674 -283.285018) (xy 311.043177 -283.312974) (xy 311.07867 -283.347066)
			(xy 311.108235 -283.38641) (xy 311.131106 -283.429987) (xy 311.14669 -283.476668) (xy 311.154585 -283.525245)
			(xy 311.15508 -283.549852) (xy 311.493928 -283.549852) (xy 311.497888 -283.500798) (xy 311.509665 -283.453014)
			(xy 311.528956 -283.407738) (xy 311.555259 -283.366142) (xy 311.587894 -283.329305) (xy 311.626015 -283.29818)
			(xy 311.668636 -283.273573) (xy 311.714652 -283.256121) (xy 311.762871 -283.246277) (xy 311.812046 -283.244296)
			(xy 311.860901 -283.250228) (xy 311.908172 -283.26392) (xy 311.952634 -283.285018) (xy 311.993137 -283.312974)
			(xy 312.02863 -283.347066) (xy 312.058195 -283.38641) (xy 312.081066 -283.429987) (xy 312.09665 -283.476668)
			(xy 312.104545 -283.525245) (xy 312.10504 -283.549852) (xy 312.443888 -283.549852) (xy 312.447848 -283.500798)
			(xy 312.459625 -283.453014) (xy 312.478916 -283.407738) (xy 312.505219 -283.366142) (xy 312.537854 -283.329305)
			(xy 312.575975 -283.29818) (xy 312.618596 -283.273573) (xy 312.664612 -283.256121) (xy 312.712831 -283.246277)
			(xy 312.762006 -283.244296) (xy 312.810861 -283.250228) (xy 312.858132 -283.26392) (xy 312.902594 -283.285018)
			(xy 312.943097 -283.312974) (xy 312.97859 -283.347066) (xy 313.008155 -283.38641) (xy 313.031026 -283.429987)
			(xy 313.04661 -283.476668) (xy 313.054505 -283.525245) (xy 313.055 -283.549852) (xy 313.054505 -283.574459)
			(xy 313.054326 -283.57556) (xy 313.373258 -283.57556) (xy 313.373258 -283.524144) (xy 313.381301 -283.473362)
			(xy 313.397189 -283.424463) (xy 313.420532 -283.378651) (xy 313.450753 -283.337055) (xy 313.487109 -283.300699)
			(xy 313.528705 -283.270478) (xy 313.574517 -283.247135) (xy 313.623416 -283.231247) (xy 313.674198 -283.223204)
			(xy 313.725614 -283.223204) (xy 313.776396 -283.231247) (xy 313.825295 -283.247135) (xy 313.871107 -283.270478)
			(xy 313.912703 -283.300699) (xy 313.949059 -283.337055) (xy 313.97928 -283.378651) (xy 314.002623 -283.424463)
			(xy 314.018511 -283.473362) (xy 314.026554 -283.524144) (xy 314.027058 -283.549852) (xy 314.026554 -283.57556)
			(xy 314.323218 -283.57556) (xy 314.323218 -283.524144) (xy 314.331261 -283.473362) (xy 314.347149 -283.424463)
			(xy 314.370492 -283.378651) (xy 314.400713 -283.337055) (xy 314.437069 -283.300699) (xy 314.478665 -283.270478)
			(xy 314.524477 -283.247135) (xy 314.573376 -283.231247) (xy 314.624158 -283.223204) (xy 314.675574 -283.223204)
			(xy 314.726356 -283.231247) (xy 314.775255 -283.247135) (xy 314.821067 -283.270478) (xy 314.862663 -283.300699)
			(xy 314.899019 -283.337055) (xy 314.92924 -283.378651) (xy 314.952583 -283.424463) (xy 314.968471 -283.473362)
			(xy 314.976514 -283.524144) (xy 314.977018 -283.549852) (xy 314.977013 -283.550106) (xy 315.294276 -283.550106)
			(xy 315.298236 -283.501052) (xy 315.310013 -283.453268) (xy 315.329304 -283.407992) (xy 315.355607 -283.366396)
			(xy 315.388242 -283.329559) (xy 315.426363 -283.298434) (xy 315.468984 -283.273827) (xy 315.515 -283.256375)
			(xy 315.563219 -283.246531) (xy 315.612394 -283.24455) (xy 315.661249 -283.250482) (xy 315.70852 -283.264174)
			(xy 315.752982 -283.285272) (xy 315.793485 -283.313228) (xy 315.828978 -283.34732) (xy 315.858543 -283.386664)
			(xy 315.881414 -283.430241) (xy 315.896998 -283.476922) (xy 315.904893 -283.525499) (xy 315.905388 -283.550106)
			(xy 315.904893 -283.574713) (xy 315.896998 -283.62329) (xy 315.881414 -283.669971) (xy 315.858543 -283.713548)
			(xy 315.828978 -283.752892) (xy 315.793485 -283.786984) (xy 315.752982 -283.81494) (xy 315.70852 -283.836038)
			(xy 315.661249 -283.84973) (xy 315.612394 -283.855662) (xy 315.563219 -283.853681) (xy 315.515 -283.843837)
			(xy 315.468984 -283.826385) (xy 315.426363 -283.801778) (xy 315.388242 -283.770653) (xy 315.355607 -283.733816)
			(xy 315.329304 -283.69222) (xy 315.310013 -283.646944) (xy 315.298236 -283.59916) (xy 315.294276 -283.550106)
			(xy 314.977013 -283.550106) (xy 314.976514 -283.57556) (xy 314.968471 -283.626342) (xy 314.952583 -283.675241)
			(xy 314.92924 -283.721053) (xy 314.899019 -283.762649) (xy 314.862663 -283.799005) (xy 314.821067 -283.829226)
			(xy 314.775255 -283.852569) (xy 314.726356 -283.868457) (xy 314.675574 -283.8765) (xy 314.624158 -283.8765)
			(xy 314.573376 -283.868457) (xy 314.524477 -283.852569) (xy 314.478665 -283.829226) (xy 314.437069 -283.799005)
			(xy 314.400713 -283.762649) (xy 314.370492 -283.721053) (xy 314.347149 -283.675241) (xy 314.331261 -283.626342)
			(xy 314.323218 -283.57556) (xy 314.026554 -283.57556) (xy 314.018511 -283.626342) (xy 314.002623 -283.675241)
			(xy 313.97928 -283.721053) (xy 313.949059 -283.762649) (xy 313.912703 -283.799005) (xy 313.871107 -283.829226)
			(xy 313.825295 -283.852569) (xy 313.776396 -283.868457) (xy 313.725614 -283.8765) (xy 313.674198 -283.8765)
			(xy 313.623416 -283.868457) (xy 313.574517 -283.852569) (xy 313.528705 -283.829226) (xy 313.487109 -283.799005)
			(xy 313.450753 -283.762649) (xy 313.420532 -283.721053) (xy 313.397189 -283.675241) (xy 313.381301 -283.626342)
			(xy 313.373258 -283.57556) (xy 313.054326 -283.57556) (xy 313.04661 -283.623036) (xy 313.031026 -283.669717)
			(xy 313.008155 -283.713294) (xy 312.97859 -283.752638) (xy 312.943097 -283.78673) (xy 312.902594 -283.814686)
			(xy 312.858132 -283.835784) (xy 312.810861 -283.849476) (xy 312.762006 -283.855408) (xy 312.712831 -283.853427)
			(xy 312.664612 -283.843583) (xy 312.618596 -283.826131) (xy 312.575975 -283.801524) (xy 312.537854 -283.770399)
			(xy 312.505219 -283.733562) (xy 312.478916 -283.691966) (xy 312.459625 -283.64669) (xy 312.447848 -283.598906)
			(xy 312.443888 -283.549852) (xy 312.10504 -283.549852) (xy 312.104545 -283.574459) (xy 312.09665 -283.623036)
			(xy 312.081066 -283.669717) (xy 312.058195 -283.713294) (xy 312.02863 -283.752638) (xy 311.993137 -283.78673)
			(xy 311.952634 -283.814686) (xy 311.908172 -283.835784) (xy 311.860901 -283.849476) (xy 311.812046 -283.855408)
			(xy 311.762871 -283.853427) (xy 311.714652 -283.843583) (xy 311.668636 -283.826131) (xy 311.626015 -283.801524)
			(xy 311.587894 -283.770399) (xy 311.555259 -283.733562) (xy 311.528956 -283.691966) (xy 311.509665 -283.64669)
			(xy 311.497888 -283.598906) (xy 311.493928 -283.549852) (xy 311.15508 -283.549852) (xy 311.154585 -283.574459)
			(xy 311.14669 -283.623036) (xy 311.131106 -283.669717) (xy 311.108235 -283.713294) (xy 311.07867 -283.752638)
			(xy 311.043177 -283.78673) (xy 311.002674 -283.814686) (xy 310.958212 -283.835784) (xy 310.910941 -283.849476)
			(xy 310.862086 -283.855408) (xy 310.812911 -283.853427) (xy 310.764692 -283.843583) (xy 310.718676 -283.826131)
			(xy 310.676055 -283.801524) (xy 310.637934 -283.770399) (xy 310.605299 -283.733562) (xy 310.578996 -283.691966)
			(xy 310.559705 -283.64669) (xy 310.547928 -283.598906) (xy 310.543968 -283.549852) (xy 310.20512 -283.549852)
			(xy 310.204625 -283.574459) (xy 310.19673 -283.623036) (xy 310.181146 -283.669717) (xy 310.158275 -283.713294)
			(xy 310.12871 -283.752638) (xy 310.093217 -283.78673) (xy 310.052714 -283.814686) (xy 310.008252 -283.835784)
			(xy 309.960981 -283.849476) (xy 309.912126 -283.855408) (xy 309.862951 -283.853427) (xy 309.814732 -283.843583)
			(xy 309.768716 -283.826131) (xy 309.726095 -283.801524) (xy 309.687974 -283.770399) (xy 309.655339 -283.733562)
			(xy 309.629036 -283.691966) (xy 309.609745 -283.64669) (xy 309.597968 -283.598906) (xy 309.594008 -283.549852)
			(xy 309.25516 -283.549852) (xy 309.254665 -283.574459) (xy 309.24677 -283.623036) (xy 309.231186 -283.669717)
			(xy 309.208315 -283.713294) (xy 309.17875 -283.752638) (xy 309.143257 -283.78673) (xy 309.102754 -283.814686)
			(xy 309.058292 -283.835784) (xy 309.011021 -283.849476) (xy 308.962166 -283.855408) (xy 308.912991 -283.853427)
			(xy 308.864772 -283.843583) (xy 308.818756 -283.826131) (xy 308.776135 -283.801524) (xy 308.738014 -283.770399)
			(xy 308.705379 -283.733562) (xy 308.679076 -283.691966) (xy 308.659785 -283.64669) (xy 308.648008 -283.598906)
			(xy 308.644048 -283.549852) (xy 308.327044 -283.549852) (xy 308.32654 -283.57556) (xy 308.318497 -283.626342)
			(xy 308.302609 -283.675241) (xy 308.279266 -283.721053) (xy 308.249045 -283.762649) (xy 308.212689 -283.799005)
			(xy 308.171093 -283.829226) (xy 308.125281 -283.852569) (xy 308.076382 -283.868457) (xy 308.0256 -283.8765)
			(xy 307.974184 -283.8765) (xy 307.923402 -283.868457) (xy 307.874503 -283.852569) (xy 307.828691 -283.829226)
			(xy 307.787095 -283.799005) (xy 307.750739 -283.762649) (xy 307.720518 -283.721053) (xy 307.697175 -283.675241)
			(xy 307.681287 -283.626342) (xy 307.673244 -283.57556) (xy 307.376326 -283.57556) (xy 307.368283 -283.626342)
			(xy 307.352395 -283.675241) (xy 307.329052 -283.721053) (xy 307.298831 -283.762649) (xy 307.262475 -283.799005)
			(xy 307.220879 -283.829226) (xy 307.175067 -283.852569) (xy 307.126168 -283.868457) (xy 307.075386 -283.8765)
			(xy 307.02397 -283.8765) (xy 306.973188 -283.868457) (xy 306.924289 -283.852569) (xy 306.878477 -283.829226)
			(xy 306.836881 -283.799005) (xy 306.800525 -283.762649) (xy 306.770304 -283.721053) (xy 306.746961 -283.675241)
			(xy 306.731073 -283.626342) (xy 306.72303 -283.57556) (xy 306.404352 -283.57556) (xy 306.396636 -283.623036)
			(xy 306.381052 -283.669717) (xy 306.358181 -283.713294) (xy 306.328616 -283.752638) (xy 306.293123 -283.78673)
			(xy 306.25262 -283.814686) (xy 306.208158 -283.835784) (xy 306.160887 -283.849476) (xy 306.112032 -283.855408)
			(xy 306.062857 -283.853427) (xy 306.014638 -283.843583) (xy 305.968622 -283.826131) (xy 305.926001 -283.801524)
			(xy 305.88788 -283.770399) (xy 305.855245 -283.733562) (xy 305.828942 -283.691966) (xy 305.809651 -283.64669)
			(xy 305.797874 -283.598906) (xy 305.793914 -283.549852) (xy 276.6314 -283.549852) (xy 276.6314 -284.024832)
			(xy 276.819118 -284.024832) (xy 276.823078 -283.975778) (xy 276.834855 -283.927994) (xy 276.854146 -283.882718)
			(xy 276.880449 -283.841122) (xy 276.913084 -283.804285) (xy 276.951205 -283.77316) (xy 276.993826 -283.748553)
			(xy 277.039842 -283.731101) (xy 277.088061 -283.721257) (xy 277.137236 -283.719276) (xy 277.186091 -283.725208)
			(xy 277.233362 -283.7389) (xy 277.277824 -283.759998) (xy 277.318327 -283.787954) (xy 277.35382 -283.822046)
			(xy 277.383385 -283.86139) (xy 277.406256 -283.904967) (xy 277.42184 -283.951648) (xy 277.429735 -284.000225)
			(xy 277.43023 -284.024832) (xy 277.769078 -284.024832) (xy 277.773038 -283.975778) (xy 277.784815 -283.927994)
			(xy 277.804106 -283.882718) (xy 277.830409 -283.841122) (xy 277.863044 -283.804285) (xy 277.901165 -283.77316)
			(xy 277.943786 -283.748553) (xy 277.989802 -283.731101) (xy 278.038021 -283.721257) (xy 278.087196 -283.719276)
			(xy 278.136051 -283.725208) (xy 278.183322 -283.7389) (xy 278.227784 -283.759998) (xy 278.268287 -283.787954)
			(xy 278.30378 -283.822046) (xy 278.333345 -283.86139) (xy 278.356216 -283.904967) (xy 278.3718 -283.951648)
			(xy 278.379695 -284.000225) (xy 278.38019 -284.024832) (xy 278.719038 -284.024832) (xy 278.722998 -283.975778)
			(xy 278.734775 -283.927994) (xy 278.754066 -283.882718) (xy 278.780369 -283.841122) (xy 278.813004 -283.804285)
			(xy 278.851125 -283.77316) (xy 278.893746 -283.748553) (xy 278.939762 -283.731101) (xy 278.987981 -283.721257)
			(xy 279.037156 -283.719276) (xy 279.086011 -283.725208) (xy 279.133282 -283.7389) (xy 279.177744 -283.759998)
			(xy 279.218247 -283.787954) (xy 279.25374 -283.822046) (xy 279.283305 -283.86139) (xy 279.306176 -283.904967)
			(xy 279.32176 -283.951648) (xy 279.329655 -284.000225) (xy 279.33015 -284.024832) (xy 279.668998 -284.024832)
			(xy 279.672958 -283.975778) (xy 279.684735 -283.927994) (xy 279.704026 -283.882718) (xy 279.730329 -283.841122)
			(xy 279.762964 -283.804285) (xy 279.801085 -283.77316) (xy 279.843706 -283.748553) (xy 279.889722 -283.731101)
			(xy 279.937941 -283.721257) (xy 279.987116 -283.719276) (xy 280.035971 -283.725208) (xy 280.083242 -283.7389)
			(xy 280.127704 -283.759998) (xy 280.168207 -283.787954) (xy 280.2037 -283.822046) (xy 280.233265 -283.86139)
			(xy 280.256136 -283.904967) (xy 280.27172 -283.951648) (xy 280.279615 -284.000225) (xy 280.28011 -284.024832)
			(xy 280.618958 -284.024832) (xy 280.622918 -283.975778) (xy 280.634695 -283.927994) (xy 280.653986 -283.882718)
			(xy 280.680289 -283.841122) (xy 280.712924 -283.804285) (xy 280.751045 -283.77316) (xy 280.793666 -283.748553)
			(xy 280.839682 -283.731101) (xy 280.887901 -283.721257) (xy 280.937076 -283.719276) (xy 280.985931 -283.725208)
			(xy 281.033202 -283.7389) (xy 281.077664 -283.759998) (xy 281.118167 -283.787954) (xy 281.15366 -283.822046)
			(xy 281.183225 -283.86139) (xy 281.206096 -283.904967) (xy 281.22168 -283.951648) (xy 281.229575 -284.000225)
			(xy 281.23007 -284.024832) (xy 281.568918 -284.024832) (xy 281.572878 -283.975778) (xy 281.584655 -283.927994)
			(xy 281.603946 -283.882718) (xy 281.630249 -283.841122) (xy 281.662884 -283.804285) (xy 281.701005 -283.77316)
			(xy 281.743626 -283.748553) (xy 281.789642 -283.731101) (xy 281.837861 -283.721257) (xy 281.887036 -283.719276)
			(xy 281.935891 -283.725208) (xy 281.983162 -283.7389) (xy 282.027624 -283.759998) (xy 282.068127 -283.787954)
			(xy 282.10362 -283.822046) (xy 282.133185 -283.86139) (xy 282.156056 -283.904967) (xy 282.17164 -283.951648)
			(xy 282.179535 -284.000225) (xy 282.18003 -284.024832) (xy 282.519132 -284.024832) (xy 282.523092 -283.975778)
			(xy 282.534869 -283.927994) (xy 282.55416 -283.882718) (xy 282.580463 -283.841122) (xy 282.613098 -283.804285)
			(xy 282.651219 -283.77316) (xy 282.69384 -283.748553) (xy 282.739856 -283.731101) (xy 282.788075 -283.721257)
			(xy 282.83725 -283.719276) (xy 282.886105 -283.725208) (xy 282.933376 -283.7389) (xy 282.977838 -283.759998)
			(xy 283.018341 -283.787954) (xy 283.053834 -283.822046) (xy 283.083399 -283.86139) (xy 283.10627 -283.904967)
			(xy 283.121854 -283.951648) (xy 283.129749 -284.000225) (xy 283.130244 -284.024832) (xy 283.469092 -284.024832)
			(xy 283.473052 -283.975778) (xy 283.484829 -283.927994) (xy 283.50412 -283.882718) (xy 283.530423 -283.841122)
			(xy 283.563058 -283.804285) (xy 283.601179 -283.77316) (xy 283.6438 -283.748553) (xy 283.689816 -283.731101)
			(xy 283.738035 -283.721257) (xy 283.78721 -283.719276) (xy 283.836065 -283.725208) (xy 283.883336 -283.7389)
			(xy 283.927798 -283.759998) (xy 283.968301 -283.787954) (xy 284.003794 -283.822046) (xy 284.033359 -283.86139)
			(xy 284.05623 -283.904967) (xy 284.071814 -283.951648) (xy 284.079709 -284.000225) (xy 284.080204 -284.024832)
			(xy 284.419052 -284.024832) (xy 284.423012 -283.975778) (xy 284.434789 -283.927994) (xy 284.45408 -283.882718)
			(xy 284.480383 -283.841122) (xy 284.513018 -283.804285) (xy 284.551139 -283.77316) (xy 284.59376 -283.748553)
			(xy 284.639776 -283.731101) (xy 284.687995 -283.721257) (xy 284.73717 -283.719276) (xy 284.786025 -283.725208)
			(xy 284.833296 -283.7389) (xy 284.877758 -283.759998) (xy 284.918261 -283.787954) (xy 284.953754 -283.822046)
			(xy 284.983319 -283.86139) (xy 285.00619 -283.904967) (xy 285.021774 -283.951648) (xy 285.029669 -284.000225)
			(xy 285.030164 -284.024832) (xy 285.369012 -284.024832) (xy 285.372972 -283.975778) (xy 285.384749 -283.927994)
			(xy 285.40404 -283.882718) (xy 285.430343 -283.841122) (xy 285.462978 -283.804285) (xy 285.501099 -283.77316)
			(xy 285.54372 -283.748553) (xy 285.589736 -283.731101) (xy 285.637955 -283.721257) (xy 285.68713 -283.719276)
			(xy 285.735985 -283.725208) (xy 285.783256 -283.7389) (xy 285.827718 -283.759998) (xy 285.868221 -283.787954)
			(xy 285.903714 -283.822046) (xy 285.933279 -283.86139) (xy 285.95615 -283.904967) (xy 285.971734 -283.951648)
			(xy 285.979629 -284.000225) (xy 285.980124 -284.024832) (xy 286.318972 -284.024832) (xy 286.322932 -283.975778)
			(xy 286.334709 -283.927994) (xy 286.354 -283.882718) (xy 286.380303 -283.841122) (xy 286.412938 -283.804285)
			(xy 286.451059 -283.77316) (xy 286.49368 -283.748553) (xy 286.539696 -283.731101) (xy 286.587915 -283.721257)
			(xy 286.63709 -283.719276) (xy 286.685945 -283.725208) (xy 286.733216 -283.7389) (xy 286.777678 -283.759998)
			(xy 286.818181 -283.787954) (xy 286.853674 -283.822046) (xy 286.883239 -283.86139) (xy 286.90611 -283.904967)
			(xy 286.921694 -283.951648) (xy 286.929589 -284.000225) (xy 286.930084 -284.024832) (xy 287.268932 -284.024832)
			(xy 287.272892 -283.975778) (xy 287.284669 -283.927994) (xy 287.30396 -283.882718) (xy 287.330263 -283.841122)
			(xy 287.362898 -283.804285) (xy 287.401019 -283.77316) (xy 287.44364 -283.748553) (xy 287.489656 -283.731101)
			(xy 287.537875 -283.721257) (xy 287.58705 -283.719276) (xy 287.635905 -283.725208) (xy 287.683176 -283.7389)
			(xy 287.727638 -283.759998) (xy 287.768141 -283.787954) (xy 287.803634 -283.822046) (xy 287.833199 -283.86139)
			(xy 287.85607 -283.904967) (xy 287.871654 -283.951648) (xy 287.879549 -284.000225) (xy 287.880044 -284.024832)
			(xy 288.218892 -284.024832) (xy 288.222852 -283.975778) (xy 288.234629 -283.927994) (xy 288.25392 -283.882718)
			(xy 288.280223 -283.841122) (xy 288.312858 -283.804285) (xy 288.350979 -283.77316) (xy 288.3936 -283.748553)
			(xy 288.439616 -283.731101) (xy 288.487835 -283.721257) (xy 288.53701 -283.719276) (xy 288.585865 -283.725208)
			(xy 288.633136 -283.7389) (xy 288.677598 -283.759998) (xy 288.718101 -283.787954) (xy 288.753594 -283.822046)
			(xy 288.783159 -283.86139) (xy 288.80603 -283.904967) (xy 288.821614 -283.951648) (xy 288.829509 -284.000225)
			(xy 288.830004 -284.024832) (xy 289.169106 -284.024832) (xy 289.173066 -283.975778) (xy 289.184843 -283.927994)
			(xy 289.204134 -283.882718) (xy 289.230437 -283.841122) (xy 289.263072 -283.804285) (xy 289.301193 -283.77316)
			(xy 289.343814 -283.748553) (xy 289.38983 -283.731101) (xy 289.438049 -283.721257) (xy 289.487224 -283.719276)
			(xy 289.536079 -283.725208) (xy 289.58335 -283.7389) (xy 289.627812 -283.759998) (xy 289.668315 -283.787954)
			(xy 289.703808 -283.822046) (xy 289.733373 -283.86139) (xy 289.756244 -283.904967) (xy 289.771828 -283.951648)
			(xy 289.779723 -284.000225) (xy 289.780218 -284.024832) (xy 290.119066 -284.024832) (xy 290.123026 -283.975778)
			(xy 290.134803 -283.927994) (xy 290.154094 -283.882718) (xy 290.180397 -283.841122) (xy 290.213032 -283.804285)
			(xy 290.251153 -283.77316) (xy 290.293774 -283.748553) (xy 290.33979 -283.731101) (xy 290.388009 -283.721257)
			(xy 290.437184 -283.719276) (xy 290.486039 -283.725208) (xy 290.53331 -283.7389) (xy 290.577772 -283.759998)
			(xy 290.618275 -283.787954) (xy 290.653768 -283.822046) (xy 290.683333 -283.86139) (xy 290.706204 -283.904967)
			(xy 290.721788 -283.951648) (xy 290.729683 -284.000225) (xy 290.730178 -284.024832) (xy 292.018986 -284.024832)
			(xy 292.022946 -283.975778) (xy 292.034723 -283.927994) (xy 292.054014 -283.882718) (xy 292.080317 -283.841122)
			(xy 292.112952 -283.804285) (xy 292.151073 -283.77316) (xy 292.193694 -283.748553) (xy 292.23971 -283.731101)
			(xy 292.287929 -283.721257) (xy 292.337104 -283.719276) (xy 292.385959 -283.725208) (xy 292.43323 -283.7389)
			(xy 292.477692 -283.759998) (xy 292.518195 -283.787954) (xy 292.553688 -283.822046) (xy 292.583253 -283.86139)
			(xy 292.606124 -283.904967) (xy 292.621708 -283.951648) (xy 292.629603 -284.000225) (xy 292.630098 -284.024832)
			(xy 292.968946 -284.024832) (xy 292.972906 -283.975778) (xy 292.984683 -283.927994) (xy 293.003974 -283.882718)
			(xy 293.030277 -283.841122) (xy 293.062912 -283.804285) (xy 293.101033 -283.77316) (xy 293.143654 -283.748553)
			(xy 293.18967 -283.731101) (xy 293.237889 -283.721257) (xy 293.287064 -283.719276) (xy 293.335919 -283.725208)
			(xy 293.38319 -283.7389) (xy 293.427652 -283.759998) (xy 293.468155 -283.787954) (xy 293.503648 -283.822046)
			(xy 293.533213 -283.86139) (xy 293.556084 -283.904967) (xy 293.571668 -283.951648) (xy 293.579563 -284.000225)
			(xy 293.580058 -284.024832) (xy 293.918906 -284.024832) (xy 293.922866 -283.975778) (xy 293.934643 -283.927994)
			(xy 293.953934 -283.882718) (xy 293.980237 -283.841122) (xy 294.012872 -283.804285) (xy 294.050993 -283.77316)
			(xy 294.093614 -283.748553) (xy 294.13963 -283.731101) (xy 294.187849 -283.721257) (xy 294.237024 -283.719276)
			(xy 294.285879 -283.725208) (xy 294.33315 -283.7389) (xy 294.377612 -283.759998) (xy 294.418115 -283.787954)
			(xy 294.453608 -283.822046) (xy 294.483173 -283.86139) (xy 294.506044 -283.904967) (xy 294.521628 -283.951648)
			(xy 294.529523 -284.000225) (xy 294.530018 -284.024832) (xy 294.86912 -284.024832) (xy 294.87308 -283.975778)
			(xy 294.884857 -283.927994) (xy 294.904148 -283.882718) (xy 294.930451 -283.841122) (xy 294.963086 -283.804285)
			(xy 295.001207 -283.77316) (xy 295.043828 -283.748553) (xy 295.089844 -283.731101) (xy 295.138063 -283.721257)
			(xy 295.187238 -283.719276) (xy 295.236093 -283.725208) (xy 295.283364 -283.7389) (xy 295.327826 -283.759998)
			(xy 295.368329 -283.787954) (xy 295.403822 -283.822046) (xy 295.433387 -283.86139) (xy 295.456258 -283.904967)
			(xy 295.471842 -283.951648) (xy 295.479737 -284.000225) (xy 295.480232 -284.024832) (xy 295.81908 -284.024832)
			(xy 295.82304 -283.975778) (xy 295.834817 -283.927994) (xy 295.854108 -283.882718) (xy 295.880411 -283.841122)
			(xy 295.913046 -283.804285) (xy 295.951167 -283.77316) (xy 295.993788 -283.748553) (xy 296.039804 -283.731101)
			(xy 296.088023 -283.721257) (xy 296.137198 -283.719276) (xy 296.186053 -283.725208) (xy 296.233324 -283.7389)
			(xy 296.277786 -283.759998) (xy 296.318289 -283.787954) (xy 296.353782 -283.822046) (xy 296.383347 -283.86139)
			(xy 296.406218 -283.904967) (xy 296.421802 -283.951648) (xy 296.429697 -284.000225) (xy 296.430192 -284.024832)
			(xy 296.76904 -284.024832) (xy 296.773 -283.975778) (xy 296.784777 -283.927994) (xy 296.804068 -283.882718)
			(xy 296.830371 -283.841122) (xy 296.863006 -283.804285) (xy 296.901127 -283.77316) (xy 296.943748 -283.748553)
			(xy 296.989764 -283.731101) (xy 297.037983 -283.721257) (xy 297.087158 -283.719276) (xy 297.136013 -283.725208)
			(xy 297.183284 -283.7389) (xy 297.227746 -283.759998) (xy 297.268249 -283.787954) (xy 297.303742 -283.822046)
			(xy 297.333307 -283.86139) (xy 297.356178 -283.904967) (xy 297.371762 -283.951648) (xy 297.379657 -284.000225)
			(xy 297.380152 -284.024832) (xy 297.719 -284.024832) (xy 297.72296 -283.975778) (xy 297.734737 -283.927994)
			(xy 297.754028 -283.882718) (xy 297.780331 -283.841122) (xy 297.812966 -283.804285) (xy 297.851087 -283.77316)
			(xy 297.893708 -283.748553) (xy 297.939724 -283.731101) (xy 297.987943 -283.721257) (xy 298.037118 -283.719276)
			(xy 298.085973 -283.725208) (xy 298.133244 -283.7389) (xy 298.177706 -283.759998) (xy 298.218209 -283.787954)
			(xy 298.253702 -283.822046) (xy 298.283267 -283.86139) (xy 298.306138 -283.904967) (xy 298.321722 -283.951648)
			(xy 298.329617 -284.000225) (xy 298.330112 -284.024832) (xy 298.66896 -284.024832) (xy 298.67292 -283.975778)
			(xy 298.684697 -283.927994) (xy 298.703988 -283.882718) (xy 298.730291 -283.841122) (xy 298.762926 -283.804285)
			(xy 298.801047 -283.77316) (xy 298.843668 -283.748553) (xy 298.889684 -283.731101) (xy 298.937903 -283.721257)
			(xy 298.987078 -283.719276) (xy 299.035933 -283.725208) (xy 299.083204 -283.7389) (xy 299.127666 -283.759998)
			(xy 299.168169 -283.787954) (xy 299.203662 -283.822046) (xy 299.233227 -283.86139) (xy 299.256098 -283.904967)
			(xy 299.271682 -283.951648) (xy 299.279577 -284.000225) (xy 299.280072 -284.024832) (xy 300.56888 -284.024832)
			(xy 300.57284 -283.975778) (xy 300.584617 -283.927994) (xy 300.603908 -283.882718) (xy 300.630211 -283.841122)
			(xy 300.662846 -283.804285) (xy 300.700967 -283.77316) (xy 300.743588 -283.748553) (xy 300.789604 -283.731101)
			(xy 300.837823 -283.721257) (xy 300.886998 -283.719276) (xy 300.935853 -283.725208) (xy 300.983124 -283.7389)
			(xy 301.027586 -283.759998) (xy 301.068089 -283.787954) (xy 301.103582 -283.822046) (xy 301.133147 -283.86139)
			(xy 301.156018 -283.904967) (xy 301.171602 -283.951648) (xy 301.179497 -284.000225) (xy 301.179992 -284.024832)
			(xy 301.519094 -284.024832) (xy 301.523054 -283.975778) (xy 301.534831 -283.927994) (xy 301.554122 -283.882718)
			(xy 301.580425 -283.841122) (xy 301.61306 -283.804285) (xy 301.651181 -283.77316) (xy 301.693802 -283.748553)
			(xy 301.739818 -283.731101) (xy 301.788037 -283.721257) (xy 301.837212 -283.719276) (xy 301.886067 -283.725208)
			(xy 301.933338 -283.7389) (xy 301.9778 -283.759998) (xy 302.018303 -283.787954) (xy 302.053796 -283.822046)
			(xy 302.083361 -283.86139) (xy 302.106232 -283.904967) (xy 302.121816 -283.951648) (xy 302.129711 -284.000225)
			(xy 302.130206 -284.024832) (xy 302.469054 -284.024832) (xy 302.473014 -283.975778) (xy 302.484791 -283.927994)
			(xy 302.504082 -283.882718) (xy 302.530385 -283.841122) (xy 302.56302 -283.804285) (xy 302.601141 -283.77316)
			(xy 302.643762 -283.748553) (xy 302.689778 -283.731101) (xy 302.737997 -283.721257) (xy 302.787172 -283.719276)
			(xy 302.836027 -283.725208) (xy 302.883298 -283.7389) (xy 302.92776 -283.759998) (xy 302.968263 -283.787954)
			(xy 303.003756 -283.822046) (xy 303.033321 -283.86139) (xy 303.056192 -283.904967) (xy 303.071776 -283.951648)
			(xy 303.079671 -284.000225) (xy 303.080166 -284.024832) (xy 303.419014 -284.024832) (xy 303.422974 -283.975778)
			(xy 303.434751 -283.927994) (xy 303.454042 -283.882718) (xy 303.480345 -283.841122) (xy 303.51298 -283.804285)
			(xy 303.551101 -283.77316) (xy 303.593722 -283.748553) (xy 303.639738 -283.731101) (xy 303.687957 -283.721257)
			(xy 303.737132 -283.719276) (xy 303.785987 -283.725208) (xy 303.833258 -283.7389) (xy 303.87772 -283.759998)
			(xy 303.918223 -283.787954) (xy 303.953716 -283.822046) (xy 303.983281 -283.86139) (xy 304.006152 -283.904967)
			(xy 304.021736 -283.951648) (xy 304.029631 -284.000225) (xy 304.030126 -284.024832) (xy 304.368974 -284.024832)
			(xy 304.372934 -283.975778) (xy 304.384711 -283.927994) (xy 304.404002 -283.882718) (xy 304.430305 -283.841122)
			(xy 304.46294 -283.804285) (xy 304.501061 -283.77316) (xy 304.543682 -283.748553) (xy 304.589698 -283.731101)
			(xy 304.637917 -283.721257) (xy 304.687092 -283.719276) (xy 304.735947 -283.725208) (xy 304.783218 -283.7389)
			(xy 304.82768 -283.759998) (xy 304.868183 -283.787954) (xy 304.903676 -283.822046) (xy 304.933241 -283.86139)
			(xy 304.956112 -283.904967) (xy 304.971696 -283.951648) (xy 304.979591 -284.000225) (xy 304.980086 -284.024832)
			(xy 304.979591 -284.049439) (xy 304.971696 -284.098016) (xy 304.956112 -284.144697) (xy 304.933241 -284.188274)
			(xy 304.903676 -284.227618) (xy 304.868183 -284.26171) (xy 304.82768 -284.289666) (xy 304.783218 -284.310764)
			(xy 304.735947 -284.324456) (xy 304.687092 -284.330388) (xy 304.637917 -284.328407) (xy 304.589698 -284.318563)
			(xy 304.543682 -284.301111) (xy 304.501061 -284.276504) (xy 304.46294 -284.245379) (xy 304.430305 -284.208542)
			(xy 304.404002 -284.166946) (xy 304.384711 -284.12167) (xy 304.372934 -284.073886) (xy 304.368974 -284.024832)
			(xy 304.030126 -284.024832) (xy 304.029631 -284.049439) (xy 304.021736 -284.098016) (xy 304.006152 -284.144697)
			(xy 303.983281 -284.188274) (xy 303.953716 -284.227618) (xy 303.918223 -284.26171) (xy 303.87772 -284.289666)
			(xy 303.833258 -284.310764) (xy 303.785987 -284.324456) (xy 303.737132 -284.330388) (xy 303.687957 -284.328407)
			(xy 303.639738 -284.318563) (xy 303.593722 -284.301111) (xy 303.551101 -284.276504) (xy 303.51298 -284.245379)
			(xy 303.480345 -284.208542) (xy 303.454042 -284.166946) (xy 303.434751 -284.12167) (xy 303.422974 -284.073886)
			(xy 303.419014 -284.024832) (xy 303.080166 -284.024832) (xy 303.079671 -284.049439) (xy 303.071776 -284.098016)
			(xy 303.056192 -284.144697) (xy 303.033321 -284.188274) (xy 303.003756 -284.227618) (xy 302.968263 -284.26171)
			(xy 302.92776 -284.289666) (xy 302.883298 -284.310764) (xy 302.836027 -284.324456) (xy 302.787172 -284.330388)
			(xy 302.737997 -284.328407) (xy 302.689778 -284.318563) (xy 302.643762 -284.301111) (xy 302.601141 -284.276504)
			(xy 302.56302 -284.245379) (xy 302.530385 -284.208542) (xy 302.504082 -284.166946) (xy 302.484791 -284.12167)
			(xy 302.473014 -284.073886) (xy 302.469054 -284.024832) (xy 302.130206 -284.024832) (xy 302.129711 -284.049439)
			(xy 302.121816 -284.098016) (xy 302.106232 -284.144697) (xy 302.083361 -284.188274) (xy 302.053796 -284.227618)
			(xy 302.018303 -284.26171) (xy 301.9778 -284.289666) (xy 301.933338 -284.310764) (xy 301.886067 -284.324456)
			(xy 301.837212 -284.330388) (xy 301.788037 -284.328407) (xy 301.739818 -284.318563) (xy 301.693802 -284.301111)
			(xy 301.651181 -284.276504) (xy 301.61306 -284.245379) (xy 301.580425 -284.208542) (xy 301.554122 -284.166946)
			(xy 301.534831 -284.12167) (xy 301.523054 -284.073886) (xy 301.519094 -284.024832) (xy 301.179992 -284.024832)
			(xy 301.179497 -284.049439) (xy 301.171602 -284.098016) (xy 301.156018 -284.144697) (xy 301.133147 -284.188274)
			(xy 301.103582 -284.227618) (xy 301.068089 -284.26171) (xy 301.027586 -284.289666) (xy 300.983124 -284.310764)
			(xy 300.935853 -284.324456) (xy 300.886998 -284.330388) (xy 300.837823 -284.328407) (xy 300.789604 -284.318563)
			(xy 300.743588 -284.301111) (xy 300.700967 -284.276504) (xy 300.662846 -284.245379) (xy 300.630211 -284.208542)
			(xy 300.603908 -284.166946) (xy 300.584617 -284.12167) (xy 300.57284 -284.073886) (xy 300.56888 -284.024832)
			(xy 299.280072 -284.024832) (xy 299.279577 -284.049439) (xy 299.271682 -284.098016) (xy 299.256098 -284.144697)
			(xy 299.233227 -284.188274) (xy 299.203662 -284.227618) (xy 299.168169 -284.26171) (xy 299.127666 -284.289666)
			(xy 299.083204 -284.310764) (xy 299.035933 -284.324456) (xy 298.987078 -284.330388) (xy 298.937903 -284.328407)
			(xy 298.889684 -284.318563) (xy 298.843668 -284.301111) (xy 298.801047 -284.276504) (xy 298.762926 -284.245379)
			(xy 298.730291 -284.208542) (xy 298.703988 -284.166946) (xy 298.684697 -284.12167) (xy 298.67292 -284.073886)
			(xy 298.66896 -284.024832) (xy 298.330112 -284.024832) (xy 298.329617 -284.049439) (xy 298.321722 -284.098016)
			(xy 298.306138 -284.144697) (xy 298.283267 -284.188274) (xy 298.253702 -284.227618) (xy 298.218209 -284.26171)
			(xy 298.177706 -284.289666) (xy 298.133244 -284.310764) (xy 298.085973 -284.324456) (xy 298.037118 -284.330388)
			(xy 297.987943 -284.328407) (xy 297.939724 -284.318563) (xy 297.893708 -284.301111) (xy 297.851087 -284.276504)
			(xy 297.812966 -284.245379) (xy 297.780331 -284.208542) (xy 297.754028 -284.166946) (xy 297.734737 -284.12167)
			(xy 297.72296 -284.073886) (xy 297.719 -284.024832) (xy 297.380152 -284.024832) (xy 297.379657 -284.049439)
			(xy 297.371762 -284.098016) (xy 297.356178 -284.144697) (xy 297.333307 -284.188274) (xy 297.303742 -284.227618)
			(xy 297.268249 -284.26171) (xy 297.227746 -284.289666) (xy 297.183284 -284.310764) (xy 297.136013 -284.324456)
			(xy 297.087158 -284.330388) (xy 297.037983 -284.328407) (xy 296.989764 -284.318563) (xy 296.943748 -284.301111)
			(xy 296.901127 -284.276504) (xy 296.863006 -284.245379) (xy 296.830371 -284.208542) (xy 296.804068 -284.166946)
			(xy 296.784777 -284.12167) (xy 296.773 -284.073886) (xy 296.76904 -284.024832) (xy 296.430192 -284.024832)
			(xy 296.429697 -284.049439) (xy 296.421802 -284.098016) (xy 296.406218 -284.144697) (xy 296.383347 -284.188274)
			(xy 296.353782 -284.227618) (xy 296.318289 -284.26171) (xy 296.277786 -284.289666) (xy 296.233324 -284.310764)
			(xy 296.186053 -284.324456) (xy 296.137198 -284.330388) (xy 296.088023 -284.328407) (xy 296.039804 -284.318563)
			(xy 295.993788 -284.301111) (xy 295.951167 -284.276504) (xy 295.913046 -284.245379) (xy 295.880411 -284.208542)
			(xy 295.854108 -284.166946) (xy 295.834817 -284.12167) (xy 295.82304 -284.073886) (xy 295.81908 -284.024832)
			(xy 295.480232 -284.024832) (xy 295.479737 -284.049439) (xy 295.471842 -284.098016) (xy 295.456258 -284.144697)
			(xy 295.433387 -284.188274) (xy 295.403822 -284.227618) (xy 295.368329 -284.26171) (xy 295.327826 -284.289666)
			(xy 295.283364 -284.310764) (xy 295.236093 -284.324456) (xy 295.187238 -284.330388) (xy 295.138063 -284.328407)
			(xy 295.089844 -284.318563) (xy 295.043828 -284.301111) (xy 295.001207 -284.276504) (xy 294.963086 -284.245379)
			(xy 294.930451 -284.208542) (xy 294.904148 -284.166946) (xy 294.884857 -284.12167) (xy 294.87308 -284.073886)
			(xy 294.86912 -284.024832) (xy 294.530018 -284.024832) (xy 294.529523 -284.049439) (xy 294.521628 -284.098016)
			(xy 294.506044 -284.144697) (xy 294.483173 -284.188274) (xy 294.453608 -284.227618) (xy 294.418115 -284.26171)
			(xy 294.377612 -284.289666) (xy 294.33315 -284.310764) (xy 294.285879 -284.324456) (xy 294.237024 -284.330388)
			(xy 294.187849 -284.328407) (xy 294.13963 -284.318563) (xy 294.093614 -284.301111) (xy 294.050993 -284.276504)
			(xy 294.012872 -284.245379) (xy 293.980237 -284.208542) (xy 293.953934 -284.166946) (xy 293.934643 -284.12167)
			(xy 293.922866 -284.073886) (xy 293.918906 -284.024832) (xy 293.580058 -284.024832) (xy 293.579563 -284.049439)
			(xy 293.571668 -284.098016) (xy 293.556084 -284.144697) (xy 293.533213 -284.188274) (xy 293.503648 -284.227618)
			(xy 293.468155 -284.26171) (xy 293.427652 -284.289666) (xy 293.38319 -284.310764) (xy 293.335919 -284.324456)
			(xy 293.287064 -284.330388) (xy 293.237889 -284.328407) (xy 293.18967 -284.318563) (xy 293.143654 -284.301111)
			(xy 293.101033 -284.276504) (xy 293.062912 -284.245379) (xy 293.030277 -284.208542) (xy 293.003974 -284.166946)
			(xy 292.984683 -284.12167) (xy 292.972906 -284.073886) (xy 292.968946 -284.024832) (xy 292.630098 -284.024832)
			(xy 292.629603 -284.049439) (xy 292.621708 -284.098016) (xy 292.606124 -284.144697) (xy 292.583253 -284.188274)
			(xy 292.553688 -284.227618) (xy 292.518195 -284.26171) (xy 292.477692 -284.289666) (xy 292.43323 -284.310764)
			(xy 292.385959 -284.324456) (xy 292.337104 -284.330388) (xy 292.287929 -284.328407) (xy 292.23971 -284.318563)
			(xy 292.193694 -284.301111) (xy 292.151073 -284.276504) (xy 292.112952 -284.245379) (xy 292.080317 -284.208542)
			(xy 292.054014 -284.166946) (xy 292.034723 -284.12167) (xy 292.022946 -284.073886) (xy 292.018986 -284.024832)
			(xy 290.730178 -284.024832) (xy 290.729683 -284.049439) (xy 290.721788 -284.098016) (xy 290.706204 -284.144697)
			(xy 290.683333 -284.188274) (xy 290.653768 -284.227618) (xy 290.618275 -284.26171) (xy 290.577772 -284.289666)
			(xy 290.53331 -284.310764) (xy 290.486039 -284.324456) (xy 290.437184 -284.330388) (xy 290.388009 -284.328407)
			(xy 290.33979 -284.318563) (xy 290.293774 -284.301111) (xy 290.251153 -284.276504) (xy 290.213032 -284.245379)
			(xy 290.180397 -284.208542) (xy 290.154094 -284.166946) (xy 290.134803 -284.12167) (xy 290.123026 -284.073886)
			(xy 290.119066 -284.024832) (xy 289.780218 -284.024832) (xy 289.779723 -284.049439) (xy 289.771828 -284.098016)
			(xy 289.756244 -284.144697) (xy 289.733373 -284.188274) (xy 289.703808 -284.227618) (xy 289.668315 -284.26171)
			(xy 289.627812 -284.289666) (xy 289.58335 -284.310764) (xy 289.536079 -284.324456) (xy 289.487224 -284.330388)
			(xy 289.438049 -284.328407) (xy 289.38983 -284.318563) (xy 289.343814 -284.301111) (xy 289.301193 -284.276504)
			(xy 289.263072 -284.245379) (xy 289.230437 -284.208542) (xy 289.204134 -284.166946) (xy 289.184843 -284.12167)
			(xy 289.173066 -284.073886) (xy 289.169106 -284.024832) (xy 288.830004 -284.024832) (xy 288.829509 -284.049439)
			(xy 288.821614 -284.098016) (xy 288.80603 -284.144697) (xy 288.783159 -284.188274) (xy 288.753594 -284.227618)
			(xy 288.718101 -284.26171) (xy 288.677598 -284.289666) (xy 288.633136 -284.310764) (xy 288.585865 -284.324456)
			(xy 288.53701 -284.330388) (xy 288.487835 -284.328407) (xy 288.439616 -284.318563) (xy 288.3936 -284.301111)
			(xy 288.350979 -284.276504) (xy 288.312858 -284.245379) (xy 288.280223 -284.208542) (xy 288.25392 -284.166946)
			(xy 288.234629 -284.12167) (xy 288.222852 -284.073886) (xy 288.218892 -284.024832) (xy 287.880044 -284.024832)
			(xy 287.879549 -284.049439) (xy 287.871654 -284.098016) (xy 287.85607 -284.144697) (xy 287.833199 -284.188274)
			(xy 287.803634 -284.227618) (xy 287.768141 -284.26171) (xy 287.727638 -284.289666) (xy 287.683176 -284.310764)
			(xy 287.635905 -284.324456) (xy 287.58705 -284.330388) (xy 287.537875 -284.328407) (xy 287.489656 -284.318563)
			(xy 287.44364 -284.301111) (xy 287.401019 -284.276504) (xy 287.362898 -284.245379) (xy 287.330263 -284.208542)
			(xy 287.30396 -284.166946) (xy 287.284669 -284.12167) (xy 287.272892 -284.073886) (xy 287.268932 -284.024832)
			(xy 286.930084 -284.024832) (xy 286.929589 -284.049439) (xy 286.921694 -284.098016) (xy 286.90611 -284.144697)
			(xy 286.883239 -284.188274) (xy 286.853674 -284.227618) (xy 286.818181 -284.26171) (xy 286.777678 -284.289666)
			(xy 286.733216 -284.310764) (xy 286.685945 -284.324456) (xy 286.63709 -284.330388) (xy 286.587915 -284.328407)
			(xy 286.539696 -284.318563) (xy 286.49368 -284.301111) (xy 286.451059 -284.276504) (xy 286.412938 -284.245379)
			(xy 286.380303 -284.208542) (xy 286.354 -284.166946) (xy 286.334709 -284.12167) (xy 286.322932 -284.073886)
			(xy 286.318972 -284.024832) (xy 285.980124 -284.024832) (xy 285.979629 -284.049439) (xy 285.971734 -284.098016)
			(xy 285.95615 -284.144697) (xy 285.933279 -284.188274) (xy 285.903714 -284.227618) (xy 285.868221 -284.26171)
			(xy 285.827718 -284.289666) (xy 285.783256 -284.310764) (xy 285.735985 -284.324456) (xy 285.68713 -284.330388)
			(xy 285.637955 -284.328407) (xy 285.589736 -284.318563) (xy 285.54372 -284.301111) (xy 285.501099 -284.276504)
			(xy 285.462978 -284.245379) (xy 285.430343 -284.208542) (xy 285.40404 -284.166946) (xy 285.384749 -284.12167)
			(xy 285.372972 -284.073886) (xy 285.369012 -284.024832) (xy 285.030164 -284.024832) (xy 285.029669 -284.049439)
			(xy 285.021774 -284.098016) (xy 285.00619 -284.144697) (xy 284.983319 -284.188274) (xy 284.953754 -284.227618)
			(xy 284.918261 -284.26171) (xy 284.877758 -284.289666) (xy 284.833296 -284.310764) (xy 284.786025 -284.324456)
			(xy 284.73717 -284.330388) (xy 284.687995 -284.328407) (xy 284.639776 -284.318563) (xy 284.59376 -284.301111)
			(xy 284.551139 -284.276504) (xy 284.513018 -284.245379) (xy 284.480383 -284.208542) (xy 284.45408 -284.166946)
			(xy 284.434789 -284.12167) (xy 284.423012 -284.073886) (xy 284.419052 -284.024832) (xy 284.080204 -284.024832)
			(xy 284.079709 -284.049439) (xy 284.071814 -284.098016) (xy 284.05623 -284.144697) (xy 284.033359 -284.188274)
			(xy 284.003794 -284.227618) (xy 283.968301 -284.26171) (xy 283.927798 -284.289666) (xy 283.883336 -284.310764)
			(xy 283.836065 -284.324456) (xy 283.78721 -284.330388) (xy 283.738035 -284.328407) (xy 283.689816 -284.318563)
			(xy 283.6438 -284.301111) (xy 283.601179 -284.276504) (xy 283.563058 -284.245379) (xy 283.530423 -284.208542)
			(xy 283.50412 -284.166946) (xy 283.484829 -284.12167) (xy 283.473052 -284.073886) (xy 283.469092 -284.024832)
			(xy 283.130244 -284.024832) (xy 283.129749 -284.049439) (xy 283.121854 -284.098016) (xy 283.10627 -284.144697)
			(xy 283.083399 -284.188274) (xy 283.053834 -284.227618) (xy 283.018341 -284.26171) (xy 282.977838 -284.289666)
			(xy 282.933376 -284.310764) (xy 282.886105 -284.324456) (xy 282.83725 -284.330388) (xy 282.788075 -284.328407)
			(xy 282.739856 -284.318563) (xy 282.69384 -284.301111) (xy 282.651219 -284.276504) (xy 282.613098 -284.245379)
			(xy 282.580463 -284.208542) (xy 282.55416 -284.166946) (xy 282.534869 -284.12167) (xy 282.523092 -284.073886)
			(xy 282.519132 -284.024832) (xy 282.18003 -284.024832) (xy 282.179535 -284.049439) (xy 282.17164 -284.098016)
			(xy 282.156056 -284.144697) (xy 282.133185 -284.188274) (xy 282.10362 -284.227618) (xy 282.068127 -284.26171)
			(xy 282.027624 -284.289666) (xy 281.983162 -284.310764) (xy 281.935891 -284.324456) (xy 281.887036 -284.330388)
			(xy 281.837861 -284.328407) (xy 281.789642 -284.318563) (xy 281.743626 -284.301111) (xy 281.701005 -284.276504)
			(xy 281.662884 -284.245379) (xy 281.630249 -284.208542) (xy 281.603946 -284.166946) (xy 281.584655 -284.12167)
			(xy 281.572878 -284.073886) (xy 281.568918 -284.024832) (xy 281.23007 -284.024832) (xy 281.229575 -284.049439)
			(xy 281.22168 -284.098016) (xy 281.206096 -284.144697) (xy 281.183225 -284.188274) (xy 281.15366 -284.227618)
			(xy 281.118167 -284.26171) (xy 281.077664 -284.289666) (xy 281.033202 -284.310764) (xy 280.985931 -284.324456)
			(xy 280.937076 -284.330388) (xy 280.887901 -284.328407) (xy 280.839682 -284.318563) (xy 280.793666 -284.301111)
			(xy 280.751045 -284.276504) (xy 280.712924 -284.245379) (xy 280.680289 -284.208542) (xy 280.653986 -284.166946)
			(xy 280.634695 -284.12167) (xy 280.622918 -284.073886) (xy 280.618958 -284.024832) (xy 280.28011 -284.024832)
			(xy 280.279615 -284.049439) (xy 280.27172 -284.098016) (xy 280.256136 -284.144697) (xy 280.233265 -284.188274)
			(xy 280.2037 -284.227618) (xy 280.168207 -284.26171) (xy 280.127704 -284.289666) (xy 280.083242 -284.310764)
			(xy 280.035971 -284.324456) (xy 279.987116 -284.330388) (xy 279.937941 -284.328407) (xy 279.889722 -284.318563)
			(xy 279.843706 -284.301111) (xy 279.801085 -284.276504) (xy 279.762964 -284.245379) (xy 279.730329 -284.208542)
			(xy 279.704026 -284.166946) (xy 279.684735 -284.12167) (xy 279.672958 -284.073886) (xy 279.668998 -284.024832)
			(xy 279.33015 -284.024832) (xy 279.329655 -284.049439) (xy 279.32176 -284.098016) (xy 279.306176 -284.144697)
			(xy 279.283305 -284.188274) (xy 279.25374 -284.227618) (xy 279.218247 -284.26171) (xy 279.177744 -284.289666)
			(xy 279.133282 -284.310764) (xy 279.086011 -284.324456) (xy 279.037156 -284.330388) (xy 278.987981 -284.328407)
			(xy 278.939762 -284.318563) (xy 278.893746 -284.301111) (xy 278.851125 -284.276504) (xy 278.813004 -284.245379)
			(xy 278.780369 -284.208542) (xy 278.754066 -284.166946) (xy 278.734775 -284.12167) (xy 278.722998 -284.073886)
			(xy 278.719038 -284.024832) (xy 278.38019 -284.024832) (xy 278.379695 -284.049439) (xy 278.3718 -284.098016)
			(xy 278.356216 -284.144697) (xy 278.333345 -284.188274) (xy 278.30378 -284.227618) (xy 278.268287 -284.26171)
			(xy 278.227784 -284.289666) (xy 278.183322 -284.310764) (xy 278.136051 -284.324456) (xy 278.087196 -284.330388)
			(xy 278.038021 -284.328407) (xy 277.989802 -284.318563) (xy 277.943786 -284.301111) (xy 277.901165 -284.276504)
			(xy 277.863044 -284.245379) (xy 277.830409 -284.208542) (xy 277.804106 -284.166946) (xy 277.784815 -284.12167)
			(xy 277.773038 -284.073886) (xy 277.769078 -284.024832) (xy 277.43023 -284.024832) (xy 277.429735 -284.049439)
			(xy 277.42184 -284.098016) (xy 277.406256 -284.144697) (xy 277.383385 -284.188274) (xy 277.35382 -284.227618)
			(xy 277.318327 -284.26171) (xy 277.277824 -284.289666) (xy 277.233362 -284.310764) (xy 277.186091 -284.324456)
			(xy 277.137236 -284.330388) (xy 277.088061 -284.328407) (xy 277.039842 -284.318563) (xy 276.993826 -284.301111)
			(xy 276.951205 -284.276504) (xy 276.913084 -284.245379) (xy 276.880449 -284.208542) (xy 276.854146 -284.166946)
			(xy 276.834855 -284.12167) (xy 276.823078 -284.073886) (xy 276.819118 -284.024832) (xy 276.6314 -284.024832)
			(xy 276.6314 -284.499812) (xy 305.793914 -284.499812) (xy 305.797874 -284.450758) (xy 305.809651 -284.402974)
			(xy 305.828942 -284.357698) (xy 305.855245 -284.316102) (xy 305.88788 -284.279265) (xy 305.926001 -284.24814)
			(xy 305.968622 -284.223533) (xy 306.014638 -284.206081) (xy 306.062857 -284.196237) (xy 306.112032 -284.194256)
			(xy 306.160887 -284.200188) (xy 306.208158 -284.21388) (xy 306.25262 -284.234978) (xy 306.293123 -284.262934)
			(xy 306.328616 -284.297026) (xy 306.358181 -284.33637) (xy 306.381052 -284.379947) (xy 306.396636 -284.426628)
			(xy 306.404531 -284.475205) (xy 306.405026 -284.499812) (xy 306.743874 -284.499812) (xy 306.747834 -284.450758)
			(xy 306.759611 -284.402974) (xy 306.778902 -284.357698) (xy 306.805205 -284.316102) (xy 306.83784 -284.279265)
			(xy 306.875961 -284.24814) (xy 306.918582 -284.223533) (xy 306.964598 -284.206081) (xy 307.012817 -284.196237)
			(xy 307.061992 -284.194256) (xy 307.110847 -284.200188) (xy 307.158118 -284.21388) (xy 307.20258 -284.234978)
			(xy 307.243083 -284.262934) (xy 307.278576 -284.297026) (xy 307.308141 -284.33637) (xy 307.331012 -284.379947)
			(xy 307.346596 -284.426628) (xy 307.354491 -284.475205) (xy 307.354986 -284.499812) (xy 307.694088 -284.499812)
			(xy 307.698048 -284.450758) (xy 307.709825 -284.402974) (xy 307.729116 -284.357698) (xy 307.755419 -284.316102)
			(xy 307.788054 -284.279265) (xy 307.826175 -284.24814) (xy 307.868796 -284.223533) (xy 307.914812 -284.206081)
			(xy 307.963031 -284.196237) (xy 308.012206 -284.194256) (xy 308.061061 -284.200188) (xy 308.108332 -284.21388)
			(xy 308.152794 -284.234978) (xy 308.193297 -284.262934) (xy 308.22879 -284.297026) (xy 308.258355 -284.33637)
			(xy 308.281226 -284.379947) (xy 308.29681 -284.426628) (xy 308.304705 -284.475205) (xy 308.3052 -284.499812)
			(xy 308.304705 -284.524419) (xy 308.304526 -284.52552) (xy 308.623204 -284.52552) (xy 308.623204 -284.474104)
			(xy 308.631247 -284.423322) (xy 308.647135 -284.374423) (xy 308.670478 -284.328611) (xy 308.700699 -284.287015)
			(xy 308.737055 -284.250659) (xy 308.778651 -284.220438) (xy 308.824463 -284.197095) (xy 308.873362 -284.181207)
			(xy 308.924144 -284.173164) (xy 308.97556 -284.173164) (xy 309.026342 -284.181207) (xy 309.075241 -284.197095)
			(xy 309.121053 -284.220438) (xy 309.162649 -284.250659) (xy 309.199005 -284.287015) (xy 309.229226 -284.328611)
			(xy 309.252569 -284.374423) (xy 309.268457 -284.423322) (xy 309.2765 -284.474104) (xy 309.277004 -284.499812)
			(xy 309.2765 -284.52552) (xy 309.573164 -284.52552) (xy 309.573164 -284.474104) (xy 309.581207 -284.423322)
			(xy 309.597095 -284.374423) (xy 309.620438 -284.328611) (xy 309.650659 -284.287015) (xy 309.687015 -284.250659)
			(xy 309.728611 -284.220438) (xy 309.774423 -284.197095) (xy 309.823322 -284.181207) (xy 309.874104 -284.173164)
			(xy 309.92552 -284.173164) (xy 309.976302 -284.181207) (xy 310.025201 -284.197095) (xy 310.071013 -284.220438)
			(xy 310.112609 -284.250659) (xy 310.148965 -284.287015) (xy 310.179186 -284.328611) (xy 310.202529 -284.374423)
			(xy 310.218417 -284.423322) (xy 310.22646 -284.474104) (xy 310.226964 -284.499812) (xy 310.543968 -284.499812)
			(xy 310.547928 -284.450758) (xy 310.559705 -284.402974) (xy 310.578996 -284.357698) (xy 310.605299 -284.316102)
			(xy 310.637934 -284.279265) (xy 310.676055 -284.24814) (xy 310.718676 -284.223533) (xy 310.764692 -284.206081)
			(xy 310.812911 -284.196237) (xy 310.862086 -284.194256) (xy 310.910941 -284.200188) (xy 310.958212 -284.21388)
			(xy 311.002674 -284.234978) (xy 311.043177 -284.262934) (xy 311.07867 -284.297026) (xy 311.108235 -284.33637)
			(xy 311.131106 -284.379947) (xy 311.14669 -284.426628) (xy 311.154585 -284.475205) (xy 311.15508 -284.499812)
			(xy 311.154585 -284.524419) (xy 311.154406 -284.52552) (xy 311.473084 -284.52552) (xy 311.473084 -284.474104)
			(xy 311.481127 -284.423322) (xy 311.497015 -284.374423) (xy 311.520358 -284.328611) (xy 311.550579 -284.287015)
			(xy 311.586935 -284.250659) (xy 311.628531 -284.220438) (xy 311.674343 -284.197095) (xy 311.723242 -284.181207)
			(xy 311.774024 -284.173164) (xy 311.82544 -284.173164) (xy 311.876222 -284.181207) (xy 311.925121 -284.197095)
			(xy 311.970933 -284.220438) (xy 312.012529 -284.250659) (xy 312.048885 -284.287015) (xy 312.079106 -284.328611)
			(xy 312.102449 -284.374423) (xy 312.118337 -284.423322) (xy 312.12638 -284.474104) (xy 312.126884 -284.499812)
			(xy 312.12638 -284.52552) (xy 312.423044 -284.52552) (xy 312.423044 -284.474104) (xy 312.431087 -284.423322)
			(xy 312.446975 -284.374423) (xy 312.470318 -284.328611) (xy 312.500539 -284.287015) (xy 312.536895 -284.250659)
			(xy 312.578491 -284.220438) (xy 312.624303 -284.197095) (xy 312.673202 -284.181207) (xy 312.723984 -284.173164)
			(xy 312.7754 -284.173164) (xy 312.826182 -284.181207) (xy 312.875081 -284.197095) (xy 312.920893 -284.220438)
			(xy 312.962489 -284.250659) (xy 312.998845 -284.287015) (xy 313.029066 -284.328611) (xy 313.052409 -284.374423)
			(xy 313.068297 -284.423322) (xy 313.07634 -284.474104) (xy 313.076844 -284.499812) (xy 313.394102 -284.499812)
			(xy 313.398062 -284.450758) (xy 313.409839 -284.402974) (xy 313.42913 -284.357698) (xy 313.455433 -284.316102)
			(xy 313.488068 -284.279265) (xy 313.526189 -284.24814) (xy 313.56881 -284.223533) (xy 313.614826 -284.206081)
			(xy 313.663045 -284.196237) (xy 313.71222 -284.194256) (xy 313.761075 -284.200188) (xy 313.808346 -284.21388)
			(xy 313.852808 -284.234978) (xy 313.893311 -284.262934) (xy 313.928804 -284.297026) (xy 313.958369 -284.33637)
			(xy 313.98124 -284.379947) (xy 313.996824 -284.426628) (xy 314.004719 -284.475205) (xy 314.005214 -284.499812)
			(xy 314.344062 -284.499812) (xy 314.348022 -284.450758) (xy 314.359799 -284.402974) (xy 314.37909 -284.357698)
			(xy 314.405393 -284.316102) (xy 314.438028 -284.279265) (xy 314.476149 -284.24814) (xy 314.51877 -284.223533)
			(xy 314.564786 -284.206081) (xy 314.613005 -284.196237) (xy 314.66218 -284.194256) (xy 314.711035 -284.200188)
			(xy 314.758306 -284.21388) (xy 314.802768 -284.234978) (xy 314.843271 -284.262934) (xy 314.878764 -284.297026)
			(xy 314.908329 -284.33637) (xy 314.9312 -284.379947) (xy 314.946784 -284.426628) (xy 314.954679 -284.475205)
			(xy 314.955174 -284.499812) (xy 314.954679 -284.524419) (xy 314.946784 -284.572996) (xy 314.9312 -284.619677)
			(xy 314.908329 -284.663254) (xy 314.878764 -284.702598) (xy 314.843271 -284.73669) (xy 314.802768 -284.764646)
			(xy 314.758306 -284.785744) (xy 314.711035 -284.799436) (xy 314.66218 -284.805368) (xy 314.613005 -284.803387)
			(xy 314.564786 -284.793543) (xy 314.51877 -284.776091) (xy 314.476149 -284.751484) (xy 314.438028 -284.720359)
			(xy 314.405393 -284.683522) (xy 314.37909 -284.641926) (xy 314.359799 -284.59665) (xy 314.348022 -284.548866)
			(xy 314.344062 -284.499812) (xy 314.005214 -284.499812) (xy 314.004719 -284.524419) (xy 313.996824 -284.572996)
			(xy 313.98124 -284.619677) (xy 313.958369 -284.663254) (xy 313.928804 -284.702598) (xy 313.893311 -284.73669)
			(xy 313.852808 -284.764646) (xy 313.808346 -284.785744) (xy 313.761075 -284.799436) (xy 313.71222 -284.805368)
			(xy 313.663045 -284.803387) (xy 313.614826 -284.793543) (xy 313.56881 -284.776091) (xy 313.526189 -284.751484)
			(xy 313.488068 -284.720359) (xy 313.455433 -284.683522) (xy 313.42913 -284.641926) (xy 313.409839 -284.59665)
			(xy 313.398062 -284.548866) (xy 313.394102 -284.499812) (xy 313.076844 -284.499812) (xy 313.07634 -284.52552)
			(xy 313.068297 -284.576302) (xy 313.052409 -284.625201) (xy 313.029066 -284.671013) (xy 312.998845 -284.712609)
			(xy 312.962489 -284.748965) (xy 312.920893 -284.779186) (xy 312.875081 -284.802529) (xy 312.826182 -284.818417)
			(xy 312.7754 -284.82646) (xy 312.723984 -284.82646) (xy 312.673202 -284.818417) (xy 312.624303 -284.802529)
			(xy 312.578491 -284.779186) (xy 312.536895 -284.748965) (xy 312.500539 -284.712609) (xy 312.470318 -284.671013)
			(xy 312.446975 -284.625201) (xy 312.431087 -284.576302) (xy 312.423044 -284.52552) (xy 312.12638 -284.52552)
			(xy 312.118337 -284.576302) (xy 312.102449 -284.625201) (xy 312.079106 -284.671013) (xy 312.048885 -284.712609)
			(xy 312.012529 -284.748965) (xy 311.970933 -284.779186) (xy 311.925121 -284.802529) (xy 311.876222 -284.818417)
			(xy 311.82544 -284.82646) (xy 311.774024 -284.82646) (xy 311.723242 -284.818417) (xy 311.674343 -284.802529)
			(xy 311.628531 -284.779186) (xy 311.586935 -284.748965) (xy 311.550579 -284.712609) (xy 311.520358 -284.671013)
			(xy 311.497015 -284.625201) (xy 311.481127 -284.576302) (xy 311.473084 -284.52552) (xy 311.154406 -284.52552)
			(xy 311.14669 -284.572996) (xy 311.131106 -284.619677) (xy 311.108235 -284.663254) (xy 311.07867 -284.702598)
			(xy 311.043177 -284.73669) (xy 311.002674 -284.764646) (xy 310.958212 -284.785744) (xy 310.910941 -284.799436)
			(xy 310.862086 -284.805368) (xy 310.812911 -284.803387) (xy 310.764692 -284.793543) (xy 310.718676 -284.776091)
			(xy 310.676055 -284.751484) (xy 310.637934 -284.720359) (xy 310.605299 -284.683522) (xy 310.578996 -284.641926)
			(xy 310.559705 -284.59665) (xy 310.547928 -284.548866) (xy 310.543968 -284.499812) (xy 310.226964 -284.499812)
			(xy 310.22646 -284.52552) (xy 310.218417 -284.576302) (xy 310.202529 -284.625201) (xy 310.179186 -284.671013)
			(xy 310.148965 -284.712609) (xy 310.112609 -284.748965) (xy 310.071013 -284.779186) (xy 310.025201 -284.802529)
			(xy 309.976302 -284.818417) (xy 309.92552 -284.82646) (xy 309.874104 -284.82646) (xy 309.823322 -284.818417)
			(xy 309.774423 -284.802529) (xy 309.728611 -284.779186) (xy 309.687015 -284.748965) (xy 309.650659 -284.712609)
			(xy 309.620438 -284.671013) (xy 309.597095 -284.625201) (xy 309.581207 -284.576302) (xy 309.573164 -284.52552)
			(xy 309.2765 -284.52552) (xy 309.268457 -284.576302) (xy 309.252569 -284.625201) (xy 309.229226 -284.671013)
			(xy 309.199005 -284.712609) (xy 309.162649 -284.748965) (xy 309.121053 -284.779186) (xy 309.075241 -284.802529)
			(xy 309.026342 -284.818417) (xy 308.97556 -284.82646) (xy 308.924144 -284.82646) (xy 308.873362 -284.818417)
			(xy 308.824463 -284.802529) (xy 308.778651 -284.779186) (xy 308.737055 -284.748965) (xy 308.700699 -284.712609)
			(xy 308.670478 -284.671013) (xy 308.647135 -284.625201) (xy 308.631247 -284.576302) (xy 308.623204 -284.52552)
			(xy 308.304526 -284.52552) (xy 308.29681 -284.572996) (xy 308.281226 -284.619677) (xy 308.258355 -284.663254)
			(xy 308.22879 -284.702598) (xy 308.193297 -284.73669) (xy 308.152794 -284.764646) (xy 308.108332 -284.785744)
			(xy 308.061061 -284.799436) (xy 308.012206 -284.805368) (xy 307.963031 -284.803387) (xy 307.914812 -284.793543)
			(xy 307.868796 -284.776091) (xy 307.826175 -284.751484) (xy 307.788054 -284.720359) (xy 307.755419 -284.683522)
			(xy 307.729116 -284.641926) (xy 307.709825 -284.59665) (xy 307.698048 -284.548866) (xy 307.694088 -284.499812)
			(xy 307.354986 -284.499812) (xy 307.354491 -284.524419) (xy 307.346596 -284.572996) (xy 307.331012 -284.619677)
			(xy 307.308141 -284.663254) (xy 307.278576 -284.702598) (xy 307.243083 -284.73669) (xy 307.20258 -284.764646)
			(xy 307.158118 -284.785744) (xy 307.110847 -284.799436) (xy 307.061992 -284.805368) (xy 307.012817 -284.803387)
			(xy 306.964598 -284.793543) (xy 306.918582 -284.776091) (xy 306.875961 -284.751484) (xy 306.83784 -284.720359)
			(xy 306.805205 -284.683522) (xy 306.778902 -284.641926) (xy 306.759611 -284.59665) (xy 306.747834 -284.548866)
			(xy 306.743874 -284.499812) (xy 306.405026 -284.499812) (xy 306.404531 -284.524419) (xy 306.396636 -284.572996)
			(xy 306.381052 -284.619677) (xy 306.358181 -284.663254) (xy 306.328616 -284.702598) (xy 306.293123 -284.73669)
			(xy 306.25262 -284.764646) (xy 306.208158 -284.785744) (xy 306.160887 -284.799436) (xy 306.112032 -284.805368)
			(xy 306.062857 -284.803387) (xy 306.014638 -284.793543) (xy 305.968622 -284.776091) (xy 305.926001 -284.751484)
			(xy 305.88788 -284.720359) (xy 305.855245 -284.683522) (xy 305.828942 -284.641926) (xy 305.809651 -284.59665)
			(xy 305.797874 -284.548866) (xy 305.793914 -284.499812) (xy 276.6314 -284.499812) (xy 276.6314 -284.974792)
			(xy 276.819118 -284.974792) (xy 276.823078 -284.925738) (xy 276.834855 -284.877954) (xy 276.854146 -284.832678)
			(xy 276.880449 -284.791082) (xy 276.913084 -284.754245) (xy 276.951205 -284.72312) (xy 276.993826 -284.698513)
			(xy 277.039842 -284.681061) (xy 277.088061 -284.671217) (xy 277.137236 -284.669236) (xy 277.186091 -284.675168)
			(xy 277.233362 -284.68886) (xy 277.277824 -284.709958) (xy 277.318327 -284.737914) (xy 277.35382 -284.772006)
			(xy 277.383385 -284.81135) (xy 277.406256 -284.854927) (xy 277.42184 -284.901608) (xy 277.429735 -284.950185)
			(xy 277.43023 -284.974792) (xy 277.769078 -284.974792) (xy 277.773038 -284.925738) (xy 277.784815 -284.877954)
			(xy 277.804106 -284.832678) (xy 277.830409 -284.791082) (xy 277.863044 -284.754245) (xy 277.901165 -284.72312)
			(xy 277.943786 -284.698513) (xy 277.989802 -284.681061) (xy 278.038021 -284.671217) (xy 278.087196 -284.669236)
			(xy 278.136051 -284.675168) (xy 278.183322 -284.68886) (xy 278.227784 -284.709958) (xy 278.268287 -284.737914)
			(xy 278.30378 -284.772006) (xy 278.333345 -284.81135) (xy 278.356216 -284.854927) (xy 278.3718 -284.901608)
			(xy 278.379695 -284.950185) (xy 278.38019 -284.974792) (xy 278.719038 -284.974792) (xy 278.722998 -284.925738)
			(xy 278.734775 -284.877954) (xy 278.754066 -284.832678) (xy 278.780369 -284.791082) (xy 278.813004 -284.754245)
			(xy 278.851125 -284.72312) (xy 278.893746 -284.698513) (xy 278.939762 -284.681061) (xy 278.987981 -284.671217)
			(xy 279.037156 -284.669236) (xy 279.086011 -284.675168) (xy 279.133282 -284.68886) (xy 279.177744 -284.709958)
			(xy 279.218247 -284.737914) (xy 279.25374 -284.772006) (xy 279.283305 -284.81135) (xy 279.306176 -284.854927)
			(xy 279.32176 -284.901608) (xy 279.329655 -284.950185) (xy 279.33015 -284.974792) (xy 279.668998 -284.974792)
			(xy 279.672958 -284.925738) (xy 279.684735 -284.877954) (xy 279.704026 -284.832678) (xy 279.730329 -284.791082)
			(xy 279.762964 -284.754245) (xy 279.801085 -284.72312) (xy 279.843706 -284.698513) (xy 279.889722 -284.681061)
			(xy 279.937941 -284.671217) (xy 279.987116 -284.669236) (xy 280.035971 -284.675168) (xy 280.083242 -284.68886)
			(xy 280.127704 -284.709958) (xy 280.168207 -284.737914) (xy 280.2037 -284.772006) (xy 280.233265 -284.81135)
			(xy 280.256136 -284.854927) (xy 280.27172 -284.901608) (xy 280.279615 -284.950185) (xy 280.28011 -284.974792)
			(xy 280.618958 -284.974792) (xy 280.622918 -284.925738) (xy 280.634695 -284.877954) (xy 280.653986 -284.832678)
			(xy 280.680289 -284.791082) (xy 280.712924 -284.754245) (xy 280.751045 -284.72312) (xy 280.793666 -284.698513)
			(xy 280.839682 -284.681061) (xy 280.887901 -284.671217) (xy 280.937076 -284.669236) (xy 280.985931 -284.675168)
			(xy 281.033202 -284.68886) (xy 281.077664 -284.709958) (xy 281.118167 -284.737914) (xy 281.15366 -284.772006)
			(xy 281.183225 -284.81135) (xy 281.206096 -284.854927) (xy 281.22168 -284.901608) (xy 281.229575 -284.950185)
			(xy 281.23007 -284.974792) (xy 281.568918 -284.974792) (xy 281.572878 -284.925738) (xy 281.584655 -284.877954)
			(xy 281.603946 -284.832678) (xy 281.630249 -284.791082) (xy 281.662884 -284.754245) (xy 281.701005 -284.72312)
			(xy 281.743626 -284.698513) (xy 281.789642 -284.681061) (xy 281.837861 -284.671217) (xy 281.887036 -284.669236)
			(xy 281.935891 -284.675168) (xy 281.983162 -284.68886) (xy 282.027624 -284.709958) (xy 282.068127 -284.737914)
			(xy 282.10362 -284.772006) (xy 282.133185 -284.81135) (xy 282.156056 -284.854927) (xy 282.17164 -284.901608)
			(xy 282.179535 -284.950185) (xy 282.18003 -284.974792) (xy 282.519132 -284.974792) (xy 282.523092 -284.925738)
			(xy 282.534869 -284.877954) (xy 282.55416 -284.832678) (xy 282.580463 -284.791082) (xy 282.613098 -284.754245)
			(xy 282.651219 -284.72312) (xy 282.69384 -284.698513) (xy 282.739856 -284.681061) (xy 282.788075 -284.671217)
			(xy 282.83725 -284.669236) (xy 282.886105 -284.675168) (xy 282.933376 -284.68886) (xy 282.977838 -284.709958)
			(xy 283.018341 -284.737914) (xy 283.053834 -284.772006) (xy 283.083399 -284.81135) (xy 283.10627 -284.854927)
			(xy 283.121854 -284.901608) (xy 283.129749 -284.950185) (xy 283.130244 -284.974792) (xy 283.469092 -284.974792)
			(xy 283.473052 -284.925738) (xy 283.484829 -284.877954) (xy 283.50412 -284.832678) (xy 283.530423 -284.791082)
			(xy 283.563058 -284.754245) (xy 283.601179 -284.72312) (xy 283.6438 -284.698513) (xy 283.689816 -284.681061)
			(xy 283.738035 -284.671217) (xy 283.78721 -284.669236) (xy 283.836065 -284.675168) (xy 283.883336 -284.68886)
			(xy 283.927798 -284.709958) (xy 283.968301 -284.737914) (xy 284.003794 -284.772006) (xy 284.033359 -284.81135)
			(xy 284.05623 -284.854927) (xy 284.071814 -284.901608) (xy 284.079709 -284.950185) (xy 284.080204 -284.974792)
			(xy 284.419052 -284.974792) (xy 284.423012 -284.925738) (xy 284.434789 -284.877954) (xy 284.45408 -284.832678)
			(xy 284.480383 -284.791082) (xy 284.513018 -284.754245) (xy 284.551139 -284.72312) (xy 284.59376 -284.698513)
			(xy 284.639776 -284.681061) (xy 284.687995 -284.671217) (xy 284.73717 -284.669236) (xy 284.786025 -284.675168)
			(xy 284.833296 -284.68886) (xy 284.877758 -284.709958) (xy 284.918261 -284.737914) (xy 284.953754 -284.772006)
			(xy 284.983319 -284.81135) (xy 285.00619 -284.854927) (xy 285.021774 -284.901608) (xy 285.029669 -284.950185)
			(xy 285.030164 -284.974792) (xy 285.369012 -284.974792) (xy 285.372972 -284.925738) (xy 285.384749 -284.877954)
			(xy 285.40404 -284.832678) (xy 285.430343 -284.791082) (xy 285.462978 -284.754245) (xy 285.501099 -284.72312)
			(xy 285.54372 -284.698513) (xy 285.589736 -284.681061) (xy 285.637955 -284.671217) (xy 285.68713 -284.669236)
			(xy 285.735985 -284.675168) (xy 285.783256 -284.68886) (xy 285.827718 -284.709958) (xy 285.868221 -284.737914)
			(xy 285.903714 -284.772006) (xy 285.933279 -284.81135) (xy 285.95615 -284.854927) (xy 285.971734 -284.901608)
			(xy 285.979629 -284.950185) (xy 285.980124 -284.974792) (xy 286.318972 -284.974792) (xy 286.322932 -284.925738)
			(xy 286.334709 -284.877954) (xy 286.354 -284.832678) (xy 286.380303 -284.791082) (xy 286.412938 -284.754245)
			(xy 286.451059 -284.72312) (xy 286.49368 -284.698513) (xy 286.539696 -284.681061) (xy 286.587915 -284.671217)
			(xy 286.63709 -284.669236) (xy 286.685945 -284.675168) (xy 286.733216 -284.68886) (xy 286.777678 -284.709958)
			(xy 286.818181 -284.737914) (xy 286.853674 -284.772006) (xy 286.883239 -284.81135) (xy 286.90611 -284.854927)
			(xy 286.921694 -284.901608) (xy 286.929589 -284.950185) (xy 286.930084 -284.974792) (xy 287.268932 -284.974792)
			(xy 287.272892 -284.925738) (xy 287.284669 -284.877954) (xy 287.30396 -284.832678) (xy 287.330263 -284.791082)
			(xy 287.362898 -284.754245) (xy 287.401019 -284.72312) (xy 287.44364 -284.698513) (xy 287.489656 -284.681061)
			(xy 287.537875 -284.671217) (xy 287.58705 -284.669236) (xy 287.635905 -284.675168) (xy 287.683176 -284.68886)
			(xy 287.727638 -284.709958) (xy 287.768141 -284.737914) (xy 287.803634 -284.772006) (xy 287.833199 -284.81135)
			(xy 287.85607 -284.854927) (xy 287.871654 -284.901608) (xy 287.879549 -284.950185) (xy 287.880044 -284.974792)
			(xy 288.218892 -284.974792) (xy 288.222852 -284.925738) (xy 288.234629 -284.877954) (xy 288.25392 -284.832678)
			(xy 288.280223 -284.791082) (xy 288.312858 -284.754245) (xy 288.350979 -284.72312) (xy 288.3936 -284.698513)
			(xy 288.439616 -284.681061) (xy 288.487835 -284.671217) (xy 288.53701 -284.669236) (xy 288.585865 -284.675168)
			(xy 288.633136 -284.68886) (xy 288.677598 -284.709958) (xy 288.718101 -284.737914) (xy 288.753594 -284.772006)
			(xy 288.783159 -284.81135) (xy 288.80603 -284.854927) (xy 288.821614 -284.901608) (xy 288.829509 -284.950185)
			(xy 288.830004 -284.974792) (xy 289.169106 -284.974792) (xy 289.173066 -284.925738) (xy 289.184843 -284.877954)
			(xy 289.204134 -284.832678) (xy 289.230437 -284.791082) (xy 289.263072 -284.754245) (xy 289.301193 -284.72312)
			(xy 289.343814 -284.698513) (xy 289.38983 -284.681061) (xy 289.438049 -284.671217) (xy 289.487224 -284.669236)
			(xy 289.536079 -284.675168) (xy 289.58335 -284.68886) (xy 289.627812 -284.709958) (xy 289.668315 -284.737914)
			(xy 289.703808 -284.772006) (xy 289.733373 -284.81135) (xy 289.756244 -284.854927) (xy 289.771828 -284.901608)
			(xy 289.779723 -284.950185) (xy 289.780218 -284.974792) (xy 290.119066 -284.974792) (xy 290.123026 -284.925738)
			(xy 290.134803 -284.877954) (xy 290.154094 -284.832678) (xy 290.180397 -284.791082) (xy 290.213032 -284.754245)
			(xy 290.251153 -284.72312) (xy 290.293774 -284.698513) (xy 290.33979 -284.681061) (xy 290.388009 -284.671217)
			(xy 290.437184 -284.669236) (xy 290.486039 -284.675168) (xy 290.53331 -284.68886) (xy 290.577772 -284.709958)
			(xy 290.618275 -284.737914) (xy 290.653768 -284.772006) (xy 290.683333 -284.81135) (xy 290.706204 -284.854927)
			(xy 290.721788 -284.901608) (xy 290.729683 -284.950185) (xy 290.730178 -284.974792) (xy 292.018986 -284.974792)
			(xy 292.022946 -284.925738) (xy 292.034723 -284.877954) (xy 292.054014 -284.832678) (xy 292.080317 -284.791082)
			(xy 292.112952 -284.754245) (xy 292.151073 -284.72312) (xy 292.193694 -284.698513) (xy 292.23971 -284.681061)
			(xy 292.287929 -284.671217) (xy 292.337104 -284.669236) (xy 292.385959 -284.675168) (xy 292.43323 -284.68886)
			(xy 292.477692 -284.709958) (xy 292.518195 -284.737914) (xy 292.553688 -284.772006) (xy 292.583253 -284.81135)
			(xy 292.606124 -284.854927) (xy 292.621708 -284.901608) (xy 292.629603 -284.950185) (xy 292.630098 -284.974792)
			(xy 292.968946 -284.974792) (xy 292.972906 -284.925738) (xy 292.984683 -284.877954) (xy 293.003974 -284.832678)
			(xy 293.030277 -284.791082) (xy 293.062912 -284.754245) (xy 293.101033 -284.72312) (xy 293.143654 -284.698513)
			(xy 293.18967 -284.681061) (xy 293.237889 -284.671217) (xy 293.287064 -284.669236) (xy 293.335919 -284.675168)
			(xy 293.38319 -284.68886) (xy 293.427652 -284.709958) (xy 293.468155 -284.737914) (xy 293.503648 -284.772006)
			(xy 293.533213 -284.81135) (xy 293.556084 -284.854927) (xy 293.571668 -284.901608) (xy 293.579563 -284.950185)
			(xy 293.580058 -284.974792) (xy 293.918906 -284.974792) (xy 293.922866 -284.925738) (xy 293.934643 -284.877954)
			(xy 293.953934 -284.832678) (xy 293.980237 -284.791082) (xy 294.012872 -284.754245) (xy 294.050993 -284.72312)
			(xy 294.093614 -284.698513) (xy 294.13963 -284.681061) (xy 294.187849 -284.671217) (xy 294.237024 -284.669236)
			(xy 294.285879 -284.675168) (xy 294.33315 -284.68886) (xy 294.377612 -284.709958) (xy 294.418115 -284.737914)
			(xy 294.453608 -284.772006) (xy 294.483173 -284.81135) (xy 294.506044 -284.854927) (xy 294.521628 -284.901608)
			(xy 294.529523 -284.950185) (xy 294.530018 -284.974792) (xy 294.86912 -284.974792) (xy 294.87308 -284.925738)
			(xy 294.884857 -284.877954) (xy 294.904148 -284.832678) (xy 294.930451 -284.791082) (xy 294.963086 -284.754245)
			(xy 295.001207 -284.72312) (xy 295.043828 -284.698513) (xy 295.089844 -284.681061) (xy 295.138063 -284.671217)
			(xy 295.187238 -284.669236) (xy 295.236093 -284.675168) (xy 295.283364 -284.68886) (xy 295.327826 -284.709958)
			(xy 295.368329 -284.737914) (xy 295.403822 -284.772006) (xy 295.433387 -284.81135) (xy 295.456258 -284.854927)
			(xy 295.471842 -284.901608) (xy 295.479737 -284.950185) (xy 295.480232 -284.974792) (xy 295.81908 -284.974792)
			(xy 295.82304 -284.925738) (xy 295.834817 -284.877954) (xy 295.854108 -284.832678) (xy 295.880411 -284.791082)
			(xy 295.913046 -284.754245) (xy 295.951167 -284.72312) (xy 295.993788 -284.698513) (xy 296.039804 -284.681061)
			(xy 296.088023 -284.671217) (xy 296.137198 -284.669236) (xy 296.186053 -284.675168) (xy 296.233324 -284.68886)
			(xy 296.277786 -284.709958) (xy 296.318289 -284.737914) (xy 296.353782 -284.772006) (xy 296.383347 -284.81135)
			(xy 296.406218 -284.854927) (xy 296.421802 -284.901608) (xy 296.429697 -284.950185) (xy 296.430192 -284.974792)
			(xy 296.76904 -284.974792) (xy 296.773 -284.925738) (xy 296.784777 -284.877954) (xy 296.804068 -284.832678)
			(xy 296.830371 -284.791082) (xy 296.863006 -284.754245) (xy 296.901127 -284.72312) (xy 296.943748 -284.698513)
			(xy 296.989764 -284.681061) (xy 297.037983 -284.671217) (xy 297.087158 -284.669236) (xy 297.136013 -284.675168)
			(xy 297.183284 -284.68886) (xy 297.227746 -284.709958) (xy 297.268249 -284.737914) (xy 297.303742 -284.772006)
			(xy 297.333307 -284.81135) (xy 297.356178 -284.854927) (xy 297.371762 -284.901608) (xy 297.379657 -284.950185)
			(xy 297.380152 -284.974792) (xy 297.719 -284.974792) (xy 297.72296 -284.925738) (xy 297.734737 -284.877954)
			(xy 297.754028 -284.832678) (xy 297.780331 -284.791082) (xy 297.812966 -284.754245) (xy 297.851087 -284.72312)
			(xy 297.893708 -284.698513) (xy 297.939724 -284.681061) (xy 297.987943 -284.671217) (xy 298.037118 -284.669236)
			(xy 298.085973 -284.675168) (xy 298.133244 -284.68886) (xy 298.177706 -284.709958) (xy 298.218209 -284.737914)
			(xy 298.253702 -284.772006) (xy 298.283267 -284.81135) (xy 298.306138 -284.854927) (xy 298.321722 -284.901608)
			(xy 298.329617 -284.950185) (xy 298.330112 -284.974792) (xy 298.66896 -284.974792) (xy 298.67292 -284.925738)
			(xy 298.684697 -284.877954) (xy 298.703988 -284.832678) (xy 298.730291 -284.791082) (xy 298.762926 -284.754245)
			(xy 298.801047 -284.72312) (xy 298.843668 -284.698513) (xy 298.889684 -284.681061) (xy 298.937903 -284.671217)
			(xy 298.987078 -284.669236) (xy 299.035933 -284.675168) (xy 299.083204 -284.68886) (xy 299.127666 -284.709958)
			(xy 299.168169 -284.737914) (xy 299.203662 -284.772006) (xy 299.233227 -284.81135) (xy 299.256098 -284.854927)
			(xy 299.271682 -284.901608) (xy 299.279577 -284.950185) (xy 299.280072 -284.974792) (xy 299.61892 -284.974792)
			(xy 299.62288 -284.925738) (xy 299.634657 -284.877954) (xy 299.653948 -284.832678) (xy 299.680251 -284.791082)
			(xy 299.712886 -284.754245) (xy 299.751007 -284.72312) (xy 299.793628 -284.698513) (xy 299.839644 -284.681061)
			(xy 299.887863 -284.671217) (xy 299.937038 -284.669236) (xy 299.985893 -284.675168) (xy 300.033164 -284.68886)
			(xy 300.077626 -284.709958) (xy 300.118129 -284.737914) (xy 300.153622 -284.772006) (xy 300.183187 -284.81135)
			(xy 300.206058 -284.854927) (xy 300.221642 -284.901608) (xy 300.229537 -284.950185) (xy 300.230032 -284.974792)
			(xy 300.56888 -284.974792) (xy 300.57284 -284.925738) (xy 300.584617 -284.877954) (xy 300.603908 -284.832678)
			(xy 300.630211 -284.791082) (xy 300.662846 -284.754245) (xy 300.700967 -284.72312) (xy 300.743588 -284.698513)
			(xy 300.789604 -284.681061) (xy 300.837823 -284.671217) (xy 300.886998 -284.669236) (xy 300.935853 -284.675168)
			(xy 300.983124 -284.68886) (xy 301.027586 -284.709958) (xy 301.068089 -284.737914) (xy 301.103582 -284.772006)
			(xy 301.133147 -284.81135) (xy 301.156018 -284.854927) (xy 301.171602 -284.901608) (xy 301.179497 -284.950185)
			(xy 301.179992 -284.974792) (xy 301.519094 -284.974792) (xy 301.523054 -284.925738) (xy 301.534831 -284.877954)
			(xy 301.554122 -284.832678) (xy 301.580425 -284.791082) (xy 301.61306 -284.754245) (xy 301.651181 -284.72312)
			(xy 301.693802 -284.698513) (xy 301.739818 -284.681061) (xy 301.788037 -284.671217) (xy 301.837212 -284.669236)
			(xy 301.886067 -284.675168) (xy 301.933338 -284.68886) (xy 301.9778 -284.709958) (xy 302.018303 -284.737914)
			(xy 302.053796 -284.772006) (xy 302.083361 -284.81135) (xy 302.106232 -284.854927) (xy 302.121816 -284.901608)
			(xy 302.129711 -284.950185) (xy 302.130206 -284.974792) (xy 302.469054 -284.974792) (xy 302.473014 -284.925738)
			(xy 302.484791 -284.877954) (xy 302.504082 -284.832678) (xy 302.530385 -284.791082) (xy 302.56302 -284.754245)
			(xy 302.601141 -284.72312) (xy 302.643762 -284.698513) (xy 302.689778 -284.681061) (xy 302.737997 -284.671217)
			(xy 302.787172 -284.669236) (xy 302.836027 -284.675168) (xy 302.883298 -284.68886) (xy 302.92776 -284.709958)
			(xy 302.968263 -284.737914) (xy 303.003756 -284.772006) (xy 303.033321 -284.81135) (xy 303.056192 -284.854927)
			(xy 303.071776 -284.901608) (xy 303.079671 -284.950185) (xy 303.080166 -284.974792) (xy 303.079671 -284.999399)
			(xy 303.071776 -285.047976) (xy 303.056192 -285.094657) (xy 303.033321 -285.138234) (xy 303.003756 -285.177578)
			(xy 302.968263 -285.21167) (xy 302.92776 -285.239626) (xy 302.883298 -285.260724) (xy 302.836027 -285.274416)
			(xy 302.787172 -285.280348) (xy 302.737997 -285.278367) (xy 302.689778 -285.268523) (xy 302.643762 -285.251071)
			(xy 302.601141 -285.226464) (xy 302.56302 -285.195339) (xy 302.530385 -285.158502) (xy 302.504082 -285.116906)
			(xy 302.484791 -285.07163) (xy 302.473014 -285.023846) (xy 302.469054 -284.974792) (xy 302.130206 -284.974792)
			(xy 302.129711 -284.999399) (xy 302.121816 -285.047976) (xy 302.106232 -285.094657) (xy 302.083361 -285.138234)
			(xy 302.053796 -285.177578) (xy 302.018303 -285.21167) (xy 301.9778 -285.239626) (xy 301.933338 -285.260724)
			(xy 301.886067 -285.274416) (xy 301.837212 -285.280348) (xy 301.788037 -285.278367) (xy 301.739818 -285.268523)
			(xy 301.693802 -285.251071) (xy 301.651181 -285.226464) (xy 301.61306 -285.195339) (xy 301.580425 -285.158502)
			(xy 301.554122 -285.116906) (xy 301.534831 -285.07163) (xy 301.523054 -285.023846) (xy 301.519094 -284.974792)
			(xy 301.179992 -284.974792) (xy 301.179497 -284.999399) (xy 301.171602 -285.047976) (xy 301.156018 -285.094657)
			(xy 301.133147 -285.138234) (xy 301.103582 -285.177578) (xy 301.068089 -285.21167) (xy 301.027586 -285.239626)
			(xy 300.983124 -285.260724) (xy 300.935853 -285.274416) (xy 300.886998 -285.280348) (xy 300.837823 -285.278367)
			(xy 300.789604 -285.268523) (xy 300.743588 -285.251071) (xy 300.700967 -285.226464) (xy 300.662846 -285.195339)
			(xy 300.630211 -285.158502) (xy 300.603908 -285.116906) (xy 300.584617 -285.07163) (xy 300.57284 -285.023846)
			(xy 300.56888 -284.974792) (xy 300.230032 -284.974792) (xy 300.229537 -284.999399) (xy 300.221642 -285.047976)
			(xy 300.206058 -285.094657) (xy 300.183187 -285.138234) (xy 300.153622 -285.177578) (xy 300.118129 -285.21167)
			(xy 300.077626 -285.239626) (xy 300.033164 -285.260724) (xy 299.985893 -285.274416) (xy 299.937038 -285.280348)
			(xy 299.887863 -285.278367) (xy 299.839644 -285.268523) (xy 299.793628 -285.251071) (xy 299.751007 -285.226464)
			(xy 299.712886 -285.195339) (xy 299.680251 -285.158502) (xy 299.653948 -285.116906) (xy 299.634657 -285.07163)
			(xy 299.62288 -285.023846) (xy 299.61892 -284.974792) (xy 299.280072 -284.974792) (xy 299.279577 -284.999399)
			(xy 299.271682 -285.047976) (xy 299.256098 -285.094657) (xy 299.233227 -285.138234) (xy 299.203662 -285.177578)
			(xy 299.168169 -285.21167) (xy 299.127666 -285.239626) (xy 299.083204 -285.260724) (xy 299.035933 -285.274416)
			(xy 298.987078 -285.280348) (xy 298.937903 -285.278367) (xy 298.889684 -285.268523) (xy 298.843668 -285.251071)
			(xy 298.801047 -285.226464) (xy 298.762926 -285.195339) (xy 298.730291 -285.158502) (xy 298.703988 -285.116906)
			(xy 298.684697 -285.07163) (xy 298.67292 -285.023846) (xy 298.66896 -284.974792) (xy 298.330112 -284.974792)
			(xy 298.329617 -284.999399) (xy 298.321722 -285.047976) (xy 298.306138 -285.094657) (xy 298.283267 -285.138234)
			(xy 298.253702 -285.177578) (xy 298.218209 -285.21167) (xy 298.177706 -285.239626) (xy 298.133244 -285.260724)
			(xy 298.085973 -285.274416) (xy 298.037118 -285.280348) (xy 297.987943 -285.278367) (xy 297.939724 -285.268523)
			(xy 297.893708 -285.251071) (xy 297.851087 -285.226464) (xy 297.812966 -285.195339) (xy 297.780331 -285.158502)
			(xy 297.754028 -285.116906) (xy 297.734737 -285.07163) (xy 297.72296 -285.023846) (xy 297.719 -284.974792)
			(xy 297.380152 -284.974792) (xy 297.379657 -284.999399) (xy 297.371762 -285.047976) (xy 297.356178 -285.094657)
			(xy 297.333307 -285.138234) (xy 297.303742 -285.177578) (xy 297.268249 -285.21167) (xy 297.227746 -285.239626)
			(xy 297.183284 -285.260724) (xy 297.136013 -285.274416) (xy 297.087158 -285.280348) (xy 297.037983 -285.278367)
			(xy 296.989764 -285.268523) (xy 296.943748 -285.251071) (xy 296.901127 -285.226464) (xy 296.863006 -285.195339)
			(xy 296.830371 -285.158502) (xy 296.804068 -285.116906) (xy 296.784777 -285.07163) (xy 296.773 -285.023846)
			(xy 296.76904 -284.974792) (xy 296.430192 -284.974792) (xy 296.429697 -284.999399) (xy 296.421802 -285.047976)
			(xy 296.406218 -285.094657) (xy 296.383347 -285.138234) (xy 296.353782 -285.177578) (xy 296.318289 -285.21167)
			(xy 296.277786 -285.239626) (xy 296.233324 -285.260724) (xy 296.186053 -285.274416) (xy 296.137198 -285.280348)
			(xy 296.088023 -285.278367) (xy 296.039804 -285.268523) (xy 295.993788 -285.251071) (xy 295.951167 -285.226464)
			(xy 295.913046 -285.195339) (xy 295.880411 -285.158502) (xy 295.854108 -285.116906) (xy 295.834817 -285.07163)
			(xy 295.82304 -285.023846) (xy 295.81908 -284.974792) (xy 295.480232 -284.974792) (xy 295.479737 -284.999399)
			(xy 295.471842 -285.047976) (xy 295.456258 -285.094657) (xy 295.433387 -285.138234) (xy 295.403822 -285.177578)
			(xy 295.368329 -285.21167) (xy 295.327826 -285.239626) (xy 295.283364 -285.260724) (xy 295.236093 -285.274416)
			(xy 295.187238 -285.280348) (xy 295.138063 -285.278367) (xy 295.089844 -285.268523) (xy 295.043828 -285.251071)
			(xy 295.001207 -285.226464) (xy 294.963086 -285.195339) (xy 294.930451 -285.158502) (xy 294.904148 -285.116906)
			(xy 294.884857 -285.07163) (xy 294.87308 -285.023846) (xy 294.86912 -284.974792) (xy 294.530018 -284.974792)
			(xy 294.529523 -284.999399) (xy 294.521628 -285.047976) (xy 294.506044 -285.094657) (xy 294.483173 -285.138234)
			(xy 294.453608 -285.177578) (xy 294.418115 -285.21167) (xy 294.377612 -285.239626) (xy 294.33315 -285.260724)
			(xy 294.285879 -285.274416) (xy 294.237024 -285.280348) (xy 294.187849 -285.278367) (xy 294.13963 -285.268523)
			(xy 294.093614 -285.251071) (xy 294.050993 -285.226464) (xy 294.012872 -285.195339) (xy 293.980237 -285.158502)
			(xy 293.953934 -285.116906) (xy 293.934643 -285.07163) (xy 293.922866 -285.023846) (xy 293.918906 -284.974792)
			(xy 293.580058 -284.974792) (xy 293.579563 -284.999399) (xy 293.571668 -285.047976) (xy 293.556084 -285.094657)
			(xy 293.533213 -285.138234) (xy 293.503648 -285.177578) (xy 293.468155 -285.21167) (xy 293.427652 -285.239626)
			(xy 293.38319 -285.260724) (xy 293.335919 -285.274416) (xy 293.287064 -285.280348) (xy 293.237889 -285.278367)
			(xy 293.18967 -285.268523) (xy 293.143654 -285.251071) (xy 293.101033 -285.226464) (xy 293.062912 -285.195339)
			(xy 293.030277 -285.158502) (xy 293.003974 -285.116906) (xy 292.984683 -285.07163) (xy 292.972906 -285.023846)
			(xy 292.968946 -284.974792) (xy 292.630098 -284.974792) (xy 292.629603 -284.999399) (xy 292.621708 -285.047976)
			(xy 292.606124 -285.094657) (xy 292.583253 -285.138234) (xy 292.553688 -285.177578) (xy 292.518195 -285.21167)
			(xy 292.477692 -285.239626) (xy 292.43323 -285.260724) (xy 292.385959 -285.274416) (xy 292.337104 -285.280348)
			(xy 292.287929 -285.278367) (xy 292.23971 -285.268523) (xy 292.193694 -285.251071) (xy 292.151073 -285.226464)
			(xy 292.112952 -285.195339) (xy 292.080317 -285.158502) (xy 292.054014 -285.116906) (xy 292.034723 -285.07163)
			(xy 292.022946 -285.023846) (xy 292.018986 -284.974792) (xy 290.730178 -284.974792) (xy 290.729683 -284.999399)
			(xy 290.721788 -285.047976) (xy 290.706204 -285.094657) (xy 290.683333 -285.138234) (xy 290.653768 -285.177578)
			(xy 290.618275 -285.21167) (xy 290.577772 -285.239626) (xy 290.53331 -285.260724) (xy 290.486039 -285.274416)
			(xy 290.437184 -285.280348) (xy 290.388009 -285.278367) (xy 290.33979 -285.268523) (xy 290.293774 -285.251071)
			(xy 290.251153 -285.226464) (xy 290.213032 -285.195339) (xy 290.180397 -285.158502) (xy 290.154094 -285.116906)
			(xy 290.134803 -285.07163) (xy 290.123026 -285.023846) (xy 290.119066 -284.974792) (xy 289.780218 -284.974792)
			(xy 289.779723 -284.999399) (xy 289.771828 -285.047976) (xy 289.756244 -285.094657) (xy 289.733373 -285.138234)
			(xy 289.703808 -285.177578) (xy 289.668315 -285.21167) (xy 289.627812 -285.239626) (xy 289.58335 -285.260724)
			(xy 289.536079 -285.274416) (xy 289.487224 -285.280348) (xy 289.438049 -285.278367) (xy 289.38983 -285.268523)
			(xy 289.343814 -285.251071) (xy 289.301193 -285.226464) (xy 289.263072 -285.195339) (xy 289.230437 -285.158502)
			(xy 289.204134 -285.116906) (xy 289.184843 -285.07163) (xy 289.173066 -285.023846) (xy 289.169106 -284.974792)
			(xy 288.830004 -284.974792) (xy 288.829509 -284.999399) (xy 288.821614 -285.047976) (xy 288.80603 -285.094657)
			(xy 288.783159 -285.138234) (xy 288.753594 -285.177578) (xy 288.718101 -285.21167) (xy 288.677598 -285.239626)
			(xy 288.633136 -285.260724) (xy 288.585865 -285.274416) (xy 288.53701 -285.280348) (xy 288.487835 -285.278367)
			(xy 288.439616 -285.268523) (xy 288.3936 -285.251071) (xy 288.350979 -285.226464) (xy 288.312858 -285.195339)
			(xy 288.280223 -285.158502) (xy 288.25392 -285.116906) (xy 288.234629 -285.07163) (xy 288.222852 -285.023846)
			(xy 288.218892 -284.974792) (xy 287.880044 -284.974792) (xy 287.879549 -284.999399) (xy 287.871654 -285.047976)
			(xy 287.85607 -285.094657) (xy 287.833199 -285.138234) (xy 287.803634 -285.177578) (xy 287.768141 -285.21167)
			(xy 287.727638 -285.239626) (xy 287.683176 -285.260724) (xy 287.635905 -285.274416) (xy 287.58705 -285.280348)
			(xy 287.537875 -285.278367) (xy 287.489656 -285.268523) (xy 287.44364 -285.251071) (xy 287.401019 -285.226464)
			(xy 287.362898 -285.195339) (xy 287.330263 -285.158502) (xy 287.30396 -285.116906) (xy 287.284669 -285.07163)
			(xy 287.272892 -285.023846) (xy 287.268932 -284.974792) (xy 286.930084 -284.974792) (xy 286.929589 -284.999399)
			(xy 286.921694 -285.047976) (xy 286.90611 -285.094657) (xy 286.883239 -285.138234) (xy 286.853674 -285.177578)
			(xy 286.818181 -285.21167) (xy 286.777678 -285.239626) (xy 286.733216 -285.260724) (xy 286.685945 -285.274416)
			(xy 286.63709 -285.280348) (xy 286.587915 -285.278367) (xy 286.539696 -285.268523) (xy 286.49368 -285.251071)
			(xy 286.451059 -285.226464) (xy 286.412938 -285.195339) (xy 286.380303 -285.158502) (xy 286.354 -285.116906)
			(xy 286.334709 -285.07163) (xy 286.322932 -285.023846) (xy 286.318972 -284.974792) (xy 285.980124 -284.974792)
			(xy 285.979629 -284.999399) (xy 285.971734 -285.047976) (xy 285.95615 -285.094657) (xy 285.933279 -285.138234)
			(xy 285.903714 -285.177578) (xy 285.868221 -285.21167) (xy 285.827718 -285.239626) (xy 285.783256 -285.260724)
			(xy 285.735985 -285.274416) (xy 285.68713 -285.280348) (xy 285.637955 -285.278367) (xy 285.589736 -285.268523)
			(xy 285.54372 -285.251071) (xy 285.501099 -285.226464) (xy 285.462978 -285.195339) (xy 285.430343 -285.158502)
			(xy 285.40404 -285.116906) (xy 285.384749 -285.07163) (xy 285.372972 -285.023846) (xy 285.369012 -284.974792)
			(xy 285.030164 -284.974792) (xy 285.029669 -284.999399) (xy 285.021774 -285.047976) (xy 285.00619 -285.094657)
			(xy 284.983319 -285.138234) (xy 284.953754 -285.177578) (xy 284.918261 -285.21167) (xy 284.877758 -285.239626)
			(xy 284.833296 -285.260724) (xy 284.786025 -285.274416) (xy 284.73717 -285.280348) (xy 284.687995 -285.278367)
			(xy 284.639776 -285.268523) (xy 284.59376 -285.251071) (xy 284.551139 -285.226464) (xy 284.513018 -285.195339)
			(xy 284.480383 -285.158502) (xy 284.45408 -285.116906) (xy 284.434789 -285.07163) (xy 284.423012 -285.023846)
			(xy 284.419052 -284.974792) (xy 284.080204 -284.974792) (xy 284.079709 -284.999399) (xy 284.071814 -285.047976)
			(xy 284.05623 -285.094657) (xy 284.033359 -285.138234) (xy 284.003794 -285.177578) (xy 283.968301 -285.21167)
			(xy 283.927798 -285.239626) (xy 283.883336 -285.260724) (xy 283.836065 -285.274416) (xy 283.78721 -285.280348)
			(xy 283.738035 -285.278367) (xy 283.689816 -285.268523) (xy 283.6438 -285.251071) (xy 283.601179 -285.226464)
			(xy 283.563058 -285.195339) (xy 283.530423 -285.158502) (xy 283.50412 -285.116906) (xy 283.484829 -285.07163)
			(xy 283.473052 -285.023846) (xy 283.469092 -284.974792) (xy 283.130244 -284.974792) (xy 283.129749 -284.999399)
			(xy 283.121854 -285.047976) (xy 283.10627 -285.094657) (xy 283.083399 -285.138234) (xy 283.053834 -285.177578)
			(xy 283.018341 -285.21167) (xy 282.977838 -285.239626) (xy 282.933376 -285.260724) (xy 282.886105 -285.274416)
			(xy 282.83725 -285.280348) (xy 282.788075 -285.278367) (xy 282.739856 -285.268523) (xy 282.69384 -285.251071)
			(xy 282.651219 -285.226464) (xy 282.613098 -285.195339) (xy 282.580463 -285.158502) (xy 282.55416 -285.116906)
			(xy 282.534869 -285.07163) (xy 282.523092 -285.023846) (xy 282.519132 -284.974792) (xy 282.18003 -284.974792)
			(xy 282.179535 -284.999399) (xy 282.17164 -285.047976) (xy 282.156056 -285.094657) (xy 282.133185 -285.138234)
			(xy 282.10362 -285.177578) (xy 282.068127 -285.21167) (xy 282.027624 -285.239626) (xy 281.983162 -285.260724)
			(xy 281.935891 -285.274416) (xy 281.887036 -285.280348) (xy 281.837861 -285.278367) (xy 281.789642 -285.268523)
			(xy 281.743626 -285.251071) (xy 281.701005 -285.226464) (xy 281.662884 -285.195339) (xy 281.630249 -285.158502)
			(xy 281.603946 -285.116906) (xy 281.584655 -285.07163) (xy 281.572878 -285.023846) (xy 281.568918 -284.974792)
			(xy 281.23007 -284.974792) (xy 281.229575 -284.999399) (xy 281.22168 -285.047976) (xy 281.206096 -285.094657)
			(xy 281.183225 -285.138234) (xy 281.15366 -285.177578) (xy 281.118167 -285.21167) (xy 281.077664 -285.239626)
			(xy 281.033202 -285.260724) (xy 280.985931 -285.274416) (xy 280.937076 -285.280348) (xy 280.887901 -285.278367)
			(xy 280.839682 -285.268523) (xy 280.793666 -285.251071) (xy 280.751045 -285.226464) (xy 280.712924 -285.195339)
			(xy 280.680289 -285.158502) (xy 280.653986 -285.116906) (xy 280.634695 -285.07163) (xy 280.622918 -285.023846)
			(xy 280.618958 -284.974792) (xy 280.28011 -284.974792) (xy 280.279615 -284.999399) (xy 280.27172 -285.047976)
			(xy 280.256136 -285.094657) (xy 280.233265 -285.138234) (xy 280.2037 -285.177578) (xy 280.168207 -285.21167)
			(xy 280.127704 -285.239626) (xy 280.083242 -285.260724) (xy 280.035971 -285.274416) (xy 279.987116 -285.280348)
			(xy 279.937941 -285.278367) (xy 279.889722 -285.268523) (xy 279.843706 -285.251071) (xy 279.801085 -285.226464)
			(xy 279.762964 -285.195339) (xy 279.730329 -285.158502) (xy 279.704026 -285.116906) (xy 279.684735 -285.07163)
			(xy 279.672958 -285.023846) (xy 279.668998 -284.974792) (xy 279.33015 -284.974792) (xy 279.329655 -284.999399)
			(xy 279.32176 -285.047976) (xy 279.306176 -285.094657) (xy 279.283305 -285.138234) (xy 279.25374 -285.177578)
			(xy 279.218247 -285.21167) (xy 279.177744 -285.239626) (xy 279.133282 -285.260724) (xy 279.086011 -285.274416)
			(xy 279.037156 -285.280348) (xy 278.987981 -285.278367) (xy 278.939762 -285.268523) (xy 278.893746 -285.251071)
			(xy 278.851125 -285.226464) (xy 278.813004 -285.195339) (xy 278.780369 -285.158502) (xy 278.754066 -285.116906)
			(xy 278.734775 -285.07163) (xy 278.722998 -285.023846) (xy 278.719038 -284.974792) (xy 278.38019 -284.974792)
			(xy 278.379695 -284.999399) (xy 278.3718 -285.047976) (xy 278.356216 -285.094657) (xy 278.333345 -285.138234)
			(xy 278.30378 -285.177578) (xy 278.268287 -285.21167) (xy 278.227784 -285.239626) (xy 278.183322 -285.260724)
			(xy 278.136051 -285.274416) (xy 278.087196 -285.280348) (xy 278.038021 -285.278367) (xy 277.989802 -285.268523)
			(xy 277.943786 -285.251071) (xy 277.901165 -285.226464) (xy 277.863044 -285.195339) (xy 277.830409 -285.158502)
			(xy 277.804106 -285.116906) (xy 277.784815 -285.07163) (xy 277.773038 -285.023846) (xy 277.769078 -284.974792)
			(xy 277.43023 -284.974792) (xy 277.429735 -284.999399) (xy 277.42184 -285.047976) (xy 277.406256 -285.094657)
			(xy 277.383385 -285.138234) (xy 277.35382 -285.177578) (xy 277.318327 -285.21167) (xy 277.277824 -285.239626)
			(xy 277.233362 -285.260724) (xy 277.186091 -285.274416) (xy 277.137236 -285.280348) (xy 277.088061 -285.278367)
			(xy 277.039842 -285.268523) (xy 276.993826 -285.251071) (xy 276.951205 -285.226464) (xy 276.913084 -285.195339)
			(xy 276.880449 -285.158502) (xy 276.854146 -285.116906) (xy 276.834855 -285.07163) (xy 276.823078 -285.023846)
			(xy 276.819118 -284.974792) (xy 276.6314 -284.974792) (xy 276.6314 -285.449772) (xy 305.793914 -285.449772)
			(xy 305.797874 -285.400718) (xy 305.809651 -285.352934) (xy 305.828942 -285.307658) (xy 305.855245 -285.266062)
			(xy 305.88788 -285.229225) (xy 305.926001 -285.1981) (xy 305.968622 -285.173493) (xy 306.014638 -285.156041)
			(xy 306.062857 -285.146197) (xy 306.112032 -285.144216) (xy 306.160887 -285.150148) (xy 306.208158 -285.16384)
			(xy 306.25262 -285.184938) (xy 306.293123 -285.212894) (xy 306.328616 -285.246986) (xy 306.358181 -285.28633)
			(xy 306.381052 -285.329907) (xy 306.396636 -285.376588) (xy 306.404531 -285.425165) (xy 306.405026 -285.449772)
			(xy 306.404531 -285.474379) (xy 306.404352 -285.47548) (xy 306.72303 -285.47548) (xy 306.72303 -285.424064)
			(xy 306.731073 -285.373282) (xy 306.746961 -285.324383) (xy 306.770304 -285.278571) (xy 306.800525 -285.236975)
			(xy 306.836881 -285.200619) (xy 306.878477 -285.170398) (xy 306.924289 -285.147055) (xy 306.973188 -285.131167)
			(xy 307.02397 -285.123124) (xy 307.075386 -285.123124) (xy 307.126168 -285.131167) (xy 307.175067 -285.147055)
			(xy 307.220879 -285.170398) (xy 307.262475 -285.200619) (xy 307.298831 -285.236975) (xy 307.329052 -285.278571)
			(xy 307.352395 -285.324383) (xy 307.368283 -285.373282) (xy 307.376326 -285.424064) (xy 307.37683 -285.449772)
			(xy 307.376326 -285.47548) (xy 307.673244 -285.47548) (xy 307.673244 -285.424064) (xy 307.681287 -285.373282)
			(xy 307.697175 -285.324383) (xy 307.720518 -285.278571) (xy 307.750739 -285.236975) (xy 307.787095 -285.200619)
			(xy 307.828691 -285.170398) (xy 307.874503 -285.147055) (xy 307.923402 -285.131167) (xy 307.974184 -285.123124)
			(xy 308.0256 -285.123124) (xy 308.076382 -285.131167) (xy 308.125281 -285.147055) (xy 308.171093 -285.170398)
			(xy 308.212689 -285.200619) (xy 308.249045 -285.236975) (xy 308.279266 -285.278571) (xy 308.302609 -285.324383)
			(xy 308.318497 -285.373282) (xy 308.32654 -285.424064) (xy 308.327044 -285.449772) (xy 308.644048 -285.449772)
			(xy 308.648008 -285.400718) (xy 308.659785 -285.352934) (xy 308.679076 -285.307658) (xy 308.705379 -285.266062)
			(xy 308.738014 -285.229225) (xy 308.776135 -285.1981) (xy 308.818756 -285.173493) (xy 308.864772 -285.156041)
			(xy 308.912991 -285.146197) (xy 308.962166 -285.144216) (xy 309.011021 -285.150148) (xy 309.058292 -285.16384)
			(xy 309.102754 -285.184938) (xy 309.143257 -285.212894) (xy 309.17875 -285.246986) (xy 309.208315 -285.28633)
			(xy 309.231186 -285.329907) (xy 309.24677 -285.376588) (xy 309.254665 -285.425165) (xy 309.25516 -285.449772)
			(xy 309.594008 -285.449772) (xy 309.597968 -285.400718) (xy 309.609745 -285.352934) (xy 309.629036 -285.307658)
			(xy 309.655339 -285.266062) (xy 309.687974 -285.229225) (xy 309.726095 -285.1981) (xy 309.768716 -285.173493)
			(xy 309.814732 -285.156041) (xy 309.862951 -285.146197) (xy 309.912126 -285.144216) (xy 309.960981 -285.150148)
			(xy 310.008252 -285.16384) (xy 310.052714 -285.184938) (xy 310.093217 -285.212894) (xy 310.12871 -285.246986)
			(xy 310.158275 -285.28633) (xy 310.181146 -285.329907) (xy 310.19673 -285.376588) (xy 310.204625 -285.425165)
			(xy 310.20512 -285.449772) (xy 310.543968 -285.449772) (xy 310.547928 -285.400718) (xy 310.559705 -285.352934)
			(xy 310.578996 -285.307658) (xy 310.605299 -285.266062) (xy 310.637934 -285.229225) (xy 310.676055 -285.1981)
			(xy 310.718676 -285.173493) (xy 310.764692 -285.156041) (xy 310.812911 -285.146197) (xy 310.862086 -285.144216)
			(xy 310.910941 -285.150148) (xy 310.958212 -285.16384) (xy 311.002674 -285.184938) (xy 311.043177 -285.212894)
			(xy 311.07867 -285.246986) (xy 311.108235 -285.28633) (xy 311.131106 -285.329907) (xy 311.14669 -285.376588)
			(xy 311.154585 -285.425165) (xy 311.15508 -285.449772) (xy 311.493928 -285.449772) (xy 311.497888 -285.400718)
			(xy 311.509665 -285.352934) (xy 311.528956 -285.307658) (xy 311.555259 -285.266062) (xy 311.587894 -285.229225)
			(xy 311.626015 -285.1981) (xy 311.668636 -285.173493) (xy 311.714652 -285.156041) (xy 311.762871 -285.146197)
			(xy 311.812046 -285.144216) (xy 311.860901 -285.150148) (xy 311.908172 -285.16384) (xy 311.952634 -285.184938)
			(xy 311.993137 -285.212894) (xy 312.02863 -285.246986) (xy 312.058195 -285.28633) (xy 312.081066 -285.329907)
			(xy 312.09665 -285.376588) (xy 312.104545 -285.425165) (xy 312.10504 -285.449772) (xy 312.443888 -285.449772)
			(xy 312.447848 -285.400718) (xy 312.459625 -285.352934) (xy 312.478916 -285.307658) (xy 312.505219 -285.266062)
			(xy 312.537854 -285.229225) (xy 312.575975 -285.1981) (xy 312.618596 -285.173493) (xy 312.664612 -285.156041)
			(xy 312.712831 -285.146197) (xy 312.762006 -285.144216) (xy 312.810861 -285.150148) (xy 312.858132 -285.16384)
			(xy 312.902594 -285.184938) (xy 312.943097 -285.212894) (xy 312.97859 -285.246986) (xy 313.008155 -285.28633)
			(xy 313.031026 -285.329907) (xy 313.04661 -285.376588) (xy 313.054505 -285.425165) (xy 313.055 -285.449772)
			(xy 313.054505 -285.474379) (xy 313.054326 -285.47548) (xy 313.373258 -285.47548) (xy 313.373258 -285.424064)
			(xy 313.381301 -285.373282) (xy 313.397189 -285.324383) (xy 313.420532 -285.278571) (xy 313.450753 -285.236975)
			(xy 313.487109 -285.200619) (xy 313.528705 -285.170398) (xy 313.574517 -285.147055) (xy 313.623416 -285.131167)
			(xy 313.674198 -285.123124) (xy 313.725614 -285.123124) (xy 313.776396 -285.131167) (xy 313.825295 -285.147055)
			(xy 313.871107 -285.170398) (xy 313.912703 -285.200619) (xy 313.949059 -285.236975) (xy 313.97928 -285.278571)
			(xy 314.002623 -285.324383) (xy 314.018511 -285.373282) (xy 314.026554 -285.424064) (xy 314.027058 -285.449772)
			(xy 314.026554 -285.47548) (xy 314.323218 -285.47548) (xy 314.323218 -285.424064) (xy 314.331261 -285.373282)
			(xy 314.347149 -285.324383) (xy 314.370492 -285.278571) (xy 314.400713 -285.236975) (xy 314.437069 -285.200619)
			(xy 314.478665 -285.170398) (xy 314.524477 -285.147055) (xy 314.573376 -285.131167) (xy 314.624158 -285.123124)
			(xy 314.675574 -285.123124) (xy 314.726356 -285.131167) (xy 314.775255 -285.147055) (xy 314.821067 -285.170398)
			(xy 314.862663 -285.200619) (xy 314.899019 -285.236975) (xy 314.92924 -285.278571) (xy 314.952583 -285.324383)
			(xy 314.968471 -285.373282) (xy 314.976514 -285.424064) (xy 314.977018 -285.449772) (xy 314.977013 -285.450026)
			(xy 315.294276 -285.450026) (xy 315.298236 -285.400972) (xy 315.310013 -285.353188) (xy 315.329304 -285.307912)
			(xy 315.355607 -285.266316) (xy 315.388242 -285.229479) (xy 315.426363 -285.198354) (xy 315.468984 -285.173747)
			(xy 315.515 -285.156295) (xy 315.563219 -285.146451) (xy 315.612394 -285.14447) (xy 315.661249 -285.150402)
			(xy 315.70852 -285.164094) (xy 315.752982 -285.185192) (xy 315.793485 -285.213148) (xy 315.828978 -285.24724)
			(xy 315.858543 -285.286584) (xy 315.881414 -285.330161) (xy 315.896998 -285.376842) (xy 315.904893 -285.425419)
			(xy 315.905388 -285.450026) (xy 315.904893 -285.474633) (xy 315.896998 -285.52321) (xy 315.881414 -285.569891)
			(xy 315.858543 -285.613468) (xy 315.828978 -285.652812) (xy 315.793485 -285.686904) (xy 315.752982 -285.71486)
			(xy 315.70852 -285.735958) (xy 315.661249 -285.74965) (xy 315.612394 -285.755582) (xy 315.563219 -285.753601)
			(xy 315.515 -285.743757) (xy 315.468984 -285.726305) (xy 315.426363 -285.701698) (xy 315.388242 -285.670573)
			(xy 315.355607 -285.633736) (xy 315.329304 -285.59214) (xy 315.310013 -285.546864) (xy 315.298236 -285.49908)
			(xy 315.294276 -285.450026) (xy 314.977013 -285.450026) (xy 314.976514 -285.47548) (xy 314.968471 -285.526262)
			(xy 314.952583 -285.575161) (xy 314.92924 -285.620973) (xy 314.899019 -285.662569) (xy 314.862663 -285.698925)
			(xy 314.821067 -285.729146) (xy 314.775255 -285.752489) (xy 314.726356 -285.768377) (xy 314.675574 -285.77642)
			(xy 314.624158 -285.77642) (xy 314.573376 -285.768377) (xy 314.524477 -285.752489) (xy 314.478665 -285.729146)
			(xy 314.437069 -285.698925) (xy 314.400713 -285.662569) (xy 314.370492 -285.620973) (xy 314.347149 -285.575161)
			(xy 314.331261 -285.526262) (xy 314.323218 -285.47548) (xy 314.026554 -285.47548) (xy 314.018511 -285.526262)
			(xy 314.002623 -285.575161) (xy 313.97928 -285.620973) (xy 313.949059 -285.662569) (xy 313.912703 -285.698925)
			(xy 313.871107 -285.729146) (xy 313.825295 -285.752489) (xy 313.776396 -285.768377) (xy 313.725614 -285.77642)
			(xy 313.674198 -285.77642) (xy 313.623416 -285.768377) (xy 313.574517 -285.752489) (xy 313.528705 -285.729146)
			(xy 313.487109 -285.698925) (xy 313.450753 -285.662569) (xy 313.420532 -285.620973) (xy 313.397189 -285.575161)
			(xy 313.381301 -285.526262) (xy 313.373258 -285.47548) (xy 313.054326 -285.47548) (xy 313.04661 -285.522956)
			(xy 313.031026 -285.569637) (xy 313.008155 -285.613214) (xy 312.97859 -285.652558) (xy 312.943097 -285.68665)
			(xy 312.902594 -285.714606) (xy 312.858132 -285.735704) (xy 312.810861 -285.749396) (xy 312.762006 -285.755328)
			(xy 312.712831 -285.753347) (xy 312.664612 -285.743503) (xy 312.618596 -285.726051) (xy 312.575975 -285.701444)
			(xy 312.537854 -285.670319) (xy 312.505219 -285.633482) (xy 312.478916 -285.591886) (xy 312.459625 -285.54661)
			(xy 312.447848 -285.498826) (xy 312.443888 -285.449772) (xy 312.10504 -285.449772) (xy 312.104545 -285.474379)
			(xy 312.09665 -285.522956) (xy 312.081066 -285.569637) (xy 312.058195 -285.613214) (xy 312.02863 -285.652558)
			(xy 311.993137 -285.68665) (xy 311.952634 -285.714606) (xy 311.908172 -285.735704) (xy 311.860901 -285.749396)
			(xy 311.812046 -285.755328) (xy 311.762871 -285.753347) (xy 311.714652 -285.743503) (xy 311.668636 -285.726051)
			(xy 311.626015 -285.701444) (xy 311.587894 -285.670319) (xy 311.555259 -285.633482) (xy 311.528956 -285.591886)
			(xy 311.509665 -285.54661) (xy 311.497888 -285.498826) (xy 311.493928 -285.449772) (xy 311.15508 -285.449772)
			(xy 311.154585 -285.474379) (xy 311.14669 -285.522956) (xy 311.131106 -285.569637) (xy 311.108235 -285.613214)
			(xy 311.07867 -285.652558) (xy 311.043177 -285.68665) (xy 311.002674 -285.714606) (xy 310.958212 -285.735704)
			(xy 310.910941 -285.749396) (xy 310.862086 -285.755328) (xy 310.812911 -285.753347) (xy 310.764692 -285.743503)
			(xy 310.718676 -285.726051) (xy 310.676055 -285.701444) (xy 310.637934 -285.670319) (xy 310.605299 -285.633482)
			(xy 310.578996 -285.591886) (xy 310.559705 -285.54661) (xy 310.547928 -285.498826) (xy 310.543968 -285.449772)
			(xy 310.20512 -285.449772) (xy 310.204625 -285.474379) (xy 310.19673 -285.522956) (xy 310.181146 -285.569637)
			(xy 310.158275 -285.613214) (xy 310.12871 -285.652558) (xy 310.093217 -285.68665) (xy 310.052714 -285.714606)
			(xy 310.008252 -285.735704) (xy 309.960981 -285.749396) (xy 309.912126 -285.755328) (xy 309.862951 -285.753347)
			(xy 309.814732 -285.743503) (xy 309.768716 -285.726051) (xy 309.726095 -285.701444) (xy 309.687974 -285.670319)
			(xy 309.655339 -285.633482) (xy 309.629036 -285.591886) (xy 309.609745 -285.54661) (xy 309.597968 -285.498826)
			(xy 309.594008 -285.449772) (xy 309.25516 -285.449772) (xy 309.254665 -285.474379) (xy 309.24677 -285.522956)
			(xy 309.231186 -285.569637) (xy 309.208315 -285.613214) (xy 309.17875 -285.652558) (xy 309.143257 -285.68665)
			(xy 309.102754 -285.714606) (xy 309.058292 -285.735704) (xy 309.011021 -285.749396) (xy 308.962166 -285.755328)
			(xy 308.912991 -285.753347) (xy 308.864772 -285.743503) (xy 308.818756 -285.726051) (xy 308.776135 -285.701444)
			(xy 308.738014 -285.670319) (xy 308.705379 -285.633482) (xy 308.679076 -285.591886) (xy 308.659785 -285.54661)
			(xy 308.648008 -285.498826) (xy 308.644048 -285.449772) (xy 308.327044 -285.449772) (xy 308.32654 -285.47548)
			(xy 308.318497 -285.526262) (xy 308.302609 -285.575161) (xy 308.279266 -285.620973) (xy 308.249045 -285.662569)
			(xy 308.212689 -285.698925) (xy 308.171093 -285.729146) (xy 308.125281 -285.752489) (xy 308.076382 -285.768377)
			(xy 308.0256 -285.77642) (xy 307.974184 -285.77642) (xy 307.923402 -285.768377) (xy 307.874503 -285.752489)
			(xy 307.828691 -285.729146) (xy 307.787095 -285.698925) (xy 307.750739 -285.662569) (xy 307.720518 -285.620973)
			(xy 307.697175 -285.575161) (xy 307.681287 -285.526262) (xy 307.673244 -285.47548) (xy 307.376326 -285.47548)
			(xy 307.368283 -285.526262) (xy 307.352395 -285.575161) (xy 307.329052 -285.620973) (xy 307.298831 -285.662569)
			(xy 307.262475 -285.698925) (xy 307.220879 -285.729146) (xy 307.175067 -285.752489) (xy 307.126168 -285.768377)
			(xy 307.075386 -285.77642) (xy 307.02397 -285.77642) (xy 306.973188 -285.768377) (xy 306.924289 -285.752489)
			(xy 306.878477 -285.729146) (xy 306.836881 -285.698925) (xy 306.800525 -285.662569) (xy 306.770304 -285.620973)
			(xy 306.746961 -285.575161) (xy 306.731073 -285.526262) (xy 306.72303 -285.47548) (xy 306.404352 -285.47548)
			(xy 306.396636 -285.522956) (xy 306.381052 -285.569637) (xy 306.358181 -285.613214) (xy 306.328616 -285.652558)
			(xy 306.293123 -285.68665) (xy 306.25262 -285.714606) (xy 306.208158 -285.735704) (xy 306.160887 -285.749396)
			(xy 306.112032 -285.755328) (xy 306.062857 -285.753347) (xy 306.014638 -285.743503) (xy 305.968622 -285.726051)
			(xy 305.926001 -285.701444) (xy 305.88788 -285.670319) (xy 305.855245 -285.633482) (xy 305.828942 -285.591886)
			(xy 305.809651 -285.54661) (xy 305.797874 -285.498826) (xy 305.793914 -285.449772) (xy 276.6314 -285.449772)
			(xy 276.6314 -285.779718) (xy 276.630973 -285.789787) (xy 276.623254 -285.808386) (xy 276.616414 -285.815786)
			(xy 276.507448 -285.924752) (xy 276.819118 -285.924752) (xy 276.823078 -285.875698) (xy 276.834855 -285.827914)
			(xy 276.854146 -285.782638) (xy 276.880449 -285.741042) (xy 276.913084 -285.704205) (xy 276.951205 -285.67308)
			(xy 276.993826 -285.648473) (xy 277.039842 -285.631021) (xy 277.088061 -285.621177) (xy 277.137236 -285.619196)
			(xy 277.186091 -285.625128) (xy 277.233362 -285.63882) (xy 277.277824 -285.659918) (xy 277.318327 -285.687874)
			(xy 277.35382 -285.721966) (xy 277.383385 -285.76131) (xy 277.406256 -285.804887) (xy 277.42184 -285.851568)
			(xy 277.429735 -285.900145) (xy 277.43023 -285.924752) (xy 277.769078 -285.924752) (xy 277.773038 -285.875698)
			(xy 277.784815 -285.827914) (xy 277.804106 -285.782638) (xy 277.830409 -285.741042) (xy 277.863044 -285.704205)
			(xy 277.901165 -285.67308) (xy 277.943786 -285.648473) (xy 277.989802 -285.631021) (xy 278.038021 -285.621177)
			(xy 278.087196 -285.619196) (xy 278.136051 -285.625128) (xy 278.183322 -285.63882) (xy 278.227784 -285.659918)
			(xy 278.268287 -285.687874) (xy 278.30378 -285.721966) (xy 278.333345 -285.76131) (xy 278.356216 -285.804887)
			(xy 278.3718 -285.851568) (xy 278.379695 -285.900145) (xy 278.38019 -285.924752) (xy 278.719038 -285.924752)
			(xy 278.722998 -285.875698) (xy 278.734775 -285.827914) (xy 278.754066 -285.782638) (xy 278.780369 -285.741042)
			(xy 278.813004 -285.704205) (xy 278.851125 -285.67308) (xy 278.893746 -285.648473) (xy 278.939762 -285.631021)
			(xy 278.987981 -285.621177) (xy 279.037156 -285.619196) (xy 279.086011 -285.625128) (xy 279.133282 -285.63882)
			(xy 279.177744 -285.659918) (xy 279.218247 -285.687874) (xy 279.25374 -285.721966) (xy 279.283305 -285.76131)
			(xy 279.306176 -285.804887) (xy 279.32176 -285.851568) (xy 279.329655 -285.900145) (xy 279.33015 -285.924752)
			(xy 279.668998 -285.924752) (xy 279.672958 -285.875698) (xy 279.684735 -285.827914) (xy 279.704026 -285.782638)
			(xy 279.730329 -285.741042) (xy 279.762964 -285.704205) (xy 279.801085 -285.67308) (xy 279.843706 -285.648473)
			(xy 279.889722 -285.631021) (xy 279.937941 -285.621177) (xy 279.987116 -285.619196) (xy 280.035971 -285.625128)
			(xy 280.083242 -285.63882) (xy 280.127704 -285.659918) (xy 280.168207 -285.687874) (xy 280.2037 -285.721966)
			(xy 280.233265 -285.76131) (xy 280.256136 -285.804887) (xy 280.27172 -285.851568) (xy 280.279615 -285.900145)
			(xy 280.28011 -285.924752) (xy 280.618958 -285.924752) (xy 280.622918 -285.875698) (xy 280.634695 -285.827914)
			(xy 280.653986 -285.782638) (xy 280.680289 -285.741042) (xy 280.712924 -285.704205) (xy 280.751045 -285.67308)
			(xy 280.793666 -285.648473) (xy 280.839682 -285.631021) (xy 280.887901 -285.621177) (xy 280.937076 -285.619196)
			(xy 280.985931 -285.625128) (xy 281.033202 -285.63882) (xy 281.077664 -285.659918) (xy 281.118167 -285.687874)
			(xy 281.15366 -285.721966) (xy 281.183225 -285.76131) (xy 281.206096 -285.804887) (xy 281.22168 -285.851568)
			(xy 281.229575 -285.900145) (xy 281.23007 -285.924752) (xy 281.568918 -285.924752) (xy 281.572878 -285.875698)
			(xy 281.584655 -285.827914) (xy 281.603946 -285.782638) (xy 281.630249 -285.741042) (xy 281.662884 -285.704205)
			(xy 281.701005 -285.67308) (xy 281.743626 -285.648473) (xy 281.789642 -285.631021) (xy 281.837861 -285.621177)
			(xy 281.887036 -285.619196) (xy 281.935891 -285.625128) (xy 281.983162 -285.63882) (xy 282.027624 -285.659918)
			(xy 282.068127 -285.687874) (xy 282.10362 -285.721966) (xy 282.133185 -285.76131) (xy 282.156056 -285.804887)
			(xy 282.17164 -285.851568) (xy 282.179535 -285.900145) (xy 282.18003 -285.924752) (xy 282.519132 -285.924752)
			(xy 282.523092 -285.875698) (xy 282.534869 -285.827914) (xy 282.55416 -285.782638) (xy 282.580463 -285.741042)
			(xy 282.613098 -285.704205) (xy 282.651219 -285.67308) (xy 282.69384 -285.648473) (xy 282.739856 -285.631021)
			(xy 282.788075 -285.621177) (xy 282.83725 -285.619196) (xy 282.886105 -285.625128) (xy 282.933376 -285.63882)
			(xy 282.977838 -285.659918) (xy 283.018341 -285.687874) (xy 283.053834 -285.721966) (xy 283.083399 -285.76131)
			(xy 283.10627 -285.804887) (xy 283.121854 -285.851568) (xy 283.129749 -285.900145) (xy 283.130244 -285.924752)
			(xy 283.469092 -285.924752) (xy 283.473052 -285.875698) (xy 283.484829 -285.827914) (xy 283.50412 -285.782638)
			(xy 283.530423 -285.741042) (xy 283.563058 -285.704205) (xy 283.601179 -285.67308) (xy 283.6438 -285.648473)
			(xy 283.689816 -285.631021) (xy 283.738035 -285.621177) (xy 283.78721 -285.619196) (xy 283.836065 -285.625128)
			(xy 283.883336 -285.63882) (xy 283.927798 -285.659918) (xy 283.968301 -285.687874) (xy 284.003794 -285.721966)
			(xy 284.033359 -285.76131) (xy 284.05623 -285.804887) (xy 284.071814 -285.851568) (xy 284.079709 -285.900145)
			(xy 284.080204 -285.924752) (xy 284.419052 -285.924752) (xy 284.423012 -285.875698) (xy 284.434789 -285.827914)
			(xy 284.45408 -285.782638) (xy 284.480383 -285.741042) (xy 284.513018 -285.704205) (xy 284.551139 -285.67308)
			(xy 284.59376 -285.648473) (xy 284.639776 -285.631021) (xy 284.687995 -285.621177) (xy 284.73717 -285.619196)
			(xy 284.786025 -285.625128) (xy 284.833296 -285.63882) (xy 284.877758 -285.659918) (xy 284.918261 -285.687874)
			(xy 284.953754 -285.721966) (xy 284.983319 -285.76131) (xy 285.00619 -285.804887) (xy 285.021774 -285.851568)
			(xy 285.029669 -285.900145) (xy 285.030164 -285.924752) (xy 285.369012 -285.924752) (xy 285.372972 -285.875698)
			(xy 285.384749 -285.827914) (xy 285.40404 -285.782638) (xy 285.430343 -285.741042) (xy 285.462978 -285.704205)
			(xy 285.501099 -285.67308) (xy 285.54372 -285.648473) (xy 285.589736 -285.631021) (xy 285.637955 -285.621177)
			(xy 285.68713 -285.619196) (xy 285.735985 -285.625128) (xy 285.783256 -285.63882) (xy 285.827718 -285.659918)
			(xy 285.868221 -285.687874) (xy 285.903714 -285.721966) (xy 285.933279 -285.76131) (xy 285.95615 -285.804887)
			(xy 285.971734 -285.851568) (xy 285.979629 -285.900145) (xy 285.980124 -285.924752) (xy 286.318972 -285.924752)
			(xy 286.322932 -285.875698) (xy 286.334709 -285.827914) (xy 286.354 -285.782638) (xy 286.380303 -285.741042)
			(xy 286.412938 -285.704205) (xy 286.451059 -285.67308) (xy 286.49368 -285.648473) (xy 286.539696 -285.631021)
			(xy 286.587915 -285.621177) (xy 286.63709 -285.619196) (xy 286.685945 -285.625128) (xy 286.733216 -285.63882)
			(xy 286.777678 -285.659918) (xy 286.818181 -285.687874) (xy 286.853674 -285.721966) (xy 286.883239 -285.76131)
			(xy 286.90611 -285.804887) (xy 286.921694 -285.851568) (xy 286.929589 -285.900145) (xy 286.930084 -285.924752)
			(xy 287.268932 -285.924752) (xy 287.272892 -285.875698) (xy 287.284669 -285.827914) (xy 287.30396 -285.782638)
			(xy 287.330263 -285.741042) (xy 287.362898 -285.704205) (xy 287.401019 -285.67308) (xy 287.44364 -285.648473)
			(xy 287.489656 -285.631021) (xy 287.537875 -285.621177) (xy 287.58705 -285.619196) (xy 287.635905 -285.625128)
			(xy 287.683176 -285.63882) (xy 287.727638 -285.659918) (xy 287.768141 -285.687874) (xy 287.803634 -285.721966)
			(xy 287.833199 -285.76131) (xy 287.85607 -285.804887) (xy 287.871654 -285.851568) (xy 287.879549 -285.900145)
			(xy 287.880044 -285.924752) (xy 288.218892 -285.924752) (xy 288.222852 -285.875698) (xy 288.234629 -285.827914)
			(xy 288.25392 -285.782638) (xy 288.280223 -285.741042) (xy 288.312858 -285.704205) (xy 288.350979 -285.67308)
			(xy 288.3936 -285.648473) (xy 288.439616 -285.631021) (xy 288.487835 -285.621177) (xy 288.53701 -285.619196)
			(xy 288.585865 -285.625128) (xy 288.633136 -285.63882) (xy 288.677598 -285.659918) (xy 288.718101 -285.687874)
			(xy 288.753594 -285.721966) (xy 288.783159 -285.76131) (xy 288.80603 -285.804887) (xy 288.821614 -285.851568)
			(xy 288.829509 -285.900145) (xy 288.830004 -285.924752) (xy 289.169106 -285.924752) (xy 289.173066 -285.875698)
			(xy 289.184843 -285.827914) (xy 289.204134 -285.782638) (xy 289.230437 -285.741042) (xy 289.263072 -285.704205)
			(xy 289.301193 -285.67308) (xy 289.343814 -285.648473) (xy 289.38983 -285.631021) (xy 289.438049 -285.621177)
			(xy 289.487224 -285.619196) (xy 289.536079 -285.625128) (xy 289.58335 -285.63882) (xy 289.627812 -285.659918)
			(xy 289.668315 -285.687874) (xy 289.703808 -285.721966) (xy 289.733373 -285.76131) (xy 289.756244 -285.804887)
			(xy 289.771828 -285.851568) (xy 289.779723 -285.900145) (xy 289.780218 -285.924752) (xy 290.119066 -285.924752)
			(xy 290.123026 -285.875698) (xy 290.134803 -285.827914) (xy 290.154094 -285.782638) (xy 290.180397 -285.741042)
			(xy 290.213032 -285.704205) (xy 290.251153 -285.67308) (xy 290.293774 -285.648473) (xy 290.33979 -285.631021)
			(xy 290.388009 -285.621177) (xy 290.437184 -285.619196) (xy 290.486039 -285.625128) (xy 290.53331 -285.63882)
			(xy 290.577772 -285.659918) (xy 290.618275 -285.687874) (xy 290.653768 -285.721966) (xy 290.683333 -285.76131)
			(xy 290.706204 -285.804887) (xy 290.721788 -285.851568) (xy 290.729683 -285.900145) (xy 290.730178 -285.924752)
			(xy 292.018986 -285.924752) (xy 292.022946 -285.875698) (xy 292.034723 -285.827914) (xy 292.054014 -285.782638)
			(xy 292.080317 -285.741042) (xy 292.112952 -285.704205) (xy 292.151073 -285.67308) (xy 292.193694 -285.648473)
			(xy 292.23971 -285.631021) (xy 292.287929 -285.621177) (xy 292.337104 -285.619196) (xy 292.385959 -285.625128)
			(xy 292.43323 -285.63882) (xy 292.477692 -285.659918) (xy 292.518195 -285.687874) (xy 292.553688 -285.721966)
			(xy 292.583253 -285.76131) (xy 292.606124 -285.804887) (xy 292.621708 -285.851568) (xy 292.629603 -285.900145)
			(xy 292.630098 -285.924752) (xy 292.968946 -285.924752) (xy 292.972906 -285.875698) (xy 292.984683 -285.827914)
			(xy 293.003974 -285.782638) (xy 293.030277 -285.741042) (xy 293.062912 -285.704205) (xy 293.101033 -285.67308)
			(xy 293.143654 -285.648473) (xy 293.18967 -285.631021) (xy 293.237889 -285.621177) (xy 293.287064 -285.619196)
			(xy 293.335919 -285.625128) (xy 293.38319 -285.63882) (xy 293.427652 -285.659918) (xy 293.468155 -285.687874)
			(xy 293.503648 -285.721966) (xy 293.533213 -285.76131) (xy 293.556084 -285.804887) (xy 293.571668 -285.851568)
			(xy 293.579563 -285.900145) (xy 293.580058 -285.924752) (xy 293.918906 -285.924752) (xy 293.922866 -285.875698)
			(xy 293.934643 -285.827914) (xy 293.953934 -285.782638) (xy 293.980237 -285.741042) (xy 294.012872 -285.704205)
			(xy 294.050993 -285.67308) (xy 294.093614 -285.648473) (xy 294.13963 -285.631021) (xy 294.187849 -285.621177)
			(xy 294.237024 -285.619196) (xy 294.285879 -285.625128) (xy 294.33315 -285.63882) (xy 294.377612 -285.659918)
			(xy 294.418115 -285.687874) (xy 294.453608 -285.721966) (xy 294.483173 -285.76131) (xy 294.506044 -285.804887)
			(xy 294.521628 -285.851568) (xy 294.529523 -285.900145) (xy 294.530018 -285.924752) (xy 294.86912 -285.924752)
			(xy 294.87308 -285.875698) (xy 294.884857 -285.827914) (xy 294.904148 -285.782638) (xy 294.930451 -285.741042)
			(xy 294.963086 -285.704205) (xy 295.001207 -285.67308) (xy 295.043828 -285.648473) (xy 295.089844 -285.631021)
			(xy 295.138063 -285.621177) (xy 295.187238 -285.619196) (xy 295.236093 -285.625128) (xy 295.283364 -285.63882)
			(xy 295.327826 -285.659918) (xy 295.368329 -285.687874) (xy 295.403822 -285.721966) (xy 295.433387 -285.76131)
			(xy 295.456258 -285.804887) (xy 295.471842 -285.851568) (xy 295.479737 -285.900145) (xy 295.480232 -285.924752)
			(xy 295.81908 -285.924752) (xy 295.82304 -285.875698) (xy 295.834817 -285.827914) (xy 295.854108 -285.782638)
			(xy 295.880411 -285.741042) (xy 295.913046 -285.704205) (xy 295.951167 -285.67308) (xy 295.993788 -285.648473)
			(xy 296.039804 -285.631021) (xy 296.088023 -285.621177) (xy 296.137198 -285.619196) (xy 296.186053 -285.625128)
			(xy 296.233324 -285.63882) (xy 296.277786 -285.659918) (xy 296.318289 -285.687874) (xy 296.353782 -285.721966)
			(xy 296.383347 -285.76131) (xy 296.406218 -285.804887) (xy 296.421802 -285.851568) (xy 296.429697 -285.900145)
			(xy 296.430192 -285.924752) (xy 296.76904 -285.924752) (xy 296.773 -285.875698) (xy 296.784777 -285.827914)
			(xy 296.804068 -285.782638) (xy 296.830371 -285.741042) (xy 296.863006 -285.704205) (xy 296.901127 -285.67308)
			(xy 296.943748 -285.648473) (xy 296.989764 -285.631021) (xy 297.037983 -285.621177) (xy 297.087158 -285.619196)
			(xy 297.136013 -285.625128) (xy 297.183284 -285.63882) (xy 297.227746 -285.659918) (xy 297.268249 -285.687874)
			(xy 297.303742 -285.721966) (xy 297.333307 -285.76131) (xy 297.356178 -285.804887) (xy 297.371762 -285.851568)
			(xy 297.379657 -285.900145) (xy 297.380152 -285.924752) (xy 297.719 -285.924752) (xy 297.72296 -285.875698)
			(xy 297.734737 -285.827914) (xy 297.754028 -285.782638) (xy 297.780331 -285.741042) (xy 297.812966 -285.704205)
			(xy 297.851087 -285.67308) (xy 297.893708 -285.648473) (xy 297.939724 -285.631021) (xy 297.987943 -285.621177)
			(xy 298.037118 -285.619196) (xy 298.085973 -285.625128) (xy 298.133244 -285.63882) (xy 298.177706 -285.659918)
			(xy 298.218209 -285.687874) (xy 298.253702 -285.721966) (xy 298.283267 -285.76131) (xy 298.306138 -285.804887)
			(xy 298.321722 -285.851568) (xy 298.329617 -285.900145) (xy 298.330112 -285.924752) (xy 298.66896 -285.924752)
			(xy 298.67292 -285.875698) (xy 298.684697 -285.827914) (xy 298.703988 -285.782638) (xy 298.730291 -285.741042)
			(xy 298.762926 -285.704205) (xy 298.801047 -285.67308) (xy 298.843668 -285.648473) (xy 298.889684 -285.631021)
			(xy 298.937903 -285.621177) (xy 298.987078 -285.619196) (xy 299.035933 -285.625128) (xy 299.083204 -285.63882)
			(xy 299.127666 -285.659918) (xy 299.168169 -285.687874) (xy 299.203662 -285.721966) (xy 299.233227 -285.76131)
			(xy 299.256098 -285.804887) (xy 299.271682 -285.851568) (xy 299.279577 -285.900145) (xy 299.280072 -285.924752)
			(xy 299.61892 -285.924752) (xy 299.62288 -285.875698) (xy 299.634657 -285.827914) (xy 299.653948 -285.782638)
			(xy 299.680251 -285.741042) (xy 299.712886 -285.704205) (xy 299.751007 -285.67308) (xy 299.793628 -285.648473)
			(xy 299.839644 -285.631021) (xy 299.887863 -285.621177) (xy 299.937038 -285.619196) (xy 299.985893 -285.625128)
			(xy 300.033164 -285.63882) (xy 300.077626 -285.659918) (xy 300.118129 -285.687874) (xy 300.153622 -285.721966)
			(xy 300.183187 -285.76131) (xy 300.206058 -285.804887) (xy 300.221642 -285.851568) (xy 300.229537 -285.900145)
			(xy 300.230032 -285.924752) (xy 300.56888 -285.924752) (xy 300.57284 -285.875698) (xy 300.584617 -285.827914)
			(xy 300.603908 -285.782638) (xy 300.630211 -285.741042) (xy 300.662846 -285.704205) (xy 300.700967 -285.67308)
			(xy 300.743588 -285.648473) (xy 300.789604 -285.631021) (xy 300.837823 -285.621177) (xy 300.886998 -285.619196)
			(xy 300.935853 -285.625128) (xy 300.983124 -285.63882) (xy 301.027586 -285.659918) (xy 301.068089 -285.687874)
			(xy 301.103582 -285.721966) (xy 301.133147 -285.76131) (xy 301.156018 -285.804887) (xy 301.171602 -285.851568)
			(xy 301.179497 -285.900145) (xy 301.179992 -285.924752) (xy 301.519094 -285.924752) (xy 301.523054 -285.875698)
			(xy 301.534831 -285.827914) (xy 301.554122 -285.782638) (xy 301.580425 -285.741042) (xy 301.61306 -285.704205)
			(xy 301.651181 -285.67308) (xy 301.693802 -285.648473) (xy 301.739818 -285.631021) (xy 301.788037 -285.621177)
			(xy 301.837212 -285.619196) (xy 301.886067 -285.625128) (xy 301.933338 -285.63882) (xy 301.9778 -285.659918)
			(xy 302.018303 -285.687874) (xy 302.053796 -285.721966) (xy 302.083361 -285.76131) (xy 302.106232 -285.804887)
			(xy 302.121816 -285.851568) (xy 302.129711 -285.900145) (xy 302.130206 -285.924752) (xy 302.469054 -285.924752)
			(xy 302.473014 -285.875698) (xy 302.484791 -285.827914) (xy 302.504082 -285.782638) (xy 302.530385 -285.741042)
			(xy 302.56302 -285.704205) (xy 302.601141 -285.67308) (xy 302.643762 -285.648473) (xy 302.689778 -285.631021)
			(xy 302.737997 -285.621177) (xy 302.787172 -285.619196) (xy 302.836027 -285.625128) (xy 302.883298 -285.63882)
			(xy 302.92776 -285.659918) (xy 302.968263 -285.687874) (xy 303.003756 -285.721966) (xy 303.033321 -285.76131)
			(xy 303.056192 -285.804887) (xy 303.071776 -285.851568) (xy 303.079671 -285.900145) (xy 303.080166 -285.924752)
			(xy 303.079671 -285.949359) (xy 303.071776 -285.997936) (xy 303.056192 -286.044617) (xy 303.033321 -286.088194)
			(xy 303.003756 -286.127538) (xy 302.968263 -286.16163) (xy 302.92776 -286.189586) (xy 302.883298 -286.210684)
			(xy 302.836027 -286.224376) (xy 302.787172 -286.230308) (xy 302.737997 -286.228327) (xy 302.689778 -286.218483)
			(xy 302.643762 -286.201031) (xy 302.601141 -286.176424) (xy 302.56302 -286.145299) (xy 302.530385 -286.108462)
			(xy 302.504082 -286.066866) (xy 302.484791 -286.02159) (xy 302.473014 -285.973806) (xy 302.469054 -285.924752)
			(xy 302.130206 -285.924752) (xy 302.129711 -285.949359) (xy 302.121816 -285.997936) (xy 302.106232 -286.044617)
			(xy 302.083361 -286.088194) (xy 302.053796 -286.127538) (xy 302.018303 -286.16163) (xy 301.9778 -286.189586)
			(xy 301.933338 -286.210684) (xy 301.886067 -286.224376) (xy 301.837212 -286.230308) (xy 301.788037 -286.228327)
			(xy 301.739818 -286.218483) (xy 301.693802 -286.201031) (xy 301.651181 -286.176424) (xy 301.61306 -286.145299)
			(xy 301.580425 -286.108462) (xy 301.554122 -286.066866) (xy 301.534831 -286.02159) (xy 301.523054 -285.973806)
			(xy 301.519094 -285.924752) (xy 301.179992 -285.924752) (xy 301.179497 -285.949359) (xy 301.171602 -285.997936)
			(xy 301.156018 -286.044617) (xy 301.133147 -286.088194) (xy 301.103582 -286.127538) (xy 301.068089 -286.16163)
			(xy 301.027586 -286.189586) (xy 300.983124 -286.210684) (xy 300.935853 -286.224376) (xy 300.886998 -286.230308)
			(xy 300.837823 -286.228327) (xy 300.789604 -286.218483) (xy 300.743588 -286.201031) (xy 300.700967 -286.176424)
			(xy 300.662846 -286.145299) (xy 300.630211 -286.108462) (xy 300.603908 -286.066866) (xy 300.584617 -286.02159)
			(xy 300.57284 -285.973806) (xy 300.56888 -285.924752) (xy 300.230032 -285.924752) (xy 300.229537 -285.949359)
			(xy 300.221642 -285.997936) (xy 300.206058 -286.044617) (xy 300.183187 -286.088194) (xy 300.153622 -286.127538)
			(xy 300.118129 -286.16163) (xy 300.077626 -286.189586) (xy 300.033164 -286.210684) (xy 299.985893 -286.224376)
			(xy 299.937038 -286.230308) (xy 299.887863 -286.228327) (xy 299.839644 -286.218483) (xy 299.793628 -286.201031)
			(xy 299.751007 -286.176424) (xy 299.712886 -286.145299) (xy 299.680251 -286.108462) (xy 299.653948 -286.066866)
			(xy 299.634657 -286.02159) (xy 299.62288 -285.973806) (xy 299.61892 -285.924752) (xy 299.280072 -285.924752)
			(xy 299.279577 -285.949359) (xy 299.271682 -285.997936) (xy 299.256098 -286.044617) (xy 299.233227 -286.088194)
			(xy 299.203662 -286.127538) (xy 299.168169 -286.16163) (xy 299.127666 -286.189586) (xy 299.083204 -286.210684)
			(xy 299.035933 -286.224376) (xy 298.987078 -286.230308) (xy 298.937903 -286.228327) (xy 298.889684 -286.218483)
			(xy 298.843668 -286.201031) (xy 298.801047 -286.176424) (xy 298.762926 -286.145299) (xy 298.730291 -286.108462)
			(xy 298.703988 -286.066866) (xy 298.684697 -286.02159) (xy 298.67292 -285.973806) (xy 298.66896 -285.924752)
			(xy 298.330112 -285.924752) (xy 298.329617 -285.949359) (xy 298.321722 -285.997936) (xy 298.306138 -286.044617)
			(xy 298.283267 -286.088194) (xy 298.253702 -286.127538) (xy 298.218209 -286.16163) (xy 298.177706 -286.189586)
			(xy 298.133244 -286.210684) (xy 298.085973 -286.224376) (xy 298.037118 -286.230308) (xy 297.987943 -286.228327)
			(xy 297.939724 -286.218483) (xy 297.893708 -286.201031) (xy 297.851087 -286.176424) (xy 297.812966 -286.145299)
			(xy 297.780331 -286.108462) (xy 297.754028 -286.066866) (xy 297.734737 -286.02159) (xy 297.72296 -285.973806)
			(xy 297.719 -285.924752) (xy 297.380152 -285.924752) (xy 297.379657 -285.949359) (xy 297.371762 -285.997936)
			(xy 297.356178 -286.044617) (xy 297.333307 -286.088194) (xy 297.303742 -286.127538) (xy 297.268249 -286.16163)
			(xy 297.227746 -286.189586) (xy 297.183284 -286.210684) (xy 297.136013 -286.224376) (xy 297.087158 -286.230308)
			(xy 297.037983 -286.228327) (xy 296.989764 -286.218483) (xy 296.943748 -286.201031) (xy 296.901127 -286.176424)
			(xy 296.863006 -286.145299) (xy 296.830371 -286.108462) (xy 296.804068 -286.066866) (xy 296.784777 -286.02159)
			(xy 296.773 -285.973806) (xy 296.76904 -285.924752) (xy 296.430192 -285.924752) (xy 296.429697 -285.949359)
			(xy 296.421802 -285.997936) (xy 296.406218 -286.044617) (xy 296.383347 -286.088194) (xy 296.353782 -286.127538)
			(xy 296.318289 -286.16163) (xy 296.277786 -286.189586) (xy 296.233324 -286.210684) (xy 296.186053 -286.224376)
			(xy 296.137198 -286.230308) (xy 296.088023 -286.228327) (xy 296.039804 -286.218483) (xy 295.993788 -286.201031)
			(xy 295.951167 -286.176424) (xy 295.913046 -286.145299) (xy 295.880411 -286.108462) (xy 295.854108 -286.066866)
			(xy 295.834817 -286.02159) (xy 295.82304 -285.973806) (xy 295.81908 -285.924752) (xy 295.480232 -285.924752)
			(xy 295.479737 -285.949359) (xy 295.471842 -285.997936) (xy 295.456258 -286.044617) (xy 295.433387 -286.088194)
			(xy 295.403822 -286.127538) (xy 295.368329 -286.16163) (xy 295.327826 -286.189586) (xy 295.283364 -286.210684)
			(xy 295.236093 -286.224376) (xy 295.187238 -286.230308) (xy 295.138063 -286.228327) (xy 295.089844 -286.218483)
			(xy 295.043828 -286.201031) (xy 295.001207 -286.176424) (xy 294.963086 -286.145299) (xy 294.930451 -286.108462)
			(xy 294.904148 -286.066866) (xy 294.884857 -286.02159) (xy 294.87308 -285.973806) (xy 294.86912 -285.924752)
			(xy 294.530018 -285.924752) (xy 294.529523 -285.949359) (xy 294.521628 -285.997936) (xy 294.506044 -286.044617)
			(xy 294.483173 -286.088194) (xy 294.453608 -286.127538) (xy 294.418115 -286.16163) (xy 294.377612 -286.189586)
			(xy 294.33315 -286.210684) (xy 294.285879 -286.224376) (xy 294.237024 -286.230308) (xy 294.187849 -286.228327)
			(xy 294.13963 -286.218483) (xy 294.093614 -286.201031) (xy 294.050993 -286.176424) (xy 294.012872 -286.145299)
			(xy 293.980237 -286.108462) (xy 293.953934 -286.066866) (xy 293.934643 -286.02159) (xy 293.922866 -285.973806)
			(xy 293.918906 -285.924752) (xy 293.580058 -285.924752) (xy 293.579563 -285.949359) (xy 293.571668 -285.997936)
			(xy 293.556084 -286.044617) (xy 293.533213 -286.088194) (xy 293.503648 -286.127538) (xy 293.468155 -286.16163)
			(xy 293.427652 -286.189586) (xy 293.38319 -286.210684) (xy 293.335919 -286.224376) (xy 293.287064 -286.230308)
			(xy 293.237889 -286.228327) (xy 293.18967 -286.218483) (xy 293.143654 -286.201031) (xy 293.101033 -286.176424)
			(xy 293.062912 -286.145299) (xy 293.030277 -286.108462) (xy 293.003974 -286.066866) (xy 292.984683 -286.02159)
			(xy 292.972906 -285.973806) (xy 292.968946 -285.924752) (xy 292.630098 -285.924752) (xy 292.629603 -285.949359)
			(xy 292.621708 -285.997936) (xy 292.606124 -286.044617) (xy 292.583253 -286.088194) (xy 292.553688 -286.127538)
			(xy 292.518195 -286.16163) (xy 292.477692 -286.189586) (xy 292.43323 -286.210684) (xy 292.385959 -286.224376)
			(xy 292.337104 -286.230308) (xy 292.287929 -286.228327) (xy 292.23971 -286.218483) (xy 292.193694 -286.201031)
			(xy 292.151073 -286.176424) (xy 292.112952 -286.145299) (xy 292.080317 -286.108462) (xy 292.054014 -286.066866)
			(xy 292.034723 -286.02159) (xy 292.022946 -285.973806) (xy 292.018986 -285.924752) (xy 290.730178 -285.924752)
			(xy 290.729683 -285.949359) (xy 290.721788 -285.997936) (xy 290.706204 -286.044617) (xy 290.683333 -286.088194)
			(xy 290.653768 -286.127538) (xy 290.618275 -286.16163) (xy 290.577772 -286.189586) (xy 290.53331 -286.210684)
			(xy 290.486039 -286.224376) (xy 290.437184 -286.230308) (xy 290.388009 -286.228327) (xy 290.33979 -286.218483)
			(xy 290.293774 -286.201031) (xy 290.251153 -286.176424) (xy 290.213032 -286.145299) (xy 290.180397 -286.108462)
			(xy 290.154094 -286.066866) (xy 290.134803 -286.02159) (xy 290.123026 -285.973806) (xy 290.119066 -285.924752)
			(xy 289.780218 -285.924752) (xy 289.779723 -285.949359) (xy 289.771828 -285.997936) (xy 289.756244 -286.044617)
			(xy 289.733373 -286.088194) (xy 289.703808 -286.127538) (xy 289.668315 -286.16163) (xy 289.627812 -286.189586)
			(xy 289.58335 -286.210684) (xy 289.536079 -286.224376) (xy 289.487224 -286.230308) (xy 289.438049 -286.228327)
			(xy 289.38983 -286.218483) (xy 289.343814 -286.201031) (xy 289.301193 -286.176424) (xy 289.263072 -286.145299)
			(xy 289.230437 -286.108462) (xy 289.204134 -286.066866) (xy 289.184843 -286.02159) (xy 289.173066 -285.973806)
			(xy 289.169106 -285.924752) (xy 288.830004 -285.924752) (xy 288.829509 -285.949359) (xy 288.821614 -285.997936)
			(xy 288.80603 -286.044617) (xy 288.783159 -286.088194) (xy 288.753594 -286.127538) (xy 288.718101 -286.16163)
			(xy 288.677598 -286.189586) (xy 288.633136 -286.210684) (xy 288.585865 -286.224376) (xy 288.53701 -286.230308)
			(xy 288.487835 -286.228327) (xy 288.439616 -286.218483) (xy 288.3936 -286.201031) (xy 288.350979 -286.176424)
			(xy 288.312858 -286.145299) (xy 288.280223 -286.108462) (xy 288.25392 -286.066866) (xy 288.234629 -286.02159)
			(xy 288.222852 -285.973806) (xy 288.218892 -285.924752) (xy 287.880044 -285.924752) (xy 287.879549 -285.949359)
			(xy 287.871654 -285.997936) (xy 287.85607 -286.044617) (xy 287.833199 -286.088194) (xy 287.803634 -286.127538)
			(xy 287.768141 -286.16163) (xy 287.727638 -286.189586) (xy 287.683176 -286.210684) (xy 287.635905 -286.224376)
			(xy 287.58705 -286.230308) (xy 287.537875 -286.228327) (xy 287.489656 -286.218483) (xy 287.44364 -286.201031)
			(xy 287.401019 -286.176424) (xy 287.362898 -286.145299) (xy 287.330263 -286.108462) (xy 287.30396 -286.066866)
			(xy 287.284669 -286.02159) (xy 287.272892 -285.973806) (xy 287.268932 -285.924752) (xy 286.930084 -285.924752)
			(xy 286.929589 -285.949359) (xy 286.921694 -285.997936) (xy 286.90611 -286.044617) (xy 286.883239 -286.088194)
			(xy 286.853674 -286.127538) (xy 286.818181 -286.16163) (xy 286.777678 -286.189586) (xy 286.733216 -286.210684)
			(xy 286.685945 -286.224376) (xy 286.63709 -286.230308) (xy 286.587915 -286.228327) (xy 286.539696 -286.218483)
			(xy 286.49368 -286.201031) (xy 286.451059 -286.176424) (xy 286.412938 -286.145299) (xy 286.380303 -286.108462)
			(xy 286.354 -286.066866) (xy 286.334709 -286.02159) (xy 286.322932 -285.973806) (xy 286.318972 -285.924752)
			(xy 285.980124 -285.924752) (xy 285.979629 -285.949359) (xy 285.971734 -285.997936) (xy 285.95615 -286.044617)
			(xy 285.933279 -286.088194) (xy 285.903714 -286.127538) (xy 285.868221 -286.16163) (xy 285.827718 -286.189586)
			(xy 285.783256 -286.210684) (xy 285.735985 -286.224376) (xy 285.68713 -286.230308) (xy 285.637955 -286.228327)
			(xy 285.589736 -286.218483) (xy 285.54372 -286.201031) (xy 285.501099 -286.176424) (xy 285.462978 -286.145299)
			(xy 285.430343 -286.108462) (xy 285.40404 -286.066866) (xy 285.384749 -286.02159) (xy 285.372972 -285.973806)
			(xy 285.369012 -285.924752) (xy 285.030164 -285.924752) (xy 285.029669 -285.949359) (xy 285.021774 -285.997936)
			(xy 285.00619 -286.044617) (xy 284.983319 -286.088194) (xy 284.953754 -286.127538) (xy 284.918261 -286.16163)
			(xy 284.877758 -286.189586) (xy 284.833296 -286.210684) (xy 284.786025 -286.224376) (xy 284.73717 -286.230308)
			(xy 284.687995 -286.228327) (xy 284.639776 -286.218483) (xy 284.59376 -286.201031) (xy 284.551139 -286.176424)
			(xy 284.513018 -286.145299) (xy 284.480383 -286.108462) (xy 284.45408 -286.066866) (xy 284.434789 -286.02159)
			(xy 284.423012 -285.973806) (xy 284.419052 -285.924752) (xy 284.080204 -285.924752) (xy 284.079709 -285.949359)
			(xy 284.071814 -285.997936) (xy 284.05623 -286.044617) (xy 284.033359 -286.088194) (xy 284.003794 -286.127538)
			(xy 283.968301 -286.16163) (xy 283.927798 -286.189586) (xy 283.883336 -286.210684) (xy 283.836065 -286.224376)
			(xy 283.78721 -286.230308) (xy 283.738035 -286.228327) (xy 283.689816 -286.218483) (xy 283.6438 -286.201031)
			(xy 283.601179 -286.176424) (xy 283.563058 -286.145299) (xy 283.530423 -286.108462) (xy 283.50412 -286.066866)
			(xy 283.484829 -286.02159) (xy 283.473052 -285.973806) (xy 283.469092 -285.924752) (xy 283.130244 -285.924752)
			(xy 283.129749 -285.949359) (xy 283.121854 -285.997936) (xy 283.10627 -286.044617) (xy 283.083399 -286.088194)
			(xy 283.053834 -286.127538) (xy 283.018341 -286.16163) (xy 282.977838 -286.189586) (xy 282.933376 -286.210684)
			(xy 282.886105 -286.224376) (xy 282.83725 -286.230308) (xy 282.788075 -286.228327) (xy 282.739856 -286.218483)
			(xy 282.69384 -286.201031) (xy 282.651219 -286.176424) (xy 282.613098 -286.145299) (xy 282.580463 -286.108462)
			(xy 282.55416 -286.066866) (xy 282.534869 -286.02159) (xy 282.523092 -285.973806) (xy 282.519132 -285.924752)
			(xy 282.18003 -285.924752) (xy 282.179535 -285.949359) (xy 282.17164 -285.997936) (xy 282.156056 -286.044617)
			(xy 282.133185 -286.088194) (xy 282.10362 -286.127538) (xy 282.068127 -286.16163) (xy 282.027624 -286.189586)
			(xy 281.983162 -286.210684) (xy 281.935891 -286.224376) (xy 281.887036 -286.230308) (xy 281.837861 -286.228327)
			(xy 281.789642 -286.218483) (xy 281.743626 -286.201031) (xy 281.701005 -286.176424) (xy 281.662884 -286.145299)
			(xy 281.630249 -286.108462) (xy 281.603946 -286.066866) (xy 281.584655 -286.02159) (xy 281.572878 -285.973806)
			(xy 281.568918 -285.924752) (xy 281.23007 -285.924752) (xy 281.229575 -285.949359) (xy 281.22168 -285.997936)
			(xy 281.206096 -286.044617) (xy 281.183225 -286.088194) (xy 281.15366 -286.127538) (xy 281.118167 -286.16163)
			(xy 281.077664 -286.189586) (xy 281.033202 -286.210684) (xy 280.985931 -286.224376) (xy 280.937076 -286.230308)
			(xy 280.887901 -286.228327) (xy 280.839682 -286.218483) (xy 280.793666 -286.201031) (xy 280.751045 -286.176424)
			(xy 280.712924 -286.145299) (xy 280.680289 -286.108462) (xy 280.653986 -286.066866) (xy 280.634695 -286.02159)
			(xy 280.622918 -285.973806) (xy 280.618958 -285.924752) (xy 280.28011 -285.924752) (xy 280.279615 -285.949359)
			(xy 280.27172 -285.997936) (xy 280.256136 -286.044617) (xy 280.233265 -286.088194) (xy 280.2037 -286.127538)
			(xy 280.168207 -286.16163) (xy 280.127704 -286.189586) (xy 280.083242 -286.210684) (xy 280.035971 -286.224376)
			(xy 279.987116 -286.230308) (xy 279.937941 -286.228327) (xy 279.889722 -286.218483) (xy 279.843706 -286.201031)
			(xy 279.801085 -286.176424) (xy 279.762964 -286.145299) (xy 279.730329 -286.108462) (xy 279.704026 -286.066866)
			(xy 279.684735 -286.02159) (xy 279.672958 -285.973806) (xy 279.668998 -285.924752) (xy 279.33015 -285.924752)
			(xy 279.329655 -285.949359) (xy 279.32176 -285.997936) (xy 279.306176 -286.044617) (xy 279.283305 -286.088194)
			(xy 279.25374 -286.127538) (xy 279.218247 -286.16163) (xy 279.177744 -286.189586) (xy 279.133282 -286.210684)
			(xy 279.086011 -286.224376) (xy 279.037156 -286.230308) (xy 278.987981 -286.228327) (xy 278.939762 -286.218483)
			(xy 278.893746 -286.201031) (xy 278.851125 -286.176424) (xy 278.813004 -286.145299) (xy 278.780369 -286.108462)
			(xy 278.754066 -286.066866) (xy 278.734775 -286.02159) (xy 278.722998 -285.973806) (xy 278.719038 -285.924752)
			(xy 278.38019 -285.924752) (xy 278.379695 -285.949359) (xy 278.3718 -285.997936) (xy 278.356216 -286.044617)
			(xy 278.333345 -286.088194) (xy 278.30378 -286.127538) (xy 278.268287 -286.16163) (xy 278.227784 -286.189586)
			(xy 278.183322 -286.210684) (xy 278.136051 -286.224376) (xy 278.087196 -286.230308) (xy 278.038021 -286.228327)
			(xy 277.989802 -286.218483) (xy 277.943786 -286.201031) (xy 277.901165 -286.176424) (xy 277.863044 -286.145299)
			(xy 277.830409 -286.108462) (xy 277.804106 -286.066866) (xy 277.784815 -286.02159) (xy 277.773038 -285.973806)
			(xy 277.769078 -285.924752) (xy 277.43023 -285.924752) (xy 277.429735 -285.949359) (xy 277.42184 -285.997936)
			(xy 277.406256 -286.044617) (xy 277.383385 -286.088194) (xy 277.35382 -286.127538) (xy 277.318327 -286.16163)
			(xy 277.277824 -286.189586) (xy 277.233362 -286.210684) (xy 277.186091 -286.224376) (xy 277.137236 -286.230308)
			(xy 277.088061 -286.228327) (xy 277.039842 -286.218483) (xy 276.993826 -286.201031) (xy 276.951205 -286.176424)
			(xy 276.913084 -286.145299) (xy 276.880449 -286.108462) (xy 276.854146 -286.066866) (xy 276.834855 -286.02159)
			(xy 276.823078 -285.973806) (xy 276.819118 -285.924752) (xy 276.507448 -285.924752) (xy 276.341586 -286.090614)
			(xy 276.334191 -286.097468) (xy 276.315592 -286.10521) (xy 276.305518 -286.1056) (xy 273.595338 -286.1056)
			(xy 273.584316 -286.106133) (xy 273.564289 -286.115342) (xy 273.55673 -286.12338) (xy 273.540792 -286.141269)
			(xy 273.504326 -286.172342) (xy 273.463454 -286.197338) (xy 273.41918 -286.215644) (xy 273.37259 -286.22681)
			(xy 273.324828 -286.230563) (xy 273.277066 -286.22681) (xy 273.230476 -286.215644) (xy 273.186202 -286.197338)
			(xy 273.14533 -286.172342) (xy 273.108864 -286.141269) (xy 273.092926 -286.12338) (xy 273.085355 -286.115354)
			(xy 273.065338 -286.106128) (xy 273.054318 -286.1056) (xy 272.645378 -286.1056) (xy 272.634362 -286.106145)
			(xy 272.614353 -286.115369) (xy 272.60677 -286.12338) (xy 272.590832 -286.141269) (xy 272.554366 -286.172342)
			(xy 272.513494 -286.197338) (xy 272.46922 -286.215644) (xy 272.42263 -286.22681) (xy 272.374868 -286.230563)
			(xy 272.327106 -286.22681) (xy 272.280516 -286.215644) (xy 272.236242 -286.197338) (xy 272.19537 -286.172342)
			(xy 272.158904 -286.141269) (xy 272.142966 -286.12338) (xy 272.135391 -286.115364) (xy 272.115374 -286.106161)
			(xy 272.104358 -286.1056) (xy 271.695418 -286.1056) (xy 271.684398 -286.106137) (xy 271.664377 -286.115351)
			(xy 271.65681 -286.12338) (xy 271.640872 -286.141269) (xy 271.604406 -286.172342) (xy 271.563534 -286.197338)
			(xy 271.51926 -286.215644) (xy 271.47267 -286.22681) (xy 271.424908 -286.230563) (xy 271.377146 -286.22681)
			(xy 271.330556 -286.215644) (xy 271.286282 -286.197338) (xy 271.24541 -286.172342) (xy 271.208944 -286.141269)
			(xy 271.193006 -286.12338) (xy 271.185433 -286.115358) (xy 271.165417 -286.106139) (xy 271.154398 -286.1056)
			(xy 270.745458 -286.1056) (xy 270.734444 -286.106149) (xy 270.714441 -286.115378) (xy 270.70685 -286.12338)
			(xy 270.690912 -286.141269) (xy 270.654446 -286.172342) (xy 270.613574 -286.197338) (xy 270.5693 -286.215644)
			(xy 270.52271 -286.22681) (xy 270.474948 -286.230563) (xy 270.427186 -286.22681) (xy 270.380596 -286.215644)
			(xy 270.336322 -286.197338) (xy 270.29545 -286.172342) (xy 270.258984 -286.141269) (xy 270.243046 -286.12338)
			(xy 270.235476 -286.115351) (xy 270.215459 -286.106117) (xy 270.204438 -286.1056) (xy 269.795244 -286.1056)
			(xy 269.784221 -286.106132) (xy 269.764192 -286.11534) (xy 269.756636 -286.12338) (xy 269.740698 -286.141269)
			(xy 269.704232 -286.172342) (xy 269.66336 -286.197338) (xy 269.619086 -286.215644) (xy 269.572496 -286.22681)
			(xy 269.524734 -286.230563) (xy 269.476972 -286.22681) (xy 269.430382 -286.215644) (xy 269.386108 -286.197338)
			(xy 269.345236 -286.172342) (xy 269.30877 -286.141269) (xy 269.292832 -286.12338) (xy 269.285261 -286.115353)
			(xy 269.265244 -286.106125) (xy 269.254224 -286.1056) (xy 268.845284 -286.1056) (xy 268.834267 -286.106144)
			(xy 268.814257 -286.115367) (xy 268.806676 -286.12338) (xy 268.790738 -286.141269) (xy 268.754272 -286.172342)
			(xy 268.7134 -286.197338) (xy 268.669126 -286.215644) (xy 268.622536 -286.22681) (xy 268.574774 -286.230563)
			(xy 268.527012 -286.22681) (xy 268.480422 -286.215644) (xy 268.436148 -286.197338) (xy 268.395276 -286.172342)
			(xy 268.35881 -286.141269) (xy 268.342872 -286.12338) (xy 268.335297 -286.115363) (xy 268.31528 -286.106158)
			(xy 268.304264 -286.1056) (xy 264.39749 -286.1056) (xy 264.385827 -286.106176) (xy 264.36492 -286.116512)
			(xy 264.357358 -286.125412) (xy 264.30097 -286.199072) (xy 264.296398 -286.221678) (xy 264.299446 -286.233362)
			(xy 264.305499 -286.257549) (xy 264.312 -286.306984) (xy 264.3124 -286.331914) (xy 264.311836 -286.361293)
			(xy 264.305844 -286.399732) (xy 305.793914 -286.399732) (xy 305.797874 -286.350678) (xy 305.809651 -286.302894)
			(xy 305.828942 -286.257618) (xy 305.855245 -286.216022) (xy 305.88788 -286.179185) (xy 305.926001 -286.14806)
			(xy 305.968622 -286.123453) (xy 306.014638 -286.106001) (xy 306.062857 -286.096157) (xy 306.112032 -286.094176)
			(xy 306.160887 -286.100108) (xy 306.208158 -286.1138) (xy 306.25262 -286.134898) (xy 306.293123 -286.162854)
			(xy 306.328616 -286.196946) (xy 306.358181 -286.23629) (xy 306.381052 -286.279867) (xy 306.396636 -286.326548)
			(xy 306.404531 -286.375125) (xy 306.405026 -286.399732) (xy 306.744128 -286.399732) (xy 306.748088 -286.350678)
			(xy 306.759865 -286.302894) (xy 306.779156 -286.257618) (xy 306.805459 -286.216022) (xy 306.838094 -286.179185)
			(xy 306.876215 -286.14806) (xy 306.918836 -286.123453) (xy 306.964852 -286.106001) (xy 307.013071 -286.096157)
			(xy 307.062246 -286.094176) (xy 307.111101 -286.100108) (xy 307.158372 -286.1138) (xy 307.202834 -286.134898)
			(xy 307.243337 -286.162854) (xy 307.27883 -286.196946) (xy 307.308395 -286.23629) (xy 307.331266 -286.279867)
			(xy 307.34685 -286.326548) (xy 307.354745 -286.375125) (xy 307.35524 -286.399732) (xy 307.694088 -286.399732)
			(xy 307.698048 -286.350678) (xy 307.709825 -286.302894) (xy 307.729116 -286.257618) (xy 307.755419 -286.216022)
			(xy 307.788054 -286.179185) (xy 307.826175 -286.14806) (xy 307.868796 -286.123453) (xy 307.914812 -286.106001)
			(xy 307.963031 -286.096157) (xy 308.012206 -286.094176) (xy 308.061061 -286.100108) (xy 308.108332 -286.1138)
			(xy 308.152794 -286.134898) (xy 308.193297 -286.162854) (xy 308.22879 -286.196946) (xy 308.258355 -286.23629)
			(xy 308.281226 -286.279867) (xy 308.29681 -286.326548) (xy 308.304705 -286.375125) (xy 308.3052 -286.399732)
			(xy 308.304705 -286.424339) (xy 308.304485 -286.425694) (xy 308.623204 -286.425694) (xy 308.623204 -286.374278)
			(xy 308.631247 -286.323496) (xy 308.647135 -286.274597) (xy 308.670478 -286.228785) (xy 308.700699 -286.187189)
			(xy 308.737055 -286.150833) (xy 308.778651 -286.120612) (xy 308.824463 -286.097269) (xy 308.873362 -286.081381)
			(xy 308.924144 -286.073338) (xy 308.97556 -286.073338) (xy 309.026342 -286.081381) (xy 309.075241 -286.097269)
			(xy 309.121053 -286.120612) (xy 309.162649 -286.150833) (xy 309.199005 -286.187189) (xy 309.229226 -286.228785)
			(xy 309.252569 -286.274597) (xy 309.268457 -286.323496) (xy 309.2765 -286.374278) (xy 309.277004 -286.399986)
			(xy 309.2765 -286.425694) (xy 309.573164 -286.425694) (xy 309.573164 -286.374278) (xy 309.581207 -286.323496)
			(xy 309.597095 -286.274597) (xy 309.620438 -286.228785) (xy 309.650659 -286.187189) (xy 309.687015 -286.150833)
			(xy 309.728611 -286.120612) (xy 309.774423 -286.097269) (xy 309.823322 -286.081381) (xy 309.874104 -286.073338)
			(xy 309.92552 -286.073338) (xy 309.976302 -286.081381) (xy 310.025201 -286.097269) (xy 310.071013 -286.120612)
			(xy 310.112609 -286.150833) (xy 310.148965 -286.187189) (xy 310.179186 -286.228785) (xy 310.202529 -286.274597)
			(xy 310.218417 -286.323496) (xy 310.22646 -286.374278) (xy 310.226959 -286.399732) (xy 310.543968 -286.399732)
			(xy 310.547928 -286.350678) (xy 310.559705 -286.302894) (xy 310.578996 -286.257618) (xy 310.605299 -286.216022)
			(xy 310.637934 -286.179185) (xy 310.676055 -286.14806) (xy 310.718676 -286.123453) (xy 310.764692 -286.106001)
			(xy 310.812911 -286.096157) (xy 310.862086 -286.094176) (xy 310.910941 -286.100108) (xy 310.958212 -286.1138)
			(xy 311.002674 -286.134898) (xy 311.043177 -286.162854) (xy 311.07867 -286.196946) (xy 311.108235 -286.23629)
			(xy 311.131106 -286.279867) (xy 311.14669 -286.326548) (xy 311.154585 -286.375125) (xy 311.15508 -286.399732)
			(xy 311.154585 -286.424339) (xy 311.154406 -286.42544) (xy 311.473084 -286.42544) (xy 311.473084 -286.374024)
			(xy 311.481127 -286.323242) (xy 311.497015 -286.274343) (xy 311.520358 -286.228531) (xy 311.550579 -286.186935)
			(xy 311.586935 -286.150579) (xy 311.628531 -286.120358) (xy 311.674343 -286.097015) (xy 311.723242 -286.081127)
			(xy 311.774024 -286.073084) (xy 311.82544 -286.073084) (xy 311.876222 -286.081127) (xy 311.925121 -286.097015)
			(xy 311.970933 -286.120358) (xy 312.012529 -286.150579) (xy 312.048885 -286.186935) (xy 312.079106 -286.228531)
			(xy 312.102449 -286.274343) (xy 312.118337 -286.323242) (xy 312.12638 -286.374024) (xy 312.126884 -286.399732)
			(xy 312.12638 -286.42544) (xy 312.423044 -286.42544) (xy 312.423044 -286.374024) (xy 312.431087 -286.323242)
			(xy 312.446975 -286.274343) (xy 312.470318 -286.228531) (xy 312.500539 -286.186935) (xy 312.536895 -286.150579)
			(xy 312.578491 -286.120358) (xy 312.624303 -286.097015) (xy 312.673202 -286.081127) (xy 312.723984 -286.073084)
			(xy 312.7754 -286.073084) (xy 312.826182 -286.081127) (xy 312.875081 -286.097015) (xy 312.920893 -286.120358)
			(xy 312.962489 -286.150579) (xy 312.998845 -286.186935) (xy 313.029066 -286.228531) (xy 313.052409 -286.274343)
			(xy 313.068297 -286.323242) (xy 313.07634 -286.374024) (xy 313.076844 -286.399732) (xy 313.394102 -286.399732)
			(xy 313.398062 -286.350678) (xy 313.409839 -286.302894) (xy 313.42913 -286.257618) (xy 313.455433 -286.216022)
			(xy 313.488068 -286.179185) (xy 313.526189 -286.14806) (xy 313.56881 -286.123453) (xy 313.614826 -286.106001)
			(xy 313.663045 -286.096157) (xy 313.71222 -286.094176) (xy 313.761075 -286.100108) (xy 313.808346 -286.1138)
			(xy 313.852808 -286.134898) (xy 313.893311 -286.162854) (xy 313.928804 -286.196946) (xy 313.958369 -286.23629)
			(xy 313.98124 -286.279867) (xy 313.996824 -286.326548) (xy 314.004719 -286.375125) (xy 314.005214 -286.399732)
			(xy 314.344062 -286.399732) (xy 314.348022 -286.350678) (xy 314.359799 -286.302894) (xy 314.37909 -286.257618)
			(xy 314.405393 -286.216022) (xy 314.438028 -286.179185) (xy 314.476149 -286.14806) (xy 314.51877 -286.123453)
			(xy 314.564786 -286.106001) (xy 314.613005 -286.096157) (xy 314.66218 -286.094176) (xy 314.711035 -286.100108)
			(xy 314.758306 -286.1138) (xy 314.802768 -286.134898) (xy 314.843271 -286.162854) (xy 314.878764 -286.196946)
			(xy 314.908329 -286.23629) (xy 314.9312 -286.279867) (xy 314.946784 -286.326548) (xy 314.954679 -286.375125)
			(xy 314.955174 -286.399732) (xy 314.954679 -286.424339) (xy 314.946784 -286.472916) (xy 314.9312 -286.519597)
			(xy 314.908329 -286.563174) (xy 314.878764 -286.602518) (xy 314.843271 -286.63661) (xy 314.802768 -286.664566)
			(xy 314.758306 -286.685664) (xy 314.711035 -286.699356) (xy 314.66218 -286.705288) (xy 314.613005 -286.703307)
			(xy 314.564786 -286.693463) (xy 314.51877 -286.676011) (xy 314.476149 -286.651404) (xy 314.438028 -286.620279)
			(xy 314.405393 -286.583442) (xy 314.37909 -286.541846) (xy 314.359799 -286.49657) (xy 314.348022 -286.448786)
			(xy 314.344062 -286.399732) (xy 314.005214 -286.399732) (xy 314.004719 -286.424339) (xy 313.996824 -286.472916)
			(xy 313.98124 -286.519597) (xy 313.958369 -286.563174) (xy 313.928804 -286.602518) (xy 313.893311 -286.63661)
			(xy 313.852808 -286.664566) (xy 313.808346 -286.685664) (xy 313.761075 -286.699356) (xy 313.71222 -286.705288)
			(xy 313.663045 -286.703307) (xy 313.614826 -286.693463) (xy 313.56881 -286.676011) (xy 313.526189 -286.651404)
			(xy 313.488068 -286.620279) (xy 313.455433 -286.583442) (xy 313.42913 -286.541846) (xy 313.409839 -286.49657)
			(xy 313.398062 -286.448786) (xy 313.394102 -286.399732) (xy 313.076844 -286.399732) (xy 313.07634 -286.42544)
			(xy 313.068297 -286.476222) (xy 313.052409 -286.525121) (xy 313.029066 -286.570933) (xy 312.998845 -286.612529)
			(xy 312.962489 -286.648885) (xy 312.920893 -286.679106) (xy 312.875081 -286.702449) (xy 312.826182 -286.718337)
			(xy 312.7754 -286.72638) (xy 312.723984 -286.72638) (xy 312.673202 -286.718337) (xy 312.624303 -286.702449)
			(xy 312.578491 -286.679106) (xy 312.536895 -286.648885) (xy 312.500539 -286.612529) (xy 312.470318 -286.570933)
			(xy 312.446975 -286.525121) (xy 312.431087 -286.476222) (xy 312.423044 -286.42544) (xy 312.12638 -286.42544)
			(xy 312.118337 -286.476222) (xy 312.102449 -286.525121) (xy 312.079106 -286.570933) (xy 312.048885 -286.612529)
			(xy 312.012529 -286.648885) (xy 311.970933 -286.679106) (xy 311.925121 -286.702449) (xy 311.876222 -286.718337)
			(xy 311.82544 -286.72638) (xy 311.774024 -286.72638) (xy 311.723242 -286.718337) (xy 311.674343 -286.702449)
			(xy 311.628531 -286.679106) (xy 311.586935 -286.648885) (xy 311.550579 -286.612529) (xy 311.520358 -286.570933)
			(xy 311.497015 -286.525121) (xy 311.481127 -286.476222) (xy 311.473084 -286.42544) (xy 311.154406 -286.42544)
			(xy 311.14669 -286.472916) (xy 311.131106 -286.519597) (xy 311.108235 -286.563174) (xy 311.07867 -286.602518)
			(xy 311.043177 -286.63661) (xy 311.002674 -286.664566) (xy 310.958212 -286.685664) (xy 310.910941 -286.699356)
			(xy 310.862086 -286.705288) (xy 310.812911 -286.703307) (xy 310.764692 -286.693463) (xy 310.718676 -286.676011)
			(xy 310.676055 -286.651404) (xy 310.637934 -286.620279) (xy 310.605299 -286.583442) (xy 310.578996 -286.541846)
			(xy 310.559705 -286.49657) (xy 310.547928 -286.448786) (xy 310.543968 -286.399732) (xy 310.226959 -286.399732)
			(xy 310.226964 -286.399986) (xy 310.22646 -286.425694) (xy 310.218417 -286.476476) (xy 310.202529 -286.525375)
			(xy 310.179186 -286.571187) (xy 310.148965 -286.612783) (xy 310.112609 -286.649139) (xy 310.071013 -286.67936)
			(xy 310.025201 -286.702703) (xy 309.976302 -286.718591) (xy 309.92552 -286.726634) (xy 309.874104 -286.726634)
			(xy 309.823322 -286.718591) (xy 309.774423 -286.702703) (xy 309.728611 -286.67936) (xy 309.687015 -286.649139)
			(xy 309.650659 -286.612783) (xy 309.620438 -286.571187) (xy 309.597095 -286.525375) (xy 309.581207 -286.476476)
			(xy 309.573164 -286.425694) (xy 309.2765 -286.425694) (xy 309.268457 -286.476476) (xy 309.252569 -286.525375)
			(xy 309.229226 -286.571187) (xy 309.199005 -286.612783) (xy 309.162649 -286.649139) (xy 309.121053 -286.67936)
			(xy 309.075241 -286.702703) (xy 309.026342 -286.718591) (xy 308.97556 -286.726634) (xy 308.924144 -286.726634)
			(xy 308.873362 -286.718591) (xy 308.824463 -286.702703) (xy 308.778651 -286.67936) (xy 308.737055 -286.649139)
			(xy 308.700699 -286.612783) (xy 308.670478 -286.571187) (xy 308.647135 -286.525375) (xy 308.631247 -286.476476)
			(xy 308.623204 -286.425694) (xy 308.304485 -286.425694) (xy 308.29681 -286.472916) (xy 308.281226 -286.519597)
			(xy 308.258355 -286.563174) (xy 308.22879 -286.602518) (xy 308.193297 -286.63661) (xy 308.152794 -286.664566)
			(xy 308.108332 -286.685664) (xy 308.061061 -286.699356) (xy 308.012206 -286.705288) (xy 307.963031 -286.703307)
			(xy 307.914812 -286.693463) (xy 307.868796 -286.676011) (xy 307.826175 -286.651404) (xy 307.788054 -286.620279)
			(xy 307.755419 -286.583442) (xy 307.729116 -286.541846) (xy 307.709825 -286.49657) (xy 307.698048 -286.448786)
			(xy 307.694088 -286.399732) (xy 307.35524 -286.399732) (xy 307.354745 -286.424339) (xy 307.34685 -286.472916)
			(xy 307.331266 -286.519597) (xy 307.308395 -286.563174) (xy 307.27883 -286.602518) (xy 307.243337 -286.63661)
			(xy 307.202834 -286.664566) (xy 307.158372 -286.685664) (xy 307.111101 -286.699356) (xy 307.062246 -286.705288)
			(xy 307.013071 -286.703307) (xy 306.964852 -286.693463) (xy 306.918836 -286.676011) (xy 306.876215 -286.651404)
			(xy 306.838094 -286.620279) (xy 306.805459 -286.583442) (xy 306.779156 -286.541846) (xy 306.759865 -286.49657)
			(xy 306.748088 -286.448786) (xy 306.744128 -286.399732) (xy 306.405026 -286.399732) (xy 306.404531 -286.424339)
			(xy 306.396636 -286.472916) (xy 306.381052 -286.519597) (xy 306.358181 -286.563174) (xy 306.328616 -286.602518)
			(xy 306.293123 -286.63661) (xy 306.25262 -286.664566) (xy 306.208158 -286.685664) (xy 306.160887 -286.699356)
			(xy 306.112032 -286.705288) (xy 306.062857 -286.703307) (xy 306.014638 -286.693463) (xy 305.968622 -286.676011)
			(xy 305.926001 -286.651404) (xy 305.88788 -286.620279) (xy 305.855245 -286.583442) (xy 305.828942 -286.541846)
			(xy 305.809651 -286.49657) (xy 305.797874 -286.448786) (xy 305.793914 -286.399732) (xy 264.305844 -286.399732)
			(xy 264.302786 -286.419352) (xy 264.284947 -286.475339) (xy 264.258741 -286.527931) (xy 264.224787 -286.575888)
			(xy 264.183887 -286.618076) (xy 264.160762 -286.636206) (xy 264.151364 -286.643572) (xy 264.14095 -286.664146)
			(xy 264.139426 -286.768032) (xy 264.149332 -286.789114) (xy 264.158476 -286.79648) (xy 264.1803 -286.814711)
			(xy 264.218829 -286.856533) (xy 264.25073 -286.903606) (xy 264.275297 -286.954889) (xy 264.291988 -287.009248)
			(xy 264.300433 -287.065482) (xy 264.30097 -287.093914) (xy 264.934444 -287.093914) (xy 264.938515 -287.038292)
			(xy 264.950641 -286.983855) (xy 264.970564 -286.931764) (xy 264.99786 -286.883129) (xy 265.031946 -286.838986)
			(xy 265.072095 -286.800277) (xy 265.117453 -286.767826) (xy 265.167053 -286.742325) (xy 265.219837 -286.724318)
			(xy 265.27468 -286.714188) (xy 265.330414 -286.712151) (xy 265.385851 -286.718251) (xy 265.439808 -286.732357)
			(xy 265.491137 -286.754169) (xy 265.538743 -286.783223) (xy 265.581611 -286.818898) (xy 265.618828 -286.860435)
			(xy 265.649601 -286.906948) (xy 265.673273 -286.957445) (xy 265.689341 -287.010852) (xy 265.697461 -287.066028)
			(xy 265.69797 -287.093914) (xy 265.820904 -287.093914) (xy 265.824975 -287.038292) (xy 265.837101 -286.983855)
			(xy 265.857024 -286.931764) (xy 265.88432 -286.883129) (xy 265.918406 -286.838986) (xy 265.958555 -286.800277)
			(xy 266.003913 -286.767826) (xy 266.053513 -286.742325) (xy 266.106297 -286.724318) (xy 266.16114 -286.714188)
			(xy 266.216874 -286.712151) (xy 266.272311 -286.718251) (xy 266.326268 -286.732357) (xy 266.377597 -286.754169)
			(xy 266.425203 -286.783223) (xy 266.468071 -286.818898) (xy 266.505288 -286.860435) (xy 266.514902 -286.874966)
			(xy 268.26897 -286.874966) (xy 268.27293 -286.825912) (xy 268.284707 -286.778128) (xy 268.303998 -286.732852)
			(xy 268.330301 -286.691256) (xy 268.362936 -286.654419) (xy 268.401057 -286.623294) (xy 268.443678 -286.598687)
			(xy 268.489694 -286.581235) (xy 268.537913 -286.571391) (xy 268.587088 -286.56941) (xy 268.635943 -286.575342)
			(xy 268.683214 -286.589034) (xy 268.727676 -286.610132) (xy 268.768179 -286.638088) (xy 268.803672 -286.67218)
			(xy 268.833237 -286.711524) (xy 268.856108 -286.755101) (xy 268.871692 -286.801782) (xy 268.879587 -286.850359)
			(xy 268.880082 -286.874966) (xy 269.21893 -286.874966) (xy 269.22289 -286.825912) (xy 269.234667 -286.778128)
			(xy 269.253958 -286.732852) (xy 269.280261 -286.691256) (xy 269.312896 -286.654419) (xy 269.351017 -286.623294)
			(xy 269.393638 -286.598687) (xy 269.439654 -286.581235) (xy 269.487873 -286.571391) (xy 269.537048 -286.56941)
			(xy 269.585903 -286.575342) (xy 269.633174 -286.589034) (xy 269.677636 -286.610132) (xy 269.718139 -286.638088)
			(xy 269.753632 -286.67218) (xy 269.783197 -286.711524) (xy 269.806068 -286.755101) (xy 269.821652 -286.801782)
			(xy 269.829547 -286.850359) (xy 269.830042 -286.874966) (xy 270.169144 -286.874966) (xy 270.173104 -286.825912)
			(xy 270.184881 -286.778128) (xy 270.204172 -286.732852) (xy 270.230475 -286.691256) (xy 270.26311 -286.654419)
			(xy 270.301231 -286.623294) (xy 270.343852 -286.598687) (xy 270.389868 -286.581235) (xy 270.438087 -286.571391)
			(xy 270.487262 -286.56941) (xy 270.536117 -286.575342) (xy 270.583388 -286.589034) (xy 270.62785 -286.610132)
			(xy 270.668353 -286.638088) (xy 270.703846 -286.67218) (xy 270.733411 -286.711524) (xy 270.756282 -286.755101)
			(xy 270.771866 -286.801782) (xy 270.779761 -286.850359) (xy 270.780256 -286.874966) (xy 271.119104 -286.874966)
			(xy 271.123064 -286.825912) (xy 271.134841 -286.778128) (xy 271.154132 -286.732852) (xy 271.180435 -286.691256)
			(xy 271.21307 -286.654419) (xy 271.251191 -286.623294) (xy 271.293812 -286.598687) (xy 271.339828 -286.581235)
			(xy 271.388047 -286.571391) (xy 271.437222 -286.56941) (xy 271.486077 -286.575342) (xy 271.533348 -286.589034)
			(xy 271.57781 -286.610132) (xy 271.618313 -286.638088) (xy 271.653806 -286.67218) (xy 271.683371 -286.711524)
			(xy 271.706242 -286.755101) (xy 271.721826 -286.801782) (xy 271.729721 -286.850359) (xy 271.730216 -286.874966)
			(xy 272.069064 -286.874966) (xy 272.073024 -286.825912) (xy 272.084801 -286.778128) (xy 272.104092 -286.732852)
			(xy 272.130395 -286.691256) (xy 272.16303 -286.654419) (xy 272.201151 -286.623294) (xy 272.243772 -286.598687)
			(xy 272.289788 -286.581235) (xy 272.338007 -286.571391) (xy 272.387182 -286.56941) (xy 272.436037 -286.575342)
			(xy 272.483308 -286.589034) (xy 272.52777 -286.610132) (xy 272.568273 -286.638088) (xy 272.603766 -286.67218)
			(xy 272.633331 -286.711524) (xy 272.656202 -286.755101) (xy 272.671786 -286.801782) (xy 272.679681 -286.850359)
			(xy 272.680176 -286.874966) (xy 273.019024 -286.874966) (xy 273.022984 -286.825912) (xy 273.034761 -286.778128)
			(xy 273.054052 -286.732852) (xy 273.080355 -286.691256) (xy 273.11299 -286.654419) (xy 273.151111 -286.623294)
			(xy 273.193732 -286.598687) (xy 273.239748 -286.581235) (xy 273.287967 -286.571391) (xy 273.337142 -286.56941)
			(xy 273.385997 -286.575342) (xy 273.433268 -286.589034) (xy 273.47773 -286.610132) (xy 273.518233 -286.638088)
			(xy 273.553726 -286.67218) (xy 273.583291 -286.711524) (xy 273.606162 -286.755101) (xy 273.621746 -286.801782)
			(xy 273.629641 -286.850359) (xy 273.630136 -286.874966) (xy 273.968984 -286.874966) (xy 273.972944 -286.825912)
			(xy 273.984721 -286.778128) (xy 274.004012 -286.732852) (xy 274.030315 -286.691256) (xy 274.06295 -286.654419)
			(xy 274.101071 -286.623294) (xy 274.143692 -286.598687) (xy 274.189708 -286.581235) (xy 274.237927 -286.571391)
			(xy 274.287102 -286.56941) (xy 274.335957 -286.575342) (xy 274.383228 -286.589034) (xy 274.42769 -286.610132)
			(xy 274.468193 -286.638088) (xy 274.503686 -286.67218) (xy 274.533251 -286.711524) (xy 274.556122 -286.755101)
			(xy 274.571706 -286.801782) (xy 274.579601 -286.850359) (xy 274.580091 -286.874712) (xy 274.918944 -286.874712)
			(xy 274.922904 -286.825658) (xy 274.934681 -286.777874) (xy 274.953972 -286.732598) (xy 274.980275 -286.691002)
			(xy 275.01291 -286.654165) (xy 275.051031 -286.62304) (xy 275.093652 -286.598433) (xy 275.139668 -286.580981)
			(xy 275.187887 -286.571137) (xy 275.237062 -286.569156) (xy 275.285917 -286.575088) (xy 275.333188 -286.58878)
			(xy 275.37765 -286.609878) (xy 275.418153 -286.637834) (xy 275.453646 -286.671926) (xy 275.483211 -286.71127)
			(xy 275.506082 -286.754847) (xy 275.521666 -286.801528) (xy 275.529561 -286.850105) (xy 275.530056 -286.874712)
			(xy 275.868904 -286.874712) (xy 275.872864 -286.825658) (xy 275.884641 -286.777874) (xy 275.903932 -286.732598)
			(xy 275.930235 -286.691002) (xy 275.96287 -286.654165) (xy 276.000991 -286.62304) (xy 276.043612 -286.598433)
			(xy 276.089628 -286.580981) (xy 276.137847 -286.571137) (xy 276.187022 -286.569156) (xy 276.235877 -286.575088)
			(xy 276.283148 -286.58878) (xy 276.32761 -286.609878) (xy 276.368113 -286.637834) (xy 276.403606 -286.671926)
			(xy 276.433171 -286.71127) (xy 276.456042 -286.754847) (xy 276.471626 -286.801528) (xy 276.479521 -286.850105)
			(xy 276.480016 -286.874712) (xy 276.480011 -286.874966) (xy 276.819118 -286.874966) (xy 276.823078 -286.825912)
			(xy 276.834855 -286.778128) (xy 276.854146 -286.732852) (xy 276.880449 -286.691256) (xy 276.913084 -286.654419)
			(xy 276.951205 -286.623294) (xy 276.993826 -286.598687) (xy 277.039842 -286.581235) (xy 277.088061 -286.571391)
			(xy 277.137236 -286.56941) (xy 277.186091 -286.575342) (xy 277.233362 -286.589034) (xy 277.277824 -286.610132)
			(xy 277.318327 -286.638088) (xy 277.35382 -286.67218) (xy 277.383385 -286.711524) (xy 277.406256 -286.755101)
			(xy 277.42184 -286.801782) (xy 277.429735 -286.850359) (xy 277.43023 -286.874966) (xy 277.769078 -286.874966)
			(xy 277.773038 -286.825912) (xy 277.784815 -286.778128) (xy 277.804106 -286.732852) (xy 277.830409 -286.691256)
			(xy 277.863044 -286.654419) (xy 277.901165 -286.623294) (xy 277.943786 -286.598687) (xy 277.989802 -286.581235)
			(xy 278.038021 -286.571391) (xy 278.087196 -286.56941) (xy 278.136051 -286.575342) (xy 278.183322 -286.589034)
			(xy 278.227784 -286.610132) (xy 278.268287 -286.638088) (xy 278.30378 -286.67218) (xy 278.333345 -286.711524)
			(xy 278.356216 -286.755101) (xy 278.3718 -286.801782) (xy 278.379695 -286.850359) (xy 278.38019 -286.874966)
			(xy 278.719038 -286.874966) (xy 278.722998 -286.825912) (xy 278.734775 -286.778128) (xy 278.754066 -286.732852)
			(xy 278.780369 -286.691256) (xy 278.813004 -286.654419) (xy 278.851125 -286.623294) (xy 278.893746 -286.598687)
			(xy 278.939762 -286.581235) (xy 278.987981 -286.571391) (xy 279.037156 -286.56941) (xy 279.086011 -286.575342)
			(xy 279.133282 -286.589034) (xy 279.177744 -286.610132) (xy 279.218247 -286.638088) (xy 279.25374 -286.67218)
			(xy 279.283305 -286.711524) (xy 279.306176 -286.755101) (xy 279.32176 -286.801782) (xy 279.329655 -286.850359)
			(xy 279.33015 -286.874966) (xy 279.668998 -286.874966) (xy 279.672958 -286.825912) (xy 279.684735 -286.778128)
			(xy 279.704026 -286.732852) (xy 279.730329 -286.691256) (xy 279.762964 -286.654419) (xy 279.801085 -286.623294)
			(xy 279.843706 -286.598687) (xy 279.889722 -286.581235) (xy 279.937941 -286.571391) (xy 279.987116 -286.56941)
			(xy 280.035971 -286.575342) (xy 280.083242 -286.589034) (xy 280.127704 -286.610132) (xy 280.168207 -286.638088)
			(xy 280.2037 -286.67218) (xy 280.233265 -286.711524) (xy 280.256136 -286.755101) (xy 280.27172 -286.801782)
			(xy 280.279615 -286.850359) (xy 280.28011 -286.874966) (xy 280.618958 -286.874966) (xy 280.622918 -286.825912)
			(xy 280.634695 -286.778128) (xy 280.653986 -286.732852) (xy 280.680289 -286.691256) (xy 280.712924 -286.654419)
			(xy 280.751045 -286.623294) (xy 280.793666 -286.598687) (xy 280.839682 -286.581235) (xy 280.887901 -286.571391)
			(xy 280.937076 -286.56941) (xy 280.985931 -286.575342) (xy 281.033202 -286.589034) (xy 281.077664 -286.610132)
			(xy 281.118167 -286.638088) (xy 281.15366 -286.67218) (xy 281.183225 -286.711524) (xy 281.206096 -286.755101)
			(xy 281.22168 -286.801782) (xy 281.229575 -286.850359) (xy 281.23007 -286.874966) (xy 281.568918 -286.874966)
			(xy 281.572878 -286.825912) (xy 281.584655 -286.778128) (xy 281.603946 -286.732852) (xy 281.630249 -286.691256)
			(xy 281.662884 -286.654419) (xy 281.701005 -286.623294) (xy 281.743626 -286.598687) (xy 281.789642 -286.581235)
			(xy 281.837861 -286.571391) (xy 281.887036 -286.56941) (xy 281.935891 -286.575342) (xy 281.983162 -286.589034)
			(xy 282.027624 -286.610132) (xy 282.068127 -286.638088) (xy 282.10362 -286.67218) (xy 282.133185 -286.711524)
			(xy 282.156056 -286.755101) (xy 282.17164 -286.801782) (xy 282.179535 -286.850359) (xy 282.18003 -286.874966)
			(xy 282.519132 -286.874966) (xy 282.523092 -286.825912) (xy 282.534869 -286.778128) (xy 282.55416 -286.732852)
			(xy 282.580463 -286.691256) (xy 282.613098 -286.654419) (xy 282.651219 -286.623294) (xy 282.69384 -286.598687)
			(xy 282.739856 -286.581235) (xy 282.788075 -286.571391) (xy 282.83725 -286.56941) (xy 282.886105 -286.575342)
			(xy 282.933376 -286.589034) (xy 282.977838 -286.610132) (xy 283.018341 -286.638088) (xy 283.053834 -286.67218)
			(xy 283.083399 -286.711524) (xy 283.10627 -286.755101) (xy 283.121854 -286.801782) (xy 283.129749 -286.850359)
			(xy 283.130244 -286.874966) (xy 283.469092 -286.874966) (xy 283.473052 -286.825912) (xy 283.484829 -286.778128)
			(xy 283.50412 -286.732852) (xy 283.530423 -286.691256) (xy 283.563058 -286.654419) (xy 283.601179 -286.623294)
			(xy 283.6438 -286.598687) (xy 283.689816 -286.581235) (xy 283.738035 -286.571391) (xy 283.78721 -286.56941)
			(xy 283.836065 -286.575342) (xy 283.883336 -286.589034) (xy 283.927798 -286.610132) (xy 283.968301 -286.638088)
			(xy 284.003794 -286.67218) (xy 284.033359 -286.711524) (xy 284.05623 -286.755101) (xy 284.071814 -286.801782)
			(xy 284.079709 -286.850359) (xy 284.080204 -286.874966) (xy 284.419052 -286.874966) (xy 284.423012 -286.825912)
			(xy 284.434789 -286.778128) (xy 284.45408 -286.732852) (xy 284.480383 -286.691256) (xy 284.513018 -286.654419)
			(xy 284.551139 -286.623294) (xy 284.59376 -286.598687) (xy 284.639776 -286.581235) (xy 284.687995 -286.571391)
			(xy 284.73717 -286.56941) (xy 284.786025 -286.575342) (xy 284.833296 -286.589034) (xy 284.877758 -286.610132)
			(xy 284.918261 -286.638088) (xy 284.953754 -286.67218) (xy 284.983319 -286.711524) (xy 285.00619 -286.755101)
			(xy 285.021774 -286.801782) (xy 285.029669 -286.850359) (xy 285.030164 -286.874966) (xy 285.369012 -286.874966)
			(xy 285.372972 -286.825912) (xy 285.384749 -286.778128) (xy 285.40404 -286.732852) (xy 285.430343 -286.691256)
			(xy 285.462978 -286.654419) (xy 285.501099 -286.623294) (xy 285.54372 -286.598687) (xy 285.589736 -286.581235)
			(xy 285.637955 -286.571391) (xy 285.68713 -286.56941) (xy 285.735985 -286.575342) (xy 285.783256 -286.589034)
			(xy 285.827718 -286.610132) (xy 285.868221 -286.638088) (xy 285.903714 -286.67218) (xy 285.933279 -286.711524)
			(xy 285.95615 -286.755101) (xy 285.971734 -286.801782) (xy 285.979629 -286.850359) (xy 285.980124 -286.874966)
			(xy 286.318972 -286.874966) (xy 286.322932 -286.825912) (xy 286.334709 -286.778128) (xy 286.354 -286.732852)
			(xy 286.380303 -286.691256) (xy 286.412938 -286.654419) (xy 286.451059 -286.623294) (xy 286.49368 -286.598687)
			(xy 286.539696 -286.581235) (xy 286.587915 -286.571391) (xy 286.63709 -286.56941) (xy 286.685945 -286.575342)
			(xy 286.733216 -286.589034) (xy 286.777678 -286.610132) (xy 286.818181 -286.638088) (xy 286.853674 -286.67218)
			(xy 286.883239 -286.711524) (xy 286.90611 -286.755101) (xy 286.921694 -286.801782) (xy 286.929589 -286.850359)
			(xy 286.930084 -286.874966) (xy 287.268932 -286.874966) (xy 287.272892 -286.825912) (xy 287.284669 -286.778128)
			(xy 287.30396 -286.732852) (xy 287.330263 -286.691256) (xy 287.362898 -286.654419) (xy 287.401019 -286.623294)
			(xy 287.44364 -286.598687) (xy 287.489656 -286.581235) (xy 287.537875 -286.571391) (xy 287.58705 -286.56941)
			(xy 287.635905 -286.575342) (xy 287.683176 -286.589034) (xy 287.727638 -286.610132) (xy 287.768141 -286.638088)
			(xy 287.803634 -286.67218) (xy 287.833199 -286.711524) (xy 287.85607 -286.755101) (xy 287.871654 -286.801782)
			(xy 287.879549 -286.850359) (xy 287.880044 -286.874966) (xy 288.218892 -286.874966) (xy 288.222852 -286.825912)
			(xy 288.234629 -286.778128) (xy 288.25392 -286.732852) (xy 288.280223 -286.691256) (xy 288.312858 -286.654419)
			(xy 288.350979 -286.623294) (xy 288.3936 -286.598687) (xy 288.439616 -286.581235) (xy 288.487835 -286.571391)
			(xy 288.53701 -286.56941) (xy 288.585865 -286.575342) (xy 288.633136 -286.589034) (xy 288.677598 -286.610132)
			(xy 288.718101 -286.638088) (xy 288.753594 -286.67218) (xy 288.783159 -286.711524) (xy 288.80603 -286.755101)
			(xy 288.821614 -286.801782) (xy 288.829509 -286.850359) (xy 288.830004 -286.874966) (xy 289.169106 -286.874966)
			(xy 289.173066 -286.825912) (xy 289.184843 -286.778128) (xy 289.204134 -286.732852) (xy 289.230437 -286.691256)
			(xy 289.263072 -286.654419) (xy 289.301193 -286.623294) (xy 289.343814 -286.598687) (xy 289.38983 -286.581235)
			(xy 289.438049 -286.571391) (xy 289.487224 -286.56941) (xy 289.536079 -286.575342) (xy 289.58335 -286.589034)
			(xy 289.627812 -286.610132) (xy 289.668315 -286.638088) (xy 289.703808 -286.67218) (xy 289.733373 -286.711524)
			(xy 289.756244 -286.755101) (xy 289.771828 -286.801782) (xy 289.779723 -286.850359) (xy 289.780218 -286.874966)
			(xy 290.119066 -286.874966) (xy 290.123026 -286.825912) (xy 290.134803 -286.778128) (xy 290.154094 -286.732852)
			(xy 290.180397 -286.691256) (xy 290.213032 -286.654419) (xy 290.251153 -286.623294) (xy 290.293774 -286.598687)
			(xy 290.33979 -286.581235) (xy 290.388009 -286.571391) (xy 290.437184 -286.56941) (xy 290.486039 -286.575342)
			(xy 290.53331 -286.589034) (xy 290.577772 -286.610132) (xy 290.618275 -286.638088) (xy 290.653768 -286.67218)
			(xy 290.683333 -286.711524) (xy 290.706204 -286.755101) (xy 290.721788 -286.801782) (xy 290.729683 -286.850359)
			(xy 290.730178 -286.874966) (xy 292.018986 -286.874966) (xy 292.022946 -286.825912) (xy 292.034723 -286.778128)
			(xy 292.054014 -286.732852) (xy 292.080317 -286.691256) (xy 292.112952 -286.654419) (xy 292.151073 -286.623294)
			(xy 292.193694 -286.598687) (xy 292.23971 -286.581235) (xy 292.287929 -286.571391) (xy 292.337104 -286.56941)
			(xy 292.385959 -286.575342) (xy 292.43323 -286.589034) (xy 292.477692 -286.610132) (xy 292.518195 -286.638088)
			(xy 292.553688 -286.67218) (xy 292.583253 -286.711524) (xy 292.606124 -286.755101) (xy 292.621708 -286.801782)
			(xy 292.629603 -286.850359) (xy 292.630098 -286.874966) (xy 292.968946 -286.874966) (xy 292.972906 -286.825912)
			(xy 292.984683 -286.778128) (xy 293.003974 -286.732852) (xy 293.030277 -286.691256) (xy 293.062912 -286.654419)
			(xy 293.101033 -286.623294) (xy 293.143654 -286.598687) (xy 293.18967 -286.581235) (xy 293.237889 -286.571391)
			(xy 293.287064 -286.56941) (xy 293.335919 -286.575342) (xy 293.38319 -286.589034) (xy 293.427652 -286.610132)
			(xy 293.468155 -286.638088) (xy 293.503648 -286.67218) (xy 293.533213 -286.711524) (xy 293.556084 -286.755101)
			(xy 293.571668 -286.801782) (xy 293.579563 -286.850359) (xy 293.580058 -286.874966) (xy 293.918906 -286.874966)
			(xy 293.922866 -286.825912) (xy 293.934643 -286.778128) (xy 293.953934 -286.732852) (xy 293.980237 -286.691256)
			(xy 294.012872 -286.654419) (xy 294.050993 -286.623294) (xy 294.093614 -286.598687) (xy 294.13963 -286.581235)
			(xy 294.187849 -286.571391) (xy 294.237024 -286.56941) (xy 294.285879 -286.575342) (xy 294.33315 -286.589034)
			(xy 294.377612 -286.610132) (xy 294.418115 -286.638088) (xy 294.453608 -286.67218) (xy 294.483173 -286.711524)
			(xy 294.506044 -286.755101) (xy 294.521628 -286.801782) (xy 294.529523 -286.850359) (xy 294.530018 -286.874966)
			(xy 294.86912 -286.874966) (xy 294.87308 -286.825912) (xy 294.884857 -286.778128) (xy 294.904148 -286.732852)
			(xy 294.930451 -286.691256) (xy 294.963086 -286.654419) (xy 295.001207 -286.623294) (xy 295.043828 -286.598687)
			(xy 295.089844 -286.581235) (xy 295.138063 -286.571391) (xy 295.187238 -286.56941) (xy 295.236093 -286.575342)
			(xy 295.283364 -286.589034) (xy 295.327826 -286.610132) (xy 295.368329 -286.638088) (xy 295.403822 -286.67218)
			(xy 295.433387 -286.711524) (xy 295.456258 -286.755101) (xy 295.471842 -286.801782) (xy 295.479737 -286.850359)
			(xy 295.480232 -286.874966) (xy 295.81908 -286.874966) (xy 295.82304 -286.825912) (xy 295.834817 -286.778128)
			(xy 295.854108 -286.732852) (xy 295.880411 -286.691256) (xy 295.913046 -286.654419) (xy 295.951167 -286.623294)
			(xy 295.993788 -286.598687) (xy 296.039804 -286.581235) (xy 296.088023 -286.571391) (xy 296.137198 -286.56941)
			(xy 296.186053 -286.575342) (xy 296.233324 -286.589034) (xy 296.277786 -286.610132) (xy 296.318289 -286.638088)
			(xy 296.353782 -286.67218) (xy 296.383347 -286.711524) (xy 296.406218 -286.755101) (xy 296.421802 -286.801782)
			(xy 296.429697 -286.850359) (xy 296.430192 -286.874966) (xy 296.76904 -286.874966) (xy 296.773 -286.825912)
			(xy 296.784777 -286.778128) (xy 296.804068 -286.732852) (xy 296.830371 -286.691256) (xy 296.863006 -286.654419)
			(xy 296.901127 -286.623294) (xy 296.943748 -286.598687) (xy 296.989764 -286.581235) (xy 297.037983 -286.571391)
			(xy 297.087158 -286.56941) (xy 297.136013 -286.575342) (xy 297.183284 -286.589034) (xy 297.227746 -286.610132)
			(xy 297.268249 -286.638088) (xy 297.303742 -286.67218) (xy 297.333307 -286.711524) (xy 297.356178 -286.755101)
			(xy 297.371762 -286.801782) (xy 297.379657 -286.850359) (xy 297.380152 -286.874966) (xy 297.719 -286.874966)
			(xy 297.72296 -286.825912) (xy 297.734737 -286.778128) (xy 297.754028 -286.732852) (xy 297.780331 -286.691256)
			(xy 297.812966 -286.654419) (xy 297.851087 -286.623294) (xy 297.893708 -286.598687) (xy 297.939724 -286.581235)
			(xy 297.987943 -286.571391) (xy 298.037118 -286.56941) (xy 298.085973 -286.575342) (xy 298.133244 -286.589034)
			(xy 298.177706 -286.610132) (xy 298.218209 -286.638088) (xy 298.253702 -286.67218) (xy 298.283267 -286.711524)
			(xy 298.306138 -286.755101) (xy 298.321722 -286.801782) (xy 298.329617 -286.850359) (xy 298.330112 -286.874966)
			(xy 298.66896 -286.874966) (xy 298.67292 -286.825912) (xy 298.684697 -286.778128) (xy 298.703988 -286.732852)
			(xy 298.730291 -286.691256) (xy 298.762926 -286.654419) (xy 298.801047 -286.623294) (xy 298.843668 -286.598687)
			(xy 298.889684 -286.581235) (xy 298.937903 -286.571391) (xy 298.987078 -286.56941) (xy 299.035933 -286.575342)
			(xy 299.083204 -286.589034) (xy 299.127666 -286.610132) (xy 299.168169 -286.638088) (xy 299.203662 -286.67218)
			(xy 299.233227 -286.711524) (xy 299.256098 -286.755101) (xy 299.271682 -286.801782) (xy 299.279577 -286.850359)
			(xy 299.280072 -286.874966) (xy 299.61892 -286.874966) (xy 299.62288 -286.825912) (xy 299.634657 -286.778128)
			(xy 299.653948 -286.732852) (xy 299.680251 -286.691256) (xy 299.712886 -286.654419) (xy 299.751007 -286.623294)
			(xy 299.793628 -286.598687) (xy 299.839644 -286.581235) (xy 299.887863 -286.571391) (xy 299.937038 -286.56941)
			(xy 299.985893 -286.575342) (xy 300.033164 -286.589034) (xy 300.077626 -286.610132) (xy 300.118129 -286.638088)
			(xy 300.153622 -286.67218) (xy 300.183187 -286.711524) (xy 300.206058 -286.755101) (xy 300.221642 -286.801782)
			(xy 300.229537 -286.850359) (xy 300.230032 -286.874966) (xy 300.56888 -286.874966) (xy 300.57284 -286.825912)
			(xy 300.584617 -286.778128) (xy 300.603908 -286.732852) (xy 300.630211 -286.691256) (xy 300.662846 -286.654419)
			(xy 300.700967 -286.623294) (xy 300.743588 -286.598687) (xy 300.789604 -286.581235) (xy 300.837823 -286.571391)
			(xy 300.886998 -286.56941) (xy 300.935853 -286.575342) (xy 300.983124 -286.589034) (xy 301.027586 -286.610132)
			(xy 301.068089 -286.638088) (xy 301.103582 -286.67218) (xy 301.133147 -286.711524) (xy 301.156018 -286.755101)
			(xy 301.171602 -286.801782) (xy 301.179497 -286.850359) (xy 301.179992 -286.874966) (xy 301.519094 -286.874966)
			(xy 301.523054 -286.825912) (xy 301.534831 -286.778128) (xy 301.554122 -286.732852) (xy 301.580425 -286.691256)
			(xy 301.61306 -286.654419) (xy 301.651181 -286.623294) (xy 301.693802 -286.598687) (xy 301.739818 -286.581235)
			(xy 301.788037 -286.571391) (xy 301.837212 -286.56941) (xy 301.886067 -286.575342) (xy 301.933338 -286.589034)
			(xy 301.9778 -286.610132) (xy 302.018303 -286.638088) (xy 302.053796 -286.67218) (xy 302.083361 -286.711524)
			(xy 302.106232 -286.755101) (xy 302.121816 -286.801782) (xy 302.129711 -286.850359) (xy 302.130206 -286.874966)
			(xy 302.469054 -286.874966) (xy 302.473014 -286.825912) (xy 302.484791 -286.778128) (xy 302.504082 -286.732852)
			(xy 302.530385 -286.691256) (xy 302.56302 -286.654419) (xy 302.601141 -286.623294) (xy 302.643762 -286.598687)
			(xy 302.689778 -286.581235) (xy 302.737997 -286.571391) (xy 302.787172 -286.56941) (xy 302.836027 -286.575342)
			(xy 302.883298 -286.589034) (xy 302.92776 -286.610132) (xy 302.968263 -286.638088) (xy 303.003756 -286.67218)
			(xy 303.033321 -286.711524) (xy 303.056192 -286.755101) (xy 303.071776 -286.801782) (xy 303.079671 -286.850359)
			(xy 303.080166 -286.874966) (xy 303.079671 -286.899573) (xy 303.071776 -286.94815) (xy 303.056192 -286.994831)
			(xy 303.033321 -287.038408) (xy 303.003756 -287.077752) (xy 302.968263 -287.111844) (xy 302.92776 -287.1398)
			(xy 302.883298 -287.160898) (xy 302.836027 -287.17459) (xy 302.787172 -287.180522) (xy 302.737997 -287.178541)
			(xy 302.689778 -287.168697) (xy 302.643762 -287.151245) (xy 302.601141 -287.126638) (xy 302.56302 -287.095513)
			(xy 302.530385 -287.058676) (xy 302.504082 -287.01708) (xy 302.484791 -286.971804) (xy 302.473014 -286.92402)
			(xy 302.469054 -286.874966) (xy 302.130206 -286.874966) (xy 302.129711 -286.899573) (xy 302.121816 -286.94815)
			(xy 302.106232 -286.994831) (xy 302.083361 -287.038408) (xy 302.053796 -287.077752) (xy 302.018303 -287.111844)
			(xy 301.9778 -287.1398) (xy 301.933338 -287.160898) (xy 301.886067 -287.17459) (xy 301.837212 -287.180522)
			(xy 301.788037 -287.178541) (xy 301.739818 -287.168697) (xy 301.693802 -287.151245) (xy 301.651181 -287.126638)
			(xy 301.61306 -287.095513) (xy 301.580425 -287.058676) (xy 301.554122 -287.01708) (xy 301.534831 -286.971804)
			(xy 301.523054 -286.92402) (xy 301.519094 -286.874966) (xy 301.179992 -286.874966) (xy 301.179497 -286.899573)
			(xy 301.171602 -286.94815) (xy 301.156018 -286.994831) (xy 301.133147 -287.038408) (xy 301.103582 -287.077752)
			(xy 301.068089 -287.111844) (xy 301.027586 -287.1398) (xy 300.983124 -287.160898) (xy 300.935853 -287.17459)
			(xy 300.886998 -287.180522) (xy 300.837823 -287.178541) (xy 300.789604 -287.168697) (xy 300.743588 -287.151245)
			(xy 300.700967 -287.126638) (xy 300.662846 -287.095513) (xy 300.630211 -287.058676) (xy 300.603908 -287.01708)
			(xy 300.584617 -286.971804) (xy 300.57284 -286.92402) (xy 300.56888 -286.874966) (xy 300.230032 -286.874966)
			(xy 300.229537 -286.899573) (xy 300.221642 -286.94815) (xy 300.206058 -286.994831) (xy 300.183187 -287.038408)
			(xy 300.153622 -287.077752) (xy 300.118129 -287.111844) (xy 300.077626 -287.1398) (xy 300.033164 -287.160898)
			(xy 299.985893 -287.17459) (xy 299.937038 -287.180522) (xy 299.887863 -287.178541) (xy 299.839644 -287.168697)
			(xy 299.793628 -287.151245) (xy 299.751007 -287.126638) (xy 299.712886 -287.095513) (xy 299.680251 -287.058676)
			(xy 299.653948 -287.01708) (xy 299.634657 -286.971804) (xy 299.62288 -286.92402) (xy 299.61892 -286.874966)
			(xy 299.280072 -286.874966) (xy 299.279577 -286.899573) (xy 299.271682 -286.94815) (xy 299.256098 -286.994831)
			(xy 299.233227 -287.038408) (xy 299.203662 -287.077752) (xy 299.168169 -287.111844) (xy 299.127666 -287.1398)
			(xy 299.083204 -287.160898) (xy 299.035933 -287.17459) (xy 298.987078 -287.180522) (xy 298.937903 -287.178541)
			(xy 298.889684 -287.168697) (xy 298.843668 -287.151245) (xy 298.801047 -287.126638) (xy 298.762926 -287.095513)
			(xy 298.730291 -287.058676) (xy 298.703988 -287.01708) (xy 298.684697 -286.971804) (xy 298.67292 -286.92402)
			(xy 298.66896 -286.874966) (xy 298.330112 -286.874966) (xy 298.329617 -286.899573) (xy 298.321722 -286.94815)
			(xy 298.306138 -286.994831) (xy 298.283267 -287.038408) (xy 298.253702 -287.077752) (xy 298.218209 -287.111844)
			(xy 298.177706 -287.1398) (xy 298.133244 -287.160898) (xy 298.085973 -287.17459) (xy 298.037118 -287.180522)
			(xy 297.987943 -287.178541) (xy 297.939724 -287.168697) (xy 297.893708 -287.151245) (xy 297.851087 -287.126638)
			(xy 297.812966 -287.095513) (xy 297.780331 -287.058676) (xy 297.754028 -287.01708) (xy 297.734737 -286.971804)
			(xy 297.72296 -286.92402) (xy 297.719 -286.874966) (xy 297.380152 -286.874966) (xy 297.379657 -286.899573)
			(xy 297.371762 -286.94815) (xy 297.356178 -286.994831) (xy 297.333307 -287.038408) (xy 297.303742 -287.077752)
			(xy 297.268249 -287.111844) (xy 297.227746 -287.1398) (xy 297.183284 -287.160898) (xy 297.136013 -287.17459)
			(xy 297.087158 -287.180522) (xy 297.037983 -287.178541) (xy 296.989764 -287.168697) (xy 296.943748 -287.151245)
			(xy 296.901127 -287.126638) (xy 296.863006 -287.095513) (xy 296.830371 -287.058676) (xy 296.804068 -287.01708)
			(xy 296.784777 -286.971804) (xy 296.773 -286.92402) (xy 296.76904 -286.874966) (xy 296.430192 -286.874966)
			(xy 296.429697 -286.899573) (xy 296.421802 -286.94815) (xy 296.406218 -286.994831) (xy 296.383347 -287.038408)
			(xy 296.353782 -287.077752) (xy 296.318289 -287.111844) (xy 296.277786 -287.1398) (xy 296.233324 -287.160898)
			(xy 296.186053 -287.17459) (xy 296.137198 -287.180522) (xy 296.088023 -287.178541) (xy 296.039804 -287.168697)
			(xy 295.993788 -287.151245) (xy 295.951167 -287.126638) (xy 295.913046 -287.095513) (xy 295.880411 -287.058676)
			(xy 295.854108 -287.01708) (xy 295.834817 -286.971804) (xy 295.82304 -286.92402) (xy 295.81908 -286.874966)
			(xy 295.480232 -286.874966) (xy 295.479737 -286.899573) (xy 295.471842 -286.94815) (xy 295.456258 -286.994831)
			(xy 295.433387 -287.038408) (xy 295.403822 -287.077752) (xy 295.368329 -287.111844) (xy 295.327826 -287.1398)
			(xy 295.283364 -287.160898) (xy 295.236093 -287.17459) (xy 295.187238 -287.180522) (xy 295.138063 -287.178541)
			(xy 295.089844 -287.168697) (xy 295.043828 -287.151245) (xy 295.001207 -287.126638) (xy 294.963086 -287.095513)
			(xy 294.930451 -287.058676) (xy 294.904148 -287.01708) (xy 294.884857 -286.971804) (xy 294.87308 -286.92402)
			(xy 294.86912 -286.874966) (xy 294.530018 -286.874966) (xy 294.529523 -286.899573) (xy 294.521628 -286.94815)
			(xy 294.506044 -286.994831) (xy 294.483173 -287.038408) (xy 294.453608 -287.077752) (xy 294.418115 -287.111844)
			(xy 294.377612 -287.1398) (xy 294.33315 -287.160898) (xy 294.285879 -287.17459) (xy 294.237024 -287.180522)
			(xy 294.187849 -287.178541) (xy 294.13963 -287.168697) (xy 294.093614 -287.151245) (xy 294.050993 -287.126638)
			(xy 294.012872 -287.095513) (xy 293.980237 -287.058676) (xy 293.953934 -287.01708) (xy 293.934643 -286.971804)
			(xy 293.922866 -286.92402) (xy 293.918906 -286.874966) (xy 293.580058 -286.874966) (xy 293.579563 -286.899573)
			(xy 293.571668 -286.94815) (xy 293.556084 -286.994831) (xy 293.533213 -287.038408) (xy 293.503648 -287.077752)
			(xy 293.468155 -287.111844) (xy 293.427652 -287.1398) (xy 293.38319 -287.160898) (xy 293.335919 -287.17459)
			(xy 293.287064 -287.180522) (xy 293.237889 -287.178541) (xy 293.18967 -287.168697) (xy 293.143654 -287.151245)
			(xy 293.101033 -287.126638) (xy 293.062912 -287.095513) (xy 293.030277 -287.058676) (xy 293.003974 -287.01708)
			(xy 292.984683 -286.971804) (xy 292.972906 -286.92402) (xy 292.968946 -286.874966) (xy 292.630098 -286.874966)
			(xy 292.629603 -286.899573) (xy 292.621708 -286.94815) (xy 292.606124 -286.994831) (xy 292.583253 -287.038408)
			(xy 292.553688 -287.077752) (xy 292.518195 -287.111844) (xy 292.477692 -287.1398) (xy 292.43323 -287.160898)
			(xy 292.385959 -287.17459) (xy 292.337104 -287.180522) (xy 292.287929 -287.178541) (xy 292.23971 -287.168697)
			(xy 292.193694 -287.151245) (xy 292.151073 -287.126638) (xy 292.112952 -287.095513) (xy 292.080317 -287.058676)
			(xy 292.054014 -287.01708) (xy 292.034723 -286.971804) (xy 292.022946 -286.92402) (xy 292.018986 -286.874966)
			(xy 290.730178 -286.874966) (xy 290.729683 -286.899573) (xy 290.721788 -286.94815) (xy 290.706204 -286.994831)
			(xy 290.683333 -287.038408) (xy 290.653768 -287.077752) (xy 290.618275 -287.111844) (xy 290.577772 -287.1398)
			(xy 290.53331 -287.160898) (xy 290.486039 -287.17459) (xy 290.437184 -287.180522) (xy 290.388009 -287.178541)
			(xy 290.33979 -287.168697) (xy 290.293774 -287.151245) (xy 290.251153 -287.126638) (xy 290.213032 -287.095513)
			(xy 290.180397 -287.058676) (xy 290.154094 -287.01708) (xy 290.134803 -286.971804) (xy 290.123026 -286.92402)
			(xy 290.119066 -286.874966) (xy 289.780218 -286.874966) (xy 289.779723 -286.899573) (xy 289.771828 -286.94815)
			(xy 289.756244 -286.994831) (xy 289.733373 -287.038408) (xy 289.703808 -287.077752) (xy 289.668315 -287.111844)
			(xy 289.627812 -287.1398) (xy 289.58335 -287.160898) (xy 289.536079 -287.17459) (xy 289.487224 -287.180522)
			(xy 289.438049 -287.178541) (xy 289.38983 -287.168697) (xy 289.343814 -287.151245) (xy 289.301193 -287.126638)
			(xy 289.263072 -287.095513) (xy 289.230437 -287.058676) (xy 289.204134 -287.01708) (xy 289.184843 -286.971804)
			(xy 289.173066 -286.92402) (xy 289.169106 -286.874966) (xy 288.830004 -286.874966) (xy 288.829509 -286.899573)
			(xy 288.821614 -286.94815) (xy 288.80603 -286.994831) (xy 288.783159 -287.038408) (xy 288.753594 -287.077752)
			(xy 288.718101 -287.111844) (xy 288.677598 -287.1398) (xy 288.633136 -287.160898) (xy 288.585865 -287.17459)
			(xy 288.53701 -287.180522) (xy 288.487835 -287.178541) (xy 288.439616 -287.168697) (xy 288.3936 -287.151245)
			(xy 288.350979 -287.126638) (xy 288.312858 -287.095513) (xy 288.280223 -287.058676) (xy 288.25392 -287.01708)
			(xy 288.234629 -286.971804) (xy 288.222852 -286.92402) (xy 288.218892 -286.874966) (xy 287.880044 -286.874966)
			(xy 287.879549 -286.899573) (xy 287.871654 -286.94815) (xy 287.85607 -286.994831) (xy 287.833199 -287.038408)
			(xy 287.803634 -287.077752) (xy 287.768141 -287.111844) (xy 287.727638 -287.1398) (xy 287.683176 -287.160898)
			(xy 287.635905 -287.17459) (xy 287.58705 -287.180522) (xy 287.537875 -287.178541) (xy 287.489656 -287.168697)
			(xy 287.44364 -287.151245) (xy 287.401019 -287.126638) (xy 287.362898 -287.095513) (xy 287.330263 -287.058676)
			(xy 287.30396 -287.01708) (xy 287.284669 -286.971804) (xy 287.272892 -286.92402) (xy 287.268932 -286.874966)
			(xy 286.930084 -286.874966) (xy 286.929589 -286.899573) (xy 286.921694 -286.94815) (xy 286.90611 -286.994831)
			(xy 286.883239 -287.038408) (xy 286.853674 -287.077752) (xy 286.818181 -287.111844) (xy 286.777678 -287.1398)
			(xy 286.733216 -287.160898) (xy 286.685945 -287.17459) (xy 286.63709 -287.180522) (xy 286.587915 -287.178541)
			(xy 286.539696 -287.168697) (xy 286.49368 -287.151245) (xy 286.451059 -287.126638) (xy 286.412938 -287.095513)
			(xy 286.380303 -287.058676) (xy 286.354 -287.01708) (xy 286.334709 -286.971804) (xy 286.322932 -286.92402)
			(xy 286.318972 -286.874966) (xy 285.980124 -286.874966) (xy 285.979629 -286.899573) (xy 285.971734 -286.94815)
			(xy 285.95615 -286.994831) (xy 285.933279 -287.038408) (xy 285.903714 -287.077752) (xy 285.868221 -287.111844)
			(xy 285.827718 -287.1398) (xy 285.783256 -287.160898) (xy 285.735985 -287.17459) (xy 285.68713 -287.180522)
			(xy 285.637955 -287.178541) (xy 285.589736 -287.168697) (xy 285.54372 -287.151245) (xy 285.501099 -287.126638)
			(xy 285.462978 -287.095513) (xy 285.430343 -287.058676) (xy 285.40404 -287.01708) (xy 285.384749 -286.971804)
			(xy 285.372972 -286.92402) (xy 285.369012 -286.874966) (xy 285.030164 -286.874966) (xy 285.029669 -286.899573)
			(xy 285.021774 -286.94815) (xy 285.00619 -286.994831) (xy 284.983319 -287.038408) (xy 284.953754 -287.077752)
			(xy 284.918261 -287.111844) (xy 284.877758 -287.1398) (xy 284.833296 -287.160898) (xy 284.786025 -287.17459)
			(xy 284.73717 -287.180522) (xy 284.687995 -287.178541) (xy 284.639776 -287.168697) (xy 284.59376 -287.151245)
			(xy 284.551139 -287.126638) (xy 284.513018 -287.095513) (xy 284.480383 -287.058676) (xy 284.45408 -287.01708)
			(xy 284.434789 -286.971804) (xy 284.423012 -286.92402) (xy 284.419052 -286.874966) (xy 284.080204 -286.874966)
			(xy 284.079709 -286.899573) (xy 284.071814 -286.94815) (xy 284.05623 -286.994831) (xy 284.033359 -287.038408)
			(xy 284.003794 -287.077752) (xy 283.968301 -287.111844) (xy 283.927798 -287.1398) (xy 283.883336 -287.160898)
			(xy 283.836065 -287.17459) (xy 283.78721 -287.180522) (xy 283.738035 -287.178541) (xy 283.689816 -287.168697)
			(xy 283.6438 -287.151245) (xy 283.601179 -287.126638) (xy 283.563058 -287.095513) (xy 283.530423 -287.058676)
			(xy 283.50412 -287.01708) (xy 283.484829 -286.971804) (xy 283.473052 -286.92402) (xy 283.469092 -286.874966)
			(xy 283.130244 -286.874966) (xy 283.129749 -286.899573) (xy 283.121854 -286.94815) (xy 283.10627 -286.994831)
			(xy 283.083399 -287.038408) (xy 283.053834 -287.077752) (xy 283.018341 -287.111844) (xy 282.977838 -287.1398)
			(xy 282.933376 -287.160898) (xy 282.886105 -287.17459) (xy 282.83725 -287.180522) (xy 282.788075 -287.178541)
			(xy 282.739856 -287.168697) (xy 282.69384 -287.151245) (xy 282.651219 -287.126638) (xy 282.613098 -287.095513)
			(xy 282.580463 -287.058676) (xy 282.55416 -287.01708) (xy 282.534869 -286.971804) (xy 282.523092 -286.92402)
			(xy 282.519132 -286.874966) (xy 282.18003 -286.874966) (xy 282.179535 -286.899573) (xy 282.17164 -286.94815)
			(xy 282.156056 -286.994831) (xy 282.133185 -287.038408) (xy 282.10362 -287.077752) (xy 282.068127 -287.111844)
			(xy 282.027624 -287.1398) (xy 281.983162 -287.160898) (xy 281.935891 -287.17459) (xy 281.887036 -287.180522)
			(xy 281.837861 -287.178541) (xy 281.789642 -287.168697) (xy 281.743626 -287.151245) (xy 281.701005 -287.126638)
			(xy 281.662884 -287.095513) (xy 281.630249 -287.058676) (xy 281.603946 -287.01708) (xy 281.584655 -286.971804)
			(xy 281.572878 -286.92402) (xy 281.568918 -286.874966) (xy 281.23007 -286.874966) (xy 281.229575 -286.899573)
			(xy 281.22168 -286.94815) (xy 281.206096 -286.994831) (xy 281.183225 -287.038408) (xy 281.15366 -287.077752)
			(xy 281.118167 -287.111844) (xy 281.077664 -287.1398) (xy 281.033202 -287.160898) (xy 280.985931 -287.17459)
			(xy 280.937076 -287.180522) (xy 280.887901 -287.178541) (xy 280.839682 -287.168697) (xy 280.793666 -287.151245)
			(xy 280.751045 -287.126638) (xy 280.712924 -287.095513) (xy 280.680289 -287.058676) (xy 280.653986 -287.01708)
			(xy 280.634695 -286.971804) (xy 280.622918 -286.92402) (xy 280.618958 -286.874966) (xy 280.28011 -286.874966)
			(xy 280.279615 -286.899573) (xy 280.27172 -286.94815) (xy 280.256136 -286.994831) (xy 280.233265 -287.038408)
			(xy 280.2037 -287.077752) (xy 280.168207 -287.111844) (xy 280.127704 -287.1398) (xy 280.083242 -287.160898)
			(xy 280.035971 -287.17459) (xy 279.987116 -287.180522) (xy 279.937941 -287.178541) (xy 279.889722 -287.168697)
			(xy 279.843706 -287.151245) (xy 279.801085 -287.126638) (xy 279.762964 -287.095513) (xy 279.730329 -287.058676)
			(xy 279.704026 -287.01708) (xy 279.684735 -286.971804) (xy 279.672958 -286.92402) (xy 279.668998 -286.874966)
			(xy 279.33015 -286.874966) (xy 279.329655 -286.899573) (xy 279.32176 -286.94815) (xy 279.306176 -286.994831)
			(xy 279.283305 -287.038408) (xy 279.25374 -287.077752) (xy 279.218247 -287.111844) (xy 279.177744 -287.1398)
			(xy 279.133282 -287.160898) (xy 279.086011 -287.17459) (xy 279.037156 -287.180522) (xy 278.987981 -287.178541)
			(xy 278.939762 -287.168697) (xy 278.893746 -287.151245) (xy 278.851125 -287.126638) (xy 278.813004 -287.095513)
			(xy 278.780369 -287.058676) (xy 278.754066 -287.01708) (xy 278.734775 -286.971804) (xy 278.722998 -286.92402)
			(xy 278.719038 -286.874966) (xy 278.38019 -286.874966) (xy 278.379695 -286.899573) (xy 278.3718 -286.94815)
			(xy 278.356216 -286.994831) (xy 278.333345 -287.038408) (xy 278.30378 -287.077752) (xy 278.268287 -287.111844)
			(xy 278.227784 -287.1398) (xy 278.183322 -287.160898) (xy 278.136051 -287.17459) (xy 278.087196 -287.180522)
			(xy 278.038021 -287.178541) (xy 277.989802 -287.168697) (xy 277.943786 -287.151245) (xy 277.901165 -287.126638)
			(xy 277.863044 -287.095513) (xy 277.830409 -287.058676) (xy 277.804106 -287.01708) (xy 277.784815 -286.971804)
			(xy 277.773038 -286.92402) (xy 277.769078 -286.874966) (xy 277.43023 -286.874966) (xy 277.429735 -286.899573)
			(xy 277.42184 -286.94815) (xy 277.406256 -286.994831) (xy 277.383385 -287.038408) (xy 277.35382 -287.077752)
			(xy 277.318327 -287.111844) (xy 277.277824 -287.1398) (xy 277.233362 -287.160898) (xy 277.186091 -287.17459)
			(xy 277.137236 -287.180522) (xy 277.088061 -287.178541) (xy 277.039842 -287.168697) (xy 276.993826 -287.151245)
			(xy 276.951205 -287.126638) (xy 276.913084 -287.095513) (xy 276.880449 -287.058676) (xy 276.854146 -287.01708)
			(xy 276.834855 -286.971804) (xy 276.823078 -286.92402) (xy 276.819118 -286.874966) (xy 276.480011 -286.874966)
			(xy 276.479521 -286.899319) (xy 276.471626 -286.947896) (xy 276.456042 -286.994577) (xy 276.433171 -287.038154)
			(xy 276.403606 -287.077498) (xy 276.368113 -287.11159) (xy 276.32761 -287.139546) (xy 276.283148 -287.160644)
			(xy 276.235877 -287.174336) (xy 276.187022 -287.180268) (xy 276.137847 -287.178287) (xy 276.089628 -287.168443)
			(xy 276.043612 -287.150991) (xy 276.000991 -287.126384) (xy 275.96287 -287.095259) (xy 275.930235 -287.058422)
			(xy 275.903932 -287.016826) (xy 275.884641 -286.97155) (xy 275.872864 -286.923766) (xy 275.868904 -286.874712)
			(xy 275.530056 -286.874712) (xy 275.529561 -286.899319) (xy 275.521666 -286.947896) (xy 275.506082 -286.994577)
			(xy 275.483211 -287.038154) (xy 275.453646 -287.077498) (xy 275.418153 -287.11159) (xy 275.37765 -287.139546)
			(xy 275.333188 -287.160644) (xy 275.285917 -287.174336) (xy 275.237062 -287.180268) (xy 275.187887 -287.178287)
			(xy 275.139668 -287.168443) (xy 275.093652 -287.150991) (xy 275.051031 -287.126384) (xy 275.01291 -287.095259)
			(xy 274.980275 -287.058422) (xy 274.953972 -287.016826) (xy 274.934681 -286.97155) (xy 274.922904 -286.923766)
			(xy 274.918944 -286.874712) (xy 274.580091 -286.874712) (xy 274.580096 -286.874966) (xy 274.579601 -286.899573)
			(xy 274.571706 -286.94815) (xy 274.556122 -286.994831) (xy 274.533251 -287.038408) (xy 274.503686 -287.077752)
			(xy 274.468193 -287.111844) (xy 274.42769 -287.1398) (xy 274.383228 -287.160898) (xy 274.335957 -287.17459)
			(xy 274.287102 -287.180522) (xy 274.237927 -287.178541) (xy 274.189708 -287.168697) (xy 274.143692 -287.151245)
			(xy 274.101071 -287.126638) (xy 274.06295 -287.095513) (xy 274.030315 -287.058676) (xy 274.004012 -287.01708)
			(xy 273.984721 -286.971804) (xy 273.972944 -286.92402) (xy 273.968984 -286.874966) (xy 273.630136 -286.874966)
			(xy 273.629641 -286.899573) (xy 273.621746 -286.94815) (xy 273.606162 -286.994831) (xy 273.583291 -287.038408)
			(xy 273.553726 -287.077752) (xy 273.518233 -287.111844) (xy 273.47773 -287.1398) (xy 273.433268 -287.160898)
			(xy 273.385997 -287.17459) (xy 273.337142 -287.180522) (xy 273.287967 -287.178541) (xy 273.239748 -287.168697)
			(xy 273.193732 -287.151245) (xy 273.151111 -287.126638) (xy 273.11299 -287.095513) (xy 273.080355 -287.058676)
			(xy 273.054052 -287.01708) (xy 273.034761 -286.971804) (xy 273.022984 -286.92402) (xy 273.019024 -286.874966)
			(xy 272.680176 -286.874966) (xy 272.679681 -286.899573) (xy 272.671786 -286.94815) (xy 272.656202 -286.994831)
			(xy 272.633331 -287.038408) (xy 272.603766 -287.077752) (xy 272.568273 -287.111844) (xy 272.52777 -287.1398)
			(xy 272.483308 -287.160898) (xy 272.436037 -287.17459) (xy 272.387182 -287.180522) (xy 272.338007 -287.178541)
			(xy 272.289788 -287.168697) (xy 272.243772 -287.151245) (xy 272.201151 -287.126638) (xy 272.16303 -287.095513)
			(xy 272.130395 -287.058676) (xy 272.104092 -287.01708) (xy 272.084801 -286.971804) (xy 272.073024 -286.92402)
			(xy 272.069064 -286.874966) (xy 271.730216 -286.874966) (xy 271.729721 -286.899573) (xy 271.721826 -286.94815)
			(xy 271.706242 -286.994831) (xy 271.683371 -287.038408) (xy 271.653806 -287.077752) (xy 271.618313 -287.111844)
			(xy 271.57781 -287.1398) (xy 271.533348 -287.160898) (xy 271.486077 -287.17459) (xy 271.437222 -287.180522)
			(xy 271.388047 -287.178541) (xy 271.339828 -287.168697) (xy 271.293812 -287.151245) (xy 271.251191 -287.126638)
			(xy 271.21307 -287.095513) (xy 271.180435 -287.058676) (xy 271.154132 -287.01708) (xy 271.134841 -286.971804)
			(xy 271.123064 -286.92402) (xy 271.119104 -286.874966) (xy 270.780256 -286.874966) (xy 270.779761 -286.899573)
			(xy 270.771866 -286.94815) (xy 270.756282 -286.994831) (xy 270.733411 -287.038408) (xy 270.703846 -287.077752)
			(xy 270.668353 -287.111844) (xy 270.62785 -287.1398) (xy 270.583388 -287.160898) (xy 270.536117 -287.17459)
			(xy 270.487262 -287.180522) (xy 270.438087 -287.178541) (xy 270.389868 -287.168697) (xy 270.343852 -287.151245)
			(xy 270.301231 -287.126638) (xy 270.26311 -287.095513) (xy 270.230475 -287.058676) (xy 270.204172 -287.01708)
			(xy 270.184881 -286.971804) (xy 270.173104 -286.92402) (xy 270.169144 -286.874966) (xy 269.830042 -286.874966)
			(xy 269.829547 -286.899573) (xy 269.821652 -286.94815) (xy 269.806068 -286.994831) (xy 269.783197 -287.038408)
			(xy 269.753632 -287.077752) (xy 269.718139 -287.111844) (xy 269.677636 -287.1398) (xy 269.633174 -287.160898)
			(xy 269.585903 -287.17459) (xy 269.537048 -287.180522) (xy 269.487873 -287.178541) (xy 269.439654 -287.168697)
			(xy 269.393638 -287.151245) (xy 269.351017 -287.126638) (xy 269.312896 -287.095513) (xy 269.280261 -287.058676)
			(xy 269.253958 -287.01708) (xy 269.234667 -286.971804) (xy 269.22289 -286.92402) (xy 269.21893 -286.874966)
			(xy 268.880082 -286.874966) (xy 268.879587 -286.899573) (xy 268.871692 -286.94815) (xy 268.856108 -286.994831)
			(xy 268.833237 -287.038408) (xy 268.803672 -287.077752) (xy 268.768179 -287.111844) (xy 268.727676 -287.1398)
			(xy 268.683214 -287.160898) (xy 268.635943 -287.17459) (xy 268.587088 -287.180522) (xy 268.537913 -287.178541)
			(xy 268.489694 -287.168697) (xy 268.443678 -287.151245) (xy 268.401057 -287.126638) (xy 268.362936 -287.095513)
			(xy 268.330301 -287.058676) (xy 268.303998 -287.01708) (xy 268.284707 -286.971804) (xy 268.27293 -286.92402)
			(xy 268.26897 -286.874966) (xy 266.514902 -286.874966) (xy 266.536061 -286.906948) (xy 266.559733 -286.957445)
			(xy 266.575801 -287.010852) (xy 266.583921 -287.066028) (xy 266.58443 -287.093914) (xy 266.583921 -287.1218)
			(xy 266.575801 -287.176976) (xy 266.559733 -287.230383) (xy 266.536061 -287.28088) (xy 266.505288 -287.327393)
			(xy 266.485081 -287.349946) (xy 305.793914 -287.349946) (xy 305.797874 -287.300892) (xy 305.809651 -287.253108)
			(xy 305.828942 -287.207832) (xy 305.855245 -287.166236) (xy 305.88788 -287.129399) (xy 305.926001 -287.098274)
			(xy 305.968622 -287.073667) (xy 306.014638 -287.056215) (xy 306.062857 -287.046371) (xy 306.112032 -287.04439)
			(xy 306.160887 -287.050322) (xy 306.208158 -287.064014) (xy 306.25262 -287.085112) (xy 306.293123 -287.113068)
			(xy 306.328616 -287.14716) (xy 306.358181 -287.186504) (xy 306.381052 -287.230081) (xy 306.396636 -287.276762)
			(xy 306.404531 -287.325339) (xy 306.405026 -287.349946) (xy 306.404531 -287.374553) (xy 306.404352 -287.375654)
			(xy 306.72303 -287.375654) (xy 306.72303 -287.324238) (xy 306.731073 -287.273456) (xy 306.746961 -287.224557)
			(xy 306.770304 -287.178745) (xy 306.800525 -287.137149) (xy 306.836881 -287.100793) (xy 306.878477 -287.070572)
			(xy 306.924289 -287.047229) (xy 306.973188 -287.031341) (xy 307.02397 -287.023298) (xy 307.075386 -287.023298)
			(xy 307.126168 -287.031341) (xy 307.175067 -287.047229) (xy 307.220879 -287.070572) (xy 307.262475 -287.100793)
			(xy 307.298831 -287.137149) (xy 307.329052 -287.178745) (xy 307.352395 -287.224557) (xy 307.368283 -287.273456)
			(xy 307.376326 -287.324238) (xy 307.37683 -287.349946) (xy 307.376326 -287.375654) (xy 307.673244 -287.375654)
			(xy 307.673244 -287.324238) (xy 307.681287 -287.273456) (xy 307.697175 -287.224557) (xy 307.720518 -287.178745)
			(xy 307.750739 -287.137149) (xy 307.787095 -287.100793) (xy 307.828691 -287.070572) (xy 307.874503 -287.047229)
			(xy 307.923402 -287.031341) (xy 307.974184 -287.023298) (xy 308.0256 -287.023298) (xy 308.076382 -287.031341)
			(xy 308.125281 -287.047229) (xy 308.171093 -287.070572) (xy 308.212689 -287.100793) (xy 308.249045 -287.137149)
			(xy 308.279266 -287.178745) (xy 308.302609 -287.224557) (xy 308.318497 -287.273456) (xy 308.32654 -287.324238)
			(xy 308.327044 -287.349946) (xy 308.644048 -287.349946) (xy 308.648008 -287.300892) (xy 308.659785 -287.253108)
			(xy 308.679076 -287.207832) (xy 308.705379 -287.166236) (xy 308.738014 -287.129399) (xy 308.776135 -287.098274)
			(xy 308.818756 -287.073667) (xy 308.864772 -287.056215) (xy 308.912991 -287.046371) (xy 308.962166 -287.04439)
			(xy 309.011021 -287.050322) (xy 309.058292 -287.064014) (xy 309.102754 -287.085112) (xy 309.143257 -287.113068)
			(xy 309.17875 -287.14716) (xy 309.208315 -287.186504) (xy 309.231186 -287.230081) (xy 309.24677 -287.276762)
			(xy 309.254665 -287.325339) (xy 309.25516 -287.349946) (xy 309.594008 -287.349946) (xy 309.597968 -287.300892)
			(xy 309.609745 -287.253108) (xy 309.629036 -287.207832) (xy 309.655339 -287.166236) (xy 309.687974 -287.129399)
			(xy 309.726095 -287.098274) (xy 309.768716 -287.073667) (xy 309.814732 -287.056215) (xy 309.862951 -287.046371)
			(xy 309.912126 -287.04439) (xy 309.960981 -287.050322) (xy 310.008252 -287.064014) (xy 310.052714 -287.085112)
			(xy 310.093217 -287.113068) (xy 310.12871 -287.14716) (xy 310.158275 -287.186504) (xy 310.181146 -287.230081)
			(xy 310.19673 -287.276762) (xy 310.204625 -287.325339) (xy 310.20512 -287.349946) (xy 310.543968 -287.349946)
			(xy 310.547928 -287.300892) (xy 310.559705 -287.253108) (xy 310.578996 -287.207832) (xy 310.605299 -287.166236)
			(xy 310.637934 -287.129399) (xy 310.676055 -287.098274) (xy 310.718676 -287.073667) (xy 310.764692 -287.056215)
			(xy 310.812911 -287.046371) (xy 310.862086 -287.04439) (xy 310.910941 -287.050322) (xy 310.958212 -287.064014)
			(xy 311.002674 -287.085112) (xy 311.043177 -287.113068) (xy 311.07867 -287.14716) (xy 311.108235 -287.186504)
			(xy 311.131106 -287.230081) (xy 311.14669 -287.276762) (xy 311.154585 -287.325339) (xy 311.15508 -287.349946)
			(xy 311.493674 -287.349946) (xy 311.497634 -287.300892) (xy 311.509411 -287.253108) (xy 311.528702 -287.207832)
			(xy 311.555005 -287.166236) (xy 311.58764 -287.129399) (xy 311.625761 -287.098274) (xy 311.668382 -287.073667)
			(xy 311.714398 -287.056215) (xy 311.762617 -287.046371) (xy 311.811792 -287.04439) (xy 311.860647 -287.050322)
			(xy 311.907918 -287.064014) (xy 311.95238 -287.085112) (xy 311.992883 -287.113068) (xy 312.028376 -287.14716)
			(xy 312.057941 -287.186504) (xy 312.080812 -287.230081) (xy 312.096396 -287.276762) (xy 312.104291 -287.325339)
			(xy 312.104786 -287.349946) (xy 312.443888 -287.349946) (xy 312.447848 -287.300892) (xy 312.459625 -287.253108)
			(xy 312.478916 -287.207832) (xy 312.505219 -287.166236) (xy 312.537854 -287.129399) (xy 312.575975 -287.098274)
			(xy 312.618596 -287.073667) (xy 312.664612 -287.056215) (xy 312.712831 -287.046371) (xy 312.762006 -287.04439)
			(xy 312.810861 -287.050322) (xy 312.858132 -287.064014) (xy 312.902594 -287.085112) (xy 312.943097 -287.113068)
			(xy 312.97859 -287.14716) (xy 313.008155 -287.186504) (xy 313.031026 -287.230081) (xy 313.04661 -287.276762)
			(xy 313.054505 -287.325339) (xy 313.055 -287.349946) (xy 313.054505 -287.374553) (xy 313.054326 -287.375654)
			(xy 313.373258 -287.375654) (xy 313.373258 -287.324238) (xy 313.381301 -287.273456) (xy 313.397189 -287.224557)
			(xy 313.420532 -287.178745) (xy 313.450753 -287.137149) (xy 313.487109 -287.100793) (xy 313.528705 -287.070572)
			(xy 313.574517 -287.047229) (xy 313.623416 -287.031341) (xy 313.674198 -287.023298) (xy 313.725614 -287.023298)
			(xy 313.776396 -287.031341) (xy 313.825295 -287.047229) (xy 313.871107 -287.070572) (xy 313.912703 -287.100793)
			(xy 313.949059 -287.137149) (xy 313.97928 -287.178745) (xy 314.002623 -287.224557) (xy 314.018511 -287.273456)
			(xy 314.026554 -287.324238) (xy 314.027058 -287.349946) (xy 314.026554 -287.375654) (xy 314.323218 -287.375654)
			(xy 314.323218 -287.324238) (xy 314.331261 -287.273456) (xy 314.347149 -287.224557) (xy 314.370492 -287.178745)
			(xy 314.400713 -287.137149) (xy 314.437069 -287.100793) (xy 314.478665 -287.070572) (xy 314.524477 -287.047229)
			(xy 314.573376 -287.031341) (xy 314.624158 -287.023298) (xy 314.675574 -287.023298) (xy 314.726356 -287.031341)
			(xy 314.775255 -287.047229) (xy 314.821067 -287.070572) (xy 314.862663 -287.100793) (xy 314.899019 -287.137149)
			(xy 314.92924 -287.178745) (xy 314.952583 -287.224557) (xy 314.968471 -287.273456) (xy 314.976514 -287.324238)
			(xy 314.977018 -287.349946) (xy 314.977013 -287.3502) (xy 315.294276 -287.3502) (xy 315.298236 -287.301146)
			(xy 315.310013 -287.253362) (xy 315.329304 -287.208086) (xy 315.355607 -287.16649) (xy 315.388242 -287.129653)
			(xy 315.426363 -287.098528) (xy 315.468984 -287.073921) (xy 315.515 -287.056469) (xy 315.563219 -287.046625)
			(xy 315.612394 -287.044644) (xy 315.661249 -287.050576) (xy 315.70852 -287.064268) (xy 315.752982 -287.085366)
			(xy 315.793485 -287.113322) (xy 315.828978 -287.147414) (xy 315.858543 -287.186758) (xy 315.881414 -287.230335)
			(xy 315.896998 -287.277016) (xy 315.904893 -287.325593) (xy 315.905388 -287.3502) (xy 315.904893 -287.374807)
			(xy 315.896998 -287.423384) (xy 315.881414 -287.470065) (xy 315.858543 -287.513642) (xy 315.828978 -287.552986)
			(xy 315.793485 -287.587078) (xy 315.752982 -287.615034) (xy 315.70852 -287.636132) (xy 315.661249 -287.649824)
			(xy 315.612394 -287.655756) (xy 315.563219 -287.653775) (xy 315.515 -287.643931) (xy 315.468984 -287.626479)
			(xy 315.426363 -287.601872) (xy 315.388242 -287.570747) (xy 315.355607 -287.53391) (xy 315.329304 -287.492314)
			(xy 315.310013 -287.447038) (xy 315.298236 -287.399254) (xy 315.294276 -287.3502) (xy 314.977013 -287.3502)
			(xy 314.976514 -287.375654) (xy 314.968471 -287.426436) (xy 314.952583 -287.475335) (xy 314.92924 -287.521147)
			(xy 314.899019 -287.562743) (xy 314.862663 -287.599099) (xy 314.821067 -287.62932) (xy 314.775255 -287.652663)
			(xy 314.726356 -287.668551) (xy 314.675574 -287.676594) (xy 314.624158 -287.676594) (xy 314.573376 -287.668551)
			(xy 314.524477 -287.652663) (xy 314.478665 -287.62932) (xy 314.437069 -287.599099) (xy 314.400713 -287.562743)
			(xy 314.370492 -287.521147) (xy 314.347149 -287.475335) (xy 314.331261 -287.426436) (xy 314.323218 -287.375654)
			(xy 314.026554 -287.375654) (xy 314.018511 -287.426436) (xy 314.002623 -287.475335) (xy 313.97928 -287.521147)
			(xy 313.949059 -287.562743) (xy 313.912703 -287.599099) (xy 313.871107 -287.62932) (xy 313.825295 -287.652663)
			(xy 313.776396 -287.668551) (xy 313.725614 -287.676594) (xy 313.674198 -287.676594) (xy 313.623416 -287.668551)
			(xy 313.574517 -287.652663) (xy 313.528705 -287.62932) (xy 313.487109 -287.599099) (xy 313.450753 -287.562743)
			(xy 313.420532 -287.521147) (xy 313.397189 -287.475335) (xy 313.381301 -287.426436) (xy 313.373258 -287.375654)
			(xy 313.054326 -287.375654) (xy 313.04661 -287.42313) (xy 313.031026 -287.469811) (xy 313.008155 -287.513388)
			(xy 312.97859 -287.552732) (xy 312.943097 -287.586824) (xy 312.902594 -287.61478) (xy 312.858132 -287.635878)
			(xy 312.810861 -287.64957) (xy 312.762006 -287.655502) (xy 312.712831 -287.653521) (xy 312.664612 -287.643677)
			(xy 312.618596 -287.626225) (xy 312.575975 -287.601618) (xy 312.537854 -287.570493) (xy 312.505219 -287.533656)
			(xy 312.478916 -287.49206) (xy 312.459625 -287.446784) (xy 312.447848 -287.399) (xy 312.443888 -287.349946)
			(xy 312.104786 -287.349946) (xy 312.104291 -287.374553) (xy 312.096396 -287.42313) (xy 312.080812 -287.469811)
			(xy 312.057941 -287.513388) (xy 312.028376 -287.552732) (xy 311.992883 -287.586824) (xy 311.95238 -287.61478)
			(xy 311.907918 -287.635878) (xy 311.860647 -287.64957) (xy 311.811792 -287.655502) (xy 311.762617 -287.653521)
			(xy 311.714398 -287.643677) (xy 311.668382 -287.626225) (xy 311.625761 -287.601618) (xy 311.58764 -287.570493)
			(xy 311.555005 -287.533656) (xy 311.528702 -287.49206) (xy 311.509411 -287.446784) (xy 311.497634 -287.399)
			(xy 311.493674 -287.349946) (xy 311.15508 -287.349946) (xy 311.154585 -287.374553) (xy 311.14669 -287.42313)
			(xy 311.131106 -287.469811) (xy 311.108235 -287.513388) (xy 311.07867 -287.552732) (xy 311.043177 -287.586824)
			(xy 311.002674 -287.61478) (xy 310.958212 -287.635878) (xy 310.910941 -287.64957) (xy 310.862086 -287.655502)
			(xy 310.812911 -287.653521) (xy 310.764692 -287.643677) (xy 310.718676 -287.626225) (xy 310.676055 -287.601618)
			(xy 310.637934 -287.570493) (xy 310.605299 -287.533656) (xy 310.578996 -287.49206) (xy 310.559705 -287.446784)
			(xy 310.547928 -287.399) (xy 310.543968 -287.349946) (xy 310.20512 -287.349946) (xy 310.204625 -287.374553)
			(xy 310.19673 -287.42313) (xy 310.181146 -287.469811) (xy 310.158275 -287.513388) (xy 310.12871 -287.552732)
			(xy 310.093217 -287.586824) (xy 310.052714 -287.61478) (xy 310.008252 -287.635878) (xy 309.960981 -287.64957)
			(xy 309.912126 -287.655502) (xy 309.862951 -287.653521) (xy 309.814732 -287.643677) (xy 309.768716 -287.626225)
			(xy 309.726095 -287.601618) (xy 309.687974 -287.570493) (xy 309.655339 -287.533656) (xy 309.629036 -287.49206)
			(xy 309.609745 -287.446784) (xy 309.597968 -287.399) (xy 309.594008 -287.349946) (xy 309.25516 -287.349946)
			(xy 309.254665 -287.374553) (xy 309.24677 -287.42313) (xy 309.231186 -287.469811) (xy 309.208315 -287.513388)
			(xy 309.17875 -287.552732) (xy 309.143257 -287.586824) (xy 309.102754 -287.61478) (xy 309.058292 -287.635878)
			(xy 309.011021 -287.64957) (xy 308.962166 -287.655502) (xy 308.912991 -287.653521) (xy 308.864772 -287.643677)
			(xy 308.818756 -287.626225) (xy 308.776135 -287.601618) (xy 308.738014 -287.570493) (xy 308.705379 -287.533656)
			(xy 308.679076 -287.49206) (xy 308.659785 -287.446784) (xy 308.648008 -287.399) (xy 308.644048 -287.349946)
			(xy 308.327044 -287.349946) (xy 308.32654 -287.375654) (xy 308.318497 -287.426436) (xy 308.302609 -287.475335)
			(xy 308.279266 -287.521147) (xy 308.249045 -287.562743) (xy 308.212689 -287.599099) (xy 308.171093 -287.62932)
			(xy 308.125281 -287.652663) (xy 308.076382 -287.668551) (xy 308.0256 -287.676594) (xy 307.974184 -287.676594)
			(xy 307.923402 -287.668551) (xy 307.874503 -287.652663) (xy 307.828691 -287.62932) (xy 307.787095 -287.599099)
			(xy 307.750739 -287.562743) (xy 307.720518 -287.521147) (xy 307.697175 -287.475335) (xy 307.681287 -287.426436)
			(xy 307.673244 -287.375654) (xy 307.376326 -287.375654) (xy 307.368283 -287.426436) (xy 307.352395 -287.475335)
			(xy 307.329052 -287.521147) (xy 307.298831 -287.562743) (xy 307.262475 -287.599099) (xy 307.220879 -287.62932)
			(xy 307.175067 -287.652663) (xy 307.126168 -287.668551) (xy 307.075386 -287.676594) (xy 307.02397 -287.676594)
			(xy 306.973188 -287.668551) (xy 306.924289 -287.652663) (xy 306.878477 -287.62932) (xy 306.836881 -287.599099)
			(xy 306.800525 -287.562743) (xy 306.770304 -287.521147) (xy 306.746961 -287.475335) (xy 306.731073 -287.426436)
			(xy 306.72303 -287.375654) (xy 306.404352 -287.375654) (xy 306.396636 -287.42313) (xy 306.381052 -287.469811)
			(xy 306.358181 -287.513388) (xy 306.328616 -287.552732) (xy 306.293123 -287.586824) (xy 306.25262 -287.61478)
			(xy 306.208158 -287.635878) (xy 306.160887 -287.64957) (xy 306.112032 -287.655502) (xy 306.062857 -287.653521)
			(xy 306.014638 -287.643677) (xy 305.968622 -287.626225) (xy 305.926001 -287.601618) (xy 305.88788 -287.570493)
			(xy 305.855245 -287.533656) (xy 305.828942 -287.49206) (xy 305.809651 -287.446784) (xy 305.797874 -287.399)
			(xy 305.793914 -287.349946) (xy 266.485081 -287.349946) (xy 266.468071 -287.36893) (xy 266.425203 -287.404605)
			(xy 266.377597 -287.433659) (xy 266.326268 -287.455471) (xy 266.272311 -287.469577) (xy 266.216874 -287.475677)
			(xy 266.16114 -287.47364) (xy 266.106297 -287.46351) (xy 266.053513 -287.445503) (xy 266.003913 -287.420002)
			(xy 265.958555 -287.387551) (xy 265.918406 -287.348842) (xy 265.88432 -287.304699) (xy 265.857024 -287.256064)
			(xy 265.837101 -287.203973) (xy 265.824975 -287.149536) (xy 265.820904 -287.093914) (xy 265.69797 -287.093914)
			(xy 265.697461 -287.1218) (xy 265.689341 -287.176976) (xy 265.673273 -287.230383) (xy 265.649601 -287.28088)
			(xy 265.618828 -287.327393) (xy 265.581611 -287.36893) (xy 265.538743 -287.404605) (xy 265.491137 -287.433659)
			(xy 265.439808 -287.455471) (xy 265.385851 -287.469577) (xy 265.330414 -287.475677) (xy 265.27468 -287.47364)
			(xy 265.219837 -287.46351) (xy 265.167053 -287.445503) (xy 265.117453 -287.420002) (xy 265.072095 -287.387551)
			(xy 265.031946 -287.348842) (xy 264.99786 -287.304699) (xy 264.970564 -287.256064) (xy 264.950641 -287.203973)
			(xy 264.938515 -287.149536) (xy 264.934444 -287.093914) (xy 264.30097 -287.093914) (xy 264.300484 -287.121165)
			(xy 264.292728 -287.175113) (xy 264.277373 -287.227408) (xy 264.254731 -287.276985) (xy 264.225265 -287.322835)
			(xy 264.189574 -287.364026) (xy 264.148383 -287.399717) (xy 264.102533 -287.429183) (xy 264.052956 -287.451825)
			(xy 264.000661 -287.46718) (xy 263.946713 -287.474936) (xy 263.892211 -287.474936) (xy 263.838263 -287.46718)
			(xy 263.785968 -287.451825) (xy 263.736391 -287.429183) (xy 263.690541 -287.399717) (xy 263.64935 -287.364026)
			(xy 263.613659 -287.322835) (xy 263.584193 -287.276985) (xy 263.561551 -287.227408) (xy 263.546196 -287.175113)
			(xy 263.53844 -287.121165) (xy 263.537954 -287.093914) (xy 263.538517 -287.064534) (xy 263.547564 -287.006475)
			(xy 263.565401 -286.950487) (xy 263.591607 -286.897894) (xy 263.625563 -286.849937) (xy 263.666466 -286.807751)
			(xy 263.689592 -286.789622) (xy 263.69899 -286.782256) (xy 263.709404 -286.761682) (xy 263.710928 -286.657796)
			(xy 263.701022 -286.636714) (xy 263.691878 -286.629348) (xy 263.670054 -286.611117) (xy 263.631527 -286.569294)
			(xy 263.599627 -286.52222) (xy 263.575059 -286.470938) (xy 263.558366 -286.416579) (xy 263.549918 -286.360346)
			(xy 263.549384 -286.331914) (xy 263.549877 -286.304211) (xy 263.557884 -286.249386) (xy 263.57373 -286.196295)
			(xy 263.597084 -286.146051) (xy 263.611868 -286.122618) (xy 263.621774 -286.107378) (xy 263.618218 -286.071818)
			(xy 263.311386 -285.764986) (xy 263.304532 -285.757591) (xy 263.29679 -285.738992) (xy 263.2964 -285.728918)
			(xy 263.2964 -275.561806) (xy 263.295782 -275.549959) (xy 263.285188 -275.528766) (xy 263.27608 -275.521166)
			(xy 263.201658 -275.465032) (xy 263.17829 -275.460714) (xy 263.166606 -275.46427) (xy 263.074906 -275.490237)
			(xy 262.889796 -275.535693) (xy 262.703012 -275.573686) (xy 262.514854 -275.604154) (xy 262.325625 -275.627049)
			(xy 262.13563 -275.642334) (xy 261.945175 -275.649984) (xy 261.84987 -275.650452) (xy 261.751681 -275.649944)
			(xy 261.55547 -275.641828) (xy 261.359762 -275.62561) (xy 261.164891 -275.601318) (xy 260.971191 -275.568994)
			(xy 260.778992 -275.528693) (xy 260.588622 -275.480483) (xy 260.400408 -275.424448) (xy 260.21467 -275.360683)
			(xy 260.031725 -275.289297) (xy 259.851887 -275.210412) (xy 259.675463 -275.124162) (xy 259.502753 -275.030695)
			(xy 259.334053 -274.930171) (xy 259.169652 -274.822761) (xy 259.00983 -274.708649) (xy 258.85486 -274.58803)
			(xy 258.705007 -274.46111) (xy 258.560527 -274.328105) (xy 258.421667 -274.189244) (xy 258.288664 -274.044763)
			(xy 258.161745 -273.894909) (xy 258.041127 -273.739938) (xy 257.927016 -273.580115) (xy 257.819608 -273.415713)
			(xy 257.719085 -273.247012) (xy 257.62562 -273.074302) (xy 257.539372 -272.897877) (xy 257.460488 -272.718038)
			(xy 257.389103 -272.535093) (xy 257.325339 -272.349354) (xy 257.269306 -272.161139) (xy 257.221098 -271.970769)
			(xy 257.180799 -271.77857) (xy 257.148476 -271.584869) (xy 257.124186 -271.389999) (xy 257.10797 -271.194291)
			(xy 257.099855 -270.998079) (xy 257.099308 -270.89989) (xy 257.099811 -270.80194) (xy 257.107887 -270.606207)
			(xy 257.124026 -270.410974) (xy 257.1482 -270.216571) (xy 257.180369 -270.023331) (xy 257.220476 -269.831581)
			(xy 257.268454 -269.641647) (xy 257.324222 -269.453853) (xy 257.387685 -269.268518) (xy 257.458734 -269.085957)
			(xy 257.537249 -268.90648) (xy 257.623097 -268.730392) (xy 257.716131 -268.557993) (xy 257.816193 -268.389577)
			(xy 257.923113 -268.225428) (xy 258.03671 -268.065827) (xy 258.15679 -267.911045) (xy 258.283149 -267.761346)
			(xy 258.348988 -267.688822) (xy 258.355255 -267.681338) (xy 258.362129 -267.663085) (xy 258.361718 -267.643585)
			(xy 258.354081 -267.625638) (xy 258.347464 -267.618464) (xy 251.17933 -260.45033) (xy 251.151136 -260.443726)
			(xy 251.137166 -260.448552) (xy 251.107028 -260.45823) (xy 251.044606 -260.468695) (xy 251.01296 -260.46938)
			(xy 250.986046 -260.468922) (xy 250.932752 -260.461361) (xy 250.88105 -260.446382) (xy 250.831968 -260.424282)
			(xy 250.786481 -260.395501) (xy 250.745493 -260.360609) (xy 250.709818 -260.320301) (xy 250.680165 -260.275377)
			(xy 250.657124 -260.226729) (xy 250.648724 -260.201156) (xy 250.646692 -260.195314) (xy 250.640342 -260.184646)
			(xy 247.48617 -257.030474) (xy 247.478773 -257.023624) (xy 247.460174 -257.015889) (xy 247.450102 -257.015488)
			(xy 233.979466 -257.015488) (xy 233.969398 -257.015917) (xy 233.950802 -257.023639) (xy 233.943398 -257.030474)
			(xy 233.635042 -257.33883) (xy 233.627676 -257.345942) (xy 233.620056 -257.364738) (xy 233.620056 -258.802886)
			(xy 234.574078 -258.802886) (xy 234.578149 -258.747264) (xy 234.590275 -258.692827) (xy 234.610198 -258.640736)
			(xy 234.637494 -258.592101) (xy 234.67158 -258.547958) (xy 234.711729 -258.509249) (xy 234.757087 -258.476798)
			(xy 234.806687 -258.451297) (xy 234.859471 -258.43329) (xy 234.914314 -258.42316) (xy 234.970048 -258.421123)
			(xy 235.025485 -258.427223) (xy 235.079442 -258.441329) (xy 235.130771 -258.463141) (xy 235.178377 -258.492195)
			(xy 235.221245 -258.52787) (xy 235.258462 -258.569407) (xy 235.289235 -258.61592) (xy 235.312907 -258.666417)
			(xy 235.328975 -258.719824) (xy 235.335293 -258.762754) (xy 236.062264 -258.762754) (xy 236.066335 -258.707132)
			(xy 236.078461 -258.652695) (xy 236.098384 -258.600604) (xy 236.12568 -258.551969) (xy 236.159766 -258.507826)
			(xy 236.199915 -258.469117) (xy 236.245273 -258.436666) (xy 236.294873 -258.411165) (xy 236.347657 -258.393158)
			(xy 236.4025 -258.383028) (xy 236.458234 -258.380991) (xy 236.513671 -258.387091) (xy 236.567628 -258.401197)
			(xy 236.618957 -258.423009) (xy 236.666563 -258.452063) (xy 236.709431 -258.487738) (xy 236.746648 -258.529275)
			(xy 236.777421 -258.575788) (xy 236.801093 -258.626285) (xy 236.817161 -258.679692) (xy 236.825281 -258.734868)
			(xy 236.82579 -258.762754) (xy 236.825281 -258.79064) (xy 236.820526 -258.822952) (xy 237.57077 -258.822952)
			(xy 237.574841 -258.76733) (xy 237.586967 -258.712893) (xy 237.60689 -258.660802) (xy 237.634186 -258.612167)
			(xy 237.668272 -258.568024) (xy 237.708421 -258.529315) (xy 237.753779 -258.496864) (xy 237.803379 -258.471363)
			(xy 237.856163 -258.453356) (xy 237.911006 -258.443226) (xy 237.96674 -258.441189) (xy 238.022177 -258.447289)
			(xy 238.076134 -258.461395) (xy 238.127463 -258.483207) (xy 238.175069 -258.512261) (xy 238.217937 -258.547936)
			(xy 238.255154 -258.589473) (xy 238.285927 -258.635986) (xy 238.309599 -258.686483) (xy 238.325667 -258.73989)
			(xy 238.333787 -258.795066) (xy 238.334296 -258.822952) (xy 238.333787 -258.850838) (xy 238.325667 -258.906014)
			(xy 238.309599 -258.959421) (xy 238.285927 -259.009918) (xy 238.255154 -259.056431) (xy 238.217937 -259.097968)
			(xy 238.175069 -259.133643) (xy 238.127463 -259.162697) (xy 238.076134 -259.184509) (xy 238.022177 -259.198615)
			(xy 237.96674 -259.204715) (xy 237.911006 -259.202678) (xy 237.856163 -259.192548) (xy 237.803379 -259.174541)
			(xy 237.753779 -259.14904) (xy 237.708421 -259.116589) (xy 237.668272 -259.07788) (xy 237.634186 -259.033737)
			(xy 237.60689 -258.985102) (xy 237.586967 -258.933011) (xy 237.574841 -258.878574) (xy 237.57077 -258.822952)
			(xy 236.820526 -258.822952) (xy 236.817161 -258.845816) (xy 236.801093 -258.899223) (xy 236.777421 -258.94972)
			(xy 236.746648 -258.996233) (xy 236.709431 -259.03777) (xy 236.666563 -259.073445) (xy 236.618957 -259.102499)
			(xy 236.567628 -259.124311) (xy 236.513671 -259.138417) (xy 236.458234 -259.144517) (xy 236.4025 -259.14248)
			(xy 236.347657 -259.13235) (xy 236.294873 -259.114343) (xy 236.245273 -259.088842) (xy 236.199915 -259.056391)
			(xy 236.159766 -259.017682) (xy 236.12568 -258.973539) (xy 236.098384 -258.924904) (xy 236.078461 -258.872813)
			(xy 236.066335 -258.818376) (xy 236.062264 -258.762754) (xy 235.335293 -258.762754) (xy 235.337095 -258.775)
			(xy 235.337604 -258.802886) (xy 235.337095 -258.830772) (xy 235.328975 -258.885948) (xy 235.312907 -258.939355)
			(xy 235.289235 -258.989852) (xy 235.258462 -259.036365) (xy 235.221245 -259.077902) (xy 235.178377 -259.113577)
			(xy 235.130771 -259.142631) (xy 235.079442 -259.164443) (xy 235.025485 -259.178549) (xy 234.970048 -259.184649)
			(xy 234.914314 -259.182612) (xy 234.859471 -259.172482) (xy 234.806687 -259.154475) (xy 234.757087 -259.128974)
			(xy 234.711729 -259.096523) (xy 234.67158 -259.057814) (xy 234.637494 -259.013671) (xy 234.610198 -258.965036)
			(xy 234.590275 -258.912945) (xy 234.578149 -258.858508) (xy 234.574078 -258.802886) (xy 233.620056 -258.802886)
			(xy 233.620056 -259.921687) (xy 234.534472 -259.921687) (xy 234.534526 -259.867157) (xy 234.542344 -259.81319)
			(xy 234.557768 -259.760887) (xy 234.580481 -259.711312) (xy 234.610023 -259.665478) (xy 234.645789 -259.624316)
			(xy 234.687053 -259.588667) (xy 234.732972 -259.559257) (xy 234.782611 -259.536686) (xy 234.834959 -259.521412)
			(xy 234.888948 -259.513749) (xy 234.943477 -259.513851) (xy 234.997437 -259.521716) (xy 235.049727 -259.537185)
			(xy 235.099281 -259.559942) (xy 235.14509 -259.589524) (xy 235.18622 -259.625327) (xy 235.221833 -259.666622)
			(xy 235.251203 -259.712567) (xy 235.273731 -259.762226) (xy 235.288958 -259.814586) (xy 235.296575 -259.868582)
			(xy 235.296964 -259.895848) (xy 235.296964 -259.910326) (xy 235.311442 -259.934456) (xy 235.417106 -259.98932)
			(xy 235.4453 -259.987542) (xy 235.456984 -259.97916) (xy 235.481224 -259.962724) (xy 235.533701 -259.936723)
			(xy 235.589534 -259.919043) (xy 235.647411 -259.910097) (xy 235.676694 -259.909564) (xy 235.706164 -259.910128)
			(xy 235.764406 -259.919156) (xy 235.820569 -259.93703) (xy 235.873318 -259.963324) (xy 235.897674 -259.979922)
			(xy 235.909358 -259.988304) (xy 235.937552 -259.990336) (xy 236.04347 -259.935218) (xy 236.057948 -259.911088)
			(xy 236.057948 -259.894832) (xy 236.058421 -259.867576) (xy 236.066174 -259.813617) (xy 236.081529 -259.761312)
			(xy 236.104171 -259.711724) (xy 236.13364 -259.665863) (xy 236.169336 -259.624663) (xy 236.210532 -259.588963)
			(xy 236.25639 -259.559489) (xy 236.305975 -259.536842) (xy 236.358279 -259.521483) (xy 236.412237 -259.513723)
			(xy 236.46675 -259.513723) (xy 236.520708 -259.52148) (xy 236.573012 -259.536838) (xy 236.622599 -259.559483)
			(xy 236.668457 -259.588955) (xy 236.709655 -259.624654) (xy 236.745352 -259.665852) (xy 236.774823 -259.711712)
			(xy 236.797467 -259.761299) (xy 236.812823 -259.813604) (xy 236.820578 -259.867562) (xy 236.820576 -259.922075)
			(xy 236.812815 -259.976032) (xy 236.808987 -259.989066) (xy 237.085376 -259.989066) (xy 237.089447 -259.933444)
			(xy 237.101573 -259.879007) (xy 237.121496 -259.826916) (xy 237.148792 -259.778281) (xy 237.182878 -259.734138)
			(xy 237.223027 -259.695429) (xy 237.268385 -259.662978) (xy 237.317985 -259.637477) (xy 237.370769 -259.61947)
			(xy 237.425612 -259.60934) (xy 237.481346 -259.607303) (xy 237.536783 -259.613403) (xy 237.59074 -259.627509)
			(xy 237.642069 -259.649321) (xy 237.689675 -259.678375) (xy 237.732543 -259.71405) (xy 237.76976 -259.755587)
			(xy 237.800533 -259.8021) (xy 237.824205 -259.852597) (xy 237.836912 -259.894832) (xy 238.343948 -259.894832)
			(xy 238.344369 -259.868281) (xy 238.351735 -259.815693) (xy 238.366329 -259.764636) (xy 238.387868 -259.716099)
			(xy 238.415936 -259.671021) (xy 238.449988 -259.630276) (xy 238.489367 -259.594651) (xy 238.51108 -259.579364)
			(xy 238.520986 -259.572506) (xy 238.53267 -259.551932) (xy 238.53775 -259.446776) (xy 238.528352 -259.425186)
			(xy 238.518954 -259.417312) (xy 238.497942 -259.399102) (xy 238.460944 -259.357596) (xy 238.43036 -259.311161)
			(xy 238.406837 -259.26078) (xy 238.390872 -259.207519) (xy 238.382804 -259.152505) (xy 238.382302 -259.124704)
			(xy 238.382759 -259.097451) (xy 238.390516 -259.043499) (xy 238.405872 -258.991201) (xy 238.428515 -258.94162)
			(xy 238.457983 -258.895766) (xy 238.493677 -258.854573) (xy 238.534871 -258.818879) (xy 238.580725 -258.789412)
			(xy 238.630306 -258.76677) (xy 238.682605 -258.751414) (xy 238.736557 -258.743659) (xy 238.76381 -258.743196)
			(xy 238.793748 -258.743735) (xy 238.852894 -258.753052) (xy 238.90985 -258.771517) (xy 238.936784 -258.784598)
			(xy 238.947706 -258.790186) (xy 238.972344 -258.790186) (xy 239.067594 -258.740656) (xy 239.081564 -258.720844)
			(xy 239.083342 -258.708652) (xy 239.087733 -258.681741) (xy 239.103073 -258.629421) (xy 239.125704 -258.579817)
			(xy 239.155165 -258.533939) (xy 239.190857 -258.492722) (xy 239.232052 -258.457006) (xy 239.277911 -258.427516)
			(xy 239.327502 -258.404855) (xy 239.379812 -258.389483) (xy 239.433779 -258.381714) (xy 239.46104 -258.381246)
			(xy 239.48829 -258.38174) (xy 239.542235 -258.389501) (xy 239.594527 -258.404859) (xy 239.644101 -258.427502)
			(xy 239.689949 -258.456968) (xy 239.731138 -258.492658) (xy 239.766829 -258.533846) (xy 239.796296 -258.579693)
			(xy 239.818939 -258.629267) (xy 239.834297 -258.681559) (xy 239.838817 -258.71297) (xy 242.868194 -258.71297)
			(xy 242.872265 -258.657348) (xy 242.884391 -258.602911) (xy 242.904314 -258.55082) (xy 242.93161 -258.502185)
			(xy 242.965696 -258.458042) (xy 243.005845 -258.419333) (xy 243.051203 -258.386882) (xy 243.100803 -258.361381)
			(xy 243.153587 -258.343374) (xy 243.20843 -258.333244) (xy 243.264164 -258.331207) (xy 243.319601 -258.337307)
			(xy 243.373558 -258.351413) (xy 243.424887 -258.373225) (xy 243.472493 -258.402279) (xy 243.515361 -258.437954)
			(xy 243.552578 -258.479491) (xy 243.583351 -258.526004) (xy 243.607023 -258.576501) (xy 243.623091 -258.629908)
			(xy 243.631211 -258.685084) (xy 243.63172 -258.71297) (xy 243.631211 -258.740856) (xy 243.623091 -258.796032)
			(xy 243.607023 -258.849439) (xy 243.583351 -258.899936) (xy 243.552578 -258.946449) (xy 243.515361 -258.987986)
			(xy 243.472493 -259.023661) (xy 243.424887 -259.052715) (xy 243.373558 -259.074527) (xy 243.319601 -259.088633)
			(xy 243.264164 -259.094733) (xy 243.20843 -259.092696) (xy 243.153587 -259.082566) (xy 243.100803 -259.064559)
			(xy 243.051203 -259.039058) (xy 243.005845 -259.006607) (xy 242.965696 -258.967898) (xy 242.93161 -258.923755)
			(xy 242.904314 -258.87512) (xy 242.884391 -258.823029) (xy 242.872265 -258.768592) (xy 242.868194 -258.71297)
			(xy 239.838817 -258.71297) (xy 239.842059 -258.735504) (xy 239.842548 -258.762754) (xy 239.842112 -258.788647)
			(xy 239.835118 -258.839958) (xy 239.821239 -258.88985) (xy 239.800731 -258.937402) (xy 239.773972 -258.981738)
			(xy 239.741454 -259.022042) (xy 239.722914 -259.040122) (xy 239.714024 -259.048504) (xy 239.705896 -259.070602)
			(xy 239.71758 -259.17525) (xy 239.73028 -259.195316) (xy 239.740694 -259.201412) (xy 239.765181 -259.216591)
			(xy 239.809722 -259.253128) (xy 239.848258 -259.295951) (xy 239.879912 -259.344085) (xy 239.903964 -259.396433)
			(xy 239.909741 -259.41655) (xy 240.657632 -259.41655) (xy 240.661703 -259.360928) (xy 240.673829 -259.306491)
			(xy 240.693752 -259.2544) (xy 240.721048 -259.205765) (xy 240.755134 -259.161622) (xy 240.795283 -259.122913)
			(xy 240.840641 -259.090462) (xy 240.890241 -259.064961) (xy 240.943025 -259.046954) (xy 240.997868 -259.036824)
			(xy 241.053602 -259.034787) (xy 241.109039 -259.040887) (xy 241.162996 -259.054993) (xy 241.214325 -259.076805)
			(xy 241.261931 -259.105859) (xy 241.304799 -259.141534) (xy 241.342016 -259.183071) (xy 241.372789 -259.229584)
			(xy 241.396461 -259.280081) (xy 241.412529 -259.333488) (xy 241.420649 -259.388664) (xy 241.421158 -259.41655)
			(xy 241.420649 -259.444436) (xy 241.412529 -259.499612) (xy 241.396461 -259.553019) (xy 241.372789 -259.603516)
			(xy 241.342016 -259.650029) (xy 241.304799 -259.691566) (xy 241.261931 -259.727241) (xy 241.214325 -259.756295)
			(xy 241.162996 -259.778107) (xy 241.109039 -259.792213) (xy 241.053602 -259.798313) (xy 240.997868 -259.796276)
			(xy 240.943025 -259.786146) (xy 240.890241 -259.768139) (xy 240.840641 -259.742638) (xy 240.795283 -259.710187)
			(xy 240.755134 -259.671478) (xy 240.721048 -259.627335) (xy 240.693752 -259.5787) (xy 240.673829 -259.526609)
			(xy 240.661703 -259.472172) (xy 240.657632 -259.41655) (xy 239.909741 -259.41655) (xy 239.919865 -259.451805)
			(xy 239.924082 -259.480304) (xy 239.925606 -259.49275) (xy 239.93983 -259.51307) (xy 240.036096 -259.563108)
			(xy 240.060734 -259.562854) (xy 240.07191 -259.557012) (xy 240.099447 -259.543219) (xy 240.15787 -259.523738)
			(xy 240.218663 -259.513891) (xy 240.249456 -259.513324) (xy 240.276713 -259.51372) (xy 240.330673 -259.521472)
			(xy 240.382981 -259.536826) (xy 240.432571 -259.559468) (xy 240.478433 -259.588937) (xy 240.519635 -259.624634)
			(xy 240.555336 -259.665831) (xy 240.584811 -259.71169) (xy 240.607459 -259.761278) (xy 240.622818 -259.813583)
			(xy 240.630577 -259.867543) (xy 240.630577 -259.922047) (xy 241.39251 -259.922047) (xy 241.39251 -259.867553)
			(xy 241.400265 -259.813614) (xy 241.415616 -259.761327) (xy 241.438252 -259.711757) (xy 241.467712 -259.665913)
			(xy 241.503396 -259.624727) (xy 241.544577 -259.589038) (xy 241.590418 -259.559573) (xy 241.639986 -259.536932)
			(xy 241.692271 -259.521574) (xy 241.746209 -259.513813) (xy 241.773456 -259.513324) (xy 241.799269 -259.513781)
			(xy 241.850422 -259.520745) (xy 241.900166 -259.534552) (xy 241.947591 -259.554949) (xy 241.991828 -259.581562)
			(xy 242.012216 -259.597398) (xy 242.022884 -259.606034) (xy 242.050062 -259.610098) (xy 242.157504 -259.56768)
			(xy 242.174522 -259.546344) (xy 242.176554 -259.532628) (xy 242.180907 -259.505753) (xy 242.196298 -259.45353)
			(xy 242.21896 -259.404027) (xy 242.248433 -259.358251) (xy 242.284117 -259.317132) (xy 242.325286 -259.281507)
			(xy 242.371105 -259.2521) (xy 242.420639 -259.229508) (xy 242.472884 -259.214191) (xy 242.526776 -259.206462)
			(xy 242.553998 -259.205984) (xy 242.583172 -259.206572) (xy 242.640838 -259.215478) (xy 242.696478 -259.233052)
			(xy 242.748797 -259.258886) (xy 242.796577 -259.292378) (xy 242.838707 -259.332749) (xy 242.874204 -259.379058)
			(xy 242.902245 -259.430228) (xy 242.922174 -259.485069) (xy 242.928394 -259.513578) (xy 242.93068 -259.526278)
			(xy 242.946682 -259.545836) (xy 243.04879 -259.588) (xy 243.073936 -259.58546) (xy 243.084604 -259.578094)
			(xy 243.108317 -259.562756) (xy 243.159328 -259.538527) (xy 243.213357 -259.522091) (xy 243.269219 -259.513809)
			(xy 243.297456 -259.513324) (xy 243.329118 -259.513932) (xy 243.391575 -259.524379) (xy 243.451451 -259.544992)
			(xy 243.479574 -259.559552) (xy 243.490242 -259.565394) (xy 243.514372 -259.566156) (xy 243.610384 -259.521452)
			(xy 243.62537 -259.502656) (xy 243.627656 -259.490718) (xy 243.633944 -259.462496) (xy 243.653883 -259.408224)
			(xy 243.681785 -259.357584) (xy 243.717012 -259.311737) (xy 243.758756 -259.271731) (xy 243.80606 -259.238485)
			(xy 243.85784 -259.21276) (xy 243.885212 -259.203444) (xy 243.898928 -259.199126) (xy 243.91747 -259.17779)
			(xy 243.937536 -259.06095) (xy 243.927122 -259.034534) (xy 243.915692 -259.025898) (xy 243.892709 -259.007773)
			(xy 243.852111 -258.965608) (xy 243.818428 -258.917738) (xy 243.79245 -258.865285) (xy 243.774788 -258.809481)
			(xy 243.765854 -258.751634) (xy 243.765324 -258.722368) (xy 243.76581 -258.695117) (xy 243.773566 -258.641169)
			(xy 243.788921 -258.588874) (xy 243.811563 -258.539297) (xy 243.841029 -258.493447) (xy 243.87672 -258.452256)
			(xy 243.917911 -258.416565) (xy 243.963761 -258.387099) (xy 244.013338 -258.364457) (xy 244.065633 -258.349102)
			(xy 244.119581 -258.341346) (xy 244.174083 -258.341346) (xy 244.228031 -258.349102) (xy 244.280326 -258.364457)
			(xy 244.329903 -258.387099) (xy 244.375753 -258.416565) (xy 244.416944 -258.452256) (xy 244.452635 -258.493447)
			(xy 244.482101 -258.539297) (xy 244.504743 -258.588874) (xy 244.520098 -258.641169) (xy 244.527854 -258.695117)
			(xy 244.52834 -258.722368) (xy 244.527849 -258.749108) (xy 244.520376 -258.802064) (xy 244.505586 -258.853459)
			(xy 244.483769 -258.902288) (xy 244.455351 -258.947593) (xy 244.420888 -258.98849) (xy 244.381055 -259.024177)
			(xy 244.336632 -259.053956) (xy 244.288488 -259.077244) (xy 244.263164 -259.085842) (xy 244.249448 -259.09016)
			(xy 244.230906 -259.111496) (xy 244.21084 -259.228336) (xy 244.221254 -259.254752) (xy 244.232684 -259.263388)
			(xy 244.255656 -259.281528) (xy 244.296255 -259.323689) (xy 244.32994 -259.371556) (xy 244.35592 -259.424005)
			(xy 244.373585 -259.479807) (xy 244.382521 -259.537652) (xy 244.383052 -259.566918) (xy 244.382539 -259.594168)
			(xy 244.374781 -259.648112) (xy 244.359426 -259.700404) (xy 244.336786 -259.749978) (xy 244.307322 -259.795826)
			(xy 244.271634 -259.837015) (xy 244.230447 -259.872706) (xy 244.196024 -259.894832) (xy 244.439438 -259.894832)
			(xy 244.443509 -259.83921) (xy 244.455635 -259.784773) (xy 244.475558 -259.732682) (xy 244.502854 -259.684047)
			(xy 244.53694 -259.639904) (xy 244.577089 -259.601195) (xy 244.622447 -259.568744) (xy 244.672047 -259.543243)
			(xy 244.724831 -259.525236) (xy 244.779674 -259.515106) (xy 244.835408 -259.513069) (xy 244.890845 -259.519169)
			(xy 244.944802 -259.533275) (xy 244.996131 -259.555087) (xy 245.043737 -259.584141) (xy 245.086605 -259.619816)
			(xy 245.123822 -259.661353) (xy 245.154595 -259.707866) (xy 245.178267 -259.758363) (xy 245.194335 -259.81177)
			(xy 245.202455 -259.866946) (xy 245.202964 -259.894832) (xy 245.202455 -259.922718) (xy 245.194335 -259.977894)
			(xy 245.178267 -260.031301) (xy 245.154595 -260.081798) (xy 245.123822 -260.128311) (xy 245.086605 -260.169848)
			(xy 245.043737 -260.205523) (xy 244.996131 -260.234577) (xy 244.944802 -260.256389) (xy 244.890845 -260.270495)
			(xy 244.835408 -260.276595) (xy 244.779674 -260.274558) (xy 244.724831 -260.264428) (xy 244.672047 -260.246421)
			(xy 244.622447 -260.22092) (xy 244.577089 -260.188469) (xy 244.53694 -260.14976) (xy 244.502854 -260.105617)
			(xy 244.475558 -260.056982) (xy 244.455635 -260.004891) (xy 244.443509 -259.950454) (xy 244.439438 -259.894832)
			(xy 244.196024 -259.894832) (xy 244.184601 -259.902174) (xy 244.135028 -259.924817) (xy 244.082738 -259.940176)
			(xy 244.028794 -259.947937) (xy 244.001544 -259.948426) (xy 243.969882 -259.947812) (xy 243.907425 -259.937367)
			(xy 243.84755 -259.916756) (xy 243.819426 -259.902198) (xy 243.808758 -259.896356) (xy 243.784628 -259.895594)
			(xy 243.688616 -259.940298) (xy 243.67363 -259.959094) (xy 243.671344 -259.971032) (xy 243.664987 -259.99938)
			(xy 243.644876 -260.053881) (xy 243.616737 -260.104705) (xy 243.58122 -260.150677) (xy 243.539147 -260.190735)
			(xy 243.491488 -260.223953) (xy 243.439346 -260.249565) (xy 243.383924 -260.266979) (xy 243.326503 -260.275792)
			(xy 243.297456 -260.27634) (xy 243.26828 -260.275764) (xy 243.210611 -260.266864) (xy 243.154967 -260.249293)
			(xy 243.102645 -260.22346) (xy 243.054862 -260.189966) (xy 243.012732 -260.149593) (xy 242.977235 -260.103279)
			(xy 242.949199 -260.052103) (xy 242.929275 -259.997258) (xy 242.92306 -259.968746) (xy 242.920774 -259.956046)
			(xy 242.904772 -259.936488) (xy 242.802664 -259.894324) (xy 242.777518 -259.896864) (xy 242.76685 -259.90423)
			(xy 242.743125 -259.919548) (xy 242.692118 -259.943781) (xy 242.638093 -259.960222) (xy 242.582234 -259.968511)
			(xy 242.553998 -259.969) (xy 242.528184 -259.968585) (xy 242.477028 -259.961613) (xy 242.427283 -259.947798)
			(xy 242.379859 -259.927391) (xy 242.335624 -259.900768) (xy 242.315238 -259.884926) (xy 242.30457 -259.87629)
			(xy 242.277392 -259.872226) (xy 242.16995 -259.914644) (xy 242.152932 -259.93598) (xy 242.1509 -259.949696)
			(xy 242.146514 -259.976565) (xy 242.131122 -260.028784) (xy 242.108462 -260.078283) (xy 242.078991 -260.124057)
			(xy 242.043311 -260.165174) (xy 242.002146 -260.200799) (xy 241.956333 -260.230207) (xy 241.906803 -260.252802)
			(xy 241.854564 -260.268123) (xy 241.800676 -260.275859) (xy 241.773456 -260.27634) (xy 241.746209 -260.275787)
			(xy 241.692271 -260.268026) (xy 241.639986 -260.252668) (xy 241.590418 -260.230027) (xy 241.544577 -260.200562)
			(xy 241.503396 -260.164873) (xy 241.467712 -260.123687) (xy 241.438252 -260.077843) (xy 241.415616 -260.028273)
			(xy 241.400265 -259.975986) (xy 241.39251 -259.922047) (xy 240.630577 -259.922047) (xy 240.630577 -259.922057)
			(xy 240.622818 -259.976017) (xy 240.607459 -260.028322) (xy 240.584811 -260.07791) (xy 240.555336 -260.123769)
			(xy 240.519635 -260.164966) (xy 240.478433 -260.200663) (xy 240.432571 -260.230132) (xy 240.382981 -260.252774)
			(xy 240.330673 -260.268128) (xy 240.276713 -260.27588) (xy 240.249456 -260.27634) (xy 240.221935 -260.275908)
			(xy 240.167468 -260.267972) (xy 240.114705 -260.252298) (xy 240.064738 -260.229212) (xy 240.018603 -260.199192)
			(xy 239.977256 -260.16286) (xy 239.941552 -260.120969) (xy 239.912233 -260.074386) (xy 239.889904 -260.024076)
			(xy 239.875029 -259.971082) (xy 239.870996 -259.943854) (xy 239.869472 -259.931408) (xy 239.855248 -259.911088)
			(xy 239.758982 -259.86105) (xy 239.734344 -259.861304) (xy 239.723168 -259.867146) (xy 239.695634 -259.880944)
			(xy 239.637209 -259.900423) (xy 239.576415 -259.910268) (xy 239.545622 -259.910834) (xy 239.518373 -259.910301)
			(xy 239.464428 -259.902549) (xy 239.412136 -259.887198) (xy 239.36256 -259.864561) (xy 239.316711 -259.835099)
			(xy 239.275521 -259.799413) (xy 239.239829 -259.758227) (xy 239.210362 -259.712382) (xy 239.187719 -259.662809)
			(xy 239.172362 -259.610519) (xy 239.164602 -259.556575) (xy 239.164114 -259.529326) (xy 239.164586 -259.502292)
			(xy 239.172228 -259.448767) (xy 239.187349 -259.396857) (xy 239.209646 -259.347601) (xy 239.238673 -259.301985)
			(xy 239.273848 -259.260924) (xy 239.314467 -259.225239) (xy 239.336834 -259.210048) (xy 239.344464 -259.204602)
			(xy 239.355416 -259.189405) (xy 239.360185 -259.171289) (xy 239.358136 -259.152669) (xy 239.349541 -259.136024)
			(xy 239.335545 -259.123572) (xy 239.326928 -259.119878) (xy 239.31701 -259.116102) (xy 239.297568 -259.107587)
			(xy 239.288066 -259.10286) (xy 239.277144 -259.097272) (xy 239.252506 -259.097272) (xy 239.157256 -259.146802)
			(xy 239.143286 -259.166614) (xy 239.141508 -259.178806) (xy 239.137315 -259.204926) (xy 239.122632 -259.255748)
			(xy 239.101065 -259.304054) (xy 239.07303 -259.348915) (xy 239.039063 -259.389471) (xy 238.999818 -259.424944)
			(xy 238.978186 -259.440172) (xy 238.96828 -259.44703) (xy 238.956596 -259.467604) (xy 238.951516 -259.57276)
			(xy 238.960914 -259.59435) (xy 238.970312 -259.602224) (xy 238.991286 -259.620476) (xy 239.028289 -259.661972)
			(xy 239.058878 -259.708398) (xy 239.082408 -259.758771) (xy 239.098381 -259.812025) (xy 239.106457 -259.867033)
			(xy 239.106964 -259.894832) (xy 239.106478 -259.922083) (xy 239.098722 -259.976031) (xy 239.083367 -260.028326)
			(xy 239.060725 -260.077903) (xy 239.031259 -260.123753) (xy 238.995568 -260.164944) (xy 238.954377 -260.200635)
			(xy 238.908527 -260.230101) (xy 238.85895 -260.252743) (xy 238.806655 -260.268098) (xy 238.752707 -260.275854)
			(xy 238.698205 -260.275854) (xy 238.644257 -260.268098) (xy 238.591962 -260.252743) (xy 238.542385 -260.230101)
			(xy 238.496535 -260.200635) (xy 238.455344 -260.164944) (xy 238.419653 -260.123753) (xy 238.390187 -260.077903)
			(xy 238.367545 -260.028326) (xy 238.35219 -259.976031) (xy 238.344434 -259.922083) (xy 238.343948 -259.894832)
			(xy 237.836912 -259.894832) (xy 237.840273 -259.906004) (xy 237.848393 -259.96118) (xy 237.848902 -259.989066)
			(xy 237.848393 -260.016952) (xy 237.840273 -260.072128) (xy 237.824205 -260.125535) (xy 237.800533 -260.176032)
			(xy 237.76976 -260.222545) (xy 237.732543 -260.264082) (xy 237.689675 -260.299757) (xy 237.642069 -260.328811)
			(xy 237.59074 -260.350623) (xy 237.536783 -260.364729) (xy 237.481346 -260.370829) (xy 237.425612 -260.368792)
			(xy 237.370769 -260.358662) (xy 237.317985 -260.340655) (xy 237.268385 -260.315154) (xy 237.223027 -260.282703)
			(xy 237.182878 -260.243994) (xy 237.148792 -260.199851) (xy 237.121496 -260.151216) (xy 237.101573 -260.099125)
			(xy 237.089447 -260.044688) (xy 237.085376 -259.989066) (xy 236.808987 -259.989066) (xy 236.797454 -260.028336)
			(xy 236.774805 -260.077921) (xy 236.74533 -260.123778) (xy 236.709628 -260.164973) (xy 236.668427 -260.200667)
			(xy 236.622566 -260.230135) (xy 236.572977 -260.252775) (xy 236.520671 -260.268128) (xy 236.466712 -260.27588)
			(xy 236.439456 -260.27634) (xy 236.409985 -260.275818) (xy 236.351739 -260.26678) (xy 236.295576 -260.248895)
			(xy 236.24283 -260.222587) (xy 236.218476 -260.205982) (xy 236.206792 -260.1976) (xy 236.178598 -260.195568)
			(xy 236.07268 -260.250686) (xy 236.058202 -260.274816) (xy 236.058202 -260.291072) (xy 236.057752 -260.31835)
			(xy 236.049985 -260.372349) (xy 236.034606 -260.424692) (xy 236.011927 -260.474311) (xy 235.982412 -260.520193)
			(xy 235.946663 -260.561403) (xy 235.905408 -260.5971) (xy 235.859489 -260.626558) (xy 235.809842 -260.649174)
			(xy 235.75748 -260.664487) (xy 235.70347 -260.672186) (xy 235.648915 -260.672114) (xy 235.594926 -260.664271)
			(xy 235.542605 -260.648818) (xy 235.493019 -260.62607) (xy 235.447178 -260.59649) (xy 235.406018 -260.560683)
			(xy 235.370379 -260.519378) (xy 235.340986 -260.473417) (xy 235.31844 -260.423739) (xy 235.3032 -260.371355)
			(xy 235.295576 -260.317335) (xy 235.295186 -260.290056) (xy 235.295186 -260.275578) (xy 235.280708 -260.251448)
			(xy 235.175044 -260.196584) (xy 235.14685 -260.198362) (xy 235.135166 -260.206744) (xy 235.110912 -260.223159)
			(xy 235.05844 -260.249164) (xy 235.002612 -260.26685) (xy 234.944737 -260.275803) (xy 234.915456 -260.27634)
			(xy 234.888191 -260.275798) (xy 234.834218 -260.268027) (xy 234.781901 -260.25265) (xy 234.732306 -260.22998)
			(xy 234.686446 -260.200479) (xy 234.645253 -260.164748) (xy 234.609568 -260.123516) (xy 234.580118 -260.077622)
			(xy 234.557502 -260.028003) (xy 234.542183 -259.975669) (xy 234.534472 -259.921687) (xy 233.620056 -259.921687)
			(xy 233.620056 -260.797548) (xy 234.533438 -260.797548) (xy 234.537509 -260.741926) (xy 234.549635 -260.687489)
			(xy 234.569558 -260.635398) (xy 234.596854 -260.586763) (xy 234.63094 -260.54262) (xy 234.671089 -260.503911)
			(xy 234.716447 -260.47146) (xy 234.766047 -260.445959) (xy 234.818831 -260.427952) (xy 234.873674 -260.417822)
			(xy 234.929408 -260.415785) (xy 234.984845 -260.421885) (xy 235.038802 -260.435991) (xy 235.090131 -260.457803)
			(xy 235.137737 -260.486857) (xy 235.180605 -260.522532) (xy 235.217822 -260.564069) (xy 235.248595 -260.610582)
			(xy 235.272267 -260.661079) (xy 235.288335 -260.714486) (xy 235.296455 -260.769662) (xy 235.296964 -260.797548)
			(xy 236.057438 -260.797548) (xy 236.061509 -260.741926) (xy 236.073635 -260.687489) (xy 236.093558 -260.635398)
			(xy 236.120854 -260.586763) (xy 236.15494 -260.54262) (xy 236.195089 -260.503911) (xy 236.240447 -260.47146)
			(xy 236.290047 -260.445959) (xy 236.342831 -260.427952) (xy 236.397674 -260.417822) (xy 236.453408 -260.415785)
			(xy 236.508845 -260.421885) (xy 236.562802 -260.435991) (xy 236.614131 -260.457803) (xy 236.661737 -260.486857)
			(xy 236.704605 -260.522532) (xy 236.741822 -260.564069) (xy 236.772595 -260.610582) (xy 236.796267 -260.661079)
			(xy 236.812335 -260.714486) (xy 236.820455 -260.769662) (xy 236.820964 -260.797548) (xy 237.581438 -260.797548)
			(xy 237.585509 -260.741926) (xy 237.597635 -260.687489) (xy 237.617558 -260.635398) (xy 237.644854 -260.586763)
			(xy 237.67894 -260.54262) (xy 237.719089 -260.503911) (xy 237.764447 -260.47146) (xy 237.814047 -260.445959)
			(xy 237.866831 -260.427952) (xy 237.921674 -260.417822) (xy 237.977408 -260.415785) (xy 238.032845 -260.421885)
			(xy 238.086802 -260.435991) (xy 238.138131 -260.457803) (xy 238.185737 -260.486857) (xy 238.228605 -260.522532)
			(xy 238.265822 -260.564069) (xy 238.296595 -260.610582) (xy 238.320267 -260.661079) (xy 238.336335 -260.714486)
			(xy 238.344455 -260.769662) (xy 238.344964 -260.797548) (xy 239.105438 -260.797548) (xy 239.109509 -260.741926)
			(xy 239.121635 -260.687489) (xy 239.141558 -260.635398) (xy 239.168854 -260.586763) (xy 239.20294 -260.54262)
			(xy 239.243089 -260.503911) (xy 239.288447 -260.47146) (xy 239.338047 -260.445959) (xy 239.390831 -260.427952)
			(xy 239.445674 -260.417822) (xy 239.501408 -260.415785) (xy 239.556845 -260.421885) (xy 239.610802 -260.435991)
			(xy 239.662131 -260.457803) (xy 239.709737 -260.486857) (xy 239.752605 -260.522532) (xy 239.789822 -260.564069)
			(xy 239.820595 -260.610582) (xy 239.844267 -260.661079) (xy 239.860335 -260.714486) (xy 239.868455 -260.769662)
			(xy 239.868964 -260.797548) (xy 240.629438 -260.797548) (xy 240.633509 -260.741926) (xy 240.645635 -260.687489)
			(xy 240.665558 -260.635398) (xy 240.692854 -260.586763) (xy 240.72694 -260.54262) (xy 240.767089 -260.503911)
			(xy 240.812447 -260.47146) (xy 240.862047 -260.445959) (xy 240.914831 -260.427952) (xy 240.969674 -260.417822)
			(xy 241.025408 -260.415785) (xy 241.080845 -260.421885) (xy 241.134802 -260.435991) (xy 241.186131 -260.457803)
			(xy 241.233737 -260.486857) (xy 241.276605 -260.522532) (xy 241.313822 -260.564069) (xy 241.344595 -260.610582)
			(xy 241.368267 -260.661079) (xy 241.384335 -260.714486) (xy 241.392455 -260.769662) (xy 241.392964 -260.797548)
			(xy 242.153438 -260.797548) (xy 242.157509 -260.741926) (xy 242.169635 -260.687489) (xy 242.189558 -260.635398)
			(xy 242.216854 -260.586763) (xy 242.25094 -260.54262) (xy 242.291089 -260.503911) (xy 242.336447 -260.47146)
			(xy 242.386047 -260.445959) (xy 242.438831 -260.427952) (xy 242.493674 -260.417822) (xy 242.549408 -260.415785)
			(xy 242.604845 -260.421885) (xy 242.658802 -260.435991) (xy 242.710131 -260.457803) (xy 242.757737 -260.486857)
			(xy 242.800605 -260.522532) (xy 242.837822 -260.564069) (xy 242.868595 -260.610582) (xy 242.892267 -260.661079)
			(xy 242.908335 -260.714486) (xy 242.916455 -260.769662) (xy 242.916964 -260.797548) (xy 242.916455 -260.825434)
			(xy 242.912223 -260.85419) (xy 243.298216 -260.85419) (xy 243.302287 -260.798568) (xy 243.314413 -260.744131)
			(xy 243.334336 -260.69204) (xy 243.361632 -260.643405) (xy 243.395718 -260.599262) (xy 243.435867 -260.560553)
			(xy 243.481225 -260.528102) (xy 243.530825 -260.502601) (xy 243.583609 -260.484594) (xy 243.638452 -260.474464)
			(xy 243.694186 -260.472427) (xy 243.749623 -260.478527) (xy 243.80358 -260.492633) (xy 243.854909 -260.514445)
			(xy 243.902515 -260.543499) (xy 243.945383 -260.579174) (xy 243.9826 -260.620711) (xy 244.013373 -260.667224)
			(xy 244.037045 -260.717721) (xy 244.053113 -260.771128) (xy 244.057001 -260.797548) (xy 244.439438 -260.797548)
			(xy 244.443509 -260.741926) (xy 244.455635 -260.687489) (xy 244.475558 -260.635398) (xy 244.502854 -260.586763)
			(xy 244.53694 -260.54262) (xy 244.577089 -260.503911) (xy 244.622447 -260.47146) (xy 244.672047 -260.445959)
			(xy 244.724831 -260.427952) (xy 244.779674 -260.417822) (xy 244.835408 -260.415785) (xy 244.890845 -260.421885)
			(xy 244.944802 -260.435991) (xy 244.996131 -260.457803) (xy 245.043737 -260.486857) (xy 245.086605 -260.522532)
			(xy 245.123822 -260.564069) (xy 245.154595 -260.610582) (xy 245.178267 -260.661079) (xy 245.194335 -260.714486)
			(xy 245.202455 -260.769662) (xy 245.202964 -260.797548) (xy 245.202455 -260.825434) (xy 245.194335 -260.88061)
			(xy 245.178267 -260.934017) (xy 245.154595 -260.984514) (xy 245.123822 -261.031027) (xy 245.086605 -261.072564)
			(xy 245.043737 -261.108239) (xy 244.996131 -261.137293) (xy 244.944802 -261.159105) (xy 244.890845 -261.173211)
			(xy 244.835408 -261.179311) (xy 244.779674 -261.177274) (xy 244.724831 -261.167144) (xy 244.672047 -261.149137)
			(xy 244.622447 -261.123636) (xy 244.577089 -261.091185) (xy 244.53694 -261.052476) (xy 244.502854 -261.008333)
			(xy 244.475558 -260.959698) (xy 244.455635 -260.907607) (xy 244.443509 -260.85317) (xy 244.439438 -260.797548)
			(xy 244.057001 -260.797548) (xy 244.061233 -260.826304) (xy 244.061742 -260.85419) (xy 244.061233 -260.882076)
			(xy 244.053113 -260.937252) (xy 244.037045 -260.990659) (xy 244.013373 -261.041156) (xy 243.9826 -261.087669)
			(xy 243.945383 -261.129206) (xy 243.902515 -261.164881) (xy 243.854909 -261.193935) (xy 243.80358 -261.215747)
			(xy 243.749623 -261.229853) (xy 243.694186 -261.235953) (xy 243.638452 -261.233916) (xy 243.583609 -261.223786)
			(xy 243.530825 -261.205779) (xy 243.481225 -261.180278) (xy 243.435867 -261.147827) (xy 243.395718 -261.109118)
			(xy 243.361632 -261.064975) (xy 243.334336 -261.01634) (xy 243.314413 -260.964249) (xy 243.302287 -260.909812)
			(xy 243.298216 -260.85419) (xy 242.912223 -260.85419) (xy 242.908335 -260.88061) (xy 242.892267 -260.934017)
			(xy 242.868595 -260.984514) (xy 242.837822 -261.031027) (xy 242.800605 -261.072564) (xy 242.757737 -261.108239)
			(xy 242.710131 -261.137293) (xy 242.658802 -261.159105) (xy 242.604845 -261.173211) (xy 242.549408 -261.179311)
			(xy 242.493674 -261.177274) (xy 242.438831 -261.167144) (xy 242.386047 -261.149137) (xy 242.336447 -261.123636)
			(xy 242.291089 -261.091185) (xy 242.25094 -261.052476) (xy 242.216854 -261.008333) (xy 242.189558 -260.959698)
			(xy 242.169635 -260.907607) (xy 242.157509 -260.85317) (xy 242.153438 -260.797548) (xy 241.392964 -260.797548)
			(xy 241.392455 -260.825434) (xy 241.384335 -260.88061) (xy 241.368267 -260.934017) (xy 241.344595 -260.984514)
			(xy 241.313822 -261.031027) (xy 241.276605 -261.072564) (xy 241.233737 -261.108239) (xy 241.186131 -261.137293)
			(xy 241.134802 -261.159105) (xy 241.080845 -261.173211) (xy 241.025408 -261.179311) (xy 240.969674 -261.177274)
			(xy 240.914831 -261.167144) (xy 240.862047 -261.149137) (xy 240.812447 -261.123636) (xy 240.767089 -261.091185)
			(xy 240.72694 -261.052476) (xy 240.692854 -261.008333) (xy 240.665558 -260.959698) (xy 240.645635 -260.907607)
			(xy 240.633509 -260.85317) (xy 240.629438 -260.797548) (xy 239.868964 -260.797548) (xy 239.868455 -260.825434)
			(xy 239.860335 -260.88061) (xy 239.844267 -260.934017) (xy 239.820595 -260.984514) (xy 239.789822 -261.031027)
			(xy 239.752605 -261.072564) (xy 239.709737 -261.108239) (xy 239.662131 -261.137293) (xy 239.610802 -261.159105)
			(xy 239.556845 -261.173211) (xy 239.501408 -261.179311) (xy 239.445674 -261.177274) (xy 239.390831 -261.167144)
			(xy 239.338047 -261.149137) (xy 239.288447 -261.123636) (xy 239.243089 -261.091185) (xy 239.20294 -261.052476)
			(xy 239.168854 -261.008333) (xy 239.141558 -260.959698) (xy 239.121635 -260.907607) (xy 239.109509 -260.85317)
			(xy 239.105438 -260.797548) (xy 238.344964 -260.797548) (xy 238.344455 -260.825434) (xy 238.336335 -260.88061)
			(xy 238.320267 -260.934017) (xy 238.296595 -260.984514) (xy 238.265822 -261.031027) (xy 238.228605 -261.072564)
			(xy 238.185737 -261.108239) (xy 238.138131 -261.137293) (xy 238.086802 -261.159105) (xy 238.032845 -261.173211)
			(xy 237.977408 -261.179311) (xy 237.921674 -261.177274) (xy 237.866831 -261.167144) (xy 237.814047 -261.149137)
			(xy 237.764447 -261.123636) (xy 237.719089 -261.091185) (xy 237.67894 -261.052476) (xy 237.644854 -261.008333)
			(xy 237.617558 -260.959698) (xy 237.597635 -260.907607) (xy 237.585509 -260.85317) (xy 237.581438 -260.797548)
			(xy 236.820964 -260.797548) (xy 236.820455 -260.825434) (xy 236.812335 -260.88061) (xy 236.796267 -260.934017)
			(xy 236.772595 -260.984514) (xy 236.741822 -261.031027) (xy 236.704605 -261.072564) (xy 236.661737 -261.108239)
			(xy 236.614131 -261.137293) (xy 236.562802 -261.159105) (xy 236.508845 -261.173211) (xy 236.453408 -261.179311)
			(xy 236.397674 -261.177274) (xy 236.342831 -261.167144) (xy 236.290047 -261.149137) (xy 236.240447 -261.123636)
			(xy 236.195089 -261.091185) (xy 236.15494 -261.052476) (xy 236.120854 -261.008333) (xy 236.093558 -260.959698)
			(xy 236.073635 -260.907607) (xy 236.061509 -260.85317) (xy 236.057438 -260.797548) (xy 235.296964 -260.797548)
			(xy 235.296455 -260.825434) (xy 235.288335 -260.88061) (xy 235.272267 -260.934017) (xy 235.248595 -260.984514)
			(xy 235.217822 -261.031027) (xy 235.180605 -261.072564) (xy 235.137737 -261.108239) (xy 235.090131 -261.137293)
			(xy 235.038802 -261.159105) (xy 234.984845 -261.173211) (xy 234.929408 -261.179311) (xy 234.873674 -261.177274)
			(xy 234.818831 -261.167144) (xy 234.766047 -261.149137) (xy 234.716447 -261.123636) (xy 234.671089 -261.091185)
			(xy 234.63094 -261.052476) (xy 234.596854 -261.008333) (xy 234.569558 -260.959698) (xy 234.549635 -260.907607)
			(xy 234.537509 -260.85317) (xy 234.533438 -260.797548) (xy 233.620056 -260.797548) (xy 233.620056 -273.471386)
			(xy 248.784108 -273.471386) (xy 248.788179 -273.415764) (xy 248.800305 -273.361327) (xy 248.820228 -273.309236)
			(xy 248.847524 -273.260601) (xy 248.88161 -273.216458) (xy 248.921759 -273.177749) (xy 248.967117 -273.145298)
			(xy 249.016717 -273.119797) (xy 249.069501 -273.10179) (xy 249.124344 -273.09166) (xy 249.180078 -273.089623)
			(xy 249.235515 -273.095723) (xy 249.289472 -273.109829) (xy 249.340801 -273.131641) (xy 249.388407 -273.160695)
			(xy 249.431275 -273.19637) (xy 249.468492 -273.237907) (xy 249.499265 -273.28442) (xy 249.522937 -273.334917)
			(xy 249.539005 -273.388324) (xy 249.547125 -273.4435) (xy 249.547634 -273.471386) (xy 249.547125 -273.499272)
			(xy 249.539005 -273.554448) (xy 249.522937 -273.607855) (xy 249.499265 -273.658352) (xy 249.468492 -273.704865)
			(xy 249.431275 -273.746402) (xy 249.388407 -273.782077) (xy 249.340801 -273.811131) (xy 249.289472 -273.832943)
			(xy 249.235515 -273.847049) (xy 249.180078 -273.853149) (xy 249.124344 -273.851112) (xy 249.069501 -273.840982)
			(xy 249.016717 -273.822975) (xy 248.967117 -273.797474) (xy 248.921759 -273.765023) (xy 248.88161 -273.726314)
			(xy 248.847524 -273.682171) (xy 248.820228 -273.633536) (xy 248.800305 -273.581445) (xy 248.788179 -273.527008)
			(xy 248.784108 -273.471386) (xy 233.620056 -273.471386) (xy 233.620056 -273.98345) (xy 249.491246 -273.98345)
			(xy 249.491732 -273.956199) (xy 249.499488 -273.902251) (xy 249.514843 -273.849956) (xy 249.537485 -273.800379)
			(xy 249.566951 -273.754529) (xy 249.602642 -273.713338) (xy 249.643833 -273.677647) (xy 249.689683 -273.648181)
			(xy 249.73926 -273.625539) (xy 249.791555 -273.610184) (xy 249.845503 -273.602428) (xy 249.900005 -273.602428)
			(xy 249.953953 -273.610184) (xy 250.006248 -273.625539) (xy 250.055825 -273.648181) (xy 250.101675 -273.677647)
			(xy 250.142866 -273.713338) (xy 250.178557 -273.754529) (xy 250.208023 -273.800379) (xy 250.230665 -273.849956)
			(xy 250.24602 -273.902251) (xy 250.253776 -273.956199) (xy 250.254262 -273.98345) (xy 250.253689 -274.014423)
			(xy 250.243735 -274.075562) (xy 250.23445 -274.105116) (xy 250.231148 -274.114768) (xy 250.232418 -274.134326)
			(xy 250.272042 -274.216368) (xy 250.286774 -274.229576) (xy 250.296172 -274.233132) (xy 250.323475 -274.243568)
			(xy 250.374805 -274.271521) (xy 250.421269 -274.306979) (xy 250.461779 -274.349111) (xy 250.495386 -274.39693)
			(xy 250.521304 -274.449317) (xy 250.538925 -274.505046) (xy 250.547838 -274.56281) (xy 250.548394 -274.592034)
			(xy 250.547908 -274.619285) (xy 250.540152 -274.673233) (xy 250.524797 -274.725528) (xy 250.502155 -274.775105)
			(xy 250.472689 -274.820955) (xy 250.436998 -274.862146) (xy 250.395807 -274.897837) (xy 250.349957 -274.927303)
			(xy 250.30038 -274.949945) (xy 250.248085 -274.9653) (xy 250.194137 -274.973056) (xy 250.139635 -274.973056)
			(xy 250.085687 -274.9653) (xy 250.033392 -274.949945) (xy 249.983815 -274.927303) (xy 249.937965 -274.897837)
			(xy 249.896774 -274.862146) (xy 249.861083 -274.820955) (xy 249.831617 -274.775105) (xy 249.808975 -274.725528)
			(xy 249.79362 -274.673233) (xy 249.785864 -274.619285) (xy 249.785378 -274.592034) (xy 249.785945 -274.561061)
			(xy 249.795903 -274.499922) (xy 249.80519 -274.470368) (xy 249.808492 -274.460716) (xy 249.807222 -274.441158)
			(xy 249.767598 -274.359116) (xy 249.752866 -274.345908) (xy 249.743468 -274.342352) (xy 249.716146 -274.331963)
			(xy 249.664817 -274.304001) (xy 249.618355 -274.268534) (xy 249.577848 -274.226395) (xy 249.544243 -274.17857)
			(xy 249.518329 -274.126177) (xy 249.50071 -274.070444) (xy 249.4918 -274.012676) (xy 249.491246 -273.98345)
			(xy 233.620056 -273.98345) (xy 233.620056 -274.632674) (xy 242.945156 -274.632674) (xy 242.949227 -274.577052)
			(xy 242.961353 -274.522615) (xy 242.981276 -274.470524) (xy 243.008572 -274.421889) (xy 243.042658 -274.377746)
			(xy 243.082807 -274.339037) (xy 243.128165 -274.306586) (xy 243.177765 -274.281085) (xy 243.230549 -274.263078)
			(xy 243.285392 -274.252948) (xy 243.341126 -274.250911) (xy 243.396563 -274.257011) (xy 243.45052 -274.271117)
			(xy 243.501849 -274.292929) (xy 243.549455 -274.321983) (xy 243.592323 -274.357658) (xy 243.62954 -274.399195)
			(xy 243.660313 -274.445708) (xy 243.683985 -274.496205) (xy 243.700053 -274.549612) (xy 243.708173 -274.604788)
			(xy 243.708682 -274.632674) (xy 243.708173 -274.66056) (xy 243.700053 -274.715736) (xy 243.684312 -274.768056)
			(xy 245.074946 -274.768056) (xy 245.079017 -274.712434) (xy 245.091143 -274.657997) (xy 245.111066 -274.605906)
			(xy 245.138362 -274.557271) (xy 245.172448 -274.513128) (xy 245.212597 -274.474419) (xy 245.257955 -274.441968)
			(xy 245.307555 -274.416467) (xy 245.360339 -274.39846) (xy 245.415182 -274.38833) (xy 245.470916 -274.386293)
			(xy 245.526353 -274.392393) (xy 245.58031 -274.406499) (xy 245.631639 -274.428311) (xy 245.679245 -274.457365)
			(xy 245.715319 -274.487386) (xy 248.722386 -274.487386) (xy 248.726457 -274.431764) (xy 248.738583 -274.377327)
			(xy 248.758506 -274.325236) (xy 248.785802 -274.276601) (xy 248.819888 -274.232458) (xy 248.860037 -274.193749)
			(xy 248.905395 -274.161298) (xy 248.954995 -274.135797) (xy 249.007779 -274.11779) (xy 249.062622 -274.10766)
			(xy 249.118356 -274.105623) (xy 249.173793 -274.111723) (xy 249.22775 -274.125829) (xy 249.279079 -274.147641)
			(xy 249.326685 -274.176695) (xy 249.369553 -274.21237) (xy 249.40677 -274.253907) (xy 249.437543 -274.30042)
			(xy 249.461215 -274.350917) (xy 249.477283 -274.404324) (xy 249.485403 -274.4595) (xy 249.485912 -274.487386)
			(xy 249.485403 -274.515272) (xy 249.477283 -274.570448) (xy 249.461215 -274.623855) (xy 249.437543 -274.674352)
			(xy 249.40677 -274.720865) (xy 249.369553 -274.762402) (xy 249.326685 -274.798077) (xy 249.279079 -274.827131)
			(xy 249.22775 -274.848943) (xy 249.173793 -274.863049) (xy 249.118356 -274.869149) (xy 249.062622 -274.867112)
			(xy 249.007779 -274.856982) (xy 248.954995 -274.838975) (xy 248.905395 -274.813474) (xy 248.860037 -274.781023)
			(xy 248.819888 -274.742314) (xy 248.785802 -274.698171) (xy 248.758506 -274.649536) (xy 248.738583 -274.597445)
			(xy 248.726457 -274.543008) (xy 248.722386 -274.487386) (xy 245.715319 -274.487386) (xy 245.722113 -274.49304)
			(xy 245.75933 -274.534577) (xy 245.790103 -274.58109) (xy 245.813775 -274.631587) (xy 245.829843 -274.684994)
			(xy 245.837963 -274.74017) (xy 245.838472 -274.768056) (xy 245.837963 -274.795942) (xy 245.829843 -274.851118)
			(xy 245.813775 -274.904525) (xy 245.790103 -274.955022) (xy 245.75933 -275.001535) (xy 245.722113 -275.043072)
			(xy 245.679245 -275.078747) (xy 245.631639 -275.107801) (xy 245.58031 -275.129613) (xy 245.526353 -275.143719)
			(xy 245.470916 -275.149819) (xy 245.415182 -275.147782) (xy 245.360339 -275.137652) (xy 245.307555 -275.119645)
			(xy 245.257955 -275.094144) (xy 245.212597 -275.061693) (xy 245.172448 -275.022984) (xy 245.138362 -274.978841)
			(xy 245.111066 -274.930206) (xy 245.091143 -274.878115) (xy 245.079017 -274.823678) (xy 245.074946 -274.768056)
			(xy 243.684312 -274.768056) (xy 243.683985 -274.769143) (xy 243.660313 -274.81964) (xy 243.62954 -274.866153)
			(xy 243.592323 -274.90769) (xy 243.549455 -274.943365) (xy 243.501849 -274.972419) (xy 243.45052 -274.994231)
			(xy 243.396563 -275.008337) (xy 243.341126 -275.014437) (xy 243.285392 -275.0124) (xy 243.230549 -275.00227)
			(xy 243.177765 -274.984263) (xy 243.128165 -274.958762) (xy 243.082807 -274.926311) (xy 243.042658 -274.887602)
			(xy 243.008572 -274.843459) (xy 242.981276 -274.794824) (xy 242.961353 -274.742733) (xy 242.949227 -274.688296)
			(xy 242.945156 -274.632674) (xy 233.620056 -274.632674) (xy 233.620056 -275.204936) (xy 246.570752 -275.204936)
			(xy 246.574823 -275.149314) (xy 246.586949 -275.094877) (xy 246.606872 -275.042786) (xy 246.634168 -274.994151)
			(xy 246.668254 -274.950008) (xy 246.708403 -274.911299) (xy 246.753761 -274.878848) (xy 246.803361 -274.853347)
			(xy 246.856145 -274.83534) (xy 246.910988 -274.82521) (xy 246.966722 -274.823173) (xy 247.022159 -274.829273)
			(xy 247.076116 -274.843379) (xy 247.127445 -274.865191) (xy 247.175051 -274.894245) (xy 247.217919 -274.92992)
			(xy 247.255136 -274.971457) (xy 247.285909 -275.01797) (xy 247.309581 -275.068467) (xy 247.325649 -275.121874)
			(xy 247.333769 -275.17705) (xy 247.334278 -275.204936) (xy 247.333769 -275.232822) (xy 247.325649 -275.287998)
			(xy 247.309581 -275.341405) (xy 247.285909 -275.391902) (xy 247.255136 -275.438415) (xy 247.217919 -275.479952)
			(xy 247.18976 -275.503386) (xy 248.722386 -275.503386) (xy 248.726457 -275.447764) (xy 248.738583 -275.393327)
			(xy 248.758506 -275.341236) (xy 248.785802 -275.292601) (xy 248.819888 -275.248458) (xy 248.860037 -275.209749)
			(xy 248.905395 -275.177298) (xy 248.954995 -275.151797) (xy 249.007779 -275.13379) (xy 249.062622 -275.12366)
			(xy 249.118356 -275.121623) (xy 249.173793 -275.127723) (xy 249.22775 -275.141829) (xy 249.279079 -275.163641)
			(xy 249.326685 -275.192695) (xy 249.369553 -275.22837) (xy 249.40677 -275.269907) (xy 249.437543 -275.31642)
			(xy 249.461215 -275.366917) (xy 249.477283 -275.420324) (xy 249.485403 -275.4755) (xy 249.485912 -275.503386)
			(xy 249.485403 -275.531272) (xy 249.477283 -275.586448) (xy 249.461215 -275.639855) (xy 249.437543 -275.690352)
			(xy 249.40677 -275.736865) (xy 249.369553 -275.778402) (xy 249.326685 -275.814077) (xy 249.279079 -275.843131)
			(xy 249.22775 -275.864943) (xy 249.173793 -275.879049) (xy 249.118356 -275.885149) (xy 249.062622 -275.883112)
			(xy 249.007779 -275.872982) (xy 248.954995 -275.854975) (xy 248.905395 -275.829474) (xy 248.860037 -275.797023)
			(xy 248.819888 -275.758314) (xy 248.785802 -275.714171) (xy 248.758506 -275.665536) (xy 248.738583 -275.613445)
			(xy 248.726457 -275.559008) (xy 248.722386 -275.503386) (xy 247.18976 -275.503386) (xy 247.175051 -275.515627)
			(xy 247.127445 -275.544681) (xy 247.076116 -275.566493) (xy 247.022159 -275.580599) (xy 246.966722 -275.586699)
			(xy 246.910988 -275.584662) (xy 246.856145 -275.574532) (xy 246.803361 -275.556525) (xy 246.753761 -275.531024)
			(xy 246.708403 -275.498573) (xy 246.668254 -275.459864) (xy 246.634168 -275.415721) (xy 246.606872 -275.367086)
			(xy 246.586949 -275.314995) (xy 246.574823 -275.260558) (xy 246.570752 -275.204936) (xy 233.620056 -275.204936)
			(xy 233.620056 -276.369018) (xy 241.385088 -276.369018) (xy 241.389159 -276.313396) (xy 241.401285 -276.258959)
			(xy 241.421208 -276.206868) (xy 241.448504 -276.158233) (xy 241.48259 -276.11409) (xy 241.522739 -276.075381)
			(xy 241.568097 -276.04293) (xy 241.617697 -276.017429) (xy 241.670481 -275.999422) (xy 241.725324 -275.989292)
			(xy 241.781058 -275.987255) (xy 241.836495 -275.993355) (xy 241.890452 -276.007461) (xy 241.941781 -276.029273)
			(xy 241.989387 -276.058327) (xy 242.032255 -276.094002) (xy 242.069472 -276.135539) (xy 242.100245 -276.182052)
			(xy 242.123917 -276.232549) (xy 242.139985 -276.285956) (xy 242.148105 -276.341132) (xy 242.148614 -276.369018)
			(xy 242.148105 -276.396904) (xy 242.139985 -276.45208) (xy 242.123917 -276.505487) (xy 242.117401 -276.519386)
			(xy 246.703086 -276.519386) (xy 246.707157 -276.463764) (xy 246.719283 -276.409327) (xy 246.739206 -276.357236)
			(xy 246.766502 -276.308601) (xy 246.800588 -276.264458) (xy 246.840737 -276.225749) (xy 246.886095 -276.193298)
			(xy 246.935695 -276.167797) (xy 246.988479 -276.14979) (xy 247.043322 -276.13966) (xy 247.099056 -276.137623)
			(xy 247.154493 -276.143723) (xy 247.20845 -276.157829) (xy 247.259779 -276.179641) (xy 247.307385 -276.208695)
			(xy 247.350253 -276.24437) (xy 247.38747 -276.285907) (xy 247.418243 -276.33242) (xy 247.441915 -276.382917)
			(xy 247.457983 -276.436324) (xy 247.466103 -276.4915) (xy 247.466612 -276.519386) (xy 248.722386 -276.519386)
			(xy 248.726457 -276.463764) (xy 248.738583 -276.409327) (xy 248.758506 -276.357236) (xy 248.785802 -276.308601)
			(xy 248.819888 -276.264458) (xy 248.860037 -276.225749) (xy 248.905395 -276.193298) (xy 248.954995 -276.167797)
			(xy 249.007779 -276.14979) (xy 249.062622 -276.13966) (xy 249.118356 -276.137623) (xy 249.173793 -276.143723)
			(xy 249.22775 -276.157829) (xy 249.279079 -276.179641) (xy 249.326685 -276.208695) (xy 249.369553 -276.24437)
			(xy 249.40677 -276.285907) (xy 249.437543 -276.33242) (xy 249.461215 -276.382917) (xy 249.477283 -276.436324)
			(xy 249.485403 -276.4915) (xy 249.485912 -276.519386) (xy 249.485403 -276.547272) (xy 249.477283 -276.602448)
			(xy 249.461215 -276.655855) (xy 249.437543 -276.706352) (xy 249.40677 -276.752865) (xy 249.369553 -276.794402)
			(xy 249.326685 -276.830077) (xy 249.279079 -276.859131) (xy 249.22775 -276.880943) (xy 249.173793 -276.895049)
			(xy 249.118356 -276.901149) (xy 249.062622 -276.899112) (xy 249.007779 -276.888982) (xy 248.954995 -276.870975)
			(xy 248.905395 -276.845474) (xy 248.860037 -276.813023) (xy 248.819888 -276.774314) (xy 248.785802 -276.730171)
			(xy 248.758506 -276.681536) (xy 248.738583 -276.629445) (xy 248.726457 -276.575008) (xy 248.722386 -276.519386)
			(xy 247.466612 -276.519386) (xy 247.466103 -276.547272) (xy 247.457983 -276.602448) (xy 247.441915 -276.655855)
			(xy 247.418243 -276.706352) (xy 247.38747 -276.752865) (xy 247.350253 -276.794402) (xy 247.307385 -276.830077)
			(xy 247.259779 -276.859131) (xy 247.20845 -276.880943) (xy 247.154493 -276.895049) (xy 247.099056 -276.901149)
			(xy 247.043322 -276.899112) (xy 246.988479 -276.888982) (xy 246.935695 -276.870975) (xy 246.886095 -276.845474)
			(xy 246.840737 -276.813023) (xy 246.800588 -276.774314) (xy 246.766502 -276.730171) (xy 246.739206 -276.681536)
			(xy 246.719283 -276.629445) (xy 246.707157 -276.575008) (xy 246.703086 -276.519386) (xy 242.117401 -276.519386)
			(xy 242.100245 -276.555984) (xy 242.069472 -276.602497) (xy 242.032255 -276.644034) (xy 241.989387 -276.679709)
			(xy 241.941781 -276.708763) (xy 241.890452 -276.730575) (xy 241.836495 -276.744681) (xy 241.781058 -276.750781)
			(xy 241.725324 -276.748744) (xy 241.670481 -276.738614) (xy 241.617697 -276.720607) (xy 241.568097 -276.695106)
			(xy 241.522739 -276.662655) (xy 241.48259 -276.623946) (xy 241.448504 -276.579803) (xy 241.421208 -276.531168)
			(xy 241.401285 -276.479077) (xy 241.389159 -276.42464) (xy 241.385088 -276.369018) (xy 233.620056 -276.369018)
			(xy 233.620056 -277.213314) (xy 243.720364 -277.213314) (xy 243.724435 -277.157692) (xy 243.736561 -277.103255)
			(xy 243.756484 -277.051164) (xy 243.78378 -277.002529) (xy 243.817866 -276.958386) (xy 243.858015 -276.919677)
			(xy 243.903373 -276.887226) (xy 243.952973 -276.861725) (xy 244.005757 -276.843718) (xy 244.0606 -276.833588)
			(xy 244.116334 -276.831551) (xy 244.171771 -276.837651) (xy 244.225728 -276.851757) (xy 244.277057 -276.873569)
			(xy 244.324663 -276.902623) (xy 244.367531 -276.938298) (xy 244.404748 -276.979835) (xy 244.435521 -277.026348)
			(xy 244.459193 -277.076845) (xy 244.475261 -277.130252) (xy 244.483381 -277.185428) (xy 244.483681 -277.201884)
			(xy 244.909846 -277.201884) (xy 244.913917 -277.146262) (xy 244.926043 -277.091825) (xy 244.945966 -277.039734)
			(xy 244.973262 -276.991099) (xy 245.007348 -276.946956) (xy 245.047497 -276.908247) (xy 245.092855 -276.875796)
			(xy 245.142455 -276.850295) (xy 245.195239 -276.832288) (xy 245.250082 -276.822158) (xy 245.305816 -276.820121)
			(xy 245.361253 -276.826221) (xy 245.41521 -276.840327) (xy 245.466539 -276.862139) (xy 245.514145 -276.891193)
			(xy 245.557013 -276.926868) (xy 245.59423 -276.968405) (xy 245.625003 -277.014918) (xy 245.648675 -277.065415)
			(xy 245.664743 -277.118822) (xy 245.672863 -277.173998) (xy 245.673372 -277.201884) (xy 245.672863 -277.22977)
			(xy 245.664743 -277.284946) (xy 245.648675 -277.338353) (xy 245.625003 -277.38885) (xy 245.59423 -277.435363)
			(xy 245.557013 -277.4769) (xy 245.514145 -277.512575) (xy 245.466539 -277.541629) (xy 245.41521 -277.563441)
			(xy 245.361253 -277.577547) (xy 245.305816 -277.583647) (xy 245.250082 -277.58161) (xy 245.195239 -277.57148)
			(xy 245.142455 -277.553473) (xy 245.092855 -277.527972) (xy 245.047497 -277.495521) (xy 245.007348 -277.456812)
			(xy 244.973262 -277.412669) (xy 244.945966 -277.364034) (xy 244.926043 -277.311943) (xy 244.913917 -277.257506)
			(xy 244.909846 -277.201884) (xy 244.483681 -277.201884) (xy 244.48389 -277.213314) (xy 244.483381 -277.2412)
			(xy 244.475261 -277.296376) (xy 244.459193 -277.349783) (xy 244.435521 -277.40028) (xy 244.404748 -277.446793)
			(xy 244.367531 -277.48833) (xy 244.324663 -277.524005) (xy 244.277057 -277.553059) (xy 244.225728 -277.574871)
			(xy 244.171771 -277.588977) (xy 244.116334 -277.595077) (xy 244.0606 -277.59304) (xy 244.005757 -277.58291)
			(xy 243.952973 -277.564903) (xy 243.903373 -277.539402) (xy 243.858015 -277.506951) (xy 243.817866 -277.468242)
			(xy 243.78378 -277.424099) (xy 243.756484 -277.375464) (xy 243.736561 -277.323373) (xy 243.724435 -277.268936)
			(xy 243.720364 -277.213314) (xy 233.620056 -277.213314) (xy 233.620056 -278.233378) (xy 242.19611 -278.233378)
			(xy 242.200181 -278.177756) (xy 242.212307 -278.123319) (xy 242.23223 -278.071228) (xy 242.259526 -278.022593)
			(xy 242.293612 -277.97845) (xy 242.333761 -277.939741) (xy 242.379119 -277.90729) (xy 242.428719 -277.881789)
			(xy 242.481503 -277.863782) (xy 242.536346 -277.853652) (xy 242.59208 -277.851615) (xy 242.647517 -277.857715)
			(xy 242.701474 -277.871821) (xy 242.752803 -277.893633) (xy 242.800409 -277.922687) (xy 242.843277 -277.958362)
			(xy 242.880494 -277.999899) (xy 242.911267 -278.046412) (xy 242.934939 -278.096909) (xy 242.951007 -278.150316)
			(xy 242.959127 -278.205492) (xy 242.959636 -278.233378) (xy 242.959127 -278.261264) (xy 242.951007 -278.31644)
			(xy 242.934939 -278.369847) (xy 242.930209 -278.379936) (xy 243.720364 -278.379936) (xy 243.724435 -278.324314)
			(xy 243.736561 -278.269877) (xy 243.756484 -278.217786) (xy 243.78378 -278.169151) (xy 243.817866 -278.125008)
			(xy 243.858015 -278.086299) (xy 243.903373 -278.053848) (xy 243.952973 -278.028347) (xy 244.005757 -278.01034)
			(xy 244.0606 -278.00021) (xy 244.116334 -277.998173) (xy 244.171771 -278.004273) (xy 244.225728 -278.018379)
			(xy 244.277057 -278.040191) (xy 244.324663 -278.069245) (xy 244.367531 -278.10492) (xy 244.404748 -278.146457)
			(xy 244.435521 -278.19297) (xy 244.459193 -278.243467) (xy 244.475261 -278.296874) (xy 244.483381 -278.35205)
			(xy 244.483686 -278.36876) (xy 244.898416 -278.36876) (xy 244.902487 -278.313138) (xy 244.914613 -278.258701)
			(xy 244.934536 -278.20661) (xy 244.961832 -278.157975) (xy 244.995918 -278.113832) (xy 245.036067 -278.075123)
			(xy 245.081425 -278.042672) (xy 245.131025 -278.017171) (xy 245.183809 -277.999164) (xy 245.238652 -277.989034)
			(xy 245.294386 -277.986997) (xy 245.349823 -277.993097) (xy 245.40378 -278.007203) (xy 245.455109 -278.029015)
			(xy 245.502715 -278.058069) (xy 245.545583 -278.093744) (xy 245.5828 -278.135281) (xy 245.613573 -278.181794)
			(xy 245.637245 -278.232291) (xy 245.653313 -278.285698) (xy 245.661433 -278.340874) (xy 245.661942 -278.36876)
			(xy 245.661433 -278.396646) (xy 245.653313 -278.451822) (xy 245.637245 -278.505229) (xy 245.615608 -278.551386)
			(xy 246.703596 -278.551386) (xy 246.70414 -278.52247) (xy 246.712858 -278.465298) (xy 246.730109 -278.410098)
			(xy 246.755496 -278.358135) (xy 246.788437 -278.310601) (xy 246.828177 -278.268585) (xy 246.850662 -278.250396)
			(xy 246.859432 -278.242842) (xy 246.869608 -278.222077) (xy 246.87022 -278.210518) (xy 246.87022 -278.130254)
			(xy 246.869612 -278.118691) (xy 246.859443 -278.09792) (xy 246.850662 -278.090376) (xy 246.828159 -278.072208)
			(xy 246.788427 -278.030182) (xy 246.755491 -277.982642) (xy 246.730107 -277.930677) (xy 246.712854 -277.875476)
			(xy 246.704129 -277.818303) (xy 246.703596 -277.789386) (xy 246.704082 -277.762135) (xy 246.711838 -277.708187)
			(xy 246.727193 -277.655892) (xy 246.749835 -277.606315) (xy 246.779301 -277.560465) (xy 246.814992 -277.519274)
			(xy 246.856183 -277.483583) (xy 246.902033 -277.454117) (xy 246.95161 -277.431475) (xy 247.003905 -277.41612)
			(xy 247.057853 -277.408364) (xy 247.112355 -277.408364) (xy 247.166303 -277.41612) (xy 247.218598 -277.431475)
			(xy 247.268175 -277.454117) (xy 247.314025 -277.483583) (xy 247.355216 -277.519274) (xy 247.370277 -277.536656)
			(xy 248.722386 -277.536656) (xy 248.726457 -277.481034) (xy 248.738583 -277.426597) (xy 248.758506 -277.374506)
			(xy 248.785802 -277.325871) (xy 248.819888 -277.281728) (xy 248.860037 -277.243019) (xy 248.905395 -277.210568)
			(xy 248.954995 -277.185067) (xy 249.007779 -277.16706) (xy 249.062622 -277.15693) (xy 249.118356 -277.154893)
			(xy 249.173793 -277.160993) (xy 249.22775 -277.175099) (xy 249.279079 -277.196911) (xy 249.326685 -277.225965)
			(xy 249.369553 -277.26164) (xy 249.40677 -277.303177) (xy 249.437543 -277.34969) (xy 249.461215 -277.400187)
			(xy 249.477283 -277.453594) (xy 249.485403 -277.50877) (xy 249.485912 -277.536656) (xy 249.485403 -277.564542)
			(xy 249.477283 -277.619718) (xy 249.461215 -277.673125) (xy 249.437543 -277.723622) (xy 249.40677 -277.770135)
			(xy 249.369553 -277.811672) (xy 249.326685 -277.847347) (xy 249.279079 -277.876401) (xy 249.22775 -277.898213)
			(xy 249.173793 -277.912319) (xy 249.118356 -277.918419) (xy 249.062622 -277.916382) (xy 249.007779 -277.906252)
			(xy 248.954995 -277.888245) (xy 248.905395 -277.862744) (xy 248.860037 -277.830293) (xy 248.819888 -277.791584)
			(xy 248.785802 -277.747441) (xy 248.758506 -277.698806) (xy 248.738583 -277.646715) (xy 248.726457 -277.592278)
			(xy 248.722386 -277.536656) (xy 247.370277 -277.536656) (xy 247.390907 -277.560465) (xy 247.420373 -277.606315)
			(xy 247.443015 -277.655892) (xy 247.45837 -277.708187) (xy 247.466126 -277.762135) (xy 247.466612 -277.789386)
			(xy 247.466117 -277.818304) (xy 247.457388 -277.875478) (xy 247.440128 -277.930679) (xy 247.414732 -277.982641)
			(xy 247.381782 -278.030174) (xy 247.342035 -278.072188) (xy 247.319546 -278.090376) (xy 247.31079 -278.097943)
			(xy 247.300606 -278.118698) (xy 247.299988 -278.130254) (xy 247.299988 -278.210518) (xy 247.300553 -278.222086)
			(xy 247.310752 -278.242857) (xy 247.319546 -278.250396) (xy 247.342037 -278.268578) (xy 247.38177 -278.310601)
			(xy 247.414707 -278.358138) (xy 247.440093 -278.410101) (xy 247.457348 -278.465299) (xy 247.466077 -278.52247)
			(xy 247.466612 -278.551386) (xy 247.466126 -278.578637) (xy 247.45837 -278.632585) (xy 247.443015 -278.68488)
			(xy 247.420373 -278.734457) (xy 247.390907 -278.780307) (xy 247.355216 -278.821498) (xy 247.314025 -278.857189)
			(xy 247.268175 -278.886655) (xy 247.218598 -278.909297) (xy 247.166303 -278.924652) (xy 247.112355 -278.932408)
			(xy 247.057853 -278.932408) (xy 247.003905 -278.924652) (xy 246.95161 -278.909297) (xy 246.902033 -278.886655)
			(xy 246.856183 -278.857189) (xy 246.814992 -278.821498) (xy 246.779301 -278.780307) (xy 246.749835 -278.734457)
			(xy 246.727193 -278.68488) (xy 246.711838 -278.632585) (xy 246.704082 -278.578637) (xy 246.703596 -278.551386)
			(xy 245.615608 -278.551386) (xy 245.613573 -278.555726) (xy 245.5828 -278.602239) (xy 245.545583 -278.643776)
			(xy 245.502715 -278.679451) (xy 245.455109 -278.708505) (xy 245.40378 -278.730317) (xy 245.349823 -278.744423)
			(xy 245.294386 -278.750523) (xy 245.238652 -278.748486) (xy 245.183809 -278.738356) (xy 245.131025 -278.720349)
			(xy 245.081425 -278.694848) (xy 245.036067 -278.662397) (xy 244.995918 -278.623688) (xy 244.961832 -278.579545)
			(xy 244.934536 -278.53091) (xy 244.914613 -278.478819) (xy 244.902487 -278.424382) (xy 244.898416 -278.36876)
			(xy 244.483686 -278.36876) (xy 244.48389 -278.379936) (xy 244.483381 -278.407822) (xy 244.475261 -278.462998)
			(xy 244.459193 -278.516405) (xy 244.435521 -278.566902) (xy 244.404748 -278.613415) (xy 244.367531 -278.654952)
			(xy 244.324663 -278.690627) (xy 244.277057 -278.719681) (xy 244.225728 -278.741493) (xy 244.171771 -278.755599)
			(xy 244.116334 -278.761699) (xy 244.0606 -278.759662) (xy 244.005757 -278.749532) (xy 243.952973 -278.731525)
			(xy 243.903373 -278.706024) (xy 243.858015 -278.673573) (xy 243.817866 -278.634864) (xy 243.78378 -278.590721)
			(xy 243.756484 -278.542086) (xy 243.736561 -278.489995) (xy 243.724435 -278.435558) (xy 243.720364 -278.379936)
			(xy 242.930209 -278.379936) (xy 242.911267 -278.420344) (xy 242.880494 -278.466857) (xy 242.843277 -278.508394)
			(xy 242.800409 -278.544069) (xy 242.752803 -278.573123) (xy 242.701474 -278.594935) (xy 242.647517 -278.609041)
			(xy 242.59208 -278.615141) (xy 242.536346 -278.613104) (xy 242.481503 -278.602974) (xy 242.428719 -278.584967)
			(xy 242.379119 -278.559466) (xy 242.333761 -278.527015) (xy 242.293612 -278.488306) (xy 242.259526 -278.444163)
			(xy 242.23223 -278.395528) (xy 242.212307 -278.343437) (xy 242.200181 -278.289) (xy 242.19611 -278.233378)
			(xy 233.620056 -278.233378) (xy 233.620056 -278.32431) (xy 233.61963 -278.334378) (xy 233.611908 -278.352976)
			(xy 233.60507 -278.360378) (xy 233.439716 -278.525732) (xy 233.43235 -278.532844) (xy 233.42473 -278.55164)
			(xy 233.42473 -279.075896) (xy 240.6302 -279.075896) (xy 240.634271 -279.020274) (xy 240.646397 -278.965837)
			(xy 240.66632 -278.913746) (xy 240.693616 -278.865111) (xy 240.727702 -278.820968) (xy 240.767851 -278.782259)
			(xy 240.813209 -278.749808) (xy 240.862809 -278.724307) (xy 240.915593 -278.7063) (xy 240.970436 -278.69617)
			(xy 241.02617 -278.694133) (xy 241.081607 -278.700233) (xy 241.135564 -278.714339) (xy 241.186893 -278.736151)
			(xy 241.234499 -278.765205) (xy 241.277367 -278.80088) (xy 241.314584 -278.842417) (xy 241.345357 -278.88893)
			(xy 241.369029 -278.939427) (xy 241.385097 -278.992834) (xy 241.393217 -279.04801) (xy 241.393726 -279.075896)
			(xy 241.393217 -279.103782) (xy 241.385097 -279.158958) (xy 241.369029 -279.212365) (xy 241.345357 -279.262862)
			(xy 241.314584 -279.309375) (xy 241.277367 -279.350912) (xy 241.234499 -279.386587) (xy 241.186893 -279.415641)
			(xy 241.135564 -279.437453) (xy 241.081607 -279.451559) (xy 241.02617 -279.457659) (xy 240.970436 -279.455622)
			(xy 240.915593 -279.445492) (xy 240.862809 -279.427485) (xy 240.813209 -279.401984) (xy 240.767851 -279.369533)
			(xy 240.727702 -279.330824) (xy 240.693616 -279.286681) (xy 240.66632 -279.238046) (xy 240.646397 -279.185955)
			(xy 240.634271 -279.131518) (xy 240.6302 -279.075896) (xy 233.42473 -279.075896) (xy 233.42473 -279.567386)
			(xy 246.703086 -279.567386) (xy 246.707157 -279.511764) (xy 246.719283 -279.457327) (xy 246.739206 -279.405236)
			(xy 246.766502 -279.356601) (xy 246.800588 -279.312458) (xy 246.840737 -279.273749) (xy 246.886095 -279.241298)
			(xy 246.935695 -279.215797) (xy 246.988479 -279.19779) (xy 247.043322 -279.18766) (xy 247.099056 -279.185623)
			(xy 247.154493 -279.191723) (xy 247.20845 -279.205829) (xy 247.259779 -279.227641) (xy 247.307385 -279.256695)
			(xy 247.350253 -279.29237) (xy 247.38747 -279.333907) (xy 247.418243 -279.38042) (xy 247.441915 -279.430917)
			(xy 247.457983 -279.484324) (xy 247.466103 -279.5395) (xy 247.466612 -279.567386) (xy 247.466103 -279.595272)
			(xy 247.457983 -279.650448) (xy 247.441915 -279.703855) (xy 247.418243 -279.754352) (xy 247.38747 -279.800865)
			(xy 247.350253 -279.842402) (xy 247.307385 -279.878077) (xy 247.259779 -279.907131) (xy 247.20845 -279.928943)
			(xy 247.154493 -279.943049) (xy 247.099056 -279.949149) (xy 247.043322 -279.947112) (xy 246.988479 -279.936982)
			(xy 246.935695 -279.918975) (xy 246.886095 -279.893474) (xy 246.840737 -279.861023) (xy 246.800588 -279.822314)
			(xy 246.766502 -279.778171) (xy 246.739206 -279.729536) (xy 246.719283 -279.677445) (xy 246.707157 -279.623008)
			(xy 246.703086 -279.567386) (xy 233.42473 -279.567386) (xy 233.42473 -280.10104) (xy 240.634264 -280.10104)
			(xy 240.638335 -280.045418) (xy 240.650461 -279.990981) (xy 240.670384 -279.93889) (xy 240.69768 -279.890255)
			(xy 240.731766 -279.846112) (xy 240.771915 -279.807403) (xy 240.817273 -279.774952) (xy 240.866873 -279.749451)
			(xy 240.919657 -279.731444) (xy 240.9745 -279.721314) (xy 241.030234 -279.719277) (xy 241.085671 -279.725377)
			(xy 241.139628 -279.739483) (xy 241.190957 -279.761295) (xy 241.238563 -279.790349) (xy 241.281431 -279.826024)
			(xy 241.318648 -279.867561) (xy 241.349421 -279.914074) (xy 241.373093 -279.964571) (xy 241.389161 -280.017978)
			(xy 241.397281 -280.073154) (xy 241.39779 -280.10104) (xy 242.653564 -280.10104) (xy 242.657635 -280.045418)
			(xy 242.669761 -279.990981) (xy 242.689684 -279.93889) (xy 242.71698 -279.890255) (xy 242.751066 -279.846112)
			(xy 242.791215 -279.807403) (xy 242.836573 -279.774952) (xy 242.886173 -279.749451) (xy 242.938957 -279.731444)
			(xy 242.9938 -279.721314) (xy 243.049534 -279.719277) (xy 243.104971 -279.725377) (xy 243.158928 -279.739483)
			(xy 243.210257 -279.761295) (xy 243.257863 -279.790349) (xy 243.300731 -279.826024) (xy 243.337948 -279.867561)
			(xy 243.368721 -279.914074) (xy 243.392393 -279.964571) (xy 243.408461 -280.017978) (xy 243.416581 -280.073154)
			(xy 243.41709 -280.10104) (xy 243.416581 -280.128926) (xy 243.408461 -280.184102) (xy 243.392393 -280.237509)
			(xy 243.368721 -280.288006) (xy 243.337948 -280.334519) (xy 243.300731 -280.376056) (xy 243.257863 -280.411731)
			(xy 243.210257 -280.440785) (xy 243.158928 -280.462597) (xy 243.104971 -280.476703) (xy 243.049534 -280.482803)
			(xy 242.9938 -280.480766) (xy 242.938957 -280.470636) (xy 242.886173 -280.452629) (xy 242.836573 -280.427128)
			(xy 242.791215 -280.394677) (xy 242.751066 -280.355968) (xy 242.71698 -280.311825) (xy 242.689684 -280.26319)
			(xy 242.669761 -280.211099) (xy 242.657635 -280.156662) (xy 242.653564 -280.10104) (xy 241.39779 -280.10104)
			(xy 241.397281 -280.128926) (xy 241.389161 -280.184102) (xy 241.373093 -280.237509) (xy 241.349421 -280.288006)
			(xy 241.318648 -280.334519) (xy 241.281431 -280.376056) (xy 241.238563 -280.411731) (xy 241.190957 -280.440785)
			(xy 241.139628 -280.462597) (xy 241.085671 -280.476703) (xy 241.030234 -280.482803) (xy 240.9745 -280.480766)
			(xy 240.919657 -280.470636) (xy 240.866873 -280.452629) (xy 240.817273 -280.427128) (xy 240.771915 -280.394677)
			(xy 240.731766 -280.355968) (xy 240.69768 -280.311825) (xy 240.670384 -280.26319) (xy 240.650461 -280.211099)
			(xy 240.638335 -280.156662) (xy 240.634264 -280.10104) (xy 233.42473 -280.10104) (xy 233.42473 -280.500582)
			(xy 245.065802 -280.500582) (xy 245.069873 -280.44496) (xy 245.081999 -280.390523) (xy 245.101922 -280.338432)
			(xy 245.129218 -280.289797) (xy 245.163304 -280.245654) (xy 245.203453 -280.206945) (xy 245.248811 -280.174494)
			(xy 245.298411 -280.148993) (xy 245.351195 -280.130986) (xy 245.406038 -280.120856) (xy 245.461772 -280.118819)
			(xy 245.517209 -280.124919) (xy 245.571166 -280.139025) (xy 245.622495 -280.160837) (xy 245.670101 -280.189891)
			(xy 245.712969 -280.225566) (xy 245.750186 -280.267103) (xy 245.780959 -280.313616) (xy 245.804631 -280.364113)
			(xy 245.820699 -280.41752) (xy 245.828819 -280.472696) (xy 245.829328 -280.500582) (xy 245.828819 -280.528468)
			(xy 245.820737 -280.583386) (xy 248.722896 -280.583386) (xy 248.723344 -280.557488) (xy 248.730348 -280.506168)
			(xy 248.744227 -280.456266) (xy 248.764725 -280.408699) (xy 248.791465 -280.364339) (xy 248.823957 -280.324002)
			(xy 248.861604 -280.288428) (xy 248.882408 -280.272998) (xy 248.891044 -280.266902) (xy 248.901966 -280.248868)
			(xy 248.914412 -280.154126) (xy 248.90857 -280.13406) (xy 248.901712 -280.125932) (xy 248.885274 -280.105359)
			(xy 248.857678 -280.060508) (xy 248.836521 -280.012284) (xy 248.822206 -279.961606) (xy 248.815008 -279.909439)
			(xy 248.81459 -279.883108) (xy 248.814996 -279.856894) (xy 248.82217 -279.80496) (xy 248.836383 -279.754496)
			(xy 248.857368 -279.706452) (xy 248.884731 -279.661732) (xy 248.917956 -279.621177) (xy 248.956419 -279.58555)
			(xy 248.977658 -279.57018) (xy 248.988834 -279.56256) (xy 249.000264 -279.538684) (xy 248.992136 -279.424384)
			(xy 248.977404 -279.402286) (xy 248.965212 -279.39619) (xy 248.941836 -279.383984) (xy 248.89841 -279.354065)
			(xy 248.859521 -279.318446) (xy 248.825911 -279.277809) (xy 248.798222 -279.232927) (xy 248.776983 -279.184659)
			(xy 248.762597 -279.133923) (xy 248.755341 -279.08169) (xy 248.7549 -279.055322) (xy 248.755386 -279.028071)
			(xy 248.763142 -278.974123) (xy 248.778497 -278.921828) (xy 248.801139 -278.872251) (xy 248.830605 -278.826401)
			(xy 248.866296 -278.78521) (xy 248.907487 -278.749519) (xy 248.953337 -278.720053) (xy 249.002914 -278.697411)
			(xy 249.055209 -278.682056) (xy 249.109157 -278.6743) (xy 249.163659 -278.6743) (xy 249.217607 -278.682056)
			(xy 249.269902 -278.697411) (xy 249.319479 -278.720053) (xy 249.365329 -278.749519) (xy 249.40652 -278.78521)
			(xy 249.429284 -278.811482) (xy 250.954284 -278.811482) (xy 250.958355 -278.75586) (xy 250.970481 -278.701423)
			(xy 250.990404 -278.649332) (xy 251.0177 -278.600697) (xy 251.051786 -278.556554) (xy 251.091935 -278.517845)
			(xy 251.137293 -278.485394) (xy 251.186893 -278.459893) (xy 251.239677 -278.441886) (xy 251.29452 -278.431756)
			(xy 251.350254 -278.429719) (xy 251.405691 -278.435819) (xy 251.459648 -278.449925) (xy 251.510977 -278.471737)
			(xy 251.558583 -278.500791) (xy 251.601451 -278.536466) (xy 251.638668 -278.578003) (xy 251.669441 -278.624516)
			(xy 251.693113 -278.675013) (xy 251.709181 -278.72842) (xy 251.717301 -278.783596) (xy 251.71781 -278.811482)
			(xy 251.717301 -278.839368) (xy 251.709181 -278.894544) (xy 251.693113 -278.947951) (xy 251.669441 -278.998448)
			(xy 251.638668 -279.044961) (xy 251.601451 -279.086498) (xy 251.558583 -279.122173) (xy 251.510977 -279.151227)
			(xy 251.459648 -279.173039) (xy 251.405691 -279.187145) (xy 251.350254 -279.193245) (xy 251.29452 -279.191208)
			(xy 251.239677 -279.181078) (xy 251.186893 -279.163071) (xy 251.137293 -279.13757) (xy 251.091935 -279.105119)
			(xy 251.051786 -279.06641) (xy 251.0177 -279.022267) (xy 250.990404 -278.973632) (xy 250.970481 -278.921541)
			(xy 250.958355 -278.867104) (xy 250.954284 -278.811482) (xy 249.429284 -278.811482) (xy 249.442211 -278.826401)
			(xy 249.471677 -278.872251) (xy 249.494319 -278.921828) (xy 249.509674 -278.974123) (xy 249.51743 -279.028071)
			(xy 249.517916 -279.055322) (xy 249.517455 -279.081534) (xy 249.510291 -279.133466) (xy 249.496087 -279.183928)
			(xy 249.47511 -279.231972) (xy 249.447756 -279.276693) (xy 249.414539 -279.31725) (xy 249.376084 -279.352879)
			(xy 249.354848 -279.36825) (xy 249.343672 -279.37587) (xy 249.332242 -279.399746) (xy 249.34037 -279.514046)
			(xy 249.355102 -279.536144) (xy 249.367294 -279.54224) (xy 249.390684 -279.554421) (xy 249.434111 -279.584344)
			(xy 249.472999 -279.619966) (xy 249.506608 -279.660607) (xy 249.534295 -279.705492) (xy 249.555532 -279.753764)
			(xy 249.569914 -279.804503) (xy 249.577167 -279.856739) (xy 249.577606 -279.883108) (xy 249.577153 -279.909006)
			(xy 249.574136 -279.931114) (xy 258.01142 -279.931114) (xy 258.015491 -279.875492) (xy 258.027617 -279.821055)
			(xy 258.04754 -279.768964) (xy 258.074836 -279.720329) (xy 258.108922 -279.676186) (xy 258.149071 -279.637477)
			(xy 258.194429 -279.605026) (xy 258.244029 -279.579525) (xy 258.296813 -279.561518) (xy 258.351656 -279.551388)
			(xy 258.40739 -279.549351) (xy 258.462827 -279.555451) (xy 258.516784 -279.569557) (xy 258.568113 -279.591369)
			(xy 258.615719 -279.620423) (xy 258.658587 -279.656098) (xy 258.695804 -279.697635) (xy 258.726577 -279.744148)
			(xy 258.750249 -279.794645) (xy 258.766317 -279.848052) (xy 258.774437 -279.903228) (xy 258.774946 -279.931114)
			(xy 259.486906 -279.931114) (xy 259.490977 -279.875492) (xy 259.503103 -279.821055) (xy 259.523026 -279.768964)
			(xy 259.550322 -279.720329) (xy 259.584408 -279.676186) (xy 259.624557 -279.637477) (xy 259.669915 -279.605026)
			(xy 259.719515 -279.579525) (xy 259.772299 -279.561518) (xy 259.827142 -279.551388) (xy 259.882876 -279.549351)
			(xy 259.938313 -279.555451) (xy 259.99227 -279.569557) (xy 260.043599 -279.591369) (xy 260.091205 -279.620423)
			(xy 260.134073 -279.656098) (xy 260.17129 -279.697635) (xy 260.202063 -279.744148) (xy 260.225735 -279.794645)
			(xy 260.241803 -279.848052) (xy 260.249923 -279.903228) (xy 260.250432 -279.931114) (xy 260.249923 -279.959)
			(xy 260.241803 -280.014176) (xy 260.228584 -280.058114) (xy 260.375906 -280.058114) (xy 260.379977 -280.002492)
			(xy 260.392103 -279.948055) (xy 260.412026 -279.895964) (xy 260.439322 -279.847329) (xy 260.473408 -279.803186)
			(xy 260.513557 -279.764477) (xy 260.558915 -279.732026) (xy 260.608515 -279.706525) (xy 260.661299 -279.688518)
			(xy 260.716142 -279.678388) (xy 260.771876 -279.676351) (xy 260.827313 -279.682451) (xy 260.88127 -279.696557)
			(xy 260.932599 -279.718369) (xy 260.980205 -279.747423) (xy 261.023073 -279.783098) (xy 261.06029 -279.824635)
			(xy 261.091063 -279.871148) (xy 261.114735 -279.921645) (xy 261.130803 -279.975052) (xy 261.138923 -280.030228)
			(xy 261.139432 -280.058114) (xy 261.138923 -280.086) (xy 261.130803 -280.141176) (xy 261.114735 -280.194583)
			(xy 261.091063 -280.24508) (xy 261.06029 -280.291593) (xy 261.023073 -280.33313) (xy 260.980205 -280.368805)
			(xy 260.932599 -280.397859) (xy 260.88127 -280.419671) (xy 260.827313 -280.433777) (xy 260.771876 -280.439877)
			(xy 260.716142 -280.43784) (xy 260.661299 -280.42771) (xy 260.608515 -280.409703) (xy 260.558915 -280.384202)
			(xy 260.513557 -280.351751) (xy 260.473408 -280.313042) (xy 260.439322 -280.268899) (xy 260.412026 -280.220264)
			(xy 260.392103 -280.168173) (xy 260.379977 -280.113736) (xy 260.375906 -280.058114) (xy 260.228584 -280.058114)
			(xy 260.225735 -280.067583) (xy 260.202063 -280.11808) (xy 260.17129 -280.164593) (xy 260.134073 -280.20613)
			(xy 260.091205 -280.241805) (xy 260.043599 -280.270859) (xy 259.99227 -280.292671) (xy 259.938313 -280.306777)
			(xy 259.882876 -280.312877) (xy 259.827142 -280.31084) (xy 259.772299 -280.30071) (xy 259.719515 -280.282703)
			(xy 259.669915 -280.257202) (xy 259.624557 -280.224751) (xy 259.584408 -280.186042) (xy 259.550322 -280.141899)
			(xy 259.523026 -280.093264) (xy 259.503103 -280.041173) (xy 259.490977 -279.986736) (xy 259.486906 -279.931114)
			(xy 258.774946 -279.931114) (xy 258.774437 -279.959) (xy 258.766317 -280.014176) (xy 258.750249 -280.067583)
			(xy 258.726577 -280.11808) (xy 258.695804 -280.164593) (xy 258.658587 -280.20613) (xy 258.615719 -280.241805)
			(xy 258.568113 -280.270859) (xy 258.516784 -280.292671) (xy 258.462827 -280.306777) (xy 258.40739 -280.312877)
			(xy 258.351656 -280.31084) (xy 258.296813 -280.30071) (xy 258.244029 -280.282703) (xy 258.194429 -280.257202)
			(xy 258.149071 -280.224751) (xy 258.108922 -280.186042) (xy 258.074836 -280.141899) (xy 258.04754 -280.093264)
			(xy 258.027617 -280.041173) (xy 258.015491 -279.986736) (xy 258.01142 -279.931114) (xy 249.574136 -279.931114)
			(xy 249.570149 -279.960326) (xy 249.556271 -280.010227) (xy 249.535775 -280.057795) (xy 249.509035 -280.102154)
			(xy 249.476544 -280.142491) (xy 249.438897 -280.178066) (xy 249.418094 -280.193496) (xy 249.409458 -280.199592)
			(xy 249.398536 -280.217626) (xy 249.38609 -280.312368) (xy 249.391932 -280.332434) (xy 249.39879 -280.340562)
			(xy 249.415225 -280.361137) (xy 249.442822 -280.405988) (xy 249.46398 -280.454211) (xy 249.478295 -280.504889)
			(xy 249.485494 -280.557055) (xy 249.485912 -280.583386) (xy 249.485426 -280.610637) (xy 249.47767 -280.664585)
			(xy 249.462315 -280.71688) (xy 249.439673 -280.766457) (xy 249.410207 -280.812307) (xy 249.374516 -280.853498)
			(xy 249.333325 -280.889189) (xy 249.287475 -280.918655) (xy 249.237898 -280.941297) (xy 249.185603 -280.956652)
			(xy 249.131655 -280.964408) (xy 249.077153 -280.964408) (xy 249.023205 -280.956652) (xy 248.97091 -280.941297)
			(xy 248.921333 -280.918655) (xy 248.875483 -280.889189) (xy 248.834292 -280.853498) (xy 248.798601 -280.812307)
			(xy 248.769135 -280.766457) (xy 248.746493 -280.71688) (xy 248.731138 -280.664585) (xy 248.723382 -280.610637)
			(xy 248.722896 -280.583386) (xy 245.820737 -280.583386) (xy 245.820699 -280.583644) (xy 245.804631 -280.637051)
			(xy 245.780959 -280.687548) (xy 245.750186 -280.734061) (xy 245.712969 -280.775598) (xy 245.670101 -280.811273)
			(xy 245.622495 -280.840327) (xy 245.571166 -280.862139) (xy 245.517209 -280.876245) (xy 245.461772 -280.882345)
			(xy 245.406038 -280.880308) (xy 245.351195 -280.870178) (xy 245.298411 -280.852171) (xy 245.248811 -280.82667)
			(xy 245.203453 -280.794219) (xy 245.163304 -280.75551) (xy 245.129218 -280.711367) (xy 245.101922 -280.662732)
			(xy 245.081999 -280.610641) (xy 245.069873 -280.556204) (xy 245.065802 -280.500582) (xy 233.42473 -280.500582)
			(xy 233.42473 -280.894282) (xy 233.425202 -280.904153) (xy 233.432665 -280.922433) (xy 233.439208 -280.929842)
			(xy 233.439462 -280.930096) (xy 234.059476 -281.55011) (xy 250.225812 -281.55011) (xy 250.229883 -281.494488)
			(xy 250.242009 -281.440051) (xy 250.261932 -281.38796) (xy 250.289228 -281.339325) (xy 250.323314 -281.295182)
			(xy 250.363463 -281.256473) (xy 250.408821 -281.224022) (xy 250.458421 -281.198521) (xy 250.511205 -281.180514)
			(xy 250.566048 -281.170384) (xy 250.621782 -281.168347) (xy 250.677219 -281.174447) (xy 250.731176 -281.188553)
			(xy 250.782505 -281.210365) (xy 250.830111 -281.239419) (xy 250.872979 -281.275094) (xy 250.910196 -281.316631)
			(xy 250.940969 -281.363144) (xy 250.964641 -281.413641) (xy 250.980709 -281.467048) (xy 250.988829 -281.522224)
			(xy 250.989338 -281.55011) (xy 250.988829 -281.577996) (xy 250.980709 -281.633172) (xy 250.964641 -281.686579)
			(xy 250.940969 -281.737076) (xy 250.910196 -281.783589) (xy 250.872979 -281.825126) (xy 250.868016 -281.829256)
			(xy 258.01142 -281.829256) (xy 258.015491 -281.773634) (xy 258.027617 -281.719197) (xy 258.04754 -281.667106)
			(xy 258.074836 -281.618471) (xy 258.108922 -281.574328) (xy 258.149071 -281.535619) (xy 258.194429 -281.503168)
			(xy 258.244029 -281.477667) (xy 258.296813 -281.45966) (xy 258.351656 -281.44953) (xy 258.40739 -281.447493)
			(xy 258.462827 -281.453593) (xy 258.516784 -281.467699) (xy 258.568113 -281.489511) (xy 258.615719 -281.518565)
			(xy 258.658587 -281.55424) (xy 258.695804 -281.595777) (xy 258.726577 -281.64229) (xy 258.750249 -281.692787)
			(xy 258.766317 -281.746194) (xy 258.774437 -281.80137) (xy 258.774946 -281.829256) (xy 259.496558 -281.829256)
			(xy 259.500629 -281.773634) (xy 259.512755 -281.719197) (xy 259.532678 -281.667106) (xy 259.559974 -281.618471)
			(xy 259.59406 -281.574328) (xy 259.634209 -281.535619) (xy 259.679567 -281.503168) (xy 259.729167 -281.477667)
			(xy 259.781951 -281.45966) (xy 259.836794 -281.44953) (xy 259.892528 -281.447493) (xy 259.947965 -281.453593)
			(xy 260.001922 -281.467699) (xy 260.053251 -281.489511) (xy 260.100857 -281.518565) (xy 260.143725 -281.55424)
			(xy 260.180942 -281.595777) (xy 260.211715 -281.64229) (xy 260.235387 -281.692787) (xy 260.251455 -281.746194)
			(xy 260.259575 -281.80137) (xy 260.260084 -281.829256) (xy 260.259575 -281.857142) (xy 260.251455 -281.912318)
			(xy 260.235387 -281.965725) (xy 260.211715 -282.016222) (xy 260.180942 -282.062735) (xy 260.143725 -282.104272)
			(xy 260.100857 -282.139947) (xy 260.053251 -282.169001) (xy 260.001922 -282.190813) (xy 259.947965 -282.204919)
			(xy 259.892528 -282.211019) (xy 259.836794 -282.208982) (xy 259.781951 -282.198852) (xy 259.729167 -282.180845)
			(xy 259.679567 -282.155344) (xy 259.634209 -282.122893) (xy 259.59406 -282.084184) (xy 259.559974 -282.040041)
			(xy 259.532678 -281.991406) (xy 259.512755 -281.939315) (xy 259.500629 -281.884878) (xy 259.496558 -281.829256)
			(xy 258.774946 -281.829256) (xy 258.774437 -281.857142) (xy 258.766317 -281.912318) (xy 258.750249 -281.965725)
			(xy 258.726577 -282.016222) (xy 258.695804 -282.062735) (xy 258.658587 -282.104272) (xy 258.615719 -282.139947)
			(xy 258.568113 -282.169001) (xy 258.516784 -282.190813) (xy 258.462827 -282.204919) (xy 258.40739 -282.211019)
			(xy 258.351656 -282.208982) (xy 258.296813 -282.198852) (xy 258.244029 -282.180845) (xy 258.194429 -282.155344)
			(xy 258.149071 -282.122893) (xy 258.108922 -282.084184) (xy 258.074836 -282.040041) (xy 258.04754 -281.991406)
			(xy 258.027617 -281.939315) (xy 258.015491 -281.884878) (xy 258.01142 -281.829256) (xy 250.868016 -281.829256)
			(xy 250.830111 -281.860801) (xy 250.782505 -281.889855) (xy 250.731176 -281.911667) (xy 250.677219 -281.925773)
			(xy 250.621782 -281.931873) (xy 250.566048 -281.929836) (xy 250.511205 -281.919706) (xy 250.458421 -281.901699)
			(xy 250.408821 -281.876198) (xy 250.363463 -281.843747) (xy 250.323314 -281.805038) (xy 250.289228 -281.760895)
			(xy 250.261932 -281.71226) (xy 250.242009 -281.660169) (xy 250.229883 -281.605732) (xy 250.225812 -281.55011)
			(xy 234.059476 -281.55011) (xy 234.515914 -282.006548) (xy 234.522762 -282.013945) (xy 234.530493 -282.032544)
			(xy 234.5309 -282.042616) (xy 234.5309 -283.009456) (xy 241.001717 -283.009456) (xy 241.001717 -282.954944)
			(xy 241.009475 -282.900988) (xy 241.024833 -282.848684) (xy 241.047478 -282.799099) (xy 241.076949 -282.753241)
			(xy 241.112647 -282.712044) (xy 241.153844 -282.676347) (xy 241.199702 -282.646876) (xy 241.249288 -282.624231)
			(xy 241.301591 -282.608874) (xy 241.355548 -282.601117) (xy 241.382804 -282.600654) (xy 241.411542 -282.601188)
			(xy 241.468369 -282.60981) (xy 241.523259 -282.626858) (xy 241.574971 -282.651947) (xy 241.622334 -282.684509)
			(xy 241.643662 -282.703778) (xy 241.650774 -282.710382) (xy 241.6683 -282.717494) (xy 241.757708 -282.717494)
			(xy 241.775234 -282.710382) (xy 241.782346 -282.703778) (xy 241.803673 -282.684508) (xy 241.851036 -282.651943)
			(xy 241.902747 -282.626852) (xy 241.957638 -282.609802) (xy 242.014465 -282.60118) (xy 242.071943 -282.60118)
			(xy 242.12877 -282.609802) (xy 242.183661 -282.626852) (xy 242.235372 -282.651943) (xy 242.282735 -282.684508)
			(xy 242.304062 -282.703778) (xy 242.311174 -282.710382) (xy 242.3287 -282.717494) (xy 242.418108 -282.717494)
			(xy 242.435634 -282.710382) (xy 242.442746 -282.703778) (xy 242.464077 -282.684512) (xy 242.511437 -282.651944)
			(xy 242.563148 -282.626849) (xy 242.618038 -282.609798) (xy 242.674865 -282.601175) (xy 242.703604 -282.600654)
			(xy 242.733728 -282.601221) (xy 242.793224 -282.610703) (xy 242.850492 -282.629414) (xy 242.904109 -282.656891)
			(xy 242.952743 -282.692451) (xy 242.974368 -282.71343) (xy 242.98148 -282.720796) (xy 243.000276 -282.728416)
			(xy 243.092732 -282.728416) (xy 243.111528 -282.720796) (xy 243.11864 -282.71343) (xy 243.140273 -282.692459)
			(xy 243.188899 -282.656888) (xy 243.242513 -282.629406) (xy 243.299782 -282.610696) (xy 243.35928 -282.601223)
			(xy 243.389404 -282.600654) (xy 243.416652 -282.601216) (xy 243.470594 -282.608973) (xy 243.522883 -282.624327)
			(xy 243.572455 -282.646966) (xy 243.6183 -282.676429) (xy 243.659486 -282.712117) (xy 243.695173 -282.753303)
			(xy 243.724636 -282.799149) (xy 243.747275 -282.848721) (xy 243.762628 -282.90101) (xy 243.770384 -282.954952)
			(xy 243.770384 -283.009448) (xy 243.770383 -283.009454) (xy 245.24914 -283.009454) (xy 245.24914 -282.954946)
			(xy 245.256897 -282.900994) (xy 245.272253 -282.848695) (xy 245.294896 -282.799113) (xy 245.324364 -282.753258)
			(xy 245.360059 -282.712064) (xy 245.401252 -282.676369) (xy 245.447106 -282.6469) (xy 245.496687 -282.624256)
			(xy 245.548986 -282.608899) (xy 245.602938 -282.60114) (xy 245.630192 -282.600654) (xy 245.65893 -282.601195)
			(xy 245.715756 -282.609815) (xy 245.770646 -282.626862) (xy 245.822358 -282.651949) (xy 245.869722 -282.68451)
			(xy 245.89105 -282.703778) (xy 245.898162 -282.710382) (xy 245.915688 -282.717494) (xy 246.005096 -282.717494)
			(xy 246.022622 -282.710382) (xy 246.029734 -282.703778) (xy 246.051061 -282.684508) (xy 246.098424 -282.651943)
			(xy 246.150135 -282.626852) (xy 246.205026 -282.609802) (xy 246.261853 -282.60118) (xy 246.319331 -282.60118)
			(xy 246.376158 -282.609802) (xy 246.431049 -282.626852) (xy 246.48276 -282.651943) (xy 246.530123 -282.684508)
			(xy 246.55145 -282.703778) (xy 246.558562 -282.710382) (xy 246.576088 -282.717494) (xy 246.665496 -282.717494)
			(xy 246.683022 -282.710382) (xy 246.690134 -282.703778) (xy 246.71147 -282.684518) (xy 246.758829 -282.651948)
			(xy 246.810538 -282.626853) (xy 246.865427 -282.6098) (xy 246.922253 -282.601176) (xy 246.950992 -282.600654)
			(xy 246.981115 -282.601229) (xy 247.040612 -282.610708) (xy 247.097879 -282.629418) (xy 247.151497 -282.656893)
			(xy 247.200131 -282.692451) (xy 247.221756 -282.71343) (xy 247.228868 -282.720796) (xy 247.247664 -282.728416)
			(xy 247.34012 -282.728416) (xy 247.358916 -282.720796) (xy 247.366028 -282.71343) (xy 247.387666 -282.692464)
			(xy 247.436291 -282.656893) (xy 247.489904 -282.62941) (xy 247.547171 -282.610698) (xy 247.606669 -282.601224)
			(xy 247.636792 -282.600654) (xy 247.664043 -282.601193) (xy 247.717989 -282.608948) (xy 247.770283 -282.624302)
			(xy 247.819859 -282.646942) (xy 247.865708 -282.676406) (xy 247.906898 -282.712097) (xy 247.942589 -282.753285)
			(xy 247.972055 -282.799134) (xy 247.994695 -282.84871) (xy 248.01005 -282.901003) (xy 248.017807 -282.954949)
			(xy 248.017807 -283.009451) (xy 248.01005 -283.063397) (xy 247.994695 -283.11569) (xy 247.987469 -283.131514)
			(xy 258.01142 -283.131514) (xy 258.015491 -283.075892) (xy 258.027617 -283.021455) (xy 258.04754 -282.969364)
			(xy 258.074836 -282.920729) (xy 258.108922 -282.876586) (xy 258.149071 -282.837877) (xy 258.194429 -282.805426)
			(xy 258.244029 -282.779925) (xy 258.296813 -282.761918) (xy 258.351656 -282.751788) (xy 258.40739 -282.749751)
			(xy 258.462827 -282.755851) (xy 258.516784 -282.769957) (xy 258.568113 -282.791769) (xy 258.615719 -282.820823)
			(xy 258.658587 -282.856498) (xy 258.695804 -282.898035) (xy 258.726577 -282.944548) (xy 258.750249 -282.995045)
			(xy 258.766317 -283.048452) (xy 258.774437 -283.103628) (xy 258.774946 -283.131514) (xy 259.486906 -283.131514)
			(xy 259.490977 -283.075892) (xy 259.503103 -283.021455) (xy 259.523026 -282.969364) (xy 259.550322 -282.920729)
			(xy 259.584408 -282.876586) (xy 259.624557 -282.837877) (xy 259.669915 -282.805426) (xy 259.719515 -282.779925)
			(xy 259.772299 -282.761918) (xy 259.827142 -282.751788) (xy 259.882876 -282.749751) (xy 259.938313 -282.755851)
			(xy 259.99227 -282.769957) (xy 260.043599 -282.791769) (xy 260.091205 -282.820823) (xy 260.134073 -282.856498)
			(xy 260.17129 -282.898035) (xy 260.202063 -282.944548) (xy 260.225735 -282.995045) (xy 260.241803 -283.048452)
			(xy 260.249923 -283.103628) (xy 260.250432 -283.131514) (xy 260.375906 -283.131514) (xy 260.379977 -283.075892)
			(xy 260.392103 -283.021455) (xy 260.412026 -282.969364) (xy 260.439322 -282.920729) (xy 260.473408 -282.876586)
			(xy 260.513557 -282.837877) (xy 260.558915 -282.805426) (xy 260.608515 -282.779925) (xy 260.661299 -282.761918)
			(xy 260.716142 -282.751788) (xy 260.771876 -282.749751) (xy 260.827313 -282.755851) (xy 260.88127 -282.769957)
			(xy 260.932599 -282.791769) (xy 260.980205 -282.820823) (xy 261.023073 -282.856498) (xy 261.06029 -282.898035)
			(xy 261.091063 -282.944548) (xy 261.114735 -282.995045) (xy 261.130803 -283.048452) (xy 261.138923 -283.103628)
			(xy 261.139432 -283.131514) (xy 261.138923 -283.1594) (xy 261.130803 -283.214576) (xy 261.114735 -283.267983)
			(xy 261.091063 -283.31848) (xy 261.06029 -283.364993) (xy 261.023073 -283.40653) (xy 260.980205 -283.442205)
			(xy 260.932599 -283.471259) (xy 260.88127 -283.493071) (xy 260.827313 -283.507177) (xy 260.771876 -283.513277)
			(xy 260.716142 -283.51124) (xy 260.661299 -283.50111) (xy 260.608515 -283.483103) (xy 260.558915 -283.457602)
			(xy 260.513557 -283.425151) (xy 260.473408 -283.386442) (xy 260.439322 -283.342299) (xy 260.412026 -283.293664)
			(xy 260.392103 -283.241573) (xy 260.379977 -283.187136) (xy 260.375906 -283.131514) (xy 260.250432 -283.131514)
			(xy 260.249923 -283.1594) (xy 260.241803 -283.214576) (xy 260.225735 -283.267983) (xy 260.202063 -283.31848)
			(xy 260.17129 -283.364993) (xy 260.134073 -283.40653) (xy 260.091205 -283.442205) (xy 260.043599 -283.471259)
			(xy 259.99227 -283.493071) (xy 259.938313 -283.507177) (xy 259.882876 -283.513277) (xy 259.827142 -283.51124)
			(xy 259.772299 -283.50111) (xy 259.719515 -283.483103) (xy 259.669915 -283.457602) (xy 259.624557 -283.425151)
			(xy 259.584408 -283.386442) (xy 259.550322 -283.342299) (xy 259.523026 -283.293664) (xy 259.503103 -283.241573)
			(xy 259.490977 -283.187136) (xy 259.486906 -283.131514) (xy 258.774946 -283.131514) (xy 258.774437 -283.1594)
			(xy 258.766317 -283.214576) (xy 258.750249 -283.267983) (xy 258.726577 -283.31848) (xy 258.695804 -283.364993)
			(xy 258.658587 -283.40653) (xy 258.615719 -283.442205) (xy 258.568113 -283.471259) (xy 258.516784 -283.493071)
			(xy 258.462827 -283.507177) (xy 258.40739 -283.513277) (xy 258.351656 -283.51124) (xy 258.296813 -283.50111)
			(xy 258.244029 -283.483103) (xy 258.194429 -283.457602) (xy 258.149071 -283.425151) (xy 258.108922 -283.386442)
			(xy 258.074836 -283.342299) (xy 258.04754 -283.293664) (xy 258.027617 -283.241573) (xy 258.015491 -283.187136)
			(xy 258.01142 -283.131514) (xy 247.987469 -283.131514) (xy 247.972055 -283.165266) (xy 247.942589 -283.211115)
			(xy 247.906898 -283.252303) (xy 247.865708 -283.287994) (xy 247.819859 -283.317458) (xy 247.770283 -283.340098)
			(xy 247.717989 -283.355452) (xy 247.664043 -283.363207) (xy 247.636792 -283.36367) (xy 247.606669 -283.363099)
			(xy 247.547173 -283.353617) (xy 247.489905 -283.334906) (xy 247.436288 -283.30743) (xy 247.387653 -283.271872)
			(xy 247.366028 -283.250894) (xy 247.358916 -283.243528) (xy 247.34012 -283.235908) (xy 247.247664 -283.235908)
			(xy 247.228868 -283.243528) (xy 247.221756 -283.250894) (xy 247.200129 -283.271871) (xy 247.151501 -283.30744)
			(xy 247.097885 -283.334921) (xy 247.040615 -283.35363) (xy 246.981116 -283.363101) (xy 246.950992 -283.36367)
			(xy 246.922254 -283.363132) (xy 246.865428 -283.35451) (xy 246.810538 -283.337462) (xy 246.758826 -283.312375)
			(xy 246.711462 -283.279814) (xy 246.690134 -283.260546) (xy 246.683022 -283.253942) (xy 246.665496 -283.24683)
			(xy 246.576088 -283.24683) (xy 246.558562 -283.253942) (xy 246.55145 -283.260546) (xy 246.530123 -283.279816)
			(xy 246.48276 -283.312381) (xy 246.431049 -283.337472) (xy 246.376158 -283.354522) (xy 246.319331 -283.363144)
			(xy 246.261853 -283.363144) (xy 246.205026 -283.354522) (xy 246.150135 -283.337472) (xy 246.098424 -283.312381)
			(xy 246.051061 -283.279816) (xy 246.029734 -283.260546) (xy 246.022622 -283.253942) (xy 246.005096 -283.24683)
			(xy 245.915688 -283.24683) (xy 245.898162 -283.253942) (xy 245.89105 -283.260546) (xy 245.869724 -283.279818)
			(xy 245.822362 -283.312385) (xy 245.77065 -283.337477) (xy 245.715759 -283.354527) (xy 245.658931 -283.36315)
			(xy 245.630192 -283.36367) (xy 245.602938 -283.36326) (xy 245.548986 -283.355501) (xy 245.496687 -283.340144)
			(xy 245.447106 -283.3175) (xy 245.401252 -283.288031) (xy 245.360059 -283.252336) (xy 245.324364 -283.211142)
			(xy 245.294896 -283.165287) (xy 245.272253 -283.115705) (xy 245.256897 -283.063406) (xy 245.24914 -283.009454)
			(xy 243.770383 -283.009454) (xy 243.762628 -283.06339) (xy 243.747275 -283.115679) (xy 243.724636 -283.165251)
			(xy 243.695173 -283.211097) (xy 243.659486 -283.252283) (xy 243.6183 -283.287971) (xy 243.572455 -283.317434)
			(xy 243.522883 -283.340073) (xy 243.470594 -283.355427) (xy 243.416652 -283.363184) (xy 243.389404 -283.36367)
			(xy 243.359281 -283.363091) (xy 243.299785 -283.353611) (xy 243.242518 -283.334902) (xy 243.1889 -283.307428)
			(xy 243.140265 -283.271872) (xy 243.11864 -283.250894) (xy 243.111528 -283.243528) (xy 243.092732 -283.235908)
			(xy 243.000276 -283.235908) (xy 242.98148 -283.243528) (xy 242.974368 -283.250894) (xy 242.952735 -283.271866)
			(xy 242.904109 -283.307435) (xy 242.850494 -283.334917) (xy 242.793226 -283.353627) (xy 242.733728 -283.363101)
			(xy 242.703604 -283.36367) (xy 242.674866 -283.363125) (xy 242.618041 -283.354505) (xy 242.563151 -283.337459)
			(xy 242.511439 -283.312372) (xy 242.464074 -283.279813) (xy 242.442746 -283.260546) (xy 242.435634 -283.253942)
			(xy 242.418108 -283.24683) (xy 242.3287 -283.24683) (xy 242.311174 -283.253942) (xy 242.304062 -283.260546)
			(xy 242.282735 -283.279816) (xy 242.235372 -283.312381) (xy 242.183661 -283.337472) (xy 242.12877 -283.354522)
			(xy 242.071943 -283.363144) (xy 242.014465 -283.363144) (xy 241.957638 -283.354522) (xy 241.902747 -283.337472)
			(xy 241.851036 -283.312381) (xy 241.803673 -283.279816) (xy 241.782346 -283.260546) (xy 241.775234 -283.253942)
			(xy 241.757708 -283.24683) (xy 241.6683 -283.24683) (xy 241.650774 -283.253942) (xy 241.643662 -283.260546)
			(xy 241.622331 -283.279812) (xy 241.57497 -283.31238) (xy 241.52326 -283.337473) (xy 241.46837 -283.354525)
			(xy 241.411543 -283.363149) (xy 241.382804 -283.36367) (xy 241.355548 -283.363283) (xy 241.301591 -283.355526)
			(xy 241.249288 -283.340169) (xy 241.199702 -283.317524) (xy 241.153844 -283.288053) (xy 241.112647 -283.252356)
			(xy 241.076949 -283.211159) (xy 241.047478 -283.165301) (xy 241.024833 -283.115716) (xy 241.009475 -283.063412)
			(xy 241.001717 -283.009456) (xy 234.5309 -283.009456) (xy 234.5309 -284.256226) (xy 234.531283 -284.26565)
			(xy 234.538114 -284.283219) (xy 234.550839 -284.297125) (xy 234.559094 -284.301692) (xy 234.653328 -284.348428)
			(xy 234.682284 -284.345634) (xy 234.693714 -284.336998) (xy 234.718642 -284.318971) (xy 234.773057 -284.290284)
			(xy 234.831368 -284.270694) (xy 234.892066 -284.260707) (xy 234.922822 -284.260036) (xy 234.923076 -284.260036)
			(xy 234.930442 -284.260036) (xy 234.95992 -284.261071) (xy 235.018042 -284.271114) (xy 235.073921 -284.289994)
			(xy 235.126223 -284.317259) (xy 235.173699 -284.352258) (xy 235.194856 -284.372812) (xy 235.201968 -284.379924)
			(xy 235.220764 -284.387798) (xy 235.31322 -284.387798) (xy 235.332016 -284.379924) (xy 235.339128 -284.372812)
			(xy 235.360753 -284.351833) (xy 235.409388 -284.316275) (xy 235.463005 -284.288799) (xy 235.520272 -284.270088)
			(xy 235.579769 -284.260606) (xy 235.609892 -284.260036) (xy 235.637142 -284.260499) (xy 235.691088 -284.268254)
			(xy 235.74338 -284.283607) (xy 235.792956 -284.306247) (xy 235.838805 -284.335711) (xy 235.879994 -284.371401)
			(xy 235.915684 -284.412589) (xy 235.945149 -284.458437) (xy 235.96779 -284.508012) (xy 235.983144 -284.560305)
			(xy 235.990901 -284.61425) (xy 235.990901 -284.66875) (xy 237.195599 -284.66875) (xy 237.195599 -284.61425)
			(xy 237.203356 -284.560304) (xy 237.218711 -284.508011) (xy 237.241352 -284.458435) (xy 237.270817 -284.412587)
			(xy 237.306509 -284.371399) (xy 237.347698 -284.335709) (xy 237.393548 -284.306245) (xy 237.443124 -284.283606)
			(xy 237.495417 -284.268253) (xy 237.549364 -284.260498) (xy 237.576614 -284.260036) (xy 237.605352 -284.260568)
			(xy 237.662179 -284.269191) (xy 237.717069 -284.28624) (xy 237.76878 -284.31133) (xy 237.816144 -284.343891)
			(xy 237.837472 -284.36316) (xy 237.844584 -284.369764) (xy 237.86211 -284.376876) (xy 237.951518 -284.376876)
			(xy 237.969044 -284.369764) (xy 237.976156 -284.36316) (xy 237.997483 -284.34389) (xy 238.044846 -284.311325)
			(xy 238.096557 -284.286234) (xy 238.151448 -284.269184) (xy 238.208275 -284.260562) (xy 238.265753 -284.260562)
			(xy 238.32258 -284.269184) (xy 238.377471 -284.286234) (xy 238.429182 -284.311325) (xy 238.476545 -284.34389)
			(xy 238.497872 -284.36316) (xy 238.504984 -284.369764) (xy 238.52251 -284.376876) (xy 238.611918 -284.376876)
			(xy 238.629444 -284.369764) (xy 238.636556 -284.36316) (xy 238.657881 -284.343886) (xy 238.705243 -284.31132)
			(xy 238.756955 -284.286227) (xy 238.811847 -284.269177) (xy 238.868675 -284.260556) (xy 238.897414 -284.260036)
			(xy 238.927538 -284.260602) (xy 238.987034 -284.270085) (xy 239.044302 -284.288797) (xy 239.097919 -284.316274)
			(xy 239.146553 -284.351833) (xy 239.168178 -284.372812) (xy 239.17529 -284.380178) (xy 239.194086 -284.387798)
			(xy 239.286542 -284.387798) (xy 239.305338 -284.380178) (xy 239.31245 -284.372812) (xy 239.334076 -284.351833)
			(xy 239.382704 -284.316264) (xy 239.43632 -284.288783) (xy 239.49359 -284.270075) (xy 239.55309 -284.260604)
			(xy 239.583214 -284.260036) (xy 239.610468 -284.260435) (xy 239.66442 -284.268194) (xy 239.716719 -284.283552)
			(xy 239.7663 -284.306197) (xy 239.812154 -284.335667) (xy 239.853348 -284.371362) (xy 239.889042 -284.412557)
			(xy 239.91851 -284.458412) (xy 239.941153 -284.507994) (xy 239.956509 -284.560294) (xy 239.964266 -284.614246)
			(xy 239.964266 -284.668754) (xy 239.956509 -284.722706) (xy 239.941153 -284.775006) (xy 239.91851 -284.824588)
			(xy 239.889042 -284.870443) (xy 239.853348 -284.911638) (xy 239.812154 -284.947333) (xy 239.7663 -284.976803)
			(xy 239.716719 -284.999448) (xy 239.66442 -285.014806) (xy 239.610468 -285.022565) (xy 239.583214 -285.023052)
			(xy 239.553091 -285.022472) (xy 239.493595 -285.012993) (xy 239.436327 -284.994284) (xy 239.38271 -284.966811)
			(xy 239.334075 -284.931254) (xy 239.31245 -284.910276) (xy 239.305338 -284.90291) (xy 239.286542 -284.89529)
			(xy 239.194086 -284.89529) (xy 239.17529 -284.90291) (xy 239.168178 -284.910276) (xy 239.146538 -284.93124)
			(xy 239.097914 -284.966811) (xy 239.044301 -284.994295) (xy 238.987034 -285.013007) (xy 238.927537 -285.022482)
			(xy 238.897414 -285.023052) (xy 238.868676 -285.022506) (xy 238.81185 -285.013887) (xy 238.75696 -284.996841)
			(xy 238.705248 -284.971755) (xy 238.657884 -284.939196) (xy 238.636556 -284.919928) (xy 238.629444 -284.913324)
			(xy 238.611918 -284.906212) (xy 238.52251 -284.906212) (xy 238.504984 -284.913324) (xy 238.497872 -284.919928)
			(xy 238.476545 -284.939198) (xy 238.429182 -284.971763) (xy 238.377471 -284.996854) (xy 238.32258 -285.013904)
			(xy 238.265753 -285.022526) (xy 238.208275 -285.022526) (xy 238.151448 -285.013904) (xy 238.096557 -284.996854)
			(xy 238.044846 -284.971763) (xy 237.997483 -284.939198) (xy 237.976156 -284.919928) (xy 237.969044 -284.913324)
			(xy 237.951518 -284.906212) (xy 237.86211 -284.906212) (xy 237.844584 -284.913324) (xy 237.837472 -284.919928)
			(xy 237.816134 -284.939186) (xy 237.768776 -284.971756) (xy 237.717067 -284.996851) (xy 237.662178 -285.013905)
			(xy 237.605352 -285.02253) (xy 237.576614 -285.023052) (xy 237.549364 -285.022502) (xy 237.495417 -285.014747)
			(xy 237.443124 -284.999394) (xy 237.393548 -284.976755) (xy 237.347698 -284.947291) (xy 237.306509 -284.911601)
			(xy 237.270817 -284.870413) (xy 237.241352 -284.824565) (xy 237.218711 -284.774989) (xy 237.203356 -284.722696)
			(xy 237.195599 -284.66875) (xy 235.990901 -284.66875) (xy 235.983144 -284.722695) (xy 235.96779 -284.774988)
			(xy 235.945149 -284.824563) (xy 235.915684 -284.870411) (xy 235.879994 -284.911599) (xy 235.838805 -284.947289)
			(xy 235.792956 -284.976753) (xy 235.74338 -284.999393) (xy 235.691088 -285.014746) (xy 235.637142 -285.022501)
			(xy 235.609892 -285.023052) (xy 235.579769 -285.022482) (xy 235.520271 -285.013008) (xy 235.463004 -284.994297)
			(xy 235.40939 -284.966814) (xy 235.360765 -284.931243) (xy 235.339128 -284.910276) (xy 235.332016 -284.903164)
			(xy 235.31322 -284.89529) (xy 235.220764 -284.89529) (xy 235.201968 -284.903164) (xy 235.194856 -284.910276)
			(xy 235.173231 -284.931254) (xy 235.124596 -284.966812) (xy 235.070979 -284.994286) (xy 235.013711 -285.012996)
			(xy 234.954215 -285.022476) (xy 234.924092 -285.023052) (xy 234.91952 -285.023052) (xy 234.889181 -285.022149)
			(xy 234.829356 -285.011917) (xy 234.771905 -284.992343) (xy 234.718277 -284.963921) (xy 234.693714 -284.94609)
			(xy 234.682284 -284.937454) (xy 234.653328 -284.93466) (xy 234.559094 -284.981396) (xy 234.550864 -284.985984)
			(xy 234.538187 -284.999899) (xy 234.531383 -285.01745) (xy 234.5309 -285.026862) (xy 234.5309 -285.029656)
			(xy 258.01142 -285.029656) (xy 258.015491 -284.974034) (xy 258.027617 -284.919597) (xy 258.04754 -284.867506)
			(xy 258.074836 -284.818871) (xy 258.108922 -284.774728) (xy 258.149071 -284.736019) (xy 258.194429 -284.703568)
			(xy 258.244029 -284.678067) (xy 258.296813 -284.66006) (xy 258.351656 -284.64993) (xy 258.40739 -284.647893)
			(xy 258.462827 -284.653993) (xy 258.516784 -284.668099) (xy 258.568113 -284.689911) (xy 258.615719 -284.718965)
			(xy 258.658587 -284.75464) (xy 258.695804 -284.796177) (xy 258.726577 -284.84269) (xy 258.750249 -284.893187)
			(xy 258.766317 -284.946594) (xy 258.774437 -285.00177) (xy 258.774946 -285.029656) (xy 259.496558 -285.029656)
			(xy 259.500629 -284.974034) (xy 259.512755 -284.919597) (xy 259.532678 -284.867506) (xy 259.559974 -284.818871)
			(xy 259.59406 -284.774728) (xy 259.634209 -284.736019) (xy 259.679567 -284.703568) (xy 259.729167 -284.678067)
			(xy 259.781951 -284.66006) (xy 259.836794 -284.64993) (xy 259.892528 -284.647893) (xy 259.947965 -284.653993)
			(xy 260.001922 -284.668099) (xy 260.053251 -284.689911) (xy 260.100857 -284.718965) (xy 260.143725 -284.75464)
			(xy 260.180942 -284.796177) (xy 260.211715 -284.84269) (xy 260.235387 -284.893187) (xy 260.251455 -284.946594)
			(xy 260.259575 -285.00177) (xy 260.260084 -285.029656) (xy 260.259575 -285.057542) (xy 260.251455 -285.112718)
			(xy 260.235387 -285.166125) (xy 260.211715 -285.216622) (xy 260.180942 -285.263135) (xy 260.143725 -285.304672)
			(xy 260.100857 -285.340347) (xy 260.053251 -285.369401) (xy 260.001922 -285.391213) (xy 259.947965 -285.405319)
			(xy 259.892528 -285.411419) (xy 259.836794 -285.409382) (xy 259.781951 -285.399252) (xy 259.729167 -285.381245)
			(xy 259.679567 -285.355744) (xy 259.634209 -285.323293) (xy 259.59406 -285.284584) (xy 259.559974 -285.240441)
			(xy 259.532678 -285.191806) (xy 259.512755 -285.139715) (xy 259.500629 -285.085278) (xy 259.496558 -285.029656)
			(xy 258.774946 -285.029656) (xy 258.774437 -285.057542) (xy 258.766317 -285.112718) (xy 258.750249 -285.166125)
			(xy 258.726577 -285.216622) (xy 258.695804 -285.263135) (xy 258.658587 -285.304672) (xy 258.615719 -285.340347)
			(xy 258.568113 -285.369401) (xy 258.516784 -285.391213) (xy 258.462827 -285.405319) (xy 258.40739 -285.411419)
			(xy 258.351656 -285.409382) (xy 258.296813 -285.399252) (xy 258.244029 -285.381245) (xy 258.194429 -285.355744)
			(xy 258.149071 -285.323293) (xy 258.108922 -285.284584) (xy 258.074836 -285.240441) (xy 258.04754 -285.191806)
			(xy 258.027617 -285.139715) (xy 258.015491 -285.085278) (xy 258.01142 -285.029656) (xy 234.5309 -285.029656)
			(xy 234.5309 -285.473256) (xy 241.001717 -285.473256) (xy 241.001717 -285.418744) (xy 241.009475 -285.364788)
			(xy 241.024833 -285.312484) (xy 241.047478 -285.262899) (xy 241.076949 -285.217041) (xy 241.112647 -285.175844)
			(xy 241.153844 -285.140147) (xy 241.199702 -285.110676) (xy 241.249288 -285.088031) (xy 241.301591 -285.072674)
			(xy 241.355548 -285.064917) (xy 241.382804 -285.064454) (xy 241.411542 -285.064988) (xy 241.468369 -285.07361)
			(xy 241.523259 -285.090658) (xy 241.574971 -285.115747) (xy 241.622334 -285.148309) (xy 241.643662 -285.167578)
			(xy 241.650774 -285.174182) (xy 241.6683 -285.181294) (xy 241.757708 -285.181294) (xy 241.775234 -285.174182)
			(xy 241.782346 -285.167578) (xy 241.803673 -285.148308) (xy 241.851036 -285.115743) (xy 241.902747 -285.090652)
			(xy 241.957638 -285.073602) (xy 242.014465 -285.06498) (xy 242.071943 -285.06498) (xy 242.12877 -285.073602)
			(xy 242.183661 -285.090652) (xy 242.235372 -285.115743) (xy 242.282735 -285.148308) (xy 242.304062 -285.167578)
			(xy 242.311174 -285.174182) (xy 242.3287 -285.181294) (xy 242.418108 -285.181294) (xy 242.435634 -285.174182)
			(xy 242.442746 -285.167578) (xy 242.464077 -285.148312) (xy 242.511437 -285.115744) (xy 242.563148 -285.090649)
			(xy 242.618038 -285.073598) (xy 242.674865 -285.064975) (xy 242.703604 -285.064454) (xy 242.733728 -285.065021)
			(xy 242.793224 -285.074503) (xy 242.850492 -285.093214) (xy 242.904109 -285.120691) (xy 242.952743 -285.156251)
			(xy 242.974368 -285.17723) (xy 242.98148 -285.184596) (xy 243.000276 -285.192216) (xy 243.092732 -285.192216)
			(xy 243.111528 -285.184596) (xy 243.11864 -285.17723) (xy 243.140273 -285.156259) (xy 243.188899 -285.120688)
			(xy 243.242513 -285.093206) (xy 243.299782 -285.074496) (xy 243.35928 -285.065023) (xy 243.389404 -285.064454)
			(xy 243.416652 -285.065016) (xy 243.470594 -285.072773) (xy 243.522883 -285.088127) (xy 243.572455 -285.110766)
			(xy 243.6183 -285.140229) (xy 243.659486 -285.175917) (xy 243.695173 -285.217103) (xy 243.724636 -285.262949)
			(xy 243.747275 -285.312521) (xy 243.762628 -285.36481) (xy 243.770384 -285.418752) (xy 243.770384 -285.473248)
			(xy 243.770383 -285.473254) (xy 245.27454 -285.473254) (xy 245.27454 -285.418746) (xy 245.282297 -285.364794)
			(xy 245.297653 -285.312495) (xy 245.320296 -285.262913) (xy 245.349764 -285.217058) (xy 245.385459 -285.175864)
			(xy 245.426652 -285.140169) (xy 245.472506 -285.1107) (xy 245.522087 -285.088056) (xy 245.574386 -285.072699)
			(xy 245.628338 -285.06494) (xy 245.655592 -285.064454) (xy 245.68433 -285.064995) (xy 245.741156 -285.073615)
			(xy 245.796046 -285.090662) (xy 245.847758 -285.115749) (xy 245.895122 -285.14831) (xy 245.91645 -285.167578)
			(xy 245.923562 -285.174182) (xy 245.941088 -285.181294) (xy 246.030496 -285.181294) (xy 246.048022 -285.174182)
			(xy 246.055134 -285.167578) (xy 246.076461 -285.148308) (xy 246.123824 -285.115743) (xy 246.175535 -285.090652)
			(xy 246.230426 -285.073602) (xy 246.287253 -285.06498) (xy 246.344731 -285.06498) (xy 246.401558 -285.073602)
			(xy 246.456449 -285.090652) (xy 246.50816 -285.115743) (xy 246.555523 -285.148308) (xy 246.57685 -285.167578)
			(xy 246.583962 -285.174182) (xy 246.601488 -285.181294) (xy 246.690896 -285.181294) (xy 246.708422 -285.174182)
			(xy 246.715534 -285.167578) (xy 246.73687 -285.148318) (xy 246.784229 -285.115748) (xy 246.835938 -285.090653)
			(xy 246.890827 -285.0736) (xy 246.947653 -285.064976) (xy 246.976392 -285.064454) (xy 247.006515 -285.065029)
			(xy 247.066012 -285.074508) (xy 247.123279 -285.093218) (xy 247.176897 -285.120693) (xy 247.225531 -285.156251)
			(xy 247.247156 -285.17723) (xy 247.254268 -285.184596) (xy 247.273064 -285.192216) (xy 247.36552 -285.192216)
			(xy 247.384316 -285.184596) (xy 247.391428 -285.17723) (xy 247.413066 -285.156264) (xy 247.461691 -285.120693)
			(xy 247.515304 -285.09321) (xy 247.572571 -285.074498) (xy 247.632069 -285.065024) (xy 247.662192 -285.064454)
			(xy 247.689443 -285.064993) (xy 247.743389 -285.072748) (xy 247.795683 -285.088102) (xy 247.845259 -285.110742)
			(xy 247.891108 -285.140206) (xy 247.932298 -285.175897) (xy 247.967989 -285.217085) (xy 247.997455 -285.262934)
			(xy 248.020095 -285.31251) (xy 248.03545 -285.364803) (xy 248.043207 -285.418749) (xy 248.043207 -285.473251)
			(xy 248.03545 -285.527197) (xy 248.020095 -285.57949) (xy 247.997455 -285.629066) (xy 247.967989 -285.674915)
			(xy 247.932298 -285.716103) (xy 247.891108 -285.751794) (xy 247.845259 -285.781258) (xy 247.795683 -285.803898)
			(xy 247.743389 -285.819252) (xy 247.689443 -285.827007) (xy 247.662192 -285.82747) (xy 247.632069 -285.826899)
			(xy 247.572573 -285.817417) (xy 247.515305 -285.798706) (xy 247.461688 -285.77123) (xy 247.413053 -285.735672)
			(xy 247.391428 -285.714694) (xy 247.384316 -285.707328) (xy 247.36552 -285.699708) (xy 247.273064 -285.699708)
			(xy 247.254268 -285.707328) (xy 247.247156 -285.714694) (xy 247.225529 -285.735671) (xy 247.176901 -285.77124)
			(xy 247.123285 -285.798721) (xy 247.066015 -285.81743) (xy 247.006516 -285.826901) (xy 246.976392 -285.82747)
			(xy 246.947654 -285.826932) (xy 246.890828 -285.81831) (xy 246.835938 -285.801262) (xy 246.784226 -285.776175)
			(xy 246.736862 -285.743614) (xy 246.715534 -285.724346) (xy 246.708422 -285.717742) (xy 246.690896 -285.71063)
			(xy 246.601488 -285.71063) (xy 246.583962 -285.717742) (xy 246.57685 -285.724346) (xy 246.555523 -285.743616)
			(xy 246.50816 -285.776181) (xy 246.456449 -285.801272) (xy 246.401558 -285.818322) (xy 246.344731 -285.826944)
			(xy 246.287253 -285.826944) (xy 246.230426 -285.818322) (xy 246.175535 -285.801272) (xy 246.123824 -285.776181)
			(xy 246.076461 -285.743616) (xy 246.055134 -285.724346) (xy 246.048022 -285.717742) (xy 246.030496 -285.71063)
			(xy 245.941088 -285.71063) (xy 245.923562 -285.717742) (xy 245.91645 -285.724346) (xy 245.895124 -285.743618)
			(xy 245.847762 -285.776185) (xy 245.79605 -285.801277) (xy 245.741159 -285.818327) (xy 245.684331 -285.82695)
			(xy 245.655592 -285.82747) (xy 245.628338 -285.82706) (xy 245.574386 -285.819301) (xy 245.522087 -285.803944)
			(xy 245.472506 -285.7813) (xy 245.426652 -285.751831) (xy 245.385459 -285.716136) (xy 245.349764 -285.674942)
			(xy 245.320296 -285.629087) (xy 245.297653 -285.579505) (xy 245.282297 -285.527206) (xy 245.27454 -285.473254)
			(xy 243.770383 -285.473254) (xy 243.762628 -285.52719) (xy 243.747275 -285.579479) (xy 243.724636 -285.629051)
			(xy 243.695173 -285.674897) (xy 243.659486 -285.716083) (xy 243.6183 -285.751771) (xy 243.572455 -285.781234)
			(xy 243.522883 -285.803873) (xy 243.470594 -285.819227) (xy 243.416652 -285.826984) (xy 243.389404 -285.82747)
			(xy 243.359281 -285.826891) (xy 243.299785 -285.817411) (xy 243.242518 -285.798702) (xy 243.1889 -285.771228)
			(xy 243.140265 -285.735672) (xy 243.11864 -285.714694) (xy 243.111528 -285.707328) (xy 243.092732 -285.699708)
			(xy 243.000276 -285.699708) (xy 242.98148 -285.707328) (xy 242.974368 -285.714694) (xy 242.952735 -285.735666)
			(xy 242.904109 -285.771235) (xy 242.850494 -285.798717) (xy 242.793226 -285.817427) (xy 242.733728 -285.826901)
			(xy 242.703604 -285.82747) (xy 242.674866 -285.826925) (xy 242.618041 -285.818305) (xy 242.563151 -285.801259)
			(xy 242.511439 -285.776172) (xy 242.464074 -285.743613) (xy 242.442746 -285.724346) (xy 242.435634 -285.717742)
			(xy 242.418108 -285.71063) (xy 242.3287 -285.71063) (xy 242.311174 -285.717742) (xy 242.304062 -285.724346)
			(xy 242.282735 -285.743616) (xy 242.235372 -285.776181) (xy 242.183661 -285.801272) (xy 242.12877 -285.818322)
			(xy 242.071943 -285.826944) (xy 242.014465 -285.826944) (xy 241.957638 -285.818322) (xy 241.902747 -285.801272)
			(xy 241.851036 -285.776181) (xy 241.803673 -285.743616) (xy 241.782346 -285.724346) (xy 241.775234 -285.717742)
			(xy 241.757708 -285.71063) (xy 241.6683 -285.71063) (xy 241.650774 -285.717742) (xy 241.643662 -285.724346)
			(xy 241.622331 -285.743612) (xy 241.57497 -285.77618) (xy 241.52326 -285.801273) (xy 241.46837 -285.818325)
			(xy 241.411543 -285.826949) (xy 241.382804 -285.82747) (xy 241.355548 -285.827083) (xy 241.301591 -285.819326)
			(xy 241.249288 -285.803969) (xy 241.199702 -285.781324) (xy 241.153844 -285.751853) (xy 241.112647 -285.716156)
			(xy 241.076949 -285.674959) (xy 241.047478 -285.629101) (xy 241.024833 -285.579516) (xy 241.009475 -285.527212)
			(xy 241.001717 -285.473256) (xy 234.5309 -285.473256) (xy 234.5309 -286.708596) (xy 249.695714 -286.708596)
			(xy 249.699785 -286.652974) (xy 249.711911 -286.598537) (xy 249.731834 -286.546446) (xy 249.75913 -286.497811)
			(xy 249.793216 -286.453668) (xy 249.833365 -286.414959) (xy 249.878723 -286.382508) (xy 249.928323 -286.357007)
			(xy 249.981107 -286.339) (xy 250.03595 -286.32887) (xy 250.091684 -286.326833) (xy 250.147121 -286.332933)
			(xy 250.201078 -286.347039) (xy 250.252407 -286.368851) (xy 250.300013 -286.397905) (xy 250.342881 -286.43358)
			(xy 250.380098 -286.475117) (xy 250.410871 -286.52163) (xy 250.434543 -286.572127) (xy 250.445339 -286.608012)
			(xy 251.525784 -286.608012) (xy 251.529855 -286.55239) (xy 251.541981 -286.497953) (xy 251.561904 -286.445862)
			(xy 251.5892 -286.397227) (xy 251.623286 -286.353084) (xy 251.663435 -286.314375) (xy 251.708793 -286.281924)
			(xy 251.758393 -286.256423) (xy 251.811177 -286.238416) (xy 251.86602 -286.228286) (xy 251.921754 -286.226249)
			(xy 251.977191 -286.232349) (xy 252.031148 -286.246455) (xy 252.082477 -286.268267) (xy 252.130083 -286.297321)
			(xy 252.171651 -286.331914) (xy 258.01142 -286.331914) (xy 258.015491 -286.276292) (xy 258.027617 -286.221855)
			(xy 258.04754 -286.169764) (xy 258.074836 -286.121129) (xy 258.108922 -286.076986) (xy 258.149071 -286.038277)
			(xy 258.194429 -286.005826) (xy 258.244029 -285.980325) (xy 258.296813 -285.962318) (xy 258.351656 -285.952188)
			(xy 258.40739 -285.950151) (xy 258.462827 -285.956251) (xy 258.516784 -285.970357) (xy 258.568113 -285.992169)
			(xy 258.615719 -286.021223) (xy 258.658587 -286.056898) (xy 258.695804 -286.098435) (xy 258.726577 -286.144948)
			(xy 258.750249 -286.195445) (xy 258.766317 -286.248852) (xy 258.774437 -286.304028) (xy 258.774946 -286.331914)
			(xy 259.486906 -286.331914) (xy 259.490977 -286.276292) (xy 259.503103 -286.221855) (xy 259.523026 -286.169764)
			(xy 259.550322 -286.121129) (xy 259.584408 -286.076986) (xy 259.624557 -286.038277) (xy 259.669915 -286.005826)
			(xy 259.719515 -285.980325) (xy 259.772299 -285.962318) (xy 259.827142 -285.952188) (xy 259.882876 -285.950151)
			(xy 259.938313 -285.956251) (xy 259.99227 -285.970357) (xy 260.043599 -285.992169) (xy 260.091205 -286.021223)
			(xy 260.134073 -286.056898) (xy 260.17129 -286.098435) (xy 260.202063 -286.144948) (xy 260.225735 -286.195445)
			(xy 260.241803 -286.248852) (xy 260.249923 -286.304028) (xy 260.250432 -286.331914) (xy 260.375906 -286.331914)
			(xy 260.379977 -286.276292) (xy 260.392103 -286.221855) (xy 260.412026 -286.169764) (xy 260.439322 -286.121129)
			(xy 260.473408 -286.076986) (xy 260.513557 -286.038277) (xy 260.558915 -286.005826) (xy 260.608515 -285.980325)
			(xy 260.661299 -285.962318) (xy 260.716142 -285.952188) (xy 260.771876 -285.950151) (xy 260.827313 -285.956251)
			(xy 260.88127 -285.970357) (xy 260.932599 -285.992169) (xy 260.980205 -286.021223) (xy 261.023073 -286.056898)
			(xy 261.06029 -286.098435) (xy 261.091063 -286.144948) (xy 261.114735 -286.195445) (xy 261.130803 -286.248852)
			(xy 261.138923 -286.304028) (xy 261.139432 -286.331914) (xy 261.138923 -286.3598) (xy 261.130803 -286.414976)
			(xy 261.114735 -286.468383) (xy 261.091063 -286.51888) (xy 261.06029 -286.565393) (xy 261.023073 -286.60693)
			(xy 260.980205 -286.642605) (xy 260.932599 -286.671659) (xy 260.88127 -286.693471) (xy 260.827313 -286.707577)
			(xy 260.771876 -286.713677) (xy 260.716142 -286.71164) (xy 260.661299 -286.70151) (xy 260.608515 -286.683503)
			(xy 260.558915 -286.658002) (xy 260.513557 -286.625551) (xy 260.473408 -286.586842) (xy 260.439322 -286.542699)
			(xy 260.412026 -286.494064) (xy 260.392103 -286.441973) (xy 260.379977 -286.387536) (xy 260.375906 -286.331914)
			(xy 260.250432 -286.331914) (xy 260.249923 -286.3598) (xy 260.241803 -286.414976) (xy 260.225735 -286.468383)
			(xy 260.202063 -286.51888) (xy 260.17129 -286.565393) (xy 260.134073 -286.60693) (xy 260.091205 -286.642605)
			(xy 260.043599 -286.671659) (xy 259.99227 -286.693471) (xy 259.938313 -286.707577) (xy 259.882876 -286.713677)
			(xy 259.827142 -286.71164) (xy 259.772299 -286.70151) (xy 259.719515 -286.683503) (xy 259.669915 -286.658002)
			(xy 259.624557 -286.625551) (xy 259.584408 -286.586842) (xy 259.550322 -286.542699) (xy 259.523026 -286.494064)
			(xy 259.503103 -286.441973) (xy 259.490977 -286.387536) (xy 259.486906 -286.331914) (xy 258.774946 -286.331914)
			(xy 258.774437 -286.3598) (xy 258.766317 -286.414976) (xy 258.750249 -286.468383) (xy 258.726577 -286.51888)
			(xy 258.695804 -286.565393) (xy 258.658587 -286.60693) (xy 258.615719 -286.642605) (xy 258.568113 -286.671659)
			(xy 258.516784 -286.693471) (xy 258.462827 -286.707577) (xy 258.40739 -286.713677) (xy 258.351656 -286.71164)
			(xy 258.296813 -286.70151) (xy 258.244029 -286.683503) (xy 258.194429 -286.658002) (xy 258.149071 -286.625551)
			(xy 258.108922 -286.586842) (xy 258.074836 -286.542699) (xy 258.04754 -286.494064) (xy 258.027617 -286.441973)
			(xy 258.015491 -286.387536) (xy 258.01142 -286.331914) (xy 252.171651 -286.331914) (xy 252.172951 -286.332996)
			(xy 252.210168 -286.374533) (xy 252.240941 -286.421046) (xy 252.264613 -286.471543) (xy 252.280681 -286.52495)
			(xy 252.288801 -286.580126) (xy 252.28931 -286.608012) (xy 252.288801 -286.635898) (xy 252.280681 -286.691074)
			(xy 252.264613 -286.744481) (xy 252.240941 -286.794978) (xy 252.210168 -286.841491) (xy 252.172951 -286.883028)
			(xy 252.130083 -286.918703) (xy 252.082477 -286.947757) (xy 252.031148 -286.969569) (xy 251.977191 -286.983675)
			(xy 251.921754 -286.989775) (xy 251.86602 -286.987738) (xy 251.811177 -286.977608) (xy 251.758393 -286.959601)
			(xy 251.708793 -286.9341) (xy 251.663435 -286.901649) (xy 251.623286 -286.86294) (xy 251.5892 -286.818797)
			(xy 251.561904 -286.770162) (xy 251.541981 -286.718071) (xy 251.529855 -286.663634) (xy 251.525784 -286.608012)
			(xy 250.445339 -286.608012) (xy 250.450611 -286.625534) (xy 250.458731 -286.68071) (xy 250.45924 -286.708596)
			(xy 250.458731 -286.736482) (xy 250.450611 -286.791658) (xy 250.434543 -286.845065) (xy 250.410871 -286.895562)
			(xy 250.380098 -286.942075) (xy 250.342881 -286.983612) (xy 250.300013 -287.019287) (xy 250.252407 -287.048341)
			(xy 250.201078 -287.070153) (xy 250.147121 -287.084259) (xy 250.091684 -287.090359) (xy 250.03595 -287.088322)
			(xy 249.981107 -287.078192) (xy 249.928323 -287.060185) (xy 249.878723 -287.034684) (xy 249.833365 -287.002233)
			(xy 249.793216 -286.963524) (xy 249.75913 -286.919381) (xy 249.731834 -286.870746) (xy 249.711911 -286.818655)
			(xy 249.699785 -286.764218) (xy 249.695714 -286.708596) (xy 234.5309 -286.708596) (xy 234.5309 -286.724598)
			(xy 234.531296 -286.734119) (xy 234.538255 -286.751844) (xy 234.55121 -286.765801) (xy 234.559602 -286.770318)
			(xy 234.58805 -286.784034) (xy 234.588304 -286.784034) (xy 234.619292 -286.799274) (xy 234.624571 -286.801648)
			(xy 234.635857 -286.80421) (xy 234.641644 -286.804354) (xy 234.677966 -286.804354) (xy 234.681974 -286.804287)
			(xy 234.689889 -286.803013) (xy 234.693714 -286.801814) (xy 234.701588 -286.799274) (xy 234.707938 -286.794702)
			(xy 234.732323 -286.777992) (xy 234.785167 -286.751503) (xy 234.841466 -286.733485) (xy 234.89987 -286.724369)
			(xy 234.929426 -286.723836) (xy 234.959552 -286.724399) (xy 235.019056 -286.733862) (xy 235.076332 -286.752564)
			(xy 235.129955 -286.780039) (xy 235.178591 -286.815604) (xy 235.20019 -286.836612) (xy 235.207302 -286.843724)
			(xy 235.226098 -286.851598) (xy 235.318554 -286.851598) (xy 235.33735 -286.843724) (xy 235.344462 -286.836612)
			(xy 235.366088 -286.815635) (xy 235.414723 -286.780081) (xy 235.468341 -286.75261) (xy 235.525608 -286.733904)
			(xy 235.585103 -286.724427) (xy 235.615226 -286.723836) (xy 235.642473 -286.724324) (xy 235.696411 -286.732083)
			(xy 235.748697 -286.747438) (xy 235.798265 -286.770078) (xy 235.844107 -286.799542) (xy 235.885289 -286.835229)
			(xy 235.920974 -286.876414) (xy 235.950434 -286.922258) (xy 235.973071 -286.971827) (xy 235.988423 -287.024114)
			(xy 235.996178 -287.078053) (xy 235.996178 -287.132547) (xy 235.996178 -287.13255) (xy 237.195599 -287.13255)
			(xy 237.195599 -287.07805) (xy 237.203356 -287.024104) (xy 237.218711 -286.971811) (xy 237.241352 -286.922235)
			(xy 237.270817 -286.876387) (xy 237.306509 -286.835199) (xy 237.347698 -286.799509) (xy 237.393548 -286.770045)
			(xy 237.443124 -286.747406) (xy 237.495417 -286.732053) (xy 237.549364 -286.724298) (xy 237.576614 -286.723836)
			(xy 237.605352 -286.724368) (xy 237.662179 -286.732991) (xy 237.717069 -286.75004) (xy 237.76878 -286.77513)
			(xy 237.816144 -286.807691) (xy 237.837472 -286.82696) (xy 237.844584 -286.833564) (xy 237.86211 -286.840676)
			(xy 237.951518 -286.840676) (xy 237.969044 -286.833564) (xy 237.976156 -286.82696) (xy 237.997483 -286.80769)
			(xy 238.044846 -286.775125) (xy 238.096557 -286.750034) (xy 238.151448 -286.732984) (xy 238.208275 -286.724362)
			(xy 238.265753 -286.724362) (xy 238.32258 -286.732984) (xy 238.377471 -286.750034) (xy 238.429182 -286.775125)
			(xy 238.476545 -286.80769) (xy 238.497872 -286.82696) (xy 238.504984 -286.833564) (xy 238.52251 -286.840676)
			(xy 238.611918 -286.840676) (xy 238.629444 -286.833564) (xy 238.636556 -286.82696) (xy 238.657881 -286.807686)
			(xy 238.705243 -286.77512) (xy 238.756955 -286.750027) (xy 238.811847 -286.732977) (xy 238.868675 -286.724356)
			(xy 238.897414 -286.723836) (xy 238.927538 -286.724402) (xy 238.987034 -286.733885) (xy 239.044302 -286.752597)
			(xy 239.097919 -286.780074) (xy 239.146553 -286.815633) (xy 239.168178 -286.836612) (xy 239.17529 -286.843978)
			(xy 239.194086 -286.851598) (xy 239.286542 -286.851598) (xy 239.305338 -286.843978) (xy 239.31245 -286.836612)
			(xy 239.334076 -286.815633) (xy 239.382704 -286.780064) (xy 239.43632 -286.752583) (xy 239.49359 -286.733875)
			(xy 239.55309 -286.724404) (xy 239.583214 -286.723836) (xy 239.610468 -286.724235) (xy 239.66442 -286.731994)
			(xy 239.716719 -286.747352) (xy 239.7663 -286.769997) (xy 239.812154 -286.799467) (xy 239.853348 -286.835162)
			(xy 239.889042 -286.876357) (xy 239.91851 -286.922212) (xy 239.941153 -286.971794) (xy 239.956509 -287.024094)
			(xy 239.964266 -287.078046) (xy 239.964266 -287.132554) (xy 239.956509 -287.186506) (xy 239.941153 -287.238806)
			(xy 239.91851 -287.288388) (xy 239.889042 -287.334243) (xy 239.853348 -287.375438) (xy 239.812154 -287.411133)
			(xy 239.7663 -287.440603) (xy 239.716719 -287.463248) (xy 239.66442 -287.478606) (xy 239.610468 -287.486365)
			(xy 239.583214 -287.486852) (xy 239.553091 -287.486272) (xy 239.493595 -287.476793) (xy 239.436327 -287.458084)
			(xy 239.38271 -287.430611) (xy 239.334075 -287.395054) (xy 239.31245 -287.374076) (xy 239.305338 -287.36671)
			(xy 239.286542 -287.35909) (xy 239.194086 -287.35909) (xy 239.17529 -287.36671) (xy 239.168178 -287.374076)
			(xy 239.146538 -287.39504) (xy 239.097914 -287.430611) (xy 239.044301 -287.458095) (xy 238.987034 -287.476807)
			(xy 238.927537 -287.486282) (xy 238.897414 -287.486852) (xy 238.868676 -287.486306) (xy 238.81185 -287.477687)
			(xy 238.75696 -287.460641) (xy 238.705248 -287.435555) (xy 238.657884 -287.402996) (xy 238.636556 -287.383728)
			(xy 238.629444 -287.377124) (xy 238.611918 -287.370012) (xy 238.52251 -287.370012) (xy 238.504984 -287.377124)
			(xy 238.497872 -287.383728) (xy 238.476545 -287.402998) (xy 238.429182 -287.435563) (xy 238.377471 -287.460654)
			(xy 238.32258 -287.477704) (xy 238.265753 -287.486326) (xy 238.208275 -287.486326) (xy 238.151448 -287.477704)
			(xy 238.096557 -287.460654) (xy 238.044846 -287.435563) (xy 237.997483 -287.402998) (xy 237.976156 -287.383728)
			(xy 237.969044 -287.377124) (xy 237.951518 -287.370012) (xy 237.86211 -287.370012) (xy 237.844584 -287.377124)
			(xy 237.837472 -287.383728) (xy 237.816134 -287.402986) (xy 237.768776 -287.435556) (xy 237.717067 -287.460651)
			(xy 237.662178 -287.477705) (xy 237.605352 -287.48633) (xy 237.576614 -287.486852) (xy 237.549364 -287.486302)
			(xy 237.495417 -287.478547) (xy 237.443124 -287.463194) (xy 237.393548 -287.440555) (xy 237.347698 -287.411091)
			(xy 237.306509 -287.375401) (xy 237.270817 -287.334213) (xy 237.241352 -287.288365) (xy 237.218711 -287.238789)
			(xy 237.203356 -287.186496) (xy 237.195599 -287.13255) (xy 235.996178 -287.13255) (xy 235.988423 -287.186486)
			(xy 235.973071 -287.238773) (xy 235.950434 -287.288342) (xy 235.920974 -287.334186) (xy 235.885289 -287.375371)
			(xy 235.844107 -287.411058) (xy 235.798265 -287.440522) (xy 235.748697 -287.463162) (xy 235.696411 -287.478517)
			(xy 235.642473 -287.486276) (xy 235.615226 -287.486852) (xy 235.585101 -287.486285) (xy 235.525601 -287.476815)
			(xy 235.46833 -287.458108) (xy 235.414713 -287.430628) (xy 235.366084 -287.395059) (xy 235.344462 -287.374076)
			(xy 235.33735 -287.366964) (xy 235.318554 -287.35909) (xy 235.226098 -287.35909) (xy 235.207302 -287.366964)
			(xy 235.20019 -287.374076) (xy 235.178566 -287.395056) (xy 235.129932 -287.430618) (xy 235.076315 -287.458098)
			(xy 235.019047 -287.476812) (xy 234.95955 -287.486297) (xy 234.929426 -287.486852) (xy 234.916561 -287.48679)
			(xy 234.890885 -287.485138) (xy 234.878118 -287.48355) (xy 234.872784 -287.482788) (xy 234.848644 -287.478769)
			(xy 234.801584 -287.465344) (xy 234.756629 -287.446007) (xy 234.714517 -287.421077) (xy 234.694984 -287.406334)
			(xy 234.6833 -287.397444) (xy 234.654598 -287.394396) (xy 234.559348 -287.440878) (xy 234.55101 -287.445366)
			(xy 234.538173 -287.459266) (xy 234.531272 -287.476884) (xy 234.5309 -287.486344) (xy 234.5309 -287.776255)
			(xy 242.583135 -287.776255) (xy 242.583135 -287.721745) (xy 242.590893 -287.667791) (xy 242.60625 -287.61549)
			(xy 242.628894 -287.565906) (xy 242.658364 -287.52005) (xy 242.694061 -287.478855) (xy 242.735257 -287.44316)
			(xy 242.781113 -287.41369) (xy 242.830697 -287.391047) (xy 242.882999 -287.375691) (xy 242.936953 -287.367934)
			(xy 242.964208 -287.367472) (xy 242.994332 -287.368031) (xy 243.053829 -287.377514) (xy 243.111097 -287.396227)
			(xy 243.164714 -287.423706) (xy 243.213348 -287.459267) (xy 243.234972 -287.480248) (xy 243.242084 -287.487614)
			(xy 243.26088 -287.495234) (xy 243.353336 -287.495234) (xy 243.372132 -287.487614) (xy 243.379244 -287.480248)
			(xy 243.400878 -287.459278) (xy 243.449504 -287.423706) (xy 243.503118 -287.396223) (xy 243.560386 -287.377513)
			(xy 243.619884 -287.368041) (xy 243.650008 -287.367472) (xy 243.677257 -287.367999) (xy 243.731201 -287.375756)
			(xy 243.783492 -287.391111) (xy 243.833066 -287.413751) (xy 243.878913 -287.443216) (xy 243.9201 -287.478906)
			(xy 243.955789 -287.520094) (xy 243.985253 -287.565941) (xy 244.007892 -287.615515) (xy 244.023246 -287.667806)
			(xy 244.031002 -287.721751) (xy 244.031002 -287.776249) (xy 244.031002 -287.776252) (xy 245.461758 -287.776252)
			(xy 245.461758 -287.721748) (xy 245.469514 -287.667798) (xy 245.48487 -287.615501) (xy 245.507511 -287.565922)
			(xy 245.536978 -287.52007) (xy 245.572671 -287.478878) (xy 245.613862 -287.443184) (xy 245.659713 -287.413716)
			(xy 245.709292 -287.391073) (xy 245.761588 -287.375717) (xy 245.815538 -287.367959) (xy 245.84279 -287.367472)
			(xy 245.871528 -287.368009) (xy 245.928355 -287.37663) (xy 245.983245 -287.393677) (xy 246.034957 -287.418765)
			(xy 246.08232 -287.451327) (xy 246.103648 -287.470596) (xy 246.11076 -287.4772) (xy 246.128286 -287.484312)
			(xy 246.217694 -287.484312) (xy 246.23522 -287.4772) (xy 246.242332 -287.470596) (xy 246.263672 -287.45134)
			(xy 246.311029 -287.41877) (xy 246.362738 -287.393673) (xy 246.417626 -287.37662) (xy 246.474452 -287.367994)
			(xy 246.50319 -287.367472) (xy 246.530442 -287.367975) (xy 246.584391 -287.37573) (xy 246.636687 -287.391084)
			(xy 246.686266 -287.413725) (xy 246.713499 -287.431226) (xy 250.520198 -287.431226) (xy 250.524269 -287.375604)
			(xy 250.536395 -287.321167) (xy 250.556318 -287.269076) (xy 250.583614 -287.220441) (xy 250.6177 -287.176298)
			(xy 250.657849 -287.137589) (xy 250.703207 -287.105138) (xy 250.752807 -287.079637) (xy 250.805591 -287.06163)
			(xy 250.860434 -287.0515) (xy 250.916168 -287.049463) (xy 250.971605 -287.055563) (xy 251.025562 -287.069669)
			(xy 251.076891 -287.091481) (xy 251.124497 -287.120535) (xy 251.167365 -287.15621) (xy 251.204582 -287.197747)
			(xy 251.235355 -287.24426) (xy 251.259027 -287.294757) (xy 251.269823 -287.330642) (xy 252.350268 -287.330642)
			(xy 252.354339 -287.27502) (xy 252.366465 -287.220583) (xy 252.386388 -287.168492) (xy 252.413684 -287.119857)
			(xy 252.44777 -287.075714) (xy 252.487919 -287.037005) (xy 252.533277 -287.004554) (xy 252.582877 -286.979053)
			(xy 252.635661 -286.961046) (xy 252.690504 -286.950916) (xy 252.746238 -286.948879) (xy 252.801675 -286.954979)
			(xy 252.855632 -286.969085) (xy 252.906961 -286.990897) (xy 252.954567 -287.019951) (xy 252.997435 -287.055626)
			(xy 253.034652 -287.097163) (xy 253.065425 -287.143676) (xy 253.089097 -287.194173) (xy 253.105165 -287.24758)
			(xy 253.113285 -287.302756) (xy 253.113794 -287.330642) (xy 253.113285 -287.358528) (xy 253.105165 -287.413704)
			(xy 253.089097 -287.467111) (xy 253.065425 -287.517608) (xy 253.034652 -287.564121) (xy 252.997435 -287.605658)
			(xy 252.954567 -287.641333) (xy 252.906961 -287.670387) (xy 252.855632 -287.692199) (xy 252.801675 -287.706305)
			(xy 252.746238 -287.712405) (xy 252.690504 -287.710368) (xy 252.635661 -287.700238) (xy 252.582877 -287.682231)
			(xy 252.533277 -287.65673) (xy 252.487919 -287.624279) (xy 252.44777 -287.58557) (xy 252.413684 -287.541427)
			(xy 252.386388 -287.492792) (xy 252.366465 -287.440701) (xy 252.354339 -287.386264) (xy 252.350268 -287.330642)
			(xy 251.269823 -287.330642) (xy 251.275095 -287.348164) (xy 251.283215 -287.40334) (xy 251.283724 -287.431226)
			(xy 251.283215 -287.459112) (xy 251.275095 -287.514288) (xy 251.259027 -287.567695) (xy 251.235355 -287.618192)
			(xy 251.204582 -287.664705) (xy 251.167365 -287.706242) (xy 251.124497 -287.741917) (xy 251.076891 -287.770971)
			(xy 251.025562 -287.792783) (xy 250.971605 -287.806889) (xy 250.916168 -287.812989) (xy 250.860434 -287.810952)
			(xy 250.805591 -287.800822) (xy 250.752807 -287.782815) (xy 250.703207 -287.757314) (xy 250.657849 -287.724863)
			(xy 250.6177 -287.686154) (xy 250.583614 -287.642011) (xy 250.556318 -287.593376) (xy 250.536395 -287.541285)
			(xy 250.524269 -287.486848) (xy 250.520198 -287.431226) (xy 246.713499 -287.431226) (xy 246.732118 -287.443191)
			(xy 246.77331 -287.478883) (xy 246.809003 -287.520074) (xy 246.83847 -287.565925) (xy 246.861112 -287.615503)
			(xy 246.876468 -287.667799) (xy 246.884225 -287.721748) (xy 246.884225 -287.776252) (xy 246.876468 -287.830201)
			(xy 246.861112 -287.882497) (xy 246.83847 -287.932075) (xy 246.809003 -287.977926) (xy 246.77331 -288.019117)
			(xy 246.732118 -288.054809) (xy 246.686266 -288.084275) (xy 246.636687 -288.106916) (xy 246.584391 -288.12227)
			(xy 246.530442 -288.130025) (xy 246.50319 -288.130488) (xy 246.474451 -288.129974) (xy 246.417623 -288.121349)
			(xy 246.362732 -288.104297) (xy 246.31102 -288.079203) (xy 246.263658 -288.046636) (xy 246.242332 -288.027364)
			(xy 246.23522 -288.02076) (xy 246.217694 -288.013648) (xy 246.128286 -288.013648) (xy 246.11076 -288.02076)
			(xy 246.103648 -288.027364) (xy 246.082325 -288.04664) (xy 246.034962 -288.079205) (xy 245.983249 -288.104297)
			(xy 245.928358 -288.121346) (xy 245.871529 -288.129968) (xy 245.84279 -288.130488) (xy 245.815538 -288.130041)
			(xy 245.761588 -288.122283) (xy 245.709292 -288.106927) (xy 245.659713 -288.084284) (xy 245.613862 -288.054816)
			(xy 245.572671 -288.019122) (xy 245.536978 -287.97793) (xy 245.507511 -287.932078) (xy 245.48487 -287.882499)
			(xy 245.469514 -287.830202) (xy 245.461758 -287.776252) (xy 244.031002 -287.776252) (xy 244.023246 -287.830194)
			(xy 244.007892 -287.882485) (xy 243.985253 -287.932059) (xy 243.955789 -287.977906) (xy 243.9201 -288.019094)
			(xy 243.878913 -288.054784) (xy 243.833066 -288.084249) (xy 243.783492 -288.106889) (xy 243.731201 -288.122244)
			(xy 243.677257 -288.130001) (xy 243.650008 -288.130488) (xy 243.619884 -288.12993) (xy 243.560386 -288.120448)
			(xy 243.503117 -288.101736) (xy 243.449501 -288.074256) (xy 243.400868 -288.038693) (xy 243.379244 -288.017712)
			(xy 243.372132 -288.010346) (xy 243.353336 -288.002726) (xy 243.26088 -288.002726) (xy 243.242084 -288.010346)
			(xy 243.234972 -288.017712) (xy 243.213341 -288.038685) (xy 243.164713 -288.074254) (xy 243.111098 -288.101735)
			(xy 243.05383 -288.120445) (xy 242.994332 -288.129918) (xy 242.964208 -288.130488) (xy 242.936953 -288.130066)
			(xy 242.882999 -288.122309) (xy 242.830697 -288.106953) (xy 242.781113 -288.08431) (xy 242.735257 -288.05484)
			(xy 242.694061 -288.019145) (xy 242.658364 -287.97795) (xy 242.628894 -287.932094) (xy 242.60625 -287.88251)
			(xy 242.590893 -287.830209) (xy 242.583135 -287.776255) (xy 234.5309 -287.776255) (xy 234.5309 -288.232596)
			(xy 249.695714 -288.232596) (xy 249.699785 -288.176974) (xy 249.711911 -288.122537) (xy 249.731834 -288.070446)
			(xy 249.75913 -288.021811) (xy 249.793216 -287.977668) (xy 249.833365 -287.938959) (xy 249.878723 -287.906508)
			(xy 249.928323 -287.881007) (xy 249.981107 -287.863) (xy 250.03595 -287.85287) (xy 250.091684 -287.850833)
			(xy 250.147121 -287.856933) (xy 250.201078 -287.871039) (xy 250.252407 -287.892851) (xy 250.300013 -287.921905)
			(xy 250.342881 -287.95758) (xy 250.380098 -287.999117) (xy 250.410871 -288.04563) (xy 250.434543 -288.096127)
			(xy 250.445339 -288.132012) (xy 251.525784 -288.132012) (xy 251.529855 -288.07639) (xy 251.541981 -288.021953)
			(xy 251.561904 -287.969862) (xy 251.5892 -287.921227) (xy 251.623286 -287.877084) (xy 251.663435 -287.838375)
			(xy 251.708793 -287.805924) (xy 251.758393 -287.780423) (xy 251.811177 -287.762416) (xy 251.86602 -287.752286)
			(xy 251.921754 -287.750249) (xy 251.977191 -287.756349) (xy 252.031148 -287.770455) (xy 252.082477 -287.792267)
			(xy 252.130083 -287.821321) (xy 252.134415 -287.824926) (xy 268.26897 -287.824926) (xy 268.27293 -287.775872)
			(xy 268.284707 -287.728088) (xy 268.303998 -287.682812) (xy 268.330301 -287.641216) (xy 268.362936 -287.604379)
			(xy 268.401057 -287.573254) (xy 268.443678 -287.548647) (xy 268.489694 -287.531195) (xy 268.537913 -287.521351)
			(xy 268.587088 -287.51937) (xy 268.635943 -287.525302) (xy 268.683214 -287.538994) (xy 268.727676 -287.560092)
			(xy 268.768179 -287.588048) (xy 268.803672 -287.62214) (xy 268.833237 -287.661484) (xy 268.856108 -287.705061)
			(xy 268.871692 -287.751742) (xy 268.879587 -287.800319) (xy 268.880082 -287.824926) (xy 269.21893 -287.824926)
			(xy 269.22289 -287.775872) (xy 269.234667 -287.728088) (xy 269.253958 -287.682812) (xy 269.280261 -287.641216)
			(xy 269.312896 -287.604379) (xy 269.351017 -287.573254) (xy 269.393638 -287.548647) (xy 269.439654 -287.531195)
			(xy 269.487873 -287.521351) (xy 269.537048 -287.51937) (xy 269.585903 -287.525302) (xy 269.633174 -287.538994)
			(xy 269.677636 -287.560092) (xy 269.718139 -287.588048) (xy 269.753632 -287.62214) (xy 269.783197 -287.661484)
			(xy 269.806068 -287.705061) (xy 269.821652 -287.751742) (xy 269.829547 -287.800319) (xy 269.830042 -287.824926)
			(xy 270.169144 -287.824926) (xy 270.173104 -287.775872) (xy 270.184881 -287.728088) (xy 270.204172 -287.682812)
			(xy 270.230475 -287.641216) (xy 270.26311 -287.604379) (xy 270.301231 -287.573254) (xy 270.343852 -287.548647)
			(xy 270.389868 -287.531195) (xy 270.438087 -287.521351) (xy 270.487262 -287.51937) (xy 270.536117 -287.525302)
			(xy 270.583388 -287.538994) (xy 270.62785 -287.560092) (xy 270.668353 -287.588048) (xy 270.703846 -287.62214)
			(xy 270.733411 -287.661484) (xy 270.756282 -287.705061) (xy 270.771866 -287.751742) (xy 270.779761 -287.800319)
			(xy 270.780256 -287.824926) (xy 273.019024 -287.824926) (xy 273.022984 -287.775872) (xy 273.034761 -287.728088)
			(xy 273.054052 -287.682812) (xy 273.080355 -287.641216) (xy 273.11299 -287.604379) (xy 273.151111 -287.573254)
			(xy 273.193732 -287.548647) (xy 273.239748 -287.531195) (xy 273.287967 -287.521351) (xy 273.337142 -287.51937)
			(xy 273.385997 -287.525302) (xy 273.433268 -287.538994) (xy 273.47773 -287.560092) (xy 273.518233 -287.588048)
			(xy 273.553726 -287.62214) (xy 273.583291 -287.661484) (xy 273.606162 -287.705061) (xy 273.621746 -287.751742)
			(xy 273.629641 -287.800319) (xy 273.630136 -287.824926) (xy 276.819118 -287.824926) (xy 276.823078 -287.775872)
			(xy 276.834855 -287.728088) (xy 276.854146 -287.682812) (xy 276.880449 -287.641216) (xy 276.913084 -287.604379)
			(xy 276.951205 -287.573254) (xy 276.993826 -287.548647) (xy 277.039842 -287.531195) (xy 277.088061 -287.521351)
			(xy 277.137236 -287.51937) (xy 277.186091 -287.525302) (xy 277.233362 -287.538994) (xy 277.277824 -287.560092)
			(xy 277.318327 -287.588048) (xy 277.35382 -287.62214) (xy 277.383385 -287.661484) (xy 277.406256 -287.705061)
			(xy 277.42184 -287.751742) (xy 277.429735 -287.800319) (xy 277.43023 -287.824926) (xy 277.769078 -287.824926)
			(xy 277.773038 -287.775872) (xy 277.784815 -287.728088) (xy 277.804106 -287.682812) (xy 277.830409 -287.641216)
			(xy 277.863044 -287.604379) (xy 277.901165 -287.573254) (xy 277.943786 -287.548647) (xy 277.989802 -287.531195)
			(xy 278.038021 -287.521351) (xy 278.087196 -287.51937) (xy 278.136051 -287.525302) (xy 278.183322 -287.538994)
			(xy 278.227784 -287.560092) (xy 278.268287 -287.588048) (xy 278.30378 -287.62214) (xy 278.333345 -287.661484)
			(xy 278.356216 -287.705061) (xy 278.3718 -287.751742) (xy 278.379695 -287.800319) (xy 278.38019 -287.824926)
			(xy 278.719038 -287.824926) (xy 278.722998 -287.775872) (xy 278.734775 -287.728088) (xy 278.754066 -287.682812)
			(xy 278.780369 -287.641216) (xy 278.813004 -287.604379) (xy 278.851125 -287.573254) (xy 278.893746 -287.548647)
			(xy 278.939762 -287.531195) (xy 278.987981 -287.521351) (xy 279.037156 -287.51937) (xy 279.086011 -287.525302)
			(xy 279.133282 -287.538994) (xy 279.177744 -287.560092) (xy 279.218247 -287.588048) (xy 279.25374 -287.62214)
			(xy 279.283305 -287.661484) (xy 279.306176 -287.705061) (xy 279.32176 -287.751742) (xy 279.329655 -287.800319)
			(xy 279.33015 -287.824926) (xy 279.668998 -287.824926) (xy 279.672958 -287.775872) (xy 279.684735 -287.728088)
			(xy 279.704026 -287.682812) (xy 279.730329 -287.641216) (xy 279.762964 -287.604379) (xy 279.801085 -287.573254)
			(xy 279.843706 -287.548647) (xy 279.889722 -287.531195) (xy 279.937941 -287.521351) (xy 279.987116 -287.51937)
			(xy 280.035971 -287.525302) (xy 280.083242 -287.538994) (xy 280.127704 -287.560092) (xy 280.168207 -287.588048)
			(xy 280.2037 -287.62214) (xy 280.233265 -287.661484) (xy 280.256136 -287.705061) (xy 280.27172 -287.751742)
			(xy 280.279615 -287.800319) (xy 280.28011 -287.824926) (xy 280.618958 -287.824926) (xy 280.622918 -287.775872)
			(xy 280.634695 -287.728088) (xy 280.653986 -287.682812) (xy 280.680289 -287.641216) (xy 280.712924 -287.604379)
			(xy 280.751045 -287.573254) (xy 280.793666 -287.548647) (xy 280.839682 -287.531195) (xy 280.887901 -287.521351)
			(xy 280.937076 -287.51937) (xy 280.985931 -287.525302) (xy 281.033202 -287.538994) (xy 281.077664 -287.560092)
			(xy 281.118167 -287.588048) (xy 281.15366 -287.62214) (xy 281.183225 -287.661484) (xy 281.206096 -287.705061)
			(xy 281.22168 -287.751742) (xy 281.229575 -287.800319) (xy 281.23007 -287.824926) (xy 281.568918 -287.824926)
			(xy 281.572878 -287.775872) (xy 281.584655 -287.728088) (xy 281.603946 -287.682812) (xy 281.630249 -287.641216)
			(xy 281.662884 -287.604379) (xy 281.701005 -287.573254) (xy 281.743626 -287.548647) (xy 281.789642 -287.531195)
			(xy 281.837861 -287.521351) (xy 281.887036 -287.51937) (xy 281.935891 -287.525302) (xy 281.983162 -287.538994)
			(xy 282.027624 -287.560092) (xy 282.068127 -287.588048) (xy 282.10362 -287.62214) (xy 282.133185 -287.661484)
			(xy 282.156056 -287.705061) (xy 282.17164 -287.751742) (xy 282.179535 -287.800319) (xy 282.18003 -287.824926)
			(xy 282.519132 -287.824926) (xy 282.523092 -287.775872) (xy 282.534869 -287.728088) (xy 282.55416 -287.682812)
			(xy 282.580463 -287.641216) (xy 282.613098 -287.604379) (xy 282.651219 -287.573254) (xy 282.69384 -287.548647)
			(xy 282.739856 -287.531195) (xy 282.788075 -287.521351) (xy 282.83725 -287.51937) (xy 282.886105 -287.525302)
			(xy 282.933376 -287.538994) (xy 282.977838 -287.560092) (xy 283.018341 -287.588048) (xy 283.053834 -287.62214)
			(xy 283.083399 -287.661484) (xy 283.10627 -287.705061) (xy 283.121854 -287.751742) (xy 283.129749 -287.800319)
			(xy 283.130244 -287.824926) (xy 283.469092 -287.824926) (xy 283.473052 -287.775872) (xy 283.484829 -287.728088)
			(xy 283.50412 -287.682812) (xy 283.530423 -287.641216) (xy 283.563058 -287.604379) (xy 283.601179 -287.573254)
			(xy 283.6438 -287.548647) (xy 283.689816 -287.531195) (xy 283.738035 -287.521351) (xy 283.78721 -287.51937)
			(xy 283.836065 -287.525302) (xy 283.883336 -287.538994) (xy 283.927798 -287.560092) (xy 283.968301 -287.588048)
			(xy 284.003794 -287.62214) (xy 284.033359 -287.661484) (xy 284.05623 -287.705061) (xy 284.071814 -287.751742)
			(xy 284.079709 -287.800319) (xy 284.080204 -287.824926) (xy 284.419052 -287.824926) (xy 284.423012 -287.775872)
			(xy 284.434789 -287.728088) (xy 284.45408 -287.682812) (xy 284.480383 -287.641216) (xy 284.513018 -287.604379)
			(xy 284.551139 -287.573254) (xy 284.59376 -287.548647) (xy 284.639776 -287.531195) (xy 284.687995 -287.521351)
			(xy 284.73717 -287.51937) (xy 284.786025 -287.525302) (xy 284.833296 -287.538994) (xy 284.877758 -287.560092)
			(xy 284.918261 -287.588048) (xy 284.953754 -287.62214) (xy 284.983319 -287.661484) (xy 285.00619 -287.705061)
			(xy 285.021774 -287.751742) (xy 285.029669 -287.800319) (xy 285.030164 -287.824926) (xy 285.369012 -287.824926)
			(xy 285.372972 -287.775872) (xy 285.384749 -287.728088) (xy 285.40404 -287.682812) (xy 285.430343 -287.641216)
			(xy 285.462978 -287.604379) (xy 285.501099 -287.573254) (xy 285.54372 -287.548647) (xy 285.589736 -287.531195)
			(xy 285.637955 -287.521351) (xy 285.68713 -287.51937) (xy 285.735985 -287.525302) (xy 285.783256 -287.538994)
			(xy 285.827718 -287.560092) (xy 285.868221 -287.588048) (xy 285.903714 -287.62214) (xy 285.933279 -287.661484)
			(xy 285.95615 -287.705061) (xy 285.971734 -287.751742) (xy 285.979629 -287.800319) (xy 285.980124 -287.824926)
			(xy 286.318972 -287.824926) (xy 286.322932 -287.775872) (xy 286.334709 -287.728088) (xy 286.354 -287.682812)
			(xy 286.380303 -287.641216) (xy 286.412938 -287.604379) (xy 286.451059 -287.573254) (xy 286.49368 -287.548647)
			(xy 286.539696 -287.531195) (xy 286.587915 -287.521351) (xy 286.63709 -287.51937) (xy 286.685945 -287.525302)
			(xy 286.733216 -287.538994) (xy 286.777678 -287.560092) (xy 286.818181 -287.588048) (xy 286.853674 -287.62214)
			(xy 286.883239 -287.661484) (xy 286.90611 -287.705061) (xy 286.921694 -287.751742) (xy 286.929589 -287.800319)
			(xy 286.930084 -287.824926) (xy 287.268932 -287.824926) (xy 287.272892 -287.775872) (xy 287.284669 -287.728088)
			(xy 287.30396 -287.682812) (xy 287.330263 -287.641216) (xy 287.362898 -287.604379) (xy 287.401019 -287.573254)
			(xy 287.44364 -287.548647) (xy 287.489656 -287.531195) (xy 287.537875 -287.521351) (xy 287.58705 -287.51937)
			(xy 287.635905 -287.525302) (xy 287.683176 -287.538994) (xy 287.727638 -287.560092) (xy 287.768141 -287.588048)
			(xy 287.803634 -287.62214) (xy 287.833199 -287.661484) (xy 287.85607 -287.705061) (xy 287.871654 -287.751742)
			(xy 287.879549 -287.800319) (xy 287.880044 -287.824926) (xy 288.218892 -287.824926) (xy 288.222852 -287.775872)
			(xy 288.234629 -287.728088) (xy 288.25392 -287.682812) (xy 288.280223 -287.641216) (xy 288.312858 -287.604379)
			(xy 288.350979 -287.573254) (xy 288.3936 -287.548647) (xy 288.439616 -287.531195) (xy 288.487835 -287.521351)
			(xy 288.53701 -287.51937) (xy 288.585865 -287.525302) (xy 288.633136 -287.538994) (xy 288.677598 -287.560092)
			(xy 288.718101 -287.588048) (xy 288.753594 -287.62214) (xy 288.783159 -287.661484) (xy 288.80603 -287.705061)
			(xy 288.821614 -287.751742) (xy 288.829509 -287.800319) (xy 288.830004 -287.824926) (xy 289.169106 -287.824926)
			(xy 289.173066 -287.775872) (xy 289.184843 -287.728088) (xy 289.204134 -287.682812) (xy 289.230437 -287.641216)
			(xy 289.263072 -287.604379) (xy 289.301193 -287.573254) (xy 289.343814 -287.548647) (xy 289.38983 -287.531195)
			(xy 289.438049 -287.521351) (xy 289.487224 -287.51937) (xy 289.536079 -287.525302) (xy 289.58335 -287.538994)
			(xy 289.627812 -287.560092) (xy 289.668315 -287.588048) (xy 289.703808 -287.62214) (xy 289.733373 -287.661484)
			(xy 289.753566 -287.699958) (xy 290.143958 -287.699958) (xy 290.147918 -287.650904) (xy 290.159695 -287.60312)
			(xy 290.178986 -287.557844) (xy 290.205289 -287.516248) (xy 290.237924 -287.479411) (xy 290.276045 -287.448286)
			(xy 290.318666 -287.423679) (xy 290.364682 -287.406227) (xy 290.412901 -287.396383) (xy 290.462076 -287.394402)
			(xy 290.510931 -287.400334) (xy 290.558202 -287.414026) (xy 290.602664 -287.435124) (xy 290.643167 -287.46308)
			(xy 290.67866 -287.497172) (xy 290.708225 -287.536516) (xy 290.731096 -287.580093) (xy 290.74668 -287.626774)
			(xy 290.754575 -287.675351) (xy 290.75507 -287.699958) (xy 290.754575 -287.724565) (xy 290.74668 -287.773142)
			(xy 290.731096 -287.819823) (xy 290.708225 -287.8634) (xy 290.68083 -287.899856) (xy 292.018986 -287.899856)
			(xy 292.022946 -287.850802) (xy 292.034723 -287.803018) (xy 292.054014 -287.757742) (xy 292.080317 -287.716146)
			(xy 292.112952 -287.679309) (xy 292.151073 -287.648184) (xy 292.193694 -287.623577) (xy 292.23971 -287.606125)
			(xy 292.287929 -287.596281) (xy 292.337104 -287.5943) (xy 292.385959 -287.600232) (xy 292.43323 -287.613924)
			(xy 292.477692 -287.635022) (xy 292.518195 -287.662978) (xy 292.553688 -287.69707) (xy 292.583253 -287.736414)
			(xy 292.606124 -287.779991) (xy 292.621125 -287.824926) (xy 292.968946 -287.824926) (xy 292.972906 -287.775872)
			(xy 292.984683 -287.728088) (xy 293.003974 -287.682812) (xy 293.030277 -287.641216) (xy 293.062912 -287.604379)
			(xy 293.101033 -287.573254) (xy 293.143654 -287.548647) (xy 293.18967 -287.531195) (xy 293.237889 -287.521351)
			(xy 293.287064 -287.51937) (xy 293.335919 -287.525302) (xy 293.38319 -287.538994) (xy 293.427652 -287.560092)
			(xy 293.468155 -287.588048) (xy 293.503648 -287.62214) (xy 293.533213 -287.661484) (xy 293.556084 -287.705061)
			(xy 293.571668 -287.751742) (xy 293.579563 -287.800319) (xy 293.580058 -287.824926) (xy 293.918906 -287.824926)
			(xy 293.922866 -287.775872) (xy 293.934643 -287.728088) (xy 293.953934 -287.682812) (xy 293.980237 -287.641216)
			(xy 294.012872 -287.604379) (xy 294.050993 -287.573254) (xy 294.093614 -287.548647) (xy 294.13963 -287.531195)
			(xy 294.187849 -287.521351) (xy 294.237024 -287.51937) (xy 294.285879 -287.525302) (xy 294.33315 -287.538994)
			(xy 294.377612 -287.560092) (xy 294.418115 -287.588048) (xy 294.453608 -287.62214) (xy 294.483173 -287.661484)
			(xy 294.506044 -287.705061) (xy 294.521628 -287.751742) (xy 294.529523 -287.800319) (xy 294.530018 -287.824926)
			(xy 294.86912 -287.824926) (xy 294.87308 -287.775872) (xy 294.884857 -287.728088) (xy 294.904148 -287.682812)
			(xy 294.930451 -287.641216) (xy 294.963086 -287.604379) (xy 295.001207 -287.573254) (xy 295.043828 -287.548647)
			(xy 295.089844 -287.531195) (xy 295.138063 -287.521351) (xy 295.187238 -287.51937) (xy 295.236093 -287.525302)
			(xy 295.283364 -287.538994) (xy 295.327826 -287.560092) (xy 295.368329 -287.588048) (xy 295.403822 -287.62214)
			(xy 295.433387 -287.661484) (xy 295.456258 -287.705061) (xy 295.471842 -287.751742) (xy 295.479737 -287.800319)
			(xy 295.480232 -287.824926) (xy 295.81908 -287.824926) (xy 295.82304 -287.775872) (xy 295.834817 -287.728088)
			(xy 295.854108 -287.682812) (xy 295.880411 -287.641216) (xy 295.913046 -287.604379) (xy 295.951167 -287.573254)
			(xy 295.993788 -287.548647) (xy 296.039804 -287.531195) (xy 296.088023 -287.521351) (xy 296.137198 -287.51937)
			(xy 296.186053 -287.525302) (xy 296.233324 -287.538994) (xy 296.277786 -287.560092) (xy 296.318289 -287.588048)
			(xy 296.353782 -287.62214) (xy 296.383347 -287.661484) (xy 296.406218 -287.705061) (xy 296.421802 -287.751742)
			(xy 296.429697 -287.800319) (xy 296.430192 -287.824926) (xy 296.76904 -287.824926) (xy 296.773 -287.775872)
			(xy 296.784777 -287.728088) (xy 296.804068 -287.682812) (xy 296.830371 -287.641216) (xy 296.863006 -287.604379)
			(xy 296.901127 -287.573254) (xy 296.943748 -287.548647) (xy 296.989764 -287.531195) (xy 297.037983 -287.521351)
			(xy 297.087158 -287.51937) (xy 297.136013 -287.525302) (xy 297.183284 -287.538994) (xy 297.227746 -287.560092)
			(xy 297.268249 -287.588048) (xy 297.303742 -287.62214) (xy 297.333307 -287.661484) (xy 297.356178 -287.705061)
			(xy 297.371762 -287.751742) (xy 297.379657 -287.800319) (xy 297.380152 -287.824926) (xy 297.719 -287.824926)
			(xy 297.72296 -287.775872) (xy 297.734737 -287.728088) (xy 297.754028 -287.682812) (xy 297.780331 -287.641216)
			(xy 297.812966 -287.604379) (xy 297.851087 -287.573254) (xy 297.893708 -287.548647) (xy 297.939724 -287.531195)
			(xy 297.987943 -287.521351) (xy 298.037118 -287.51937) (xy 298.085973 -287.525302) (xy 298.133244 -287.538994)
			(xy 298.177706 -287.560092) (xy 298.218209 -287.588048) (xy 298.253702 -287.62214) (xy 298.283267 -287.661484)
			(xy 298.306138 -287.705061) (xy 298.321722 -287.751742) (xy 298.329617 -287.800319) (xy 298.330112 -287.824926)
			(xy 298.66896 -287.824926) (xy 298.67292 -287.775872) (xy 298.684697 -287.728088) (xy 298.703988 -287.682812)
			(xy 298.730291 -287.641216) (xy 298.762926 -287.604379) (xy 298.801047 -287.573254) (xy 298.843668 -287.548647)
			(xy 298.889684 -287.531195) (xy 298.937903 -287.521351) (xy 298.987078 -287.51937) (xy 299.035933 -287.525302)
			(xy 299.083204 -287.538994) (xy 299.127666 -287.560092) (xy 299.168169 -287.588048) (xy 299.203662 -287.62214)
			(xy 299.233227 -287.661484) (xy 299.256098 -287.705061) (xy 299.271682 -287.751742) (xy 299.279577 -287.800319)
			(xy 299.280072 -287.824926) (xy 299.61892 -287.824926) (xy 299.62288 -287.775872) (xy 299.634657 -287.728088)
			(xy 299.653948 -287.682812) (xy 299.680251 -287.641216) (xy 299.712886 -287.604379) (xy 299.751007 -287.573254)
			(xy 299.793628 -287.548647) (xy 299.839644 -287.531195) (xy 299.887863 -287.521351) (xy 299.937038 -287.51937)
			(xy 299.985893 -287.525302) (xy 300.033164 -287.538994) (xy 300.077626 -287.560092) (xy 300.118129 -287.588048)
			(xy 300.153622 -287.62214) (xy 300.183187 -287.661484) (xy 300.206058 -287.705061) (xy 300.221642 -287.751742)
			(xy 300.229537 -287.800319) (xy 300.230032 -287.824926) (xy 300.56888 -287.824926) (xy 300.57284 -287.775872)
			(xy 300.584617 -287.728088) (xy 300.603908 -287.682812) (xy 300.630211 -287.641216) (xy 300.662846 -287.604379)
			(xy 300.700967 -287.573254) (xy 300.743588 -287.548647) (xy 300.789604 -287.531195) (xy 300.837823 -287.521351)
			(xy 300.886998 -287.51937) (xy 300.935853 -287.525302) (xy 300.983124 -287.538994) (xy 301.027586 -287.560092)
			(xy 301.068089 -287.588048) (xy 301.103582 -287.62214) (xy 301.133147 -287.661484) (xy 301.156018 -287.705061)
			(xy 301.171602 -287.751742) (xy 301.179497 -287.800319) (xy 301.179992 -287.824926) (xy 302.469054 -287.824926)
			(xy 302.473014 -287.775872) (xy 302.484791 -287.728088) (xy 302.504082 -287.682812) (xy 302.530385 -287.641216)
			(xy 302.56302 -287.604379) (xy 302.601141 -287.573254) (xy 302.643762 -287.548647) (xy 302.689778 -287.531195)
			(xy 302.737997 -287.521351) (xy 302.787172 -287.51937) (xy 302.836027 -287.525302) (xy 302.883298 -287.538994)
			(xy 302.92776 -287.560092) (xy 302.968263 -287.588048) (xy 303.003756 -287.62214) (xy 303.033321 -287.661484)
			(xy 303.056192 -287.705061) (xy 303.071776 -287.751742) (xy 303.079671 -287.800319) (xy 303.080166 -287.824926)
			(xy 303.079671 -287.849533) (xy 303.071776 -287.89811) (xy 303.056192 -287.944791) (xy 303.033321 -287.988368)
			(xy 303.003756 -288.027712) (xy 302.968263 -288.061804) (xy 302.92776 -288.08976) (xy 302.883298 -288.110858)
			(xy 302.836027 -288.12455) (xy 302.787172 -288.130482) (xy 302.737997 -288.128501) (xy 302.689778 -288.118657)
			(xy 302.643762 -288.101205) (xy 302.601141 -288.076598) (xy 302.56302 -288.045473) (xy 302.530385 -288.008636)
			(xy 302.504082 -287.96704) (xy 302.484791 -287.921764) (xy 302.473014 -287.87398) (xy 302.469054 -287.824926)
			(xy 301.179992 -287.824926) (xy 301.179497 -287.849533) (xy 301.171602 -287.89811) (xy 301.156018 -287.944791)
			(xy 301.133147 -287.988368) (xy 301.103582 -288.027712) (xy 301.068089 -288.061804) (xy 301.027586 -288.08976)
			(xy 300.983124 -288.110858) (xy 300.935853 -288.12455) (xy 300.886998 -288.130482) (xy 300.837823 -288.128501)
			(xy 300.789604 -288.118657) (xy 300.743588 -288.101205) (xy 300.700967 -288.076598) (xy 300.662846 -288.045473)
			(xy 300.630211 -288.008636) (xy 300.603908 -287.96704) (xy 300.584617 -287.921764) (xy 300.57284 -287.87398)
			(xy 300.56888 -287.824926) (xy 300.230032 -287.824926) (xy 300.229537 -287.849533) (xy 300.221642 -287.89811)
			(xy 300.206058 -287.944791) (xy 300.183187 -287.988368) (xy 300.153622 -288.027712) (xy 300.118129 -288.061804)
			(xy 300.077626 -288.08976) (xy 300.033164 -288.110858) (xy 299.985893 -288.12455) (xy 299.937038 -288.130482)
			(xy 299.887863 -288.128501) (xy 299.839644 -288.118657) (xy 299.793628 -288.101205) (xy 299.751007 -288.076598)
			(xy 299.712886 -288.045473) (xy 299.680251 -288.008636) (xy 299.653948 -287.96704) (xy 299.634657 -287.921764)
			(xy 299.62288 -287.87398) (xy 299.61892 -287.824926) (xy 299.280072 -287.824926) (xy 299.279577 -287.849533)
			(xy 299.271682 -287.89811) (xy 299.256098 -287.944791) (xy 299.233227 -287.988368) (xy 299.203662 -288.027712)
			(xy 299.168169 -288.061804) (xy 299.127666 -288.08976) (xy 299.083204 -288.110858) (xy 299.035933 -288.12455)
			(xy 298.987078 -288.130482) (xy 298.937903 -288.128501) (xy 298.889684 -288.118657) (xy 298.843668 -288.101205)
			(xy 298.801047 -288.076598) (xy 298.762926 -288.045473) (xy 298.730291 -288.008636) (xy 298.703988 -287.96704)
			(xy 298.684697 -287.921764) (xy 298.67292 -287.87398) (xy 298.66896 -287.824926) (xy 298.330112 -287.824926)
			(xy 298.329617 -287.849533) (xy 298.321722 -287.89811) (xy 298.306138 -287.944791) (xy 298.283267 -287.988368)
			(xy 298.253702 -288.027712) (xy 298.218209 -288.061804) (xy 298.177706 -288.08976) (xy 298.133244 -288.110858)
			(xy 298.085973 -288.12455) (xy 298.037118 -288.130482) (xy 297.987943 -288.128501) (xy 297.939724 -288.118657)
			(xy 297.893708 -288.101205) (xy 297.851087 -288.076598) (xy 297.812966 -288.045473) (xy 297.780331 -288.008636)
			(xy 297.754028 -287.96704) (xy 297.734737 -287.921764) (xy 297.72296 -287.87398) (xy 297.719 -287.824926)
			(xy 297.380152 -287.824926) (xy 297.379657 -287.849533) (xy 297.371762 -287.89811) (xy 297.356178 -287.944791)
			(xy 297.333307 -287.988368) (xy 297.303742 -288.027712) (xy 297.268249 -288.061804) (xy 297.227746 -288.08976)
			(xy 297.183284 -288.110858) (xy 297.136013 -288.12455) (xy 297.087158 -288.130482) (xy 297.037983 -288.128501)
			(xy 296.989764 -288.118657) (xy 296.943748 -288.101205) (xy 296.901127 -288.076598) (xy 296.863006 -288.045473)
			(xy 296.830371 -288.008636) (xy 296.804068 -287.96704) (xy 296.784777 -287.921764) (xy 296.773 -287.87398)
			(xy 296.76904 -287.824926) (xy 296.430192 -287.824926) (xy 296.429697 -287.849533) (xy 296.421802 -287.89811)
			(xy 296.406218 -287.944791) (xy 296.383347 -287.988368) (xy 296.353782 -288.027712) (xy 296.318289 -288.061804)
			(xy 296.277786 -288.08976) (xy 296.233324 -288.110858) (xy 296.186053 -288.12455) (xy 296.137198 -288.130482)
			(xy 296.088023 -288.128501) (xy 296.039804 -288.118657) (xy 295.993788 -288.101205) (xy 295.951167 -288.076598)
			(xy 295.913046 -288.045473) (xy 295.880411 -288.008636) (xy 295.854108 -287.96704) (xy 295.834817 -287.921764)
			(xy 295.82304 -287.87398) (xy 295.81908 -287.824926) (xy 295.480232 -287.824926) (xy 295.479737 -287.849533)
			(xy 295.471842 -287.89811) (xy 295.456258 -287.944791) (xy 295.433387 -287.988368) (xy 295.403822 -288.027712)
			(xy 295.368329 -288.061804) (xy 295.327826 -288.08976) (xy 295.283364 -288.110858) (xy 295.236093 -288.12455)
			(xy 295.187238 -288.130482) (xy 295.138063 -288.128501) (xy 295.089844 -288.118657) (xy 295.043828 -288.101205)
			(xy 295.001207 -288.076598) (xy 294.963086 -288.045473) (xy 294.930451 -288.008636) (xy 294.904148 -287.96704)
			(xy 294.884857 -287.921764) (xy 294.87308 -287.87398) (xy 294.86912 -287.824926) (xy 294.530018 -287.824926)
			(xy 294.529523 -287.849533) (xy 294.521628 -287.89811) (xy 294.506044 -287.944791) (xy 294.483173 -287.988368)
			(xy 294.453608 -288.027712) (xy 294.418115 -288.061804) (xy 294.377612 -288.08976) (xy 294.33315 -288.110858)
			(xy 294.285879 -288.12455) (xy 294.237024 -288.130482) (xy 294.187849 -288.128501) (xy 294.13963 -288.118657)
			(xy 294.093614 -288.101205) (xy 294.050993 -288.076598) (xy 294.012872 -288.045473) (xy 293.980237 -288.008636)
			(xy 293.953934 -287.96704) (xy 293.934643 -287.921764) (xy 293.922866 -287.87398) (xy 293.918906 -287.824926)
			(xy 293.580058 -287.824926) (xy 293.579563 -287.849533) (xy 293.571668 -287.89811) (xy 293.556084 -287.944791)
			(xy 293.533213 -287.988368) (xy 293.503648 -288.027712) (xy 293.468155 -288.061804) (xy 293.427652 -288.08976)
			(xy 293.38319 -288.110858) (xy 293.335919 -288.12455) (xy 293.287064 -288.130482) (xy 293.237889 -288.128501)
			(xy 293.18967 -288.118657) (xy 293.143654 -288.101205) (xy 293.101033 -288.076598) (xy 293.062912 -288.045473)
			(xy 293.030277 -288.008636) (xy 293.003974 -287.96704) (xy 292.984683 -287.921764) (xy 292.972906 -287.87398)
			(xy 292.968946 -287.824926) (xy 292.621125 -287.824926) (xy 292.621708 -287.826672) (xy 292.629603 -287.875249)
			(xy 292.630098 -287.899856) (xy 292.629603 -287.924463) (xy 292.621708 -287.97304) (xy 292.606124 -288.019721)
			(xy 292.583253 -288.063298) (xy 292.553688 -288.102642) (xy 292.518195 -288.136734) (xy 292.477692 -288.16469)
			(xy 292.43323 -288.185788) (xy 292.385959 -288.19948) (xy 292.337104 -288.205412) (xy 292.287929 -288.203431)
			(xy 292.23971 -288.193587) (xy 292.193694 -288.176135) (xy 292.151073 -288.151528) (xy 292.112952 -288.120403)
			(xy 292.080317 -288.083566) (xy 292.054014 -288.04197) (xy 292.034723 -287.996694) (xy 292.022946 -287.94891)
			(xy 292.018986 -287.899856) (xy 290.68083 -287.899856) (xy 290.67866 -287.902744) (xy 290.643167 -287.936836)
			(xy 290.602664 -287.964792) (xy 290.558202 -287.98589) (xy 290.510931 -287.999582) (xy 290.462076 -288.005514)
			(xy 290.412901 -288.003533) (xy 290.364682 -287.993689) (xy 290.318666 -287.976237) (xy 290.276045 -287.95163)
			(xy 290.237924 -287.920505) (xy 290.205289 -287.883668) (xy 290.178986 -287.842072) (xy 290.159695 -287.796796)
			(xy 290.147918 -287.749012) (xy 290.143958 -287.699958) (xy 289.753566 -287.699958) (xy 289.756244 -287.705061)
			(xy 289.771828 -287.751742) (xy 289.779723 -287.800319) (xy 289.780218 -287.824926) (xy 289.779723 -287.849533)
			(xy 289.771828 -287.89811) (xy 289.756244 -287.944791) (xy 289.733373 -287.988368) (xy 289.703808 -288.027712)
			(xy 289.668315 -288.061804) (xy 289.627812 -288.08976) (xy 289.58335 -288.110858) (xy 289.536079 -288.12455)
			(xy 289.487224 -288.130482) (xy 289.438049 -288.128501) (xy 289.38983 -288.118657) (xy 289.343814 -288.101205)
			(xy 289.301193 -288.076598) (xy 289.263072 -288.045473) (xy 289.230437 -288.008636) (xy 289.204134 -287.96704)
			(xy 289.184843 -287.921764) (xy 289.173066 -287.87398) (xy 289.169106 -287.824926) (xy 288.830004 -287.824926)
			(xy 288.829509 -287.849533) (xy 288.821614 -287.89811) (xy 288.80603 -287.944791) (xy 288.783159 -287.988368)
			(xy 288.753594 -288.027712) (xy 288.718101 -288.061804) (xy 288.677598 -288.08976) (xy 288.633136 -288.110858)
			(xy 288.585865 -288.12455) (xy 288.53701 -288.130482) (xy 288.487835 -288.128501) (xy 288.439616 -288.118657)
			(xy 288.3936 -288.101205) (xy 288.350979 -288.076598) (xy 288.312858 -288.045473) (xy 288.280223 -288.008636)
			(xy 288.25392 -287.96704) (xy 288.234629 -287.921764) (xy 288.222852 -287.87398) (xy 288.218892 -287.824926)
			(xy 287.880044 -287.824926) (xy 287.879549 -287.849533) (xy 287.871654 -287.89811) (xy 287.85607 -287.944791)
			(xy 287.833199 -287.988368) (xy 287.803634 -288.027712) (xy 287.768141 -288.061804) (xy 287.727638 -288.08976)
			(xy 287.683176 -288.110858) (xy 287.635905 -288.12455) (xy 287.58705 -288.130482) (xy 287.537875 -288.128501)
			(xy 287.489656 -288.118657) (xy 287.44364 -288.101205) (xy 287.401019 -288.076598) (xy 287.362898 -288.045473)
			(xy 287.330263 -288.008636) (xy 287.30396 -287.96704) (xy 287.284669 -287.921764) (xy 287.272892 -287.87398)
			(xy 287.268932 -287.824926) (xy 286.930084 -287.824926) (xy 286.929589 -287.849533) (xy 286.921694 -287.89811)
			(xy 286.90611 -287.944791) (xy 286.883239 -287.988368) (xy 286.853674 -288.027712) (xy 286.818181 -288.061804)
			(xy 286.777678 -288.08976) (xy 286.733216 -288.110858) (xy 286.685945 -288.12455) (xy 286.63709 -288.130482)
			(xy 286.587915 -288.128501) (xy 286.539696 -288.118657) (xy 286.49368 -288.101205) (xy 286.451059 -288.076598)
			(xy 286.412938 -288.045473) (xy 286.380303 -288.008636) (xy 286.354 -287.96704) (xy 286.334709 -287.921764)
			(xy 286.322932 -287.87398) (xy 286.318972 -287.824926) (xy 285.980124 -287.824926) (xy 285.979629 -287.849533)
			(xy 285.971734 -287.89811) (xy 285.95615 -287.944791) (xy 285.933279 -287.988368) (xy 285.903714 -288.027712)
			(xy 285.868221 -288.061804) (xy 285.827718 -288.08976) (xy 285.783256 -288.110858) (xy 285.735985 -288.12455)
			(xy 285.68713 -288.130482) (xy 285.637955 -288.128501) (xy 285.589736 -288.118657) (xy 285.54372 -288.101205)
			(xy 285.501099 -288.076598) (xy 285.462978 -288.045473) (xy 285.430343 -288.008636) (xy 285.40404 -287.96704)
			(xy 285.384749 -287.921764) (xy 285.372972 -287.87398) (xy 285.369012 -287.824926) (xy 285.030164 -287.824926)
			(xy 285.029669 -287.849533) (xy 285.021774 -287.89811) (xy 285.00619 -287.944791) (xy 284.983319 -287.988368)
			(xy 284.953754 -288.027712) (xy 284.918261 -288.061804) (xy 284.877758 -288.08976) (xy 284.833296 -288.110858)
			(xy 284.786025 -288.12455) (xy 284.73717 -288.130482) (xy 284.687995 -288.128501) (xy 284.639776 -288.118657)
			(xy 284.59376 -288.101205) (xy 284.551139 -288.076598) (xy 284.513018 -288.045473) (xy 284.480383 -288.008636)
			(xy 284.45408 -287.96704) (xy 284.434789 -287.921764) (xy 284.423012 -287.87398) (xy 284.419052 -287.824926)
			(xy 284.080204 -287.824926) (xy 284.079709 -287.849533) (xy 284.071814 -287.89811) (xy 284.05623 -287.944791)
			(xy 284.033359 -287.988368) (xy 284.003794 -288.027712) (xy 283.968301 -288.061804) (xy 283.927798 -288.08976)
			(xy 283.883336 -288.110858) (xy 283.836065 -288.12455) (xy 283.78721 -288.130482) (xy 283.738035 -288.128501)
			(xy 283.689816 -288.118657) (xy 283.6438 -288.101205) (xy 283.601179 -288.076598) (xy 283.563058 -288.045473)
			(xy 283.530423 -288.008636) (xy 283.50412 -287.96704) (xy 283.484829 -287.921764) (xy 283.473052 -287.87398)
			(xy 283.469092 -287.824926) (xy 283.130244 -287.824926) (xy 283.129749 -287.849533) (xy 283.121854 -287.89811)
			(xy 283.10627 -287.944791) (xy 283.083399 -287.988368) (xy 283.053834 -288.027712) (xy 283.018341 -288.061804)
			(xy 282.977838 -288.08976) (xy 282.933376 -288.110858) (xy 282.886105 -288.12455) (xy 282.83725 -288.130482)
			(xy 282.788075 -288.128501) (xy 282.739856 -288.118657) (xy 282.69384 -288.101205) (xy 282.651219 -288.076598)
			(xy 282.613098 -288.045473) (xy 282.580463 -288.008636) (xy 282.55416 -287.96704) (xy 282.534869 -287.921764)
			(xy 282.523092 -287.87398) (xy 282.519132 -287.824926) (xy 282.18003 -287.824926) (xy 282.179535 -287.849533)
			(xy 282.17164 -287.89811) (xy 282.156056 -287.944791) (xy 282.133185 -287.988368) (xy 282.10362 -288.027712)
			(xy 282.068127 -288.061804) (xy 282.027624 -288.08976) (xy 281.983162 -288.110858) (xy 281.935891 -288.12455)
			(xy 281.887036 -288.130482) (xy 281.837861 -288.128501) (xy 281.789642 -288.118657) (xy 281.743626 -288.101205)
			(xy 281.701005 -288.076598) (xy 281.662884 -288.045473) (xy 281.630249 -288.008636) (xy 281.603946 -287.96704)
			(xy 281.584655 -287.921764) (xy 281.572878 -287.87398) (xy 281.568918 -287.824926) (xy 281.23007 -287.824926)
			(xy 281.229575 -287.849533) (xy 281.22168 -287.89811) (xy 281.206096 -287.944791) (xy 281.183225 -287.988368)
			(xy 281.15366 -288.027712) (xy 281.118167 -288.061804) (xy 281.077664 -288.08976) (xy 281.033202 -288.110858)
			(xy 280.985931 -288.12455) (xy 280.937076 -288.130482) (xy 280.887901 -288.128501) (xy 280.839682 -288.118657)
			(xy 280.793666 -288.101205) (xy 280.751045 -288.076598) (xy 280.712924 -288.045473) (xy 280.680289 -288.008636)
			(xy 280.653986 -287.96704) (xy 280.634695 -287.921764) (xy 280.622918 -287.87398) (xy 280.618958 -287.824926)
			(xy 280.28011 -287.824926) (xy 280.279615 -287.849533) (xy 280.27172 -287.89811) (xy 280.256136 -287.944791)
			(xy 280.233265 -287.988368) (xy 280.2037 -288.027712) (xy 280.168207 -288.061804) (xy 280.127704 -288.08976)
			(xy 280.083242 -288.110858) (xy 280.035971 -288.12455) (xy 279.987116 -288.130482) (xy 279.937941 -288.128501)
			(xy 279.889722 -288.118657) (xy 279.843706 -288.101205) (xy 279.801085 -288.076598) (xy 279.762964 -288.045473)
			(xy 279.730329 -288.008636) (xy 279.704026 -287.96704) (xy 279.684735 -287.921764) (xy 279.672958 -287.87398)
			(xy 279.668998 -287.824926) (xy 279.33015 -287.824926) (xy 279.329655 -287.849533) (xy 279.32176 -287.89811)
			(xy 279.306176 -287.944791) (xy 279.283305 -287.988368) (xy 279.25374 -288.027712) (xy 279.218247 -288.061804)
			(xy 279.177744 -288.08976) (xy 279.133282 -288.110858) (xy 279.086011 -288.12455) (xy 279.037156 -288.130482)
			(xy 278.987981 -288.128501) (xy 278.939762 -288.118657) (xy 278.893746 -288.101205) (xy 278.851125 -288.076598)
			(xy 278.813004 -288.045473) (xy 278.780369 -288.008636) (xy 278.754066 -287.96704) (xy 278.734775 -287.921764)
			(xy 278.722998 -287.87398) (xy 278.719038 -287.824926) (xy 278.38019 -287.824926) (xy 278.379695 -287.849533)
			(xy 278.3718 -287.89811) (xy 278.356216 -287.944791) (xy 278.333345 -287.988368) (xy 278.30378 -288.027712)
			(xy 278.268287 -288.061804) (xy 278.227784 -288.08976) (xy 278.183322 -288.110858) (xy 278.136051 -288.12455)
			(xy 278.087196 -288.130482) (xy 278.038021 -288.128501) (xy 277.989802 -288.118657) (xy 277.943786 -288.101205)
			(xy 277.901165 -288.076598) (xy 277.863044 -288.045473) (xy 277.830409 -288.008636) (xy 277.804106 -287.96704)
			(xy 277.784815 -287.921764) (xy 277.773038 -287.87398) (xy 277.769078 -287.824926) (xy 277.43023 -287.824926)
			(xy 277.429735 -287.849533) (xy 277.42184 -287.89811) (xy 277.406256 -287.944791) (xy 277.383385 -287.988368)
			(xy 277.35382 -288.027712) (xy 277.318327 -288.061804) (xy 277.277824 -288.08976) (xy 277.233362 -288.110858)
			(xy 277.186091 -288.12455) (xy 277.137236 -288.130482) (xy 277.088061 -288.128501) (xy 277.039842 -288.118657)
			(xy 276.993826 -288.101205) (xy 276.951205 -288.076598) (xy 276.913084 -288.045473) (xy 276.880449 -288.008636)
			(xy 276.854146 -287.96704) (xy 276.834855 -287.921764) (xy 276.823078 -287.87398) (xy 276.819118 -287.824926)
			(xy 273.630136 -287.824926) (xy 273.629641 -287.849533) (xy 273.621746 -287.89811) (xy 273.606162 -287.944791)
			(xy 273.583291 -287.988368) (xy 273.553726 -288.027712) (xy 273.518233 -288.061804) (xy 273.47773 -288.08976)
			(xy 273.433268 -288.110858) (xy 273.385997 -288.12455) (xy 273.337142 -288.130482) (xy 273.287967 -288.128501)
			(xy 273.239748 -288.118657) (xy 273.193732 -288.101205) (xy 273.151111 -288.076598) (xy 273.11299 -288.045473)
			(xy 273.080355 -288.008636) (xy 273.054052 -287.96704) (xy 273.034761 -287.921764) (xy 273.022984 -287.87398)
			(xy 273.019024 -287.824926) (xy 270.780256 -287.824926) (xy 270.779761 -287.849533) (xy 270.771866 -287.89811)
			(xy 270.756282 -287.944791) (xy 270.733411 -287.988368) (xy 270.703846 -288.027712) (xy 270.668353 -288.061804)
			(xy 270.62785 -288.08976) (xy 270.583388 -288.110858) (xy 270.536117 -288.12455) (xy 270.487262 -288.130482)
			(xy 270.438087 -288.128501) (xy 270.389868 -288.118657) (xy 270.343852 -288.101205) (xy 270.301231 -288.076598)
			(xy 270.26311 -288.045473) (xy 270.230475 -288.008636) (xy 270.204172 -287.96704) (xy 270.184881 -287.921764)
			(xy 270.173104 -287.87398) (xy 270.169144 -287.824926) (xy 269.830042 -287.824926) (xy 269.829547 -287.849533)
			(xy 269.821652 -287.89811) (xy 269.806068 -287.944791) (xy 269.783197 -287.988368) (xy 269.753632 -288.027712)
			(xy 269.718139 -288.061804) (xy 269.677636 -288.08976) (xy 269.633174 -288.110858) (xy 269.585903 -288.12455)
			(xy 269.537048 -288.130482) (xy 269.487873 -288.128501) (xy 269.439654 -288.118657) (xy 269.393638 -288.101205)
			(xy 269.351017 -288.076598) (xy 269.312896 -288.045473) (xy 269.280261 -288.008636) (xy 269.253958 -287.96704)
			(xy 269.234667 -287.921764) (xy 269.22289 -287.87398) (xy 269.21893 -287.824926) (xy 268.880082 -287.824926)
			(xy 268.879587 -287.849533) (xy 268.871692 -287.89811) (xy 268.856108 -287.944791) (xy 268.833237 -287.988368)
			(xy 268.803672 -288.027712) (xy 268.768179 -288.061804) (xy 268.727676 -288.08976) (xy 268.683214 -288.110858)
			(xy 268.635943 -288.12455) (xy 268.587088 -288.130482) (xy 268.537913 -288.128501) (xy 268.489694 -288.118657)
			(xy 268.443678 -288.101205) (xy 268.401057 -288.076598) (xy 268.362936 -288.045473) (xy 268.330301 -288.008636)
			(xy 268.303998 -287.96704) (xy 268.284707 -287.921764) (xy 268.27293 -287.87398) (xy 268.26897 -287.824926)
			(xy 252.134415 -287.824926) (xy 252.172951 -287.856996) (xy 252.210168 -287.898533) (xy 252.240941 -287.945046)
			(xy 252.264613 -287.995543) (xy 252.280681 -288.04895) (xy 252.288801 -288.104126) (xy 252.28931 -288.132012)
			(xy 252.288801 -288.159898) (xy 252.280681 -288.215074) (xy 252.276174 -288.230056) (xy 258.01142 -288.230056)
			(xy 258.015491 -288.174434) (xy 258.027617 -288.119997) (xy 258.04754 -288.067906) (xy 258.074836 -288.019271)
			(xy 258.108922 -287.975128) (xy 258.149071 -287.936419) (xy 258.194429 -287.903968) (xy 258.244029 -287.878467)
			(xy 258.296813 -287.86046) (xy 258.351656 -287.85033) (xy 258.40739 -287.848293) (xy 258.462827 -287.854393)
			(xy 258.516784 -287.868499) (xy 258.568113 -287.890311) (xy 258.615719 -287.919365) (xy 258.658587 -287.95504)
			(xy 258.695804 -287.996577) (xy 258.726577 -288.04309) (xy 258.750249 -288.093587) (xy 258.766317 -288.146994)
			(xy 258.774437 -288.20217) (xy 258.774946 -288.230056) (xy 259.496558 -288.230056) (xy 259.500629 -288.174434)
			(xy 259.512755 -288.119997) (xy 259.532678 -288.067906) (xy 259.559974 -288.019271) (xy 259.59406 -287.975128)
			(xy 259.634209 -287.936419) (xy 259.679567 -287.903968) (xy 259.729167 -287.878467) (xy 259.781951 -287.86046)
			(xy 259.836794 -287.85033) (xy 259.892528 -287.848293) (xy 259.947965 -287.854393) (xy 260.001922 -287.868499)
			(xy 260.053251 -287.890311) (xy 260.100857 -287.919365) (xy 260.143725 -287.95504) (xy 260.180942 -287.996577)
			(xy 260.211715 -288.04309) (xy 260.235387 -288.093587) (xy 260.251455 -288.146994) (xy 260.259575 -288.20217)
			(xy 260.260084 -288.230056) (xy 260.259575 -288.257942) (xy 260.25218 -288.308192) (xy 305.793963 -288.308192)
			(xy 305.79665 -288.25862) (xy 305.80732 -288.210135) (xy 305.825695 -288.164015) (xy 305.851289 -288.121475)
			(xy 305.883428 -288.083636) (xy 305.921265 -288.051496) (xy 305.963804 -288.0259) (xy 306.009923 -288.007524)
			(xy 306.058408 -287.996851) (xy 306.10798 -287.994163) (xy 306.157335 -287.99953) (xy 306.205171 -288.012812)
			(xy 306.250228 -288.033658) (xy 306.291319 -288.061518) (xy 306.327361 -288.095659) (xy 306.357405 -288.135182)
			(xy 306.380658 -288.179045) (xy 306.39651 -288.226092) (xy 306.404541 -288.275083) (xy 306.405026 -288.299906)
			(xy 306.40485 -288.314089) (xy 306.402177 -288.342329) (xy 306.399692 -288.356294) (xy 306.397406 -288.36874)
			(xy 306.404772 -288.392362) (xy 306.482242 -288.469832) (xy 306.505864 -288.477198) (xy 306.51831 -288.474912)
			(xy 306.532276 -288.472438) (xy 306.560516 -288.469765) (xy 306.574698 -288.469578) (xy 306.588945 -288.469746)
			(xy 306.617313 -288.472414) (xy 306.63134 -288.474912) (xy 306.643532 -288.477198) (xy 306.667662 -288.469832)
			(xy 306.744878 -288.392616) (xy 306.752244 -288.36874) (xy 306.749958 -288.356294) (xy 306.747485 -288.342328)
			(xy 306.744811 -288.314088) (xy 306.744624 -288.299906) (xy 306.745071 -288.275085) (xy 306.753101 -288.226097)
			(xy 306.768951 -288.179053) (xy 306.792202 -288.135194) (xy 306.822243 -288.095673) (xy 306.858282 -288.061533)
			(xy 306.899368 -288.033674) (xy 306.944421 -288.012828) (xy 306.992253 -287.999545) (xy 307.041604 -287.994176)
			(xy 307.091173 -287.996861) (xy 307.139654 -288.00753) (xy 307.185772 -288.025901) (xy 307.228309 -288.051492)
			(xy 307.266146 -288.083627) (xy 307.298286 -288.12146) (xy 307.323882 -288.163994) (xy 307.342259 -288.210109)
			(xy 307.352934 -288.25859) (xy 307.355177 -288.299906) (xy 307.694088 -288.299906) (xy 307.698048 -288.250852)
			(xy 307.709825 -288.203068) (xy 307.729116 -288.157792) (xy 307.755419 -288.116196) (xy 307.788054 -288.079359)
			(xy 307.826175 -288.048234) (xy 307.868796 -288.023627) (xy 307.914812 -288.006175) (xy 307.963031 -287.996331)
			(xy 308.012206 -287.99435) (xy 308.061061 -288.000282) (xy 308.108332 -288.013974) (xy 308.152794 -288.035072)
			(xy 308.193297 -288.063028) (xy 308.22879 -288.09712) (xy 308.258355 -288.136464) (xy 308.281226 -288.180041)
			(xy 308.29681 -288.226722) (xy 308.304705 -288.275299) (xy 308.3052 -288.299906) (xy 308.304705 -288.324513)
			(xy 308.304526 -288.325614) (xy 308.623204 -288.325614) (xy 308.623204 -288.274198) (xy 308.631247 -288.223416)
			(xy 308.647135 -288.174517) (xy 308.670478 -288.128705) (xy 308.700699 -288.087109) (xy 308.737055 -288.050753)
			(xy 308.778651 -288.020532) (xy 308.824463 -287.997189) (xy 308.873362 -287.981301) (xy 308.924144 -287.973258)
			(xy 308.97556 -287.973258) (xy 309.026342 -287.981301) (xy 309.075241 -287.997189) (xy 309.121053 -288.020532)
			(xy 309.162649 -288.050753) (xy 309.199005 -288.087109) (xy 309.229226 -288.128705) (xy 309.252569 -288.174517)
			(xy 309.268457 -288.223416) (xy 309.2765 -288.274198) (xy 309.277004 -288.299906) (xy 309.2765 -288.325614)
			(xy 309.573164 -288.325614) (xy 309.573164 -288.274198) (xy 309.581207 -288.223416) (xy 309.597095 -288.174517)
			(xy 309.620438 -288.128705) (xy 309.650659 -288.087109) (xy 309.687015 -288.050753) (xy 309.728611 -288.020532)
			(xy 309.774423 -287.997189) (xy 309.823322 -287.981301) (xy 309.874104 -287.973258) (xy 309.92552 -287.973258)
			(xy 309.976302 -287.981301) (xy 310.025201 -287.997189) (xy 310.071013 -288.020532) (xy 310.112609 -288.050753)
			(xy 310.148965 -288.087109) (xy 310.179186 -288.128705) (xy 310.202529 -288.174517) (xy 310.218417 -288.223416)
			(xy 310.22646 -288.274198) (xy 310.226964 -288.299906) (xy 310.543968 -288.299906) (xy 310.547928 -288.250852)
			(xy 310.559705 -288.203068) (xy 310.578996 -288.157792) (xy 310.605299 -288.116196) (xy 310.637934 -288.079359)
			(xy 310.676055 -288.048234) (xy 310.718676 -288.023627) (xy 310.764692 -288.006175) (xy 310.812911 -287.996331)
			(xy 310.862086 -287.99435) (xy 310.910941 -288.000282) (xy 310.958212 -288.013974) (xy 311.002674 -288.035072)
			(xy 311.043177 -288.063028) (xy 311.07867 -288.09712) (xy 311.108235 -288.136464) (xy 311.131106 -288.180041)
			(xy 311.14669 -288.226722) (xy 311.154585 -288.275299) (xy 311.15508 -288.299906) (xy 311.154585 -288.324513)
			(xy 311.154446 -288.325369) (xy 311.472991 -288.325369) (xy 311.472998 -288.273936) (xy 311.481053 -288.223139)
			(xy 311.496956 -288.174226) (xy 311.520315 -288.128405) (xy 311.550557 -288.086802) (xy 311.586935 -288.050444)
			(xy 311.628553 -288.020224) (xy 311.674387 -287.996889) (xy 311.723308 -287.981012) (xy 311.77411 -287.972985)
			(xy 311.825543 -287.973004) (xy 311.876339 -287.981071) (xy 311.925247 -287.996986) (xy 311.971063 -288.020357)
			(xy 312.012658 -288.050608) (xy 312.049008 -288.086995) (xy 312.079217 -288.128621) (xy 312.102541 -288.174461)
			(xy 312.118407 -288.223385) (xy 312.126422 -288.274189) (xy 312.126884 -288.299906) (xy 312.126671 -288.313629)
			(xy 312.124258 -288.340969) (xy 312.122058 -288.354516) (xy 312.12028 -288.366454) (xy 312.127138 -288.389314)
			(xy 312.200798 -288.465768) (xy 312.223404 -288.473642) (xy 312.235342 -288.472118) (xy 312.245141 -288.470931)
			(xy 312.264841 -288.469659) (xy 312.274712 -288.469578) (xy 312.284583 -288.469649) (xy 312.304284 -288.470922)
			(xy 312.314082 -288.472118) (xy 312.32602 -288.473642) (xy 312.348626 -288.465768) (xy 312.422286 -288.389314)
			(xy 312.429144 -288.366454) (xy 312.427366 -288.354516) (xy 312.425145 -288.340972) (xy 312.422731 -288.31363)
			(xy 312.42254 -288.299906) (xy 312.423044 -288.274198) (xy 312.431087 -288.223416) (xy 312.446975 -288.174517)
			(xy 312.470318 -288.128705) (xy 312.500539 -288.087109) (xy 312.536895 -288.050753) (xy 312.578491 -288.020532)
			(xy 312.624303 -287.997189) (xy 312.673202 -287.981301) (xy 312.723984 -287.973258) (xy 312.7754 -287.973258)
			(xy 312.826182 -287.981301) (xy 312.875081 -287.997189) (xy 312.920893 -288.020532) (xy 312.962489 -288.050753)
			(xy 312.998845 -288.087109) (xy 313.029066 -288.128705) (xy 313.052409 -288.174517) (xy 313.068297 -288.223416)
			(xy 313.07634 -288.274198) (xy 313.076844 -288.299906) (xy 313.076631 -288.313629) (xy 313.074218 -288.340969)
			(xy 313.072018 -288.354516) (xy 313.069986 -288.366454) (xy 313.077098 -288.389314) (xy 313.150758 -288.465768)
			(xy 313.173364 -288.473642) (xy 313.185556 -288.472118) (xy 313.195355 -288.470929) (xy 313.215055 -288.469658)
			(xy 313.224926 -288.469578) (xy 313.239109 -288.469751) (xy 313.267349 -288.472426) (xy 313.281314 -288.474912)
			(xy 313.29376 -288.477198) (xy 313.317382 -288.469832) (xy 313.394852 -288.392362) (xy 313.402218 -288.36874)
			(xy 313.399932 -288.356294) (xy 313.397459 -288.342328) (xy 313.394785 -288.314088) (xy 313.394598 -288.299906)
			(xy 313.39512 -288.274651) (xy 313.403433 -288.224829) (xy 313.419834 -288.177055) (xy 313.443875 -288.132632)
			(xy 313.474899 -288.092772) (xy 313.512061 -288.058562) (xy 313.554347 -288.030936) (xy 313.600603 -288.010646)
			(xy 313.649568 -287.998246) (xy 313.699906 -287.994075) (xy 313.750244 -287.998246) (xy 313.799209 -288.010646)
			(xy 313.845465 -288.030936) (xy 313.887751 -288.058562) (xy 313.924913 -288.092772) (xy 313.955937 -288.132632)
			(xy 313.979978 -288.177055) (xy 313.996379 -288.224829) (xy 314.004692 -288.274651) (xy 314.005214 -288.299906)
			(xy 314.005038 -288.314089) (xy 314.002365 -288.342329) (xy 313.99988 -288.356294) (xy 313.997594 -288.36874)
			(xy 314.00496 -288.392362) (xy 314.08243 -288.469832) (xy 314.106052 -288.477198) (xy 314.118498 -288.474912)
			(xy 314.132465 -288.47244) (xy 314.160704 -288.469765) (xy 314.174886 -288.469578) (xy 314.189069 -288.469757)
			(xy 314.217309 -288.472427) (xy 314.231274 -288.474912) (xy 314.24372 -288.477198) (xy 314.267342 -288.469832)
			(xy 314.344812 -288.392362) (xy 314.352178 -288.36874) (xy 314.349892 -288.356294) (xy 314.347419 -288.342328)
			(xy 314.344745 -288.314088) (xy 314.344558 -288.299906) (xy 314.34508 -288.274651) (xy 314.353393 -288.224829)
			(xy 314.369794 -288.177055) (xy 314.393835 -288.132632) (xy 314.424859 -288.092772) (xy 314.462021 -288.058562)
			(xy 314.504307 -288.030936) (xy 314.550563 -288.010646) (xy 314.599528 -287.998246) (xy 314.649866 -287.994075)
			(xy 314.700204 -287.998246) (xy 314.749169 -288.010646) (xy 314.795425 -288.030936) (xy 314.837711 -288.058562)
			(xy 314.874873 -288.092772) (xy 314.905897 -288.132632) (xy 314.929938 -288.177055) (xy 314.946339 -288.224829)
			(xy 314.954652 -288.274651) (xy 314.955174 -288.299906) (xy 314.954999 -288.314089) (xy 314.952326 -288.342329)
			(xy 314.94984 -288.356294) (xy 314.947554 -288.36874) (xy 314.95492 -288.392362) (xy 315.03239 -288.469832)
			(xy 315.056012 -288.477198) (xy 315.068458 -288.474912) (xy 315.082423 -288.472432) (xy 315.110663 -288.469762)
			(xy 315.124846 -288.469578) (xy 315.147629 -288.469993) (xy 315.192686 -288.476777) (xy 315.236238 -288.490173)
			(xy 315.277319 -288.509884) (xy 315.31502 -288.535474) (xy 315.348506 -288.566376) (xy 315.363098 -288.583878)
			(xy 315.370664 -288.592477) (xy 315.391281 -288.602401) (xy 315.402722 -288.602928) (xy 315.48197 -288.602928)
			(xy 315.493383 -288.60227) (xy 315.51396 -288.592386) (xy 315.521594 -288.583878) (xy 315.53619 -288.566378)
			(xy 315.569664 -288.535461) (xy 315.607361 -288.509862) (xy 315.648444 -288.49015) (xy 315.692 -288.476762)
			(xy 315.737062 -288.469997) (xy 315.759846 -288.469578) (xy 315.785098 -288.470131) (xy 315.834911 -288.47845)
			(xy 315.882676 -288.494855) (xy 315.92709 -288.518896) (xy 315.966942 -288.54992) (xy 316.001145 -288.587079)
			(xy 316.028765 -288.62936) (xy 316.04905 -288.675611) (xy 316.061447 -288.724569) (xy 316.065617 -288.7749)
			(xy 316.061447 -288.825231) (xy 316.04905 -288.874189) (xy 316.028765 -288.92044) (xy 316.001145 -288.962721)
			(xy 315.966942 -288.99988) (xy 315.92709 -289.030904) (xy 315.882676 -289.054945) (xy 315.834911 -289.07135)
			(xy 315.785098 -289.079669) (xy 315.759846 -289.080194) (xy 315.737063 -289.079795) (xy 315.692004 -289.073009)
			(xy 315.648451 -289.059611) (xy 315.60737 -289.039896) (xy 315.569669 -289.014303) (xy 315.536185 -288.983397)
			(xy 315.521594 -288.965894) (xy 315.514036 -288.957287) (xy 315.493412 -288.947369) (xy 315.48197 -288.946844)
			(xy 315.402722 -288.946844) (xy 315.39131 -288.947507) (xy 315.370733 -288.957388) (xy 315.363098 -288.965894)
			(xy 315.348524 -288.983413) (xy 315.315044 -289.014326) (xy 315.277341 -289.03992) (xy 315.236254 -289.059629)
			(xy 315.192695 -289.073013) (xy 315.147631 -289.079776) (xy 315.124846 -289.080194) (xy 315.100853 -289.079719)
			(xy 315.053458 -289.072219) (xy 315.00782 -289.057396) (xy 314.965063 -289.035615) (xy 314.92624 -289.007413)
			(xy 314.892308 -288.973484) (xy 314.864102 -288.934664) (xy 314.842316 -288.89191) (xy 314.827488 -288.846273)
			(xy 314.819983 -288.798879) (xy 314.819538 -288.774886) (xy 314.819712 -288.760703) (xy 314.822386 -288.732463)
			(xy 314.824872 -288.718498) (xy 314.827158 -288.706052) (xy 314.819792 -288.68243) (xy 314.742322 -288.60496)
			(xy 314.7187 -288.597594) (xy 314.706254 -288.59988) (xy 314.692288 -288.602359) (xy 314.664049 -288.605029)
			(xy 314.649866 -288.605214) (xy 314.635683 -288.605042) (xy 314.607443 -288.602367) (xy 314.593478 -288.59988)
			(xy 314.581032 -288.597594) (xy 314.55741 -288.60496) (xy 314.47994 -288.68243) (xy 314.472574 -288.706052)
			(xy 314.47486 -288.718498) (xy 314.477332 -288.732465) (xy 314.480007 -288.760704) (xy 314.480194 -288.774886)
			(xy 314.479672 -288.800141) (xy 314.471359 -288.849963) (xy 314.454958 -288.897737) (xy 314.430917 -288.94216)
			(xy 314.399893 -288.98202) (xy 314.362731 -289.01623) (xy 314.320445 -289.043856) (xy 314.274189 -289.064146)
			(xy 314.225224 -289.076546) (xy 314.174886 -289.080717) (xy 314.124548 -289.076546) (xy 314.075583 -289.064146)
			(xy 314.029327 -289.043856) (xy 313.987041 -289.01623) (xy 313.949879 -288.98202) (xy 313.918855 -288.94216)
			(xy 313.894814 -288.897737) (xy 313.878413 -288.849963) (xy 313.8701 -288.800141) (xy 313.869578 -288.774886)
			(xy 313.869753 -288.760703) (xy 313.872426 -288.732463) (xy 313.874912 -288.718498) (xy 313.877198 -288.706052)
			(xy 313.869832 -288.68243) (xy 313.792362 -288.60496) (xy 313.76874 -288.597594) (xy 313.756294 -288.59988)
			(xy 313.742328 -288.602353) (xy 313.714088 -288.605027) (xy 313.699906 -288.605214) (xy 313.685723 -288.605036)
			(xy 313.657483 -288.602365) (xy 313.643518 -288.59988) (xy 313.631072 -288.597594) (xy 313.60745 -288.60496)
			(xy 313.52998 -288.68243) (xy 313.522614 -288.706052) (xy 313.5249 -288.718498) (xy 313.527372 -288.732465)
			(xy 313.530047 -288.760704) (xy 313.530234 -288.774886) (xy 313.529712 -288.800141) (xy 313.521399 -288.849963)
			(xy 313.504998 -288.897737) (xy 313.480957 -288.94216) (xy 313.449933 -288.98202) (xy 313.412771 -289.01623)
			(xy 313.370485 -289.043856) (xy 313.324229 -289.064146) (xy 313.275264 -289.076546) (xy 313.224926 -289.080717)
			(xy 313.174588 -289.076546) (xy 313.125623 -289.064146) (xy 313.079367 -289.043856) (xy 313.037081 -289.01623)
			(xy 312.999919 -288.98202) (xy 312.968895 -288.94216) (xy 312.944854 -288.897737) (xy 312.928453 -288.849963)
			(xy 312.92014 -288.800141) (xy 312.919618 -288.774886) (xy 312.919689 -288.765015) (xy 312.920961 -288.745314)
			(xy 312.922158 -288.735516) (xy 312.923682 -288.723578) (xy 312.915808 -288.700718) (xy 312.839354 -288.627312)
			(xy 312.816494 -288.6202) (xy 312.804302 -288.622232) (xy 312.790753 -288.62439) (xy 312.763411 -288.626677)
			(xy 312.749692 -288.626804) (xy 312.735974 -288.626658) (xy 312.708633 -288.62437) (xy 312.695082 -288.622232)
			(xy 312.683144 -288.620454) (xy 312.660284 -288.627312) (xy 312.58383 -288.700972) (xy 312.575956 -288.723578)
			(xy 312.57748 -288.735516) (xy 312.578665 -288.745316) (xy 312.579938 -288.765015) (xy 312.58002 -288.774886)
			(xy 312.579498 -288.800141) (xy 312.571185 -288.849963) (xy 312.554784 -288.897737) (xy 312.530743 -288.94216)
			(xy 312.499719 -288.98202) (xy 312.462557 -289.01623) (xy 312.420271 -289.043856) (xy 312.374015 -289.064146)
			(xy 312.32505 -289.076546) (xy 312.274712 -289.080717) (xy 312.224374 -289.076546) (xy 312.175409 -289.064146)
			(xy 312.129153 -289.043856) (xy 312.086867 -289.01623) (xy 312.049705 -288.98202) (xy 312.018681 -288.94216)
			(xy 311.99464 -288.897737) (xy 311.978239 -288.849963) (xy 311.969926 -288.800141) (xy 311.969404 -288.774886)
			(xy 311.969475 -288.765015) (xy 311.970747 -288.745314) (xy 311.971944 -288.735516) (xy 311.973468 -288.723578)
			(xy 311.965594 -288.700972) (xy 311.88914 -288.627312) (xy 311.86628 -288.620454) (xy 311.854342 -288.622232)
			(xy 311.840793 -288.624385) (xy 311.813451 -288.626675) (xy 311.799732 -288.626804) (xy 311.774016 -288.626408)
			(xy 311.723216 -288.618366) (xy 311.6743 -288.602475) (xy 311.628472 -288.579126) (xy 311.586863 -288.548895)
			(xy 311.550495 -288.512526) (xy 311.520266 -288.470914) (xy 311.496919 -288.425086) (xy 311.48103 -288.376169)
			(xy 311.472991 -288.325369) (xy 311.154446 -288.325369) (xy 311.14669 -288.37309) (xy 311.131106 -288.419771)
			(xy 311.108235 -288.463348) (xy 311.07867 -288.502692) (xy 311.043177 -288.536784) (xy 311.002674 -288.56474)
			(xy 310.958212 -288.585838) (xy 310.910941 -288.59953) (xy 310.862086 -288.605462) (xy 310.812911 -288.603481)
			(xy 310.764692 -288.593637) (xy 310.718676 -288.576185) (xy 310.676055 -288.551578) (xy 310.637934 -288.520453)
			(xy 310.605299 -288.483616) (xy 310.578996 -288.44202) (xy 310.559705 -288.396744) (xy 310.547928 -288.34896)
			(xy 310.543968 -288.299906) (xy 310.226964 -288.299906) (xy 310.22646 -288.325614) (xy 310.218417 -288.376396)
			(xy 310.202529 -288.425295) (xy 310.179186 -288.471107) (xy 310.148965 -288.512703) (xy 310.112609 -288.549059)
			(xy 310.071013 -288.57928) (xy 310.025201 -288.602623) (xy 309.976302 -288.618511) (xy 309.92552 -288.626554)
			(xy 309.874104 -288.626554) (xy 309.823322 -288.618511) (xy 309.774423 -288.602623) (xy 309.728611 -288.57928)
			(xy 309.687015 -288.549059) (xy 309.650659 -288.512703) (xy 309.620438 -288.471107) (xy 309.597095 -288.425295)
			(xy 309.581207 -288.376396) (xy 309.573164 -288.325614) (xy 309.2765 -288.325614) (xy 309.268457 -288.376396)
			(xy 309.252569 -288.425295) (xy 309.229226 -288.471107) (xy 309.199005 -288.512703) (xy 309.162649 -288.549059)
			(xy 309.121053 -288.57928) (xy 309.075241 -288.602623) (xy 309.026342 -288.618511) (xy 308.97556 -288.626554)
			(xy 308.924144 -288.626554) (xy 308.873362 -288.618511) (xy 308.824463 -288.602623) (xy 308.778651 -288.57928)
			(xy 308.737055 -288.549059) (xy 308.700699 -288.512703) (xy 308.670478 -288.471107) (xy 308.647135 -288.425295)
			(xy 308.631247 -288.376396) (xy 308.623204 -288.325614) (xy 308.304526 -288.325614) (xy 308.29681 -288.37309)
			(xy 308.281226 -288.419771) (xy 308.258355 -288.463348) (xy 308.22879 -288.502692) (xy 308.193297 -288.536784)
			(xy 308.152794 -288.56474) (xy 308.108332 -288.585838) (xy 308.061061 -288.59953) (xy 308.012206 -288.605462)
			(xy 307.963031 -288.603481) (xy 307.914812 -288.593637) (xy 307.868796 -288.576185) (xy 307.826175 -288.551578)
			(xy 307.788054 -288.520453) (xy 307.755419 -288.483616) (xy 307.729116 -288.44202) (xy 307.709825 -288.396744)
			(xy 307.698048 -288.34896) (xy 307.694088 -288.299906) (xy 307.355177 -288.299906) (xy 307.355625 -288.308158)
			(xy 307.350262 -288.35751) (xy 307.336985 -288.405343) (xy 307.316145 -288.450398) (xy 307.28829 -288.491489)
			(xy 307.254155 -288.527532) (xy 307.214638 -288.557577) (xy 307.170781 -288.580834) (xy 307.12374 -288.596689)
			(xy 307.074753 -288.604726) (xy 307.049932 -288.605214) (xy 307.035685 -288.605049) (xy 307.007318 -288.602375)
			(xy 306.99329 -288.59988) (xy 306.981098 -288.597594) (xy 306.956968 -288.60496) (xy 306.879752 -288.682176)
			(xy 306.872386 -288.706052) (xy 306.874672 -288.718498) (xy 306.877144 -288.732465) (xy 306.879819 -288.760704)
			(xy 306.880006 -288.774886) (xy 306.879484 -288.800141) (xy 306.871171 -288.849963) (xy 306.85477 -288.897737)
			(xy 306.830729 -288.94216) (xy 306.799705 -288.98202) (xy 306.762543 -289.01623) (xy 306.720257 -289.043856)
			(xy 306.674001 -289.064146) (xy 306.625036 -289.076546) (xy 306.574698 -289.080717) (xy 306.52436 -289.076546)
			(xy 306.475395 -289.064146) (xy 306.429139 -289.043856) (xy 306.386853 -289.01623) (xy 306.349691 -288.98202)
			(xy 306.318667 -288.94216) (xy 306.294626 -288.897737) (xy 306.278225 -288.849963) (xy 306.269912 -288.800141)
			(xy 306.26939 -288.774886) (xy 306.269565 -288.760703) (xy 306.272238 -288.732463) (xy 306.274724 -288.718498)
			(xy 306.27701 -288.706052) (xy 306.269644 -288.68243) (xy 306.192174 -288.60496) (xy 306.168552 -288.597594)
			(xy 306.156106 -288.59988) (xy 306.142139 -288.602352) (xy 306.1139 -288.605027) (xy 306.099718 -288.605214)
			(xy 306.074895 -288.604741) (xy 306.025903 -288.596713) (xy 305.978856 -288.580863) (xy 305.934992 -288.557611)
			(xy 305.895468 -288.527569) (xy 305.861326 -288.491528) (xy 305.833463 -288.450438) (xy 305.812616 -288.405382)
			(xy 305.799333 -288.357547) (xy 305.793963 -288.308192) (xy 260.25218 -288.308192) (xy 260.251455 -288.313118)
			(xy 260.235387 -288.366525) (xy 260.211715 -288.417022) (xy 260.180942 -288.463535) (xy 260.143725 -288.505072)
			(xy 260.100857 -288.540747) (xy 260.053251 -288.569801) (xy 260.001922 -288.591613) (xy 259.947965 -288.605719)
			(xy 259.892528 -288.611819) (xy 259.836794 -288.609782) (xy 259.781951 -288.599652) (xy 259.729167 -288.581645)
			(xy 259.679567 -288.556144) (xy 259.634209 -288.523693) (xy 259.59406 -288.484984) (xy 259.559974 -288.440841)
			(xy 259.532678 -288.392206) (xy 259.512755 -288.340115) (xy 259.500629 -288.285678) (xy 259.496558 -288.230056)
			(xy 258.774946 -288.230056) (xy 258.774437 -288.257942) (xy 258.766317 -288.313118) (xy 258.750249 -288.366525)
			(xy 258.726577 -288.417022) (xy 258.695804 -288.463535) (xy 258.658587 -288.505072) (xy 258.615719 -288.540747)
			(xy 258.568113 -288.569801) (xy 258.516784 -288.591613) (xy 258.462827 -288.605719) (xy 258.40739 -288.611819)
			(xy 258.351656 -288.609782) (xy 258.296813 -288.599652) (xy 258.244029 -288.581645) (xy 258.194429 -288.556144)
			(xy 258.149071 -288.523693) (xy 258.108922 -288.484984) (xy 258.074836 -288.440841) (xy 258.04754 -288.392206)
			(xy 258.027617 -288.340115) (xy 258.015491 -288.285678) (xy 258.01142 -288.230056) (xy 252.276174 -288.230056)
			(xy 252.264613 -288.268481) (xy 252.240941 -288.318978) (xy 252.210168 -288.365491) (xy 252.172951 -288.407028)
			(xy 252.130083 -288.442703) (xy 252.082477 -288.471757) (xy 252.031148 -288.493569) (xy 251.977191 -288.507675)
			(xy 251.921754 -288.513775) (xy 251.86602 -288.511738) (xy 251.811177 -288.501608) (xy 251.758393 -288.483601)
			(xy 251.708793 -288.4581) (xy 251.663435 -288.425649) (xy 251.623286 -288.38694) (xy 251.5892 -288.342797)
			(xy 251.561904 -288.294162) (xy 251.541981 -288.242071) (xy 251.529855 -288.187634) (xy 251.525784 -288.132012)
			(xy 250.445339 -288.132012) (xy 250.450611 -288.149534) (xy 250.458731 -288.20471) (xy 250.45924 -288.232596)
			(xy 250.458731 -288.260482) (xy 250.450611 -288.315658) (xy 250.434543 -288.369065) (xy 250.410871 -288.419562)
			(xy 250.380098 -288.466075) (xy 250.342881 -288.507612) (xy 250.300013 -288.543287) (xy 250.252407 -288.572341)
			(xy 250.201078 -288.594153) (xy 250.147121 -288.608259) (xy 250.091684 -288.614359) (xy 250.03595 -288.612322)
			(xy 249.981107 -288.602192) (xy 249.928323 -288.584185) (xy 249.878723 -288.558684) (xy 249.833365 -288.526233)
			(xy 249.793216 -288.487524) (xy 249.75913 -288.443381) (xy 249.731834 -288.394746) (xy 249.711911 -288.342655)
			(xy 249.699785 -288.288218) (xy 249.695714 -288.232596) (xy 234.5309 -288.232596) (xy 234.5309 -288.67945)
			(xy 244.031782 -288.67945) (xy 244.031782 -288.62495) (xy 244.039537 -288.571006) (xy 244.054891 -288.518714)
			(xy 244.07753 -288.469139) (xy 244.106993 -288.423291) (xy 244.142681 -288.382102) (xy 244.183867 -288.346411)
			(xy 244.229713 -288.316944) (xy 244.279286 -288.294301) (xy 244.331577 -288.278944) (xy 244.38552 -288.271184)
			(xy 244.41277 -288.270696) (xy 244.439373 -288.271169) (xy 244.492065 -288.278547) (xy 244.54322 -288.293177)
			(xy 244.591845 -288.314776) (xy 244.636996 -288.342923) (xy 244.677795 -288.377074) (xy 244.713452 -288.416564)
			(xy 244.728746 -288.438336) (xy 244.73708 -288.449816) (xy 244.758824 -288.46802) (xy 244.784737 -288.479538)
			(xy 244.81282 -288.483478) (xy 244.840903 -288.479538) (xy 244.866816 -288.46802) (xy 244.88856 -288.449816)
			(xy 244.896894 -288.438336) (xy 244.912179 -288.416559) (xy 244.947848 -288.37708) (xy 244.988653 -288.342937)
			(xy 245.033804 -288.314793) (xy 245.082427 -288.293192) (xy 245.133579 -288.278552) (xy 245.186267 -288.271159)
			(xy 245.21287 -288.270696) (xy 245.240125 -288.271149) (xy 245.294079 -288.278903) (xy 245.346381 -288.294256)
			(xy 245.395966 -288.316898) (xy 245.441823 -288.346365) (xy 245.48302 -288.382059) (xy 245.518717 -288.423253)
			(xy 245.548188 -288.469108) (xy 245.570833 -288.518691) (xy 245.586191 -288.570991) (xy 245.593949 -288.624946)
			(xy 245.593949 -288.679454) (xy 245.586191 -288.733409) (xy 245.570833 -288.785709) (xy 245.548188 -288.835292)
			(xy 245.518717 -288.881147) (xy 245.48302 -288.922341) (xy 245.441823 -288.958035) (xy 245.395966 -288.987502)
			(xy 245.38043 -288.994596) (xy 250.59843 -288.994596) (xy 250.602501 -288.938974) (xy 250.614627 -288.884537)
			(xy 250.63455 -288.832446) (xy 250.661846 -288.783811) (xy 250.695932 -288.739668) (xy 250.736081 -288.700959)
			(xy 250.781439 -288.668508) (xy 250.831039 -288.643007) (xy 250.883823 -288.625) (xy 250.938666 -288.61487)
			(xy 250.9944 -288.612833) (xy 251.049837 -288.618933) (xy 251.103794 -288.633039) (xy 251.155123 -288.654851)
			(xy 251.202729 -288.683905) (xy 251.245597 -288.71958) (xy 251.282814 -288.761117) (xy 251.313587 -288.80763)
			(xy 251.337259 -288.858127) (xy 251.348055 -288.894012) (xy 252.4285 -288.894012) (xy 252.432571 -288.83839)
			(xy 252.444697 -288.783953) (xy 252.46462 -288.731862) (xy 252.491916 -288.683227) (xy 252.526002 -288.639084)
			(xy 252.566151 -288.600375) (xy 252.611509 -288.567924) (xy 252.661109 -288.542423) (xy 252.713893 -288.524416)
			(xy 252.768736 -288.514286) (xy 252.82447 -288.512249) (xy 252.879907 -288.518349) (xy 252.933864 -288.532455)
			(xy 252.985193 -288.554267) (xy 253.032799 -288.583321) (xy 253.075667 -288.618996) (xy 253.112884 -288.660533)
			(xy 253.143657 -288.707046) (xy 253.167329 -288.757543) (xy 253.172547 -288.774886) (xy 268.26897 -288.774886)
			(xy 268.27293 -288.725832) (xy 268.284707 -288.678048) (xy 268.303998 -288.632772) (xy 268.330301 -288.591176)
			(xy 268.362936 -288.554339) (xy 268.401057 -288.523214) (xy 268.443678 -288.498607) (xy 268.489694 -288.481155)
			(xy 268.537913 -288.471311) (xy 268.587088 -288.46933) (xy 268.635943 -288.475262) (xy 268.683214 -288.488954)
			(xy 268.727676 -288.510052) (xy 268.768179 -288.538008) (xy 268.803672 -288.5721) (xy 268.833237 -288.611444)
			(xy 268.856108 -288.655021) (xy 268.871692 -288.701702) (xy 268.879587 -288.750279) (xy 268.880082 -288.774886)
			(xy 269.21893 -288.774886) (xy 269.22289 -288.725832) (xy 269.234667 -288.678048) (xy 269.253958 -288.632772)
			(xy 269.280261 -288.591176) (xy 269.312896 -288.554339) (xy 269.351017 -288.523214) (xy 269.393638 -288.498607)
			(xy 269.439654 -288.481155) (xy 269.487873 -288.471311) (xy 269.537048 -288.46933) (xy 269.585903 -288.475262)
			(xy 269.633174 -288.488954) (xy 269.677636 -288.510052) (xy 269.718139 -288.538008) (xy 269.753632 -288.5721)
			(xy 269.783197 -288.611444) (xy 269.806068 -288.655021) (xy 269.821652 -288.701702) (xy 269.829547 -288.750279)
			(xy 269.830042 -288.774886) (xy 270.169144 -288.774886) (xy 270.173104 -288.725832) (xy 270.184881 -288.678048)
			(xy 270.204172 -288.632772) (xy 270.230475 -288.591176) (xy 270.26311 -288.554339) (xy 270.301231 -288.523214)
			(xy 270.343852 -288.498607) (xy 270.389868 -288.481155) (xy 270.438087 -288.471311) (xy 270.487262 -288.46933)
			(xy 270.536117 -288.475262) (xy 270.583388 -288.488954) (xy 270.62785 -288.510052) (xy 270.668353 -288.538008)
			(xy 270.703846 -288.5721) (xy 270.733411 -288.611444) (xy 270.756282 -288.655021) (xy 270.771866 -288.701702)
			(xy 270.779761 -288.750279) (xy 270.780256 -288.774886) (xy 274.918944 -288.774886) (xy 274.922904 -288.725832)
			(xy 274.934681 -288.678048) (xy 274.953972 -288.632772) (xy 274.980275 -288.591176) (xy 275.01291 -288.554339)
			(xy 275.051031 -288.523214) (xy 275.093652 -288.498607) (xy 275.139668 -288.481155) (xy 275.187887 -288.471311)
			(xy 275.237062 -288.46933) (xy 275.285917 -288.475262) (xy 275.333188 -288.488954) (xy 275.37765 -288.510052)
			(xy 275.418153 -288.538008) (xy 275.453646 -288.5721) (xy 275.483211 -288.611444) (xy 275.506082 -288.655021)
			(xy 275.521666 -288.701702) (xy 275.529561 -288.750279) (xy 275.530056 -288.774886) (xy 275.868904 -288.774886)
			(xy 275.872864 -288.725832) (xy 275.884641 -288.678048) (xy 275.903932 -288.632772) (xy 275.930235 -288.591176)
			(xy 275.96287 -288.554339) (xy 276.000991 -288.523214) (xy 276.043612 -288.498607) (xy 276.089628 -288.481155)
			(xy 276.137847 -288.471311) (xy 276.187022 -288.46933) (xy 276.235877 -288.475262) (xy 276.283148 -288.488954)
			(xy 276.32761 -288.510052) (xy 276.368113 -288.538008) (xy 276.403606 -288.5721) (xy 276.433171 -288.611444)
			(xy 276.456042 -288.655021) (xy 276.471626 -288.701702) (xy 276.479521 -288.750279) (xy 276.480016 -288.774886)
			(xy 276.819118 -288.774886) (xy 276.823078 -288.725832) (xy 276.834855 -288.678048) (xy 276.854146 -288.632772)
			(xy 276.880449 -288.591176) (xy 276.913084 -288.554339) (xy 276.951205 -288.523214) (xy 276.993826 -288.498607)
			(xy 277.039842 -288.481155) (xy 277.088061 -288.471311) (xy 277.137236 -288.46933) (xy 277.186091 -288.475262)
			(xy 277.233362 -288.488954) (xy 277.277824 -288.510052) (xy 277.318327 -288.538008) (xy 277.35382 -288.5721)
			(xy 277.383385 -288.611444) (xy 277.406256 -288.655021) (xy 277.42184 -288.701702) (xy 277.429735 -288.750279)
			(xy 277.43023 -288.774886) (xy 277.769078 -288.774886) (xy 277.773038 -288.725832) (xy 277.784815 -288.678048)
			(xy 277.804106 -288.632772) (xy 277.830409 -288.591176) (xy 277.863044 -288.554339) (xy 277.901165 -288.523214)
			(xy 277.943786 -288.498607) (xy 277.989802 -288.481155) (xy 278.038021 -288.471311) (xy 278.087196 -288.46933)
			(xy 278.136051 -288.475262) (xy 278.183322 -288.488954) (xy 278.227784 -288.510052) (xy 278.268287 -288.538008)
			(xy 278.30378 -288.5721) (xy 278.333345 -288.611444) (xy 278.356216 -288.655021) (xy 278.3718 -288.701702)
			(xy 278.379695 -288.750279) (xy 278.38019 -288.774886) (xy 278.719038 -288.774886) (xy 278.722998 -288.725832)
			(xy 278.734775 -288.678048) (xy 278.754066 -288.632772) (xy 278.780369 -288.591176) (xy 278.813004 -288.554339)
			(xy 278.851125 -288.523214) (xy 278.893746 -288.498607) (xy 278.939762 -288.481155) (xy 278.987981 -288.471311)
			(xy 279.037156 -288.46933) (xy 279.086011 -288.475262) (xy 279.133282 -288.488954) (xy 279.177744 -288.510052)
			(xy 279.218247 -288.538008) (xy 279.25374 -288.5721) (xy 279.283305 -288.611444) (xy 279.306176 -288.655021)
			(xy 279.32176 -288.701702) (xy 279.329655 -288.750279) (xy 279.33015 -288.774886) (xy 279.668998 -288.774886)
			(xy 279.672958 -288.725832) (xy 279.684735 -288.678048) (xy 279.704026 -288.632772) (xy 279.730329 -288.591176)
			(xy 279.762964 -288.554339) (xy 279.801085 -288.523214) (xy 279.843706 -288.498607) (xy 279.889722 -288.481155)
			(xy 279.937941 -288.471311) (xy 279.987116 -288.46933) (xy 280.035971 -288.475262) (xy 280.083242 -288.488954)
			(xy 280.127704 -288.510052) (xy 280.168207 -288.538008) (xy 280.2037 -288.5721) (xy 280.233265 -288.611444)
			(xy 280.256136 -288.655021) (xy 280.27172 -288.701702) (xy 280.279615 -288.750279) (xy 280.28011 -288.774886)
			(xy 280.618958 -288.774886) (xy 280.622918 -288.725832) (xy 280.634695 -288.678048) (xy 280.653986 -288.632772)
			(xy 280.680289 -288.591176) (xy 280.712924 -288.554339) (xy 280.751045 -288.523214) (xy 280.793666 -288.498607)
			(xy 280.839682 -288.481155) (xy 280.887901 -288.471311) (xy 280.937076 -288.46933) (xy 280.985931 -288.475262)
			(xy 281.033202 -288.488954) (xy 281.077664 -288.510052) (xy 281.118167 -288.538008) (xy 281.15366 -288.5721)
			(xy 281.183225 -288.611444) (xy 281.206096 -288.655021) (xy 281.22168 -288.701702) (xy 281.229575 -288.750279)
			(xy 281.23007 -288.774886) (xy 281.568918 -288.774886) (xy 281.572878 -288.725832) (xy 281.584655 -288.678048)
			(xy 281.603946 -288.632772) (xy 281.630249 -288.591176) (xy 281.662884 -288.554339) (xy 281.701005 -288.523214)
			(xy 281.743626 -288.498607) (xy 281.789642 -288.481155) (xy 281.837861 -288.471311) (xy 281.887036 -288.46933)
			(xy 281.935891 -288.475262) (xy 281.983162 -288.488954) (xy 282.027624 -288.510052) (xy 282.068127 -288.538008)
			(xy 282.10362 -288.5721) (xy 282.133185 -288.611444) (xy 282.156056 -288.655021) (xy 282.17164 -288.701702)
			(xy 282.179535 -288.750279) (xy 282.18003 -288.774886) (xy 300.56888 -288.774886) (xy 300.57284 -288.725832)
			(xy 300.584617 -288.678048) (xy 300.603908 -288.632772) (xy 300.630211 -288.591176) (xy 300.662846 -288.554339)
			(xy 300.700967 -288.523214) (xy 300.743588 -288.498607) (xy 300.789604 -288.481155) (xy 300.837823 -288.471311)
			(xy 300.886998 -288.46933) (xy 300.935853 -288.475262) (xy 300.983124 -288.488954) (xy 301.027586 -288.510052)
			(xy 301.068089 -288.538008) (xy 301.103582 -288.5721) (xy 301.133147 -288.611444) (xy 301.156018 -288.655021)
			(xy 301.171602 -288.701702) (xy 301.179497 -288.750279) (xy 301.179992 -288.774886) (xy 301.519094 -288.774886)
			(xy 301.523054 -288.725832) (xy 301.534831 -288.678048) (xy 301.554122 -288.632772) (xy 301.580425 -288.591176)
			(xy 301.61306 -288.554339) (xy 301.651181 -288.523214) (xy 301.693802 -288.498607) (xy 301.739818 -288.481155)
			(xy 301.788037 -288.471311) (xy 301.837212 -288.46933) (xy 301.886067 -288.475262) (xy 301.933338 -288.488954)
			(xy 301.9778 -288.510052) (xy 302.018303 -288.538008) (xy 302.053796 -288.5721) (xy 302.083361 -288.611444)
			(xy 302.106232 -288.655021) (xy 302.121816 -288.701702) (xy 302.129711 -288.750279) (xy 302.130206 -288.774886)
			(xy 302.469054 -288.774886) (xy 302.473014 -288.725832) (xy 302.484791 -288.678048) (xy 302.504082 -288.632772)
			(xy 302.530385 -288.591176) (xy 302.56302 -288.554339) (xy 302.601141 -288.523214) (xy 302.643762 -288.498607)
			(xy 302.689778 -288.481155) (xy 302.737997 -288.471311) (xy 302.787172 -288.46933) (xy 302.836027 -288.475262)
			(xy 302.883298 -288.488954) (xy 302.92776 -288.510052) (xy 302.968263 -288.538008) (xy 303.003756 -288.5721)
			(xy 303.033321 -288.611444) (xy 303.056192 -288.655021) (xy 303.071776 -288.701702) (xy 303.079671 -288.750279)
			(xy 303.080166 -288.774886) (xy 303.419014 -288.774886) (xy 303.422974 -288.725832) (xy 303.434751 -288.678048)
			(xy 303.454042 -288.632772) (xy 303.480345 -288.591176) (xy 303.51298 -288.554339) (xy 303.551101 -288.523214)
			(xy 303.593722 -288.498607) (xy 303.639738 -288.481155) (xy 303.687957 -288.471311) (xy 303.737132 -288.46933)
			(xy 303.785987 -288.475262) (xy 303.833258 -288.488954) (xy 303.87772 -288.510052) (xy 303.918223 -288.538008)
			(xy 303.953716 -288.5721) (xy 303.983281 -288.611444) (xy 304.006152 -288.655021) (xy 304.021736 -288.701702)
			(xy 304.029631 -288.750279) (xy 304.030126 -288.774886) (xy 304.368974 -288.774886) (xy 304.372934 -288.725832)
			(xy 304.384711 -288.678048) (xy 304.404002 -288.632772) (xy 304.430305 -288.591176) (xy 304.46294 -288.554339)
			(xy 304.501061 -288.523214) (xy 304.543682 -288.498607) (xy 304.589698 -288.481155) (xy 304.637917 -288.471311)
			(xy 304.687092 -288.46933) (xy 304.735947 -288.475262) (xy 304.783218 -288.488954) (xy 304.82768 -288.510052)
			(xy 304.868183 -288.538008) (xy 304.903676 -288.5721) (xy 304.933241 -288.611444) (xy 304.956112 -288.655021)
			(xy 304.971696 -288.701702) (xy 304.979591 -288.750279) (xy 304.980086 -288.774886) (xy 304.979591 -288.799493)
			(xy 304.971696 -288.84807) (xy 304.956112 -288.894751) (xy 304.933241 -288.938328) (xy 304.903676 -288.977672)
			(xy 304.868183 -289.011764) (xy 304.82768 -289.03972) (xy 304.783218 -289.060818) (xy 304.735947 -289.07451)
			(xy 304.687092 -289.080442) (xy 304.637917 -289.078461) (xy 304.589698 -289.068617) (xy 304.543682 -289.051165)
			(xy 304.501061 -289.026558) (xy 304.46294 -288.995433) (xy 304.430305 -288.958596) (xy 304.404002 -288.917)
			(xy 304.384711 -288.871724) (xy 304.372934 -288.82394) (xy 304.368974 -288.774886) (xy 304.030126 -288.774886)
			(xy 304.029631 -288.799493) (xy 304.021736 -288.84807) (xy 304.006152 -288.894751) (xy 303.983281 -288.938328)
			(xy 303.953716 -288.977672) (xy 303.918223 -289.011764) (xy 303.87772 -289.03972) (xy 303.833258 -289.060818)
			(xy 303.785987 -289.07451) (xy 303.737132 -289.080442) (xy 303.687957 -289.078461) (xy 303.639738 -289.068617)
			(xy 303.593722 -289.051165) (xy 303.551101 -289.026558) (xy 303.51298 -288.995433) (xy 303.480345 -288.958596)
			(xy 303.454042 -288.917) (xy 303.434751 -288.871724) (xy 303.422974 -288.82394) (xy 303.419014 -288.774886)
			(xy 303.080166 -288.774886) (xy 303.079671 -288.799493) (xy 303.071776 -288.84807) (xy 303.056192 -288.894751)
			(xy 303.033321 -288.938328) (xy 303.003756 -288.977672) (xy 302.968263 -289.011764) (xy 302.92776 -289.03972)
			(xy 302.883298 -289.060818) (xy 302.836027 -289.07451) (xy 302.787172 -289.080442) (xy 302.737997 -289.078461)
			(xy 302.689778 -289.068617) (xy 302.643762 -289.051165) (xy 302.601141 -289.026558) (xy 302.56302 -288.995433)
			(xy 302.530385 -288.958596) (xy 302.504082 -288.917) (xy 302.484791 -288.871724) (xy 302.473014 -288.82394)
			(xy 302.469054 -288.774886) (xy 302.130206 -288.774886) (xy 302.129711 -288.799493) (xy 302.121816 -288.84807)
			(xy 302.106232 -288.894751) (xy 302.083361 -288.938328) (xy 302.053796 -288.977672) (xy 302.018303 -289.011764)
			(xy 301.9778 -289.03972) (xy 301.933338 -289.060818) (xy 301.886067 -289.07451) (xy 301.837212 -289.080442)
			(xy 301.788037 -289.078461) (xy 301.739818 -289.068617) (xy 301.693802 -289.051165) (xy 301.651181 -289.026558)
			(xy 301.61306 -288.995433) (xy 301.580425 -288.958596) (xy 301.554122 -288.917) (xy 301.534831 -288.871724)
			(xy 301.523054 -288.82394) (xy 301.519094 -288.774886) (xy 301.179992 -288.774886) (xy 301.179497 -288.799493)
			(xy 301.171602 -288.84807) (xy 301.156018 -288.894751) (xy 301.133147 -288.938328) (xy 301.103582 -288.977672)
			(xy 301.068089 -289.011764) (xy 301.027586 -289.03972) (xy 300.983124 -289.060818) (xy 300.935853 -289.07451)
			(xy 300.886998 -289.080442) (xy 300.837823 -289.078461) (xy 300.789604 -289.068617) (xy 300.743588 -289.051165)
			(xy 300.700967 -289.026558) (xy 300.662846 -288.995433) (xy 300.630211 -288.958596) (xy 300.603908 -288.917)
			(xy 300.584617 -288.871724) (xy 300.57284 -288.82394) (xy 300.56888 -288.774886) (xy 282.18003 -288.774886)
			(xy 282.179535 -288.799493) (xy 282.17164 -288.84807) (xy 282.156056 -288.894751) (xy 282.133185 -288.938328)
			(xy 282.10362 -288.977672) (xy 282.068127 -289.011764) (xy 282.027624 -289.03972) (xy 281.983162 -289.060818)
			(xy 281.935891 -289.07451) (xy 281.887036 -289.080442) (xy 281.837861 -289.078461) (xy 281.789642 -289.068617)
			(xy 281.743626 -289.051165) (xy 281.701005 -289.026558) (xy 281.662884 -288.995433) (xy 281.630249 -288.958596)
			(xy 281.603946 -288.917) (xy 281.584655 -288.871724) (xy 281.572878 -288.82394) (xy 281.568918 -288.774886)
			(xy 281.23007 -288.774886) (xy 281.229575 -288.799493) (xy 281.22168 -288.84807) (xy 281.206096 -288.894751)
			(xy 281.183225 -288.938328) (xy 281.15366 -288.977672) (xy 281.118167 -289.011764) (xy 281.077664 -289.03972)
			(xy 281.033202 -289.060818) (xy 280.985931 -289.07451) (xy 280.937076 -289.080442) (xy 280.887901 -289.078461)
			(xy 280.839682 -289.068617) (xy 280.793666 -289.051165) (xy 280.751045 -289.026558) (xy 280.712924 -288.995433)
			(xy 280.680289 -288.958596) (xy 280.653986 -288.917) (xy 280.634695 -288.871724) (xy 280.622918 -288.82394)
			(xy 280.618958 -288.774886) (xy 280.28011 -288.774886) (xy 280.279615 -288.799493) (xy 280.27172 -288.84807)
			(xy 280.256136 -288.894751) (xy 280.233265 -288.938328) (xy 280.2037 -288.977672) (xy 280.168207 -289.011764)
			(xy 280.127704 -289.03972) (xy 280.083242 -289.060818) (xy 280.035971 -289.07451) (xy 279.987116 -289.080442)
			(xy 279.937941 -289.078461) (xy 279.889722 -289.068617) (xy 279.843706 -289.051165) (xy 279.801085 -289.026558)
			(xy 279.762964 -288.995433) (xy 279.730329 -288.958596) (xy 279.704026 -288.917) (xy 279.684735 -288.871724)
			(xy 279.672958 -288.82394) (xy 279.668998 -288.774886) (xy 279.33015 -288.774886) (xy 279.329655 -288.799493)
			(xy 279.32176 -288.84807) (xy 279.306176 -288.894751) (xy 279.283305 -288.938328) (xy 279.25374 -288.977672)
			(xy 279.218247 -289.011764) (xy 279.177744 -289.03972) (xy 279.133282 -289.060818) (xy 279.086011 -289.07451)
			(xy 279.037156 -289.080442) (xy 278.987981 -289.078461) (xy 278.939762 -289.068617) (xy 278.893746 -289.051165)
			(xy 278.851125 -289.026558) (xy 278.813004 -288.995433) (xy 278.780369 -288.958596) (xy 278.754066 -288.917)
			(xy 278.734775 -288.871724) (xy 278.722998 -288.82394) (xy 278.719038 -288.774886) (xy 278.38019 -288.774886)
			(xy 278.379695 -288.799493) (xy 278.3718 -288.84807) (xy 278.356216 -288.894751) (xy 278.333345 -288.938328)
			(xy 278.30378 -288.977672) (xy 278.268287 -289.011764) (xy 278.227784 -289.03972) (xy 278.183322 -289.060818)
			(xy 278.136051 -289.07451) (xy 278.087196 -289.080442) (xy 278.038021 -289.078461) (xy 277.989802 -289.068617)
			(xy 277.943786 -289.051165) (xy 277.901165 -289.026558) (xy 277.863044 -288.995433) (xy 277.830409 -288.958596)
			(xy 277.804106 -288.917) (xy 277.784815 -288.871724) (xy 277.773038 -288.82394) (xy 277.769078 -288.774886)
			(xy 277.43023 -288.774886) (xy 277.429735 -288.799493) (xy 277.42184 -288.84807) (xy 277.406256 -288.894751)
			(xy 277.383385 -288.938328) (xy 277.35382 -288.977672) (xy 277.318327 -289.011764) (xy 277.277824 -289.03972)
			(xy 277.233362 -289.060818) (xy 277.186091 -289.07451) (xy 277.137236 -289.080442) (xy 277.088061 -289.078461)
			(xy 277.039842 -289.068617) (xy 276.993826 -289.051165) (xy 276.951205 -289.026558) (xy 276.913084 -288.995433)
			(xy 276.880449 -288.958596) (xy 276.854146 -288.917) (xy 276.834855 -288.871724) (xy 276.823078 -288.82394)
			(xy 276.819118 -288.774886) (xy 276.480016 -288.774886) (xy 276.479521 -288.799493) (xy 276.471626 -288.84807)
			(xy 276.456042 -288.894751) (xy 276.433171 -288.938328) (xy 276.403606 -288.977672) (xy 276.368113 -289.011764)
			(xy 276.32761 -289.03972) (xy 276.283148 -289.060818) (xy 276.235877 -289.07451) (xy 276.187022 -289.080442)
			(xy 276.137847 -289.078461) (xy 276.089628 -289.068617) (xy 276.043612 -289.051165) (xy 276.000991 -289.026558)
			(xy 275.96287 -288.995433) (xy 275.930235 -288.958596) (xy 275.903932 -288.917) (xy 275.884641 -288.871724)
			(xy 275.872864 -288.82394) (xy 275.868904 -288.774886) (xy 275.530056 -288.774886) (xy 275.529561 -288.799493)
			(xy 275.521666 -288.84807) (xy 275.506082 -288.894751) (xy 275.483211 -288.938328) (xy 275.453646 -288.977672)
			(xy 275.418153 -289.011764) (xy 275.37765 -289.03972) (xy 275.333188 -289.060818) (xy 275.285917 -289.07451)
			(xy 275.237062 -289.080442) (xy 275.187887 -289.078461) (xy 275.139668 -289.068617) (xy 275.093652 -289.051165)
			(xy 275.051031 -289.026558) (xy 275.01291 -288.995433) (xy 274.980275 -288.958596) (xy 274.953972 -288.917)
			(xy 274.934681 -288.871724) (xy 274.922904 -288.82394) (xy 274.918944 -288.774886) (xy 270.780256 -288.774886)
			(xy 270.779761 -288.799493) (xy 270.771866 -288.84807) (xy 270.756282 -288.894751) (xy 270.733411 -288.938328)
			(xy 270.703846 -288.977672) (xy 270.668353 -289.011764) (xy 270.62785 -289.03972) (xy 270.583388 -289.060818)
			(xy 270.536117 -289.07451) (xy 270.487262 -289.080442) (xy 270.438087 -289.078461) (xy 270.389868 -289.068617)
			(xy 270.343852 -289.051165) (xy 270.301231 -289.026558) (xy 270.26311 -288.995433) (xy 270.230475 -288.958596)
			(xy 270.204172 -288.917) (xy 270.184881 -288.871724) (xy 270.173104 -288.82394) (xy 270.169144 -288.774886)
			(xy 269.830042 -288.774886) (xy 269.829547 -288.799493) (xy 269.821652 -288.84807) (xy 269.806068 -288.894751)
			(xy 269.783197 -288.938328) (xy 269.753632 -288.977672) (xy 269.718139 -289.011764) (xy 269.677636 -289.03972)
			(xy 269.633174 -289.060818) (xy 269.585903 -289.07451) (xy 269.537048 -289.080442) (xy 269.487873 -289.078461)
			(xy 269.439654 -289.068617) (xy 269.393638 -289.051165) (xy 269.351017 -289.026558) (xy 269.312896 -288.995433)
			(xy 269.280261 -288.958596) (xy 269.253958 -288.917) (xy 269.234667 -288.871724) (xy 269.22289 -288.82394)
			(xy 269.21893 -288.774886) (xy 268.880082 -288.774886) (xy 268.879587 -288.799493) (xy 268.871692 -288.84807)
			(xy 268.856108 -288.894751) (xy 268.833237 -288.938328) (xy 268.803672 -288.977672) (xy 268.768179 -289.011764)
			(xy 268.727676 -289.03972) (xy 268.683214 -289.060818) (xy 268.635943 -289.07451) (xy 268.587088 -289.080442)
			(xy 268.537913 -289.078461) (xy 268.489694 -289.068617) (xy 268.443678 -289.051165) (xy 268.401057 -289.026558)
			(xy 268.362936 -288.995433) (xy 268.330301 -288.958596) (xy 268.303998 -288.917) (xy 268.284707 -288.871724)
			(xy 268.27293 -288.82394) (xy 268.26897 -288.774886) (xy 253.172547 -288.774886) (xy 253.183397 -288.81095)
			(xy 253.191517 -288.866126) (xy 253.192026 -288.894012) (xy 253.191517 -288.921898) (xy 253.183397 -288.977074)
			(xy 253.167329 -289.030481) (xy 253.143657 -289.080978) (xy 253.112884 -289.127491) (xy 253.075667 -289.169028)
			(xy 253.032799 -289.204703) (xy 252.985193 -289.233757) (xy 252.933864 -289.255569) (xy 252.879907 -289.269675)
			(xy 252.82447 -289.275775) (xy 252.768736 -289.273738) (xy 252.713893 -289.263608) (xy 252.661109 -289.245601)
			(xy 252.611509 -289.2201) (xy 252.566151 -289.187649) (xy 252.526002 -289.14894) (xy 252.491916 -289.104797)
			(xy 252.46462 -289.056162) (xy 252.444697 -289.004071) (xy 252.432571 -288.949634) (xy 252.4285 -288.894012)
			(xy 251.348055 -288.894012) (xy 251.353327 -288.911534) (xy 251.361447 -288.96671) (xy 251.361956 -288.994596)
			(xy 251.361447 -289.022482) (xy 251.353327 -289.077658) (xy 251.337259 -289.131065) (xy 251.313587 -289.181562)
			(xy 251.282814 -289.228075) (xy 251.245597 -289.269612) (xy 251.202729 -289.305287) (xy 251.155123 -289.334341)
			(xy 251.103794 -289.356153) (xy 251.049837 -289.370259) (xy 250.9944 -289.376359) (xy 250.938666 -289.374322)
			(xy 250.883823 -289.364192) (xy 250.831039 -289.346185) (xy 250.781439 -289.320684) (xy 250.736081 -289.288233)
			(xy 250.695932 -289.249524) (xy 250.661846 -289.205381) (xy 250.63455 -289.156746) (xy 250.614627 -289.104655)
			(xy 250.602501 -289.050218) (xy 250.59843 -288.994596) (xy 245.38043 -288.994596) (xy 245.346381 -289.010144)
			(xy 245.294079 -289.025497) (xy 245.240125 -289.033251) (xy 245.21287 -289.033712) (xy 245.186268 -289.033205)
			(xy 245.133578 -289.025833) (xy 245.082424 -289.011208) (xy 245.033799 -288.989615) (xy 244.988648 -288.961473)
			(xy 244.947847 -288.927327) (xy 244.912189 -288.887842) (xy 244.896894 -288.866072) (xy 244.88856 -288.854592)
			(xy 244.866816 -288.836388) (xy 244.840903 -288.82487) (xy 244.81282 -288.82093) (xy 244.784737 -288.82487)
			(xy 244.758824 -288.836388) (xy 244.73708 -288.854592) (xy 244.728746 -288.866072) (xy 244.713438 -288.887832)
			(xy 244.677773 -288.927311) (xy 244.636972 -288.961455) (xy 244.591824 -288.989601) (xy 244.543205 -289.011205)
			(xy 244.492057 -289.025848) (xy 244.439371 -289.033246) (xy 244.41277 -289.033712) (xy 244.38552 -289.033216)
			(xy 244.331577 -289.025456) (xy 244.279286 -289.010099) (xy 244.229713 -288.987456) (xy 244.183867 -288.957989)
			(xy 244.142681 -288.922298) (xy 244.106993 -288.881109) (xy 244.07753 -288.835261) (xy 244.054891 -288.785686)
			(xy 244.039537 -288.733394) (xy 244.031782 -288.67945) (xy 234.5309 -288.67945) (xy 234.5309 -289.010598)
			(xy 234.531296 -289.020119) (xy 234.538255 -289.037844) (xy 234.55121 -289.051801) (xy 234.559602 -289.056318)
			(xy 234.58805 -289.070034) (xy 234.588304 -289.070034) (xy 234.619292 -289.085274) (xy 234.624571 -289.087648)
			(xy 234.635857 -289.09021) (xy 234.641644 -289.090354) (xy 234.677966 -289.090354) (xy 234.681974 -289.090287)
			(xy 234.689889 -289.089013) (xy 234.693714 -289.087814) (xy 234.701588 -289.085274) (xy 234.707938 -289.080702)
			(xy 234.732323 -289.063992) (xy 234.785167 -289.037503) (xy 234.841466 -289.019485) (xy 234.89987 -289.010369)
			(xy 234.929426 -289.009836) (xy 234.955033 -289.010232) (xy 235.005792 -289.017049) (xy 235.055181 -289.030599)
			(xy 235.102313 -289.050637) (xy 235.146339 -289.076802) (xy 235.166662 -289.092386) (xy 235.170472 -289.095434)
			(xy 235.175298 -289.097974) (xy 235.18077 -289.100647) (xy 235.19258 -289.103598) (xy 235.198666 -289.103816)
			(xy 235.231178 -289.103816) (xy 235.231178 -289.114992) (xy 235.291122 -289.114992) (xy 235.30814 -289.108642)
			(xy 235.315252 -289.102546) (xy 235.336129 -289.085154) (xy 235.38188 -289.055839) (xy 235.431328 -289.033314)
			(xy 235.483473 -289.018035) (xy 235.537258 -289.010313) (xy 235.564426 -289.009836) (xy 235.591673 -289.010324)
			(xy 235.645611 -289.018083) (xy 235.697897 -289.033438) (xy 235.747465 -289.056078) (xy 235.793307 -289.085542)
			(xy 235.834489 -289.121229) (xy 235.870174 -289.162414) (xy 235.899634 -289.208258) (xy 235.922271 -289.257827)
			(xy 235.937623 -289.310114) (xy 235.945378 -289.364053) (xy 235.945378 -289.418547) (xy 235.945378 -289.41855)
			(xy 236.509799 -289.41855) (xy 236.509799 -289.36405) (xy 236.517556 -289.310104) (xy 236.532911 -289.257811)
			(xy 236.555552 -289.208235) (xy 236.585017 -289.162387) (xy 236.620709 -289.121199) (xy 236.661898 -289.085509)
			(xy 236.707748 -289.056045) (xy 236.757324 -289.033406) (xy 236.809617 -289.018053) (xy 236.863564 -289.010298)
			(xy 236.890814 -289.009836) (xy 236.920938 -289.010402) (xy 236.980434 -289.019885) (xy 237.037702 -289.038597)
			(xy 237.091319 -289.066074) (xy 237.139953 -289.101633) (xy 237.161578 -289.122612) (xy 237.16869 -289.129978)
			(xy 237.187486 -289.137598) (xy 237.279942 -289.137598) (xy 237.298738 -289.129978) (xy 237.30585 -289.122612)
			(xy 237.327476 -289.101633) (xy 237.376104 -289.066064) (xy 237.42972 -289.038583) (xy 237.48699 -289.019875)
			(xy 237.54649 -289.010404) (xy 237.576614 -289.009836) (xy 237.603868 -289.010235) (xy 237.65782 -289.017994)
			(xy 237.710119 -289.033352) (xy 237.7597 -289.055997) (xy 237.805554 -289.085467) (xy 237.846748 -289.121162)
			(xy 237.882442 -289.162357) (xy 237.91191 -289.208212) (xy 237.934553 -289.257794) (xy 237.949909 -289.310094)
			(xy 237.957666 -289.364046) (xy 237.957666 -289.418554) (xy 237.949909 -289.472506) (xy 237.934553 -289.524806)
			(xy 237.91191 -289.574388) (xy 237.882442 -289.620243) (xy 237.846748 -289.661438) (xy 237.805554 -289.697133)
			(xy 237.7597 -289.726603) (xy 237.710119 -289.749248) (xy 237.685097 -289.756596) (xy 249.695714 -289.756596)
			(xy 249.699785 -289.700974) (xy 249.711911 -289.646537) (xy 249.731834 -289.594446) (xy 249.75913 -289.545811)
			(xy 249.793216 -289.501668) (xy 249.833365 -289.462959) (xy 249.878723 -289.430508) (xy 249.928323 -289.405007)
			(xy 249.981107 -289.387) (xy 250.03595 -289.37687) (xy 250.091684 -289.374833) (xy 250.147121 -289.380933)
			(xy 250.201078 -289.395039) (xy 250.252407 -289.416851) (xy 250.300013 -289.445905) (xy 250.342881 -289.48158)
			(xy 250.380098 -289.523117) (xy 250.410871 -289.56963) (xy 250.434543 -289.620127) (xy 250.445339 -289.656012)
			(xy 251.525784 -289.656012) (xy 251.529855 -289.60039) (xy 251.541981 -289.545953) (xy 251.561904 -289.493862)
			(xy 251.5892 -289.445227) (xy 251.623286 -289.401084) (xy 251.663435 -289.362375) (xy 251.708793 -289.329924)
			(xy 251.758393 -289.304423) (xy 251.811177 -289.286416) (xy 251.86602 -289.276286) (xy 251.921754 -289.274249)
			(xy 251.977191 -289.280349) (xy 252.031148 -289.294455) (xy 252.082477 -289.316267) (xy 252.130083 -289.345321)
			(xy 252.172951 -289.380996) (xy 252.210168 -289.422533) (xy 252.240941 -289.469046) (xy 252.264613 -289.519543)
			(xy 252.268455 -289.532314) (xy 258.01142 -289.532314) (xy 258.015491 -289.476692) (xy 258.027617 -289.422255)
			(xy 258.04754 -289.370164) (xy 258.074836 -289.321529) (xy 258.108922 -289.277386) (xy 258.149071 -289.238677)
			(xy 258.194429 -289.206226) (xy 258.244029 -289.180725) (xy 258.296813 -289.162718) (xy 258.351656 -289.152588)
			(xy 258.40739 -289.150551) (xy 258.462827 -289.156651) (xy 258.516784 -289.170757) (xy 258.568113 -289.192569)
			(xy 258.615719 -289.221623) (xy 258.658587 -289.257298) (xy 258.695804 -289.298835) (xy 258.726577 -289.345348)
			(xy 258.750249 -289.395845) (xy 258.766317 -289.449252) (xy 258.774437 -289.504428) (xy 258.774946 -289.532314)
			(xy 259.486906 -289.532314) (xy 259.490977 -289.476692) (xy 259.503103 -289.422255) (xy 259.523026 -289.370164)
			(xy 259.550322 -289.321529) (xy 259.584408 -289.277386) (xy 259.624557 -289.238677) (xy 259.669915 -289.206226)
			(xy 259.719515 -289.180725) (xy 259.772299 -289.162718) (xy 259.827142 -289.152588) (xy 259.882876 -289.150551)
			(xy 259.938313 -289.156651) (xy 259.99227 -289.170757) (xy 260.043599 -289.192569) (xy 260.091205 -289.221623)
			(xy 260.134073 -289.257298) (xy 260.17129 -289.298835) (xy 260.202063 -289.345348) (xy 260.225735 -289.395845)
			(xy 260.241803 -289.449252) (xy 260.249923 -289.504428) (xy 260.250432 -289.532314) (xy 260.375906 -289.532314)
			(xy 260.379977 -289.476692) (xy 260.392103 -289.422255) (xy 260.412026 -289.370164) (xy 260.439322 -289.321529)
			(xy 260.473408 -289.277386) (xy 260.513557 -289.238677) (xy 260.558915 -289.206226) (xy 260.608515 -289.180725)
			(xy 260.661299 -289.162718) (xy 260.716142 -289.152588) (xy 260.771876 -289.150551) (xy 260.827313 -289.156651)
			(xy 260.88127 -289.170757) (xy 260.932599 -289.192569) (xy 260.980205 -289.221623) (xy 261.023073 -289.257298)
			(xy 261.06029 -289.298835) (xy 261.091063 -289.345348) (xy 261.114735 -289.395845) (xy 261.130803 -289.449252)
			(xy 261.138923 -289.504428) (xy 261.139432 -289.532314) (xy 261.138923 -289.5602) (xy 261.130803 -289.615376)
			(xy 261.114735 -289.668783) (xy 261.091063 -289.71928) (xy 261.06029 -289.765793) (xy 261.023073 -289.80733)
			(xy 260.980205 -289.843005) (xy 260.932599 -289.872059) (xy 260.88127 -289.893871) (xy 260.827313 -289.907977)
			(xy 260.771876 -289.914077) (xy 260.716142 -289.91204) (xy 260.661299 -289.90191) (xy 260.608515 -289.883903)
			(xy 260.558915 -289.858402) (xy 260.513557 -289.825951) (xy 260.473408 -289.787242) (xy 260.439322 -289.743099)
			(xy 260.412026 -289.694464) (xy 260.392103 -289.642373) (xy 260.379977 -289.587936) (xy 260.375906 -289.532314)
			(xy 260.250432 -289.532314) (xy 260.249923 -289.5602) (xy 260.241803 -289.615376) (xy 260.225735 -289.668783)
			(xy 260.202063 -289.71928) (xy 260.17129 -289.765793) (xy 260.134073 -289.80733) (xy 260.091205 -289.843005)
			(xy 260.043599 -289.872059) (xy 259.99227 -289.893871) (xy 259.938313 -289.907977) (xy 259.882876 -289.914077)
			(xy 259.827142 -289.91204) (xy 259.772299 -289.90191) (xy 259.719515 -289.883903) (xy 259.669915 -289.858402)
			(xy 259.624557 -289.825951) (xy 259.584408 -289.787242) (xy 259.550322 -289.743099) (xy 259.523026 -289.694464)
			(xy 259.503103 -289.642373) (xy 259.490977 -289.587936) (xy 259.486906 -289.532314) (xy 258.774946 -289.532314)
			(xy 258.774437 -289.5602) (xy 258.766317 -289.615376) (xy 258.750249 -289.668783) (xy 258.726577 -289.71928)
			(xy 258.695804 -289.765793) (xy 258.658587 -289.80733) (xy 258.615719 -289.843005) (xy 258.568113 -289.872059)
			(xy 258.516784 -289.893871) (xy 258.462827 -289.907977) (xy 258.40739 -289.914077) (xy 258.351656 -289.91204)
			(xy 258.296813 -289.90191) (xy 258.244029 -289.883903) (xy 258.194429 -289.858402) (xy 258.149071 -289.825951)
			(xy 258.108922 -289.787242) (xy 258.074836 -289.743099) (xy 258.04754 -289.694464) (xy 258.027617 -289.642373)
			(xy 258.015491 -289.587936) (xy 258.01142 -289.532314) (xy 252.268455 -289.532314) (xy 252.280681 -289.57295)
			(xy 252.288801 -289.628126) (xy 252.28931 -289.656012) (xy 252.288801 -289.683898) (xy 252.280681 -289.739074)
			(xy 252.264613 -289.792481) (xy 252.240941 -289.842978) (xy 252.210168 -289.889491) (xy 252.172951 -289.931028)
			(xy 252.130083 -289.966703) (xy 252.082477 -289.995757) (xy 252.031148 -290.017569) (xy 251.977191 -290.031675)
			(xy 251.921754 -290.037775) (xy 251.86602 -290.035738) (xy 251.811177 -290.025608) (xy 251.758393 -290.007601)
			(xy 251.708793 -289.9821) (xy 251.663435 -289.949649) (xy 251.623286 -289.91094) (xy 251.5892 -289.866797)
			(xy 251.561904 -289.818162) (xy 251.541981 -289.766071) (xy 251.529855 -289.711634) (xy 251.525784 -289.656012)
			(xy 250.445339 -289.656012) (xy 250.450611 -289.673534) (xy 250.458731 -289.72871) (xy 250.45924 -289.756596)
			(xy 250.458731 -289.784482) (xy 250.450611 -289.839658) (xy 250.434543 -289.893065) (xy 250.410871 -289.943562)
			(xy 250.380098 -289.990075) (xy 250.342881 -290.031612) (xy 250.300013 -290.067287) (xy 250.252407 -290.096341)
			(xy 250.201078 -290.118153) (xy 250.147121 -290.132259) (xy 250.091684 -290.138359) (xy 250.03595 -290.136322)
			(xy 249.981107 -290.126192) (xy 249.928323 -290.108185) (xy 249.878723 -290.082684) (xy 249.833365 -290.050233)
			(xy 249.793216 -290.011524) (xy 249.75913 -289.967381) (xy 249.731834 -289.918746) (xy 249.711911 -289.866655)
			(xy 249.699785 -289.812218) (xy 249.695714 -289.756596) (xy 237.685097 -289.756596) (xy 237.65782 -289.764606)
			(xy 237.603868 -289.772365) (xy 237.576614 -289.772852) (xy 237.546491 -289.772272) (xy 237.486995 -289.762793)
			(xy 237.429727 -289.744084) (xy 237.37611 -289.716611) (xy 237.327475 -289.681054) (xy 237.30585 -289.660076)
			(xy 237.298738 -289.65271) (xy 237.279942 -289.64509) (xy 237.187486 -289.64509) (xy 237.16869 -289.65271)
			(xy 237.161578 -289.660076) (xy 237.139938 -289.68104) (xy 237.091314 -289.716611) (xy 237.037701 -289.744095)
			(xy 236.980434 -289.762807) (xy 236.920937 -289.772282) (xy 236.890814 -289.772852) (xy 236.863564 -289.772302)
			(xy 236.809617 -289.764547) (xy 236.757324 -289.749194) (xy 236.707748 -289.726555) (xy 236.661898 -289.697091)
			(xy 236.620709 -289.661401) (xy 236.585017 -289.620213) (xy 236.555552 -289.574365) (xy 236.532911 -289.524789)
			(xy 236.517556 -289.472496) (xy 236.509799 -289.41855) (xy 235.945378 -289.41855) (xy 235.937623 -289.472486)
			(xy 235.922271 -289.524773) (xy 235.899634 -289.574342) (xy 235.870174 -289.620186) (xy 235.834489 -289.661371)
			(xy 235.793307 -289.697058) (xy 235.747465 -289.726522) (xy 235.697897 -289.749162) (xy 235.645611 -289.764517)
			(xy 235.591673 -289.772276) (xy 235.564426 -289.772852) (xy 235.538817 -289.77246) (xy 235.488056 -289.765648)
			(xy 235.438663 -289.752104) (xy 235.391527 -289.73207) (xy 235.347497 -289.705908) (xy 235.32719 -289.690302)
			(xy 235.32338 -289.687254) (xy 235.318554 -289.684714) (xy 235.313083 -289.682036) (xy 235.301273 -289.679074)
			(xy 235.295186 -289.678872) (xy 235.262674 -289.678872) (xy 235.262674 -289.667696) (xy 235.20273 -289.667696)
			(xy 235.185712 -289.674046) (xy 235.1786 -289.680142) (xy 235.157722 -289.697532) (xy 235.111971 -289.726842)
			(xy 235.062522 -289.749362) (xy 235.010378 -289.764634) (xy 234.956593 -289.77235) (xy 234.929426 -289.772852)
			(xy 234.916561 -289.77279) (xy 234.890885 -289.771138) (xy 234.878118 -289.76955) (xy 234.872784 -289.768788)
			(xy 234.848644 -289.764769) (xy 234.801584 -289.751344) (xy 234.756629 -289.732007) (xy 234.714517 -289.707077)
			(xy 234.694984 -289.692334) (xy 234.6833 -289.683444) (xy 234.654598 -289.680396) (xy 234.559348 -289.726878)
			(xy 234.55101 -289.731366) (xy 234.538173 -289.745266) (xy 234.531272 -289.762884) (xy 234.5309 -289.772344)
			(xy 234.5309 -290.294314) (xy 263.537954 -290.294314) (xy 263.53852 -290.264933) (xy 263.547548 -290.206868)
			(xy 263.565376 -290.150875) (xy 263.591583 -290.09828) (xy 263.625547 -290.050328) (xy 263.666466 -290.008154)
			(xy 263.689592 -289.990022) (xy 263.69899 -289.982656) (xy 263.709404 -289.962082) (xy 263.710928 -289.858196)
			(xy 263.701022 -289.837114) (xy 263.691878 -289.829748) (xy 263.670018 -289.811556) (xy 263.63148 -289.769733)
			(xy 263.599575 -289.722655) (xy 263.57501 -289.671363) (xy 263.558329 -289.616993) (xy 263.549902 -289.56075)
			(xy 263.549384 -289.532314) (xy 263.54987 -289.505063) (xy 263.557626 -289.451115) (xy 263.572981 -289.39882)
			(xy 263.595623 -289.349243) (xy 263.625089 -289.303393) (xy 263.66078 -289.262202) (xy 263.701971 -289.226511)
			(xy 263.747821 -289.197045) (xy 263.797398 -289.174403) (xy 263.849693 -289.159048) (xy 263.903641 -289.151292)
			(xy 263.958143 -289.151292) (xy 264.012091 -289.159048) (xy 264.064386 -289.174403) (xy 264.113963 -289.197045)
			(xy 264.159813 -289.226511) (xy 264.201004 -289.262202) (xy 264.236695 -289.303393) (xy 264.266161 -289.349243)
			(xy 264.288803 -289.39882) (xy 264.304158 -289.451115) (xy 264.311914 -289.505063) (xy 264.3124 -289.532314)
			(xy 264.311872 -289.561697) (xy 264.302839 -289.619764) (xy 264.285005 -289.675759) (xy 264.260539 -289.724846)
			(xy 268.26897 -289.724846) (xy 268.27293 -289.675792) (xy 268.284707 -289.628008) (xy 268.303998 -289.582732)
			(xy 268.330301 -289.541136) (xy 268.362936 -289.504299) (xy 268.401057 -289.473174) (xy 268.443678 -289.448567)
			(xy 268.489694 -289.431115) (xy 268.537913 -289.421271) (xy 268.587088 -289.41929) (xy 268.635943 -289.425222)
			(xy 268.683214 -289.438914) (xy 268.727676 -289.460012) (xy 268.768179 -289.487968) (xy 268.803672 -289.52206)
			(xy 268.833237 -289.561404) (xy 268.856108 -289.604981) (xy 268.871692 -289.651662) (xy 268.879587 -289.700239)
			(xy 268.880082 -289.724846) (xy 269.21893 -289.724846) (xy 269.22289 -289.675792) (xy 269.234667 -289.628008)
			(xy 269.253958 -289.582732) (xy 269.280261 -289.541136) (xy 269.312896 -289.504299) (xy 269.351017 -289.473174)
			(xy 269.393638 -289.448567) (xy 269.439654 -289.431115) (xy 269.487873 -289.421271) (xy 269.537048 -289.41929)
			(xy 269.585903 -289.425222) (xy 269.633174 -289.438914) (xy 269.677636 -289.460012) (xy 269.718139 -289.487968)
			(xy 269.753632 -289.52206) (xy 269.783197 -289.561404) (xy 269.806068 -289.604981) (xy 269.821652 -289.651662)
			(xy 269.829547 -289.700239) (xy 269.830042 -289.724846) (xy 270.169144 -289.724846) (xy 270.173104 -289.675792)
			(xy 270.184881 -289.628008) (xy 270.204172 -289.582732) (xy 270.230475 -289.541136) (xy 270.26311 -289.504299)
			(xy 270.301231 -289.473174) (xy 270.343852 -289.448567) (xy 270.389868 -289.431115) (xy 270.438087 -289.421271)
			(xy 270.487262 -289.41929) (xy 270.536117 -289.425222) (xy 270.583388 -289.438914) (xy 270.62785 -289.460012)
			(xy 270.668353 -289.487968) (xy 270.703846 -289.52206) (xy 270.733411 -289.561404) (xy 270.756282 -289.604981)
			(xy 270.771866 -289.651662) (xy 270.779761 -289.700239) (xy 270.780256 -289.724846) (xy 271.119104 -289.724846)
			(xy 271.123064 -289.675792) (xy 271.134841 -289.628008) (xy 271.154132 -289.582732) (xy 271.180435 -289.541136)
			(xy 271.21307 -289.504299) (xy 271.251191 -289.473174) (xy 271.293812 -289.448567) (xy 271.339828 -289.431115)
			(xy 271.388047 -289.421271) (xy 271.437222 -289.41929) (xy 271.486077 -289.425222) (xy 271.533348 -289.438914)
			(xy 271.57781 -289.460012) (xy 271.618313 -289.487968) (xy 271.653806 -289.52206) (xy 271.683371 -289.561404)
			(xy 271.706242 -289.604981) (xy 271.721826 -289.651662) (xy 271.729721 -289.700239) (xy 271.730216 -289.724846)
			(xy 272.069064 -289.724846) (xy 272.073024 -289.675792) (xy 272.084801 -289.628008) (xy 272.104092 -289.582732)
			(xy 272.130395 -289.541136) (xy 272.16303 -289.504299) (xy 272.201151 -289.473174) (xy 272.243772 -289.448567)
			(xy 272.289788 -289.431115) (xy 272.338007 -289.421271) (xy 272.387182 -289.41929) (xy 272.436037 -289.425222)
			(xy 272.483308 -289.438914) (xy 272.52777 -289.460012) (xy 272.568273 -289.487968) (xy 272.603766 -289.52206)
			(xy 272.633331 -289.561404) (xy 272.656202 -289.604981) (xy 272.671786 -289.651662) (xy 272.679681 -289.700239)
			(xy 272.680176 -289.724846) (xy 273.019024 -289.724846) (xy 273.022984 -289.675792) (xy 273.034761 -289.628008)
			(xy 273.054052 -289.582732) (xy 273.080355 -289.541136) (xy 273.11299 -289.504299) (xy 273.151111 -289.473174)
			(xy 273.193732 -289.448567) (xy 273.239748 -289.431115) (xy 273.287967 -289.421271) (xy 273.337142 -289.41929)
			(xy 273.385997 -289.425222) (xy 273.433268 -289.438914) (xy 273.47773 -289.460012) (xy 273.518233 -289.487968)
			(xy 273.553726 -289.52206) (xy 273.583291 -289.561404) (xy 273.606162 -289.604981) (xy 273.621746 -289.651662)
			(xy 273.629641 -289.700239) (xy 273.630136 -289.724846) (xy 273.968984 -289.724846) (xy 273.972944 -289.675792)
			(xy 273.984721 -289.628008) (xy 274.004012 -289.582732) (xy 274.030315 -289.541136) (xy 274.06295 -289.504299)
			(xy 274.101071 -289.473174) (xy 274.143692 -289.448567) (xy 274.189708 -289.431115) (xy 274.237927 -289.421271)
			(xy 274.287102 -289.41929) (xy 274.335957 -289.425222) (xy 274.383228 -289.438914) (xy 274.42769 -289.460012)
			(xy 274.468193 -289.487968) (xy 274.503686 -289.52206) (xy 274.533251 -289.561404) (xy 274.556122 -289.604981)
			(xy 274.571706 -289.651662) (xy 274.579601 -289.700239) (xy 274.580096 -289.724846) (xy 274.918944 -289.724846)
			(xy 274.922904 -289.675792) (xy 274.934681 -289.628008) (xy 274.953972 -289.582732) (xy 274.980275 -289.541136)
			(xy 275.01291 -289.504299) (xy 275.051031 -289.473174) (xy 275.093652 -289.448567) (xy 275.139668 -289.431115)
			(xy 275.187887 -289.421271) (xy 275.237062 -289.41929) (xy 275.285917 -289.425222) (xy 275.333188 -289.438914)
			(xy 275.37765 -289.460012) (xy 275.418153 -289.487968) (xy 275.453646 -289.52206) (xy 275.483211 -289.561404)
			(xy 275.506082 -289.604981) (xy 275.521666 -289.651662) (xy 275.529561 -289.700239) (xy 275.530056 -289.724846)
			(xy 275.868904 -289.724846) (xy 275.872864 -289.675792) (xy 275.884641 -289.628008) (xy 275.903932 -289.582732)
			(xy 275.930235 -289.541136) (xy 275.96287 -289.504299) (xy 276.000991 -289.473174) (xy 276.043612 -289.448567)
			(xy 276.089628 -289.431115) (xy 276.137847 -289.421271) (xy 276.187022 -289.41929) (xy 276.235877 -289.425222)
			(xy 276.283148 -289.438914) (xy 276.32761 -289.460012) (xy 276.368113 -289.487968) (xy 276.403606 -289.52206)
			(xy 276.433171 -289.561404) (xy 276.456042 -289.604981) (xy 276.471626 -289.651662) (xy 276.479521 -289.700239)
			(xy 276.480016 -289.724846) (xy 276.819118 -289.724846) (xy 276.823078 -289.675792) (xy 276.834855 -289.628008)
			(xy 276.854146 -289.582732) (xy 276.880449 -289.541136) (xy 276.913084 -289.504299) (xy 276.951205 -289.473174)
			(xy 276.993826 -289.448567) (xy 277.039842 -289.431115) (xy 277.088061 -289.421271) (xy 277.137236 -289.41929)
			(xy 277.186091 -289.425222) (xy 277.233362 -289.438914) (xy 277.277824 -289.460012) (xy 277.318327 -289.487968)
			(xy 277.35382 -289.52206) (xy 277.383385 -289.561404) (xy 277.406256 -289.604981) (xy 277.42184 -289.651662)
			(xy 277.429735 -289.700239) (xy 277.43023 -289.724846) (xy 277.769078 -289.724846) (xy 277.773038 -289.675792)
			(xy 277.784815 -289.628008) (xy 277.804106 -289.582732) (xy 277.830409 -289.541136) (xy 277.863044 -289.504299)
			(xy 277.901165 -289.473174) (xy 277.943786 -289.448567) (xy 277.989802 -289.431115) (xy 278.038021 -289.421271)
			(xy 278.087196 -289.41929) (xy 278.136051 -289.425222) (xy 278.183322 -289.438914) (xy 278.227784 -289.460012)
			(xy 278.268287 -289.487968) (xy 278.30378 -289.52206) (xy 278.333345 -289.561404) (xy 278.356216 -289.604981)
			(xy 278.3718 -289.651662) (xy 278.379695 -289.700239) (xy 278.38019 -289.724846) (xy 278.719038 -289.724846)
			(xy 278.722998 -289.675792) (xy 278.734775 -289.628008) (xy 278.754066 -289.582732) (xy 278.780369 -289.541136)
			(xy 278.813004 -289.504299) (xy 278.851125 -289.473174) (xy 278.893746 -289.448567) (xy 278.939762 -289.431115)
			(xy 278.987981 -289.421271) (xy 279.037156 -289.41929) (xy 279.086011 -289.425222) (xy 279.133282 -289.438914)
			(xy 279.177744 -289.460012) (xy 279.218247 -289.487968) (xy 279.25374 -289.52206) (xy 279.283305 -289.561404)
			(xy 279.306176 -289.604981) (xy 279.32176 -289.651662) (xy 279.329655 -289.700239) (xy 279.33015 -289.724846)
			(xy 279.668998 -289.724846) (xy 279.672958 -289.675792) (xy 279.684735 -289.628008) (xy 279.704026 -289.582732)
			(xy 279.730329 -289.541136) (xy 279.762964 -289.504299) (xy 279.801085 -289.473174) (xy 279.843706 -289.448567)
			(xy 279.889722 -289.431115) (xy 279.937941 -289.421271) (xy 279.987116 -289.41929) (xy 280.035971 -289.425222)
			(xy 280.083242 -289.438914) (xy 280.127704 -289.460012) (xy 280.168207 -289.487968) (xy 280.2037 -289.52206)
			(xy 280.233265 -289.561404) (xy 280.256136 -289.604981) (xy 280.27172 -289.651662) (xy 280.279615 -289.700239)
			(xy 280.28011 -289.724846) (xy 280.618958 -289.724846) (xy 280.622918 -289.675792) (xy 280.634695 -289.628008)
			(xy 280.653986 -289.582732) (xy 280.680289 -289.541136) (xy 280.712924 -289.504299) (xy 280.751045 -289.473174)
			(xy 280.793666 -289.448567) (xy 280.839682 -289.431115) (xy 280.887901 -289.421271) (xy 280.937076 -289.41929)
			(xy 280.985931 -289.425222) (xy 281.033202 -289.438914) (xy 281.077664 -289.460012) (xy 281.118167 -289.487968)
			(xy 281.15366 -289.52206) (xy 281.183225 -289.561404) (xy 281.206096 -289.604981) (xy 281.22168 -289.651662)
			(xy 281.229575 -289.700239) (xy 281.23007 -289.724846) (xy 281.568918 -289.724846) (xy 281.572878 -289.675792)
			(xy 281.584655 -289.628008) (xy 281.603946 -289.582732) (xy 281.630249 -289.541136) (xy 281.662884 -289.504299)
			(xy 281.701005 -289.473174) (xy 281.743626 -289.448567) (xy 281.789642 -289.431115) (xy 281.837861 -289.421271)
			(xy 281.887036 -289.41929) (xy 281.935891 -289.425222) (xy 281.983162 -289.438914) (xy 282.027624 -289.460012)
			(xy 282.068127 -289.487968) (xy 282.10362 -289.52206) (xy 282.133185 -289.561404) (xy 282.156056 -289.604981)
			(xy 282.17164 -289.651662) (xy 282.179535 -289.700239) (xy 282.18003 -289.724846) (xy 282.519132 -289.724846)
			(xy 282.523092 -289.675792) (xy 282.534869 -289.628008) (xy 282.55416 -289.582732) (xy 282.580463 -289.541136)
			(xy 282.613098 -289.504299) (xy 282.651219 -289.473174) (xy 282.69384 -289.448567) (xy 282.739856 -289.431115)
			(xy 282.788075 -289.421271) (xy 282.83725 -289.41929) (xy 282.886105 -289.425222) (xy 282.933376 -289.438914)
			(xy 282.977838 -289.460012) (xy 283.018341 -289.487968) (xy 283.053834 -289.52206) (xy 283.083399 -289.561404)
			(xy 283.10627 -289.604981) (xy 283.121854 -289.651662) (xy 283.129749 -289.700239) (xy 283.130244 -289.724846)
			(xy 283.469092 -289.724846) (xy 283.473052 -289.675792) (xy 283.484829 -289.628008) (xy 283.50412 -289.582732)
			(xy 283.530423 -289.541136) (xy 283.563058 -289.504299) (xy 283.601179 -289.473174) (xy 283.6438 -289.448567)
			(xy 283.689816 -289.431115) (xy 283.738035 -289.421271) (xy 283.78721 -289.41929) (xy 283.836065 -289.425222)
			(xy 283.883336 -289.438914) (xy 283.927798 -289.460012) (xy 283.968301 -289.487968) (xy 284.003794 -289.52206)
			(xy 284.033359 -289.561404) (xy 284.05623 -289.604981) (xy 284.071814 -289.651662) (xy 284.079709 -289.700239)
			(xy 284.080204 -289.724846) (xy 284.419052 -289.724846) (xy 284.423012 -289.675792) (xy 284.434789 -289.628008)
			(xy 284.45408 -289.582732) (xy 284.480383 -289.541136) (xy 284.513018 -289.504299) (xy 284.551139 -289.473174)
			(xy 284.59376 -289.448567) (xy 284.639776 -289.431115) (xy 284.687995 -289.421271) (xy 284.73717 -289.41929)
			(xy 284.786025 -289.425222) (xy 284.833296 -289.438914) (xy 284.877758 -289.460012) (xy 284.918261 -289.487968)
			(xy 284.953754 -289.52206) (xy 284.983319 -289.561404) (xy 285.00619 -289.604981) (xy 285.021774 -289.651662)
			(xy 285.029669 -289.700239) (xy 285.030164 -289.724846) (xy 285.369012 -289.724846) (xy 285.372972 -289.675792)
			(xy 285.384749 -289.628008) (xy 285.40404 -289.582732) (xy 285.430343 -289.541136) (xy 285.462978 -289.504299)
			(xy 285.501099 -289.473174) (xy 285.54372 -289.448567) (xy 285.589736 -289.431115) (xy 285.637955 -289.421271)
			(xy 285.68713 -289.41929) (xy 285.735985 -289.425222) (xy 285.783256 -289.438914) (xy 285.827718 -289.460012)
			(xy 285.868221 -289.487968) (xy 285.903714 -289.52206) (xy 285.933279 -289.561404) (xy 285.95615 -289.604981)
			(xy 285.971734 -289.651662) (xy 285.979629 -289.700239) (xy 285.980124 -289.724846) (xy 286.318972 -289.724846)
			(xy 286.322932 -289.675792) (xy 286.334709 -289.628008) (xy 286.354 -289.582732) (xy 286.380303 -289.541136)
			(xy 286.412938 -289.504299) (xy 286.451059 -289.473174) (xy 286.49368 -289.448567) (xy 286.539696 -289.431115)
			(xy 286.587915 -289.421271) (xy 286.63709 -289.41929) (xy 286.685945 -289.425222) (xy 286.733216 -289.438914)
			(xy 286.777678 -289.460012) (xy 286.818181 -289.487968) (xy 286.853674 -289.52206) (xy 286.883239 -289.561404)
			(xy 286.90611 -289.604981) (xy 286.921694 -289.651662) (xy 286.929589 -289.700239) (xy 286.930084 -289.724846)
			(xy 287.268932 -289.724846) (xy 287.272892 -289.675792) (xy 287.284669 -289.628008) (xy 287.30396 -289.582732)
			(xy 287.330263 -289.541136) (xy 287.362898 -289.504299) (xy 287.401019 -289.473174) (xy 287.44364 -289.448567)
			(xy 287.489656 -289.431115) (xy 287.537875 -289.421271) (xy 287.58705 -289.41929) (xy 287.635905 -289.425222)
			(xy 287.683176 -289.438914) (xy 287.727638 -289.460012) (xy 287.768141 -289.487968) (xy 287.803634 -289.52206)
			(xy 287.833199 -289.561404) (xy 287.85607 -289.604981) (xy 287.871654 -289.651662) (xy 287.879549 -289.700239)
			(xy 287.880044 -289.724846) (xy 288.218892 -289.724846) (xy 288.222852 -289.675792) (xy 288.234629 -289.628008)
			(xy 288.25392 -289.582732) (xy 288.280223 -289.541136) (xy 288.312858 -289.504299) (xy 288.350979 -289.473174)
			(xy 288.3936 -289.448567) (xy 288.439616 -289.431115) (xy 288.487835 -289.421271) (xy 288.53701 -289.41929)
			(xy 288.585865 -289.425222) (xy 288.633136 -289.438914) (xy 288.677598 -289.460012) (xy 288.718101 -289.487968)
			(xy 288.753594 -289.52206) (xy 288.783159 -289.561404) (xy 288.80603 -289.604981) (xy 288.821614 -289.651662)
			(xy 288.829509 -289.700239) (xy 288.830004 -289.724846) (xy 289.169106 -289.724846) (xy 289.173066 -289.675792)
			(xy 289.184843 -289.628008) (xy 289.204134 -289.582732) (xy 289.230437 -289.541136) (xy 289.263072 -289.504299)
			(xy 289.301193 -289.473174) (xy 289.343814 -289.448567) (xy 289.38983 -289.431115) (xy 289.438049 -289.421271)
			(xy 289.487224 -289.41929) (xy 289.536079 -289.425222) (xy 289.58335 -289.438914) (xy 289.627812 -289.460012)
			(xy 289.668315 -289.487968) (xy 289.703808 -289.52206) (xy 289.733373 -289.561404) (xy 289.756244 -289.604981)
			(xy 289.771828 -289.651662) (xy 289.779723 -289.700239) (xy 289.780218 -289.724846) (xy 290.119066 -289.724846)
			(xy 290.123026 -289.675792) (xy 290.134803 -289.628008) (xy 290.154094 -289.582732) (xy 290.180397 -289.541136)
			(xy 290.213032 -289.504299) (xy 290.251153 -289.473174) (xy 290.293774 -289.448567) (xy 290.33979 -289.431115)
			(xy 290.388009 -289.421271) (xy 290.437184 -289.41929) (xy 290.486039 -289.425222) (xy 290.53331 -289.438914)
			(xy 290.577772 -289.460012) (xy 290.618275 -289.487968) (xy 290.653768 -289.52206) (xy 290.683333 -289.561404)
			(xy 290.706204 -289.604981) (xy 290.721788 -289.651662) (xy 290.729683 -289.700239) (xy 290.730178 -289.724846)
			(xy 292.018986 -289.724846) (xy 292.022946 -289.675792) (xy 292.034723 -289.628008) (xy 292.054014 -289.582732)
			(xy 292.080317 -289.541136) (xy 292.112952 -289.504299) (xy 292.151073 -289.473174) (xy 292.193694 -289.448567)
			(xy 292.23971 -289.431115) (xy 292.287929 -289.421271) (xy 292.337104 -289.41929) (xy 292.385959 -289.425222)
			(xy 292.43323 -289.438914) (xy 292.477692 -289.460012) (xy 292.518195 -289.487968) (xy 292.553688 -289.52206)
			(xy 292.583253 -289.561404) (xy 292.606124 -289.604981) (xy 292.621708 -289.651662) (xy 292.629603 -289.700239)
			(xy 292.630098 -289.724846) (xy 292.968946 -289.724846) (xy 292.972906 -289.675792) (xy 292.984683 -289.628008)
			(xy 293.003974 -289.582732) (xy 293.030277 -289.541136) (xy 293.062912 -289.504299) (xy 293.101033 -289.473174)
			(xy 293.143654 -289.448567) (xy 293.18967 -289.431115) (xy 293.237889 -289.421271) (xy 293.287064 -289.41929)
			(xy 293.335919 -289.425222) (xy 293.38319 -289.438914) (xy 293.427652 -289.460012) (xy 293.468155 -289.487968)
			(xy 293.503648 -289.52206) (xy 293.533213 -289.561404) (xy 293.556084 -289.604981) (xy 293.571668 -289.651662)
			(xy 293.579563 -289.700239) (xy 293.580058 -289.724846) (xy 293.918906 -289.724846) (xy 293.922866 -289.675792)
			(xy 293.934643 -289.628008) (xy 293.953934 -289.582732) (xy 293.980237 -289.541136) (xy 294.012872 -289.504299)
			(xy 294.050993 -289.473174) (xy 294.093614 -289.448567) (xy 294.13963 -289.431115) (xy 294.187849 -289.421271)
			(xy 294.237024 -289.41929) (xy 294.285879 -289.425222) (xy 294.33315 -289.438914) (xy 294.377612 -289.460012)
			(xy 294.418115 -289.487968) (xy 294.453608 -289.52206) (xy 294.483173 -289.561404) (xy 294.506044 -289.604981)
			(xy 294.521628 -289.651662) (xy 294.529523 -289.700239) (xy 294.530018 -289.724846) (xy 294.86912 -289.724846)
			(xy 294.87308 -289.675792) (xy 294.884857 -289.628008) (xy 294.904148 -289.582732) (xy 294.930451 -289.541136)
			(xy 294.963086 -289.504299) (xy 295.001207 -289.473174) (xy 295.043828 -289.448567) (xy 295.089844 -289.431115)
			(xy 295.138063 -289.421271) (xy 295.187238 -289.41929) (xy 295.236093 -289.425222) (xy 295.283364 -289.438914)
			(xy 295.327826 -289.460012) (xy 295.368329 -289.487968) (xy 295.403822 -289.52206) (xy 295.433387 -289.561404)
			(xy 295.456258 -289.604981) (xy 295.471842 -289.651662) (xy 295.479737 -289.700239) (xy 295.480232 -289.724846)
			(xy 295.81908 -289.724846) (xy 295.82304 -289.675792) (xy 295.834817 -289.628008) (xy 295.854108 -289.582732)
			(xy 295.880411 -289.541136) (xy 295.913046 -289.504299) (xy 295.951167 -289.473174) (xy 295.993788 -289.448567)
			(xy 296.039804 -289.431115) (xy 296.088023 -289.421271) (xy 296.137198 -289.41929) (xy 296.186053 -289.425222)
			(xy 296.233324 -289.438914) (xy 296.277786 -289.460012) (xy 296.318289 -289.487968) (xy 296.353782 -289.52206)
			(xy 296.383347 -289.561404) (xy 296.406218 -289.604981) (xy 296.421802 -289.651662) (xy 296.429697 -289.700239)
			(xy 296.430192 -289.724846) (xy 296.76904 -289.724846) (xy 296.773 -289.675792) (xy 296.784777 -289.628008)
			(xy 296.804068 -289.582732) (xy 296.830371 -289.541136) (xy 296.863006 -289.504299) (xy 296.901127 -289.473174)
			(xy 296.943748 -289.448567) (xy 296.989764 -289.431115) (xy 297.037983 -289.421271) (xy 297.087158 -289.41929)
			(xy 297.136013 -289.425222) (xy 297.183284 -289.438914) (xy 297.227746 -289.460012) (xy 297.268249 -289.487968)
			(xy 297.303742 -289.52206) (xy 297.333307 -289.561404) (xy 297.356178 -289.604981) (xy 297.371762 -289.651662)
			(xy 297.379657 -289.700239) (xy 297.380152 -289.724846) (xy 297.719 -289.724846) (xy 297.72296 -289.675792)
			(xy 297.734737 -289.628008) (xy 297.754028 -289.582732) (xy 297.780331 -289.541136) (xy 297.812966 -289.504299)
			(xy 297.851087 -289.473174) (xy 297.893708 -289.448567) (xy 297.939724 -289.431115) (xy 297.987943 -289.421271)
			(xy 298.037118 -289.41929) (xy 298.085973 -289.425222) (xy 298.133244 -289.438914) (xy 298.177706 -289.460012)
			(xy 298.218209 -289.487968) (xy 298.253702 -289.52206) (xy 298.283267 -289.561404) (xy 298.306138 -289.604981)
			(xy 298.321722 -289.651662) (xy 298.329617 -289.700239) (xy 298.330112 -289.724846) (xy 298.66896 -289.724846)
			(xy 298.67292 -289.675792) (xy 298.684697 -289.628008) (xy 298.703988 -289.582732) (xy 298.730291 -289.541136)
			(xy 298.762926 -289.504299) (xy 298.801047 -289.473174) (xy 298.843668 -289.448567) (xy 298.889684 -289.431115)
			(xy 298.937903 -289.421271) (xy 298.987078 -289.41929) (xy 299.035933 -289.425222) (xy 299.083204 -289.438914)
			(xy 299.127666 -289.460012) (xy 299.168169 -289.487968) (xy 299.203662 -289.52206) (xy 299.233227 -289.561404)
			(xy 299.256098 -289.604981) (xy 299.271682 -289.651662) (xy 299.279577 -289.700239) (xy 299.280072 -289.724846)
			(xy 299.61892 -289.724846) (xy 299.62288 -289.675792) (xy 299.634657 -289.628008) (xy 299.653948 -289.582732)
			(xy 299.680251 -289.541136) (xy 299.712886 -289.504299) (xy 299.751007 -289.473174) (xy 299.793628 -289.448567)
			(xy 299.839644 -289.431115) (xy 299.887863 -289.421271) (xy 299.937038 -289.41929) (xy 299.985893 -289.425222)
			(xy 300.033164 -289.438914) (xy 300.077626 -289.460012) (xy 300.118129 -289.487968) (xy 300.153622 -289.52206)
			(xy 300.183187 -289.561404) (xy 300.206058 -289.604981) (xy 300.221642 -289.651662) (xy 300.229537 -289.700239)
			(xy 300.230032 -289.724846) (xy 300.56888 -289.724846) (xy 300.57284 -289.675792) (xy 300.584617 -289.628008)
			(xy 300.603908 -289.582732) (xy 300.630211 -289.541136) (xy 300.662846 -289.504299) (xy 300.700967 -289.473174)
			(xy 300.743588 -289.448567) (xy 300.789604 -289.431115) (xy 300.837823 -289.421271) (xy 300.886998 -289.41929)
			(xy 300.935853 -289.425222) (xy 300.983124 -289.438914) (xy 301.027586 -289.460012) (xy 301.068089 -289.487968)
			(xy 301.103582 -289.52206) (xy 301.133147 -289.561404) (xy 301.156018 -289.604981) (xy 301.171602 -289.651662)
			(xy 301.179497 -289.700239) (xy 301.179992 -289.724846) (xy 301.519094 -289.724846) (xy 301.523054 -289.675792)
			(xy 301.534831 -289.628008) (xy 301.554122 -289.582732) (xy 301.580425 -289.541136) (xy 301.61306 -289.504299)
			(xy 301.651181 -289.473174) (xy 301.693802 -289.448567) (xy 301.739818 -289.431115) (xy 301.788037 -289.421271)
			(xy 301.837212 -289.41929) (xy 301.886067 -289.425222) (xy 301.933338 -289.438914) (xy 301.9778 -289.460012)
			(xy 302.018303 -289.487968) (xy 302.053796 -289.52206) (xy 302.083361 -289.561404) (xy 302.106232 -289.604981)
			(xy 302.121816 -289.651662) (xy 302.129711 -289.700239) (xy 302.130206 -289.724846) (xy 302.469054 -289.724846)
			(xy 302.473014 -289.675792) (xy 302.484791 -289.628008) (xy 302.504082 -289.582732) (xy 302.530385 -289.541136)
			(xy 302.56302 -289.504299) (xy 302.601141 -289.473174) (xy 302.643762 -289.448567) (xy 302.689778 -289.431115)
			(xy 302.737997 -289.421271) (xy 302.787172 -289.41929) (xy 302.836027 -289.425222) (xy 302.883298 -289.438914)
			(xy 302.92776 -289.460012) (xy 302.968263 -289.487968) (xy 303.003756 -289.52206) (xy 303.033321 -289.561404)
			(xy 303.056192 -289.604981) (xy 303.071776 -289.651662) (xy 303.079671 -289.700239) (xy 303.080166 -289.724846)
			(xy 303.419014 -289.724846) (xy 303.422974 -289.675792) (xy 303.434751 -289.628008) (xy 303.454042 -289.582732)
			(xy 303.480345 -289.541136) (xy 303.51298 -289.504299) (xy 303.551101 -289.473174) (xy 303.593722 -289.448567)
			(xy 303.639738 -289.431115) (xy 303.687957 -289.421271) (xy 303.737132 -289.41929) (xy 303.785987 -289.425222)
			(xy 303.833258 -289.438914) (xy 303.87772 -289.460012) (xy 303.918223 -289.487968) (xy 303.953716 -289.52206)
			(xy 303.983281 -289.561404) (xy 304.006152 -289.604981) (xy 304.021736 -289.651662) (xy 304.029631 -289.700239)
			(xy 304.030126 -289.724846) (xy 304.368974 -289.724846) (xy 304.372934 -289.675792) (xy 304.384711 -289.628008)
			(xy 304.404002 -289.582732) (xy 304.430305 -289.541136) (xy 304.46294 -289.504299) (xy 304.501061 -289.473174)
			(xy 304.543682 -289.448567) (xy 304.589698 -289.431115) (xy 304.637917 -289.421271) (xy 304.687092 -289.41929)
			(xy 304.735947 -289.425222) (xy 304.783218 -289.438914) (xy 304.82768 -289.460012) (xy 304.868183 -289.487968)
			(xy 304.903676 -289.52206) (xy 304.933241 -289.561404) (xy 304.956112 -289.604981) (xy 304.971696 -289.651662)
			(xy 304.979591 -289.700239) (xy 304.980086 -289.724846) (xy 305.318934 -289.724846) (xy 305.322894 -289.675792)
			(xy 305.334671 -289.628008) (xy 305.353962 -289.582732) (xy 305.380265 -289.541136) (xy 305.4129 -289.504299)
			(xy 305.451021 -289.473174) (xy 305.493642 -289.448567) (xy 305.539658 -289.431115) (xy 305.587877 -289.421271)
			(xy 305.637052 -289.41929) (xy 305.685907 -289.425222) (xy 305.733178 -289.438914) (xy 305.77764 -289.460012)
			(xy 305.818143 -289.487968) (xy 305.853636 -289.52206) (xy 305.883201 -289.561404) (xy 305.906072 -289.604981)
			(xy 305.921656 -289.651662) (xy 305.929551 -289.700239) (xy 305.930046 -289.724846) (xy 306.269148 -289.724846)
			(xy 306.273108 -289.675792) (xy 306.284885 -289.628008) (xy 306.304176 -289.582732) (xy 306.330479 -289.541136)
			(xy 306.363114 -289.504299) (xy 306.401235 -289.473174) (xy 306.443856 -289.448567) (xy 306.489872 -289.431115)
			(xy 306.538091 -289.421271) (xy 306.587266 -289.41929) (xy 306.636121 -289.425222) (xy 306.683392 -289.438914)
			(xy 306.727854 -289.460012) (xy 306.768357 -289.487968) (xy 306.80385 -289.52206) (xy 306.833415 -289.561404)
			(xy 306.856286 -289.604981) (xy 306.87187 -289.651662) (xy 306.879765 -289.700239) (xy 306.88026 -289.724846)
			(xy 308.169068 -289.724846) (xy 308.173028 -289.675792) (xy 308.184805 -289.628008) (xy 308.204096 -289.582732)
			(xy 308.230399 -289.541136) (xy 308.263034 -289.504299) (xy 308.301155 -289.473174) (xy 308.343776 -289.448567)
			(xy 308.389792 -289.431115) (xy 308.438011 -289.421271) (xy 308.487186 -289.41929) (xy 308.536041 -289.425222)
			(xy 308.583312 -289.438914) (xy 308.627774 -289.460012) (xy 308.668277 -289.487968) (xy 308.70377 -289.52206)
			(xy 308.733335 -289.561404) (xy 308.756206 -289.604981) (xy 308.77179 -289.651662) (xy 308.779685 -289.700239)
			(xy 308.78018 -289.724846) (xy 309.119028 -289.724846) (xy 309.122988 -289.675792) (xy 309.134765 -289.628008)
			(xy 309.154056 -289.582732) (xy 309.180359 -289.541136) (xy 309.212994 -289.504299) (xy 309.251115 -289.473174)
			(xy 309.293736 -289.448567) (xy 309.339752 -289.431115) (xy 309.387971 -289.421271) (xy 309.437146 -289.41929)
			(xy 309.486001 -289.425222) (xy 309.533272 -289.438914) (xy 309.577734 -289.460012) (xy 309.618237 -289.487968)
			(xy 309.65373 -289.52206) (xy 309.683295 -289.561404) (xy 309.706166 -289.604981) (xy 309.72175 -289.651662)
			(xy 309.729645 -289.700239) (xy 309.73014 -289.724846) (xy 310.068988 -289.724846) (xy 310.072948 -289.675792)
			(xy 310.084725 -289.628008) (xy 310.104016 -289.582732) (xy 310.130319 -289.541136) (xy 310.162954 -289.504299)
			(xy 310.201075 -289.473174) (xy 310.243696 -289.448567) (xy 310.289712 -289.431115) (xy 310.337931 -289.421271)
			(xy 310.387106 -289.41929) (xy 310.435961 -289.425222) (xy 310.483232 -289.438914) (xy 310.527694 -289.460012)
			(xy 310.568197 -289.487968) (xy 310.60369 -289.52206) (xy 310.633255 -289.561404) (xy 310.656126 -289.604981)
			(xy 310.67171 -289.651662) (xy 310.679605 -289.700239) (xy 310.6801 -289.724846) (xy 311.018948 -289.724846)
			(xy 311.022908 -289.675792) (xy 311.034685 -289.628008) (xy 311.053976 -289.582732) (xy 311.080279 -289.541136)
			(xy 311.112914 -289.504299) (xy 311.151035 -289.473174) (xy 311.193656 -289.448567) (xy 311.239672 -289.431115)
			(xy 311.287891 -289.421271) (xy 311.337066 -289.41929) (xy 311.385921 -289.425222) (xy 311.433192 -289.438914)
			(xy 311.477654 -289.460012) (xy 311.518157 -289.487968) (xy 311.55365 -289.52206) (xy 311.583215 -289.561404)
			(xy 311.606086 -289.604981) (xy 311.62167 -289.651662) (xy 311.629565 -289.700239) (xy 311.63006 -289.724846)
			(xy 311.968908 -289.724846) (xy 311.972868 -289.675792) (xy 311.984645 -289.628008) (xy 312.003936 -289.582732)
			(xy 312.030239 -289.541136) (xy 312.062874 -289.504299) (xy 312.100995 -289.473174) (xy 312.143616 -289.448567)
			(xy 312.189632 -289.431115) (xy 312.237851 -289.421271) (xy 312.287026 -289.41929) (xy 312.335881 -289.425222)
			(xy 312.383152 -289.438914) (xy 312.427614 -289.460012) (xy 312.468117 -289.487968) (xy 312.50361 -289.52206)
			(xy 312.533175 -289.561404) (xy 312.556046 -289.604981) (xy 312.57163 -289.651662) (xy 312.579525 -289.700239)
			(xy 312.58002 -289.724846) (xy 312.919122 -289.724846) (xy 312.923082 -289.675792) (xy 312.934859 -289.628008)
			(xy 312.95415 -289.582732) (xy 312.980453 -289.541136) (xy 313.013088 -289.504299) (xy 313.051209 -289.473174)
			(xy 313.09383 -289.448567) (xy 313.139846 -289.431115) (xy 313.188065 -289.421271) (xy 313.23724 -289.41929)
			(xy 313.286095 -289.425222) (xy 313.333366 -289.438914) (xy 313.377828 -289.460012) (xy 313.418331 -289.487968)
			(xy 313.453824 -289.52206) (xy 313.483389 -289.561404) (xy 313.50626 -289.604981) (xy 313.521844 -289.651662)
			(xy 313.529739 -289.700239) (xy 313.530234 -289.724846) (xy 313.869082 -289.724846) (xy 313.873042 -289.675792)
			(xy 313.884819 -289.628008) (xy 313.90411 -289.582732) (xy 313.930413 -289.541136) (xy 313.963048 -289.504299)
			(xy 314.001169 -289.473174) (xy 314.04379 -289.448567) (xy 314.089806 -289.431115) (xy 314.138025 -289.421271)
			(xy 314.1872 -289.41929) (xy 314.236055 -289.425222) (xy 314.283326 -289.438914) (xy 314.327788 -289.460012)
			(xy 314.368291 -289.487968) (xy 314.403784 -289.52206) (xy 314.433349 -289.561404) (xy 314.45622 -289.604981)
			(xy 314.471804 -289.651662) (xy 314.479699 -289.700239) (xy 314.480194 -289.724846) (xy 314.819042 -289.724846)
			(xy 314.823002 -289.675792) (xy 314.834779 -289.628008) (xy 314.85407 -289.582732) (xy 314.880373 -289.541136)
			(xy 314.913008 -289.504299) (xy 314.951129 -289.473174) (xy 314.99375 -289.448567) (xy 315.039766 -289.431115)
			(xy 315.087985 -289.421271) (xy 315.13716 -289.41929) (xy 315.186015 -289.425222) (xy 315.233286 -289.438914)
			(xy 315.277748 -289.460012) (xy 315.318251 -289.487968) (xy 315.353744 -289.52206) (xy 315.383309 -289.561404)
			(xy 315.40618 -289.604981) (xy 315.421764 -289.651662) (xy 315.429659 -289.700239) (xy 315.430154 -289.724846)
			(xy 315.429659 -289.749453) (xy 315.421764 -289.79803) (xy 315.40618 -289.844711) (xy 315.383309 -289.888288)
			(xy 315.353744 -289.927632) (xy 315.318251 -289.961724) (xy 315.277748 -289.98968) (xy 315.233286 -290.010778)
			(xy 315.186015 -290.02447) (xy 315.13716 -290.030402) (xy 315.087985 -290.028421) (xy 315.039766 -290.018577)
			(xy 314.99375 -290.001125) (xy 314.951129 -289.976518) (xy 314.913008 -289.945393) (xy 314.880373 -289.908556)
			(xy 314.85407 -289.86696) (xy 314.834779 -289.821684) (xy 314.823002 -289.7739) (xy 314.819042 -289.724846)
			(xy 314.480194 -289.724846) (xy 314.479699 -289.749453) (xy 314.471804 -289.79803) (xy 314.45622 -289.844711)
			(xy 314.433349 -289.888288) (xy 314.403784 -289.927632) (xy 314.368291 -289.961724) (xy 314.327788 -289.98968)
			(xy 314.283326 -290.010778) (xy 314.236055 -290.02447) (xy 314.1872 -290.030402) (xy 314.138025 -290.028421)
			(xy 314.089806 -290.018577) (xy 314.04379 -290.001125) (xy 314.001169 -289.976518) (xy 313.963048 -289.945393)
			(xy 313.930413 -289.908556) (xy 313.90411 -289.86696) (xy 313.884819 -289.821684) (xy 313.873042 -289.7739)
			(xy 313.869082 -289.724846) (xy 313.530234 -289.724846) (xy 313.529739 -289.749453) (xy 313.521844 -289.79803)
			(xy 313.50626 -289.844711) (xy 313.483389 -289.888288) (xy 313.453824 -289.927632) (xy 313.418331 -289.961724)
			(xy 313.377828 -289.98968) (xy 313.333366 -290.010778) (xy 313.286095 -290.02447) (xy 313.23724 -290.030402)
			(xy 313.188065 -290.028421) (xy 313.139846 -290.018577) (xy 313.09383 -290.001125) (xy 313.051209 -289.976518)
			(xy 313.013088 -289.945393) (xy 312.980453 -289.908556) (xy 312.95415 -289.86696) (xy 312.934859 -289.821684)
			(xy 312.923082 -289.7739) (xy 312.919122 -289.724846) (xy 312.58002 -289.724846) (xy 312.579525 -289.749453)
			(xy 312.57163 -289.79803) (xy 312.556046 -289.844711) (xy 312.533175 -289.888288) (xy 312.50361 -289.927632)
			(xy 312.468117 -289.961724) (xy 312.427614 -289.98968) (xy 312.383152 -290.010778) (xy 312.335881 -290.02447)
			(xy 312.287026 -290.030402) (xy 312.237851 -290.028421) (xy 312.189632 -290.018577) (xy 312.143616 -290.001125)
			(xy 312.100995 -289.976518) (xy 312.062874 -289.945393) (xy 312.030239 -289.908556) (xy 312.003936 -289.86696)
			(xy 311.984645 -289.821684) (xy 311.972868 -289.7739) (xy 311.968908 -289.724846) (xy 311.63006 -289.724846)
			(xy 311.629565 -289.749453) (xy 311.62167 -289.79803) (xy 311.606086 -289.844711) (xy 311.583215 -289.888288)
			(xy 311.55365 -289.927632) (xy 311.518157 -289.961724) (xy 311.477654 -289.98968) (xy 311.433192 -290.010778)
			(xy 311.385921 -290.02447) (xy 311.337066 -290.030402) (xy 311.287891 -290.028421) (xy 311.239672 -290.018577)
			(xy 311.193656 -290.001125) (xy 311.151035 -289.976518) (xy 311.112914 -289.945393) (xy 311.080279 -289.908556)
			(xy 311.053976 -289.86696) (xy 311.034685 -289.821684) (xy 311.022908 -289.7739) (xy 311.018948 -289.724846)
			(xy 310.6801 -289.724846) (xy 310.679605 -289.749453) (xy 310.67171 -289.79803) (xy 310.656126 -289.844711)
			(xy 310.633255 -289.888288) (xy 310.60369 -289.927632) (xy 310.568197 -289.961724) (xy 310.527694 -289.98968)
			(xy 310.483232 -290.010778) (xy 310.435961 -290.02447) (xy 310.387106 -290.030402) (xy 310.337931 -290.028421)
			(xy 310.289712 -290.018577) (xy 310.243696 -290.001125) (xy 310.201075 -289.976518) (xy 310.162954 -289.945393)
			(xy 310.130319 -289.908556) (xy 310.104016 -289.86696) (xy 310.084725 -289.821684) (xy 310.072948 -289.7739)
			(xy 310.068988 -289.724846) (xy 309.73014 -289.724846) (xy 309.729645 -289.749453) (xy 309.72175 -289.79803)
			(xy 309.706166 -289.844711) (xy 309.683295 -289.888288) (xy 309.65373 -289.927632) (xy 309.618237 -289.961724)
			(xy 309.577734 -289.98968) (xy 309.533272 -290.010778) (xy 309.486001 -290.02447) (xy 309.437146 -290.030402)
			(xy 309.387971 -290.028421) (xy 309.339752 -290.018577) (xy 309.293736 -290.001125) (xy 309.251115 -289.976518)
			(xy 309.212994 -289.945393) (xy 309.180359 -289.908556) (xy 309.154056 -289.86696) (xy 309.134765 -289.821684)
			(xy 309.122988 -289.7739) (xy 309.119028 -289.724846) (xy 308.78018 -289.724846) (xy 308.779685 -289.749453)
			(xy 308.77179 -289.79803) (xy 308.756206 -289.844711) (xy 308.733335 -289.888288) (xy 308.70377 -289.927632)
			(xy 308.668277 -289.961724) (xy 308.627774 -289.98968) (xy 308.583312 -290.010778) (xy 308.536041 -290.02447)
			(xy 308.487186 -290.030402) (xy 308.438011 -290.028421) (xy 308.389792 -290.018577) (xy 308.343776 -290.001125)
			(xy 308.301155 -289.976518) (xy 308.263034 -289.945393) (xy 308.230399 -289.908556) (xy 308.204096 -289.86696)
			(xy 308.184805 -289.821684) (xy 308.173028 -289.7739) (xy 308.169068 -289.724846) (xy 306.88026 -289.724846)
			(xy 306.879765 -289.749453) (xy 306.87187 -289.79803) (xy 306.856286 -289.844711) (xy 306.833415 -289.888288)
			(xy 306.80385 -289.927632) (xy 306.768357 -289.961724) (xy 306.727854 -289.98968) (xy 306.683392 -290.010778)
			(xy 306.636121 -290.02447) (xy 306.587266 -290.030402) (xy 306.538091 -290.028421) (xy 306.489872 -290.018577)
			(xy 306.443856 -290.001125) (xy 306.401235 -289.976518) (xy 306.363114 -289.945393) (xy 306.330479 -289.908556)
			(xy 306.304176 -289.86696) (xy 306.284885 -289.821684) (xy 306.273108 -289.7739) (xy 306.269148 -289.724846)
			(xy 305.930046 -289.724846) (xy 305.929551 -289.749453) (xy 305.921656 -289.79803) (xy 305.906072 -289.844711)
			(xy 305.883201 -289.888288) (xy 305.853636 -289.927632) (xy 305.818143 -289.961724) (xy 305.77764 -289.98968)
			(xy 305.733178 -290.010778) (xy 305.685907 -290.02447) (xy 305.637052 -290.030402) (xy 305.587877 -290.028421)
			(xy 305.539658 -290.018577) (xy 305.493642 -290.001125) (xy 305.451021 -289.976518) (xy 305.4129 -289.945393)
			(xy 305.380265 -289.908556) (xy 305.353962 -289.86696) (xy 305.334671 -289.821684) (xy 305.322894 -289.7739)
			(xy 305.318934 -289.724846) (xy 304.980086 -289.724846) (xy 304.979591 -289.749453) (xy 304.971696 -289.79803)
			(xy 304.956112 -289.844711) (xy 304.933241 -289.888288) (xy 304.903676 -289.927632) (xy 304.868183 -289.961724)
			(xy 304.82768 -289.98968) (xy 304.783218 -290.010778) (xy 304.735947 -290.02447) (xy 304.687092 -290.030402)
			(xy 304.637917 -290.028421) (xy 304.589698 -290.018577) (xy 304.543682 -290.001125) (xy 304.501061 -289.976518)
			(xy 304.46294 -289.945393) (xy 304.430305 -289.908556) (xy 304.404002 -289.86696) (xy 304.384711 -289.821684)
			(xy 304.372934 -289.7739) (xy 304.368974 -289.724846) (xy 304.030126 -289.724846) (xy 304.029631 -289.749453)
			(xy 304.021736 -289.79803) (xy 304.006152 -289.844711) (xy 303.983281 -289.888288) (xy 303.953716 -289.927632)
			(xy 303.918223 -289.961724) (xy 303.87772 -289.98968) (xy 303.833258 -290.010778) (xy 303.785987 -290.02447)
			(xy 303.737132 -290.030402) (xy 303.687957 -290.028421) (xy 303.639738 -290.018577) (xy 303.593722 -290.001125)
			(xy 303.551101 -289.976518) (xy 303.51298 -289.945393) (xy 303.480345 -289.908556) (xy 303.454042 -289.86696)
			(xy 303.434751 -289.821684) (xy 303.422974 -289.7739) (xy 303.419014 -289.724846) (xy 303.080166 -289.724846)
			(xy 303.079671 -289.749453) (xy 303.071776 -289.79803) (xy 303.056192 -289.844711) (xy 303.033321 -289.888288)
			(xy 303.003756 -289.927632) (xy 302.968263 -289.961724) (xy 302.92776 -289.98968) (xy 302.883298 -290.010778)
			(xy 302.836027 -290.02447) (xy 302.787172 -290.030402) (xy 302.737997 -290.028421) (xy 302.689778 -290.018577)
			(xy 302.643762 -290.001125) (xy 302.601141 -289.976518) (xy 302.56302 -289.945393) (xy 302.530385 -289.908556)
			(xy 302.504082 -289.86696) (xy 302.484791 -289.821684) (xy 302.473014 -289.7739) (xy 302.469054 -289.724846)
			(xy 302.130206 -289.724846) (xy 302.129711 -289.749453) (xy 302.121816 -289.79803) (xy 302.106232 -289.844711)
			(xy 302.083361 -289.888288) (xy 302.053796 -289.927632) (xy 302.018303 -289.961724) (xy 301.9778 -289.98968)
			(xy 301.933338 -290.010778) (xy 301.886067 -290.02447) (xy 301.837212 -290.030402) (xy 301.788037 -290.028421)
			(xy 301.739818 -290.018577) (xy 301.693802 -290.001125) (xy 301.651181 -289.976518) (xy 301.61306 -289.945393)
			(xy 301.580425 -289.908556) (xy 301.554122 -289.86696) (xy 301.534831 -289.821684) (xy 301.523054 -289.7739)
			(xy 301.519094 -289.724846) (xy 301.179992 -289.724846) (xy 301.179497 -289.749453) (xy 301.171602 -289.79803)
			(xy 301.156018 -289.844711) (xy 301.133147 -289.888288) (xy 301.103582 -289.927632) (xy 301.068089 -289.961724)
			(xy 301.027586 -289.98968) (xy 300.983124 -290.010778) (xy 300.935853 -290.02447) (xy 300.886998 -290.030402)
			(xy 300.837823 -290.028421) (xy 300.789604 -290.018577) (xy 300.743588 -290.001125) (xy 300.700967 -289.976518)
			(xy 300.662846 -289.945393) (xy 300.630211 -289.908556) (xy 300.603908 -289.86696) (xy 300.584617 -289.821684)
			(xy 300.57284 -289.7739) (xy 300.56888 -289.724846) (xy 300.230032 -289.724846) (xy 300.229537 -289.749453)
			(xy 300.221642 -289.79803) (xy 300.206058 -289.844711) (xy 300.183187 -289.888288) (xy 300.153622 -289.927632)
			(xy 300.118129 -289.961724) (xy 300.077626 -289.98968) (xy 300.033164 -290.010778) (xy 299.985893 -290.02447)
			(xy 299.937038 -290.030402) (xy 299.887863 -290.028421) (xy 299.839644 -290.018577) (xy 299.793628 -290.001125)
			(xy 299.751007 -289.976518) (xy 299.712886 -289.945393) (xy 299.680251 -289.908556) (xy 299.653948 -289.86696)
			(xy 299.634657 -289.821684) (xy 299.62288 -289.7739) (xy 299.61892 -289.724846) (xy 299.280072 -289.724846)
			(xy 299.279577 -289.749453) (xy 299.271682 -289.79803) (xy 299.256098 -289.844711) (xy 299.233227 -289.888288)
			(xy 299.203662 -289.927632) (xy 299.168169 -289.961724) (xy 299.127666 -289.98968) (xy 299.083204 -290.010778)
			(xy 299.035933 -290.02447) (xy 298.987078 -290.030402) (xy 298.937903 -290.028421) (xy 298.889684 -290.018577)
			(xy 298.843668 -290.001125) (xy 298.801047 -289.976518) (xy 298.762926 -289.945393) (xy 298.730291 -289.908556)
			(xy 298.703988 -289.86696) (xy 298.684697 -289.821684) (xy 298.67292 -289.7739) (xy 298.66896 -289.724846)
			(xy 298.330112 -289.724846) (xy 298.329617 -289.749453) (xy 298.321722 -289.79803) (xy 298.306138 -289.844711)
			(xy 298.283267 -289.888288) (xy 298.253702 -289.927632) (xy 298.218209 -289.961724) (xy 298.177706 -289.98968)
			(xy 298.133244 -290.010778) (xy 298.085973 -290.02447) (xy 298.037118 -290.030402) (xy 297.987943 -290.028421)
			(xy 297.939724 -290.018577) (xy 297.893708 -290.001125) (xy 297.851087 -289.976518) (xy 297.812966 -289.945393)
			(xy 297.780331 -289.908556) (xy 297.754028 -289.86696) (xy 297.734737 -289.821684) (xy 297.72296 -289.7739)
			(xy 297.719 -289.724846) (xy 297.380152 -289.724846) (xy 297.379657 -289.749453) (xy 297.371762 -289.79803)
			(xy 297.356178 -289.844711) (xy 297.333307 -289.888288) (xy 297.303742 -289.927632) (xy 297.268249 -289.961724)
			(xy 297.227746 -289.98968) (xy 297.183284 -290.010778) (xy 297.136013 -290.02447) (xy 297.087158 -290.030402)
			(xy 297.037983 -290.028421) (xy 296.989764 -290.018577) (xy 296.943748 -290.001125) (xy 296.901127 -289.976518)
			(xy 296.863006 -289.945393) (xy 296.830371 -289.908556) (xy 296.804068 -289.86696) (xy 296.784777 -289.821684)
			(xy 296.773 -289.7739) (xy 296.76904 -289.724846) (xy 296.430192 -289.724846) (xy 296.429697 -289.749453)
			(xy 296.421802 -289.79803) (xy 296.406218 -289.844711) (xy 296.383347 -289.888288) (xy 296.353782 -289.927632)
			(xy 296.318289 -289.961724) (xy 296.277786 -289.98968) (xy 296.233324 -290.010778) (xy 296.186053 -290.02447)
			(xy 296.137198 -290.030402) (xy 296.088023 -290.028421) (xy 296.039804 -290.018577) (xy 295.993788 -290.001125)
			(xy 295.951167 -289.976518) (xy 295.913046 -289.945393) (xy 295.880411 -289.908556) (xy 295.854108 -289.86696)
			(xy 295.834817 -289.821684) (xy 295.82304 -289.7739) (xy 295.81908 -289.724846) (xy 295.480232 -289.724846)
			(xy 295.479737 -289.749453) (xy 295.471842 -289.79803) (xy 295.456258 -289.844711) (xy 295.433387 -289.888288)
			(xy 295.403822 -289.927632) (xy 295.368329 -289.961724) (xy 295.327826 -289.98968) (xy 295.283364 -290.010778)
			(xy 295.236093 -290.02447) (xy 295.187238 -290.030402) (xy 295.138063 -290.028421) (xy 295.089844 -290.018577)
			(xy 295.043828 -290.001125) (xy 295.001207 -289.976518) (xy 294.963086 -289.945393) (xy 294.930451 -289.908556)
			(xy 294.904148 -289.86696) (xy 294.884857 -289.821684) (xy 294.87308 -289.7739) (xy 294.86912 -289.724846)
			(xy 294.530018 -289.724846) (xy 294.529523 -289.749453) (xy 294.521628 -289.79803) (xy 294.506044 -289.844711)
			(xy 294.483173 -289.888288) (xy 294.453608 -289.927632) (xy 294.418115 -289.961724) (xy 294.377612 -289.98968)
			(xy 294.33315 -290.010778) (xy 294.285879 -290.02447) (xy 294.237024 -290.030402) (xy 294.187849 -290.028421)
			(xy 294.13963 -290.018577) (xy 294.093614 -290.001125) (xy 294.050993 -289.976518) (xy 294.012872 -289.945393)
			(xy 293.980237 -289.908556) (xy 293.953934 -289.86696) (xy 293.934643 -289.821684) (xy 293.922866 -289.7739)
			(xy 293.918906 -289.724846) (xy 293.580058 -289.724846) (xy 293.579563 -289.749453) (xy 293.571668 -289.79803)
			(xy 293.556084 -289.844711) (xy 293.533213 -289.888288) (xy 293.503648 -289.927632) (xy 293.468155 -289.961724)
			(xy 293.427652 -289.98968) (xy 293.38319 -290.010778) (xy 293.335919 -290.02447) (xy 293.287064 -290.030402)
			(xy 293.237889 -290.028421) (xy 293.18967 -290.018577) (xy 293.143654 -290.001125) (xy 293.101033 -289.976518)
			(xy 293.062912 -289.945393) (xy 293.030277 -289.908556) (xy 293.003974 -289.86696) (xy 292.984683 -289.821684)
			(xy 292.972906 -289.7739) (xy 292.968946 -289.724846) (xy 292.630098 -289.724846) (xy 292.629603 -289.749453)
			(xy 292.621708 -289.79803) (xy 292.606124 -289.844711) (xy 292.583253 -289.888288) (xy 292.553688 -289.927632)
			(xy 292.518195 -289.961724) (xy 292.477692 -289.98968) (xy 292.43323 -290.010778) (xy 292.385959 -290.02447)
			(xy 292.337104 -290.030402) (xy 292.287929 -290.028421) (xy 292.23971 -290.018577) (xy 292.193694 -290.001125)
			(xy 292.151073 -289.976518) (xy 292.112952 -289.945393) (xy 292.080317 -289.908556) (xy 292.054014 -289.86696)
			(xy 292.034723 -289.821684) (xy 292.022946 -289.7739) (xy 292.018986 -289.724846) (xy 290.730178 -289.724846)
			(xy 290.729683 -289.749453) (xy 290.721788 -289.79803) (xy 290.706204 -289.844711) (xy 290.683333 -289.888288)
			(xy 290.653768 -289.927632) (xy 290.618275 -289.961724) (xy 290.577772 -289.98968) (xy 290.53331 -290.010778)
			(xy 290.486039 -290.02447) (xy 290.437184 -290.030402) (xy 290.388009 -290.028421) (xy 290.33979 -290.018577)
			(xy 290.293774 -290.001125) (xy 290.251153 -289.976518) (xy 290.213032 -289.945393) (xy 290.180397 -289.908556)
			(xy 290.154094 -289.86696) (xy 290.134803 -289.821684) (xy 290.123026 -289.7739) (xy 290.119066 -289.724846)
			(xy 289.780218 -289.724846) (xy 289.779723 -289.749453) (xy 289.771828 -289.79803) (xy 289.756244 -289.844711)
			(xy 289.733373 -289.888288) (xy 289.703808 -289.927632) (xy 289.668315 -289.961724) (xy 289.627812 -289.98968)
			(xy 289.58335 -290.010778) (xy 289.536079 -290.02447) (xy 289.487224 -290.030402) (xy 289.438049 -290.028421)
			(xy 289.38983 -290.018577) (xy 289.343814 -290.001125) (xy 289.301193 -289.976518) (xy 289.263072 -289.945393)
			(xy 289.230437 -289.908556) (xy 289.204134 -289.86696) (xy 289.184843 -289.821684) (xy 289.173066 -289.7739)
			(xy 289.169106 -289.724846) (xy 288.830004 -289.724846) (xy 288.829509 -289.749453) (xy 288.821614 -289.79803)
			(xy 288.80603 -289.844711) (xy 288.783159 -289.888288) (xy 288.753594 -289.927632) (xy 288.718101 -289.961724)
			(xy 288.677598 -289.98968) (xy 288.633136 -290.010778) (xy 288.585865 -290.02447) (xy 288.53701 -290.030402)
			(xy 288.487835 -290.028421) (xy 288.439616 -290.018577) (xy 288.3936 -290.001125) (xy 288.350979 -289.976518)
			(xy 288.312858 -289.945393) (xy 288.280223 -289.908556) (xy 288.25392 -289.86696) (xy 288.234629 -289.821684)
			(xy 288.222852 -289.7739) (xy 288.218892 -289.724846) (xy 287.880044 -289.724846) (xy 287.879549 -289.749453)
			(xy 287.871654 -289.79803) (xy 287.85607 -289.844711) (xy 287.833199 -289.888288) (xy 287.803634 -289.927632)
			(xy 287.768141 -289.961724) (xy 287.727638 -289.98968) (xy 287.683176 -290.010778) (xy 287.635905 -290.02447)
			(xy 287.58705 -290.030402) (xy 287.537875 -290.028421) (xy 287.489656 -290.018577) (xy 287.44364 -290.001125)
			(xy 287.401019 -289.976518) (xy 287.362898 -289.945393) (xy 287.330263 -289.908556) (xy 287.30396 -289.86696)
			(xy 287.284669 -289.821684) (xy 287.272892 -289.7739) (xy 287.268932 -289.724846) (xy 286.930084 -289.724846)
			(xy 286.929589 -289.749453) (xy 286.921694 -289.79803) (xy 286.90611 -289.844711) (xy 286.883239 -289.888288)
			(xy 286.853674 -289.927632) (xy 286.818181 -289.961724) (xy 286.777678 -289.98968) (xy 286.733216 -290.010778)
			(xy 286.685945 -290.02447) (xy 286.63709 -290.030402) (xy 286.587915 -290.028421) (xy 286.539696 -290.018577)
			(xy 286.49368 -290.001125) (xy 286.451059 -289.976518) (xy 286.412938 -289.945393) (xy 286.380303 -289.908556)
			(xy 286.354 -289.86696) (xy 286.334709 -289.821684) (xy 286.322932 -289.7739) (xy 286.318972 -289.724846)
			(xy 285.980124 -289.724846) (xy 285.979629 -289.749453) (xy 285.971734 -289.79803) (xy 285.95615 -289.844711)
			(xy 285.933279 -289.888288) (xy 285.903714 -289.927632) (xy 285.868221 -289.961724) (xy 285.827718 -289.98968)
			(xy 285.783256 -290.010778) (xy 285.735985 -290.02447) (xy 285.68713 -290.030402) (xy 285.637955 -290.028421)
			(xy 285.589736 -290.018577) (xy 285.54372 -290.001125) (xy 285.501099 -289.976518) (xy 285.462978 -289.945393)
			(xy 285.430343 -289.908556) (xy 285.40404 -289.86696) (xy 285.384749 -289.821684) (xy 285.372972 -289.7739)
			(xy 285.369012 -289.724846) (xy 285.030164 -289.724846) (xy 285.029669 -289.749453) (xy 285.021774 -289.79803)
			(xy 285.00619 -289.844711) (xy 284.983319 -289.888288) (xy 284.953754 -289.927632) (xy 284.918261 -289.961724)
			(xy 284.877758 -289.98968) (xy 284.833296 -290.010778) (xy 284.786025 -290.02447) (xy 284.73717 -290.030402)
			(xy 284.687995 -290.028421) (xy 284.639776 -290.018577) (xy 284.59376 -290.001125) (xy 284.551139 -289.976518)
			(xy 284.513018 -289.945393) (xy 284.480383 -289.908556) (xy 284.45408 -289.86696) (xy 284.434789 -289.821684)
			(xy 284.423012 -289.7739) (xy 284.419052 -289.724846) (xy 284.080204 -289.724846) (xy 284.079709 -289.749453)
			(xy 284.071814 -289.79803) (xy 284.05623 -289.844711) (xy 284.033359 -289.888288) (xy 284.003794 -289.927632)
			(xy 283.968301 -289.961724) (xy 283.927798 -289.98968) (xy 283.883336 -290.010778) (xy 283.836065 -290.02447)
			(xy 283.78721 -290.030402) (xy 283.738035 -290.028421) (xy 283.689816 -290.018577) (xy 283.6438 -290.001125)
			(xy 283.601179 -289.976518) (xy 283.563058 -289.945393) (xy 283.530423 -289.908556) (xy 283.50412 -289.86696)
			(xy 283.484829 -289.821684) (xy 283.473052 -289.7739) (xy 283.469092 -289.724846) (xy 283.130244 -289.724846)
			(xy 283.129749 -289.749453) (xy 283.121854 -289.79803) (xy 283.10627 -289.844711) (xy 283.083399 -289.888288)
			(xy 283.053834 -289.927632) (xy 283.018341 -289.961724) (xy 282.977838 -289.98968) (xy 282.933376 -290.010778)
			(xy 282.886105 -290.02447) (xy 282.83725 -290.030402) (xy 282.788075 -290.028421) (xy 282.739856 -290.018577)
			(xy 282.69384 -290.001125) (xy 282.651219 -289.976518) (xy 282.613098 -289.945393) (xy 282.580463 -289.908556)
			(xy 282.55416 -289.86696) (xy 282.534869 -289.821684) (xy 282.523092 -289.7739) (xy 282.519132 -289.724846)
			(xy 282.18003 -289.724846) (xy 282.179535 -289.749453) (xy 282.17164 -289.79803) (xy 282.156056 -289.844711)
			(xy 282.133185 -289.888288) (xy 282.10362 -289.927632) (xy 282.068127 -289.961724) (xy 282.027624 -289.98968)
			(xy 281.983162 -290.010778) (xy 281.935891 -290.02447) (xy 281.887036 -290.030402) (xy 281.837861 -290.028421)
			(xy 281.789642 -290.018577) (xy 281.743626 -290.001125) (xy 281.701005 -289.976518) (xy 281.662884 -289.945393)
			(xy 281.630249 -289.908556) (xy 281.603946 -289.86696) (xy 281.584655 -289.821684) (xy 281.572878 -289.7739)
			(xy 281.568918 -289.724846) (xy 281.23007 -289.724846) (xy 281.229575 -289.749453) (xy 281.22168 -289.79803)
			(xy 281.206096 -289.844711) (xy 281.183225 -289.888288) (xy 281.15366 -289.927632) (xy 281.118167 -289.961724)
			(xy 281.077664 -289.98968) (xy 281.033202 -290.010778) (xy 280.985931 -290.02447) (xy 280.937076 -290.030402)
			(xy 280.887901 -290.028421) (xy 280.839682 -290.018577) (xy 280.793666 -290.001125) (xy 280.751045 -289.976518)
			(xy 280.712924 -289.945393) (xy 280.680289 -289.908556) (xy 280.653986 -289.86696) (xy 280.634695 -289.821684)
			(xy 280.622918 -289.7739) (xy 280.618958 -289.724846) (xy 280.28011 -289.724846) (xy 280.279615 -289.749453)
			(xy 280.27172 -289.79803) (xy 280.256136 -289.844711) (xy 280.233265 -289.888288) (xy 280.2037 -289.927632)
			(xy 280.168207 -289.961724) (xy 280.127704 -289.98968) (xy 280.083242 -290.010778) (xy 280.035971 -290.02447)
			(xy 279.987116 -290.030402) (xy 279.937941 -290.028421) (xy 279.889722 -290.018577) (xy 279.843706 -290.001125)
			(xy 279.801085 -289.976518) (xy 279.762964 -289.945393) (xy 279.730329 -289.908556) (xy 279.704026 -289.86696)
			(xy 279.684735 -289.821684) (xy 279.672958 -289.7739) (xy 279.668998 -289.724846) (xy 279.33015 -289.724846)
			(xy 279.329655 -289.749453) (xy 279.32176 -289.79803) (xy 279.306176 -289.844711) (xy 279.283305 -289.888288)
			(xy 279.25374 -289.927632) (xy 279.218247 -289.961724) (xy 279.177744 -289.98968) (xy 279.133282 -290.010778)
			(xy 279.086011 -290.02447) (xy 279.037156 -290.030402) (xy 278.987981 -290.028421) (xy 278.939762 -290.018577)
			(xy 278.893746 -290.001125) (xy 278.851125 -289.976518) (xy 278.813004 -289.945393) (xy 278.780369 -289.908556)
			(xy 278.754066 -289.86696) (xy 278.734775 -289.821684) (xy 278.722998 -289.7739) (xy 278.719038 -289.724846)
			(xy 278.38019 -289.724846) (xy 278.379695 -289.749453) (xy 278.3718 -289.79803) (xy 278.356216 -289.844711)
			(xy 278.333345 -289.888288) (xy 278.30378 -289.927632) (xy 278.268287 -289.961724) (xy 278.227784 -289.98968)
			(xy 278.183322 -290.010778) (xy 278.136051 -290.02447) (xy 278.087196 -290.030402) (xy 278.038021 -290.028421)
			(xy 277.989802 -290.018577) (xy 277.943786 -290.001125) (xy 277.901165 -289.976518) (xy 277.863044 -289.945393)
			(xy 277.830409 -289.908556) (xy 277.804106 -289.86696) (xy 277.784815 -289.821684) (xy 277.773038 -289.7739)
			(xy 277.769078 -289.724846) (xy 277.43023 -289.724846) (xy 277.429735 -289.749453) (xy 277.42184 -289.79803)
			(xy 277.406256 -289.844711) (xy 277.383385 -289.888288) (xy 277.35382 -289.927632) (xy 277.318327 -289.961724)
			(xy 277.277824 -289.98968) (xy 277.233362 -290.010778) (xy 277.186091 -290.02447) (xy 277.137236 -290.030402)
			(xy 277.088061 -290.028421) (xy 277.039842 -290.018577) (xy 276.993826 -290.001125) (xy 276.951205 -289.976518)
			(xy 276.913084 -289.945393) (xy 276.880449 -289.908556) (xy 276.854146 -289.86696) (xy 276.834855 -289.821684)
			(xy 276.823078 -289.7739) (xy 276.819118 -289.724846) (xy 276.480016 -289.724846) (xy 276.479521 -289.749453)
			(xy 276.471626 -289.79803) (xy 276.456042 -289.844711) (xy 276.433171 -289.888288) (xy 276.403606 -289.927632)
			(xy 276.368113 -289.961724) (xy 276.32761 -289.98968) (xy 276.283148 -290.010778) (xy 276.235877 -290.02447)
			(xy 276.187022 -290.030402) (xy 276.137847 -290.028421) (xy 276.089628 -290.018577) (xy 276.043612 -290.001125)
			(xy 276.000991 -289.976518) (xy 275.96287 -289.945393) (xy 275.930235 -289.908556) (xy 275.903932 -289.86696)
			(xy 275.884641 -289.821684) (xy 275.872864 -289.7739) (xy 275.868904 -289.724846) (xy 275.530056 -289.724846)
			(xy 275.529561 -289.749453) (xy 275.521666 -289.79803) (xy 275.506082 -289.844711) (xy 275.483211 -289.888288)
			(xy 275.453646 -289.927632) (xy 275.418153 -289.961724) (xy 275.37765 -289.98968) (xy 275.333188 -290.010778)
			(xy 275.285917 -290.02447) (xy 275.237062 -290.030402) (xy 275.187887 -290.028421) (xy 275.139668 -290.018577)
			(xy 275.093652 -290.001125) (xy 275.051031 -289.976518) (xy 275.01291 -289.945393) (xy 274.980275 -289.908556)
			(xy 274.953972 -289.86696) (xy 274.934681 -289.821684) (xy 274.922904 -289.7739) (xy 274.918944 -289.724846)
			(xy 274.580096 -289.724846) (xy 274.579601 -289.749453) (xy 274.571706 -289.79803) (xy 274.556122 -289.844711)
			(xy 274.533251 -289.888288) (xy 274.503686 -289.927632) (xy 274.468193 -289.961724) (xy 274.42769 -289.98968)
			(xy 274.383228 -290.010778) (xy 274.335957 -290.02447) (xy 274.287102 -290.030402) (xy 274.237927 -290.028421)
			(xy 274.189708 -290.018577) (xy 274.143692 -290.001125) (xy 274.101071 -289.976518) (xy 274.06295 -289.945393)
			(xy 274.030315 -289.908556) (xy 274.004012 -289.86696) (xy 273.984721 -289.821684) (xy 273.972944 -289.7739)
			(xy 273.968984 -289.724846) (xy 273.630136 -289.724846) (xy 273.629641 -289.749453) (xy 273.621746 -289.79803)
			(xy 273.606162 -289.844711) (xy 273.583291 -289.888288) (xy 273.553726 -289.927632) (xy 273.518233 -289.961724)
			(xy 273.47773 -289.98968) (xy 273.433268 -290.010778) (xy 273.385997 -290.02447) (xy 273.337142 -290.030402)
			(xy 273.287967 -290.028421) (xy 273.239748 -290.018577) (xy 273.193732 -290.001125) (xy 273.151111 -289.976518)
			(xy 273.11299 -289.945393) (xy 273.080355 -289.908556) (xy 273.054052 -289.86696) (xy 273.034761 -289.821684)
			(xy 273.022984 -289.7739) (xy 273.019024 -289.724846) (xy 272.680176 -289.724846) (xy 272.679681 -289.749453)
			(xy 272.671786 -289.79803) (xy 272.656202 -289.844711) (xy 272.633331 -289.888288) (xy 272.603766 -289.927632)
			(xy 272.568273 -289.961724) (xy 272.52777 -289.98968) (xy 272.483308 -290.010778) (xy 272.436037 -290.02447)
			(xy 272.387182 -290.030402) (xy 272.338007 -290.028421) (xy 272.289788 -290.018577) (xy 272.243772 -290.001125)
			(xy 272.201151 -289.976518) (xy 272.16303 -289.945393) (xy 272.130395 -289.908556) (xy 272.104092 -289.86696)
			(xy 272.084801 -289.821684) (xy 272.073024 -289.7739) (xy 272.069064 -289.724846) (xy 271.730216 -289.724846)
			(xy 271.729721 -289.749453) (xy 271.721826 -289.79803) (xy 271.706242 -289.844711) (xy 271.683371 -289.888288)
			(xy 271.653806 -289.927632) (xy 271.618313 -289.961724) (xy 271.57781 -289.98968) (xy 271.533348 -290.010778)
			(xy 271.486077 -290.02447) (xy 271.437222 -290.030402) (xy 271.388047 -290.028421) (xy 271.339828 -290.018577)
			(xy 271.293812 -290.001125) (xy 271.251191 -289.976518) (xy 271.21307 -289.945393) (xy 271.180435 -289.908556)
			(xy 271.154132 -289.86696) (xy 271.134841 -289.821684) (xy 271.123064 -289.7739) (xy 271.119104 -289.724846)
			(xy 270.780256 -289.724846) (xy 270.779761 -289.749453) (xy 270.771866 -289.79803) (xy 270.756282 -289.844711)
			(xy 270.733411 -289.888288) (xy 270.703846 -289.927632) (xy 270.668353 -289.961724) (xy 270.62785 -289.98968)
			(xy 270.583388 -290.010778) (xy 270.536117 -290.02447) (xy 270.487262 -290.030402) (xy 270.438087 -290.028421)
			(xy 270.389868 -290.018577) (xy 270.343852 -290.001125) (xy 270.301231 -289.976518) (xy 270.26311 -289.945393)
			(xy 270.230475 -289.908556) (xy 270.204172 -289.86696) (xy 270.184881 -289.821684) (xy 270.173104 -289.7739)
			(xy 270.169144 -289.724846) (xy 269.830042 -289.724846) (xy 269.829547 -289.749453) (xy 269.821652 -289.79803)
			(xy 269.806068 -289.844711) (xy 269.783197 -289.888288) (xy 269.753632 -289.927632) (xy 269.718139 -289.961724)
			(xy 269.677636 -289.98968) (xy 269.633174 -290.010778) (xy 269.585903 -290.02447) (xy 269.537048 -290.030402)
			(xy 269.487873 -290.028421) (xy 269.439654 -290.018577) (xy 269.393638 -290.001125) (xy 269.351017 -289.976518)
			(xy 269.312896 -289.945393) (xy 269.280261 -289.908556) (xy 269.253958 -289.86696) (xy 269.234667 -289.821684)
			(xy 269.22289 -289.7739) (xy 269.21893 -289.724846) (xy 268.880082 -289.724846) (xy 268.879587 -289.749453)
			(xy 268.871692 -289.79803) (xy 268.856108 -289.844711) (xy 268.833237 -289.888288) (xy 268.803672 -289.927632)
			(xy 268.768179 -289.961724) (xy 268.727676 -289.98968) (xy 268.683214 -290.010778) (xy 268.635943 -290.02447)
			(xy 268.587088 -290.030402) (xy 268.537913 -290.028421) (xy 268.489694 -290.018577) (xy 268.443678 -290.001125)
			(xy 268.401057 -289.976518) (xy 268.362936 -289.945393) (xy 268.330301 -289.908556) (xy 268.303998 -289.86696)
			(xy 268.284707 -289.821684) (xy 268.27293 -289.7739) (xy 268.26897 -289.724846) (xy 264.260539 -289.724846)
			(xy 264.258791 -289.728354) (xy 264.224818 -289.776305) (xy 264.183891 -289.818476) (xy 264.160762 -289.836606)
			(xy 264.151364 -289.843972) (xy 264.14095 -289.864546) (xy 264.139426 -289.968432) (xy 264.149332 -289.989514)
			(xy 264.158476 -289.99688) (xy 264.180292 -290.015123) (xy 264.218835 -290.056933) (xy 264.250747 -290.104001)
			(xy 264.275319 -290.155284) (xy 264.292009 -290.209645) (xy 264.300447 -290.265881) (xy 264.30097 -290.294314)
			(xy 264.934444 -290.294314) (xy 264.938515 -290.238692) (xy 264.950641 -290.184255) (xy 264.970564 -290.132164)
			(xy 264.99786 -290.083529) (xy 265.031946 -290.039386) (xy 265.072095 -290.000677) (xy 265.117453 -289.968226)
			(xy 265.167053 -289.942725) (xy 265.219837 -289.924718) (xy 265.27468 -289.914588) (xy 265.330414 -289.912551)
			(xy 265.385851 -289.918651) (xy 265.439808 -289.932757) (xy 265.491137 -289.954569) (xy 265.538743 -289.983623)
			(xy 265.581611 -290.019298) (xy 265.618828 -290.060835) (xy 265.649601 -290.107348) (xy 265.673273 -290.157845)
			(xy 265.689341 -290.211252) (xy 265.697461 -290.266428) (xy 265.69797 -290.294314) (xy 265.820904 -290.294314)
			(xy 265.824975 -290.238692) (xy 265.837101 -290.184255) (xy 265.857024 -290.132164) (xy 265.88432 -290.083529)
			(xy 265.918406 -290.039386) (xy 265.958555 -290.000677) (xy 266.003913 -289.968226) (xy 266.053513 -289.942725)
			(xy 266.106297 -289.924718) (xy 266.16114 -289.914588) (xy 266.216874 -289.912551) (xy 266.272311 -289.918651)
			(xy 266.326268 -289.932757) (xy 266.377597 -289.954569) (xy 266.425203 -289.983623) (xy 266.468071 -290.019298)
			(xy 266.505288 -290.060835) (xy 266.536061 -290.107348) (xy 266.559733 -290.157845) (xy 266.575801 -290.211252)
			(xy 266.583921 -290.266428) (xy 266.58443 -290.294314) (xy 266.583921 -290.3222) (xy 266.575801 -290.377376)
			(xy 266.559733 -290.430783) (xy 266.536061 -290.48128) (xy 266.505288 -290.527793) (xy 266.468071 -290.56933)
			(xy 266.425203 -290.605005) (xy 266.377597 -290.634059) (xy 266.326268 -290.655871) (xy 266.272311 -290.669977)
			(xy 266.228425 -290.674806) (xy 268.26897 -290.674806) (xy 268.27293 -290.625752) (xy 268.284707 -290.577968)
			(xy 268.303998 -290.532692) (xy 268.330301 -290.491096) (xy 268.362936 -290.454259) (xy 268.401057 -290.423134)
			(xy 268.443678 -290.398527) (xy 268.489694 -290.381075) (xy 268.537913 -290.371231) (xy 268.587088 -290.36925)
			(xy 268.635943 -290.375182) (xy 268.683214 -290.388874) (xy 268.727676 -290.409972) (xy 268.768179 -290.437928)
			(xy 268.803672 -290.47202) (xy 268.833237 -290.511364) (xy 268.856108 -290.554941) (xy 268.871692 -290.601622)
			(xy 268.879587 -290.650199) (xy 268.880082 -290.674806) (xy 269.21893 -290.674806) (xy 269.22289 -290.625752)
			(xy 269.234667 -290.577968) (xy 269.253958 -290.532692) (xy 269.280261 -290.491096) (xy 269.312896 -290.454259)
			(xy 269.351017 -290.423134) (xy 269.393638 -290.398527) (xy 269.439654 -290.381075) (xy 269.487873 -290.371231)
			(xy 269.537048 -290.36925) (xy 269.585903 -290.375182) (xy 269.633174 -290.388874) (xy 269.677636 -290.409972)
			(xy 269.718139 -290.437928) (xy 269.753632 -290.47202) (xy 269.783197 -290.511364) (xy 269.806068 -290.554941)
			(xy 269.821652 -290.601622) (xy 269.829547 -290.650199) (xy 269.830042 -290.674806) (xy 270.169144 -290.674806)
			(xy 270.173104 -290.625752) (xy 270.184881 -290.577968) (xy 270.204172 -290.532692) (xy 270.230475 -290.491096)
			(xy 270.26311 -290.454259) (xy 270.301231 -290.423134) (xy 270.343852 -290.398527) (xy 270.389868 -290.381075)
			(xy 270.438087 -290.371231) (xy 270.487262 -290.36925) (xy 270.536117 -290.375182) (xy 270.583388 -290.388874)
			(xy 270.62785 -290.409972) (xy 270.668353 -290.437928) (xy 270.703846 -290.47202) (xy 270.733411 -290.511364)
			(xy 270.756282 -290.554941) (xy 270.771866 -290.601622) (xy 270.779761 -290.650199) (xy 270.780256 -290.674806)
			(xy 273.019024 -290.674806) (xy 273.022984 -290.625752) (xy 273.034761 -290.577968) (xy 273.054052 -290.532692)
			(xy 273.080355 -290.491096) (xy 273.11299 -290.454259) (xy 273.151111 -290.423134) (xy 273.193732 -290.398527)
			(xy 273.239748 -290.381075) (xy 273.287967 -290.371231) (xy 273.337142 -290.36925) (xy 273.385997 -290.375182)
			(xy 273.433268 -290.388874) (xy 273.47773 -290.409972) (xy 273.518233 -290.437928) (xy 273.553726 -290.47202)
			(xy 273.583291 -290.511364) (xy 273.606162 -290.554941) (xy 273.621746 -290.601622) (xy 273.629641 -290.650199)
			(xy 273.630136 -290.674806) (xy 273.968984 -290.674806) (xy 273.972944 -290.625752) (xy 273.984721 -290.577968)
			(xy 274.004012 -290.532692) (xy 274.030315 -290.491096) (xy 274.06295 -290.454259) (xy 274.101071 -290.423134)
			(xy 274.143692 -290.398527) (xy 274.189708 -290.381075) (xy 274.237927 -290.371231) (xy 274.287102 -290.36925)
			(xy 274.335957 -290.375182) (xy 274.383228 -290.388874) (xy 274.42769 -290.409972) (xy 274.468193 -290.437928)
			(xy 274.503686 -290.47202) (xy 274.533251 -290.511364) (xy 274.556122 -290.554941) (xy 274.571706 -290.601622)
			(xy 274.579601 -290.650199) (xy 274.580096 -290.674806) (xy 274.918944 -290.674806) (xy 274.922904 -290.625752)
			(xy 274.934681 -290.577968) (xy 274.953972 -290.532692) (xy 274.980275 -290.491096) (xy 275.01291 -290.454259)
			(xy 275.051031 -290.423134) (xy 275.093652 -290.398527) (xy 275.139668 -290.381075) (xy 275.187887 -290.371231)
			(xy 275.237062 -290.36925) (xy 275.285917 -290.375182) (xy 275.333188 -290.388874) (xy 275.37765 -290.409972)
			(xy 275.418153 -290.437928) (xy 275.453646 -290.47202) (xy 275.483211 -290.511364) (xy 275.506082 -290.554941)
			(xy 275.521666 -290.601622) (xy 275.529561 -290.650199) (xy 275.530056 -290.674806) (xy 275.868904 -290.674806)
			(xy 275.872864 -290.625752) (xy 275.884641 -290.577968) (xy 275.903932 -290.532692) (xy 275.930235 -290.491096)
			(xy 275.96287 -290.454259) (xy 276.000991 -290.423134) (xy 276.043612 -290.398527) (xy 276.089628 -290.381075)
			(xy 276.137847 -290.371231) (xy 276.187022 -290.36925) (xy 276.235877 -290.375182) (xy 276.283148 -290.388874)
			(xy 276.32761 -290.409972) (xy 276.368113 -290.437928) (xy 276.403606 -290.47202) (xy 276.433171 -290.511364)
			(xy 276.456042 -290.554941) (xy 276.471626 -290.601622) (xy 276.479521 -290.650199) (xy 276.480016 -290.674806)
			(xy 276.819118 -290.674806) (xy 276.823078 -290.625752) (xy 276.834855 -290.577968) (xy 276.854146 -290.532692)
			(xy 276.880449 -290.491096) (xy 276.913084 -290.454259) (xy 276.951205 -290.423134) (xy 276.993826 -290.398527)
			(xy 277.039842 -290.381075) (xy 277.088061 -290.371231) (xy 277.137236 -290.36925) (xy 277.186091 -290.375182)
			(xy 277.233362 -290.388874) (xy 277.277824 -290.409972) (xy 277.318327 -290.437928) (xy 277.35382 -290.47202)
			(xy 277.383385 -290.511364) (xy 277.406256 -290.554941) (xy 277.42184 -290.601622) (xy 277.429735 -290.650199)
			(xy 277.43023 -290.674806) (xy 277.769078 -290.674806) (xy 277.773038 -290.625752) (xy 277.784815 -290.577968)
			(xy 277.804106 -290.532692) (xy 277.830409 -290.491096) (xy 277.863044 -290.454259) (xy 277.901165 -290.423134)
			(xy 277.943786 -290.398527) (xy 277.989802 -290.381075) (xy 278.038021 -290.371231) (xy 278.087196 -290.36925)
			(xy 278.136051 -290.375182) (xy 278.183322 -290.388874) (xy 278.227784 -290.409972) (xy 278.268287 -290.437928)
			(xy 278.30378 -290.47202) (xy 278.333345 -290.511364) (xy 278.356216 -290.554941) (xy 278.3718 -290.601622)
			(xy 278.379695 -290.650199) (xy 278.38019 -290.674806) (xy 278.719038 -290.674806) (xy 278.722998 -290.625752)
			(xy 278.734775 -290.577968) (xy 278.754066 -290.532692) (xy 278.780369 -290.491096) (xy 278.813004 -290.454259)
			(xy 278.851125 -290.423134) (xy 278.893746 -290.398527) (xy 278.939762 -290.381075) (xy 278.987981 -290.371231)
			(xy 279.037156 -290.36925) (xy 279.086011 -290.375182) (xy 279.133282 -290.388874) (xy 279.177744 -290.409972)
			(xy 279.218247 -290.437928) (xy 279.25374 -290.47202) (xy 279.283305 -290.511364) (xy 279.306176 -290.554941)
			(xy 279.32176 -290.601622) (xy 279.329655 -290.650199) (xy 279.33015 -290.674806) (xy 279.668998 -290.674806)
			(xy 279.672958 -290.625752) (xy 279.684735 -290.577968) (xy 279.704026 -290.532692) (xy 279.730329 -290.491096)
			(xy 279.762964 -290.454259) (xy 279.801085 -290.423134) (xy 279.843706 -290.398527) (xy 279.889722 -290.381075)
			(xy 279.937941 -290.371231) (xy 279.987116 -290.36925) (xy 280.035971 -290.375182) (xy 280.083242 -290.388874)
			(xy 280.127704 -290.409972) (xy 280.168207 -290.437928) (xy 280.2037 -290.47202) (xy 280.233265 -290.511364)
			(xy 280.256136 -290.554941) (xy 280.27172 -290.601622) (xy 280.279615 -290.650199) (xy 280.28011 -290.674806)
			(xy 280.618958 -290.674806) (xy 280.622918 -290.625752) (xy 280.634695 -290.577968) (xy 280.653986 -290.532692)
			(xy 280.680289 -290.491096) (xy 280.712924 -290.454259) (xy 280.751045 -290.423134) (xy 280.793666 -290.398527)
			(xy 280.839682 -290.381075) (xy 280.887901 -290.371231) (xy 280.937076 -290.36925) (xy 280.985931 -290.375182)
			(xy 281.033202 -290.388874) (xy 281.077664 -290.409972) (xy 281.118167 -290.437928) (xy 281.15366 -290.47202)
			(xy 281.183225 -290.511364) (xy 281.206096 -290.554941) (xy 281.22168 -290.601622) (xy 281.229575 -290.650199)
			(xy 281.23007 -290.674806) (xy 281.568918 -290.674806) (xy 281.572878 -290.625752) (xy 281.584655 -290.577968)
			(xy 281.603946 -290.532692) (xy 281.630249 -290.491096) (xy 281.662884 -290.454259) (xy 281.701005 -290.423134)
			(xy 281.743626 -290.398527) (xy 281.789642 -290.381075) (xy 281.837861 -290.371231) (xy 281.887036 -290.36925)
			(xy 281.935891 -290.375182) (xy 281.983162 -290.388874) (xy 282.027624 -290.409972) (xy 282.068127 -290.437928)
			(xy 282.10362 -290.47202) (xy 282.133185 -290.511364) (xy 282.156056 -290.554941) (xy 282.17164 -290.601622)
			(xy 282.179535 -290.650199) (xy 282.18003 -290.674806) (xy 282.519132 -290.674806) (xy 282.523092 -290.625752)
			(xy 282.534869 -290.577968) (xy 282.55416 -290.532692) (xy 282.580463 -290.491096) (xy 282.613098 -290.454259)
			(xy 282.651219 -290.423134) (xy 282.69384 -290.398527) (xy 282.739856 -290.381075) (xy 282.788075 -290.371231)
			(xy 282.83725 -290.36925) (xy 282.886105 -290.375182) (xy 282.933376 -290.388874) (xy 282.977838 -290.409972)
			(xy 283.018341 -290.437928) (xy 283.053834 -290.47202) (xy 283.083399 -290.511364) (xy 283.10627 -290.554941)
			(xy 283.121854 -290.601622) (xy 283.129749 -290.650199) (xy 283.130244 -290.674806) (xy 283.469092 -290.674806)
			(xy 283.473052 -290.625752) (xy 283.484829 -290.577968) (xy 283.50412 -290.532692) (xy 283.530423 -290.491096)
			(xy 283.563058 -290.454259) (xy 283.601179 -290.423134) (xy 283.6438 -290.398527) (xy 283.689816 -290.381075)
			(xy 283.738035 -290.371231) (xy 283.78721 -290.36925) (xy 283.836065 -290.375182) (xy 283.883336 -290.388874)
			(xy 283.927798 -290.409972) (xy 283.968301 -290.437928) (xy 284.003794 -290.47202) (xy 284.033359 -290.511364)
			(xy 284.05623 -290.554941) (xy 284.071814 -290.601622) (xy 284.079709 -290.650199) (xy 284.080204 -290.674806)
			(xy 284.419052 -290.674806) (xy 284.423012 -290.625752) (xy 284.434789 -290.577968) (xy 284.45408 -290.532692)
			(xy 284.480383 -290.491096) (xy 284.513018 -290.454259) (xy 284.551139 -290.423134) (xy 284.59376 -290.398527)
			(xy 284.639776 -290.381075) (xy 284.687995 -290.371231) (xy 284.73717 -290.36925) (xy 284.786025 -290.375182)
			(xy 284.833296 -290.388874) (xy 284.877758 -290.409972) (xy 284.918261 -290.437928) (xy 284.953754 -290.47202)
			(xy 284.983319 -290.511364) (xy 285.00619 -290.554941) (xy 285.021774 -290.601622) (xy 285.029669 -290.650199)
			(xy 285.030164 -290.674806) (xy 285.369012 -290.674806) (xy 285.372972 -290.625752) (xy 285.384749 -290.577968)
			(xy 285.40404 -290.532692) (xy 285.430343 -290.491096) (xy 285.462978 -290.454259) (xy 285.501099 -290.423134)
			(xy 285.54372 -290.398527) (xy 285.589736 -290.381075) (xy 285.637955 -290.371231) (xy 285.68713 -290.36925)
			(xy 285.735985 -290.375182) (xy 285.783256 -290.388874) (xy 285.827718 -290.409972) (xy 285.868221 -290.437928)
			(xy 285.903714 -290.47202) (xy 285.933279 -290.511364) (xy 285.95615 -290.554941) (xy 285.971734 -290.601622)
			(xy 285.979629 -290.650199) (xy 285.980124 -290.674806) (xy 286.318972 -290.674806) (xy 286.322932 -290.625752)
			(xy 286.334709 -290.577968) (xy 286.354 -290.532692) (xy 286.380303 -290.491096) (xy 286.412938 -290.454259)
			(xy 286.451059 -290.423134) (xy 286.49368 -290.398527) (xy 286.539696 -290.381075) (xy 286.587915 -290.371231)
			(xy 286.63709 -290.36925) (xy 286.685945 -290.375182) (xy 286.733216 -290.388874) (xy 286.777678 -290.409972)
			(xy 286.818181 -290.437928) (xy 286.853674 -290.47202) (xy 286.883239 -290.511364) (xy 286.90611 -290.554941)
			(xy 286.921694 -290.601622) (xy 286.929589 -290.650199) (xy 286.930084 -290.674806) (xy 287.268932 -290.674806)
			(xy 287.272892 -290.625752) (xy 287.284669 -290.577968) (xy 287.30396 -290.532692) (xy 287.330263 -290.491096)
			(xy 287.362898 -290.454259) (xy 287.401019 -290.423134) (xy 287.44364 -290.398527) (xy 287.489656 -290.381075)
			(xy 287.537875 -290.371231) (xy 287.58705 -290.36925) (xy 287.635905 -290.375182) (xy 287.683176 -290.388874)
			(xy 287.727638 -290.409972) (xy 287.768141 -290.437928) (xy 287.803634 -290.47202) (xy 287.833199 -290.511364)
			(xy 287.85607 -290.554941) (xy 287.871654 -290.601622) (xy 287.879549 -290.650199) (xy 287.880044 -290.674806)
			(xy 288.218892 -290.674806) (xy 288.222852 -290.625752) (xy 288.234629 -290.577968) (xy 288.25392 -290.532692)
			(xy 288.280223 -290.491096) (xy 288.312858 -290.454259) (xy 288.350979 -290.423134) (xy 288.3936 -290.398527)
			(xy 288.439616 -290.381075) (xy 288.487835 -290.371231) (xy 288.53701 -290.36925) (xy 288.585865 -290.375182)
			(xy 288.633136 -290.388874) (xy 288.677598 -290.409972) (xy 288.718101 -290.437928) (xy 288.753594 -290.47202)
			(xy 288.783159 -290.511364) (xy 288.80603 -290.554941) (xy 288.821614 -290.601622) (xy 288.829509 -290.650199)
			(xy 288.830004 -290.674806) (xy 289.169106 -290.674806) (xy 289.173066 -290.625752) (xy 289.184843 -290.577968)
			(xy 289.204134 -290.532692) (xy 289.230437 -290.491096) (xy 289.263072 -290.454259) (xy 289.301193 -290.423134)
			(xy 289.343814 -290.398527) (xy 289.38983 -290.381075) (xy 289.438049 -290.371231) (xy 289.487224 -290.36925)
			(xy 289.536079 -290.375182) (xy 289.58335 -290.388874) (xy 289.627812 -290.409972) (xy 289.668315 -290.437928)
			(xy 289.703808 -290.47202) (xy 289.733373 -290.511364) (xy 289.756244 -290.554941) (xy 289.771828 -290.601622)
			(xy 289.779723 -290.650199) (xy 289.780218 -290.674806) (xy 290.119066 -290.674806) (xy 290.123026 -290.625752)
			(xy 290.134803 -290.577968) (xy 290.154094 -290.532692) (xy 290.180397 -290.491096) (xy 290.213032 -290.454259)
			(xy 290.251153 -290.423134) (xy 290.293774 -290.398527) (xy 290.33979 -290.381075) (xy 290.388009 -290.371231)
			(xy 290.437184 -290.36925) (xy 290.486039 -290.375182) (xy 290.53331 -290.388874) (xy 290.577772 -290.409972)
			(xy 290.618275 -290.437928) (xy 290.653768 -290.47202) (xy 290.683333 -290.511364) (xy 290.706204 -290.554941)
			(xy 290.721788 -290.601622) (xy 290.729683 -290.650199) (xy 290.730178 -290.674806) (xy 292.018986 -290.674806)
			(xy 292.022946 -290.625752) (xy 292.034723 -290.577968) (xy 292.054014 -290.532692) (xy 292.080317 -290.491096)
			(xy 292.112952 -290.454259) (xy 292.151073 -290.423134) (xy 292.193694 -290.398527) (xy 292.23971 -290.381075)
			(xy 292.287929 -290.371231) (xy 292.337104 -290.36925) (xy 292.385959 -290.375182) (xy 292.43323 -290.388874)
			(xy 292.477692 -290.409972) (xy 292.518195 -290.437928) (xy 292.553688 -290.47202) (xy 292.583253 -290.511364)
			(xy 292.606124 -290.554941) (xy 292.621708 -290.601622) (xy 292.629603 -290.650199) (xy 292.630098 -290.674806)
			(xy 292.968946 -290.674806) (xy 292.972906 -290.625752) (xy 292.984683 -290.577968) (xy 293.003974 -290.532692)
			(xy 293.030277 -290.491096) (xy 293.062912 -290.454259) (xy 293.101033 -290.423134) (xy 293.143654 -290.398527)
			(xy 293.18967 -290.381075) (xy 293.237889 -290.371231) (xy 293.287064 -290.36925) (xy 293.335919 -290.375182)
			(xy 293.38319 -290.388874) (xy 293.427652 -290.409972) (xy 293.468155 -290.437928) (xy 293.503648 -290.47202)
			(xy 293.533213 -290.511364) (xy 293.556084 -290.554941) (xy 293.571668 -290.601622) (xy 293.579563 -290.650199)
			(xy 293.580058 -290.674806) (xy 293.918906 -290.674806) (xy 293.922866 -290.625752) (xy 293.934643 -290.577968)
			(xy 293.953934 -290.532692) (xy 293.980237 -290.491096) (xy 294.012872 -290.454259) (xy 294.050993 -290.423134)
			(xy 294.093614 -290.398527) (xy 294.13963 -290.381075) (xy 294.187849 -290.371231) (xy 294.237024 -290.36925)
			(xy 294.285879 -290.375182) (xy 294.33315 -290.388874) (xy 294.377612 -290.409972) (xy 294.418115 -290.437928)
			(xy 294.453608 -290.47202) (xy 294.483173 -290.511364) (xy 294.506044 -290.554941) (xy 294.521628 -290.601622)
			(xy 294.529523 -290.650199) (xy 294.530018 -290.674806) (xy 294.86912 -290.674806) (xy 294.87308 -290.625752)
			(xy 294.884857 -290.577968) (xy 294.904148 -290.532692) (xy 294.930451 -290.491096) (xy 294.963086 -290.454259)
			(xy 295.001207 -290.423134) (xy 295.043828 -290.398527) (xy 295.089844 -290.381075) (xy 295.138063 -290.371231)
			(xy 295.187238 -290.36925) (xy 295.236093 -290.375182) (xy 295.283364 -290.388874) (xy 295.327826 -290.409972)
			(xy 295.368329 -290.437928) (xy 295.403822 -290.47202) (xy 295.433387 -290.511364) (xy 295.456258 -290.554941)
			(xy 295.471842 -290.601622) (xy 295.479737 -290.650199) (xy 295.480232 -290.674806) (xy 295.81908 -290.674806)
			(xy 295.82304 -290.625752) (xy 295.834817 -290.577968) (xy 295.854108 -290.532692) (xy 295.880411 -290.491096)
			(xy 295.913046 -290.454259) (xy 295.951167 -290.423134) (xy 295.993788 -290.398527) (xy 296.039804 -290.381075)
			(xy 296.088023 -290.371231) (xy 296.137198 -290.36925) (xy 296.186053 -290.375182) (xy 296.233324 -290.388874)
			(xy 296.277786 -290.409972) (xy 296.318289 -290.437928) (xy 296.353782 -290.47202) (xy 296.383347 -290.511364)
			(xy 296.406218 -290.554941) (xy 296.421802 -290.601622) (xy 296.429697 -290.650199) (xy 296.430192 -290.674806)
			(xy 296.76904 -290.674806) (xy 296.773 -290.625752) (xy 296.784777 -290.577968) (xy 296.804068 -290.532692)
			(xy 296.830371 -290.491096) (xy 296.863006 -290.454259) (xy 296.901127 -290.423134) (xy 296.943748 -290.398527)
			(xy 296.989764 -290.381075) (xy 297.037983 -290.371231) (xy 297.087158 -290.36925) (xy 297.136013 -290.375182)
			(xy 297.183284 -290.388874) (xy 297.227746 -290.409972) (xy 297.268249 -290.437928) (xy 297.303742 -290.47202)
			(xy 297.333307 -290.511364) (xy 297.356178 -290.554941) (xy 297.371762 -290.601622) (xy 297.379657 -290.650199)
			(xy 297.380152 -290.674806) (xy 297.719 -290.674806) (xy 297.72296 -290.625752) (xy 297.734737 -290.577968)
			(xy 297.754028 -290.532692) (xy 297.780331 -290.491096) (xy 297.812966 -290.454259) (xy 297.851087 -290.423134)
			(xy 297.893708 -290.398527) (xy 297.939724 -290.381075) (xy 297.987943 -290.371231) (xy 298.037118 -290.36925)
			(xy 298.085973 -290.375182) (xy 298.133244 -290.388874) (xy 298.177706 -290.409972) (xy 298.218209 -290.437928)
			(xy 298.253702 -290.47202) (xy 298.283267 -290.511364) (xy 298.306138 -290.554941) (xy 298.321722 -290.601622)
			(xy 298.329617 -290.650199) (xy 298.330112 -290.674806) (xy 298.66896 -290.674806) (xy 298.67292 -290.625752)
			(xy 298.684697 -290.577968) (xy 298.703988 -290.532692) (xy 298.730291 -290.491096) (xy 298.762926 -290.454259)
			(xy 298.801047 -290.423134) (xy 298.843668 -290.398527) (xy 298.889684 -290.381075) (xy 298.937903 -290.371231)
			(xy 298.987078 -290.36925) (xy 299.035933 -290.375182) (xy 299.083204 -290.388874) (xy 299.127666 -290.409972)
			(xy 299.168169 -290.437928) (xy 299.203662 -290.47202) (xy 299.233227 -290.511364) (xy 299.256098 -290.554941)
			(xy 299.271682 -290.601622) (xy 299.279577 -290.650199) (xy 299.280072 -290.674806) (xy 299.61892 -290.674806)
			(xy 299.62288 -290.625752) (xy 299.634657 -290.577968) (xy 299.653948 -290.532692) (xy 299.680251 -290.491096)
			(xy 299.712886 -290.454259) (xy 299.751007 -290.423134) (xy 299.793628 -290.398527) (xy 299.839644 -290.381075)
			(xy 299.887863 -290.371231) (xy 299.937038 -290.36925) (xy 299.985893 -290.375182) (xy 300.033164 -290.388874)
			(xy 300.077626 -290.409972) (xy 300.118129 -290.437928) (xy 300.153622 -290.47202) (xy 300.183187 -290.511364)
			(xy 300.206058 -290.554941) (xy 300.221642 -290.601622) (xy 300.229537 -290.650199) (xy 300.230032 -290.674806)
			(xy 300.56888 -290.674806) (xy 300.57284 -290.625752) (xy 300.584617 -290.577968) (xy 300.603908 -290.532692)
			(xy 300.630211 -290.491096) (xy 300.662846 -290.454259) (xy 300.700967 -290.423134) (xy 300.743588 -290.398527)
			(xy 300.789604 -290.381075) (xy 300.837823 -290.371231) (xy 300.886998 -290.36925) (xy 300.935853 -290.375182)
			(xy 300.983124 -290.388874) (xy 301.027586 -290.409972) (xy 301.068089 -290.437928) (xy 301.103582 -290.47202)
			(xy 301.133147 -290.511364) (xy 301.156018 -290.554941) (xy 301.171602 -290.601622) (xy 301.179497 -290.650199)
			(xy 301.179992 -290.674806) (xy 301.519094 -290.674806) (xy 301.523054 -290.625752) (xy 301.534831 -290.577968)
			(xy 301.554122 -290.532692) (xy 301.580425 -290.491096) (xy 301.61306 -290.454259) (xy 301.651181 -290.423134)
			(xy 301.693802 -290.398527) (xy 301.739818 -290.381075) (xy 301.788037 -290.371231) (xy 301.837212 -290.36925)
			(xy 301.886067 -290.375182) (xy 301.933338 -290.388874) (xy 301.9778 -290.409972) (xy 302.018303 -290.437928)
			(xy 302.053796 -290.47202) (xy 302.083361 -290.511364) (xy 302.106232 -290.554941) (xy 302.121816 -290.601622)
			(xy 302.129711 -290.650199) (xy 302.130206 -290.674806) (xy 302.469054 -290.674806) (xy 302.473014 -290.625752)
			(xy 302.484791 -290.577968) (xy 302.504082 -290.532692) (xy 302.530385 -290.491096) (xy 302.56302 -290.454259)
			(xy 302.601141 -290.423134) (xy 302.643762 -290.398527) (xy 302.689778 -290.381075) (xy 302.737997 -290.371231)
			(xy 302.787172 -290.36925) (xy 302.836027 -290.375182) (xy 302.883298 -290.388874) (xy 302.92776 -290.409972)
			(xy 302.968263 -290.437928) (xy 303.003756 -290.47202) (xy 303.033321 -290.511364) (xy 303.056192 -290.554941)
			(xy 303.071776 -290.601622) (xy 303.079671 -290.650199) (xy 303.080166 -290.674806) (xy 303.419014 -290.674806)
			(xy 303.422974 -290.625752) (xy 303.434751 -290.577968) (xy 303.454042 -290.532692) (xy 303.480345 -290.491096)
			(xy 303.51298 -290.454259) (xy 303.551101 -290.423134) (xy 303.593722 -290.398527) (xy 303.639738 -290.381075)
			(xy 303.687957 -290.371231) (xy 303.737132 -290.36925) (xy 303.785987 -290.375182) (xy 303.833258 -290.388874)
			(xy 303.87772 -290.409972) (xy 303.918223 -290.437928) (xy 303.953716 -290.47202) (xy 303.983281 -290.511364)
			(xy 304.006152 -290.554941) (xy 304.021736 -290.601622) (xy 304.029631 -290.650199) (xy 304.030126 -290.674806)
			(xy 304.368974 -290.674806) (xy 304.372934 -290.625752) (xy 304.384711 -290.577968) (xy 304.404002 -290.532692)
			(xy 304.430305 -290.491096) (xy 304.46294 -290.454259) (xy 304.501061 -290.423134) (xy 304.543682 -290.398527)
			(xy 304.589698 -290.381075) (xy 304.637917 -290.371231) (xy 304.687092 -290.36925) (xy 304.735947 -290.375182)
			(xy 304.783218 -290.388874) (xy 304.82768 -290.409972) (xy 304.868183 -290.437928) (xy 304.903676 -290.47202)
			(xy 304.933241 -290.511364) (xy 304.956112 -290.554941) (xy 304.971696 -290.601622) (xy 304.979591 -290.650199)
			(xy 304.980086 -290.674806) (xy 305.318934 -290.674806) (xy 305.322894 -290.625752) (xy 305.334671 -290.577968)
			(xy 305.353962 -290.532692) (xy 305.380265 -290.491096) (xy 305.4129 -290.454259) (xy 305.451021 -290.423134)
			(xy 305.493642 -290.398527) (xy 305.539658 -290.381075) (xy 305.587877 -290.371231) (xy 305.637052 -290.36925)
			(xy 305.685907 -290.375182) (xy 305.733178 -290.388874) (xy 305.77764 -290.409972) (xy 305.818143 -290.437928)
			(xy 305.853636 -290.47202) (xy 305.883201 -290.511364) (xy 305.906072 -290.554941) (xy 305.921656 -290.601622)
			(xy 305.929551 -290.650199) (xy 305.930046 -290.674806) (xy 306.268894 -290.674806) (xy 306.272854 -290.625752)
			(xy 306.284631 -290.577968) (xy 306.303922 -290.532692) (xy 306.330225 -290.491096) (xy 306.36286 -290.454259)
			(xy 306.400981 -290.423134) (xy 306.443602 -290.398527) (xy 306.489618 -290.381075) (xy 306.537837 -290.371231)
			(xy 306.587012 -290.36925) (xy 306.635867 -290.375182) (xy 306.683138 -290.388874) (xy 306.7276 -290.409972)
			(xy 306.768103 -290.437928) (xy 306.803596 -290.47202) (xy 306.833161 -290.511364) (xy 306.856032 -290.554941)
			(xy 306.871616 -290.601622) (xy 306.879511 -290.650199) (xy 306.880006 -290.674806) (xy 307.219108 -290.674806)
			(xy 307.223068 -290.625752) (xy 307.234845 -290.577968) (xy 307.254136 -290.532692) (xy 307.280439 -290.491096)
			(xy 307.313074 -290.454259) (xy 307.351195 -290.423134) (xy 307.393816 -290.398527) (xy 307.439832 -290.381075)
			(xy 307.488051 -290.371231) (xy 307.537226 -290.36925) (xy 307.586081 -290.375182) (xy 307.633352 -290.388874)
			(xy 307.677814 -290.409972) (xy 307.718317 -290.437928) (xy 307.75381 -290.47202) (xy 307.783375 -290.511364)
			(xy 307.806246 -290.554941) (xy 307.82183 -290.601622) (xy 307.829725 -290.650199) (xy 307.83022 -290.674806)
			(xy 308.169068 -290.674806) (xy 308.173028 -290.625752) (xy 308.184805 -290.577968) (xy 308.204096 -290.532692)
			(xy 308.230399 -290.491096) (xy 308.263034 -290.454259) (xy 308.301155 -290.423134) (xy 308.343776 -290.398527)
			(xy 308.389792 -290.381075) (xy 308.438011 -290.371231) (xy 308.487186 -290.36925) (xy 308.536041 -290.375182)
			(xy 308.583312 -290.388874) (xy 308.627774 -290.409972) (xy 308.668277 -290.437928) (xy 308.70377 -290.47202)
			(xy 308.733335 -290.511364) (xy 308.756206 -290.554941) (xy 308.77179 -290.601622) (xy 308.779685 -290.650199)
			(xy 308.78018 -290.674806) (xy 309.119028 -290.674806) (xy 309.122988 -290.625752) (xy 309.134765 -290.577968)
			(xy 309.154056 -290.532692) (xy 309.180359 -290.491096) (xy 309.212994 -290.454259) (xy 309.251115 -290.423134)
			(xy 309.293736 -290.398527) (xy 309.339752 -290.381075) (xy 309.387971 -290.371231) (xy 309.437146 -290.36925)
			(xy 309.486001 -290.375182) (xy 309.533272 -290.388874) (xy 309.577734 -290.409972) (xy 309.618237 -290.437928)
			(xy 309.65373 -290.47202) (xy 309.683295 -290.511364) (xy 309.706166 -290.554941) (xy 309.72175 -290.601622)
			(xy 309.729645 -290.650199) (xy 309.73014 -290.674806) (xy 310.068988 -290.674806) (xy 310.072948 -290.625752)
			(xy 310.084725 -290.577968) (xy 310.104016 -290.532692) (xy 310.130319 -290.491096) (xy 310.162954 -290.454259)
			(xy 310.201075 -290.423134) (xy 310.243696 -290.398527) (xy 310.289712 -290.381075) (xy 310.337931 -290.371231)
			(xy 310.387106 -290.36925) (xy 310.435961 -290.375182) (xy 310.483232 -290.388874) (xy 310.527694 -290.409972)
			(xy 310.568197 -290.437928) (xy 310.60369 -290.47202) (xy 310.633255 -290.511364) (xy 310.656126 -290.554941)
			(xy 310.67171 -290.601622) (xy 310.679605 -290.650199) (xy 310.6801 -290.674806) (xy 311.018948 -290.674806)
			(xy 311.022908 -290.625752) (xy 311.034685 -290.577968) (xy 311.053976 -290.532692) (xy 311.080279 -290.491096)
			(xy 311.112914 -290.454259) (xy 311.151035 -290.423134) (xy 311.193656 -290.398527) (xy 311.239672 -290.381075)
			(xy 311.287891 -290.371231) (xy 311.337066 -290.36925) (xy 311.385921 -290.375182) (xy 311.433192 -290.388874)
			(xy 311.477654 -290.409972) (xy 311.518157 -290.437928) (xy 311.55365 -290.47202) (xy 311.583215 -290.511364)
			(xy 311.606086 -290.554941) (xy 311.62167 -290.601622) (xy 311.629565 -290.650199) (xy 311.63006 -290.674806)
			(xy 311.968908 -290.674806) (xy 311.972868 -290.625752) (xy 311.984645 -290.577968) (xy 312.003936 -290.532692)
			(xy 312.030239 -290.491096) (xy 312.062874 -290.454259) (xy 312.100995 -290.423134) (xy 312.143616 -290.398527)
			(xy 312.189632 -290.381075) (xy 312.237851 -290.371231) (xy 312.287026 -290.36925) (xy 312.335881 -290.375182)
			(xy 312.383152 -290.388874) (xy 312.427614 -290.409972) (xy 312.468117 -290.437928) (xy 312.50361 -290.47202)
			(xy 312.533175 -290.511364) (xy 312.556046 -290.554941) (xy 312.57163 -290.601622) (xy 312.579525 -290.650199)
			(xy 312.58002 -290.674806) (xy 312.919122 -290.674806) (xy 312.923082 -290.625752) (xy 312.934859 -290.577968)
			(xy 312.95415 -290.532692) (xy 312.980453 -290.491096) (xy 313.013088 -290.454259) (xy 313.051209 -290.423134)
			(xy 313.09383 -290.398527) (xy 313.139846 -290.381075) (xy 313.188065 -290.371231) (xy 313.23724 -290.36925)
			(xy 313.286095 -290.375182) (xy 313.333366 -290.388874) (xy 313.377828 -290.409972) (xy 313.418331 -290.437928)
			(xy 313.453824 -290.47202) (xy 313.483389 -290.511364) (xy 313.50626 -290.554941) (xy 313.521844 -290.601622)
			(xy 313.529739 -290.650199) (xy 313.530234 -290.674806) (xy 313.869082 -290.674806) (xy 313.873042 -290.625752)
			(xy 313.884819 -290.577968) (xy 313.90411 -290.532692) (xy 313.930413 -290.491096) (xy 313.963048 -290.454259)
			(xy 314.001169 -290.423134) (xy 314.04379 -290.398527) (xy 314.089806 -290.381075) (xy 314.138025 -290.371231)
			(xy 314.1872 -290.36925) (xy 314.236055 -290.375182) (xy 314.283326 -290.388874) (xy 314.327788 -290.409972)
			(xy 314.368291 -290.437928) (xy 314.403784 -290.47202) (xy 314.433349 -290.511364) (xy 314.45622 -290.554941)
			(xy 314.471804 -290.601622) (xy 314.479699 -290.650199) (xy 314.480194 -290.674806) (xy 314.819042 -290.674806)
			(xy 314.823002 -290.625752) (xy 314.834779 -290.577968) (xy 314.85407 -290.532692) (xy 314.880373 -290.491096)
			(xy 314.913008 -290.454259) (xy 314.951129 -290.423134) (xy 314.99375 -290.398527) (xy 315.039766 -290.381075)
			(xy 315.087985 -290.371231) (xy 315.13716 -290.36925) (xy 315.186015 -290.375182) (xy 315.233286 -290.388874)
			(xy 315.277748 -290.409972) (xy 315.318251 -290.437928) (xy 315.353744 -290.47202) (xy 315.383309 -290.511364)
			(xy 315.40618 -290.554941) (xy 315.421764 -290.601622) (xy 315.429659 -290.650199) (xy 315.430154 -290.674806)
			(xy 315.429659 -290.699413) (xy 315.421764 -290.74799) (xy 315.40618 -290.794671) (xy 315.383309 -290.838248)
			(xy 315.353744 -290.877592) (xy 315.318251 -290.911684) (xy 315.277748 -290.93964) (xy 315.233286 -290.960738)
			(xy 315.186015 -290.97443) (xy 315.13716 -290.980362) (xy 315.087985 -290.978381) (xy 315.039766 -290.968537)
			(xy 314.99375 -290.951085) (xy 314.951129 -290.926478) (xy 314.913008 -290.895353) (xy 314.880373 -290.858516)
			(xy 314.85407 -290.81692) (xy 314.834779 -290.771644) (xy 314.823002 -290.72386) (xy 314.819042 -290.674806)
			(xy 314.480194 -290.674806) (xy 314.479699 -290.699413) (xy 314.471804 -290.74799) (xy 314.45622 -290.794671)
			(xy 314.433349 -290.838248) (xy 314.403784 -290.877592) (xy 314.368291 -290.911684) (xy 314.327788 -290.93964)
			(xy 314.283326 -290.960738) (xy 314.236055 -290.97443) (xy 314.1872 -290.980362) (xy 314.138025 -290.978381)
			(xy 314.089806 -290.968537) (xy 314.04379 -290.951085) (xy 314.001169 -290.926478) (xy 313.963048 -290.895353)
			(xy 313.930413 -290.858516) (xy 313.90411 -290.81692) (xy 313.884819 -290.771644) (xy 313.873042 -290.72386)
			(xy 313.869082 -290.674806) (xy 313.530234 -290.674806) (xy 313.529739 -290.699413) (xy 313.521844 -290.74799)
			(xy 313.50626 -290.794671) (xy 313.483389 -290.838248) (xy 313.453824 -290.877592) (xy 313.418331 -290.911684)
			(xy 313.377828 -290.93964) (xy 313.333366 -290.960738) (xy 313.286095 -290.97443) (xy 313.23724 -290.980362)
			(xy 313.188065 -290.978381) (xy 313.139846 -290.968537) (xy 313.09383 -290.951085) (xy 313.051209 -290.926478)
			(xy 313.013088 -290.895353) (xy 312.980453 -290.858516) (xy 312.95415 -290.81692) (xy 312.934859 -290.771644)
			(xy 312.923082 -290.72386) (xy 312.919122 -290.674806) (xy 312.58002 -290.674806) (xy 312.579525 -290.699413)
			(xy 312.57163 -290.74799) (xy 312.556046 -290.794671) (xy 312.533175 -290.838248) (xy 312.50361 -290.877592)
			(xy 312.468117 -290.911684) (xy 312.427614 -290.93964) (xy 312.383152 -290.960738) (xy 312.335881 -290.97443)
			(xy 312.287026 -290.980362) (xy 312.237851 -290.978381) (xy 312.189632 -290.968537) (xy 312.143616 -290.951085)
			(xy 312.100995 -290.926478) (xy 312.062874 -290.895353) (xy 312.030239 -290.858516) (xy 312.003936 -290.81692)
			(xy 311.984645 -290.771644) (xy 311.972868 -290.72386) (xy 311.968908 -290.674806) (xy 311.63006 -290.674806)
			(xy 311.629565 -290.699413) (xy 311.62167 -290.74799) (xy 311.606086 -290.794671) (xy 311.583215 -290.838248)
			(xy 311.55365 -290.877592) (xy 311.518157 -290.911684) (xy 311.477654 -290.93964) (xy 311.433192 -290.960738)
			(xy 311.385921 -290.97443) (xy 311.337066 -290.980362) (xy 311.287891 -290.978381) (xy 311.239672 -290.968537)
			(xy 311.193656 -290.951085) (xy 311.151035 -290.926478) (xy 311.112914 -290.895353) (xy 311.080279 -290.858516)
			(xy 311.053976 -290.81692) (xy 311.034685 -290.771644) (xy 311.022908 -290.72386) (xy 311.018948 -290.674806)
			(xy 310.6801 -290.674806) (xy 310.679605 -290.699413) (xy 310.67171 -290.74799) (xy 310.656126 -290.794671)
			(xy 310.633255 -290.838248) (xy 310.60369 -290.877592) (xy 310.568197 -290.911684) (xy 310.527694 -290.93964)
			(xy 310.483232 -290.960738) (xy 310.435961 -290.97443) (xy 310.387106 -290.980362) (xy 310.337931 -290.978381)
			(xy 310.289712 -290.968537) (xy 310.243696 -290.951085) (xy 310.201075 -290.926478) (xy 310.162954 -290.895353)
			(xy 310.130319 -290.858516) (xy 310.104016 -290.81692) (xy 310.084725 -290.771644) (xy 310.072948 -290.72386)
			(xy 310.068988 -290.674806) (xy 309.73014 -290.674806) (xy 309.729645 -290.699413) (xy 309.72175 -290.74799)
			(xy 309.706166 -290.794671) (xy 309.683295 -290.838248) (xy 309.65373 -290.877592) (xy 309.618237 -290.911684)
			(xy 309.577734 -290.93964) (xy 309.533272 -290.960738) (xy 309.486001 -290.97443) (xy 309.437146 -290.980362)
			(xy 309.387971 -290.978381) (xy 309.339752 -290.968537) (xy 309.293736 -290.951085) (xy 309.251115 -290.926478)
			(xy 309.212994 -290.895353) (xy 309.180359 -290.858516) (xy 309.154056 -290.81692) (xy 309.134765 -290.771644)
			(xy 309.122988 -290.72386) (xy 309.119028 -290.674806) (xy 308.78018 -290.674806) (xy 308.779685 -290.699413)
			(xy 308.77179 -290.74799) (xy 308.756206 -290.794671) (xy 308.733335 -290.838248) (xy 308.70377 -290.877592)
			(xy 308.668277 -290.911684) (xy 308.627774 -290.93964) (xy 308.583312 -290.960738) (xy 308.536041 -290.97443)
			(xy 308.487186 -290.980362) (xy 308.438011 -290.978381) (xy 308.389792 -290.968537) (xy 308.343776 -290.951085)
			(xy 308.301155 -290.926478) (xy 308.263034 -290.895353) (xy 308.230399 -290.858516) (xy 308.204096 -290.81692)
			(xy 308.184805 -290.771644) (xy 308.173028 -290.72386) (xy 308.169068 -290.674806) (xy 307.83022 -290.674806)
			(xy 307.829725 -290.699413) (xy 307.82183 -290.74799) (xy 307.806246 -290.794671) (xy 307.783375 -290.838248)
			(xy 307.75381 -290.877592) (xy 307.718317 -290.911684) (xy 307.677814 -290.93964) (xy 307.633352 -290.960738)
			(xy 307.586081 -290.97443) (xy 307.537226 -290.980362) (xy 307.488051 -290.978381) (xy 307.439832 -290.968537)
			(xy 307.393816 -290.951085) (xy 307.351195 -290.926478) (xy 307.313074 -290.895353) (xy 307.280439 -290.858516)
			(xy 307.254136 -290.81692) (xy 307.234845 -290.771644) (xy 307.223068 -290.72386) (xy 307.219108 -290.674806)
			(xy 306.880006 -290.674806) (xy 306.879511 -290.699413) (xy 306.871616 -290.74799) (xy 306.856032 -290.794671)
			(xy 306.833161 -290.838248) (xy 306.803596 -290.877592) (xy 306.768103 -290.911684) (xy 306.7276 -290.93964)
			(xy 306.683138 -290.960738) (xy 306.635867 -290.97443) (xy 306.587012 -290.980362) (xy 306.537837 -290.978381)
			(xy 306.489618 -290.968537) (xy 306.443602 -290.951085) (xy 306.400981 -290.926478) (xy 306.36286 -290.895353)
			(xy 306.330225 -290.858516) (xy 306.303922 -290.81692) (xy 306.284631 -290.771644) (xy 306.272854 -290.72386)
			(xy 306.268894 -290.674806) (xy 305.930046 -290.674806) (xy 305.929551 -290.699413) (xy 305.921656 -290.74799)
			(xy 305.906072 -290.794671) (xy 305.883201 -290.838248) (xy 305.853636 -290.877592) (xy 305.818143 -290.911684)
			(xy 305.77764 -290.93964) (xy 305.733178 -290.960738) (xy 305.685907 -290.97443) (xy 305.637052 -290.980362)
			(xy 305.587877 -290.978381) (xy 305.539658 -290.968537) (xy 305.493642 -290.951085) (xy 305.451021 -290.926478)
			(xy 305.4129 -290.895353) (xy 305.380265 -290.858516) (xy 305.353962 -290.81692) (xy 305.334671 -290.771644)
			(xy 305.322894 -290.72386) (xy 305.318934 -290.674806) (xy 304.980086 -290.674806) (xy 304.979591 -290.699413)
			(xy 304.971696 -290.74799) (xy 304.956112 -290.794671) (xy 304.933241 -290.838248) (xy 304.903676 -290.877592)
			(xy 304.868183 -290.911684) (xy 304.82768 -290.93964) (xy 304.783218 -290.960738) (xy 304.735947 -290.97443)
			(xy 304.687092 -290.980362) (xy 304.637917 -290.978381) (xy 304.589698 -290.968537) (xy 304.543682 -290.951085)
			(xy 304.501061 -290.926478) (xy 304.46294 -290.895353) (xy 304.430305 -290.858516) (xy 304.404002 -290.81692)
			(xy 304.384711 -290.771644) (xy 304.372934 -290.72386) (xy 304.368974 -290.674806) (xy 304.030126 -290.674806)
			(xy 304.029631 -290.699413) (xy 304.021736 -290.74799) (xy 304.006152 -290.794671) (xy 303.983281 -290.838248)
			(xy 303.953716 -290.877592) (xy 303.918223 -290.911684) (xy 303.87772 -290.93964) (xy 303.833258 -290.960738)
			(xy 303.785987 -290.97443) (xy 303.737132 -290.980362) (xy 303.687957 -290.978381) (xy 303.639738 -290.968537)
			(xy 303.593722 -290.951085) (xy 303.551101 -290.926478) (xy 303.51298 -290.895353) (xy 303.480345 -290.858516)
			(xy 303.454042 -290.81692) (xy 303.434751 -290.771644) (xy 303.422974 -290.72386) (xy 303.419014 -290.674806)
			(xy 303.080166 -290.674806) (xy 303.079671 -290.699413) (xy 303.071776 -290.74799) (xy 303.056192 -290.794671)
			(xy 303.033321 -290.838248) (xy 303.003756 -290.877592) (xy 302.968263 -290.911684) (xy 302.92776 -290.93964)
			(xy 302.883298 -290.960738) (xy 302.836027 -290.97443) (xy 302.787172 -290.980362) (xy 302.737997 -290.978381)
			(xy 302.689778 -290.968537) (xy 302.643762 -290.951085) (xy 302.601141 -290.926478) (xy 302.56302 -290.895353)
			(xy 302.530385 -290.858516) (xy 302.504082 -290.81692) (xy 302.484791 -290.771644) (xy 302.473014 -290.72386)
			(xy 302.469054 -290.674806) (xy 302.130206 -290.674806) (xy 302.129711 -290.699413) (xy 302.121816 -290.74799)
			(xy 302.106232 -290.794671) (xy 302.083361 -290.838248) (xy 302.053796 -290.877592) (xy 302.018303 -290.911684)
			(xy 301.9778 -290.93964) (xy 301.933338 -290.960738) (xy 301.886067 -290.97443) (xy 301.837212 -290.980362)
			(xy 301.788037 -290.978381) (xy 301.739818 -290.968537) (xy 301.693802 -290.951085) (xy 301.651181 -290.926478)
			(xy 301.61306 -290.895353) (xy 301.580425 -290.858516) (xy 301.554122 -290.81692) (xy 301.534831 -290.771644)
			(xy 301.523054 -290.72386) (xy 301.519094 -290.674806) (xy 301.179992 -290.674806) (xy 301.179497 -290.699413)
			(xy 301.171602 -290.74799) (xy 301.156018 -290.794671) (xy 301.133147 -290.838248) (xy 301.103582 -290.877592)
			(xy 301.068089 -290.911684) (xy 301.027586 -290.93964) (xy 300.983124 -290.960738) (xy 300.935853 -290.97443)
			(xy 300.886998 -290.980362) (xy 300.837823 -290.978381) (xy 300.789604 -290.968537) (xy 300.743588 -290.951085)
			(xy 300.700967 -290.926478) (xy 300.662846 -290.895353) (xy 300.630211 -290.858516) (xy 300.603908 -290.81692)
			(xy 300.584617 -290.771644) (xy 300.57284 -290.72386) (xy 300.56888 -290.674806) (xy 300.230032 -290.674806)
			(xy 300.229537 -290.699413) (xy 300.221642 -290.74799) (xy 300.206058 -290.794671) (xy 300.183187 -290.838248)
			(xy 300.153622 -290.877592) (xy 300.118129 -290.911684) (xy 300.077626 -290.93964) (xy 300.033164 -290.960738)
			(xy 299.985893 -290.97443) (xy 299.937038 -290.980362) (xy 299.887863 -290.978381) (xy 299.839644 -290.968537)
			(xy 299.793628 -290.951085) (xy 299.751007 -290.926478) (xy 299.712886 -290.895353) (xy 299.680251 -290.858516)
			(xy 299.653948 -290.81692) (xy 299.634657 -290.771644) (xy 299.62288 -290.72386) (xy 299.61892 -290.674806)
			(xy 299.280072 -290.674806) (xy 299.279577 -290.699413) (xy 299.271682 -290.74799) (xy 299.256098 -290.794671)
			(xy 299.233227 -290.838248) (xy 299.203662 -290.877592) (xy 299.168169 -290.911684) (xy 299.127666 -290.93964)
			(xy 299.083204 -290.960738) (xy 299.035933 -290.97443) (xy 298.987078 -290.980362) (xy 298.937903 -290.978381)
			(xy 298.889684 -290.968537) (xy 298.843668 -290.951085) (xy 298.801047 -290.926478) (xy 298.762926 -290.895353)
			(xy 298.730291 -290.858516) (xy 298.703988 -290.81692) (xy 298.684697 -290.771644) (xy 298.67292 -290.72386)
			(xy 298.66896 -290.674806) (xy 298.330112 -290.674806) (xy 298.329617 -290.699413) (xy 298.321722 -290.74799)
			(xy 298.306138 -290.794671) (xy 298.283267 -290.838248) (xy 298.253702 -290.877592) (xy 298.218209 -290.911684)
			(xy 298.177706 -290.93964) (xy 298.133244 -290.960738) (xy 298.085973 -290.97443) (xy 298.037118 -290.980362)
			(xy 297.987943 -290.978381) (xy 297.939724 -290.968537) (xy 297.893708 -290.951085) (xy 297.851087 -290.926478)
			(xy 297.812966 -290.895353) (xy 297.780331 -290.858516) (xy 297.754028 -290.81692) (xy 297.734737 -290.771644)
			(xy 297.72296 -290.72386) (xy 297.719 -290.674806) (xy 297.380152 -290.674806) (xy 297.379657 -290.699413)
			(xy 297.371762 -290.74799) (xy 297.356178 -290.794671) (xy 297.333307 -290.838248) (xy 297.303742 -290.877592)
			(xy 297.268249 -290.911684) (xy 297.227746 -290.93964) (xy 297.183284 -290.960738) (xy 297.136013 -290.97443)
			(xy 297.087158 -290.980362) (xy 297.037983 -290.978381) (xy 296.989764 -290.968537) (xy 296.943748 -290.951085)
			(xy 296.901127 -290.926478) (xy 296.863006 -290.895353) (xy 296.830371 -290.858516) (xy 296.804068 -290.81692)
			(xy 296.784777 -290.771644) (xy 296.773 -290.72386) (xy 296.76904 -290.674806) (xy 296.430192 -290.674806)
			(xy 296.429697 -290.699413) (xy 296.421802 -290.74799) (xy 296.406218 -290.794671) (xy 296.383347 -290.838248)
			(xy 296.353782 -290.877592) (xy 296.318289 -290.911684) (xy 296.277786 -290.93964) (xy 296.233324 -290.960738)
			(xy 296.186053 -290.97443) (xy 296.137198 -290.980362) (xy 296.088023 -290.978381) (xy 296.039804 -290.968537)
			(xy 295.993788 -290.951085) (xy 295.951167 -290.926478) (xy 295.913046 -290.895353) (xy 295.880411 -290.858516)
			(xy 295.854108 -290.81692) (xy 295.834817 -290.771644) (xy 295.82304 -290.72386) (xy 295.81908 -290.674806)
			(xy 295.480232 -290.674806) (xy 295.479737 -290.699413) (xy 295.471842 -290.74799) (xy 295.456258 -290.794671)
			(xy 295.433387 -290.838248) (xy 295.403822 -290.877592) (xy 295.368329 -290.911684) (xy 295.327826 -290.93964)
			(xy 295.283364 -290.960738) (xy 295.236093 -290.97443) (xy 295.187238 -290.980362) (xy 295.138063 -290.978381)
			(xy 295.089844 -290.968537) (xy 295.043828 -290.951085) (xy 295.001207 -290.926478) (xy 294.963086 -290.895353)
			(xy 294.930451 -290.858516) (xy 294.904148 -290.81692) (xy 294.884857 -290.771644) (xy 294.87308 -290.72386)
			(xy 294.86912 -290.674806) (xy 294.530018 -290.674806) (xy 294.529523 -290.699413) (xy 294.521628 -290.74799)
			(xy 294.506044 -290.794671) (xy 294.483173 -290.838248) (xy 294.453608 -290.877592) (xy 294.418115 -290.911684)
			(xy 294.377612 -290.93964) (xy 294.33315 -290.960738) (xy 294.285879 -290.97443) (xy 294.237024 -290.980362)
			(xy 294.187849 -290.978381) (xy 294.13963 -290.968537) (xy 294.093614 -290.951085) (xy 294.050993 -290.926478)
			(xy 294.012872 -290.895353) (xy 293.980237 -290.858516) (xy 293.953934 -290.81692) (xy 293.934643 -290.771644)
			(xy 293.922866 -290.72386) (xy 293.918906 -290.674806) (xy 293.580058 -290.674806) (xy 293.579563 -290.699413)
			(xy 293.571668 -290.74799) (xy 293.556084 -290.794671) (xy 293.533213 -290.838248) (xy 293.503648 -290.877592)
			(xy 293.468155 -290.911684) (xy 293.427652 -290.93964) (xy 293.38319 -290.960738) (xy 293.335919 -290.97443)
			(xy 293.287064 -290.980362) (xy 293.237889 -290.978381) (xy 293.18967 -290.968537) (xy 293.143654 -290.951085)
			(xy 293.101033 -290.926478) (xy 293.062912 -290.895353) (xy 293.030277 -290.858516) (xy 293.003974 -290.81692)
			(xy 292.984683 -290.771644) (xy 292.972906 -290.72386) (xy 292.968946 -290.674806) (xy 292.630098 -290.674806)
			(xy 292.629603 -290.699413) (xy 292.621708 -290.74799) (xy 292.606124 -290.794671) (xy 292.583253 -290.838248)
			(xy 292.553688 -290.877592) (xy 292.518195 -290.911684) (xy 292.477692 -290.93964) (xy 292.43323 -290.960738)
			(xy 292.385959 -290.97443) (xy 292.337104 -290.980362) (xy 292.287929 -290.978381) (xy 292.23971 -290.968537)
			(xy 292.193694 -290.951085) (xy 292.151073 -290.926478) (xy 292.112952 -290.895353) (xy 292.080317 -290.858516)
			(xy 292.054014 -290.81692) (xy 292.034723 -290.771644) (xy 292.022946 -290.72386) (xy 292.018986 -290.674806)
			(xy 290.730178 -290.674806) (xy 290.729683 -290.699413) (xy 290.721788 -290.74799) (xy 290.706204 -290.794671)
			(xy 290.683333 -290.838248) (xy 290.653768 -290.877592) (xy 290.618275 -290.911684) (xy 290.577772 -290.93964)
			(xy 290.53331 -290.960738) (xy 290.486039 -290.97443) (xy 290.437184 -290.980362) (xy 290.388009 -290.978381)
			(xy 290.33979 -290.968537) (xy 290.293774 -290.951085) (xy 290.251153 -290.926478) (xy 290.213032 -290.895353)
			(xy 290.180397 -290.858516) (xy 290.154094 -290.81692) (xy 290.134803 -290.771644) (xy 290.123026 -290.72386)
			(xy 290.119066 -290.674806) (xy 289.780218 -290.674806) (xy 289.779723 -290.699413) (xy 289.771828 -290.74799)
			(xy 289.756244 -290.794671) (xy 289.733373 -290.838248) (xy 289.703808 -290.877592) (xy 289.668315 -290.911684)
			(xy 289.627812 -290.93964) (xy 289.58335 -290.960738) (xy 289.536079 -290.97443) (xy 289.487224 -290.980362)
			(xy 289.438049 -290.978381) (xy 289.38983 -290.968537) (xy 289.343814 -290.951085) (xy 289.301193 -290.926478)
			(xy 289.263072 -290.895353) (xy 289.230437 -290.858516) (xy 289.204134 -290.81692) (xy 289.184843 -290.771644)
			(xy 289.173066 -290.72386) (xy 289.169106 -290.674806) (xy 288.830004 -290.674806) (xy 288.829509 -290.699413)
			(xy 288.821614 -290.74799) (xy 288.80603 -290.794671) (xy 288.783159 -290.838248) (xy 288.753594 -290.877592)
			(xy 288.718101 -290.911684) (xy 288.677598 -290.93964) (xy 288.633136 -290.960738) (xy 288.585865 -290.97443)
			(xy 288.53701 -290.980362) (xy 288.487835 -290.978381) (xy 288.439616 -290.968537) (xy 288.3936 -290.951085)
			(xy 288.350979 -290.926478) (xy 288.312858 -290.895353) (xy 288.280223 -290.858516) (xy 288.25392 -290.81692)
			(xy 288.234629 -290.771644) (xy 288.222852 -290.72386) (xy 288.218892 -290.674806) (xy 287.880044 -290.674806)
			(xy 287.879549 -290.699413) (xy 287.871654 -290.74799) (xy 287.85607 -290.794671) (xy 287.833199 -290.838248)
			(xy 287.803634 -290.877592) (xy 287.768141 -290.911684) (xy 287.727638 -290.93964) (xy 287.683176 -290.960738)
			(xy 287.635905 -290.97443) (xy 287.58705 -290.980362) (xy 287.537875 -290.978381) (xy 287.489656 -290.968537)
			(xy 287.44364 -290.951085) (xy 287.401019 -290.926478) (xy 287.362898 -290.895353) (xy 287.330263 -290.858516)
			(xy 287.30396 -290.81692) (xy 287.284669 -290.771644) (xy 287.272892 -290.72386) (xy 287.268932 -290.674806)
			(xy 286.930084 -290.674806) (xy 286.929589 -290.699413) (xy 286.921694 -290.74799) (xy 286.90611 -290.794671)
			(xy 286.883239 -290.838248) (xy 286.853674 -290.877592) (xy 286.818181 -290.911684) (xy 286.777678 -290.93964)
			(xy 286.733216 -290.960738) (xy 286.685945 -290.97443) (xy 286.63709 -290.980362) (xy 286.587915 -290.978381)
			(xy 286.539696 -290.968537) (xy 286.49368 -290.951085) (xy 286.451059 -290.926478) (xy 286.412938 -290.895353)
			(xy 286.380303 -290.858516) (xy 286.354 -290.81692) (xy 286.334709 -290.771644) (xy 286.322932 -290.72386)
			(xy 286.318972 -290.674806) (xy 285.980124 -290.674806) (xy 285.979629 -290.699413) (xy 285.971734 -290.74799)
			(xy 285.95615 -290.794671) (xy 285.933279 -290.838248) (xy 285.903714 -290.877592) (xy 285.868221 -290.911684)
			(xy 285.827718 -290.93964) (xy 285.783256 -290.960738) (xy 285.735985 -290.97443) (xy 285.68713 -290.980362)
			(xy 285.637955 -290.978381) (xy 285.589736 -290.968537) (xy 285.54372 -290.951085) (xy 285.501099 -290.926478)
			(xy 285.462978 -290.895353) (xy 285.430343 -290.858516) (xy 285.40404 -290.81692) (xy 285.384749 -290.771644)
			(xy 285.372972 -290.72386) (xy 285.369012 -290.674806) (xy 285.030164 -290.674806) (xy 285.029669 -290.699413)
			(xy 285.021774 -290.74799) (xy 285.00619 -290.794671) (xy 284.983319 -290.838248) (xy 284.953754 -290.877592)
			(xy 284.918261 -290.911684) (xy 284.877758 -290.93964) (xy 284.833296 -290.960738) (xy 284.786025 -290.97443)
			(xy 284.73717 -290.980362) (xy 284.687995 -290.978381) (xy 284.639776 -290.968537) (xy 284.59376 -290.951085)
			(xy 284.551139 -290.926478) (xy 284.513018 -290.895353) (xy 284.480383 -290.858516) (xy 284.45408 -290.81692)
			(xy 284.434789 -290.771644) (xy 284.423012 -290.72386) (xy 284.419052 -290.674806) (xy 284.080204 -290.674806)
			(xy 284.079709 -290.699413) (xy 284.071814 -290.74799) (xy 284.05623 -290.794671) (xy 284.033359 -290.838248)
			(xy 284.003794 -290.877592) (xy 283.968301 -290.911684) (xy 283.927798 -290.93964) (xy 283.883336 -290.960738)
			(xy 283.836065 -290.97443) (xy 283.78721 -290.980362) (xy 283.738035 -290.978381) (xy 283.689816 -290.968537)
			(xy 283.6438 -290.951085) (xy 283.601179 -290.926478) (xy 283.563058 -290.895353) (xy 283.530423 -290.858516)
			(xy 283.50412 -290.81692) (xy 283.484829 -290.771644) (xy 283.473052 -290.72386) (xy 283.469092 -290.674806)
			(xy 283.130244 -290.674806) (xy 283.129749 -290.699413) (xy 283.121854 -290.74799) (xy 283.10627 -290.794671)
			(xy 283.083399 -290.838248) (xy 283.053834 -290.877592) (xy 283.018341 -290.911684) (xy 282.977838 -290.93964)
			(xy 282.933376 -290.960738) (xy 282.886105 -290.97443) (xy 282.83725 -290.980362) (xy 282.788075 -290.978381)
			(xy 282.739856 -290.968537) (xy 282.69384 -290.951085) (xy 282.651219 -290.926478) (xy 282.613098 -290.895353)
			(xy 282.580463 -290.858516) (xy 282.55416 -290.81692) (xy 282.534869 -290.771644) (xy 282.523092 -290.72386)
			(xy 282.519132 -290.674806) (xy 282.18003 -290.674806) (xy 282.179535 -290.699413) (xy 282.17164 -290.74799)
			(xy 282.156056 -290.794671) (xy 282.133185 -290.838248) (xy 282.10362 -290.877592) (xy 282.068127 -290.911684)
			(xy 282.027624 -290.93964) (xy 281.983162 -290.960738) (xy 281.935891 -290.97443) (xy 281.887036 -290.980362)
			(xy 281.837861 -290.978381) (xy 281.789642 -290.968537) (xy 281.743626 -290.951085) (xy 281.701005 -290.926478)
			(xy 281.662884 -290.895353) (xy 281.630249 -290.858516) (xy 281.603946 -290.81692) (xy 281.584655 -290.771644)
			(xy 281.572878 -290.72386) (xy 281.568918 -290.674806) (xy 281.23007 -290.674806) (xy 281.229575 -290.699413)
			(xy 281.22168 -290.74799) (xy 281.206096 -290.794671) (xy 281.183225 -290.838248) (xy 281.15366 -290.877592)
			(xy 281.118167 -290.911684) (xy 281.077664 -290.93964) (xy 281.033202 -290.960738) (xy 280.985931 -290.97443)
			(xy 280.937076 -290.980362) (xy 280.887901 -290.978381) (xy 280.839682 -290.968537) (xy 280.793666 -290.951085)
			(xy 280.751045 -290.926478) (xy 280.712924 -290.895353) (xy 280.680289 -290.858516) (xy 280.653986 -290.81692)
			(xy 280.634695 -290.771644) (xy 280.622918 -290.72386) (xy 280.618958 -290.674806) (xy 280.28011 -290.674806)
			(xy 280.279615 -290.699413) (xy 280.27172 -290.74799) (xy 280.256136 -290.794671) (xy 280.233265 -290.838248)
			(xy 280.2037 -290.877592) (xy 280.168207 -290.911684) (xy 280.127704 -290.93964) (xy 280.083242 -290.960738)
			(xy 280.035971 -290.97443) (xy 279.987116 -290.980362) (xy 279.937941 -290.978381) (xy 279.889722 -290.968537)
			(xy 279.843706 -290.951085) (xy 279.801085 -290.926478) (xy 279.762964 -290.895353) (xy 279.730329 -290.858516)
			(xy 279.704026 -290.81692) (xy 279.684735 -290.771644) (xy 279.672958 -290.72386) (xy 279.668998 -290.674806)
			(xy 279.33015 -290.674806) (xy 279.329655 -290.699413) (xy 279.32176 -290.74799) (xy 279.306176 -290.794671)
			(xy 279.283305 -290.838248) (xy 279.25374 -290.877592) (xy 279.218247 -290.911684) (xy 279.177744 -290.93964)
			(xy 279.133282 -290.960738) (xy 279.086011 -290.97443) (xy 279.037156 -290.980362) (xy 278.987981 -290.978381)
			(xy 278.939762 -290.968537) (xy 278.893746 -290.951085) (xy 278.851125 -290.926478) (xy 278.813004 -290.895353)
			(xy 278.780369 -290.858516) (xy 278.754066 -290.81692) (xy 278.734775 -290.771644) (xy 278.722998 -290.72386)
			(xy 278.719038 -290.674806) (xy 278.38019 -290.674806) (xy 278.379695 -290.699413) (xy 278.3718 -290.74799)
			(xy 278.356216 -290.794671) (xy 278.333345 -290.838248) (xy 278.30378 -290.877592) (xy 278.268287 -290.911684)
			(xy 278.227784 -290.93964) (xy 278.183322 -290.960738) (xy 278.136051 -290.97443) (xy 278.087196 -290.980362)
			(xy 278.038021 -290.978381) (xy 277.989802 -290.968537) (xy 277.943786 -290.951085) (xy 277.901165 -290.926478)
			(xy 277.863044 -290.895353) (xy 277.830409 -290.858516) (xy 277.804106 -290.81692) (xy 277.784815 -290.771644)
			(xy 277.773038 -290.72386) (xy 277.769078 -290.674806) (xy 277.43023 -290.674806) (xy 277.429735 -290.699413)
			(xy 277.42184 -290.74799) (xy 277.406256 -290.794671) (xy 277.383385 -290.838248) (xy 277.35382 -290.877592)
			(xy 277.318327 -290.911684) (xy 277.277824 -290.93964) (xy 277.233362 -290.960738) (xy 277.186091 -290.97443)
			(xy 277.137236 -290.980362) (xy 277.088061 -290.978381) (xy 277.039842 -290.968537) (xy 276.993826 -290.951085)
			(xy 276.951205 -290.926478) (xy 276.913084 -290.895353) (xy 276.880449 -290.858516) (xy 276.854146 -290.81692)
			(xy 276.834855 -290.771644) (xy 276.823078 -290.72386) (xy 276.819118 -290.674806) (xy 276.480016 -290.674806)
			(xy 276.479521 -290.699413) (xy 276.471626 -290.74799) (xy 276.456042 -290.794671) (xy 276.433171 -290.838248)
			(xy 276.403606 -290.877592) (xy 276.368113 -290.911684) (xy 276.32761 -290.93964) (xy 276.283148 -290.960738)
			(xy 276.235877 -290.97443) (xy 276.187022 -290.980362) (xy 276.137847 -290.978381) (xy 276.089628 -290.968537)
			(xy 276.043612 -290.951085) (xy 276.000991 -290.926478) (xy 275.96287 -290.895353) (xy 275.930235 -290.858516)
			(xy 275.903932 -290.81692) (xy 275.884641 -290.771644) (xy 275.872864 -290.72386) (xy 275.868904 -290.674806)
			(xy 275.530056 -290.674806) (xy 275.529561 -290.699413) (xy 275.521666 -290.74799) (xy 275.506082 -290.794671)
			(xy 275.483211 -290.838248) (xy 275.453646 -290.877592) (xy 275.418153 -290.911684) (xy 275.37765 -290.93964)
			(xy 275.333188 -290.960738) (xy 275.285917 -290.97443) (xy 275.237062 -290.980362) (xy 275.187887 -290.978381)
			(xy 275.139668 -290.968537) (xy 275.093652 -290.951085) (xy 275.051031 -290.926478) (xy 275.01291 -290.895353)
			(xy 274.980275 -290.858516) (xy 274.953972 -290.81692) (xy 274.934681 -290.771644) (xy 274.922904 -290.72386)
			(xy 274.918944 -290.674806) (xy 274.580096 -290.674806) (xy 274.579601 -290.699413) (xy 274.571706 -290.74799)
			(xy 274.556122 -290.794671) (xy 274.533251 -290.838248) (xy 274.503686 -290.877592) (xy 274.468193 -290.911684)
			(xy 274.42769 -290.93964) (xy 274.383228 -290.960738) (xy 274.335957 -290.97443) (xy 274.287102 -290.980362)
			(xy 274.237927 -290.978381) (xy 274.189708 -290.968537) (xy 274.143692 -290.951085) (xy 274.101071 -290.926478)
			(xy 274.06295 -290.895353) (xy 274.030315 -290.858516) (xy 274.004012 -290.81692) (xy 273.984721 -290.771644)
			(xy 273.972944 -290.72386) (xy 273.968984 -290.674806) (xy 273.630136 -290.674806) (xy 273.629641 -290.699413)
			(xy 273.621746 -290.74799) (xy 273.606162 -290.794671) (xy 273.583291 -290.838248) (xy 273.553726 -290.877592)
			(xy 273.518233 -290.911684) (xy 273.47773 -290.93964) (xy 273.433268 -290.960738) (xy 273.385997 -290.97443)
			(xy 273.337142 -290.980362) (xy 273.287967 -290.978381) (xy 273.239748 -290.968537) (xy 273.193732 -290.951085)
			(xy 273.151111 -290.926478) (xy 273.11299 -290.895353) (xy 273.080355 -290.858516) (xy 273.054052 -290.81692)
			(xy 273.034761 -290.771644) (xy 273.022984 -290.72386) (xy 273.019024 -290.674806) (xy 270.780256 -290.674806)
			(xy 270.779761 -290.699413) (xy 270.771866 -290.74799) (xy 270.756282 -290.794671) (xy 270.733411 -290.838248)
			(xy 270.703846 -290.877592) (xy 270.668353 -290.911684) (xy 270.62785 -290.93964) (xy 270.583388 -290.960738)
			(xy 270.536117 -290.97443) (xy 270.487262 -290.980362) (xy 270.438087 -290.978381) (xy 270.389868 -290.968537)
			(xy 270.343852 -290.951085) (xy 270.301231 -290.926478) (xy 270.26311 -290.895353) (xy 270.230475 -290.858516)
			(xy 270.204172 -290.81692) (xy 270.184881 -290.771644) (xy 270.173104 -290.72386) (xy 270.169144 -290.674806)
			(xy 269.830042 -290.674806) (xy 269.829547 -290.699413) (xy 269.821652 -290.74799) (xy 269.806068 -290.794671)
			(xy 269.783197 -290.838248) (xy 269.753632 -290.877592) (xy 269.718139 -290.911684) (xy 269.677636 -290.93964)
			(xy 269.633174 -290.960738) (xy 269.585903 -290.97443) (xy 269.537048 -290.980362) (xy 269.487873 -290.978381)
			(xy 269.439654 -290.968537) (xy 269.393638 -290.951085) (xy 269.351017 -290.926478) (xy 269.312896 -290.895353)
			(xy 269.280261 -290.858516) (xy 269.253958 -290.81692) (xy 269.234667 -290.771644) (xy 269.22289 -290.72386)
			(xy 269.21893 -290.674806) (xy 268.880082 -290.674806) (xy 268.879587 -290.699413) (xy 268.871692 -290.74799)
			(xy 268.856108 -290.794671) (xy 268.833237 -290.838248) (xy 268.803672 -290.877592) (xy 268.768179 -290.911684)
			(xy 268.727676 -290.93964) (xy 268.683214 -290.960738) (xy 268.635943 -290.97443) (xy 268.587088 -290.980362)
			(xy 268.537913 -290.978381) (xy 268.489694 -290.968537) (xy 268.443678 -290.951085) (xy 268.401057 -290.926478)
			(xy 268.362936 -290.895353) (xy 268.330301 -290.858516) (xy 268.303998 -290.81692) (xy 268.284707 -290.771644)
			(xy 268.27293 -290.72386) (xy 268.26897 -290.674806) (xy 266.228425 -290.674806) (xy 266.216874 -290.676077)
			(xy 266.16114 -290.67404) (xy 266.106297 -290.66391) (xy 266.053513 -290.645903) (xy 266.003913 -290.620402)
			(xy 265.958555 -290.587951) (xy 265.918406 -290.549242) (xy 265.88432 -290.505099) (xy 265.857024 -290.456464)
			(xy 265.837101 -290.404373) (xy 265.824975 -290.349936) (xy 265.820904 -290.294314) (xy 265.69797 -290.294314)
			(xy 265.697461 -290.3222) (xy 265.689341 -290.377376) (xy 265.673273 -290.430783) (xy 265.649601 -290.48128)
			(xy 265.618828 -290.527793) (xy 265.581611 -290.56933) (xy 265.538743 -290.605005) (xy 265.491137 -290.634059)
			(xy 265.439808 -290.655871) (xy 265.385851 -290.669977) (xy 265.330414 -290.676077) (xy 265.27468 -290.67404)
			(xy 265.219837 -290.66391) (xy 265.167053 -290.645903) (xy 265.117453 -290.620402) (xy 265.072095 -290.587951)
			(xy 265.031946 -290.549242) (xy 264.99786 -290.505099) (xy 264.970564 -290.456464) (xy 264.950641 -290.404373)
			(xy 264.938515 -290.349936) (xy 264.934444 -290.294314) (xy 264.30097 -290.294314) (xy 264.300484 -290.321565)
			(xy 264.292728 -290.375513) (xy 264.277373 -290.427808) (xy 264.254731 -290.477385) (xy 264.225265 -290.523235)
			(xy 264.189574 -290.564426) (xy 264.148383 -290.600117) (xy 264.102533 -290.629583) (xy 264.052956 -290.652225)
			(xy 264.000661 -290.66758) (xy 263.946713 -290.675336) (xy 263.892211 -290.675336) (xy 263.838263 -290.66758)
			(xy 263.785968 -290.652225) (xy 263.736391 -290.629583) (xy 263.690541 -290.600117) (xy 263.64935 -290.564426)
			(xy 263.613659 -290.523235) (xy 263.584193 -290.477385) (xy 263.561551 -290.427808) (xy 263.546196 -290.375513)
			(xy 263.53844 -290.321565) (xy 263.537954 -290.294314) (xy 234.5309 -290.294314) (xy 234.5309 -290.900149)
			(xy 243.338104 -290.900149) (xy 243.338104 -290.845651) (xy 243.34586 -290.791707) (xy 243.361214 -290.739416)
			(xy 243.383853 -290.689843) (xy 243.413317 -290.643996) (xy 243.449006 -290.602809) (xy 243.490193 -290.567119)
			(xy 243.536039 -290.537655) (xy 243.585613 -290.515015) (xy 243.637903 -290.499661) (xy 243.691847 -290.491904)
			(xy 243.719096 -290.491418) (xy 243.746466 -290.491882) (xy 243.800646 -290.4997) (xy 243.853149 -290.515189)
			(xy 243.902896 -290.538031) (xy 243.948862 -290.567756) (xy 243.969794 -290.585398) (xy 243.976906 -290.591494)
			(xy 243.993924 -290.597844) (xy 244.079268 -290.597844) (xy 244.096286 -290.591494) (xy 244.103398 -290.585398)
			(xy 244.12432 -290.567746) (xy 244.170295 -290.538036) (xy 244.220046 -290.515203) (xy 244.272549 -290.499715)
			(xy 244.326726 -290.49189) (xy 244.354096 -290.491418) (xy 244.381351 -290.491829) (xy 244.435306 -290.499586)
			(xy 244.487608 -290.514942) (xy 244.537192 -290.537586) (xy 244.583049 -290.567056) (xy 244.624245 -290.602752)
			(xy 244.659941 -290.643948) (xy 244.689412 -290.689804) (xy 244.712056 -290.739388) (xy 244.727413 -290.79169)
			(xy 244.735171 -290.845645) (xy 244.735171 -290.900149) (xy 245.078004 -290.900149) (xy 245.078004 -290.845651)
			(xy 245.08576 -290.791707) (xy 245.101114 -290.739416) (xy 245.123753 -290.689843) (xy 245.153217 -290.643996)
			(xy 245.188906 -290.602809) (xy 245.230093 -290.567119) (xy 245.275939 -290.537655) (xy 245.325513 -290.515015)
			(xy 245.377803 -290.499661) (xy 245.431747 -290.491904) (xy 245.458996 -290.491418) (xy 245.486366 -290.491882)
			(xy 245.540546 -290.4997) (xy 245.593049 -290.515189) (xy 245.642796 -290.538031) (xy 245.688762 -290.567756)
			(xy 245.709694 -290.585398) (xy 245.716806 -290.591494) (xy 245.733824 -290.597844) (xy 245.819168 -290.597844)
			(xy 245.836186 -290.591494) (xy 245.843298 -290.585398) (xy 245.86422 -290.567746) (xy 245.910195 -290.538036)
			(xy 245.959946 -290.515203) (xy 246.012449 -290.499715) (xy 246.066626 -290.49189) (xy 246.093996 -290.491418)
			(xy 246.121251 -290.491829) (xy 246.175206 -290.499586) (xy 246.227508 -290.514942) (xy 246.277092 -290.537586)
			(xy 246.322949 -290.567056) (xy 246.364145 -290.602752) (xy 246.399841 -290.643948) (xy 246.429312 -290.689804)
			(xy 246.451956 -290.739388) (xy 246.467313 -290.79169) (xy 246.475071 -290.845645) (xy 246.475071 -290.900155)
			(xy 246.467313 -290.95411) (xy 246.451956 -291.006412) (xy 246.429312 -291.055996) (xy 246.399841 -291.101852)
			(xy 246.364145 -291.143048) (xy 246.322949 -291.178744) (xy 246.277092 -291.208214) (xy 246.227508 -291.230858)
			(xy 246.175206 -291.246214) (xy 246.121251 -291.253971) (xy 246.093996 -291.254434) (xy 246.066625 -291.253986)
			(xy 246.012444 -291.246167) (xy 245.95994 -291.230674) (xy 245.910194 -291.207828) (xy 245.864228 -291.178098)
			(xy 245.843298 -291.160454) (xy 245.836186 -291.154358) (xy 245.819168 -291.148008) (xy 245.733824 -291.148008)
			(xy 245.716806 -291.154358) (xy 245.709694 -291.160454) (xy 245.688769 -291.178102) (xy 245.642795 -291.207814)
			(xy 245.593046 -291.230649) (xy 245.540543 -291.246138) (xy 245.486366 -291.253962) (xy 245.458996 -291.254434)
			(xy 245.431747 -291.253896) (xy 245.377803 -291.246139) (xy 245.325513 -291.230785) (xy 245.275939 -291.208145)
			(xy 245.230093 -291.178681) (xy 245.188906 -291.142991) (xy 245.153217 -291.101804) (xy 245.123753 -291.055957)
			(xy 245.101114 -291.006384) (xy 245.08576 -290.954093) (xy 245.078004 -290.900149) (xy 244.735171 -290.900149)
			(xy 244.735171 -290.900155) (xy 244.727413 -290.95411) (xy 244.712056 -291.006412) (xy 244.689412 -291.055996)
			(xy 244.659941 -291.101852) (xy 244.624245 -291.143048) (xy 244.583049 -291.178744) (xy 244.537192 -291.208214)
			(xy 244.487608 -291.230858) (xy 244.435306 -291.246214) (xy 244.381351 -291.253971) (xy 244.354096 -291.254434)
			(xy 244.326725 -291.253986) (xy 244.272544 -291.246167) (xy 244.22004 -291.230674) (xy 244.170294 -291.207828)
			(xy 244.124328 -291.178098) (xy 244.103398 -291.160454) (xy 244.096286 -291.154358) (xy 244.079268 -291.148008)
			(xy 243.993924 -291.148008) (xy 243.976906 -291.154358) (xy 243.969794 -291.160454) (xy 243.948869 -291.178102)
			(xy 243.902895 -291.207814) (xy 243.853146 -291.230649) (xy 243.800643 -291.246138) (xy 243.746466 -291.253962)
			(xy 243.719096 -291.254434) (xy 243.691847 -291.253896) (xy 243.637903 -291.246139) (xy 243.585613 -291.230785)
			(xy 243.536039 -291.208145) (xy 243.490193 -291.178681) (xy 243.449006 -291.142991) (xy 243.413317 -291.101804)
			(xy 243.383853 -291.055957) (xy 243.361214 -291.006384) (xy 243.34586 -290.954093) (xy 243.338104 -290.900149)
			(xy 234.5309 -290.900149) (xy 234.5309 -291.17671) (xy 234.531408 -291.183568) (xy 234.532842 -291.191976)
			(xy 234.540513 -291.207198) (xy 234.552778 -291.219035) (xy 234.560364 -291.222938) (xy 234.562142 -291.2237)
			(xy 234.66298 -291.26561) (xy 234.693206 -291.259768) (xy 234.704128 -291.248592) (xy 234.725757 -291.227684)
			(xy 234.774375 -291.192261) (xy 234.827947 -291.164902) (xy 234.885148 -291.146285) (xy 234.944561 -291.13687)
			(xy 234.974638 -291.136324) (xy 235.000245 -291.136721) (xy 235.051003 -291.14354) (xy 235.100392 -291.15709)
			(xy 235.147523 -291.177128) (xy 235.191548 -291.203294) (xy 235.211874 -291.218874) (xy 235.215684 -291.221922)
			(xy 235.22051 -291.224462) (xy 235.225982 -291.227134) (xy 235.237793 -291.230083) (xy 235.243878 -291.230304)
			(xy 235.27639 -291.230304) (xy 235.27639 -291.24148) (xy 235.336334 -291.24148) (xy 235.353352 -291.23513)
			(xy 235.360464 -291.229034) (xy 235.381342 -291.211643) (xy 235.427093 -291.18233) (xy 235.476541 -291.159807)
			(xy 235.528685 -291.144531) (xy 235.58247 -291.13681) (xy 235.609638 -291.136324) (xy 235.636885 -291.136813)
			(xy 235.690824 -291.144573) (xy 235.74311 -291.15993) (xy 235.792678 -291.182572) (xy 235.83852 -291.212036)
			(xy 235.879702 -291.247725) (xy 235.915386 -291.288911) (xy 235.944847 -291.334755) (xy 235.967483 -291.384326)
			(xy 235.982835 -291.436613) (xy 235.99059 -291.490553) (xy 235.99059 -291.545047) (xy 235.99059 -291.545049)
			(xy 236.34701 -291.545049) (xy 236.34701 -291.490551) (xy 236.354766 -291.436608) (xy 236.37012 -291.384318)
			(xy 236.392759 -291.334745) (xy 236.422223 -291.288898) (xy 236.457911 -291.247711) (xy 236.499098 -291.212023)
			(xy 236.544945 -291.182559) (xy 236.594518 -291.15992) (xy 236.646808 -291.144566) (xy 236.700751 -291.13681)
			(xy 236.728 -291.136324) (xy 236.755371 -291.136784) (xy 236.80955 -291.144603) (xy 236.862053 -291.160093)
			(xy 236.9118 -291.182936) (xy 236.957767 -291.212662) (xy 236.978698 -291.230304) (xy 236.98581 -291.2364)
			(xy 237.002828 -291.24275) (xy 237.088172 -291.24275) (xy 237.10519 -291.2364) (xy 237.112302 -291.230304)
			(xy 237.133223 -291.212651) (xy 237.179199 -291.182941) (xy 237.228949 -291.160108) (xy 237.281452 -291.14462)
			(xy 237.33563 -291.136796) (xy 237.363 -291.136324) (xy 237.390254 -291.136746) (xy 237.444206 -291.144503)
			(xy 237.496505 -291.159859) (xy 237.546086 -291.182502) (xy 237.591941 -291.211971) (xy 237.633134 -291.247666)
			(xy 237.668829 -291.288859) (xy 237.698298 -291.334714) (xy 237.720941 -291.384295) (xy 237.734495 -291.430456)
			(xy 258.01142 -291.430456) (xy 258.015491 -291.374834) (xy 258.027617 -291.320397) (xy 258.04754 -291.268306)
			(xy 258.074836 -291.219671) (xy 258.108922 -291.175528) (xy 258.149071 -291.136819) (xy 258.194429 -291.104368)
			(xy 258.244029 -291.078867) (xy 258.296813 -291.06086) (xy 258.351656 -291.05073) (xy 258.40739 -291.048693)
			(xy 258.462827 -291.054793) (xy 258.516784 -291.068899) (xy 258.568113 -291.090711) (xy 258.615719 -291.119765)
			(xy 258.658587 -291.15544) (xy 258.695804 -291.196977) (xy 258.726577 -291.24349) (xy 258.750249 -291.293987)
			(xy 258.766317 -291.347394) (xy 258.774437 -291.40257) (xy 258.774946 -291.430456) (xy 259.496558 -291.430456)
			(xy 259.500629 -291.374834) (xy 259.512755 -291.320397) (xy 259.532678 -291.268306) (xy 259.559974 -291.219671)
			(xy 259.59406 -291.175528) (xy 259.634209 -291.136819) (xy 259.679567 -291.104368) (xy 259.729167 -291.078867)
			(xy 259.781951 -291.06086) (xy 259.836794 -291.05073) (xy 259.892528 -291.048693) (xy 259.947965 -291.054793)
			(xy 260.001922 -291.068899) (xy 260.053251 -291.090711) (xy 260.100857 -291.119765) (xy 260.143725 -291.15544)
			(xy 260.180942 -291.196977) (xy 260.211715 -291.24349) (xy 260.235387 -291.293987) (xy 260.251455 -291.347394)
			(xy 260.259575 -291.40257) (xy 260.260084 -291.430456) (xy 260.259575 -291.458342) (xy 260.251455 -291.513518)
			(xy 260.235387 -291.566925) (xy 260.211715 -291.617422) (xy 260.206856 -291.624766) (xy 268.26897 -291.624766)
			(xy 268.27293 -291.575712) (xy 268.284707 -291.527928) (xy 268.303998 -291.482652) (xy 268.330301 -291.441056)
			(xy 268.362936 -291.404219) (xy 268.401057 -291.373094) (xy 268.443678 -291.348487) (xy 268.489694 -291.331035)
			(xy 268.537913 -291.321191) (xy 268.587088 -291.31921) (xy 268.635943 -291.325142) (xy 268.683214 -291.338834)
			(xy 268.727676 -291.359932) (xy 268.768179 -291.387888) (xy 268.803672 -291.42198) (xy 268.833237 -291.461324)
			(xy 268.856108 -291.504901) (xy 268.871692 -291.551582) (xy 268.879587 -291.600159) (xy 268.880082 -291.624766)
			(xy 269.21893 -291.624766) (xy 269.22289 -291.575712) (xy 269.234667 -291.527928) (xy 269.253958 -291.482652)
			(xy 269.280261 -291.441056) (xy 269.312896 -291.404219) (xy 269.351017 -291.373094) (xy 269.393638 -291.348487)
			(xy 269.439654 -291.331035) (xy 269.487873 -291.321191) (xy 269.537048 -291.31921) (xy 269.585903 -291.325142)
			(xy 269.633174 -291.338834) (xy 269.677636 -291.359932) (xy 269.718139 -291.387888) (xy 269.753632 -291.42198)
			(xy 269.783197 -291.461324) (xy 269.806068 -291.504901) (xy 269.821652 -291.551582) (xy 269.829547 -291.600159)
			(xy 269.830042 -291.624766) (xy 270.169144 -291.624766) (xy 270.173104 -291.575712) (xy 270.184881 -291.527928)
			(xy 270.204172 -291.482652) (xy 270.230475 -291.441056) (xy 270.26311 -291.404219) (xy 270.301231 -291.373094)
			(xy 270.343852 -291.348487) (xy 270.389868 -291.331035) (xy 270.438087 -291.321191) (xy 270.487262 -291.31921)
			(xy 270.536117 -291.325142) (xy 270.583388 -291.338834) (xy 270.62785 -291.359932) (xy 270.668353 -291.387888)
			(xy 270.703846 -291.42198) (xy 270.733411 -291.461324) (xy 270.756282 -291.504901) (xy 270.771866 -291.551582)
			(xy 270.779761 -291.600159) (xy 270.780256 -291.624766) (xy 273.019024 -291.624766) (xy 273.022984 -291.575712)
			(xy 273.034761 -291.527928) (xy 273.054052 -291.482652) (xy 273.080355 -291.441056) (xy 273.11299 -291.404219)
			(xy 273.151111 -291.373094) (xy 273.193732 -291.348487) (xy 273.239748 -291.331035) (xy 273.287967 -291.321191)
			(xy 273.337142 -291.31921) (xy 273.385997 -291.325142) (xy 273.433268 -291.338834) (xy 273.47773 -291.359932)
			(xy 273.518233 -291.387888) (xy 273.553726 -291.42198) (xy 273.583291 -291.461324) (xy 273.606162 -291.504901)
			(xy 273.621746 -291.551582) (xy 273.629641 -291.600159) (xy 273.630136 -291.624766) (xy 273.968984 -291.624766)
			(xy 273.972944 -291.575712) (xy 273.984721 -291.527928) (xy 274.004012 -291.482652) (xy 274.030315 -291.441056)
			(xy 274.06295 -291.404219) (xy 274.101071 -291.373094) (xy 274.143692 -291.348487) (xy 274.189708 -291.331035)
			(xy 274.237927 -291.321191) (xy 274.287102 -291.31921) (xy 274.335957 -291.325142) (xy 274.383228 -291.338834)
			(xy 274.42769 -291.359932) (xy 274.468193 -291.387888) (xy 274.503686 -291.42198) (xy 274.533251 -291.461324)
			(xy 274.556122 -291.504901) (xy 274.571706 -291.551582) (xy 274.579601 -291.600159) (xy 274.580096 -291.624766)
			(xy 274.918944 -291.624766) (xy 274.922904 -291.575712) (xy 274.934681 -291.527928) (xy 274.953972 -291.482652)
			(xy 274.980275 -291.441056) (xy 275.01291 -291.404219) (xy 275.051031 -291.373094) (xy 275.093652 -291.348487)
			(xy 275.139668 -291.331035) (xy 275.187887 -291.321191) (xy 275.237062 -291.31921) (xy 275.285917 -291.325142)
			(xy 275.333188 -291.338834) (xy 275.37765 -291.359932) (xy 275.418153 -291.387888) (xy 275.453646 -291.42198)
			(xy 275.483211 -291.461324) (xy 275.506082 -291.504901) (xy 275.521666 -291.551582) (xy 275.529561 -291.600159)
			(xy 275.530056 -291.624766) (xy 275.868904 -291.624766) (xy 275.872864 -291.575712) (xy 275.884641 -291.527928)
			(xy 275.903932 -291.482652) (xy 275.930235 -291.441056) (xy 275.96287 -291.404219) (xy 276.000991 -291.373094)
			(xy 276.043612 -291.348487) (xy 276.089628 -291.331035) (xy 276.137847 -291.321191) (xy 276.187022 -291.31921)
			(xy 276.235877 -291.325142) (xy 276.283148 -291.338834) (xy 276.32761 -291.359932) (xy 276.368113 -291.387888)
			(xy 276.403606 -291.42198) (xy 276.433171 -291.461324) (xy 276.456042 -291.504901) (xy 276.471626 -291.551582)
			(xy 276.479521 -291.600159) (xy 276.480016 -291.624766) (xy 276.819118 -291.624766) (xy 276.823078 -291.575712)
			(xy 276.834855 -291.527928) (xy 276.854146 -291.482652) (xy 276.880449 -291.441056) (xy 276.913084 -291.404219)
			(xy 276.951205 -291.373094) (xy 276.993826 -291.348487) (xy 277.039842 -291.331035) (xy 277.088061 -291.321191)
			(xy 277.137236 -291.31921) (xy 277.186091 -291.325142) (xy 277.233362 -291.338834) (xy 277.277824 -291.359932)
			(xy 277.318327 -291.387888) (xy 277.35382 -291.42198) (xy 277.383385 -291.461324) (xy 277.406256 -291.504901)
			(xy 277.42184 -291.551582) (xy 277.429735 -291.600159) (xy 277.43023 -291.624766) (xy 277.769078 -291.624766)
			(xy 277.773038 -291.575712) (xy 277.784815 -291.527928) (xy 277.804106 -291.482652) (xy 277.830409 -291.441056)
			(xy 277.863044 -291.404219) (xy 277.901165 -291.373094) (xy 277.943786 -291.348487) (xy 277.989802 -291.331035)
			(xy 278.038021 -291.321191) (xy 278.087196 -291.31921) (xy 278.136051 -291.325142) (xy 278.183322 -291.338834)
			(xy 278.227784 -291.359932) (xy 278.268287 -291.387888) (xy 278.30378 -291.42198) (xy 278.333345 -291.461324)
			(xy 278.356216 -291.504901) (xy 278.3718 -291.551582) (xy 278.379695 -291.600159) (xy 278.38019 -291.624766)
			(xy 279.668998 -291.624766) (xy 279.672958 -291.575712) (xy 279.684735 -291.527928) (xy 279.704026 -291.482652)
			(xy 279.730329 -291.441056) (xy 279.762964 -291.404219) (xy 279.801085 -291.373094) (xy 279.843706 -291.348487)
			(xy 279.889722 -291.331035) (xy 279.937941 -291.321191) (xy 279.987116 -291.31921) (xy 280.035971 -291.325142)
			(xy 280.083242 -291.338834) (xy 280.127704 -291.359932) (xy 280.168207 -291.387888) (xy 280.2037 -291.42198)
			(xy 280.233265 -291.461324) (xy 280.256136 -291.504901) (xy 280.27172 -291.551582) (xy 280.279615 -291.600159)
			(xy 280.28011 -291.624766) (xy 280.618958 -291.624766) (xy 280.622918 -291.575712) (xy 280.634695 -291.527928)
			(xy 280.653986 -291.482652) (xy 280.680289 -291.441056) (xy 280.712924 -291.404219) (xy 280.751045 -291.373094)
			(xy 280.793666 -291.348487) (xy 280.839682 -291.331035) (xy 280.887901 -291.321191) (xy 280.937076 -291.31921)
			(xy 280.985931 -291.325142) (xy 281.033202 -291.338834) (xy 281.077664 -291.359932) (xy 281.118167 -291.387888)
			(xy 281.15366 -291.42198) (xy 281.183225 -291.461324) (xy 281.206096 -291.504901) (xy 281.22168 -291.551582)
			(xy 281.229575 -291.600159) (xy 281.23007 -291.624766) (xy 281.568918 -291.624766) (xy 281.572878 -291.575712)
			(xy 281.584655 -291.527928) (xy 281.603946 -291.482652) (xy 281.630249 -291.441056) (xy 281.662884 -291.404219)
			(xy 281.701005 -291.373094) (xy 281.743626 -291.348487) (xy 281.789642 -291.331035) (xy 281.837861 -291.321191)
			(xy 281.887036 -291.31921) (xy 281.935891 -291.325142) (xy 281.983162 -291.338834) (xy 282.027624 -291.359932)
			(xy 282.068127 -291.387888) (xy 282.10362 -291.42198) (xy 282.133185 -291.461324) (xy 282.156056 -291.504901)
			(xy 282.17164 -291.551582) (xy 282.179535 -291.600159) (xy 282.18003 -291.624766) (xy 282.519132 -291.624766)
			(xy 282.523092 -291.575712) (xy 282.534869 -291.527928) (xy 282.55416 -291.482652) (xy 282.580463 -291.441056)
			(xy 282.613098 -291.404219) (xy 282.651219 -291.373094) (xy 282.69384 -291.348487) (xy 282.739856 -291.331035)
			(xy 282.788075 -291.321191) (xy 282.83725 -291.31921) (xy 282.886105 -291.325142) (xy 282.933376 -291.338834)
			(xy 282.977838 -291.359932) (xy 283.018341 -291.387888) (xy 283.053834 -291.42198) (xy 283.083399 -291.461324)
			(xy 283.10627 -291.504901) (xy 283.121854 -291.551582) (xy 283.129749 -291.600159) (xy 283.130244 -291.624766)
			(xy 283.469092 -291.624766) (xy 283.473052 -291.575712) (xy 283.484829 -291.527928) (xy 283.50412 -291.482652)
			(xy 283.530423 -291.441056) (xy 283.563058 -291.404219) (xy 283.601179 -291.373094) (xy 283.6438 -291.348487)
			(xy 283.689816 -291.331035) (xy 283.738035 -291.321191) (xy 283.78721 -291.31921) (xy 283.836065 -291.325142)
			(xy 283.883336 -291.338834) (xy 283.927798 -291.359932) (xy 283.968301 -291.387888) (xy 284.003794 -291.42198)
			(xy 284.033359 -291.461324) (xy 284.05623 -291.504901) (xy 284.071814 -291.551582) (xy 284.079709 -291.600159)
			(xy 284.080204 -291.624766) (xy 284.419052 -291.624766) (xy 284.423012 -291.575712) (xy 284.434789 -291.527928)
			(xy 284.45408 -291.482652) (xy 284.480383 -291.441056) (xy 284.513018 -291.404219) (xy 284.551139 -291.373094)
			(xy 284.59376 -291.348487) (xy 284.639776 -291.331035) (xy 284.687995 -291.321191) (xy 284.73717 -291.31921)
			(xy 284.786025 -291.325142) (xy 284.833296 -291.338834) (xy 284.877758 -291.359932) (xy 284.918261 -291.387888)
			(xy 284.953754 -291.42198) (xy 284.983319 -291.461324) (xy 285.00619 -291.504901) (xy 285.021774 -291.551582)
			(xy 285.029669 -291.600159) (xy 285.030164 -291.624766) (xy 285.369012 -291.624766) (xy 285.372972 -291.575712)
			(xy 285.384749 -291.527928) (xy 285.40404 -291.482652) (xy 285.430343 -291.441056) (xy 285.462978 -291.404219)
			(xy 285.501099 -291.373094) (xy 285.54372 -291.348487) (xy 285.589736 -291.331035) (xy 285.637955 -291.321191)
			(xy 285.68713 -291.31921) (xy 285.735985 -291.325142) (xy 285.783256 -291.338834) (xy 285.827718 -291.359932)
			(xy 285.868221 -291.387888) (xy 285.903714 -291.42198) (xy 285.933279 -291.461324) (xy 285.95615 -291.504901)
			(xy 285.971734 -291.551582) (xy 285.979629 -291.600159) (xy 285.980124 -291.624766) (xy 286.318972 -291.624766)
			(xy 286.322932 -291.575712) (xy 286.334709 -291.527928) (xy 286.354 -291.482652) (xy 286.380303 -291.441056)
			(xy 286.412938 -291.404219) (xy 286.451059 -291.373094) (xy 286.49368 -291.348487) (xy 286.539696 -291.331035)
			(xy 286.587915 -291.321191) (xy 286.63709 -291.31921) (xy 286.685945 -291.325142) (xy 286.733216 -291.338834)
			(xy 286.777678 -291.359932) (xy 286.818181 -291.387888) (xy 286.853674 -291.42198) (xy 286.883239 -291.461324)
			(xy 286.90611 -291.504901) (xy 286.921694 -291.551582) (xy 286.929589 -291.600159) (xy 286.930084 -291.624766)
			(xy 287.268932 -291.624766) (xy 287.272892 -291.575712) (xy 287.284669 -291.527928) (xy 287.30396 -291.482652)
			(xy 287.330263 -291.441056) (xy 287.362898 -291.404219) (xy 287.401019 -291.373094) (xy 287.44364 -291.348487)
			(xy 287.489656 -291.331035) (xy 287.537875 -291.321191) (xy 287.58705 -291.31921) (xy 287.635905 -291.325142)
			(xy 287.683176 -291.338834) (xy 287.727638 -291.359932) (xy 287.768141 -291.387888) (xy 287.803634 -291.42198)
			(xy 287.833199 -291.461324) (xy 287.85607 -291.504901) (xy 287.871654 -291.551582) (xy 287.879549 -291.600159)
			(xy 287.880044 -291.624766) (xy 288.218892 -291.624766) (xy 288.222852 -291.575712) (xy 288.234629 -291.527928)
			(xy 288.25392 -291.482652) (xy 288.280223 -291.441056) (xy 288.312858 -291.404219) (xy 288.350979 -291.373094)
			(xy 288.3936 -291.348487) (xy 288.439616 -291.331035) (xy 288.487835 -291.321191) (xy 288.53701 -291.31921)
			(xy 288.585865 -291.325142) (xy 288.633136 -291.338834) (xy 288.677598 -291.359932) (xy 288.718101 -291.387888)
			(xy 288.753594 -291.42198) (xy 288.783159 -291.461324) (xy 288.80603 -291.504901) (xy 288.821614 -291.551582)
			(xy 288.829509 -291.600159) (xy 288.830004 -291.624766) (xy 289.169106 -291.624766) (xy 289.173066 -291.575712)
			(xy 289.184843 -291.527928) (xy 289.204134 -291.482652) (xy 289.230437 -291.441056) (xy 289.263072 -291.404219)
			(xy 289.301193 -291.373094) (xy 289.343814 -291.348487) (xy 289.38983 -291.331035) (xy 289.438049 -291.321191)
			(xy 289.487224 -291.31921) (xy 289.536079 -291.325142) (xy 289.58335 -291.338834) (xy 289.627812 -291.359932)
			(xy 289.668315 -291.387888) (xy 289.703808 -291.42198) (xy 289.733373 -291.461324) (xy 289.756244 -291.504901)
			(xy 289.771828 -291.551582) (xy 289.779723 -291.600159) (xy 289.780218 -291.624766) (xy 290.119066 -291.624766)
			(xy 290.123026 -291.575712) (xy 290.134803 -291.527928) (xy 290.154094 -291.482652) (xy 290.180397 -291.441056)
			(xy 290.213032 -291.404219) (xy 290.251153 -291.373094) (xy 290.293774 -291.348487) (xy 290.33979 -291.331035)
			(xy 290.388009 -291.321191) (xy 290.437184 -291.31921) (xy 290.486039 -291.325142) (xy 290.53331 -291.338834)
			(xy 290.577772 -291.359932) (xy 290.618275 -291.387888) (xy 290.653768 -291.42198) (xy 290.683333 -291.461324)
			(xy 290.706204 -291.504901) (xy 290.721788 -291.551582) (xy 290.729683 -291.600159) (xy 290.730178 -291.624766)
			(xy 292.018986 -291.624766) (xy 292.022946 -291.575712) (xy 292.034723 -291.527928) (xy 292.054014 -291.482652)
			(xy 292.080317 -291.441056) (xy 292.112952 -291.404219) (xy 292.151073 -291.373094) (xy 292.193694 -291.348487)
			(xy 292.23971 -291.331035) (xy 292.287929 -291.321191) (xy 292.337104 -291.31921) (xy 292.385959 -291.325142)
			(xy 292.43323 -291.338834) (xy 292.477692 -291.359932) (xy 292.518195 -291.387888) (xy 292.553688 -291.42198)
			(xy 292.583253 -291.461324) (xy 292.606124 -291.504901) (xy 292.621708 -291.551582) (xy 292.629603 -291.600159)
			(xy 292.630098 -291.624766) (xy 292.968946 -291.624766) (xy 292.972906 -291.575712) (xy 292.984683 -291.527928)
			(xy 293.003974 -291.482652) (xy 293.030277 -291.441056) (xy 293.062912 -291.404219) (xy 293.101033 -291.373094)
			(xy 293.143654 -291.348487) (xy 293.18967 -291.331035) (xy 293.237889 -291.321191) (xy 293.287064 -291.31921)
			(xy 293.335919 -291.325142) (xy 293.38319 -291.338834) (xy 293.427652 -291.359932) (xy 293.468155 -291.387888)
			(xy 293.503648 -291.42198) (xy 293.533213 -291.461324) (xy 293.556084 -291.504901) (xy 293.571668 -291.551582)
			(xy 293.579563 -291.600159) (xy 293.580058 -291.624766) (xy 293.918906 -291.624766) (xy 293.922866 -291.575712)
			(xy 293.934643 -291.527928) (xy 293.953934 -291.482652) (xy 293.980237 -291.441056) (xy 294.012872 -291.404219)
			(xy 294.050993 -291.373094) (xy 294.093614 -291.348487) (xy 294.13963 -291.331035) (xy 294.187849 -291.321191)
			(xy 294.237024 -291.31921) (xy 294.285879 -291.325142) (xy 294.33315 -291.338834) (xy 294.377612 -291.359932)
			(xy 294.418115 -291.387888) (xy 294.453608 -291.42198) (xy 294.483173 -291.461324) (xy 294.506044 -291.504901)
			(xy 294.521628 -291.551582) (xy 294.529523 -291.600159) (xy 294.530018 -291.624766) (xy 294.86912 -291.624766)
			(xy 294.87308 -291.575712) (xy 294.884857 -291.527928) (xy 294.904148 -291.482652) (xy 294.930451 -291.441056)
			(xy 294.963086 -291.404219) (xy 295.001207 -291.373094) (xy 295.043828 -291.348487) (xy 295.089844 -291.331035)
			(xy 295.138063 -291.321191) (xy 295.187238 -291.31921) (xy 295.236093 -291.325142) (xy 295.283364 -291.338834)
			(xy 295.327826 -291.359932) (xy 295.368329 -291.387888) (xy 295.403822 -291.42198) (xy 295.433387 -291.461324)
			(xy 295.456258 -291.504901) (xy 295.471842 -291.551582) (xy 295.479737 -291.600159) (xy 295.480232 -291.624766)
			(xy 295.81908 -291.624766) (xy 295.82304 -291.575712) (xy 295.834817 -291.527928) (xy 295.854108 -291.482652)
			(xy 295.880411 -291.441056) (xy 295.913046 -291.404219) (xy 295.951167 -291.373094) (xy 295.993788 -291.348487)
			(xy 296.039804 -291.331035) (xy 296.088023 -291.321191) (xy 296.137198 -291.31921) (xy 296.186053 -291.325142)
			(xy 296.233324 -291.338834) (xy 296.277786 -291.359932) (xy 296.318289 -291.387888) (xy 296.353782 -291.42198)
			(xy 296.383347 -291.461324) (xy 296.406218 -291.504901) (xy 296.421802 -291.551582) (xy 296.429697 -291.600159)
			(xy 296.430192 -291.624766) (xy 296.76904 -291.624766) (xy 296.773 -291.575712) (xy 296.784777 -291.527928)
			(xy 296.804068 -291.482652) (xy 296.830371 -291.441056) (xy 296.863006 -291.404219) (xy 296.901127 -291.373094)
			(xy 296.943748 -291.348487) (xy 296.989764 -291.331035) (xy 297.037983 -291.321191) (xy 297.087158 -291.31921)
			(xy 297.136013 -291.325142) (xy 297.183284 -291.338834) (xy 297.227746 -291.359932) (xy 297.268249 -291.387888)
			(xy 297.303742 -291.42198) (xy 297.333307 -291.461324) (xy 297.356178 -291.504901) (xy 297.371762 -291.551582)
			(xy 297.379657 -291.600159) (xy 297.380152 -291.624766) (xy 297.719 -291.624766) (xy 297.72296 -291.575712)
			(xy 297.734737 -291.527928) (xy 297.754028 -291.482652) (xy 297.780331 -291.441056) (xy 297.812966 -291.404219)
			(xy 297.851087 -291.373094) (xy 297.893708 -291.348487) (xy 297.939724 -291.331035) (xy 297.987943 -291.321191)
			(xy 298.037118 -291.31921) (xy 298.085973 -291.325142) (xy 298.133244 -291.338834) (xy 298.177706 -291.359932)
			(xy 298.218209 -291.387888) (xy 298.253702 -291.42198) (xy 298.283267 -291.461324) (xy 298.306138 -291.504901)
			(xy 298.321722 -291.551582) (xy 298.329617 -291.600159) (xy 298.330112 -291.624766) (xy 298.66896 -291.624766)
			(xy 298.67292 -291.575712) (xy 298.684697 -291.527928) (xy 298.703988 -291.482652) (xy 298.730291 -291.441056)
			(xy 298.762926 -291.404219) (xy 298.801047 -291.373094) (xy 298.843668 -291.348487) (xy 298.889684 -291.331035)
			(xy 298.937903 -291.321191) (xy 298.987078 -291.31921) (xy 299.035933 -291.325142) (xy 299.083204 -291.338834)
			(xy 299.127666 -291.359932) (xy 299.168169 -291.387888) (xy 299.203662 -291.42198) (xy 299.233227 -291.461324)
			(xy 299.256098 -291.504901) (xy 299.271682 -291.551582) (xy 299.279577 -291.600159) (xy 299.280072 -291.624766)
			(xy 299.61892 -291.624766) (xy 299.62288 -291.575712) (xy 299.634657 -291.527928) (xy 299.653948 -291.482652)
			(xy 299.680251 -291.441056) (xy 299.712886 -291.404219) (xy 299.751007 -291.373094) (xy 299.793628 -291.348487)
			(xy 299.839644 -291.331035) (xy 299.887863 -291.321191) (xy 299.937038 -291.31921) (xy 299.985893 -291.325142)
			(xy 300.033164 -291.338834) (xy 300.077626 -291.359932) (xy 300.118129 -291.387888) (xy 300.153622 -291.42198)
			(xy 300.183187 -291.461324) (xy 300.206058 -291.504901) (xy 300.221642 -291.551582) (xy 300.229537 -291.600159)
			(xy 300.230032 -291.624766) (xy 300.56888 -291.624766) (xy 300.57284 -291.575712) (xy 300.584617 -291.527928)
			(xy 300.603908 -291.482652) (xy 300.630211 -291.441056) (xy 300.662846 -291.404219) (xy 300.700967 -291.373094)
			(xy 300.743588 -291.348487) (xy 300.789604 -291.331035) (xy 300.837823 -291.321191) (xy 300.886998 -291.31921)
			(xy 300.935853 -291.325142) (xy 300.983124 -291.338834) (xy 301.027586 -291.359932) (xy 301.068089 -291.387888)
			(xy 301.103582 -291.42198) (xy 301.133147 -291.461324) (xy 301.156018 -291.504901) (xy 301.171602 -291.551582)
			(xy 301.179497 -291.600159) (xy 301.179992 -291.624766) (xy 301.519094 -291.624766) (xy 301.523054 -291.575712)
			(xy 301.534831 -291.527928) (xy 301.554122 -291.482652) (xy 301.580425 -291.441056) (xy 301.61306 -291.404219)
			(xy 301.651181 -291.373094) (xy 301.693802 -291.348487) (xy 301.739818 -291.331035) (xy 301.788037 -291.321191)
			(xy 301.837212 -291.31921) (xy 301.886067 -291.325142) (xy 301.933338 -291.338834) (xy 301.9778 -291.359932)
			(xy 302.018303 -291.387888) (xy 302.053796 -291.42198) (xy 302.083361 -291.461324) (xy 302.106232 -291.504901)
			(xy 302.121816 -291.551582) (xy 302.129711 -291.600159) (xy 302.130206 -291.624766) (xy 302.469054 -291.624766)
			(xy 302.473014 -291.575712) (xy 302.484791 -291.527928) (xy 302.504082 -291.482652) (xy 302.530385 -291.441056)
			(xy 302.56302 -291.404219) (xy 302.601141 -291.373094) (xy 302.643762 -291.348487) (xy 302.689778 -291.331035)
			(xy 302.737997 -291.321191) (xy 302.787172 -291.31921) (xy 302.836027 -291.325142) (xy 302.883298 -291.338834)
			(xy 302.92776 -291.359932) (xy 302.968263 -291.387888) (xy 303.003756 -291.42198) (xy 303.033321 -291.461324)
			(xy 303.056192 -291.504901) (xy 303.071776 -291.551582) (xy 303.079671 -291.600159) (xy 303.080166 -291.624766)
			(xy 303.419014 -291.624766) (xy 303.422974 -291.575712) (xy 303.434751 -291.527928) (xy 303.454042 -291.482652)
			(xy 303.480345 -291.441056) (xy 303.51298 -291.404219) (xy 303.551101 -291.373094) (xy 303.593722 -291.348487)
			(xy 303.639738 -291.331035) (xy 303.687957 -291.321191) (xy 303.737132 -291.31921) (xy 303.785987 -291.325142)
			(xy 303.833258 -291.338834) (xy 303.87772 -291.359932) (xy 303.918223 -291.387888) (xy 303.953716 -291.42198)
			(xy 303.983281 -291.461324) (xy 304.006152 -291.504901) (xy 304.021736 -291.551582) (xy 304.029631 -291.600159)
			(xy 304.030126 -291.624766) (xy 304.368974 -291.624766) (xy 304.372934 -291.575712) (xy 304.384711 -291.527928)
			(xy 304.404002 -291.482652) (xy 304.430305 -291.441056) (xy 304.46294 -291.404219) (xy 304.501061 -291.373094)
			(xy 304.543682 -291.348487) (xy 304.589698 -291.331035) (xy 304.637917 -291.321191) (xy 304.687092 -291.31921)
			(xy 304.735947 -291.325142) (xy 304.783218 -291.338834) (xy 304.82768 -291.359932) (xy 304.868183 -291.387888)
			(xy 304.903676 -291.42198) (xy 304.933241 -291.461324) (xy 304.956112 -291.504901) (xy 304.971696 -291.551582)
			(xy 304.979591 -291.600159) (xy 304.980086 -291.624766) (xy 305.318934 -291.624766) (xy 305.322894 -291.575712)
			(xy 305.334671 -291.527928) (xy 305.353962 -291.482652) (xy 305.380265 -291.441056) (xy 305.4129 -291.404219)
			(xy 305.451021 -291.373094) (xy 305.493642 -291.348487) (xy 305.539658 -291.331035) (xy 305.587877 -291.321191)
			(xy 305.637052 -291.31921) (xy 305.685907 -291.325142) (xy 305.733178 -291.338834) (xy 305.77764 -291.359932)
			(xy 305.818143 -291.387888) (xy 305.853636 -291.42198) (xy 305.883201 -291.461324) (xy 305.906072 -291.504901)
			(xy 305.921656 -291.551582) (xy 305.929551 -291.600159) (xy 305.930046 -291.624766) (xy 306.269148 -291.624766)
			(xy 306.273108 -291.575712) (xy 306.284885 -291.527928) (xy 306.304176 -291.482652) (xy 306.330479 -291.441056)
			(xy 306.363114 -291.404219) (xy 306.401235 -291.373094) (xy 306.443856 -291.348487) (xy 306.489872 -291.331035)
			(xy 306.538091 -291.321191) (xy 306.587266 -291.31921) (xy 306.636121 -291.325142) (xy 306.683392 -291.338834)
			(xy 306.727854 -291.359932) (xy 306.768357 -291.387888) (xy 306.80385 -291.42198) (xy 306.833415 -291.461324)
			(xy 306.856286 -291.504901) (xy 306.87187 -291.551582) (xy 306.879765 -291.600159) (xy 306.88026 -291.624766)
			(xy 308.169068 -291.624766) (xy 308.173028 -291.575712) (xy 308.184805 -291.527928) (xy 308.204096 -291.482652)
			(xy 308.230399 -291.441056) (xy 308.263034 -291.404219) (xy 308.301155 -291.373094) (xy 308.343776 -291.348487)
			(xy 308.389792 -291.331035) (xy 308.438011 -291.321191) (xy 308.487186 -291.31921) (xy 308.536041 -291.325142)
			(xy 308.583312 -291.338834) (xy 308.627774 -291.359932) (xy 308.668277 -291.387888) (xy 308.70377 -291.42198)
			(xy 308.733335 -291.461324) (xy 308.756206 -291.504901) (xy 308.77179 -291.551582) (xy 308.779685 -291.600159)
			(xy 308.78018 -291.624766) (xy 309.119028 -291.624766) (xy 309.122988 -291.575712) (xy 309.134765 -291.527928)
			(xy 309.154056 -291.482652) (xy 309.180359 -291.441056) (xy 309.212994 -291.404219) (xy 309.251115 -291.373094)
			(xy 309.293736 -291.348487) (xy 309.339752 -291.331035) (xy 309.387971 -291.321191) (xy 309.437146 -291.31921)
			(xy 309.486001 -291.325142) (xy 309.533272 -291.338834) (xy 309.577734 -291.359932) (xy 309.618237 -291.387888)
			(xy 309.65373 -291.42198) (xy 309.683295 -291.461324) (xy 309.706166 -291.504901) (xy 309.72175 -291.551582)
			(xy 309.729645 -291.600159) (xy 309.73014 -291.624766) (xy 310.068988 -291.624766) (xy 310.072948 -291.575712)
			(xy 310.084725 -291.527928) (xy 310.104016 -291.482652) (xy 310.130319 -291.441056) (xy 310.162954 -291.404219)
			(xy 310.201075 -291.373094) (xy 310.243696 -291.348487) (xy 310.289712 -291.331035) (xy 310.337931 -291.321191)
			(xy 310.387106 -291.31921) (xy 310.435961 -291.325142) (xy 310.483232 -291.338834) (xy 310.527694 -291.359932)
			(xy 310.568197 -291.387888) (xy 310.60369 -291.42198) (xy 310.633255 -291.461324) (xy 310.656126 -291.504901)
			(xy 310.67171 -291.551582) (xy 310.679605 -291.600159) (xy 310.6801 -291.624766) (xy 311.018948 -291.624766)
			(xy 311.022908 -291.575712) (xy 311.034685 -291.527928) (xy 311.053976 -291.482652) (xy 311.080279 -291.441056)
			(xy 311.112914 -291.404219) (xy 311.151035 -291.373094) (xy 311.193656 -291.348487) (xy 311.239672 -291.331035)
			(xy 311.287891 -291.321191) (xy 311.337066 -291.31921) (xy 311.385921 -291.325142) (xy 311.433192 -291.338834)
			(xy 311.477654 -291.359932) (xy 311.518157 -291.387888) (xy 311.55365 -291.42198) (xy 311.583215 -291.461324)
			(xy 311.606086 -291.504901) (xy 311.62167 -291.551582) (xy 311.629565 -291.600159) (xy 311.63006 -291.624766)
			(xy 311.968908 -291.624766) (xy 311.972868 -291.575712) (xy 311.984645 -291.527928) (xy 312.003936 -291.482652)
			(xy 312.030239 -291.441056) (xy 312.062874 -291.404219) (xy 312.100995 -291.373094) (xy 312.143616 -291.348487)
			(xy 312.189632 -291.331035) (xy 312.237851 -291.321191) (xy 312.287026 -291.31921) (xy 312.335881 -291.325142)
			(xy 312.383152 -291.338834) (xy 312.427614 -291.359932) (xy 312.468117 -291.387888) (xy 312.50361 -291.42198)
			(xy 312.533175 -291.461324) (xy 312.556046 -291.504901) (xy 312.57163 -291.551582) (xy 312.579525 -291.600159)
			(xy 312.58002 -291.624766) (xy 312.919122 -291.624766) (xy 312.923082 -291.575712) (xy 312.934859 -291.527928)
			(xy 312.95415 -291.482652) (xy 312.980453 -291.441056) (xy 313.013088 -291.404219) (xy 313.051209 -291.373094)
			(xy 313.09383 -291.348487) (xy 313.139846 -291.331035) (xy 313.188065 -291.321191) (xy 313.23724 -291.31921)
			(xy 313.286095 -291.325142) (xy 313.333366 -291.338834) (xy 313.377828 -291.359932) (xy 313.418331 -291.387888)
			(xy 313.453824 -291.42198) (xy 313.483389 -291.461324) (xy 313.50626 -291.504901) (xy 313.521844 -291.551582)
			(xy 313.529739 -291.600159) (xy 313.530234 -291.624766) (xy 313.869082 -291.624766) (xy 313.873042 -291.575712)
			(xy 313.884819 -291.527928) (xy 313.90411 -291.482652) (xy 313.930413 -291.441056) (xy 313.963048 -291.404219)
			(xy 314.001169 -291.373094) (xy 314.04379 -291.348487) (xy 314.089806 -291.331035) (xy 314.138025 -291.321191)
			(xy 314.1872 -291.31921) (xy 314.236055 -291.325142) (xy 314.283326 -291.338834) (xy 314.327788 -291.359932)
			(xy 314.368291 -291.387888) (xy 314.403784 -291.42198) (xy 314.433349 -291.461324) (xy 314.45622 -291.504901)
			(xy 314.471804 -291.551582) (xy 314.479699 -291.600159) (xy 314.480194 -291.624766) (xy 314.819042 -291.624766)
			(xy 314.823002 -291.575712) (xy 314.834779 -291.527928) (xy 314.85407 -291.482652) (xy 314.880373 -291.441056)
			(xy 314.913008 -291.404219) (xy 314.951129 -291.373094) (xy 314.99375 -291.348487) (xy 315.039766 -291.331035)
			(xy 315.087985 -291.321191) (xy 315.13716 -291.31921) (xy 315.186015 -291.325142) (xy 315.233286 -291.338834)
			(xy 315.277748 -291.359932) (xy 315.318251 -291.387888) (xy 315.353744 -291.42198) (xy 315.383309 -291.461324)
			(xy 315.40618 -291.504901) (xy 315.421764 -291.551582) (xy 315.429659 -291.600159) (xy 315.430154 -291.624766)
			(xy 315.429659 -291.649373) (xy 315.421764 -291.69795) (xy 315.40618 -291.744631) (xy 315.383309 -291.788208)
			(xy 315.353744 -291.827552) (xy 315.318251 -291.861644) (xy 315.277748 -291.8896) (xy 315.233286 -291.910698)
			(xy 315.186015 -291.92439) (xy 315.13716 -291.930322) (xy 315.087985 -291.928341) (xy 315.039766 -291.918497)
			(xy 314.99375 -291.901045) (xy 314.951129 -291.876438) (xy 314.913008 -291.845313) (xy 314.880373 -291.808476)
			(xy 314.85407 -291.76688) (xy 314.834779 -291.721604) (xy 314.823002 -291.67382) (xy 314.819042 -291.624766)
			(xy 314.480194 -291.624766) (xy 314.479699 -291.649373) (xy 314.471804 -291.69795) (xy 314.45622 -291.744631)
			(xy 314.433349 -291.788208) (xy 314.403784 -291.827552) (xy 314.368291 -291.861644) (xy 314.327788 -291.8896)
			(xy 314.283326 -291.910698) (xy 314.236055 -291.92439) (xy 314.1872 -291.930322) (xy 314.138025 -291.928341)
			(xy 314.089806 -291.918497) (xy 314.04379 -291.901045) (xy 314.001169 -291.876438) (xy 313.963048 -291.845313)
			(xy 313.930413 -291.808476) (xy 313.90411 -291.76688) (xy 313.884819 -291.721604) (xy 313.873042 -291.67382)
			(xy 313.869082 -291.624766) (xy 313.530234 -291.624766) (xy 313.529739 -291.649373) (xy 313.521844 -291.69795)
			(xy 313.50626 -291.744631) (xy 313.483389 -291.788208) (xy 313.453824 -291.827552) (xy 313.418331 -291.861644)
			(xy 313.377828 -291.8896) (xy 313.333366 -291.910698) (xy 313.286095 -291.92439) (xy 313.23724 -291.930322)
			(xy 313.188065 -291.928341) (xy 313.139846 -291.918497) (xy 313.09383 -291.901045) (xy 313.051209 -291.876438)
			(xy 313.013088 -291.845313) (xy 312.980453 -291.808476) (xy 312.95415 -291.76688) (xy 312.934859 -291.721604)
			(xy 312.923082 -291.67382) (xy 312.919122 -291.624766) (xy 312.58002 -291.624766) (xy 312.579525 -291.649373)
			(xy 312.57163 -291.69795) (xy 312.556046 -291.744631) (xy 312.533175 -291.788208) (xy 312.50361 -291.827552)
			(xy 312.468117 -291.861644) (xy 312.427614 -291.8896) (xy 312.383152 -291.910698) (xy 312.335881 -291.92439)
			(xy 312.287026 -291.930322) (xy 312.237851 -291.928341) (xy 312.189632 -291.918497) (xy 312.143616 -291.901045)
			(xy 312.100995 -291.876438) (xy 312.062874 -291.845313) (xy 312.030239 -291.808476) (xy 312.003936 -291.76688)
			(xy 311.984645 -291.721604) (xy 311.972868 -291.67382) (xy 311.968908 -291.624766) (xy 311.63006 -291.624766)
			(xy 311.629565 -291.649373) (xy 311.62167 -291.69795) (xy 311.606086 -291.744631) (xy 311.583215 -291.788208)
			(xy 311.55365 -291.827552) (xy 311.518157 -291.861644) (xy 311.477654 -291.8896) (xy 311.433192 -291.910698)
			(xy 311.385921 -291.92439) (xy 311.337066 -291.930322) (xy 311.287891 -291.928341) (xy 311.239672 -291.918497)
			(xy 311.193656 -291.901045) (xy 311.151035 -291.876438) (xy 311.112914 -291.845313) (xy 311.080279 -291.808476)
			(xy 311.053976 -291.76688) (xy 311.034685 -291.721604) (xy 311.022908 -291.67382) (xy 311.018948 -291.624766)
			(xy 310.6801 -291.624766) (xy 310.679605 -291.649373) (xy 310.67171 -291.69795) (xy 310.656126 -291.744631)
			(xy 310.633255 -291.788208) (xy 310.60369 -291.827552) (xy 310.568197 -291.861644) (xy 310.527694 -291.8896)
			(xy 310.483232 -291.910698) (xy 310.435961 -291.92439) (xy 310.387106 -291.930322) (xy 310.337931 -291.928341)
			(xy 310.289712 -291.918497) (xy 310.243696 -291.901045) (xy 310.201075 -291.876438) (xy 310.162954 -291.845313)
			(xy 310.130319 -291.808476) (xy 310.104016 -291.76688) (xy 310.084725 -291.721604) (xy 310.072948 -291.67382)
			(xy 310.068988 -291.624766) (xy 309.73014 -291.624766) (xy 309.729645 -291.649373) (xy 309.72175 -291.69795)
			(xy 309.706166 -291.744631) (xy 309.683295 -291.788208) (xy 309.65373 -291.827552) (xy 309.618237 -291.861644)
			(xy 309.577734 -291.8896) (xy 309.533272 -291.910698) (xy 309.486001 -291.92439) (xy 309.437146 -291.930322)
			(xy 309.387971 -291.928341) (xy 309.339752 -291.918497) (xy 309.293736 -291.901045) (xy 309.251115 -291.876438)
			(xy 309.212994 -291.845313) (xy 309.180359 -291.808476) (xy 309.154056 -291.76688) (xy 309.134765 -291.721604)
			(xy 309.122988 -291.67382) (xy 309.119028 -291.624766) (xy 308.78018 -291.624766) (xy 308.779685 -291.649373)
			(xy 308.77179 -291.69795) (xy 308.756206 -291.744631) (xy 308.733335 -291.788208) (xy 308.70377 -291.827552)
			(xy 308.668277 -291.861644) (xy 308.627774 -291.8896) (xy 308.583312 -291.910698) (xy 308.536041 -291.92439)
			(xy 308.487186 -291.930322) (xy 308.438011 -291.928341) (xy 308.389792 -291.918497) (xy 308.343776 -291.901045)
			(xy 308.301155 -291.876438) (xy 308.263034 -291.845313) (xy 308.230399 -291.808476) (xy 308.204096 -291.76688)
			(xy 308.184805 -291.721604) (xy 308.173028 -291.67382) (xy 308.169068 -291.624766) (xy 306.88026 -291.624766)
			(xy 306.879765 -291.649373) (xy 306.87187 -291.69795) (xy 306.856286 -291.744631) (xy 306.833415 -291.788208)
			(xy 306.80385 -291.827552) (xy 306.768357 -291.861644) (xy 306.727854 -291.8896) (xy 306.683392 -291.910698)
			(xy 306.636121 -291.92439) (xy 306.587266 -291.930322) (xy 306.538091 -291.928341) (xy 306.489872 -291.918497)
			(xy 306.443856 -291.901045) (xy 306.401235 -291.876438) (xy 306.363114 -291.845313) (xy 306.330479 -291.808476)
			(xy 306.304176 -291.76688) (xy 306.284885 -291.721604) (xy 306.273108 -291.67382) (xy 306.269148 -291.624766)
			(xy 305.930046 -291.624766) (xy 305.929551 -291.649373) (xy 305.921656 -291.69795) (xy 305.906072 -291.744631)
			(xy 305.883201 -291.788208) (xy 305.853636 -291.827552) (xy 305.818143 -291.861644) (xy 305.77764 -291.8896)
			(xy 305.733178 -291.910698) (xy 305.685907 -291.92439) (xy 305.637052 -291.930322) (xy 305.587877 -291.928341)
			(xy 305.539658 -291.918497) (xy 305.493642 -291.901045) (xy 305.451021 -291.876438) (xy 305.4129 -291.845313)
			(xy 305.380265 -291.808476) (xy 305.353962 -291.76688) (xy 305.334671 -291.721604) (xy 305.322894 -291.67382)
			(xy 305.318934 -291.624766) (xy 304.980086 -291.624766) (xy 304.979591 -291.649373) (xy 304.971696 -291.69795)
			(xy 304.956112 -291.744631) (xy 304.933241 -291.788208) (xy 304.903676 -291.827552) (xy 304.868183 -291.861644)
			(xy 304.82768 -291.8896) (xy 304.783218 -291.910698) (xy 304.735947 -291.92439) (xy 304.687092 -291.930322)
			(xy 304.637917 -291.928341) (xy 304.589698 -291.918497) (xy 304.543682 -291.901045) (xy 304.501061 -291.876438)
			(xy 304.46294 -291.845313) (xy 304.430305 -291.808476) (xy 304.404002 -291.76688) (xy 304.384711 -291.721604)
			(xy 304.372934 -291.67382) (xy 304.368974 -291.624766) (xy 304.030126 -291.624766) (xy 304.029631 -291.649373)
			(xy 304.021736 -291.69795) (xy 304.006152 -291.744631) (xy 303.983281 -291.788208) (xy 303.953716 -291.827552)
			(xy 303.918223 -291.861644) (xy 303.87772 -291.8896) (xy 303.833258 -291.910698) (xy 303.785987 -291.92439)
			(xy 303.737132 -291.930322) (xy 303.687957 -291.928341) (xy 303.639738 -291.918497) (xy 303.593722 -291.901045)
			(xy 303.551101 -291.876438) (xy 303.51298 -291.845313) (xy 303.480345 -291.808476) (xy 303.454042 -291.76688)
			(xy 303.434751 -291.721604) (xy 303.422974 -291.67382) (xy 303.419014 -291.624766) (xy 303.080166 -291.624766)
			(xy 303.079671 -291.649373) (xy 303.071776 -291.69795) (xy 303.056192 -291.744631) (xy 303.033321 -291.788208)
			(xy 303.003756 -291.827552) (xy 302.968263 -291.861644) (xy 302.92776 -291.8896) (xy 302.883298 -291.910698)
			(xy 302.836027 -291.92439) (xy 302.787172 -291.930322) (xy 302.737997 -291.928341) (xy 302.689778 -291.918497)
			(xy 302.643762 -291.901045) (xy 302.601141 -291.876438) (xy 302.56302 -291.845313) (xy 302.530385 -291.808476)
			(xy 302.504082 -291.76688) (xy 302.484791 -291.721604) (xy 302.473014 -291.67382) (xy 302.469054 -291.624766)
			(xy 302.130206 -291.624766) (xy 302.129711 -291.649373) (xy 302.121816 -291.69795) (xy 302.106232 -291.744631)
			(xy 302.083361 -291.788208) (xy 302.053796 -291.827552) (xy 302.018303 -291.861644) (xy 301.9778 -291.8896)
			(xy 301.933338 -291.910698) (xy 301.886067 -291.92439) (xy 301.837212 -291.930322) (xy 301.788037 -291.928341)
			(xy 301.739818 -291.918497) (xy 301.693802 -291.901045) (xy 301.651181 -291.876438) (xy 301.61306 -291.845313)
			(xy 301.580425 -291.808476) (xy 301.554122 -291.76688) (xy 301.534831 -291.721604) (xy 301.523054 -291.67382)
			(xy 301.519094 -291.624766) (xy 301.179992 -291.624766) (xy 301.179497 -291.649373) (xy 301.171602 -291.69795)
			(xy 301.156018 -291.744631) (xy 301.133147 -291.788208) (xy 301.103582 -291.827552) (xy 301.068089 -291.861644)
			(xy 301.027586 -291.8896) (xy 300.983124 -291.910698) (xy 300.935853 -291.92439) (xy 300.886998 -291.930322)
			(xy 300.837823 -291.928341) (xy 300.789604 -291.918497) (xy 300.743588 -291.901045) (xy 300.700967 -291.876438)
			(xy 300.662846 -291.845313) (xy 300.630211 -291.808476) (xy 300.603908 -291.76688) (xy 300.584617 -291.721604)
			(xy 300.57284 -291.67382) (xy 300.56888 -291.624766) (xy 300.230032 -291.624766) (xy 300.229537 -291.649373)
			(xy 300.221642 -291.69795) (xy 300.206058 -291.744631) (xy 300.183187 -291.788208) (xy 300.153622 -291.827552)
			(xy 300.118129 -291.861644) (xy 300.077626 -291.8896) (xy 300.033164 -291.910698) (xy 299.985893 -291.92439)
			(xy 299.937038 -291.930322) (xy 299.887863 -291.928341) (xy 299.839644 -291.918497) (xy 299.793628 -291.901045)
			(xy 299.751007 -291.876438) (xy 299.712886 -291.845313) (xy 299.680251 -291.808476) (xy 299.653948 -291.76688)
			(xy 299.634657 -291.721604) (xy 299.62288 -291.67382) (xy 299.61892 -291.624766) (xy 299.280072 -291.624766)
			(xy 299.279577 -291.649373) (xy 299.271682 -291.69795) (xy 299.256098 -291.744631) (xy 299.233227 -291.788208)
			(xy 299.203662 -291.827552) (xy 299.168169 -291.861644) (xy 299.127666 -291.8896) (xy 299.083204 -291.910698)
			(xy 299.035933 -291.92439) (xy 298.987078 -291.930322) (xy 298.937903 -291.928341) (xy 298.889684 -291.918497)
			(xy 298.843668 -291.901045) (xy 298.801047 -291.876438) (xy 298.762926 -291.845313) (xy 298.730291 -291.808476)
			(xy 298.703988 -291.76688) (xy 298.684697 -291.721604) (xy 298.67292 -291.67382) (xy 298.66896 -291.624766)
			(xy 298.330112 -291.624766) (xy 298.329617 -291.649373) (xy 298.321722 -291.69795) (xy 298.306138 -291.744631)
			(xy 298.283267 -291.788208) (xy 298.253702 -291.827552) (xy 298.218209 -291.861644) (xy 298.177706 -291.8896)
			(xy 298.133244 -291.910698) (xy 298.085973 -291.92439) (xy 298.037118 -291.930322) (xy 297.987943 -291.928341)
			(xy 297.939724 -291.918497) (xy 297.893708 -291.901045) (xy 297.851087 -291.876438) (xy 297.812966 -291.845313)
			(xy 297.780331 -291.808476) (xy 297.754028 -291.76688) (xy 297.734737 -291.721604) (xy 297.72296 -291.67382)
			(xy 297.719 -291.624766) (xy 297.380152 -291.624766) (xy 297.379657 -291.649373) (xy 297.371762 -291.69795)
			(xy 297.356178 -291.744631) (xy 297.333307 -291.788208) (xy 297.303742 -291.827552) (xy 297.268249 -291.861644)
			(xy 297.227746 -291.8896) (xy 297.183284 -291.910698) (xy 297.136013 -291.92439) (xy 297.087158 -291.930322)
			(xy 297.037983 -291.928341) (xy 296.989764 -291.918497) (xy 296.943748 -291.901045) (xy 296.901127 -291.876438)
			(xy 296.863006 -291.845313) (xy 296.830371 -291.808476) (xy 296.804068 -291.76688) (xy 296.784777 -291.721604)
			(xy 296.773 -291.67382) (xy 296.76904 -291.624766) (xy 296.430192 -291.624766) (xy 296.429697 -291.649373)
			(xy 296.421802 -291.69795) (xy 296.406218 -291.744631) (xy 296.383347 -291.788208) (xy 296.353782 -291.827552)
			(xy 296.318289 -291.861644) (xy 296.277786 -291.8896) (xy 296.233324 -291.910698) (xy 296.186053 -291.92439)
			(xy 296.137198 -291.930322) (xy 296.088023 -291.928341) (xy 296.039804 -291.918497) (xy 295.993788 -291.901045)
			(xy 295.951167 -291.876438) (xy 295.913046 -291.845313) (xy 295.880411 -291.808476) (xy 295.854108 -291.76688)
			(xy 295.834817 -291.721604) (xy 295.82304 -291.67382) (xy 295.81908 -291.624766) (xy 295.480232 -291.624766)
			(xy 295.479737 -291.649373) (xy 295.471842 -291.69795) (xy 295.456258 -291.744631) (xy 295.433387 -291.788208)
			(xy 295.403822 -291.827552) (xy 295.368329 -291.861644) (xy 295.327826 -291.8896) (xy 295.283364 -291.910698)
			(xy 295.236093 -291.92439) (xy 295.187238 -291.930322) (xy 295.138063 -291.928341) (xy 295.089844 -291.918497)
			(xy 295.043828 -291.901045) (xy 295.001207 -291.876438) (xy 294.963086 -291.845313) (xy 294.930451 -291.808476)
			(xy 294.904148 -291.76688) (xy 294.884857 -291.721604) (xy 294.87308 -291.67382) (xy 294.86912 -291.624766)
			(xy 294.530018 -291.624766) (xy 294.529523 -291.649373) (xy 294.521628 -291.69795) (xy 294.506044 -291.744631)
			(xy 294.483173 -291.788208) (xy 294.453608 -291.827552) (xy 294.418115 -291.861644) (xy 294.377612 -291.8896)
			(xy 294.33315 -291.910698) (xy 294.285879 -291.92439) (xy 294.237024 -291.930322) (xy 294.187849 -291.928341)
			(xy 294.13963 -291.918497) (xy 294.093614 -291.901045) (xy 294.050993 -291.876438) (xy 294.012872 -291.845313)
			(xy 293.980237 -291.808476) (xy 293.953934 -291.76688) (xy 293.934643 -291.721604) (xy 293.922866 -291.67382)
			(xy 293.918906 -291.624766) (xy 293.580058 -291.624766) (xy 293.579563 -291.649373) (xy 293.571668 -291.69795)
			(xy 293.556084 -291.744631) (xy 293.533213 -291.788208) (xy 293.503648 -291.827552) (xy 293.468155 -291.861644)
			(xy 293.427652 -291.8896) (xy 293.38319 -291.910698) (xy 293.335919 -291.92439) (xy 293.287064 -291.930322)
			(xy 293.237889 -291.928341) (xy 293.18967 -291.918497) (xy 293.143654 -291.901045) (xy 293.101033 -291.876438)
			(xy 293.062912 -291.845313) (xy 293.030277 -291.808476) (xy 293.003974 -291.76688) (xy 292.984683 -291.721604)
			(xy 292.972906 -291.67382) (xy 292.968946 -291.624766) (xy 292.630098 -291.624766) (xy 292.629603 -291.649373)
			(xy 292.621708 -291.69795) (xy 292.606124 -291.744631) (xy 292.583253 -291.788208) (xy 292.553688 -291.827552)
			(xy 292.518195 -291.861644) (xy 292.477692 -291.8896) (xy 292.43323 -291.910698) (xy 292.385959 -291.92439)
			(xy 292.337104 -291.930322) (xy 292.287929 -291.928341) (xy 292.23971 -291.918497) (xy 292.193694 -291.901045)
			(xy 292.151073 -291.876438) (xy 292.112952 -291.845313) (xy 292.080317 -291.808476) (xy 292.054014 -291.76688)
			(xy 292.034723 -291.721604) (xy 292.022946 -291.67382) (xy 292.018986 -291.624766) (xy 290.730178 -291.624766)
			(xy 290.729683 -291.649373) (xy 290.721788 -291.69795) (xy 290.706204 -291.744631) (xy 290.683333 -291.788208)
			(xy 290.653768 -291.827552) (xy 290.618275 -291.861644) (xy 290.577772 -291.8896) (xy 290.53331 -291.910698)
			(xy 290.486039 -291.92439) (xy 290.437184 -291.930322) (xy 290.388009 -291.928341) (xy 290.33979 -291.918497)
			(xy 290.293774 -291.901045) (xy 290.251153 -291.876438) (xy 290.213032 -291.845313) (xy 290.180397 -291.808476)
			(xy 290.154094 -291.76688) (xy 290.134803 -291.721604) (xy 290.123026 -291.67382) (xy 290.119066 -291.624766)
			(xy 289.780218 -291.624766) (xy 289.779723 -291.649373) (xy 289.771828 -291.69795) (xy 289.756244 -291.744631)
			(xy 289.733373 -291.788208) (xy 289.703808 -291.827552) (xy 289.668315 -291.861644) (xy 289.627812 -291.8896)
			(xy 289.58335 -291.910698) (xy 289.536079 -291.92439) (xy 289.487224 -291.930322) (xy 289.438049 -291.928341)
			(xy 289.38983 -291.918497) (xy 289.343814 -291.901045) (xy 289.301193 -291.876438) (xy 289.263072 -291.845313)
			(xy 289.230437 -291.808476) (xy 289.204134 -291.76688) (xy 289.184843 -291.721604) (xy 289.173066 -291.67382)
			(xy 289.169106 -291.624766) (xy 288.830004 -291.624766) (xy 288.829509 -291.649373) (xy 288.821614 -291.69795)
			(xy 288.80603 -291.744631) (xy 288.783159 -291.788208) (xy 288.753594 -291.827552) (xy 288.718101 -291.861644)
			(xy 288.677598 -291.8896) (xy 288.633136 -291.910698) (xy 288.585865 -291.92439) (xy 288.53701 -291.930322)
			(xy 288.487835 -291.928341) (xy 288.439616 -291.918497) (xy 288.3936 -291.901045) (xy 288.350979 -291.876438)
			(xy 288.312858 -291.845313) (xy 288.280223 -291.808476) (xy 288.25392 -291.76688) (xy 288.234629 -291.721604)
			(xy 288.222852 -291.67382) (xy 288.218892 -291.624766) (xy 287.880044 -291.624766) (xy 287.879549 -291.649373)
			(xy 287.871654 -291.69795) (xy 287.85607 -291.744631) (xy 287.833199 -291.788208) (xy 287.803634 -291.827552)
			(xy 287.768141 -291.861644) (xy 287.727638 -291.8896) (xy 287.683176 -291.910698) (xy 287.635905 -291.92439)
			(xy 287.58705 -291.930322) (xy 287.537875 -291.928341) (xy 287.489656 -291.918497) (xy 287.44364 -291.901045)
			(xy 287.401019 -291.876438) (xy 287.362898 -291.845313) (xy 287.330263 -291.808476) (xy 287.30396 -291.76688)
			(xy 287.284669 -291.721604) (xy 287.272892 -291.67382) (xy 287.268932 -291.624766) (xy 286.930084 -291.624766)
			(xy 286.929589 -291.649373) (xy 286.921694 -291.69795) (xy 286.90611 -291.744631) (xy 286.883239 -291.788208)
			(xy 286.853674 -291.827552) (xy 286.818181 -291.861644) (xy 286.777678 -291.8896) (xy 286.733216 -291.910698)
			(xy 286.685945 -291.92439) (xy 286.63709 -291.930322) (xy 286.587915 -291.928341) (xy 286.539696 -291.918497)
			(xy 286.49368 -291.901045) (xy 286.451059 -291.876438) (xy 286.412938 -291.845313) (xy 286.380303 -291.808476)
			(xy 286.354 -291.76688) (xy 286.334709 -291.721604) (xy 286.322932 -291.67382) (xy 286.318972 -291.624766)
			(xy 285.980124 -291.624766) (xy 285.979629 -291.649373) (xy 285.971734 -291.69795) (xy 285.95615 -291.744631)
			(xy 285.933279 -291.788208) (xy 285.903714 -291.827552) (xy 285.868221 -291.861644) (xy 285.827718 -291.8896)
			(xy 285.783256 -291.910698) (xy 285.735985 -291.92439) (xy 285.68713 -291.930322) (xy 285.637955 -291.928341)
			(xy 285.589736 -291.918497) (xy 285.54372 -291.901045) (xy 285.501099 -291.876438) (xy 285.462978 -291.845313)
			(xy 285.430343 -291.808476) (xy 285.40404 -291.76688) (xy 285.384749 -291.721604) (xy 285.372972 -291.67382)
			(xy 285.369012 -291.624766) (xy 285.030164 -291.624766) (xy 285.029669 -291.649373) (xy 285.021774 -291.69795)
			(xy 285.00619 -291.744631) (xy 284.983319 -291.788208) (xy 284.953754 -291.827552) (xy 284.918261 -291.861644)
			(xy 284.877758 -291.8896) (xy 284.833296 -291.910698) (xy 284.786025 -291.92439) (xy 284.73717 -291.930322)
			(xy 284.687995 -291.928341) (xy 284.639776 -291.918497) (xy 284.59376 -291.901045) (xy 284.551139 -291.876438)
			(xy 284.513018 -291.845313) (xy 284.480383 -291.808476) (xy 284.45408 -291.76688) (xy 284.434789 -291.721604)
			(xy 284.423012 -291.67382) (xy 284.419052 -291.624766) (xy 284.080204 -291.624766) (xy 284.079709 -291.649373)
			(xy 284.071814 -291.69795) (xy 284.05623 -291.744631) (xy 284.033359 -291.788208) (xy 284.003794 -291.827552)
			(xy 283.968301 -291.861644) (xy 283.927798 -291.8896) (xy 283.883336 -291.910698) (xy 283.836065 -291.92439)
			(xy 283.78721 -291.930322) (xy 283.738035 -291.928341) (xy 283.689816 -291.918497) (xy 283.6438 -291.901045)
			(xy 283.601179 -291.876438) (xy 283.563058 -291.845313) (xy 283.530423 -291.808476) (xy 283.50412 -291.76688)
			(xy 283.484829 -291.721604) (xy 283.473052 -291.67382) (xy 283.469092 -291.624766) (xy 283.130244 -291.624766)
			(xy 283.129749 -291.649373) (xy 283.121854 -291.69795) (xy 283.10627 -291.744631) (xy 283.083399 -291.788208)
			(xy 283.053834 -291.827552) (xy 283.018341 -291.861644) (xy 282.977838 -291.8896) (xy 282.933376 -291.910698)
			(xy 282.886105 -291.92439) (xy 282.83725 -291.930322) (xy 282.788075 -291.928341) (xy 282.739856 -291.918497)
			(xy 282.69384 -291.901045) (xy 282.651219 -291.876438) (xy 282.613098 -291.845313) (xy 282.580463 -291.808476)
			(xy 282.55416 -291.76688) (xy 282.534869 -291.721604) (xy 282.523092 -291.67382) (xy 282.519132 -291.624766)
			(xy 282.18003 -291.624766) (xy 282.179535 -291.649373) (xy 282.17164 -291.69795) (xy 282.156056 -291.744631)
			(xy 282.133185 -291.788208) (xy 282.10362 -291.827552) (xy 282.068127 -291.861644) (xy 282.027624 -291.8896)
			(xy 281.983162 -291.910698) (xy 281.935891 -291.92439) (xy 281.887036 -291.930322) (xy 281.837861 -291.928341)
			(xy 281.789642 -291.918497) (xy 281.743626 -291.901045) (xy 281.701005 -291.876438) (xy 281.662884 -291.845313)
			(xy 281.630249 -291.808476) (xy 281.603946 -291.76688) (xy 281.584655 -291.721604) (xy 281.572878 -291.67382)
			(xy 281.568918 -291.624766) (xy 281.23007 -291.624766) (xy 281.229575 -291.649373) (xy 281.22168 -291.69795)
			(xy 281.206096 -291.744631) (xy 281.183225 -291.788208) (xy 281.15366 -291.827552) (xy 281.118167 -291.861644)
			(xy 281.077664 -291.8896) (xy 281.033202 -291.910698) (xy 280.985931 -291.92439) (xy 280.937076 -291.930322)
			(xy 280.887901 -291.928341) (xy 280.839682 -291.918497) (xy 280.793666 -291.901045) (xy 280.751045 -291.876438)
			(xy 280.712924 -291.845313) (xy 280.680289 -291.808476) (xy 280.653986 -291.76688) (xy 280.634695 -291.721604)
			(xy 280.622918 -291.67382) (xy 280.618958 -291.624766) (xy 280.28011 -291.624766) (xy 280.279615 -291.649373)
			(xy 280.27172 -291.69795) (xy 280.256136 -291.744631) (xy 280.233265 -291.788208) (xy 280.2037 -291.827552)
			(xy 280.168207 -291.861644) (xy 280.127704 -291.8896) (xy 280.083242 -291.910698) (xy 280.035971 -291.92439)
			(xy 279.987116 -291.930322) (xy 279.937941 -291.928341) (xy 279.889722 -291.918497) (xy 279.843706 -291.901045)
			(xy 279.801085 -291.876438) (xy 279.762964 -291.845313) (xy 279.730329 -291.808476) (xy 279.704026 -291.76688)
			(xy 279.684735 -291.721604) (xy 279.672958 -291.67382) (xy 279.668998 -291.624766) (xy 278.38019 -291.624766)
			(xy 278.379695 -291.649373) (xy 278.3718 -291.69795) (xy 278.356216 -291.744631) (xy 278.333345 -291.788208)
			(xy 278.30378 -291.827552) (xy 278.268287 -291.861644) (xy 278.227784 -291.8896) (xy 278.183322 -291.910698)
			(xy 278.136051 -291.92439) (xy 278.087196 -291.930322) (xy 278.038021 -291.928341) (xy 277.989802 -291.918497)
			(xy 277.943786 -291.901045) (xy 277.901165 -291.876438) (xy 277.863044 -291.845313) (xy 277.830409 -291.808476)
			(xy 277.804106 -291.76688) (xy 277.784815 -291.721604) (xy 277.773038 -291.67382) (xy 277.769078 -291.624766)
			(xy 277.43023 -291.624766) (xy 277.429735 -291.649373) (xy 277.42184 -291.69795) (xy 277.406256 -291.744631)
			(xy 277.383385 -291.788208) (xy 277.35382 -291.827552) (xy 277.318327 -291.861644) (xy 277.277824 -291.8896)
			(xy 277.233362 -291.910698) (xy 277.186091 -291.92439) (xy 277.137236 -291.930322) (xy 277.088061 -291.928341)
			(xy 277.039842 -291.918497) (xy 276.993826 -291.901045) (xy 276.951205 -291.876438) (xy 276.913084 -291.845313)
			(xy 276.880449 -291.808476) (xy 276.854146 -291.76688) (xy 276.834855 -291.721604) (xy 276.823078 -291.67382)
			(xy 276.819118 -291.624766) (xy 276.480016 -291.624766) (xy 276.479521 -291.649373) (xy 276.471626 -291.69795)
			(xy 276.456042 -291.744631) (xy 276.433171 -291.788208) (xy 276.403606 -291.827552) (xy 276.368113 -291.861644)
			(xy 276.32761 -291.8896) (xy 276.283148 -291.910698) (xy 276.235877 -291.92439) (xy 276.187022 -291.930322)
			(xy 276.137847 -291.928341) (xy 276.089628 -291.918497) (xy 276.043612 -291.901045) (xy 276.000991 -291.876438)
			(xy 275.96287 -291.845313) (xy 275.930235 -291.808476) (xy 275.903932 -291.76688) (xy 275.884641 -291.721604)
			(xy 275.872864 -291.67382) (xy 275.868904 -291.624766) (xy 275.530056 -291.624766) (xy 275.529561 -291.649373)
			(xy 275.521666 -291.69795) (xy 275.506082 -291.744631) (xy 275.483211 -291.788208) (xy 275.453646 -291.827552)
			(xy 275.418153 -291.861644) (xy 275.37765 -291.8896) (xy 275.333188 -291.910698) (xy 275.285917 -291.92439)
			(xy 275.237062 -291.930322) (xy 275.187887 -291.928341) (xy 275.139668 -291.918497) (xy 275.093652 -291.901045)
			(xy 275.051031 -291.876438) (xy 275.01291 -291.845313) (xy 274.980275 -291.808476) (xy 274.953972 -291.76688)
			(xy 274.934681 -291.721604) (xy 274.922904 -291.67382) (xy 274.918944 -291.624766) (xy 274.580096 -291.624766)
			(xy 274.579601 -291.649373) (xy 274.571706 -291.69795) (xy 274.556122 -291.744631) (xy 274.533251 -291.788208)
			(xy 274.503686 -291.827552) (xy 274.468193 -291.861644) (xy 274.42769 -291.8896) (xy 274.383228 -291.910698)
			(xy 274.335957 -291.92439) (xy 274.287102 -291.930322) (xy 274.237927 -291.928341) (xy 274.189708 -291.918497)
			(xy 274.143692 -291.901045) (xy 274.101071 -291.876438) (xy 274.06295 -291.845313) (xy 274.030315 -291.808476)
			(xy 274.004012 -291.76688) (xy 273.984721 -291.721604) (xy 273.972944 -291.67382) (xy 273.968984 -291.624766)
			(xy 273.630136 -291.624766) (xy 273.629641 -291.649373) (xy 273.621746 -291.69795) (xy 273.606162 -291.744631)
			(xy 273.583291 -291.788208) (xy 273.553726 -291.827552) (xy 273.518233 -291.861644) (xy 273.47773 -291.8896)
			(xy 273.433268 -291.910698) (xy 273.385997 -291.92439) (xy 273.337142 -291.930322) (xy 273.287967 -291.928341)
			(xy 273.239748 -291.918497) (xy 273.193732 -291.901045) (xy 273.151111 -291.876438) (xy 273.11299 -291.845313)
			(xy 273.080355 -291.808476) (xy 273.054052 -291.76688) (xy 273.034761 -291.721604) (xy 273.022984 -291.67382)
			(xy 273.019024 -291.624766) (xy 270.780256 -291.624766) (xy 270.779761 -291.649373) (xy 270.771866 -291.69795)
			(xy 270.756282 -291.744631) (xy 270.733411 -291.788208) (xy 270.703846 -291.827552) (xy 270.668353 -291.861644)
			(xy 270.62785 -291.8896) (xy 270.583388 -291.910698) (xy 270.536117 -291.92439) (xy 270.487262 -291.930322)
			(xy 270.438087 -291.928341) (xy 270.389868 -291.918497) (xy 270.343852 -291.901045) (xy 270.301231 -291.876438)
			(xy 270.26311 -291.845313) (xy 270.230475 -291.808476) (xy 270.204172 -291.76688) (xy 270.184881 -291.721604)
			(xy 270.173104 -291.67382) (xy 270.169144 -291.624766) (xy 269.830042 -291.624766) (xy 269.829547 -291.649373)
			(xy 269.821652 -291.69795) (xy 269.806068 -291.744631) (xy 269.783197 -291.788208) (xy 269.753632 -291.827552)
			(xy 269.718139 -291.861644) (xy 269.677636 -291.8896) (xy 269.633174 -291.910698) (xy 269.585903 -291.92439)
			(xy 269.537048 -291.930322) (xy 269.487873 -291.928341) (xy 269.439654 -291.918497) (xy 269.393638 -291.901045)
			(xy 269.351017 -291.876438) (xy 269.312896 -291.845313) (xy 269.280261 -291.808476) (xy 269.253958 -291.76688)
			(xy 269.234667 -291.721604) (xy 269.22289 -291.67382) (xy 269.21893 -291.624766) (xy 268.880082 -291.624766)
			(xy 268.879587 -291.649373) (xy 268.871692 -291.69795) (xy 268.856108 -291.744631) (xy 268.833237 -291.788208)
			(xy 268.803672 -291.827552) (xy 268.768179 -291.861644) (xy 268.727676 -291.8896) (xy 268.683214 -291.910698)
			(xy 268.635943 -291.92439) (xy 268.587088 -291.930322) (xy 268.537913 -291.928341) (xy 268.489694 -291.918497)
			(xy 268.443678 -291.901045) (xy 268.401057 -291.876438) (xy 268.362936 -291.845313) (xy 268.330301 -291.808476)
			(xy 268.303998 -291.76688) (xy 268.284707 -291.721604) (xy 268.27293 -291.67382) (xy 268.26897 -291.624766)
			(xy 260.206856 -291.624766) (xy 260.180942 -291.663935) (xy 260.143725 -291.705472) (xy 260.100857 -291.741147)
			(xy 260.053251 -291.770201) (xy 260.001922 -291.792013) (xy 259.947965 -291.806119) (xy 259.892528 -291.812219)
			(xy 259.836794 -291.810182) (xy 259.781951 -291.800052) (xy 259.729167 -291.782045) (xy 259.679567 -291.756544)
			(xy 259.634209 -291.724093) (xy 259.59406 -291.685384) (xy 259.559974 -291.641241) (xy 259.532678 -291.592606)
			(xy 259.512755 -291.540515) (xy 259.500629 -291.486078) (xy 259.496558 -291.430456) (xy 258.774946 -291.430456)
			(xy 258.774437 -291.458342) (xy 258.766317 -291.513518) (xy 258.750249 -291.566925) (xy 258.726577 -291.617422)
			(xy 258.695804 -291.663935) (xy 258.658587 -291.705472) (xy 258.615719 -291.741147) (xy 258.568113 -291.770201)
			(xy 258.516784 -291.792013) (xy 258.462827 -291.806119) (xy 258.40739 -291.812219) (xy 258.351656 -291.810182)
			(xy 258.296813 -291.800052) (xy 258.244029 -291.782045) (xy 258.194429 -291.756544) (xy 258.149071 -291.724093)
			(xy 258.108922 -291.685384) (xy 258.074836 -291.641241) (xy 258.04754 -291.592606) (xy 258.027617 -291.540515)
			(xy 258.015491 -291.486078) (xy 258.01142 -291.430456) (xy 237.734495 -291.430456) (xy 237.736297 -291.436594)
			(xy 237.744054 -291.490546) (xy 237.744054 -291.545054) (xy 237.736297 -291.599006) (xy 237.720941 -291.651305)
			(xy 237.698298 -291.700886) (xy 237.668829 -291.746741) (xy 237.633134 -291.787934) (xy 237.591941 -291.823629)
			(xy 237.546086 -291.853098) (xy 237.496505 -291.875741) (xy 237.444206 -291.891097) (xy 237.390254 -291.898854)
			(xy 237.363 -291.89934) (xy 237.335629 -291.898889) (xy 237.281449 -291.891069) (xy 237.228945 -291.875578)
			(xy 237.179198 -291.852732) (xy 237.133233 -291.823004) (xy 237.112302 -291.80536) (xy 237.10519 -291.799264)
			(xy 237.088172 -291.792914) (xy 237.002828 -291.792914) (xy 236.98581 -291.799264) (xy 236.978698 -291.80536)
			(xy 236.957772 -291.823007) (xy 236.911798 -291.852719) (xy 236.862049 -291.875554) (xy 236.809547 -291.891043)
			(xy 236.75537 -291.898868) (xy 236.728 -291.89934) (xy 236.700751 -291.89879) (xy 236.646808 -291.891034)
			(xy 236.594518 -291.87568) (xy 236.544945 -291.853041) (xy 236.499098 -291.823577) (xy 236.457911 -291.787889)
			(xy 236.422223 -291.746702) (xy 236.392759 -291.700855) (xy 236.37012 -291.651282) (xy 236.354766 -291.598992)
			(xy 236.34701 -291.545049) (xy 235.99059 -291.545049) (xy 235.982835 -291.598987) (xy 235.967483 -291.651274)
			(xy 235.944847 -291.700845) (xy 235.915386 -291.746689) (xy 235.879702 -291.787875) (xy 235.83852 -291.823564)
			(xy 235.792678 -291.853028) (xy 235.74311 -291.87567) (xy 235.690824 -291.891027) (xy 235.636885 -291.898787)
			(xy 235.609638 -291.89934) (xy 235.584032 -291.898942) (xy 235.533276 -291.892119) (xy 235.483889 -291.878565)
			(xy 235.436761 -291.858523) (xy 235.39274 -291.832354) (xy 235.372402 -291.81679) (xy 235.368592 -291.813742)
			(xy 235.363766 -291.811202) (xy 235.358293 -291.808534) (xy 235.346483 -291.805593) (xy 235.340398 -291.80536)
			(xy 235.307886 -291.80536) (xy 235.307886 -291.794184) (xy 235.247942 -291.794184) (xy 235.230924 -291.800534)
			(xy 235.223812 -291.80663) (xy 235.202934 -291.824021) (xy 235.157184 -291.853334) (xy 235.107735 -291.875856)
			(xy 235.055591 -291.89113) (xy 235.001806 -291.898848) (xy 234.974638 -291.89934) (xy 234.944585 -291.898779)
			(xy 234.885222 -291.889356) (xy 234.828073 -291.870737) (xy 234.774552 -291.843384) (xy 234.725984 -291.807973)
			(xy 234.704382 -291.787072) (xy 234.69346 -291.77615) (xy 234.663234 -291.770054) (xy 234.562142 -291.811964)
			(xy 234.55757 -291.81425) (xy 234.54732 -291.820534) (xy 234.533676 -291.840288) (xy 234.531408 -291.852096)
			(xy 234.5309 -291.858954) (xy 234.5309 -292.732714) (xy 258.01142 -292.732714) (xy 258.015491 -292.677092)
			(xy 258.027617 -292.622655) (xy 258.04754 -292.570564) (xy 258.074836 -292.521929) (xy 258.108922 -292.477786)
			(xy 258.149071 -292.439077) (xy 258.194429 -292.406626) (xy 258.244029 -292.381125) (xy 258.296813 -292.363118)
			(xy 258.351656 -292.352988) (xy 258.40739 -292.350951) (xy 258.462827 -292.357051) (xy 258.516784 -292.371157)
			(xy 258.568113 -292.392969) (xy 258.615719 -292.422023) (xy 258.658587 -292.457698) (xy 258.695804 -292.499235)
			(xy 258.726577 -292.545748) (xy 258.750249 -292.596245) (xy 258.766317 -292.649652) (xy 258.774437 -292.704828)
			(xy 258.774946 -292.732714) (xy 259.486906 -292.732714) (xy 259.490977 -292.677092) (xy 259.503103 -292.622655)
			(xy 259.523026 -292.570564) (xy 259.550322 -292.521929) (xy 259.584408 -292.477786) (xy 259.624557 -292.439077)
			(xy 259.669915 -292.406626) (xy 259.719515 -292.381125) (xy 259.772299 -292.363118) (xy 259.827142 -292.352988)
			(xy 259.882876 -292.350951) (xy 259.938313 -292.357051) (xy 259.99227 -292.371157) (xy 260.043599 -292.392969)
			(xy 260.091205 -292.422023) (xy 260.134073 -292.457698) (xy 260.17129 -292.499235) (xy 260.202063 -292.545748)
			(xy 260.225735 -292.596245) (xy 260.241803 -292.649652) (xy 260.249923 -292.704828) (xy 260.250432 -292.732714)
			(xy 260.375906 -292.732714) (xy 260.379977 -292.677092) (xy 260.392103 -292.622655) (xy 260.412026 -292.570564)
			(xy 260.439322 -292.521929) (xy 260.473408 -292.477786) (xy 260.513557 -292.439077) (xy 260.558915 -292.406626)
			(xy 260.608515 -292.381125) (xy 260.661299 -292.363118) (xy 260.716142 -292.352988) (xy 260.771876 -292.350951)
			(xy 260.827313 -292.357051) (xy 260.88127 -292.371157) (xy 260.932599 -292.392969) (xy 260.980205 -292.422023)
			(xy 261.023073 -292.457698) (xy 261.06029 -292.499235) (xy 261.091063 -292.545748) (xy 261.114735 -292.596245)
			(xy 261.130803 -292.649652) (xy 261.138923 -292.704828) (xy 261.139432 -292.732714) (xy 261.138923 -292.7606)
			(xy 261.130803 -292.815776) (xy 261.114735 -292.869183) (xy 261.091063 -292.91968) (xy 261.06029 -292.966193)
			(xy 261.023073 -293.00773) (xy 260.980205 -293.043405) (xy 260.932599 -293.072459) (xy 260.88127 -293.094271)
			(xy 260.827313 -293.108377) (xy 260.771876 -293.114477) (xy 260.716142 -293.11244) (xy 260.661299 -293.10231)
			(xy 260.608515 -293.084303) (xy 260.558915 -293.058802) (xy 260.513557 -293.026351) (xy 260.473408 -292.987642)
			(xy 260.439322 -292.943499) (xy 260.412026 -292.894864) (xy 260.392103 -292.842773) (xy 260.379977 -292.788336)
			(xy 260.375906 -292.732714) (xy 260.250432 -292.732714) (xy 260.249923 -292.7606) (xy 260.241803 -292.815776)
			(xy 260.225735 -292.869183) (xy 260.202063 -292.91968) (xy 260.17129 -292.966193) (xy 260.134073 -293.00773)
			(xy 260.091205 -293.043405) (xy 260.043599 -293.072459) (xy 259.99227 -293.094271) (xy 259.938313 -293.108377)
			(xy 259.882876 -293.114477) (xy 259.827142 -293.11244) (xy 259.772299 -293.10231) (xy 259.719515 -293.084303)
			(xy 259.669915 -293.058802) (xy 259.624557 -293.026351) (xy 259.584408 -292.987642) (xy 259.550322 -292.943499)
			(xy 259.523026 -292.894864) (xy 259.503103 -292.842773) (xy 259.490977 -292.788336) (xy 259.486906 -292.732714)
			(xy 258.774946 -292.732714) (xy 258.774437 -292.7606) (xy 258.766317 -292.815776) (xy 258.750249 -292.869183)
			(xy 258.726577 -292.91968) (xy 258.695804 -292.966193) (xy 258.658587 -293.00773) (xy 258.615719 -293.043405)
			(xy 258.568113 -293.072459) (xy 258.516784 -293.094271) (xy 258.462827 -293.108377) (xy 258.40739 -293.114477)
			(xy 258.351656 -293.11244) (xy 258.296813 -293.10231) (xy 258.244029 -293.084303) (xy 258.194429 -293.058802)
			(xy 258.149071 -293.026351) (xy 258.108922 -292.987642) (xy 258.074836 -292.943499) (xy 258.04754 -292.894864)
			(xy 258.027617 -292.842773) (xy 258.015491 -292.788336) (xy 258.01142 -292.732714) (xy 234.5309 -292.732714)
			(xy 234.5309 -293.494714) (xy 263.537954 -293.494714) (xy 263.53852 -293.465333) (xy 263.547548 -293.407268)
			(xy 263.565376 -293.351275) (xy 263.591583 -293.29868) (xy 263.625547 -293.250728) (xy 263.666466 -293.208554)
			(xy 263.689592 -293.190422) (xy 263.69899 -293.183056) (xy 263.709404 -293.162482) (xy 263.710928 -293.058596)
			(xy 263.701022 -293.037514) (xy 263.691878 -293.030148) (xy 263.670018 -293.011956) (xy 263.63148 -292.970133)
			(xy 263.599575 -292.923055) (xy 263.57501 -292.871763) (xy 263.558329 -292.817393) (xy 263.549902 -292.76115)
			(xy 263.549384 -292.732714) (xy 263.54987 -292.705463) (xy 263.557626 -292.651515) (xy 263.572981 -292.59922)
			(xy 263.595623 -292.549643) (xy 263.625089 -292.503793) (xy 263.66078 -292.462602) (xy 263.701971 -292.426911)
			(xy 263.747821 -292.397445) (xy 263.797398 -292.374803) (xy 263.849693 -292.359448) (xy 263.903641 -292.351692)
			(xy 263.958143 -292.351692) (xy 264.012091 -292.359448) (xy 264.064386 -292.374803) (xy 264.113963 -292.397445)
			(xy 264.159813 -292.426911) (xy 264.201004 -292.462602) (xy 264.236695 -292.503793) (xy 264.266161 -292.549643)
			(xy 264.277733 -292.57498) (xy 268.26897 -292.57498) (xy 268.27293 -292.525926) (xy 268.284707 -292.478142)
			(xy 268.303998 -292.432866) (xy 268.330301 -292.39127) (xy 268.362936 -292.354433) (xy 268.401057 -292.323308)
			(xy 268.443678 -292.298701) (xy 268.489694 -292.281249) (xy 268.537913 -292.271405) (xy 268.587088 -292.269424)
			(xy 268.635943 -292.275356) (xy 268.683214 -292.289048) (xy 268.727676 -292.310146) (xy 268.768179 -292.338102)
			(xy 268.803672 -292.372194) (xy 268.833237 -292.411538) (xy 268.856108 -292.455115) (xy 268.871692 -292.501796)
			(xy 268.879587 -292.550373) (xy 268.880082 -292.57498) (xy 269.21893 -292.57498) (xy 269.22289 -292.525926)
			(xy 269.234667 -292.478142) (xy 269.253958 -292.432866) (xy 269.280261 -292.39127) (xy 269.312896 -292.354433)
			(xy 269.351017 -292.323308) (xy 269.393638 -292.298701) (xy 269.439654 -292.281249) (xy 269.487873 -292.271405)
			(xy 269.537048 -292.269424) (xy 269.585903 -292.275356) (xy 269.633174 -292.289048) (xy 269.677636 -292.310146)
			(xy 269.718139 -292.338102) (xy 269.753632 -292.372194) (xy 269.783197 -292.411538) (xy 269.806068 -292.455115)
			(xy 269.821652 -292.501796) (xy 269.829547 -292.550373) (xy 269.830042 -292.57498) (xy 270.169144 -292.57498)
			(xy 270.173104 -292.525926) (xy 270.184881 -292.478142) (xy 270.204172 -292.432866) (xy 270.230475 -292.39127)
			(xy 270.26311 -292.354433) (xy 270.301231 -292.323308) (xy 270.343852 -292.298701) (xy 270.389868 -292.281249)
			(xy 270.438087 -292.271405) (xy 270.487262 -292.269424) (xy 270.536117 -292.275356) (xy 270.583388 -292.289048)
			(xy 270.62785 -292.310146) (xy 270.668353 -292.338102) (xy 270.703846 -292.372194) (xy 270.733411 -292.411538)
			(xy 270.756282 -292.455115) (xy 270.771866 -292.501796) (xy 270.779761 -292.550373) (xy 270.780251 -292.574726)
			(xy 271.119104 -292.574726) (xy 271.123064 -292.525672) (xy 271.134841 -292.477888) (xy 271.154132 -292.432612)
			(xy 271.180435 -292.391016) (xy 271.21307 -292.354179) (xy 271.251191 -292.323054) (xy 271.293812 -292.298447)
			(xy 271.339828 -292.280995) (xy 271.388047 -292.271151) (xy 271.437222 -292.26917) (xy 271.486077 -292.275102)
			(xy 271.533348 -292.288794) (xy 271.57781 -292.309892) (xy 271.618313 -292.337848) (xy 271.653806 -292.37194)
			(xy 271.683371 -292.411284) (xy 271.706242 -292.454861) (xy 271.721826 -292.501542) (xy 271.729721 -292.550119)
			(xy 271.730216 -292.574726) (xy 272.069064 -292.574726) (xy 272.073024 -292.525672) (xy 272.084801 -292.477888)
			(xy 272.104092 -292.432612) (xy 272.130395 -292.391016) (xy 272.16303 -292.354179) (xy 272.201151 -292.323054)
			(xy 272.243772 -292.298447) (xy 272.289788 -292.280995) (xy 272.338007 -292.271151) (xy 272.387182 -292.26917)
			(xy 272.436037 -292.275102) (xy 272.483308 -292.288794) (xy 272.52777 -292.309892) (xy 272.568273 -292.337848)
			(xy 272.603766 -292.37194) (xy 272.633331 -292.411284) (xy 272.656202 -292.454861) (xy 272.671786 -292.501542)
			(xy 272.679681 -292.550119) (xy 272.680176 -292.574726) (xy 272.680171 -292.57498) (xy 273.019024 -292.57498)
			(xy 273.022984 -292.525926) (xy 273.034761 -292.478142) (xy 273.054052 -292.432866) (xy 273.080355 -292.39127)
			(xy 273.11299 -292.354433) (xy 273.151111 -292.323308) (xy 273.193732 -292.298701) (xy 273.239748 -292.281249)
			(xy 273.287967 -292.271405) (xy 273.337142 -292.269424) (xy 273.385997 -292.275356) (xy 273.433268 -292.289048)
			(xy 273.47773 -292.310146) (xy 273.518233 -292.338102) (xy 273.553726 -292.372194) (xy 273.583291 -292.411538)
			(xy 273.606162 -292.455115) (xy 273.621746 -292.501796) (xy 273.629641 -292.550373) (xy 273.630136 -292.57498)
			(xy 273.629641 -292.599587) (xy 273.629309 -292.601629) (xy 273.919178 -292.601629) (xy 273.919178 -292.548331)
			(xy 273.927121 -292.495627) (xy 273.942831 -292.444697) (xy 273.965957 -292.396676) (xy 273.995981 -292.352639)
			(xy 274.032233 -292.313568) (xy 274.073904 -292.280337) (xy 274.120062 -292.253688) (xy 274.169676 -292.234216)
			(xy 274.221638 -292.222356) (xy 274.274788 -292.218373) (xy 274.327938 -292.222356) (xy 274.3799 -292.234216)
			(xy 274.429514 -292.253688) (xy 274.475672 -292.280337) (xy 274.517343 -292.313568) (xy 274.553595 -292.352639)
			(xy 274.583619 -292.396676) (xy 274.606745 -292.444697) (xy 274.622455 -292.495627) (xy 274.630398 -292.548331)
			(xy 274.630896 -292.57498) (xy 274.918944 -292.57498) (xy 274.922904 -292.525926) (xy 274.934681 -292.478142)
			(xy 274.953972 -292.432866) (xy 274.980275 -292.39127) (xy 275.01291 -292.354433) (xy 275.051031 -292.323308)
			(xy 275.093652 -292.298701) (xy 275.139668 -292.281249) (xy 275.187887 -292.271405) (xy 275.237062 -292.269424)
			(xy 275.285917 -292.275356) (xy 275.333188 -292.289048) (xy 275.37765 -292.310146) (xy 275.418153 -292.338102)
			(xy 275.453646 -292.372194) (xy 275.483211 -292.411538) (xy 275.506082 -292.455115) (xy 275.521666 -292.501796)
			(xy 275.529561 -292.550373) (xy 275.530056 -292.57498) (xy 275.868904 -292.57498) (xy 275.872864 -292.525926)
			(xy 275.884641 -292.478142) (xy 275.903932 -292.432866) (xy 275.930235 -292.39127) (xy 275.96287 -292.354433)
			(xy 276.000991 -292.323308) (xy 276.043612 -292.298701) (xy 276.089628 -292.281249) (xy 276.137847 -292.271405)
			(xy 276.187022 -292.269424) (xy 276.235877 -292.275356) (xy 276.283148 -292.289048) (xy 276.32761 -292.310146)
			(xy 276.368113 -292.338102) (xy 276.403606 -292.372194) (xy 276.433171 -292.411538) (xy 276.456042 -292.455115)
			(xy 276.471626 -292.501796) (xy 276.479521 -292.550373) (xy 276.480016 -292.57498) (xy 276.819118 -292.57498)
			(xy 276.823078 -292.525926) (xy 276.834855 -292.478142) (xy 276.854146 -292.432866) (xy 276.880449 -292.39127)
			(xy 276.913084 -292.354433) (xy 276.951205 -292.323308) (xy 276.993826 -292.298701) (xy 277.039842 -292.281249)
			(xy 277.088061 -292.271405) (xy 277.137236 -292.269424) (xy 277.186091 -292.275356) (xy 277.233362 -292.289048)
			(xy 277.277824 -292.310146) (xy 277.318327 -292.338102) (xy 277.35382 -292.372194) (xy 277.383385 -292.411538)
			(xy 277.406256 -292.455115) (xy 277.42184 -292.501796) (xy 277.429735 -292.550373) (xy 277.43023 -292.57498)
			(xy 277.769078 -292.57498) (xy 277.773038 -292.525926) (xy 277.784815 -292.478142) (xy 277.804106 -292.432866)
			(xy 277.830409 -292.39127) (xy 277.863044 -292.354433) (xy 277.901165 -292.323308) (xy 277.943786 -292.298701)
			(xy 277.989802 -292.281249) (xy 278.038021 -292.271405) (xy 278.087196 -292.269424) (xy 278.136051 -292.275356)
			(xy 278.183322 -292.289048) (xy 278.227784 -292.310146) (xy 278.268287 -292.338102) (xy 278.30378 -292.372194)
			(xy 278.333345 -292.411538) (xy 278.356216 -292.455115) (xy 278.3718 -292.501796) (xy 278.379695 -292.550373)
			(xy 278.38019 -292.57498) (xy 278.719038 -292.57498) (xy 278.722998 -292.525926) (xy 278.734775 -292.478142)
			(xy 278.754066 -292.432866) (xy 278.780369 -292.39127) (xy 278.813004 -292.354433) (xy 278.851125 -292.323308)
			(xy 278.893746 -292.298701) (xy 278.939762 -292.281249) (xy 278.987981 -292.271405) (xy 279.037156 -292.269424)
			(xy 279.086011 -292.275356) (xy 279.133282 -292.289048) (xy 279.177744 -292.310146) (xy 279.218247 -292.338102)
			(xy 279.25374 -292.372194) (xy 279.283305 -292.411538) (xy 279.306176 -292.455115) (xy 279.32176 -292.501796)
			(xy 279.329655 -292.550373) (xy 279.33015 -292.57498) (xy 279.668998 -292.57498) (xy 279.672958 -292.525926)
			(xy 279.684735 -292.478142) (xy 279.704026 -292.432866) (xy 279.730329 -292.39127) (xy 279.762964 -292.354433)
			(xy 279.801085 -292.323308) (xy 279.843706 -292.298701) (xy 279.889722 -292.281249) (xy 279.937941 -292.271405)
			(xy 279.987116 -292.269424) (xy 280.035971 -292.275356) (xy 280.083242 -292.289048) (xy 280.127704 -292.310146)
			(xy 280.168207 -292.338102) (xy 280.2037 -292.372194) (xy 280.233265 -292.411538) (xy 280.256136 -292.455115)
			(xy 280.27172 -292.501796) (xy 280.279615 -292.550373) (xy 280.280105 -292.574726) (xy 280.618958 -292.574726)
			(xy 280.622918 -292.525672) (xy 280.634695 -292.477888) (xy 280.653986 -292.432612) (xy 280.680289 -292.391016)
			(xy 280.712924 -292.354179) (xy 280.751045 -292.323054) (xy 280.793666 -292.298447) (xy 280.839682 -292.280995)
			(xy 280.887901 -292.271151) (xy 280.937076 -292.26917) (xy 280.985931 -292.275102) (xy 281.033202 -292.288794)
			(xy 281.077664 -292.309892) (xy 281.118167 -292.337848) (xy 281.15366 -292.37194) (xy 281.183225 -292.411284)
			(xy 281.206096 -292.454861) (xy 281.22168 -292.501542) (xy 281.229575 -292.550119) (xy 281.23007 -292.574726)
			(xy 281.568918 -292.574726) (xy 281.572878 -292.525672) (xy 281.584655 -292.477888) (xy 281.603946 -292.432612)
			(xy 281.630249 -292.391016) (xy 281.662884 -292.354179) (xy 281.701005 -292.323054) (xy 281.743626 -292.298447)
			(xy 281.789642 -292.280995) (xy 281.837861 -292.271151) (xy 281.887036 -292.26917) (xy 281.935891 -292.275102)
			(xy 281.983162 -292.288794) (xy 282.027624 -292.309892) (xy 282.068127 -292.337848) (xy 282.10362 -292.37194)
			(xy 282.133185 -292.411284) (xy 282.156056 -292.454861) (xy 282.17164 -292.501542) (xy 282.179535 -292.550119)
			(xy 282.18003 -292.574726) (xy 282.180025 -292.57498) (xy 282.519132 -292.57498) (xy 282.523092 -292.525926)
			(xy 282.534869 -292.478142) (xy 282.55416 -292.432866) (xy 282.580463 -292.39127) (xy 282.613098 -292.354433)
			(xy 282.651219 -292.323308) (xy 282.69384 -292.298701) (xy 282.739856 -292.281249) (xy 282.788075 -292.271405)
			(xy 282.83725 -292.269424) (xy 282.886105 -292.275356) (xy 282.933376 -292.289048) (xy 282.977838 -292.310146)
			(xy 283.018341 -292.338102) (xy 283.053834 -292.372194) (xy 283.083399 -292.411538) (xy 283.10627 -292.455115)
			(xy 283.121854 -292.501796) (xy 283.129749 -292.550373) (xy 283.130244 -292.57498) (xy 283.469092 -292.57498)
			(xy 283.473052 -292.525926) (xy 283.484829 -292.478142) (xy 283.50412 -292.432866) (xy 283.530423 -292.39127)
			(xy 283.563058 -292.354433) (xy 283.601179 -292.323308) (xy 283.6438 -292.298701) (xy 283.689816 -292.281249)
			(xy 283.738035 -292.271405) (xy 283.78721 -292.269424) (xy 283.836065 -292.275356) (xy 283.883336 -292.289048)
			(xy 283.927798 -292.310146) (xy 283.968301 -292.338102) (xy 284.003794 -292.372194) (xy 284.033359 -292.411538)
			(xy 284.05623 -292.455115) (xy 284.071814 -292.501796) (xy 284.079709 -292.550373) (xy 284.080204 -292.57498)
			(xy 284.419052 -292.57498) (xy 284.423012 -292.525926) (xy 284.434789 -292.478142) (xy 284.45408 -292.432866)
			(xy 284.480383 -292.39127) (xy 284.513018 -292.354433) (xy 284.551139 -292.323308) (xy 284.59376 -292.298701)
			(xy 284.639776 -292.281249) (xy 284.687995 -292.271405) (xy 284.73717 -292.269424) (xy 284.786025 -292.275356)
			(xy 284.833296 -292.289048) (xy 284.877758 -292.310146) (xy 284.918261 -292.338102) (xy 284.953754 -292.372194)
			(xy 284.983319 -292.411538) (xy 285.00619 -292.455115) (xy 285.021774 -292.501796) (xy 285.029669 -292.550373)
			(xy 285.030164 -292.57498) (xy 285.369012 -292.57498) (xy 285.372972 -292.525926) (xy 285.384749 -292.478142)
			(xy 285.40404 -292.432866) (xy 285.430343 -292.39127) (xy 285.462978 -292.354433) (xy 285.501099 -292.323308)
			(xy 285.54372 -292.298701) (xy 285.589736 -292.281249) (xy 285.637955 -292.271405) (xy 285.68713 -292.269424)
			(xy 285.735985 -292.275356) (xy 285.783256 -292.289048) (xy 285.827718 -292.310146) (xy 285.868221 -292.338102)
			(xy 285.903714 -292.372194) (xy 285.933279 -292.411538) (xy 285.95615 -292.455115) (xy 285.971734 -292.501796)
			(xy 285.979629 -292.550373) (xy 285.980124 -292.57498) (xy 286.318972 -292.57498) (xy 286.322932 -292.525926)
			(xy 286.334709 -292.478142) (xy 286.354 -292.432866) (xy 286.380303 -292.39127) (xy 286.412938 -292.354433)
			(xy 286.451059 -292.323308) (xy 286.49368 -292.298701) (xy 286.539696 -292.281249) (xy 286.587915 -292.271405)
			(xy 286.63709 -292.269424) (xy 286.685945 -292.275356) (xy 286.733216 -292.289048) (xy 286.777678 -292.310146)
			(xy 286.818181 -292.338102) (xy 286.853674 -292.372194) (xy 286.883239 -292.411538) (xy 286.90611 -292.455115)
			(xy 286.921694 -292.501796) (xy 286.929589 -292.550373) (xy 286.930084 -292.57498) (xy 287.268932 -292.57498)
			(xy 287.272892 -292.525926) (xy 287.284669 -292.478142) (xy 287.30396 -292.432866) (xy 287.330263 -292.39127)
			(xy 287.362898 -292.354433) (xy 287.401019 -292.323308) (xy 287.44364 -292.298701) (xy 287.489656 -292.281249)
			(xy 287.537875 -292.271405) (xy 287.58705 -292.269424) (xy 287.635905 -292.275356) (xy 287.683176 -292.289048)
			(xy 287.727638 -292.310146) (xy 287.768141 -292.338102) (xy 287.803634 -292.372194) (xy 287.833199 -292.411538)
			(xy 287.85607 -292.455115) (xy 287.871654 -292.501796) (xy 287.879549 -292.550373) (xy 287.880044 -292.57498)
			(xy 288.219146 -292.57498) (xy 288.223106 -292.525926) (xy 288.234883 -292.478142) (xy 288.254174 -292.432866)
			(xy 288.280477 -292.39127) (xy 288.313112 -292.354433) (xy 288.351233 -292.323308) (xy 288.393854 -292.298701)
			(xy 288.43987 -292.281249) (xy 288.488089 -292.271405) (xy 288.537264 -292.269424) (xy 288.586119 -292.275356)
			(xy 288.63339 -292.289048) (xy 288.677852 -292.310146) (xy 288.718355 -292.338102) (xy 288.753848 -292.372194)
			(xy 288.783413 -292.411538) (xy 288.806284 -292.455115) (xy 288.821868 -292.501796) (xy 288.829763 -292.550373)
			(xy 288.830258 -292.57498) (xy 289.169106 -292.57498) (xy 289.173066 -292.525926) (xy 289.184843 -292.478142)
			(xy 289.204134 -292.432866) (xy 289.230437 -292.39127) (xy 289.263072 -292.354433) (xy 289.301193 -292.323308)
			(xy 289.343814 -292.298701) (xy 289.38983 -292.281249) (xy 289.438049 -292.271405) (xy 289.487224 -292.269424)
			(xy 289.536079 -292.275356) (xy 289.58335 -292.289048) (xy 289.627812 -292.310146) (xy 289.668315 -292.338102)
			(xy 289.703808 -292.372194) (xy 289.733373 -292.411538) (xy 289.756244 -292.455115) (xy 289.771828 -292.501796)
			(xy 289.779723 -292.550373) (xy 289.780218 -292.57498) (xy 290.119066 -292.57498) (xy 290.123026 -292.525926)
			(xy 290.134803 -292.478142) (xy 290.154094 -292.432866) (xy 290.180397 -292.39127) (xy 290.213032 -292.354433)
			(xy 290.251153 -292.323308) (xy 290.293774 -292.298701) (xy 290.33979 -292.281249) (xy 290.388009 -292.271405)
			(xy 290.437184 -292.269424) (xy 290.486039 -292.275356) (xy 290.53331 -292.289048) (xy 290.577772 -292.310146)
			(xy 290.618275 -292.338102) (xy 290.653768 -292.372194) (xy 290.683333 -292.411538) (xy 290.706204 -292.455115)
			(xy 290.721788 -292.501796) (xy 290.729683 -292.550373) (xy 290.730173 -292.574726) (xy 292.018986 -292.574726)
			(xy 292.022946 -292.525672) (xy 292.034723 -292.477888) (xy 292.054014 -292.432612) (xy 292.080317 -292.391016)
			(xy 292.112952 -292.354179) (xy 292.151073 -292.323054) (xy 292.193694 -292.298447) (xy 292.23971 -292.280995)
			(xy 292.287929 -292.271151) (xy 292.337104 -292.26917) (xy 292.385959 -292.275102) (xy 292.43323 -292.288794)
			(xy 292.477692 -292.309892) (xy 292.518195 -292.337848) (xy 292.553688 -292.37194) (xy 292.583253 -292.411284)
			(xy 292.606124 -292.454861) (xy 292.621708 -292.501542) (xy 292.629603 -292.550119) (xy 292.630098 -292.574726)
			(xy 292.968946 -292.574726) (xy 292.972906 -292.525672) (xy 292.984683 -292.477888) (xy 293.003974 -292.432612)
			(xy 293.030277 -292.391016) (xy 293.062912 -292.354179) (xy 293.101033 -292.323054) (xy 293.143654 -292.298447)
			(xy 293.18967 -292.280995) (xy 293.237889 -292.271151) (xy 293.287064 -292.26917) (xy 293.335919 -292.275102)
			(xy 293.38319 -292.288794) (xy 293.427652 -292.309892) (xy 293.468155 -292.337848) (xy 293.503648 -292.37194)
			(xy 293.533213 -292.411284) (xy 293.556084 -292.454861) (xy 293.571668 -292.501542) (xy 293.579563 -292.550119)
			(xy 293.580058 -292.574726) (xy 293.918906 -292.574726) (xy 293.922866 -292.525672) (xy 293.934643 -292.477888)
			(xy 293.953934 -292.432612) (xy 293.980237 -292.391016) (xy 294.012872 -292.354179) (xy 294.050993 -292.323054)
			(xy 294.093614 -292.298447) (xy 294.13963 -292.280995) (xy 294.187849 -292.271151) (xy 294.237024 -292.26917)
			(xy 294.285879 -292.275102) (xy 294.33315 -292.288794) (xy 294.377612 -292.309892) (xy 294.418115 -292.337848)
			(xy 294.453608 -292.37194) (xy 294.483173 -292.411284) (xy 294.506044 -292.454861) (xy 294.521628 -292.501542)
			(xy 294.529523 -292.550119) (xy 294.530018 -292.574726) (xy 294.86912 -292.574726) (xy 294.87308 -292.525672)
			(xy 294.884857 -292.477888) (xy 294.904148 -292.432612) (xy 294.930451 -292.391016) (xy 294.963086 -292.354179)
			(xy 295.001207 -292.323054) (xy 295.043828 -292.298447) (xy 295.089844 -292.280995) (xy 295.138063 -292.271151)
			(xy 295.187238 -292.26917) (xy 295.236093 -292.275102) (xy 295.283364 -292.288794) (xy 295.327826 -292.309892)
			(xy 295.368329 -292.337848) (xy 295.403822 -292.37194) (xy 295.433387 -292.411284) (xy 295.456258 -292.454861)
			(xy 295.471842 -292.501542) (xy 295.479737 -292.550119) (xy 295.480232 -292.574726) (xy 295.81908 -292.574726)
			(xy 295.82304 -292.525672) (xy 295.834817 -292.477888) (xy 295.854108 -292.432612) (xy 295.880411 -292.391016)
			(xy 295.913046 -292.354179) (xy 295.951167 -292.323054) (xy 295.993788 -292.298447) (xy 296.039804 -292.280995)
			(xy 296.088023 -292.271151) (xy 296.137198 -292.26917) (xy 296.186053 -292.275102) (xy 296.233324 -292.288794)
			(xy 296.277786 -292.309892) (xy 296.318289 -292.337848) (xy 296.353782 -292.37194) (xy 296.383347 -292.411284)
			(xy 296.406218 -292.454861) (xy 296.421802 -292.501542) (xy 296.429697 -292.550119) (xy 296.430192 -292.574726)
			(xy 296.76904 -292.574726) (xy 296.773 -292.525672) (xy 296.784777 -292.477888) (xy 296.804068 -292.432612)
			(xy 296.830371 -292.391016) (xy 296.863006 -292.354179) (xy 296.901127 -292.323054) (xy 296.943748 -292.298447)
			(xy 296.989764 -292.280995) (xy 297.037983 -292.271151) (xy 297.087158 -292.26917) (xy 297.136013 -292.275102)
			(xy 297.183284 -292.288794) (xy 297.227746 -292.309892) (xy 297.268249 -292.337848) (xy 297.303742 -292.37194)
			(xy 297.333307 -292.411284) (xy 297.356178 -292.454861) (xy 297.371762 -292.501542) (xy 297.379657 -292.550119)
			(xy 297.380152 -292.574726) (xy 297.719 -292.574726) (xy 297.72296 -292.525672) (xy 297.734737 -292.477888)
			(xy 297.754028 -292.432612) (xy 297.780331 -292.391016) (xy 297.812966 -292.354179) (xy 297.851087 -292.323054)
			(xy 297.893708 -292.298447) (xy 297.939724 -292.280995) (xy 297.987943 -292.271151) (xy 298.037118 -292.26917)
			(xy 298.085973 -292.275102) (xy 298.133244 -292.288794) (xy 298.177706 -292.309892) (xy 298.218209 -292.337848)
			(xy 298.253702 -292.37194) (xy 298.283267 -292.411284) (xy 298.306138 -292.454861) (xy 298.321722 -292.501542)
			(xy 298.329617 -292.550119) (xy 298.330112 -292.574726) (xy 298.66896 -292.574726) (xy 298.67292 -292.525672)
			(xy 298.684697 -292.477888) (xy 298.703988 -292.432612) (xy 298.730291 -292.391016) (xy 298.762926 -292.354179)
			(xy 298.801047 -292.323054) (xy 298.843668 -292.298447) (xy 298.889684 -292.280995) (xy 298.937903 -292.271151)
			(xy 298.987078 -292.26917) (xy 299.035933 -292.275102) (xy 299.083204 -292.288794) (xy 299.127666 -292.309892)
			(xy 299.168169 -292.337848) (xy 299.203662 -292.37194) (xy 299.233227 -292.411284) (xy 299.256098 -292.454861)
			(xy 299.271682 -292.501542) (xy 299.279577 -292.550119) (xy 299.280072 -292.574726) (xy 299.61892 -292.574726)
			(xy 299.62288 -292.525672) (xy 299.634657 -292.477888) (xy 299.653948 -292.432612) (xy 299.680251 -292.391016)
			(xy 299.712886 -292.354179) (xy 299.751007 -292.323054) (xy 299.793628 -292.298447) (xy 299.839644 -292.280995)
			(xy 299.887863 -292.271151) (xy 299.937038 -292.26917) (xy 299.985893 -292.275102) (xy 300.033164 -292.288794)
			(xy 300.077626 -292.309892) (xy 300.118129 -292.337848) (xy 300.153622 -292.37194) (xy 300.183187 -292.411284)
			(xy 300.206058 -292.454861) (xy 300.221642 -292.501542) (xy 300.229537 -292.550119) (xy 300.230032 -292.574726)
			(xy 300.56888 -292.574726) (xy 300.57284 -292.525672) (xy 300.584617 -292.477888) (xy 300.603908 -292.432612)
			(xy 300.630211 -292.391016) (xy 300.662846 -292.354179) (xy 300.700967 -292.323054) (xy 300.743588 -292.298447)
			(xy 300.789604 -292.280995) (xy 300.837823 -292.271151) (xy 300.886998 -292.26917) (xy 300.935853 -292.275102)
			(xy 300.983124 -292.288794) (xy 301.027586 -292.309892) (xy 301.068089 -292.337848) (xy 301.103582 -292.37194)
			(xy 301.133147 -292.411284) (xy 301.156018 -292.454861) (xy 301.171602 -292.501542) (xy 301.179497 -292.550119)
			(xy 301.179992 -292.574726) (xy 301.519094 -292.574726) (xy 301.523054 -292.525672) (xy 301.534831 -292.477888)
			(xy 301.554122 -292.432612) (xy 301.580425 -292.391016) (xy 301.61306 -292.354179) (xy 301.651181 -292.323054)
			(xy 301.693802 -292.298447) (xy 301.739818 -292.280995) (xy 301.788037 -292.271151) (xy 301.837212 -292.26917)
			(xy 301.886067 -292.275102) (xy 301.933338 -292.288794) (xy 301.9778 -292.309892) (xy 302.018303 -292.337848)
			(xy 302.053796 -292.37194) (xy 302.083361 -292.411284) (xy 302.106232 -292.454861) (xy 302.121816 -292.501542)
			(xy 302.129711 -292.550119) (xy 302.130206 -292.574726) (xy 302.130201 -292.57498) (xy 302.469054 -292.57498)
			(xy 302.473014 -292.525926) (xy 302.484791 -292.478142) (xy 302.504082 -292.432866) (xy 302.530385 -292.39127)
			(xy 302.56302 -292.354433) (xy 302.601141 -292.323308) (xy 302.643762 -292.298701) (xy 302.689778 -292.281249)
			(xy 302.737997 -292.271405) (xy 302.787172 -292.269424) (xy 302.836027 -292.275356) (xy 302.883298 -292.289048)
			(xy 302.92776 -292.310146) (xy 302.968263 -292.338102) (xy 303.003756 -292.372194) (xy 303.033321 -292.411538)
			(xy 303.056192 -292.455115) (xy 303.071776 -292.501796) (xy 303.079671 -292.550373) (xy 303.080161 -292.574726)
			(xy 303.419014 -292.574726) (xy 303.422974 -292.525672) (xy 303.434751 -292.477888) (xy 303.454042 -292.432612)
			(xy 303.480345 -292.391016) (xy 303.51298 -292.354179) (xy 303.551101 -292.323054) (xy 303.593722 -292.298447)
			(xy 303.639738 -292.280995) (xy 303.687957 -292.271151) (xy 303.737132 -292.26917) (xy 303.785987 -292.275102)
			(xy 303.833258 -292.288794) (xy 303.87772 -292.309892) (xy 303.918223 -292.337848) (xy 303.953716 -292.37194)
			(xy 303.983281 -292.411284) (xy 304.006152 -292.454861) (xy 304.021736 -292.501542) (xy 304.029631 -292.550119)
			(xy 304.030126 -292.574726) (xy 304.368974 -292.574726) (xy 304.372934 -292.525672) (xy 304.384711 -292.477888)
			(xy 304.404002 -292.432612) (xy 304.430305 -292.391016) (xy 304.46294 -292.354179) (xy 304.501061 -292.323054)
			(xy 304.543682 -292.298447) (xy 304.589698 -292.280995) (xy 304.637917 -292.271151) (xy 304.687092 -292.26917)
			(xy 304.735947 -292.275102) (xy 304.783218 -292.288794) (xy 304.82768 -292.309892) (xy 304.868183 -292.337848)
			(xy 304.903676 -292.37194) (xy 304.933241 -292.411284) (xy 304.956112 -292.454861) (xy 304.971696 -292.501542)
			(xy 304.979591 -292.550119) (xy 304.980086 -292.574726) (xy 305.318934 -292.574726) (xy 305.322894 -292.525672)
			(xy 305.334671 -292.477888) (xy 305.353962 -292.432612) (xy 305.380265 -292.391016) (xy 305.4129 -292.354179)
			(xy 305.451021 -292.323054) (xy 305.493642 -292.298447) (xy 305.539658 -292.280995) (xy 305.587877 -292.271151)
			(xy 305.637052 -292.26917) (xy 305.685907 -292.275102) (xy 305.733178 -292.288794) (xy 305.77764 -292.309892)
			(xy 305.818143 -292.337848) (xy 305.853636 -292.37194) (xy 305.883201 -292.411284) (xy 305.906072 -292.454861)
			(xy 305.921656 -292.501542) (xy 305.929551 -292.550119) (xy 305.930046 -292.574726) (xy 306.268894 -292.574726)
			(xy 306.272854 -292.525672) (xy 306.284631 -292.477888) (xy 306.303922 -292.432612) (xy 306.330225 -292.391016)
			(xy 306.36286 -292.354179) (xy 306.400981 -292.323054) (xy 306.443602 -292.298447) (xy 306.489618 -292.280995)
			(xy 306.537837 -292.271151) (xy 306.587012 -292.26917) (xy 306.635867 -292.275102) (xy 306.683138 -292.288794)
			(xy 306.7276 -292.309892) (xy 306.768103 -292.337848) (xy 306.803596 -292.37194) (xy 306.833161 -292.411284)
			(xy 306.856032 -292.454861) (xy 306.871616 -292.501542) (xy 306.879511 -292.550119) (xy 306.880006 -292.574726)
			(xy 307.219108 -292.574726) (xy 307.223068 -292.525672) (xy 307.234845 -292.477888) (xy 307.254136 -292.432612)
			(xy 307.280439 -292.391016) (xy 307.313074 -292.354179) (xy 307.351195 -292.323054) (xy 307.393816 -292.298447)
			(xy 307.439832 -292.280995) (xy 307.488051 -292.271151) (xy 307.537226 -292.26917) (xy 307.586081 -292.275102)
			(xy 307.633352 -292.288794) (xy 307.677814 -292.309892) (xy 307.718317 -292.337848) (xy 307.75381 -292.37194)
			(xy 307.783375 -292.411284) (xy 307.806246 -292.454861) (xy 307.82183 -292.501542) (xy 307.829725 -292.550119)
			(xy 307.83022 -292.574726) (xy 308.169068 -292.574726) (xy 308.173028 -292.525672) (xy 308.184805 -292.477888)
			(xy 308.204096 -292.432612) (xy 308.230399 -292.391016) (xy 308.263034 -292.354179) (xy 308.301155 -292.323054)
			(xy 308.343776 -292.298447) (xy 308.389792 -292.280995) (xy 308.438011 -292.271151) (xy 308.487186 -292.26917)
			(xy 308.536041 -292.275102) (xy 308.583312 -292.288794) (xy 308.627774 -292.309892) (xy 308.668277 -292.337848)
			(xy 308.70377 -292.37194) (xy 308.733335 -292.411284) (xy 308.756206 -292.454861) (xy 308.77179 -292.501542)
			(xy 308.779685 -292.550119) (xy 308.78018 -292.574726) (xy 309.119028 -292.574726) (xy 309.122988 -292.525672)
			(xy 309.134765 -292.477888) (xy 309.154056 -292.432612) (xy 309.180359 -292.391016) (xy 309.212994 -292.354179)
			(xy 309.251115 -292.323054) (xy 309.293736 -292.298447) (xy 309.339752 -292.280995) (xy 309.387971 -292.271151)
			(xy 309.437146 -292.26917) (xy 309.486001 -292.275102) (xy 309.533272 -292.288794) (xy 309.577734 -292.309892)
			(xy 309.618237 -292.337848) (xy 309.65373 -292.37194) (xy 309.683295 -292.411284) (xy 309.706166 -292.454861)
			(xy 309.72175 -292.501542) (xy 309.729645 -292.550119) (xy 309.73014 -292.574726) (xy 310.068988 -292.574726)
			(xy 310.072948 -292.525672) (xy 310.084725 -292.477888) (xy 310.104016 -292.432612) (xy 310.130319 -292.391016)
			(xy 310.162954 -292.354179) (xy 310.201075 -292.323054) (xy 310.243696 -292.298447) (xy 310.289712 -292.280995)
			(xy 310.337931 -292.271151) (xy 310.387106 -292.26917) (xy 310.435961 -292.275102) (xy 310.483232 -292.288794)
			(xy 310.527694 -292.309892) (xy 310.568197 -292.337848) (xy 310.60369 -292.37194) (xy 310.633255 -292.411284)
			(xy 310.656126 -292.454861) (xy 310.67171 -292.501542) (xy 310.679605 -292.550119) (xy 310.6801 -292.574726)
			(xy 311.018948 -292.574726) (xy 311.022908 -292.525672) (xy 311.034685 -292.477888) (xy 311.053976 -292.432612)
			(xy 311.080279 -292.391016) (xy 311.112914 -292.354179) (xy 311.151035 -292.323054) (xy 311.193656 -292.298447)
			(xy 311.239672 -292.280995) (xy 311.287891 -292.271151) (xy 311.337066 -292.26917) (xy 311.385921 -292.275102)
			(xy 311.433192 -292.288794) (xy 311.477654 -292.309892) (xy 311.518157 -292.337848) (xy 311.55365 -292.37194)
			(xy 311.583215 -292.411284) (xy 311.606086 -292.454861) (xy 311.62167 -292.501542) (xy 311.629565 -292.550119)
			(xy 311.63006 -292.574726) (xy 311.968908 -292.574726) (xy 311.972868 -292.525672) (xy 311.984645 -292.477888)
			(xy 312.003936 -292.432612) (xy 312.030239 -292.391016) (xy 312.062874 -292.354179) (xy 312.100995 -292.323054)
			(xy 312.143616 -292.298447) (xy 312.189632 -292.280995) (xy 312.237851 -292.271151) (xy 312.287026 -292.26917)
			(xy 312.335881 -292.275102) (xy 312.383152 -292.288794) (xy 312.427614 -292.309892) (xy 312.468117 -292.337848)
			(xy 312.50361 -292.37194) (xy 312.533175 -292.411284) (xy 312.556046 -292.454861) (xy 312.57163 -292.501542)
			(xy 312.579525 -292.550119) (xy 312.58002 -292.574726) (xy 312.919122 -292.574726) (xy 312.923082 -292.525672)
			(xy 312.934859 -292.477888) (xy 312.95415 -292.432612) (xy 312.980453 -292.391016) (xy 313.013088 -292.354179)
			(xy 313.051209 -292.323054) (xy 313.09383 -292.298447) (xy 313.139846 -292.280995) (xy 313.188065 -292.271151)
			(xy 313.23724 -292.26917) (xy 313.286095 -292.275102) (xy 313.333366 -292.288794) (xy 313.377828 -292.309892)
			(xy 313.418331 -292.337848) (xy 313.453824 -292.37194) (xy 313.483389 -292.411284) (xy 313.50626 -292.454861)
			(xy 313.521844 -292.501542) (xy 313.529739 -292.550119) (xy 313.530234 -292.574726) (xy 313.530229 -292.57498)
			(xy 313.869082 -292.57498) (xy 313.873042 -292.525926) (xy 313.884819 -292.478142) (xy 313.90411 -292.432866)
			(xy 313.930413 -292.39127) (xy 313.963048 -292.354433) (xy 314.001169 -292.323308) (xy 314.04379 -292.298701)
			(xy 314.089806 -292.281249) (xy 314.138025 -292.271405) (xy 314.1872 -292.269424) (xy 314.236055 -292.275356)
			(xy 314.283326 -292.289048) (xy 314.327788 -292.310146) (xy 314.368291 -292.338102) (xy 314.403784 -292.372194)
			(xy 314.433349 -292.411538) (xy 314.45622 -292.455115) (xy 314.471804 -292.501796) (xy 314.479699 -292.550373)
			(xy 314.480194 -292.57498) (xy 314.819042 -292.57498) (xy 314.823002 -292.525926) (xy 314.834779 -292.478142)
			(xy 314.85407 -292.432866) (xy 314.880373 -292.39127) (xy 314.913008 -292.354433) (xy 314.951129 -292.323308)
			(xy 314.99375 -292.298701) (xy 315.039766 -292.281249) (xy 315.087985 -292.271405) (xy 315.13716 -292.269424)
			(xy 315.186015 -292.275356) (xy 315.233286 -292.289048) (xy 315.277748 -292.310146) (xy 315.318251 -292.338102)
			(xy 315.353744 -292.372194) (xy 315.383309 -292.411538) (xy 315.40618 -292.455115) (xy 315.421764 -292.501796)
			(xy 315.429659 -292.550373) (xy 315.430154 -292.57498) (xy 315.429659 -292.599587) (xy 315.421764 -292.648164)
			(xy 315.40618 -292.694845) (xy 315.383309 -292.738422) (xy 315.353744 -292.777766) (xy 315.318251 -292.811858)
			(xy 315.277748 -292.839814) (xy 315.233286 -292.860912) (xy 315.186015 -292.874604) (xy 315.13716 -292.880536)
			(xy 315.087985 -292.878555) (xy 315.039766 -292.868711) (xy 314.99375 -292.851259) (xy 314.951129 -292.826652)
			(xy 314.913008 -292.795527) (xy 314.880373 -292.75869) (xy 314.85407 -292.717094) (xy 314.834779 -292.671818)
			(xy 314.823002 -292.624034) (xy 314.819042 -292.57498) (xy 314.480194 -292.57498) (xy 314.479699 -292.599587)
			(xy 314.471804 -292.648164) (xy 314.45622 -292.694845) (xy 314.433349 -292.738422) (xy 314.403784 -292.777766)
			(xy 314.368291 -292.811858) (xy 314.327788 -292.839814) (xy 314.283326 -292.860912) (xy 314.236055 -292.874604)
			(xy 314.1872 -292.880536) (xy 314.138025 -292.878555) (xy 314.089806 -292.868711) (xy 314.04379 -292.851259)
			(xy 314.001169 -292.826652) (xy 313.963048 -292.795527) (xy 313.930413 -292.75869) (xy 313.90411 -292.717094)
			(xy 313.884819 -292.671818) (xy 313.873042 -292.624034) (xy 313.869082 -292.57498) (xy 313.530229 -292.57498)
			(xy 313.529739 -292.599333) (xy 313.521844 -292.64791) (xy 313.50626 -292.694591) (xy 313.483389 -292.738168)
			(xy 313.453824 -292.777512) (xy 313.418331 -292.811604) (xy 313.377828 -292.83956) (xy 313.333366 -292.860658)
			(xy 313.286095 -292.87435) (xy 313.23724 -292.880282) (xy 313.188065 -292.878301) (xy 313.139846 -292.868457)
			(xy 313.09383 -292.851005) (xy 313.051209 -292.826398) (xy 313.013088 -292.795273) (xy 312.980453 -292.758436)
			(xy 312.95415 -292.71684) (xy 312.934859 -292.671564) (xy 312.923082 -292.62378) (xy 312.919122 -292.574726)
			(xy 312.58002 -292.574726) (xy 312.579525 -292.599333) (xy 312.57163 -292.64791) (xy 312.556046 -292.694591)
			(xy 312.533175 -292.738168) (xy 312.50361 -292.777512) (xy 312.468117 -292.811604) (xy 312.427614 -292.83956)
			(xy 312.383152 -292.860658) (xy 312.335881 -292.87435) (xy 312.287026 -292.880282) (xy 312.237851 -292.878301)
			(xy 312.189632 -292.868457) (xy 312.143616 -292.851005) (xy 312.100995 -292.826398) (xy 312.062874 -292.795273)
			(xy 312.030239 -292.758436) (xy 312.003936 -292.71684) (xy 311.984645 -292.671564) (xy 311.972868 -292.62378)
			(xy 311.968908 -292.574726) (xy 311.63006 -292.574726) (xy 311.629565 -292.599333) (xy 311.62167 -292.64791)
			(xy 311.606086 -292.694591) (xy 311.583215 -292.738168) (xy 311.55365 -292.777512) (xy 311.518157 -292.811604)
			(xy 311.477654 -292.83956) (xy 311.433192 -292.860658) (xy 311.385921 -292.87435) (xy 311.337066 -292.880282)
			(xy 311.287891 -292.878301) (xy 311.239672 -292.868457) (xy 311.193656 -292.851005) (xy 311.151035 -292.826398)
			(xy 311.112914 -292.795273) (xy 311.080279 -292.758436) (xy 311.053976 -292.71684) (xy 311.034685 -292.671564)
			(xy 311.022908 -292.62378) (xy 311.018948 -292.574726) (xy 310.6801 -292.574726) (xy 310.679605 -292.599333)
			(xy 310.67171 -292.64791) (xy 310.656126 -292.694591) (xy 310.633255 -292.738168) (xy 310.60369 -292.777512)
			(xy 310.568197 -292.811604) (xy 310.527694 -292.83956) (xy 310.483232 -292.860658) (xy 310.435961 -292.87435)
			(xy 310.387106 -292.880282) (xy 310.337931 -292.878301) (xy 310.289712 -292.868457) (xy 310.243696 -292.851005)
			(xy 310.201075 -292.826398) (xy 310.162954 -292.795273) (xy 310.130319 -292.758436) (xy 310.104016 -292.71684)
			(xy 310.084725 -292.671564) (xy 310.072948 -292.62378) (xy 310.068988 -292.574726) (xy 309.73014 -292.574726)
			(xy 309.729645 -292.599333) (xy 309.72175 -292.64791) (xy 309.706166 -292.694591) (xy 309.683295 -292.738168)
			(xy 309.65373 -292.777512) (xy 309.618237 -292.811604) (xy 309.577734 -292.83956) (xy 309.533272 -292.860658)
			(xy 309.486001 -292.87435) (xy 309.437146 -292.880282) (xy 309.387971 -292.878301) (xy 309.339752 -292.868457)
			(xy 309.293736 -292.851005) (xy 309.251115 -292.826398) (xy 309.212994 -292.795273) (xy 309.180359 -292.758436)
			(xy 309.154056 -292.71684) (xy 309.134765 -292.671564) (xy 309.122988 -292.62378) (xy 309.119028 -292.574726)
			(xy 308.78018 -292.574726) (xy 308.779685 -292.599333) (xy 308.77179 -292.64791) (xy 308.756206 -292.694591)
			(xy 308.733335 -292.738168) (xy 308.70377 -292.777512) (xy 308.668277 -292.811604) (xy 308.627774 -292.83956)
			(xy 308.583312 -292.860658) (xy 308.536041 -292.87435) (xy 308.487186 -292.880282) (xy 308.438011 -292.878301)
			(xy 308.389792 -292.868457) (xy 308.343776 -292.851005) (xy 308.301155 -292.826398) (xy 308.263034 -292.795273)
			(xy 308.230399 -292.758436) (xy 308.204096 -292.71684) (xy 308.184805 -292.671564) (xy 308.173028 -292.62378)
			(xy 308.169068 -292.574726) (xy 307.83022 -292.574726) (xy 307.829725 -292.599333) (xy 307.82183 -292.64791)
			(xy 307.806246 -292.694591) (xy 307.783375 -292.738168) (xy 307.75381 -292.777512) (xy 307.718317 -292.811604)
			(xy 307.677814 -292.83956) (xy 307.633352 -292.860658) (xy 307.586081 -292.87435) (xy 307.537226 -292.880282)
			(xy 307.488051 -292.878301) (xy 307.439832 -292.868457) (xy 307.393816 -292.851005) (xy 307.351195 -292.826398)
			(xy 307.313074 -292.795273) (xy 307.280439 -292.758436) (xy 307.254136 -292.71684) (xy 307.234845 -292.671564)
			(xy 307.223068 -292.62378) (xy 307.219108 -292.574726) (xy 306.880006 -292.574726) (xy 306.879511 -292.599333)
			(xy 306.871616 -292.64791) (xy 306.856032 -292.694591) (xy 306.833161 -292.738168) (xy 306.803596 -292.777512)
			(xy 306.768103 -292.811604) (xy 306.7276 -292.83956) (xy 306.683138 -292.860658) (xy 306.635867 -292.87435)
			(xy 306.587012 -292.880282) (xy 306.537837 -292.878301) (xy 306.489618 -292.868457) (xy 306.443602 -292.851005)
			(xy 306.400981 -292.826398) (xy 306.36286 -292.795273) (xy 306.330225 -292.758436) (xy 306.303922 -292.71684)
			(xy 306.284631 -292.671564) (xy 306.272854 -292.62378) (xy 306.268894 -292.574726) (xy 305.930046 -292.574726)
			(xy 305.929551 -292.599333) (xy 305.921656 -292.64791) (xy 305.906072 -292.694591) (xy 305.883201 -292.738168)
			(xy 305.853636 -292.777512) (xy 305.818143 -292.811604) (xy 305.77764 -292.83956) (xy 305.733178 -292.860658)
			(xy 305.685907 -292.87435) (xy 305.637052 -292.880282) (xy 305.587877 -292.878301) (xy 305.539658 -292.868457)
			(xy 305.493642 -292.851005) (xy 305.451021 -292.826398) (xy 305.4129 -292.795273) (xy 305.380265 -292.758436)
			(xy 305.353962 -292.71684) (xy 305.334671 -292.671564) (xy 305.322894 -292.62378) (xy 305.318934 -292.574726)
			(xy 304.980086 -292.574726) (xy 304.979591 -292.599333) (xy 304.971696 -292.64791) (xy 304.956112 -292.694591)
			(xy 304.933241 -292.738168) (xy 304.903676 -292.777512) (xy 304.868183 -292.811604) (xy 304.82768 -292.83956)
			(xy 304.783218 -292.860658) (xy 304.735947 -292.87435) (xy 304.687092 -292.880282) (xy 304.637917 -292.878301)
			(xy 304.589698 -292.868457) (xy 304.543682 -292.851005) (xy 304.501061 -292.826398) (xy 304.46294 -292.795273)
			(xy 304.430305 -292.758436) (xy 304.404002 -292.71684) (xy 304.384711 -292.671564) (xy 304.372934 -292.62378)
			(xy 304.368974 -292.574726) (xy 304.030126 -292.574726) (xy 304.029631 -292.599333) (xy 304.021736 -292.64791)
			(xy 304.006152 -292.694591) (xy 303.983281 -292.738168) (xy 303.953716 -292.777512) (xy 303.918223 -292.811604)
			(xy 303.87772 -292.83956) (xy 303.833258 -292.860658) (xy 303.785987 -292.87435) (xy 303.737132 -292.880282)
			(xy 303.687957 -292.878301) (xy 303.639738 -292.868457) (xy 303.593722 -292.851005) (xy 303.551101 -292.826398)
			(xy 303.51298 -292.795273) (xy 303.480345 -292.758436) (xy 303.454042 -292.71684) (xy 303.434751 -292.671564)
			(xy 303.422974 -292.62378) (xy 303.419014 -292.574726) (xy 303.080161 -292.574726) (xy 303.080166 -292.57498)
			(xy 303.079671 -292.599587) (xy 303.071776 -292.648164) (xy 303.056192 -292.694845) (xy 303.033321 -292.738422)
			(xy 303.003756 -292.777766) (xy 302.968263 -292.811858) (xy 302.92776 -292.839814) (xy 302.883298 -292.860912)
			(xy 302.836027 -292.874604) (xy 302.787172 -292.880536) (xy 302.737997 -292.878555) (xy 302.689778 -292.868711)
			(xy 302.643762 -292.851259) (xy 302.601141 -292.826652) (xy 302.56302 -292.795527) (xy 302.530385 -292.75869)
			(xy 302.504082 -292.717094) (xy 302.484791 -292.671818) (xy 302.473014 -292.624034) (xy 302.469054 -292.57498)
			(xy 302.130201 -292.57498) (xy 302.129711 -292.599333) (xy 302.121816 -292.64791) (xy 302.106232 -292.694591)
			(xy 302.083361 -292.738168) (xy 302.053796 -292.777512) (xy 302.018303 -292.811604) (xy 301.9778 -292.83956)
			(xy 301.933338 -292.860658) (xy 301.886067 -292.87435) (xy 301.837212 -292.880282) (xy 301.788037 -292.878301)
			(xy 301.739818 -292.868457) (xy 301.693802 -292.851005) (xy 301.651181 -292.826398) (xy 301.61306 -292.795273)
			(xy 301.580425 -292.758436) (xy 301.554122 -292.71684) (xy 301.534831 -292.671564) (xy 301.523054 -292.62378)
			(xy 301.519094 -292.574726) (xy 301.179992 -292.574726) (xy 301.179497 -292.599333) (xy 301.171602 -292.64791)
			(xy 301.156018 -292.694591) (xy 301.133147 -292.738168) (xy 301.103582 -292.777512) (xy 301.068089 -292.811604)
			(xy 301.027586 -292.83956) (xy 300.983124 -292.860658) (xy 300.935853 -292.87435) (xy 300.886998 -292.880282)
			(xy 300.837823 -292.878301) (xy 300.789604 -292.868457) (xy 300.743588 -292.851005) (xy 300.700967 -292.826398)
			(xy 300.662846 -292.795273) (xy 300.630211 -292.758436) (xy 300.603908 -292.71684) (xy 300.584617 -292.671564)
			(xy 300.57284 -292.62378) (xy 300.56888 -292.574726) (xy 300.230032 -292.574726) (xy 300.229537 -292.599333)
			(xy 300.221642 -292.64791) (xy 300.206058 -292.694591) (xy 300.183187 -292.738168) (xy 300.153622 -292.777512)
			(xy 300.118129 -292.811604) (xy 300.077626 -292.83956) (xy 300.033164 -292.860658) (xy 299.985893 -292.87435)
			(xy 299.937038 -292.880282) (xy 299.887863 -292.878301) (xy 299.839644 -292.868457) (xy 299.793628 -292.851005)
			(xy 299.751007 -292.826398) (xy 299.712886 -292.795273) (xy 299.680251 -292.758436) (xy 299.653948 -292.71684)
			(xy 299.634657 -292.671564) (xy 299.62288 -292.62378) (xy 299.61892 -292.574726) (xy 299.280072 -292.574726)
			(xy 299.279577 -292.599333) (xy 299.271682 -292.64791) (xy 299.256098 -292.694591) (xy 299.233227 -292.738168)
			(xy 299.203662 -292.777512) (xy 299.168169 -292.811604) (xy 299.127666 -292.83956) (xy 299.083204 -292.860658)
			(xy 299.035933 -292.87435) (xy 298.987078 -292.880282) (xy 298.937903 -292.878301) (xy 298.889684 -292.868457)
			(xy 298.843668 -292.851005) (xy 298.801047 -292.826398) (xy 298.762926 -292.795273) (xy 298.730291 -292.758436)
			(xy 298.703988 -292.71684) (xy 298.684697 -292.671564) (xy 298.67292 -292.62378) (xy 298.66896 -292.574726)
			(xy 298.330112 -292.574726) (xy 298.329617 -292.599333) (xy 298.321722 -292.64791) (xy 298.306138 -292.694591)
			(xy 298.283267 -292.738168) (xy 298.253702 -292.777512) (xy 298.218209 -292.811604) (xy 298.177706 -292.83956)
			(xy 298.133244 -292.860658) (xy 298.085973 -292.87435) (xy 298.037118 -292.880282) (xy 297.987943 -292.878301)
			(xy 297.939724 -292.868457) (xy 297.893708 -292.851005) (xy 297.851087 -292.826398) (xy 297.812966 -292.795273)
			(xy 297.780331 -292.758436) (xy 297.754028 -292.71684) (xy 297.734737 -292.671564) (xy 297.72296 -292.62378)
			(xy 297.719 -292.574726) (xy 297.380152 -292.574726) (xy 297.379657 -292.599333) (xy 297.371762 -292.64791)
			(xy 297.356178 -292.694591) (xy 297.333307 -292.738168) (xy 297.303742 -292.777512) (xy 297.268249 -292.811604)
			(xy 297.227746 -292.83956) (xy 297.183284 -292.860658) (xy 297.136013 -292.87435) (xy 297.087158 -292.880282)
			(xy 297.037983 -292.878301) (xy 296.989764 -292.868457) (xy 296.943748 -292.851005) (xy 296.901127 -292.826398)
			(xy 296.863006 -292.795273) (xy 296.830371 -292.758436) (xy 296.804068 -292.71684) (xy 296.784777 -292.671564)
			(xy 296.773 -292.62378) (xy 296.76904 -292.574726) (xy 296.430192 -292.574726) (xy 296.429697 -292.599333)
			(xy 296.421802 -292.64791) (xy 296.406218 -292.694591) (xy 296.383347 -292.738168) (xy 296.353782 -292.777512)
			(xy 296.318289 -292.811604) (xy 296.277786 -292.83956) (xy 296.233324 -292.860658) (xy 296.186053 -292.87435)
			(xy 296.137198 -292.880282) (xy 296.088023 -292.878301) (xy 296.039804 -292.868457) (xy 295.993788 -292.851005)
			(xy 295.951167 -292.826398) (xy 295.913046 -292.795273) (xy 295.880411 -292.758436) (xy 295.854108 -292.71684)
			(xy 295.834817 -292.671564) (xy 295.82304 -292.62378) (xy 295.81908 -292.574726) (xy 295.480232 -292.574726)
			(xy 295.479737 -292.599333) (xy 295.471842 -292.64791) (xy 295.456258 -292.694591) (xy 295.433387 -292.738168)
			(xy 295.403822 -292.777512) (xy 295.368329 -292.811604) (xy 295.327826 -292.83956) (xy 295.283364 -292.860658)
			(xy 295.236093 -292.87435) (xy 295.187238 -292.880282) (xy 295.138063 -292.878301) (xy 295.089844 -292.868457)
			(xy 295.043828 -292.851005) (xy 295.001207 -292.826398) (xy 294.963086 -292.795273) (xy 294.930451 -292.758436)
			(xy 294.904148 -292.71684) (xy 294.884857 -292.671564) (xy 294.87308 -292.62378) (xy 294.86912 -292.574726)
			(xy 294.530018 -292.574726) (xy 294.529523 -292.599333) (xy 294.521628 -292.64791) (xy 294.506044 -292.694591)
			(xy 294.483173 -292.738168) (xy 294.453608 -292.777512) (xy 294.418115 -292.811604) (xy 294.377612 -292.83956)
			(xy 294.33315 -292.860658) (xy 294.285879 -292.87435) (xy 294.237024 -292.880282) (xy 294.187849 -292.878301)
			(xy 294.13963 -292.868457) (xy 294.093614 -292.851005) (xy 294.050993 -292.826398) (xy 294.012872 -292.795273)
			(xy 293.980237 -292.758436) (xy 293.953934 -292.71684) (xy 293.934643 -292.671564) (xy 293.922866 -292.62378)
			(xy 293.918906 -292.574726) (xy 293.580058 -292.574726) (xy 293.579563 -292.599333) (xy 293.571668 -292.64791)
			(xy 293.556084 -292.694591) (xy 293.533213 -292.738168) (xy 293.503648 -292.777512) (xy 293.468155 -292.811604)
			(xy 293.427652 -292.83956) (xy 293.38319 -292.860658) (xy 293.335919 -292.87435) (xy 293.287064 -292.880282)
			(xy 293.237889 -292.878301) (xy 293.18967 -292.868457) (xy 293.143654 -292.851005) (xy 293.101033 -292.826398)
			(xy 293.062912 -292.795273) (xy 293.030277 -292.758436) (xy 293.003974 -292.71684) (xy 292.984683 -292.671564)
			(xy 292.972906 -292.62378) (xy 292.968946 -292.574726) (xy 292.630098 -292.574726) (xy 292.629603 -292.599333)
			(xy 292.621708 -292.64791) (xy 292.606124 -292.694591) (xy 292.583253 -292.738168) (xy 292.553688 -292.777512)
			(xy 292.518195 -292.811604) (xy 292.477692 -292.83956) (xy 292.43323 -292.860658) (xy 292.385959 -292.87435)
			(xy 292.337104 -292.880282) (xy 292.287929 -292.878301) (xy 292.23971 -292.868457) (xy 292.193694 -292.851005)
			(xy 292.151073 -292.826398) (xy 292.112952 -292.795273) (xy 292.080317 -292.758436) (xy 292.054014 -292.71684)
			(xy 292.034723 -292.671564) (xy 292.022946 -292.62378) (xy 292.018986 -292.574726) (xy 290.730173 -292.574726)
			(xy 290.730178 -292.57498) (xy 290.729683 -292.599587) (xy 290.721788 -292.648164) (xy 290.706204 -292.694845)
			(xy 290.683333 -292.738422) (xy 290.653768 -292.777766) (xy 290.618275 -292.811858) (xy 290.577772 -292.839814)
			(xy 290.53331 -292.860912) (xy 290.486039 -292.874604) (xy 290.437184 -292.880536) (xy 290.388009 -292.878555)
			(xy 290.33979 -292.868711) (xy 290.293774 -292.851259) (xy 290.251153 -292.826652) (xy 290.213032 -292.795527)
			(xy 290.180397 -292.75869) (xy 290.154094 -292.717094) (xy 290.134803 -292.671818) (xy 290.123026 -292.624034)
			(xy 290.119066 -292.57498) (xy 289.780218 -292.57498) (xy 289.779723 -292.599587) (xy 289.771828 -292.648164)
			(xy 289.756244 -292.694845) (xy 289.733373 -292.738422) (xy 289.703808 -292.777766) (xy 289.668315 -292.811858)
			(xy 289.627812 -292.839814) (xy 289.58335 -292.860912) (xy 289.536079 -292.874604) (xy 289.487224 -292.880536)
			(xy 289.438049 -292.878555) (xy 289.38983 -292.868711) (xy 289.343814 -292.851259) (xy 289.301193 -292.826652)
			(xy 289.263072 -292.795527) (xy 289.230437 -292.75869) (xy 289.204134 -292.717094) (xy 289.184843 -292.671818)
			(xy 289.173066 -292.624034) (xy 289.169106 -292.57498) (xy 288.830258 -292.57498) (xy 288.829763 -292.599587)
			(xy 288.821868 -292.648164) (xy 288.806284 -292.694845) (xy 288.783413 -292.738422) (xy 288.753848 -292.777766)
			(xy 288.718355 -292.811858) (xy 288.677852 -292.839814) (xy 288.63339 -292.860912) (xy 288.586119 -292.874604)
			(xy 288.537264 -292.880536) (xy 288.488089 -292.878555) (xy 288.43987 -292.868711) (xy 288.393854 -292.851259)
			(xy 288.351233 -292.826652) (xy 288.313112 -292.795527) (xy 288.280477 -292.75869) (xy 288.254174 -292.717094)
			(xy 288.234883 -292.671818) (xy 288.223106 -292.624034) (xy 288.219146 -292.57498) (xy 287.880044 -292.57498)
			(xy 287.879549 -292.599587) (xy 287.871654 -292.648164) (xy 287.85607 -292.694845) (xy 287.833199 -292.738422)
			(xy 287.803634 -292.777766) (xy 287.768141 -292.811858) (xy 287.727638 -292.839814) (xy 287.683176 -292.860912)
			(xy 287.635905 -292.874604) (xy 287.58705 -292.880536) (xy 287.537875 -292.878555) (xy 287.489656 -292.868711)
			(xy 287.44364 -292.851259) (xy 287.401019 -292.826652) (xy 287.362898 -292.795527) (xy 287.330263 -292.75869)
			(xy 287.30396 -292.717094) (xy 287.284669 -292.671818) (xy 287.272892 -292.624034) (xy 287.268932 -292.57498)
			(xy 286.930084 -292.57498) (xy 286.929589 -292.599587) (xy 286.921694 -292.648164) (xy 286.90611 -292.694845)
			(xy 286.883239 -292.738422) (xy 286.853674 -292.777766) (xy 286.818181 -292.811858) (xy 286.777678 -292.839814)
			(xy 286.733216 -292.860912) (xy 286.685945 -292.874604) (xy 286.63709 -292.880536) (xy 286.587915 -292.878555)
			(xy 286.539696 -292.868711) (xy 286.49368 -292.851259) (xy 286.451059 -292.826652) (xy 286.412938 -292.795527)
			(xy 286.380303 -292.75869) (xy 286.354 -292.717094) (xy 286.334709 -292.671818) (xy 286.322932 -292.624034)
			(xy 286.318972 -292.57498) (xy 285.980124 -292.57498) (xy 285.979629 -292.599587) (xy 285.971734 -292.648164)
			(xy 285.95615 -292.694845) (xy 285.933279 -292.738422) (xy 285.903714 -292.777766) (xy 285.868221 -292.811858)
			(xy 285.827718 -292.839814) (xy 285.783256 -292.860912) (xy 285.735985 -292.874604) (xy 285.68713 -292.880536)
			(xy 285.637955 -292.878555) (xy 285.589736 -292.868711) (xy 285.54372 -292.851259) (xy 285.501099 -292.826652)
			(xy 285.462978 -292.795527) (xy 285.430343 -292.75869) (xy 285.40404 -292.717094) (xy 285.384749 -292.671818)
			(xy 285.372972 -292.624034) (xy 285.369012 -292.57498) (xy 285.030164 -292.57498) (xy 285.029669 -292.599587)
			(xy 285.021774 -292.648164) (xy 285.00619 -292.694845) (xy 284.983319 -292.738422) (xy 284.953754 -292.777766)
			(xy 284.918261 -292.811858) (xy 284.877758 -292.839814) (xy 284.833296 -292.860912) (xy 284.786025 -292.874604)
			(xy 284.73717 -292.880536) (xy 284.687995 -292.878555) (xy 284.639776 -292.868711) (xy 284.59376 -292.851259)
			(xy 284.551139 -292.826652) (xy 284.513018 -292.795527) (xy 284.480383 -292.75869) (xy 284.45408 -292.717094)
			(xy 284.434789 -292.671818) (xy 284.423012 -292.624034) (xy 284.419052 -292.57498) (xy 284.080204 -292.57498)
			(xy 284.079709 -292.599587) (xy 284.071814 -292.648164) (xy 284.05623 -292.694845) (xy 284.033359 -292.738422)
			(xy 284.003794 -292.777766) (xy 283.968301 -292.811858) (xy 283.927798 -292.839814) (xy 283.883336 -292.860912)
			(xy 283.836065 -292.874604) (xy 283.78721 -292.880536) (xy 283.738035 -292.878555) (xy 283.689816 -292.868711)
			(xy 283.6438 -292.851259) (xy 283.601179 -292.826652) (xy 283.563058 -292.795527) (xy 283.530423 -292.75869)
			(xy 283.50412 -292.717094) (xy 283.484829 -292.671818) (xy 283.473052 -292.624034) (xy 283.469092 -292.57498)
			(xy 283.130244 -292.57498) (xy 283.129749 -292.599587) (xy 283.121854 -292.648164) (xy 283.10627 -292.694845)
			(xy 283.083399 -292.738422) (xy 283.053834 -292.777766) (xy 283.018341 -292.811858) (xy 282.977838 -292.839814)
			(xy 282.933376 -292.860912) (xy 282.886105 -292.874604) (xy 282.83725 -292.880536) (xy 282.788075 -292.878555)
			(xy 282.739856 -292.868711) (xy 282.69384 -292.851259) (xy 282.651219 -292.826652) (xy 282.613098 -292.795527)
			(xy 282.580463 -292.75869) (xy 282.55416 -292.717094) (xy 282.534869 -292.671818) (xy 282.523092 -292.624034)
			(xy 282.519132 -292.57498) (xy 282.180025 -292.57498) (xy 282.179535 -292.599333) (xy 282.17164 -292.64791)
			(xy 282.156056 -292.694591) (xy 282.133185 -292.738168) (xy 282.10362 -292.777512) (xy 282.068127 -292.811604)
			(xy 282.027624 -292.83956) (xy 281.983162 -292.860658) (xy 281.935891 -292.87435) (xy 281.887036 -292.880282)
			(xy 281.837861 -292.878301) (xy 281.789642 -292.868457) (xy 281.743626 -292.851005) (xy 281.701005 -292.826398)
			(xy 281.662884 -292.795273) (xy 281.630249 -292.758436) (xy 281.603946 -292.71684) (xy 281.584655 -292.671564)
			(xy 281.572878 -292.62378) (xy 281.568918 -292.574726) (xy 281.23007 -292.574726) (xy 281.229575 -292.599333)
			(xy 281.22168 -292.64791) (xy 281.206096 -292.694591) (xy 281.183225 -292.738168) (xy 281.15366 -292.777512)
			(xy 281.118167 -292.811604) (xy 281.077664 -292.83956) (xy 281.033202 -292.860658) (xy 280.985931 -292.87435)
			(xy 280.937076 -292.880282) (xy 280.887901 -292.878301) (xy 280.839682 -292.868457) (xy 280.793666 -292.851005)
			(xy 280.751045 -292.826398) (xy 280.712924 -292.795273) (xy 280.680289 -292.758436) (xy 280.653986 -292.71684)
			(xy 280.634695 -292.671564) (xy 280.622918 -292.62378) (xy 280.618958 -292.574726) (xy 280.280105 -292.574726)
			(xy 280.28011 -292.57498) (xy 280.279615 -292.599587) (xy 280.27172 -292.648164) (xy 280.256136 -292.694845)
			(xy 280.233265 -292.738422) (xy 280.2037 -292.777766) (xy 280.168207 -292.811858) (xy 280.127704 -292.839814)
			(xy 280.083242 -292.860912) (xy 280.035971 -292.874604) (xy 279.987116 -292.880536) (xy 279.937941 -292.878555)
			(xy 279.889722 -292.868711) (xy 279.843706 -292.851259) (xy 279.801085 -292.826652) (xy 279.762964 -292.795527)
			(xy 279.730329 -292.75869) (xy 279.704026 -292.717094) (xy 279.684735 -292.671818) (xy 279.672958 -292.624034)
			(xy 279.668998 -292.57498) (xy 279.33015 -292.57498) (xy 279.329655 -292.599587) (xy 279.32176 -292.648164)
			(xy 279.306176 -292.694845) (xy 279.283305 -292.738422) (xy 279.25374 -292.777766) (xy 279.218247 -292.811858)
			(xy 279.177744 -292.839814) (xy 279.133282 -292.860912) (xy 279.086011 -292.874604) (xy 279.037156 -292.880536)
			(xy 278.987981 -292.878555) (xy 278.939762 -292.868711) (xy 278.893746 -292.851259) (xy 278.851125 -292.826652)
			(xy 278.813004 -292.795527) (xy 278.780369 -292.75869) (xy 278.754066 -292.717094) (xy 278.734775 -292.671818)
			(xy 278.722998 -292.624034) (xy 278.719038 -292.57498) (xy 278.38019 -292.57498) (xy 278.379695 -292.599587)
			(xy 278.3718 -292.648164) (xy 278.356216 -292.694845) (xy 278.333345 -292.738422) (xy 278.30378 -292.777766)
			(xy 278.268287 -292.811858) (xy 278.227784 -292.839814) (xy 278.183322 -292.860912) (xy 278.136051 -292.874604)
			(xy 278.087196 -292.880536) (xy 278.038021 -292.878555) (xy 277.989802 -292.868711) (xy 277.943786 -292.851259)
			(xy 277.901165 -292.826652) (xy 277.863044 -292.795527) (xy 277.830409 -292.75869) (xy 277.804106 -292.717094)
			(xy 277.784815 -292.671818) (xy 277.773038 -292.624034) (xy 277.769078 -292.57498) (xy 277.43023 -292.57498)
			(xy 277.429735 -292.599587) (xy 277.42184 -292.648164) (xy 277.406256 -292.694845) (xy 277.383385 -292.738422)
			(xy 277.35382 -292.777766) (xy 277.318327 -292.811858) (xy 277.277824 -292.839814) (xy 277.233362 -292.860912)
			(xy 277.186091 -292.874604) (xy 277.137236 -292.880536) (xy 277.088061 -292.878555) (xy 277.039842 -292.868711)
			(xy 276.993826 -292.851259) (xy 276.951205 -292.826652) (xy 276.913084 -292.795527) (xy 276.880449 -292.75869)
			(xy 276.854146 -292.717094) (xy 276.834855 -292.671818) (xy 276.823078 -292.624034) (xy 276.819118 -292.57498)
			(xy 276.480016 -292.57498) (xy 276.479521 -292.599587) (xy 276.471626 -292.648164) (xy 276.456042 -292.694845)
			(xy 276.433171 -292.738422) (xy 276.403606 -292.777766) (xy 276.368113 -292.811858) (xy 276.32761 -292.839814)
			(xy 276.283148 -292.860912) (xy 276.235877 -292.874604) (xy 276.187022 -292.880536) (xy 276.137847 -292.878555)
			(xy 276.089628 -292.868711) (xy 276.043612 -292.851259) (xy 276.000991 -292.826652) (xy 275.96287 -292.795527)
			(xy 275.930235 -292.75869) (xy 275.903932 -292.717094) (xy 275.884641 -292.671818) (xy 275.872864 -292.624034)
			(xy 275.868904 -292.57498) (xy 275.530056 -292.57498) (xy 275.529561 -292.599587) (xy 275.521666 -292.648164)
			(xy 275.506082 -292.694845) (xy 275.483211 -292.738422) (xy 275.453646 -292.777766) (xy 275.418153 -292.811858)
			(xy 275.37765 -292.839814) (xy 275.333188 -292.860912) (xy 275.285917 -292.874604) (xy 275.237062 -292.880536)
			(xy 275.187887 -292.878555) (xy 275.139668 -292.868711) (xy 275.093652 -292.851259) (xy 275.051031 -292.826652)
			(xy 275.01291 -292.795527) (xy 274.980275 -292.75869) (xy 274.953972 -292.717094) (xy 274.934681 -292.671818)
			(xy 274.922904 -292.624034) (xy 274.918944 -292.57498) (xy 274.630896 -292.57498) (xy 274.630398 -292.601629)
			(xy 274.622455 -292.654333) (xy 274.606745 -292.705263) (xy 274.583619 -292.753284) (xy 274.553595 -292.797321)
			(xy 274.517343 -292.836392) (xy 274.475672 -292.869623) (xy 274.429514 -292.896272) (xy 274.3799 -292.915744)
			(xy 274.327938 -292.927604) (xy 274.274788 -292.931588) (xy 274.221638 -292.927604) (xy 274.169676 -292.915744)
			(xy 274.120062 -292.896272) (xy 274.073904 -292.869623) (xy 274.032233 -292.836392) (xy 273.995981 -292.797321)
			(xy 273.965957 -292.753284) (xy 273.942831 -292.705263) (xy 273.927121 -292.654333) (xy 273.919178 -292.601629)
			(xy 273.629309 -292.601629) (xy 273.621746 -292.648164) (xy 273.606162 -292.694845) (xy 273.583291 -292.738422)
			(xy 273.553726 -292.777766) (xy 273.518233 -292.811858) (xy 273.47773 -292.839814) (xy 273.433268 -292.860912)
			(xy 273.385997 -292.874604) (xy 273.337142 -292.880536) (xy 273.287967 -292.878555) (xy 273.239748 -292.868711)
			(xy 273.193732 -292.851259) (xy 273.151111 -292.826652) (xy 273.11299 -292.795527) (xy 273.080355 -292.75869)
			(xy 273.054052 -292.717094) (xy 273.034761 -292.671818) (xy 273.022984 -292.624034) (xy 273.019024 -292.57498)
			(xy 272.680171 -292.57498) (xy 272.679681 -292.599333) (xy 272.671786 -292.64791) (xy 272.656202 -292.694591)
			(xy 272.633331 -292.738168) (xy 272.603766 -292.777512) (xy 272.568273 -292.811604) (xy 272.52777 -292.83956)
			(xy 272.483308 -292.860658) (xy 272.436037 -292.87435) (xy 272.387182 -292.880282) (xy 272.338007 -292.878301)
			(xy 272.289788 -292.868457) (xy 272.243772 -292.851005) (xy 272.201151 -292.826398) (xy 272.16303 -292.795273)
			(xy 272.130395 -292.758436) (xy 272.104092 -292.71684) (xy 272.084801 -292.671564) (xy 272.073024 -292.62378)
			(xy 272.069064 -292.574726) (xy 271.730216 -292.574726) (xy 271.729721 -292.599333) (xy 271.721826 -292.64791)
			(xy 271.706242 -292.694591) (xy 271.683371 -292.738168) (xy 271.653806 -292.777512) (xy 271.618313 -292.811604)
			(xy 271.57781 -292.83956) (xy 271.533348 -292.860658) (xy 271.486077 -292.87435) (xy 271.437222 -292.880282)
			(xy 271.388047 -292.878301) (xy 271.339828 -292.868457) (xy 271.293812 -292.851005) (xy 271.251191 -292.826398)
			(xy 271.21307 -292.795273) (xy 271.180435 -292.758436) (xy 271.154132 -292.71684) (xy 271.134841 -292.671564)
			(xy 271.123064 -292.62378) (xy 271.119104 -292.574726) (xy 270.780251 -292.574726) (xy 270.780256 -292.57498)
			(xy 270.779761 -292.599587) (xy 270.771866 -292.648164) (xy 270.756282 -292.694845) (xy 270.733411 -292.738422)
			(xy 270.703846 -292.777766) (xy 270.668353 -292.811858) (xy 270.62785 -292.839814) (xy 270.583388 -292.860912)
			(xy 270.536117 -292.874604) (xy 270.487262 -292.880536) (xy 270.438087 -292.878555) (xy 270.389868 -292.868711)
			(xy 270.343852 -292.851259) (xy 270.301231 -292.826652) (xy 270.26311 -292.795527) (xy 270.230475 -292.75869)
			(xy 270.204172 -292.717094) (xy 270.184881 -292.671818) (xy 270.173104 -292.624034) (xy 270.169144 -292.57498)
			(xy 269.830042 -292.57498) (xy 269.829547 -292.599587) (xy 269.821652 -292.648164) (xy 269.806068 -292.694845)
			(xy 269.783197 -292.738422) (xy 269.753632 -292.777766) (xy 269.718139 -292.811858) (xy 269.677636 -292.839814)
			(xy 269.633174 -292.860912) (xy 269.585903 -292.874604) (xy 269.537048 -292.880536) (xy 269.487873 -292.878555)
			(xy 269.439654 -292.868711) (xy 269.393638 -292.851259) (xy 269.351017 -292.826652) (xy 269.312896 -292.795527)
			(xy 269.280261 -292.75869) (xy 269.253958 -292.717094) (xy 269.234667 -292.671818) (xy 269.22289 -292.624034)
			(xy 269.21893 -292.57498) (xy 268.880082 -292.57498) (xy 268.879587 -292.599587) (xy 268.871692 -292.648164)
			(xy 268.856108 -292.694845) (xy 268.833237 -292.738422) (xy 268.803672 -292.777766) (xy 268.768179 -292.811858)
			(xy 268.727676 -292.839814) (xy 268.683214 -292.860912) (xy 268.635943 -292.874604) (xy 268.587088 -292.880536)
			(xy 268.537913 -292.878555) (xy 268.489694 -292.868711) (xy 268.443678 -292.851259) (xy 268.401057 -292.826652)
			(xy 268.362936 -292.795527) (xy 268.330301 -292.75869) (xy 268.303998 -292.717094) (xy 268.284707 -292.671818)
			(xy 268.27293 -292.624034) (xy 268.26897 -292.57498) (xy 264.277733 -292.57498) (xy 264.288803 -292.59922)
			(xy 264.304158 -292.651515) (xy 264.311914 -292.705463) (xy 264.3124 -292.732714) (xy 264.311872 -292.762097)
			(xy 264.302839 -292.820164) (xy 264.285005 -292.876159) (xy 264.258791 -292.928754) (xy 264.224818 -292.976705)
			(xy 264.183891 -293.018876) (xy 264.160762 -293.037006) (xy 264.151364 -293.044372) (xy 264.14095 -293.064946)
			(xy 264.139426 -293.168832) (xy 264.149332 -293.189914) (xy 264.158476 -293.19728) (xy 264.180292 -293.215523)
			(xy 264.218835 -293.257333) (xy 264.250747 -293.304401) (xy 264.275319 -293.355684) (xy 264.292009 -293.410045)
			(xy 264.300447 -293.466281) (xy 264.30097 -293.494714) (xy 264.934444 -293.494714) (xy 264.938515 -293.439092)
			(xy 264.950641 -293.384655) (xy 264.970564 -293.332564) (xy 264.99786 -293.283929) (xy 265.031946 -293.239786)
			(xy 265.072095 -293.201077) (xy 265.117453 -293.168626) (xy 265.167053 -293.143125) (xy 265.219837 -293.125118)
			(xy 265.27468 -293.114988) (xy 265.330414 -293.112951) (xy 265.385851 -293.119051) (xy 265.439808 -293.133157)
			(xy 265.491137 -293.154969) (xy 265.538743 -293.184023) (xy 265.581611 -293.219698) (xy 265.618828 -293.261235)
			(xy 265.649601 -293.307748) (xy 265.673273 -293.358245) (xy 265.689341 -293.411652) (xy 265.697461 -293.466828)
			(xy 265.69797 -293.494714) (xy 265.820904 -293.494714) (xy 265.824975 -293.439092) (xy 265.837101 -293.384655)
			(xy 265.857024 -293.332564) (xy 265.88432 -293.283929) (xy 265.918406 -293.239786) (xy 265.958555 -293.201077)
			(xy 266.003913 -293.168626) (xy 266.053513 -293.143125) (xy 266.106297 -293.125118) (xy 266.16114 -293.114988)
			(xy 266.216874 -293.112951) (xy 266.272311 -293.119051) (xy 266.326268 -293.133157) (xy 266.377597 -293.154969)
			(xy 266.425203 -293.184023) (xy 266.468071 -293.219698) (xy 266.505288 -293.261235) (xy 266.536061 -293.307748)
			(xy 266.559733 -293.358245) (xy 266.575801 -293.411652) (xy 266.583921 -293.466828) (xy 266.58443 -293.494714)
			(xy 266.583921 -293.5226) (xy 266.583577 -293.52494) (xy 270.169144 -293.52494) (xy 270.173104 -293.475886)
			(xy 270.184881 -293.428102) (xy 270.204172 -293.382826) (xy 270.230475 -293.34123) (xy 270.26311 -293.304393)
			(xy 270.301231 -293.273268) (xy 270.343852 -293.248661) (xy 270.389868 -293.231209) (xy 270.438087 -293.221365)
			(xy 270.487262 -293.219384) (xy 270.536117 -293.225316) (xy 270.583388 -293.239008) (xy 270.62785 -293.260106)
			(xy 270.668353 -293.288062) (xy 270.703846 -293.322154) (xy 270.733411 -293.361498) (xy 270.756282 -293.405075)
			(xy 270.771866 -293.451756) (xy 270.779761 -293.500333) (xy 270.780256 -293.52494) (xy 271.119104 -293.52494)
			(xy 271.123064 -293.475886) (xy 271.134841 -293.428102) (xy 271.154132 -293.382826) (xy 271.180435 -293.34123)
			(xy 271.21307 -293.304393) (xy 271.251191 -293.273268) (xy 271.293812 -293.248661) (xy 271.339828 -293.231209)
			(xy 271.388047 -293.221365) (xy 271.437222 -293.219384) (xy 271.486077 -293.225316) (xy 271.533348 -293.239008)
			(xy 271.57781 -293.260106) (xy 271.618313 -293.288062) (xy 271.653806 -293.322154) (xy 271.683371 -293.361498)
			(xy 271.706242 -293.405075) (xy 271.721826 -293.451756) (xy 271.729721 -293.500333) (xy 271.730216 -293.52494)
			(xy 272.069064 -293.52494) (xy 272.073024 -293.475886) (xy 272.084801 -293.428102) (xy 272.104092 -293.382826)
			(xy 272.130395 -293.34123) (xy 272.16303 -293.304393) (xy 272.201151 -293.273268) (xy 272.243772 -293.248661)
			(xy 272.289788 -293.231209) (xy 272.338007 -293.221365) (xy 272.387182 -293.219384) (xy 272.436037 -293.225316)
			(xy 272.483308 -293.239008) (xy 272.52777 -293.260106) (xy 272.568273 -293.288062) (xy 272.603766 -293.322154)
			(xy 272.633331 -293.361498) (xy 272.656202 -293.405075) (xy 272.671786 -293.451756) (xy 272.679681 -293.500333)
			(xy 272.680176 -293.52494) (xy 273.019024 -293.52494) (xy 273.022984 -293.475886) (xy 273.034761 -293.428102)
			(xy 273.054052 -293.382826) (xy 273.080355 -293.34123) (xy 273.11299 -293.304393) (xy 273.151111 -293.273268)
			(xy 273.193732 -293.248661) (xy 273.239748 -293.231209) (xy 273.287967 -293.221365) (xy 273.337142 -293.219384)
			(xy 273.385997 -293.225316) (xy 273.433268 -293.239008) (xy 273.47773 -293.260106) (xy 273.518233 -293.288062)
			(xy 273.553726 -293.322154) (xy 273.583291 -293.361498) (xy 273.606162 -293.405075) (xy 273.621746 -293.451756)
			(xy 273.629641 -293.500333) (xy 273.630136 -293.52494) (xy 273.968984 -293.52494) (xy 273.972944 -293.475886)
			(xy 273.984721 -293.428102) (xy 274.004012 -293.382826) (xy 274.030315 -293.34123) (xy 274.06295 -293.304393)
			(xy 274.101071 -293.273268) (xy 274.143692 -293.248661) (xy 274.189708 -293.231209) (xy 274.237927 -293.221365)
			(xy 274.287102 -293.219384) (xy 274.335957 -293.225316) (xy 274.383228 -293.239008) (xy 274.42769 -293.260106)
			(xy 274.468193 -293.288062) (xy 274.503686 -293.322154) (xy 274.533251 -293.361498) (xy 274.556122 -293.405075)
			(xy 274.571706 -293.451756) (xy 274.579601 -293.500333) (xy 274.580096 -293.52494) (xy 274.579601 -293.549547)
			(xy 274.579269 -293.551589) (xy 274.869138 -293.551589) (xy 274.869138 -293.498291) (xy 274.877081 -293.445587)
			(xy 274.892791 -293.394657) (xy 274.915917 -293.346636) (xy 274.945941 -293.302599) (xy 274.982193 -293.263528)
			(xy 275.023864 -293.230297) (xy 275.070022 -293.203648) (xy 275.119636 -293.184176) (xy 275.171598 -293.172316)
			(xy 275.224748 -293.168333) (xy 275.277898 -293.172316) (xy 275.32986 -293.184176) (xy 275.379474 -293.203648)
			(xy 275.425632 -293.230297) (xy 275.467303 -293.263528) (xy 275.503555 -293.302599) (xy 275.533579 -293.346636)
			(xy 275.556705 -293.394657) (xy 275.572415 -293.445587) (xy 275.580358 -293.498291) (xy 275.580856 -293.52494)
			(xy 275.868904 -293.52494) (xy 275.872864 -293.475886) (xy 275.884641 -293.428102) (xy 275.903932 -293.382826)
			(xy 275.930235 -293.34123) (xy 275.96287 -293.304393) (xy 276.000991 -293.273268) (xy 276.043612 -293.248661)
			(xy 276.089628 -293.231209) (xy 276.137847 -293.221365) (xy 276.187022 -293.219384) (xy 276.235877 -293.225316)
			(xy 276.283148 -293.239008) (xy 276.32761 -293.260106) (xy 276.368113 -293.288062) (xy 276.403606 -293.322154)
			(xy 276.433171 -293.361498) (xy 276.456042 -293.405075) (xy 276.471626 -293.451756) (xy 276.479521 -293.500333)
			(xy 276.480016 -293.52494) (xy 277.769078 -293.52494) (xy 277.773038 -293.475886) (xy 277.784815 -293.428102)
			(xy 277.804106 -293.382826) (xy 277.830409 -293.34123) (xy 277.863044 -293.304393) (xy 277.901165 -293.273268)
			(xy 277.943786 -293.248661) (xy 277.989802 -293.231209) (xy 278.038021 -293.221365) (xy 278.087196 -293.219384)
			(xy 278.136051 -293.225316) (xy 278.183322 -293.239008) (xy 278.227784 -293.260106) (xy 278.268287 -293.288062)
			(xy 278.30378 -293.322154) (xy 278.333345 -293.361498) (xy 278.356216 -293.405075) (xy 278.3718 -293.451756)
			(xy 278.379695 -293.500333) (xy 278.38019 -293.52494) (xy 279.668998 -293.52494) (xy 279.672958 -293.475886)
			(xy 279.684735 -293.428102) (xy 279.704026 -293.382826) (xy 279.730329 -293.34123) (xy 279.762964 -293.304393)
			(xy 279.801085 -293.273268) (xy 279.843706 -293.248661) (xy 279.889722 -293.231209) (xy 279.937941 -293.221365)
			(xy 279.987116 -293.219384) (xy 280.035971 -293.225316) (xy 280.083242 -293.239008) (xy 280.127704 -293.260106)
			(xy 280.168207 -293.288062) (xy 280.2037 -293.322154) (xy 280.233265 -293.361498) (xy 280.256136 -293.405075)
			(xy 280.27172 -293.451756) (xy 280.279615 -293.500333) (xy 280.28011 -293.52494) (xy 280.618958 -293.52494)
			(xy 280.622918 -293.475886) (xy 280.634695 -293.428102) (xy 280.653986 -293.382826) (xy 280.680289 -293.34123)
			(xy 280.712924 -293.304393) (xy 280.751045 -293.273268) (xy 280.793666 -293.248661) (xy 280.839682 -293.231209)
			(xy 280.887901 -293.221365) (xy 280.937076 -293.219384) (xy 280.985931 -293.225316) (xy 281.033202 -293.239008)
			(xy 281.077664 -293.260106) (xy 281.118167 -293.288062) (xy 281.15366 -293.322154) (xy 281.183225 -293.361498)
			(xy 281.206096 -293.405075) (xy 281.22168 -293.451756) (xy 281.229575 -293.500333) (xy 281.23007 -293.52494)
			(xy 281.568918 -293.52494) (xy 281.572878 -293.475886) (xy 281.584655 -293.428102) (xy 281.603946 -293.382826)
			(xy 281.630249 -293.34123) (xy 281.662884 -293.304393) (xy 281.701005 -293.273268) (xy 281.743626 -293.248661)
			(xy 281.789642 -293.231209) (xy 281.837861 -293.221365) (xy 281.887036 -293.219384) (xy 281.935891 -293.225316)
			(xy 281.983162 -293.239008) (xy 282.027624 -293.260106) (xy 282.068127 -293.288062) (xy 282.10362 -293.322154)
			(xy 282.133185 -293.361498) (xy 282.156056 -293.405075) (xy 282.17164 -293.451756) (xy 282.179535 -293.500333)
			(xy 282.18003 -293.52494) (xy 282.519132 -293.52494) (xy 282.523092 -293.475886) (xy 282.534869 -293.428102)
			(xy 282.55416 -293.382826) (xy 282.580463 -293.34123) (xy 282.613098 -293.304393) (xy 282.651219 -293.273268)
			(xy 282.69384 -293.248661) (xy 282.739856 -293.231209) (xy 282.788075 -293.221365) (xy 282.83725 -293.219384)
			(xy 282.886105 -293.225316) (xy 282.933376 -293.239008) (xy 282.977838 -293.260106) (xy 283.018341 -293.288062)
			(xy 283.053834 -293.322154) (xy 283.083399 -293.361498) (xy 283.10627 -293.405075) (xy 283.121854 -293.451756)
			(xy 283.129749 -293.500333) (xy 283.130244 -293.52494) (xy 283.469092 -293.52494) (xy 283.473052 -293.475886)
			(xy 283.484829 -293.428102) (xy 283.50412 -293.382826) (xy 283.530423 -293.34123) (xy 283.563058 -293.304393)
			(xy 283.601179 -293.273268) (xy 283.6438 -293.248661) (xy 283.689816 -293.231209) (xy 283.738035 -293.221365)
			(xy 283.78721 -293.219384) (xy 283.836065 -293.225316) (xy 283.883336 -293.239008) (xy 283.927798 -293.260106)
			(xy 283.968301 -293.288062) (xy 284.003794 -293.322154) (xy 284.033359 -293.361498) (xy 284.05623 -293.405075)
			(xy 284.071814 -293.451756) (xy 284.079709 -293.500333) (xy 284.080204 -293.52494) (xy 284.419052 -293.52494)
			(xy 284.423012 -293.475886) (xy 284.434789 -293.428102) (xy 284.45408 -293.382826) (xy 284.480383 -293.34123)
			(xy 284.513018 -293.304393) (xy 284.551139 -293.273268) (xy 284.59376 -293.248661) (xy 284.639776 -293.231209)
			(xy 284.687995 -293.221365) (xy 284.73717 -293.219384) (xy 284.786025 -293.225316) (xy 284.833296 -293.239008)
			(xy 284.877758 -293.260106) (xy 284.918261 -293.288062) (xy 284.953754 -293.322154) (xy 284.983319 -293.361498)
			(xy 285.00619 -293.405075) (xy 285.021774 -293.451756) (xy 285.029669 -293.500333) (xy 285.030164 -293.52494)
			(xy 285.369012 -293.52494) (xy 285.372972 -293.475886) (xy 285.384749 -293.428102) (xy 285.40404 -293.382826)
			(xy 285.430343 -293.34123) (xy 285.462978 -293.304393) (xy 285.501099 -293.273268) (xy 285.54372 -293.248661)
			(xy 285.589736 -293.231209) (xy 285.637955 -293.221365) (xy 285.68713 -293.219384) (xy 285.735985 -293.225316)
			(xy 285.783256 -293.239008) (xy 285.827718 -293.260106) (xy 285.868221 -293.288062) (xy 285.903714 -293.322154)
			(xy 285.933279 -293.361498) (xy 285.95615 -293.405075) (xy 285.971734 -293.451756) (xy 285.979629 -293.500333)
			(xy 285.980124 -293.52494) (xy 286.318972 -293.52494) (xy 286.322932 -293.475886) (xy 286.334709 -293.428102)
			(xy 286.354 -293.382826) (xy 286.380303 -293.34123) (xy 286.412938 -293.304393) (xy 286.451059 -293.273268)
			(xy 286.49368 -293.248661) (xy 286.539696 -293.231209) (xy 286.587915 -293.221365) (xy 286.63709 -293.219384)
			(xy 286.685945 -293.225316) (xy 286.733216 -293.239008) (xy 286.777678 -293.260106) (xy 286.818181 -293.288062)
			(xy 286.853674 -293.322154) (xy 286.883239 -293.361498) (xy 286.90611 -293.405075) (xy 286.921694 -293.451756)
			(xy 286.929589 -293.500333) (xy 286.930084 -293.52494) (xy 287.268932 -293.52494) (xy 287.272892 -293.475886)
			(xy 287.284669 -293.428102) (xy 287.30396 -293.382826) (xy 287.330263 -293.34123) (xy 287.362898 -293.304393)
			(xy 287.401019 -293.273268) (xy 287.44364 -293.248661) (xy 287.489656 -293.231209) (xy 287.537875 -293.221365)
			(xy 287.58705 -293.219384) (xy 287.635905 -293.225316) (xy 287.683176 -293.239008) (xy 287.727638 -293.260106)
			(xy 287.768141 -293.288062) (xy 287.803634 -293.322154) (xy 287.833199 -293.361498) (xy 287.85607 -293.405075)
			(xy 287.871654 -293.451756) (xy 287.879549 -293.500333) (xy 287.880044 -293.52494) (xy 288.218892 -293.52494)
			(xy 288.222852 -293.475886) (xy 288.234629 -293.428102) (xy 288.25392 -293.382826) (xy 288.280223 -293.34123)
			(xy 288.312858 -293.304393) (xy 288.350979 -293.273268) (xy 288.3936 -293.248661) (xy 288.439616 -293.231209)
			(xy 288.487835 -293.221365) (xy 288.53701 -293.219384) (xy 288.585865 -293.225316) (xy 288.633136 -293.239008)
			(xy 288.677598 -293.260106) (xy 288.718101 -293.288062) (xy 288.753594 -293.322154) (xy 288.783159 -293.361498)
			(xy 288.80603 -293.405075) (xy 288.821614 -293.451756) (xy 288.829509 -293.500333) (xy 288.830004 -293.52494)
			(xy 289.169106 -293.52494) (xy 289.173066 -293.475886) (xy 289.184843 -293.428102) (xy 289.204134 -293.382826)
			(xy 289.230437 -293.34123) (xy 289.263072 -293.304393) (xy 289.301193 -293.273268) (xy 289.343814 -293.248661)
			(xy 289.38983 -293.231209) (xy 289.438049 -293.221365) (xy 289.487224 -293.219384) (xy 289.536079 -293.225316)
			(xy 289.58335 -293.239008) (xy 289.627812 -293.260106) (xy 289.668315 -293.288062) (xy 289.703808 -293.322154)
			(xy 289.733373 -293.361498) (xy 289.756244 -293.405075) (xy 289.771828 -293.451756) (xy 289.779723 -293.500333)
			(xy 289.780218 -293.52494) (xy 290.119066 -293.52494) (xy 290.123026 -293.475886) (xy 290.134803 -293.428102)
			(xy 290.154094 -293.382826) (xy 290.180397 -293.34123) (xy 290.213032 -293.304393) (xy 290.251153 -293.273268)
			(xy 290.293774 -293.248661) (xy 290.33979 -293.231209) (xy 290.388009 -293.221365) (xy 290.437184 -293.219384)
			(xy 290.486039 -293.225316) (xy 290.53331 -293.239008) (xy 290.577772 -293.260106) (xy 290.618275 -293.288062)
			(xy 290.653768 -293.322154) (xy 290.683333 -293.361498) (xy 290.706204 -293.405075) (xy 290.721788 -293.451756)
			(xy 290.729683 -293.500333) (xy 290.730178 -293.52494) (xy 292.018986 -293.52494) (xy 292.022946 -293.475886)
			(xy 292.034723 -293.428102) (xy 292.054014 -293.382826) (xy 292.080317 -293.34123) (xy 292.112952 -293.304393)
			(xy 292.151073 -293.273268) (xy 292.193694 -293.248661) (xy 292.23971 -293.231209) (xy 292.287929 -293.221365)
			(xy 292.337104 -293.219384) (xy 292.385959 -293.225316) (xy 292.43323 -293.239008) (xy 292.477692 -293.260106)
			(xy 292.518195 -293.288062) (xy 292.553688 -293.322154) (xy 292.583253 -293.361498) (xy 292.606124 -293.405075)
			(xy 292.621708 -293.451756) (xy 292.629603 -293.500333) (xy 292.630098 -293.52494) (xy 292.968946 -293.52494)
			(xy 292.972906 -293.475886) (xy 292.984683 -293.428102) (xy 293.003974 -293.382826) (xy 293.030277 -293.34123)
			(xy 293.062912 -293.304393) (xy 293.101033 -293.273268) (xy 293.143654 -293.248661) (xy 293.18967 -293.231209)
			(xy 293.237889 -293.221365) (xy 293.287064 -293.219384) (xy 293.335919 -293.225316) (xy 293.38319 -293.239008)
			(xy 293.427652 -293.260106) (xy 293.468155 -293.288062) (xy 293.503648 -293.322154) (xy 293.533213 -293.361498)
			(xy 293.556084 -293.405075) (xy 293.571668 -293.451756) (xy 293.579563 -293.500333) (xy 293.580058 -293.52494)
			(xy 293.918906 -293.52494) (xy 293.922866 -293.475886) (xy 293.934643 -293.428102) (xy 293.953934 -293.382826)
			(xy 293.980237 -293.34123) (xy 294.012872 -293.304393) (xy 294.050993 -293.273268) (xy 294.093614 -293.248661)
			(xy 294.13963 -293.231209) (xy 294.187849 -293.221365) (xy 294.237024 -293.219384) (xy 294.285879 -293.225316)
			(xy 294.33315 -293.239008) (xy 294.377612 -293.260106) (xy 294.418115 -293.288062) (xy 294.453608 -293.322154)
			(xy 294.483173 -293.361498) (xy 294.506044 -293.405075) (xy 294.521628 -293.451756) (xy 294.529523 -293.500333)
			(xy 294.530018 -293.52494) (xy 294.86912 -293.52494) (xy 294.87308 -293.475886) (xy 294.884857 -293.428102)
			(xy 294.904148 -293.382826) (xy 294.930451 -293.34123) (xy 294.963086 -293.304393) (xy 295.001207 -293.273268)
			(xy 295.043828 -293.248661) (xy 295.089844 -293.231209) (xy 295.138063 -293.221365) (xy 295.187238 -293.219384)
			(xy 295.236093 -293.225316) (xy 295.283364 -293.239008) (xy 295.327826 -293.260106) (xy 295.368329 -293.288062)
			(xy 295.403822 -293.322154) (xy 295.433387 -293.361498) (xy 295.456258 -293.405075) (xy 295.471842 -293.451756)
			(xy 295.479737 -293.500333) (xy 295.480232 -293.52494) (xy 295.81908 -293.52494) (xy 295.82304 -293.475886)
			(xy 295.834817 -293.428102) (xy 295.854108 -293.382826) (xy 295.880411 -293.34123) (xy 295.913046 -293.304393)
			(xy 295.951167 -293.273268) (xy 295.993788 -293.248661) (xy 296.039804 -293.231209) (xy 296.088023 -293.221365)
			(xy 296.137198 -293.219384) (xy 296.186053 -293.225316) (xy 296.233324 -293.239008) (xy 296.277786 -293.260106)
			(xy 296.318289 -293.288062) (xy 296.353782 -293.322154) (xy 296.383347 -293.361498) (xy 296.406218 -293.405075)
			(xy 296.421802 -293.451756) (xy 296.429697 -293.500333) (xy 296.430192 -293.52494) (xy 296.76904 -293.52494)
			(xy 296.773 -293.475886) (xy 296.784777 -293.428102) (xy 296.804068 -293.382826) (xy 296.830371 -293.34123)
			(xy 296.863006 -293.304393) (xy 296.901127 -293.273268) (xy 296.943748 -293.248661) (xy 296.989764 -293.231209)
			(xy 297.037983 -293.221365) (xy 297.087158 -293.219384) (xy 297.136013 -293.225316) (xy 297.183284 -293.239008)
			(xy 297.227746 -293.260106) (xy 297.268249 -293.288062) (xy 297.303742 -293.322154) (xy 297.333307 -293.361498)
			(xy 297.356178 -293.405075) (xy 297.371762 -293.451756) (xy 297.379657 -293.500333) (xy 297.380152 -293.52494)
			(xy 297.719 -293.52494) (xy 297.72296 -293.475886) (xy 297.734737 -293.428102) (xy 297.754028 -293.382826)
			(xy 297.780331 -293.34123) (xy 297.812966 -293.304393) (xy 297.851087 -293.273268) (xy 297.893708 -293.248661)
			(xy 297.939724 -293.231209) (xy 297.987943 -293.221365) (xy 298.037118 -293.219384) (xy 298.085973 -293.225316)
			(xy 298.133244 -293.239008) (xy 298.177706 -293.260106) (xy 298.218209 -293.288062) (xy 298.253702 -293.322154)
			(xy 298.283267 -293.361498) (xy 298.306138 -293.405075) (xy 298.321722 -293.451756) (xy 298.329617 -293.500333)
			(xy 298.330112 -293.52494) (xy 298.66896 -293.52494) (xy 298.67292 -293.475886) (xy 298.684697 -293.428102)
			(xy 298.703988 -293.382826) (xy 298.730291 -293.34123) (xy 298.762926 -293.304393) (xy 298.801047 -293.273268)
			(xy 298.843668 -293.248661) (xy 298.889684 -293.231209) (xy 298.937903 -293.221365) (xy 298.987078 -293.219384)
			(xy 299.035933 -293.225316) (xy 299.083204 -293.239008) (xy 299.127666 -293.260106) (xy 299.168169 -293.288062)
			(xy 299.203662 -293.322154) (xy 299.233227 -293.361498) (xy 299.256098 -293.405075) (xy 299.271682 -293.451756)
			(xy 299.279577 -293.500333) (xy 299.280072 -293.52494) (xy 299.61892 -293.52494) (xy 299.62288 -293.475886)
			(xy 299.634657 -293.428102) (xy 299.653948 -293.382826) (xy 299.680251 -293.34123) (xy 299.712886 -293.304393)
			(xy 299.751007 -293.273268) (xy 299.793628 -293.248661) (xy 299.839644 -293.231209) (xy 299.887863 -293.221365)
			(xy 299.937038 -293.219384) (xy 299.985893 -293.225316) (xy 300.033164 -293.239008) (xy 300.077626 -293.260106)
			(xy 300.118129 -293.288062) (xy 300.153622 -293.322154) (xy 300.183187 -293.361498) (xy 300.206058 -293.405075)
			(xy 300.221642 -293.451756) (xy 300.229537 -293.500333) (xy 300.230032 -293.52494) (xy 300.56888 -293.52494)
			(xy 300.57284 -293.475886) (xy 300.584617 -293.428102) (xy 300.603908 -293.382826) (xy 300.630211 -293.34123)
			(xy 300.662846 -293.304393) (xy 300.700967 -293.273268) (xy 300.743588 -293.248661) (xy 300.789604 -293.231209)
			(xy 300.837823 -293.221365) (xy 300.886998 -293.219384) (xy 300.935853 -293.225316) (xy 300.983124 -293.239008)
			(xy 301.027586 -293.260106) (xy 301.068089 -293.288062) (xy 301.103582 -293.322154) (xy 301.133147 -293.361498)
			(xy 301.156018 -293.405075) (xy 301.171602 -293.451756) (xy 301.179497 -293.500333) (xy 301.179992 -293.52494)
			(xy 301.519094 -293.52494) (xy 301.523054 -293.475886) (xy 301.534831 -293.428102) (xy 301.554122 -293.382826)
			(xy 301.580425 -293.34123) (xy 301.61306 -293.304393) (xy 301.651181 -293.273268) (xy 301.693802 -293.248661)
			(xy 301.739818 -293.231209) (xy 301.788037 -293.221365) (xy 301.837212 -293.219384) (xy 301.886067 -293.225316)
			(xy 301.933338 -293.239008) (xy 301.9778 -293.260106) (xy 302.018303 -293.288062) (xy 302.053796 -293.322154)
			(xy 302.083361 -293.361498) (xy 302.106232 -293.405075) (xy 302.121816 -293.451756) (xy 302.129711 -293.500333)
			(xy 302.130206 -293.52494) (xy 303.419014 -293.52494) (xy 303.422974 -293.475886) (xy 303.434751 -293.428102)
			(xy 303.454042 -293.382826) (xy 303.480345 -293.34123) (xy 303.51298 -293.304393) (xy 303.551101 -293.273268)
			(xy 303.593722 -293.248661) (xy 303.639738 -293.231209) (xy 303.687957 -293.221365) (xy 303.737132 -293.219384)
			(xy 303.785987 -293.225316) (xy 303.833258 -293.239008) (xy 303.87772 -293.260106) (xy 303.918223 -293.288062)
			(xy 303.953716 -293.322154) (xy 303.983281 -293.361498) (xy 304.006152 -293.405075) (xy 304.021736 -293.451756)
			(xy 304.029631 -293.500333) (xy 304.030126 -293.52494) (xy 304.368974 -293.52494) (xy 304.372934 -293.475886)
			(xy 304.384711 -293.428102) (xy 304.404002 -293.382826) (xy 304.430305 -293.34123) (xy 304.46294 -293.304393)
			(xy 304.501061 -293.273268) (xy 304.543682 -293.248661) (xy 304.589698 -293.231209) (xy 304.637917 -293.221365)
			(xy 304.687092 -293.219384) (xy 304.735947 -293.225316) (xy 304.783218 -293.239008) (xy 304.82768 -293.260106)
			(xy 304.868183 -293.288062) (xy 304.903676 -293.322154) (xy 304.933241 -293.361498) (xy 304.956112 -293.405075)
			(xy 304.971696 -293.451756) (xy 304.979591 -293.500333) (xy 304.980086 -293.52494) (xy 305.318934 -293.52494)
			(xy 305.322894 -293.475886) (xy 305.334671 -293.428102) (xy 305.353962 -293.382826) (xy 305.380265 -293.34123)
			(xy 305.4129 -293.304393) (xy 305.451021 -293.273268) (xy 305.493642 -293.248661) (xy 305.539658 -293.231209)
			(xy 305.587877 -293.221365) (xy 305.637052 -293.219384) (xy 305.685907 -293.225316) (xy 305.733178 -293.239008)
			(xy 305.77764 -293.260106) (xy 305.818143 -293.288062) (xy 305.853636 -293.322154) (xy 305.883201 -293.361498)
			(xy 305.906072 -293.405075) (xy 305.921656 -293.451756) (xy 305.929551 -293.500333) (xy 305.930046 -293.52494)
			(xy 306.269148 -293.52494) (xy 306.273108 -293.475886) (xy 306.284885 -293.428102) (xy 306.304176 -293.382826)
			(xy 306.330479 -293.34123) (xy 306.363114 -293.304393) (xy 306.401235 -293.273268) (xy 306.443856 -293.248661)
			(xy 306.489872 -293.231209) (xy 306.538091 -293.221365) (xy 306.587266 -293.219384) (xy 306.636121 -293.225316)
			(xy 306.683392 -293.239008) (xy 306.727854 -293.260106) (xy 306.768357 -293.288062) (xy 306.80385 -293.322154)
			(xy 306.833415 -293.361498) (xy 306.856286 -293.405075) (xy 306.87187 -293.451756) (xy 306.879765 -293.500333)
			(xy 306.88026 -293.52494) (xy 307.219108 -293.52494) (xy 307.223068 -293.475886) (xy 307.234845 -293.428102)
			(xy 307.254136 -293.382826) (xy 307.280439 -293.34123) (xy 307.313074 -293.304393) (xy 307.351195 -293.273268)
			(xy 307.393816 -293.248661) (xy 307.439832 -293.231209) (xy 307.488051 -293.221365) (xy 307.537226 -293.219384)
			(xy 307.586081 -293.225316) (xy 307.633352 -293.239008) (xy 307.677814 -293.260106) (xy 307.718317 -293.288062)
			(xy 307.75381 -293.322154) (xy 307.783375 -293.361498) (xy 307.806246 -293.405075) (xy 307.82183 -293.451756)
			(xy 307.829725 -293.500333) (xy 307.83022 -293.52494) (xy 308.169068 -293.52494) (xy 308.173028 -293.475886)
			(xy 308.184805 -293.428102) (xy 308.204096 -293.382826) (xy 308.230399 -293.34123) (xy 308.263034 -293.304393)
			(xy 308.301155 -293.273268) (xy 308.343776 -293.248661) (xy 308.389792 -293.231209) (xy 308.438011 -293.221365)
			(xy 308.487186 -293.219384) (xy 308.536041 -293.225316) (xy 308.583312 -293.239008) (xy 308.627774 -293.260106)
			(xy 308.668277 -293.288062) (xy 308.70377 -293.322154) (xy 308.733335 -293.361498) (xy 308.756206 -293.405075)
			(xy 308.77179 -293.451756) (xy 308.779685 -293.500333) (xy 308.78018 -293.52494) (xy 309.119028 -293.52494)
			(xy 309.122988 -293.475886) (xy 309.134765 -293.428102) (xy 309.154056 -293.382826) (xy 309.180359 -293.34123)
			(xy 309.212994 -293.304393) (xy 309.251115 -293.273268) (xy 309.293736 -293.248661) (xy 309.339752 -293.231209)
			(xy 309.387971 -293.221365) (xy 309.437146 -293.219384) (xy 309.486001 -293.225316) (xy 309.533272 -293.239008)
			(xy 309.577734 -293.260106) (xy 309.618237 -293.288062) (xy 309.65373 -293.322154) (xy 309.683295 -293.361498)
			(xy 309.706166 -293.405075) (xy 309.72175 -293.451756) (xy 309.729645 -293.500333) (xy 309.73014 -293.52494)
			(xy 310.068988 -293.52494) (xy 310.072948 -293.475886) (xy 310.084725 -293.428102) (xy 310.104016 -293.382826)
			(xy 310.130319 -293.34123) (xy 310.162954 -293.304393) (xy 310.201075 -293.273268) (xy 310.243696 -293.248661)
			(xy 310.289712 -293.231209) (xy 310.337931 -293.221365) (xy 310.387106 -293.219384) (xy 310.435961 -293.225316)
			(xy 310.483232 -293.239008) (xy 310.527694 -293.260106) (xy 310.568197 -293.288062) (xy 310.60369 -293.322154)
			(xy 310.633255 -293.361498) (xy 310.656126 -293.405075) (xy 310.67171 -293.451756) (xy 310.679605 -293.500333)
			(xy 310.6801 -293.52494) (xy 311.018948 -293.52494) (xy 311.022908 -293.475886) (xy 311.034685 -293.428102)
			(xy 311.053976 -293.382826) (xy 311.080279 -293.34123) (xy 311.112914 -293.304393) (xy 311.151035 -293.273268)
			(xy 311.193656 -293.248661) (xy 311.239672 -293.231209) (xy 311.287891 -293.221365) (xy 311.337066 -293.219384)
			(xy 311.385921 -293.225316) (xy 311.433192 -293.239008) (xy 311.477654 -293.260106) (xy 311.518157 -293.288062)
			(xy 311.55365 -293.322154) (xy 311.583215 -293.361498) (xy 311.606086 -293.405075) (xy 311.62167 -293.451756)
			(xy 311.629565 -293.500333) (xy 311.63006 -293.52494) (xy 311.968908 -293.52494) (xy 311.972868 -293.475886)
			(xy 311.984645 -293.428102) (xy 312.003936 -293.382826) (xy 312.030239 -293.34123) (xy 312.062874 -293.304393)
			(xy 312.100995 -293.273268) (xy 312.143616 -293.248661) (xy 312.189632 -293.231209) (xy 312.237851 -293.221365)
			(xy 312.287026 -293.219384) (xy 312.335881 -293.225316) (xy 312.383152 -293.239008) (xy 312.427614 -293.260106)
			(xy 312.468117 -293.288062) (xy 312.50361 -293.322154) (xy 312.533175 -293.361498) (xy 312.556046 -293.405075)
			(xy 312.57163 -293.451756) (xy 312.579525 -293.500333) (xy 312.58002 -293.52494) (xy 312.919122 -293.52494)
			(xy 312.923082 -293.475886) (xy 312.934859 -293.428102) (xy 312.95415 -293.382826) (xy 312.980453 -293.34123)
			(xy 313.013088 -293.304393) (xy 313.051209 -293.273268) (xy 313.09383 -293.248661) (xy 313.139846 -293.231209)
			(xy 313.188065 -293.221365) (xy 313.23724 -293.219384) (xy 313.286095 -293.225316) (xy 313.333366 -293.239008)
			(xy 313.377828 -293.260106) (xy 313.418331 -293.288062) (xy 313.453824 -293.322154) (xy 313.483389 -293.361498)
			(xy 313.50626 -293.405075) (xy 313.521844 -293.451756) (xy 313.529739 -293.500333) (xy 313.530234 -293.52494)
			(xy 313.869082 -293.52494) (xy 313.873042 -293.475886) (xy 313.884819 -293.428102) (xy 313.90411 -293.382826)
			(xy 313.930413 -293.34123) (xy 313.963048 -293.304393) (xy 314.001169 -293.273268) (xy 314.04379 -293.248661)
			(xy 314.089806 -293.231209) (xy 314.138025 -293.221365) (xy 314.1872 -293.219384) (xy 314.236055 -293.225316)
			(xy 314.283326 -293.239008) (xy 314.327788 -293.260106) (xy 314.368291 -293.288062) (xy 314.403784 -293.322154)
			(xy 314.433349 -293.361498) (xy 314.45622 -293.405075) (xy 314.471804 -293.451756) (xy 314.479699 -293.500333)
			(xy 314.480194 -293.52494) (xy 314.819042 -293.52494) (xy 314.823002 -293.475886) (xy 314.834779 -293.428102)
			(xy 314.85407 -293.382826) (xy 314.880373 -293.34123) (xy 314.913008 -293.304393) (xy 314.951129 -293.273268)
			(xy 314.99375 -293.248661) (xy 315.039766 -293.231209) (xy 315.087985 -293.221365) (xy 315.13716 -293.219384)
			(xy 315.186015 -293.225316) (xy 315.233286 -293.239008) (xy 315.277748 -293.260106) (xy 315.318251 -293.288062)
			(xy 315.353744 -293.322154) (xy 315.383309 -293.361498) (xy 315.40618 -293.405075) (xy 315.421764 -293.451756)
			(xy 315.429659 -293.500333) (xy 315.430154 -293.52494) (xy 315.429659 -293.549547) (xy 315.421764 -293.598124)
			(xy 315.40618 -293.644805) (xy 315.383309 -293.688382) (xy 315.353744 -293.727726) (xy 315.318251 -293.761818)
			(xy 315.277748 -293.789774) (xy 315.233286 -293.810872) (xy 315.186015 -293.824564) (xy 315.13716 -293.830496)
			(xy 315.087985 -293.828515) (xy 315.039766 -293.818671) (xy 314.99375 -293.801219) (xy 314.951129 -293.776612)
			(xy 314.913008 -293.745487) (xy 314.880373 -293.70865) (xy 314.85407 -293.667054) (xy 314.834779 -293.621778)
			(xy 314.823002 -293.573994) (xy 314.819042 -293.52494) (xy 314.480194 -293.52494) (xy 314.479699 -293.549547)
			(xy 314.471804 -293.598124) (xy 314.45622 -293.644805) (xy 314.433349 -293.688382) (xy 314.403784 -293.727726)
			(xy 314.368291 -293.761818) (xy 314.327788 -293.789774) (xy 314.283326 -293.810872) (xy 314.236055 -293.824564)
			(xy 314.1872 -293.830496) (xy 314.138025 -293.828515) (xy 314.089806 -293.818671) (xy 314.04379 -293.801219)
			(xy 314.001169 -293.776612) (xy 313.963048 -293.745487) (xy 313.930413 -293.70865) (xy 313.90411 -293.667054)
			(xy 313.884819 -293.621778) (xy 313.873042 -293.573994) (xy 313.869082 -293.52494) (xy 313.530234 -293.52494)
			(xy 313.529739 -293.549547) (xy 313.521844 -293.598124) (xy 313.50626 -293.644805) (xy 313.483389 -293.688382)
			(xy 313.453824 -293.727726) (xy 313.418331 -293.761818) (xy 313.377828 -293.789774) (xy 313.333366 -293.810872)
			(xy 313.286095 -293.824564) (xy 313.23724 -293.830496) (xy 313.188065 -293.828515) (xy 313.139846 -293.818671)
			(xy 313.09383 -293.801219) (xy 313.051209 -293.776612) (xy 313.013088 -293.745487) (xy 312.980453 -293.70865)
			(xy 312.95415 -293.667054) (xy 312.934859 -293.621778) (xy 312.923082 -293.573994) (xy 312.919122 -293.52494)
			(xy 312.58002 -293.52494) (xy 312.579525 -293.549547) (xy 312.57163 -293.598124) (xy 312.556046 -293.644805)
			(xy 312.533175 -293.688382) (xy 312.50361 -293.727726) (xy 312.468117 -293.761818) (xy 312.427614 -293.789774)
			(xy 312.383152 -293.810872) (xy 312.335881 -293.824564) (xy 312.287026 -293.830496) (xy 312.237851 -293.828515)
			(xy 312.189632 -293.818671) (xy 312.143616 -293.801219) (xy 312.100995 -293.776612) (xy 312.062874 -293.745487)
			(xy 312.030239 -293.70865) (xy 312.003936 -293.667054) (xy 311.984645 -293.621778) (xy 311.972868 -293.573994)
			(xy 311.968908 -293.52494) (xy 311.63006 -293.52494) (xy 311.629565 -293.549547) (xy 311.62167 -293.598124)
			(xy 311.606086 -293.644805) (xy 311.583215 -293.688382) (xy 311.55365 -293.727726) (xy 311.518157 -293.761818)
			(xy 311.477654 -293.789774) (xy 311.433192 -293.810872) (xy 311.385921 -293.824564) (xy 311.337066 -293.830496)
			(xy 311.287891 -293.828515) (xy 311.239672 -293.818671) (xy 311.193656 -293.801219) (xy 311.151035 -293.776612)
			(xy 311.112914 -293.745487) (xy 311.080279 -293.70865) (xy 311.053976 -293.667054) (xy 311.034685 -293.621778)
			(xy 311.022908 -293.573994) (xy 311.018948 -293.52494) (xy 310.6801 -293.52494) (xy 310.679605 -293.549547)
			(xy 310.67171 -293.598124) (xy 310.656126 -293.644805) (xy 310.633255 -293.688382) (xy 310.60369 -293.727726)
			(xy 310.568197 -293.761818) (xy 310.527694 -293.789774) (xy 310.483232 -293.810872) (xy 310.435961 -293.824564)
			(xy 310.387106 -293.830496) (xy 310.337931 -293.828515) (xy 310.289712 -293.818671) (xy 310.243696 -293.801219)
			(xy 310.201075 -293.776612) (xy 310.162954 -293.745487) (xy 310.130319 -293.70865) (xy 310.104016 -293.667054)
			(xy 310.084725 -293.621778) (xy 310.072948 -293.573994) (xy 310.068988 -293.52494) (xy 309.73014 -293.52494)
			(xy 309.729645 -293.549547) (xy 309.72175 -293.598124) (xy 309.706166 -293.644805) (xy 309.683295 -293.688382)
			(xy 309.65373 -293.727726) (xy 309.618237 -293.761818) (xy 309.577734 -293.789774) (xy 309.533272 -293.810872)
			(xy 309.486001 -293.824564) (xy 309.437146 -293.830496) (xy 309.387971 -293.828515) (xy 309.339752 -293.818671)
			(xy 309.293736 -293.801219) (xy 309.251115 -293.776612) (xy 309.212994 -293.745487) (xy 309.180359 -293.70865)
			(xy 309.154056 -293.667054) (xy 309.134765 -293.621778) (xy 309.122988 -293.573994) (xy 309.119028 -293.52494)
			(xy 308.78018 -293.52494) (xy 308.779685 -293.549547) (xy 308.77179 -293.598124) (xy 308.756206 -293.644805)
			(xy 308.733335 -293.688382) (xy 308.70377 -293.727726) (xy 308.668277 -293.761818) (xy 308.627774 -293.789774)
			(xy 308.583312 -293.810872) (xy 308.536041 -293.824564) (xy 308.487186 -293.830496) (xy 308.438011 -293.828515)
			(xy 308.389792 -293.818671) (xy 308.343776 -293.801219) (xy 308.301155 -293.776612) (xy 308.263034 -293.745487)
			(xy 308.230399 -293.70865) (xy 308.204096 -293.667054) (xy 308.184805 -293.621778) (xy 308.173028 -293.573994)
			(xy 308.169068 -293.52494) (xy 307.83022 -293.52494) (xy 307.829725 -293.549547) (xy 307.82183 -293.598124)
			(xy 307.806246 -293.644805) (xy 307.783375 -293.688382) (xy 307.75381 -293.727726) (xy 307.718317 -293.761818)
			(xy 307.677814 -293.789774) (xy 307.633352 -293.810872) (xy 307.586081 -293.824564) (xy 307.537226 -293.830496)
			(xy 307.488051 -293.828515) (xy 307.439832 -293.818671) (xy 307.393816 -293.801219) (xy 307.351195 -293.776612)
			(xy 307.313074 -293.745487) (xy 307.280439 -293.70865) (xy 307.254136 -293.667054) (xy 307.234845 -293.621778)
			(xy 307.223068 -293.573994) (xy 307.219108 -293.52494) (xy 306.88026 -293.52494) (xy 306.879765 -293.549547)
			(xy 306.87187 -293.598124) (xy 306.856286 -293.644805) (xy 306.833415 -293.688382) (xy 306.80385 -293.727726)
			(xy 306.768357 -293.761818) (xy 306.727854 -293.789774) (xy 306.683392 -293.810872) (xy 306.636121 -293.824564)
			(xy 306.587266 -293.830496) (xy 306.538091 -293.828515) (xy 306.489872 -293.818671) (xy 306.443856 -293.801219)
			(xy 306.401235 -293.776612) (xy 306.363114 -293.745487) (xy 306.330479 -293.70865) (xy 306.304176 -293.667054)
			(xy 306.284885 -293.621778) (xy 306.273108 -293.573994) (xy 306.269148 -293.52494) (xy 305.930046 -293.52494)
			(xy 305.929551 -293.549547) (xy 305.921656 -293.598124) (xy 305.906072 -293.644805) (xy 305.883201 -293.688382)
			(xy 305.853636 -293.727726) (xy 305.818143 -293.761818) (xy 305.77764 -293.789774) (xy 305.733178 -293.810872)
			(xy 305.685907 -293.824564) (xy 305.637052 -293.830496) (xy 305.587877 -293.828515) (xy 305.539658 -293.818671)
			(xy 305.493642 -293.801219) (xy 305.451021 -293.776612) (xy 305.4129 -293.745487) (xy 305.380265 -293.70865)
			(xy 305.353962 -293.667054) (xy 305.334671 -293.621778) (xy 305.322894 -293.573994) (xy 305.318934 -293.52494)
			(xy 304.980086 -293.52494) (xy 304.979591 -293.549547) (xy 304.971696 -293.598124) (xy 304.956112 -293.644805)
			(xy 304.933241 -293.688382) (xy 304.903676 -293.727726) (xy 304.868183 -293.761818) (xy 304.82768 -293.789774)
			(xy 304.783218 -293.810872) (xy 304.735947 -293.824564) (xy 304.687092 -293.830496) (xy 304.637917 -293.828515)
			(xy 304.589698 -293.818671) (xy 304.543682 -293.801219) (xy 304.501061 -293.776612) (xy 304.46294 -293.745487)
			(xy 304.430305 -293.70865) (xy 304.404002 -293.667054) (xy 304.384711 -293.621778) (xy 304.372934 -293.573994)
			(xy 304.368974 -293.52494) (xy 304.030126 -293.52494) (xy 304.029631 -293.549547) (xy 304.021736 -293.598124)
			(xy 304.006152 -293.644805) (xy 303.983281 -293.688382) (xy 303.953716 -293.727726) (xy 303.918223 -293.761818)
			(xy 303.87772 -293.789774) (xy 303.833258 -293.810872) (xy 303.785987 -293.824564) (xy 303.737132 -293.830496)
			(xy 303.687957 -293.828515) (xy 303.639738 -293.818671) (xy 303.593722 -293.801219) (xy 303.551101 -293.776612)
			(xy 303.51298 -293.745487) (xy 303.480345 -293.70865) (xy 303.454042 -293.667054) (xy 303.434751 -293.621778)
			(xy 303.422974 -293.573994) (xy 303.419014 -293.52494) (xy 302.130206 -293.52494) (xy 302.129711 -293.549547)
			(xy 302.121816 -293.598124) (xy 302.106232 -293.644805) (xy 302.083361 -293.688382) (xy 302.053796 -293.727726)
			(xy 302.018303 -293.761818) (xy 301.9778 -293.789774) (xy 301.933338 -293.810872) (xy 301.886067 -293.824564)
			(xy 301.837212 -293.830496) (xy 301.788037 -293.828515) (xy 301.739818 -293.818671) (xy 301.693802 -293.801219)
			(xy 301.651181 -293.776612) (xy 301.61306 -293.745487) (xy 301.580425 -293.70865) (xy 301.554122 -293.667054)
			(xy 301.534831 -293.621778) (xy 301.523054 -293.573994) (xy 301.519094 -293.52494) (xy 301.179992 -293.52494)
			(xy 301.179497 -293.549547) (xy 301.171602 -293.598124) (xy 301.156018 -293.644805) (xy 301.133147 -293.688382)
			(xy 301.103582 -293.727726) (xy 301.068089 -293.761818) (xy 301.027586 -293.789774) (xy 300.983124 -293.810872)
			(xy 300.935853 -293.824564) (xy 300.886998 -293.830496) (xy 300.837823 -293.828515) (xy 300.789604 -293.818671)
			(xy 300.743588 -293.801219) (xy 300.700967 -293.776612) (xy 300.662846 -293.745487) (xy 300.630211 -293.70865)
			(xy 300.603908 -293.667054) (xy 300.584617 -293.621778) (xy 300.57284 -293.573994) (xy 300.56888 -293.52494)
			(xy 300.230032 -293.52494) (xy 300.229537 -293.549547) (xy 300.221642 -293.598124) (xy 300.206058 -293.644805)
			(xy 300.183187 -293.688382) (xy 300.153622 -293.727726) (xy 300.118129 -293.761818) (xy 300.077626 -293.789774)
			(xy 300.033164 -293.810872) (xy 299.985893 -293.824564) (xy 299.937038 -293.830496) (xy 299.887863 -293.828515)
			(xy 299.839644 -293.818671) (xy 299.793628 -293.801219) (xy 299.751007 -293.776612) (xy 299.712886 -293.745487)
			(xy 299.680251 -293.70865) (xy 299.653948 -293.667054) (xy 299.634657 -293.621778) (xy 299.62288 -293.573994)
			(xy 299.61892 -293.52494) (xy 299.280072 -293.52494) (xy 299.279577 -293.549547) (xy 299.271682 -293.598124)
			(xy 299.256098 -293.644805) (xy 299.233227 -293.688382) (xy 299.203662 -293.727726) (xy 299.168169 -293.761818)
			(xy 299.127666 -293.789774) (xy 299.083204 -293.810872) (xy 299.035933 -293.824564) (xy 298.987078 -293.830496)
			(xy 298.937903 -293.828515) (xy 298.889684 -293.818671) (xy 298.843668 -293.801219) (xy 298.801047 -293.776612)
			(xy 298.762926 -293.745487) (xy 298.730291 -293.70865) (xy 298.703988 -293.667054) (xy 298.684697 -293.621778)
			(xy 298.67292 -293.573994) (xy 298.66896 -293.52494) (xy 298.330112 -293.52494) (xy 298.329617 -293.549547)
			(xy 298.321722 -293.598124) (xy 298.306138 -293.644805) (xy 298.283267 -293.688382) (xy 298.253702 -293.727726)
			(xy 298.218209 -293.761818) (xy 298.177706 -293.789774) (xy 298.133244 -293.810872) (xy 298.085973 -293.824564)
			(xy 298.037118 -293.830496) (xy 297.987943 -293.828515) (xy 297.939724 -293.818671) (xy 297.893708 -293.801219)
			(xy 297.851087 -293.776612) (xy 297.812966 -293.745487) (xy 297.780331 -293.70865) (xy 297.754028 -293.667054)
			(xy 297.734737 -293.621778) (xy 297.72296 -293.573994) (xy 297.719 -293.52494) (xy 297.380152 -293.52494)
			(xy 297.379657 -293.549547) (xy 297.371762 -293.598124) (xy 297.356178 -293.644805) (xy 297.333307 -293.688382)
			(xy 297.303742 -293.727726) (xy 297.268249 -293.761818) (xy 297.227746 -293.789774) (xy 297.183284 -293.810872)
			(xy 297.136013 -293.824564) (xy 297.087158 -293.830496) (xy 297.037983 -293.828515) (xy 296.989764 -293.818671)
			(xy 296.943748 -293.801219) (xy 296.901127 -293.776612) (xy 296.863006 -293.745487) (xy 296.830371 -293.70865)
			(xy 296.804068 -293.667054) (xy 296.784777 -293.621778) (xy 296.773 -293.573994) (xy 296.76904 -293.52494)
			(xy 296.430192 -293.52494) (xy 296.429697 -293.549547) (xy 296.421802 -293.598124) (xy 296.406218 -293.644805)
			(xy 296.383347 -293.688382) (xy 296.353782 -293.727726) (xy 296.318289 -293.761818) (xy 296.277786 -293.789774)
			(xy 296.233324 -293.810872) (xy 296.186053 -293.824564) (xy 296.137198 -293.830496) (xy 296.088023 -293.828515)
			(xy 296.039804 -293.818671) (xy 295.993788 -293.801219) (xy 295.951167 -293.776612) (xy 295.913046 -293.745487)
			(xy 295.880411 -293.70865) (xy 295.854108 -293.667054) (xy 295.834817 -293.621778) (xy 295.82304 -293.573994)
			(xy 295.81908 -293.52494) (xy 295.480232 -293.52494) (xy 295.479737 -293.549547) (xy 295.471842 -293.598124)
			(xy 295.456258 -293.644805) (xy 295.433387 -293.688382) (xy 295.403822 -293.727726) (xy 295.368329 -293.761818)
			(xy 295.327826 -293.789774) (xy 295.283364 -293.810872) (xy 295.236093 -293.824564) (xy 295.187238 -293.830496)
			(xy 295.138063 -293.828515) (xy 295.089844 -293.818671) (xy 295.043828 -293.801219) (xy 295.001207 -293.776612)
			(xy 294.963086 -293.745487) (xy 294.930451 -293.70865) (xy 294.904148 -293.667054) (xy 294.884857 -293.621778)
			(xy 294.87308 -293.573994) (xy 294.86912 -293.52494) (xy 294.530018 -293.52494) (xy 294.529523 -293.549547)
			(xy 294.521628 -293.598124) (xy 294.506044 -293.644805) (xy 294.483173 -293.688382) (xy 294.453608 -293.727726)
			(xy 294.418115 -293.761818) (xy 294.377612 -293.789774) (xy 294.33315 -293.810872) (xy 294.285879 -293.824564)
			(xy 294.237024 -293.830496) (xy 294.187849 -293.828515) (xy 294.13963 -293.818671) (xy 294.093614 -293.801219)
			(xy 294.050993 -293.776612) (xy 294.012872 -293.745487) (xy 293.980237 -293.70865) (xy 293.953934 -293.667054)
			(xy 293.934643 -293.621778) (xy 293.922866 -293.573994) (xy 293.918906 -293.52494) (xy 293.580058 -293.52494)
			(xy 293.579563 -293.549547) (xy 293.571668 -293.598124) (xy 293.556084 -293.644805) (xy 293.533213 -293.688382)
			(xy 293.503648 -293.727726) (xy 293.468155 -293.761818) (xy 293.427652 -293.789774) (xy 293.38319 -293.810872)
			(xy 293.335919 -293.824564) (xy 293.287064 -293.830496) (xy 293.237889 -293.828515) (xy 293.18967 -293.818671)
			(xy 293.143654 -293.801219) (xy 293.101033 -293.776612) (xy 293.062912 -293.745487) (xy 293.030277 -293.70865)
			(xy 293.003974 -293.667054) (xy 292.984683 -293.621778) (xy 292.972906 -293.573994) (xy 292.968946 -293.52494)
			(xy 292.630098 -293.52494) (xy 292.629603 -293.549547) (xy 292.621708 -293.598124) (xy 292.606124 -293.644805)
			(xy 292.583253 -293.688382) (xy 292.553688 -293.727726) (xy 292.518195 -293.761818) (xy 292.477692 -293.789774)
			(xy 292.43323 -293.810872) (xy 292.385959 -293.824564) (xy 292.337104 -293.830496) (xy 292.287929 -293.828515)
			(xy 292.23971 -293.818671) (xy 292.193694 -293.801219) (xy 292.151073 -293.776612) (xy 292.112952 -293.745487)
			(xy 292.080317 -293.70865) (xy 292.054014 -293.667054) (xy 292.034723 -293.621778) (xy 292.022946 -293.573994)
			(xy 292.018986 -293.52494) (xy 290.730178 -293.52494) (xy 290.729683 -293.549547) (xy 290.721788 -293.598124)
			(xy 290.706204 -293.644805) (xy 290.683333 -293.688382) (xy 290.653768 -293.727726) (xy 290.618275 -293.761818)
			(xy 290.577772 -293.789774) (xy 290.53331 -293.810872) (xy 290.486039 -293.824564) (xy 290.437184 -293.830496)
			(xy 290.388009 -293.828515) (xy 290.33979 -293.818671) (xy 290.293774 -293.801219) (xy 290.251153 -293.776612)
			(xy 290.213032 -293.745487) (xy 290.180397 -293.70865) (xy 290.154094 -293.667054) (xy 290.134803 -293.621778)
			(xy 290.123026 -293.573994) (xy 290.119066 -293.52494) (xy 289.780218 -293.52494) (xy 289.779723 -293.549547)
			(xy 289.771828 -293.598124) (xy 289.756244 -293.644805) (xy 289.733373 -293.688382) (xy 289.703808 -293.727726)
			(xy 289.668315 -293.761818) (xy 289.627812 -293.789774) (xy 289.58335 -293.810872) (xy 289.536079 -293.824564)
			(xy 289.487224 -293.830496) (xy 289.438049 -293.828515) (xy 289.38983 -293.818671) (xy 289.343814 -293.801219)
			(xy 289.301193 -293.776612) (xy 289.263072 -293.745487) (xy 289.230437 -293.70865) (xy 289.204134 -293.667054)
			(xy 289.184843 -293.621778) (xy 289.173066 -293.573994) (xy 289.169106 -293.52494) (xy 288.830004 -293.52494)
			(xy 288.829509 -293.549547) (xy 288.821614 -293.598124) (xy 288.80603 -293.644805) (xy 288.783159 -293.688382)
			(xy 288.753594 -293.727726) (xy 288.718101 -293.761818) (xy 288.677598 -293.789774) (xy 288.633136 -293.810872)
			(xy 288.585865 -293.824564) (xy 288.53701 -293.830496) (xy 288.487835 -293.828515) (xy 288.439616 -293.818671)
			(xy 288.3936 -293.801219) (xy 288.350979 -293.776612) (xy 288.312858 -293.745487) (xy 288.280223 -293.70865)
			(xy 288.25392 -293.667054) (xy 288.234629 -293.621778) (xy 288.222852 -293.573994) (xy 288.218892 -293.52494)
			(xy 287.880044 -293.52494) (xy 287.879549 -293.549547) (xy 287.871654 -293.598124) (xy 287.85607 -293.644805)
			(xy 287.833199 -293.688382) (xy 287.803634 -293.727726) (xy 287.768141 -293.761818) (xy 287.727638 -293.789774)
			(xy 287.683176 -293.810872) (xy 287.635905 -293.824564) (xy 287.58705 -293.830496) (xy 287.537875 -293.828515)
			(xy 287.489656 -293.818671) (xy 287.44364 -293.801219) (xy 287.401019 -293.776612) (xy 287.362898 -293.745487)
			(xy 287.330263 -293.70865) (xy 287.30396 -293.667054) (xy 287.284669 -293.621778) (xy 287.272892 -293.573994)
			(xy 287.268932 -293.52494) (xy 286.930084 -293.52494) (xy 286.929589 -293.549547) (xy 286.921694 -293.598124)
			(xy 286.90611 -293.644805) (xy 286.883239 -293.688382) (xy 286.853674 -293.727726) (xy 286.818181 -293.761818)
			(xy 286.777678 -293.789774) (xy 286.733216 -293.810872) (xy 286.685945 -293.824564) (xy 286.63709 -293.830496)
			(xy 286.587915 -293.828515) (xy 286.539696 -293.818671) (xy 286.49368 -293.801219) (xy 286.451059 -293.776612)
			(xy 286.412938 -293.745487) (xy 286.380303 -293.70865) (xy 286.354 -293.667054) (xy 286.334709 -293.621778)
			(xy 286.322932 -293.573994) (xy 286.318972 -293.52494) (xy 285.980124 -293.52494) (xy 285.979629 -293.549547)
			(xy 285.971734 -293.598124) (xy 285.95615 -293.644805) (xy 285.933279 -293.688382) (xy 285.903714 -293.727726)
			(xy 285.868221 -293.761818) (xy 285.827718 -293.789774) (xy 285.783256 -293.810872) (xy 285.735985 -293.824564)
			(xy 285.68713 -293.830496) (xy 285.637955 -293.828515) (xy 285.589736 -293.818671) (xy 285.54372 -293.801219)
			(xy 285.501099 -293.776612) (xy 285.462978 -293.745487) (xy 285.430343 -293.70865) (xy 285.40404 -293.667054)
			(xy 285.384749 -293.621778) (xy 285.372972 -293.573994) (xy 285.369012 -293.52494) (xy 285.030164 -293.52494)
			(xy 285.029669 -293.549547) (xy 285.021774 -293.598124) (xy 285.00619 -293.644805) (xy 284.983319 -293.688382)
			(xy 284.953754 -293.727726) (xy 284.918261 -293.761818) (xy 284.877758 -293.789774) (xy 284.833296 -293.810872)
			(xy 284.786025 -293.824564) (xy 284.73717 -293.830496) (xy 284.687995 -293.828515) (xy 284.639776 -293.818671)
			(xy 284.59376 -293.801219) (xy 284.551139 -293.776612) (xy 284.513018 -293.745487) (xy 284.480383 -293.70865)
			(xy 284.45408 -293.667054) (xy 284.434789 -293.621778) (xy 284.423012 -293.573994) (xy 284.419052 -293.52494)
			(xy 284.080204 -293.52494) (xy 284.079709 -293.549547) (xy 284.071814 -293.598124) (xy 284.05623 -293.644805)
			(xy 284.033359 -293.688382) (xy 284.003794 -293.727726) (xy 283.968301 -293.761818) (xy 283.927798 -293.789774)
			(xy 283.883336 -293.810872) (xy 283.836065 -293.824564) (xy 283.78721 -293.830496) (xy 283.738035 -293.828515)
			(xy 283.689816 -293.818671) (xy 283.6438 -293.801219) (xy 283.601179 -293.776612) (xy 283.563058 -293.745487)
			(xy 283.530423 -293.70865) (xy 283.50412 -293.667054) (xy 283.484829 -293.621778) (xy 283.473052 -293.573994)
			(xy 283.469092 -293.52494) (xy 283.130244 -293.52494) (xy 283.129749 -293.549547) (xy 283.121854 -293.598124)
			(xy 283.10627 -293.644805) (xy 283.083399 -293.688382) (xy 283.053834 -293.727726) (xy 283.018341 -293.761818)
			(xy 282.977838 -293.789774) (xy 282.933376 -293.810872) (xy 282.886105 -293.824564) (xy 282.83725 -293.830496)
			(xy 282.788075 -293.828515) (xy 282.739856 -293.818671) (xy 282.69384 -293.801219) (xy 282.651219 -293.776612)
			(xy 282.613098 -293.745487) (xy 282.580463 -293.70865) (xy 282.55416 -293.667054) (xy 282.534869 -293.621778)
			(xy 282.523092 -293.573994) (xy 282.519132 -293.52494) (xy 282.18003 -293.52494) (xy 282.179535 -293.549547)
			(xy 282.17164 -293.598124) (xy 282.156056 -293.644805) (xy 282.133185 -293.688382) (xy 282.10362 -293.727726)
			(xy 282.068127 -293.761818) (xy 282.027624 -293.789774) (xy 281.983162 -293.810872) (xy 281.935891 -293.824564)
			(xy 281.887036 -293.830496) (xy 281.837861 -293.828515) (xy 281.789642 -293.818671) (xy 281.743626 -293.801219)
			(xy 281.701005 -293.776612) (xy 281.662884 -293.745487) (xy 281.630249 -293.70865) (xy 281.603946 -293.667054)
			(xy 281.584655 -293.621778) (xy 281.572878 -293.573994) (xy 281.568918 -293.52494) (xy 281.23007 -293.52494)
			(xy 281.229575 -293.549547) (xy 281.22168 -293.598124) (xy 281.206096 -293.644805) (xy 281.183225 -293.688382)
			(xy 281.15366 -293.727726) (xy 281.118167 -293.761818) (xy 281.077664 -293.789774) (xy 281.033202 -293.810872)
			(xy 280.985931 -293.824564) (xy 280.937076 -293.830496) (xy 280.887901 -293.828515) (xy 280.839682 -293.818671)
			(xy 280.793666 -293.801219) (xy 280.751045 -293.776612) (xy 280.712924 -293.745487) (xy 280.680289 -293.70865)
			(xy 280.653986 -293.667054) (xy 280.634695 -293.621778) (xy 280.622918 -293.573994) (xy 280.618958 -293.52494)
			(xy 280.28011 -293.52494) (xy 280.279615 -293.549547) (xy 280.27172 -293.598124) (xy 280.256136 -293.644805)
			(xy 280.233265 -293.688382) (xy 280.2037 -293.727726) (xy 280.168207 -293.761818) (xy 280.127704 -293.789774)
			(xy 280.083242 -293.810872) (xy 280.035971 -293.824564) (xy 279.987116 -293.830496) (xy 279.937941 -293.828515)
			(xy 279.889722 -293.818671) (xy 279.843706 -293.801219) (xy 279.801085 -293.776612) (xy 279.762964 -293.745487)
			(xy 279.730329 -293.70865) (xy 279.704026 -293.667054) (xy 279.684735 -293.621778) (xy 279.672958 -293.573994)
			(xy 279.668998 -293.52494) (xy 278.38019 -293.52494) (xy 278.379695 -293.549547) (xy 278.3718 -293.598124)
			(xy 278.356216 -293.644805) (xy 278.333345 -293.688382) (xy 278.30378 -293.727726) (xy 278.268287 -293.761818)
			(xy 278.227784 -293.789774) (xy 278.183322 -293.810872) (xy 278.136051 -293.824564) (xy 278.087196 -293.830496)
			(xy 278.038021 -293.828515) (xy 277.989802 -293.818671) (xy 277.943786 -293.801219) (xy 277.901165 -293.776612)
			(xy 277.863044 -293.745487) (xy 277.830409 -293.70865) (xy 277.804106 -293.667054) (xy 277.784815 -293.621778)
			(xy 277.773038 -293.573994) (xy 277.769078 -293.52494) (xy 276.480016 -293.52494) (xy 276.479521 -293.549547)
			(xy 276.471626 -293.598124) (xy 276.456042 -293.644805) (xy 276.433171 -293.688382) (xy 276.403606 -293.727726)
			(xy 276.368113 -293.761818) (xy 276.32761 -293.789774) (xy 276.283148 -293.810872) (xy 276.235877 -293.824564)
			(xy 276.187022 -293.830496) (xy 276.137847 -293.828515) (xy 276.089628 -293.818671) (xy 276.043612 -293.801219)
			(xy 276.000991 -293.776612) (xy 275.96287 -293.745487) (xy 275.930235 -293.70865) (xy 275.903932 -293.667054)
			(xy 275.884641 -293.621778) (xy 275.872864 -293.573994) (xy 275.868904 -293.52494) (xy 275.580856 -293.52494)
			(xy 275.580358 -293.551589) (xy 275.572415 -293.604293) (xy 275.556705 -293.655223) (xy 275.533579 -293.703244)
			(xy 275.503555 -293.747281) (xy 275.467303 -293.786352) (xy 275.425632 -293.819583) (xy 275.379474 -293.846232)
			(xy 275.32986 -293.865704) (xy 275.277898 -293.877564) (xy 275.224748 -293.881548) (xy 275.171598 -293.877564)
			(xy 275.119636 -293.865704) (xy 275.070022 -293.846232) (xy 275.023864 -293.819583) (xy 274.982193 -293.786352)
			(xy 274.945941 -293.747281) (xy 274.915917 -293.703244) (xy 274.892791 -293.655223) (xy 274.877081 -293.604293)
			(xy 274.869138 -293.551589) (xy 274.579269 -293.551589) (xy 274.571706 -293.598124) (xy 274.556122 -293.644805)
			(xy 274.533251 -293.688382) (xy 274.503686 -293.727726) (xy 274.468193 -293.761818) (xy 274.42769 -293.789774)
			(xy 274.383228 -293.810872) (xy 274.335957 -293.824564) (xy 274.287102 -293.830496) (xy 274.237927 -293.828515)
			(xy 274.189708 -293.818671) (xy 274.143692 -293.801219) (xy 274.101071 -293.776612) (xy 274.06295 -293.745487)
			(xy 274.030315 -293.70865) (xy 274.004012 -293.667054) (xy 273.984721 -293.621778) (xy 273.972944 -293.573994)
			(xy 273.968984 -293.52494) (xy 273.630136 -293.52494) (xy 273.629641 -293.549547) (xy 273.621746 -293.598124)
			(xy 273.606162 -293.644805) (xy 273.583291 -293.688382) (xy 273.553726 -293.727726) (xy 273.518233 -293.761818)
			(xy 273.47773 -293.789774) (xy 273.433268 -293.810872) (xy 273.385997 -293.824564) (xy 273.337142 -293.830496)
			(xy 273.287967 -293.828515) (xy 273.239748 -293.818671) (xy 273.193732 -293.801219) (xy 273.151111 -293.776612)
			(xy 273.11299 -293.745487) (xy 273.080355 -293.70865) (xy 273.054052 -293.667054) (xy 273.034761 -293.621778)
			(xy 273.022984 -293.573994) (xy 273.019024 -293.52494) (xy 272.680176 -293.52494) (xy 272.679681 -293.549547)
			(xy 272.671786 -293.598124) (xy 272.656202 -293.644805) (xy 272.633331 -293.688382) (xy 272.603766 -293.727726)
			(xy 272.568273 -293.761818) (xy 272.52777 -293.789774) (xy 272.483308 -293.810872) (xy 272.436037 -293.824564)
			(xy 272.387182 -293.830496) (xy 272.338007 -293.828515) (xy 272.289788 -293.818671) (xy 272.243772 -293.801219)
			(xy 272.201151 -293.776612) (xy 272.16303 -293.745487) (xy 272.130395 -293.70865) (xy 272.104092 -293.667054)
			(xy 272.084801 -293.621778) (xy 272.073024 -293.573994) (xy 272.069064 -293.52494) (xy 271.730216 -293.52494)
			(xy 271.729721 -293.549547) (xy 271.721826 -293.598124) (xy 271.706242 -293.644805) (xy 271.683371 -293.688382)
			(xy 271.653806 -293.727726) (xy 271.618313 -293.761818) (xy 271.57781 -293.789774) (xy 271.533348 -293.810872)
			(xy 271.486077 -293.824564) (xy 271.437222 -293.830496) (xy 271.388047 -293.828515) (xy 271.339828 -293.818671)
			(xy 271.293812 -293.801219) (xy 271.251191 -293.776612) (xy 271.21307 -293.745487) (xy 271.180435 -293.70865)
			(xy 271.154132 -293.667054) (xy 271.134841 -293.621778) (xy 271.123064 -293.573994) (xy 271.119104 -293.52494)
			(xy 270.780256 -293.52494) (xy 270.779761 -293.549547) (xy 270.771866 -293.598124) (xy 270.756282 -293.644805)
			(xy 270.733411 -293.688382) (xy 270.703846 -293.727726) (xy 270.668353 -293.761818) (xy 270.62785 -293.789774)
			(xy 270.583388 -293.810872) (xy 270.536117 -293.824564) (xy 270.487262 -293.830496) (xy 270.438087 -293.828515)
			(xy 270.389868 -293.818671) (xy 270.343852 -293.801219) (xy 270.301231 -293.776612) (xy 270.26311 -293.745487)
			(xy 270.230475 -293.70865) (xy 270.204172 -293.667054) (xy 270.184881 -293.621778) (xy 270.173104 -293.573994)
			(xy 270.169144 -293.52494) (xy 266.583577 -293.52494) (xy 266.575801 -293.577776) (xy 266.559733 -293.631183)
			(xy 266.536061 -293.68168) (xy 266.505288 -293.728193) (xy 266.468071 -293.76973) (xy 266.425203 -293.805405)
			(xy 266.377597 -293.834459) (xy 266.326268 -293.856271) (xy 266.272311 -293.870377) (xy 266.216874 -293.876477)
			(xy 266.16114 -293.87444) (xy 266.106297 -293.86431) (xy 266.053513 -293.846303) (xy 266.003913 -293.820802)
			(xy 265.958555 -293.788351) (xy 265.918406 -293.749642) (xy 265.88432 -293.705499) (xy 265.857024 -293.656864)
			(xy 265.837101 -293.604773) (xy 265.824975 -293.550336) (xy 265.820904 -293.494714) (xy 265.69797 -293.494714)
			(xy 265.697461 -293.5226) (xy 265.689341 -293.577776) (xy 265.673273 -293.631183) (xy 265.649601 -293.68168)
			(xy 265.618828 -293.728193) (xy 265.581611 -293.76973) (xy 265.538743 -293.805405) (xy 265.491137 -293.834459)
			(xy 265.439808 -293.856271) (xy 265.385851 -293.870377) (xy 265.330414 -293.876477) (xy 265.27468 -293.87444)
			(xy 265.219837 -293.86431) (xy 265.167053 -293.846303) (xy 265.117453 -293.820802) (xy 265.072095 -293.788351)
			(xy 265.031946 -293.749642) (xy 264.99786 -293.705499) (xy 264.970564 -293.656864) (xy 264.950641 -293.604773)
			(xy 264.938515 -293.550336) (xy 264.934444 -293.494714) (xy 264.30097 -293.494714) (xy 264.300484 -293.521965)
			(xy 264.292728 -293.575913) (xy 264.277373 -293.628208) (xy 264.254731 -293.677785) (xy 264.225265 -293.723635)
			(xy 264.189574 -293.764826) (xy 264.148383 -293.800517) (xy 264.102533 -293.829983) (xy 264.052956 -293.852625)
			(xy 264.000661 -293.86798) (xy 263.946713 -293.875736) (xy 263.892211 -293.875736) (xy 263.838263 -293.86798)
			(xy 263.785968 -293.852625) (xy 263.736391 -293.829983) (xy 263.690541 -293.800517) (xy 263.64935 -293.764826)
			(xy 263.613659 -293.723635) (xy 263.584193 -293.677785) (xy 263.561551 -293.628208) (xy 263.546196 -293.575913)
			(xy 263.53844 -293.521965) (xy 263.537954 -293.494714) (xy 234.5309 -293.494714) (xy 234.5309 -297.369992)
			(xy 248.970807 -297.369992) (xy 248.974815 -297.205466) (xy 248.986828 -297.041331) (xy 249.006818 -296.877975)
			(xy 249.034738 -296.715786) (xy 249.070521 -296.555149) (xy 249.114083 -296.396445) (xy 249.165321 -296.24005)
			(xy 249.224112 -296.086335) (xy 249.290317 -295.935664) (xy 249.36378 -295.788396) (xy 249.444325 -295.644879)
			(xy 249.531763 -295.505453) (xy 249.625885 -295.370451) (xy 249.726469 -295.240191) (xy 249.833275 -295.114982)
			(xy 249.946051 -294.995122) (xy 250.064529 -294.880896) (xy 250.188427 -294.772573) (xy 250.317453 -294.67041)
			(xy 250.451299 -294.574651) (xy 250.58965 -294.485523) (xy 250.732175 -294.403235) (xy 250.878538 -294.327985)
			(xy 251.028391 -294.25995) (xy 251.181379 -294.199291) (xy 251.337139 -294.146154) (xy 251.495301 -294.100662)
			(xy 251.655491 -294.062926) (xy 251.817328 -294.033033) (xy 251.980428 -294.011055) (xy 252.144405 -293.997044)
			(xy 252.308869 -293.991034) (xy 252.473432 -293.993037) (xy 252.637701 -294.003051) (xy 252.801288 -294.021051)
			(xy 252.963805 -294.046994) (xy 253.124866 -294.080819) (xy 253.284089 -294.122445) (xy 253.441096 -294.171774)
			(xy 253.595516 -294.228689) (xy 253.746981 -294.293055) (xy 253.895133 -294.364719) (xy 254.039621 -294.443511)
			(xy 254.1801 -294.529245) (xy 254.316239 -294.621716) (xy 254.328378 -294.630856) (xy 258.01142 -294.630856)
			(xy 258.015491 -294.575234) (xy 258.027617 -294.520797) (xy 258.04754 -294.468706) (xy 258.074836 -294.420071)
			(xy 258.108922 -294.375928) (xy 258.149071 -294.337219) (xy 258.194429 -294.304768) (xy 258.244029 -294.279267)
			(xy 258.296813 -294.26126) (xy 258.351656 -294.25113) (xy 258.40739 -294.249093) (xy 258.462827 -294.255193)
			(xy 258.516784 -294.269299) (xy 258.568113 -294.291111) (xy 258.615719 -294.320165) (xy 258.658587 -294.35584)
			(xy 258.695804 -294.397377) (xy 258.726577 -294.44389) (xy 258.750249 -294.494387) (xy 258.766317 -294.547794)
			(xy 258.774437 -294.60297) (xy 258.774946 -294.630856) (xy 259.496558 -294.630856) (xy 259.500629 -294.575234)
			(xy 259.512755 -294.520797) (xy 259.532678 -294.468706) (xy 259.559974 -294.420071) (xy 259.59406 -294.375928)
			(xy 259.634209 -294.337219) (xy 259.679567 -294.304768) (xy 259.729167 -294.279267) (xy 259.781951 -294.26126)
			(xy 259.836794 -294.25113) (xy 259.892528 -294.249093) (xy 259.947965 -294.255193) (xy 260.001922 -294.269299)
			(xy 260.053251 -294.291111) (xy 260.100857 -294.320165) (xy 260.143725 -294.35584) (xy 260.180942 -294.397377)
			(xy 260.211715 -294.44389) (xy 260.226252 -294.4749) (xy 268.26897 -294.4749) (xy 268.27293 -294.425846)
			(xy 268.284707 -294.378062) (xy 268.303998 -294.332786) (xy 268.330301 -294.29119) (xy 268.362936 -294.254353)
			(xy 268.401057 -294.223228) (xy 268.443678 -294.198621) (xy 268.489694 -294.181169) (xy 268.537913 -294.171325)
			(xy 268.587088 -294.169344) (xy 268.635943 -294.175276) (xy 268.683214 -294.188968) (xy 268.727676 -294.210066)
			(xy 268.768179 -294.238022) (xy 268.803672 -294.272114) (xy 268.833237 -294.311458) (xy 268.856108 -294.355035)
			(xy 268.871692 -294.401716) (xy 268.879587 -294.450293) (xy 268.880082 -294.4749) (xy 269.21893 -294.4749)
			(xy 269.22289 -294.425846) (xy 269.234667 -294.378062) (xy 269.253958 -294.332786) (xy 269.280261 -294.29119)
			(xy 269.312896 -294.254353) (xy 269.351017 -294.223228) (xy 269.393638 -294.198621) (xy 269.439654 -294.181169)
			(xy 269.487873 -294.171325) (xy 269.537048 -294.169344) (xy 269.585903 -294.175276) (xy 269.633174 -294.188968)
			(xy 269.677636 -294.210066) (xy 269.718139 -294.238022) (xy 269.753632 -294.272114) (xy 269.783197 -294.311458)
			(xy 269.806068 -294.355035) (xy 269.821652 -294.401716) (xy 269.829547 -294.450293) (xy 269.830042 -294.4749)
			(xy 270.169144 -294.4749) (xy 270.173104 -294.425846) (xy 270.184881 -294.378062) (xy 270.204172 -294.332786)
			(xy 270.230475 -294.29119) (xy 270.26311 -294.254353) (xy 270.301231 -294.223228) (xy 270.343852 -294.198621)
			(xy 270.389868 -294.181169) (xy 270.438087 -294.171325) (xy 270.487262 -294.169344) (xy 270.536117 -294.175276)
			(xy 270.583388 -294.188968) (xy 270.62785 -294.210066) (xy 270.668353 -294.238022) (xy 270.703846 -294.272114)
			(xy 270.733411 -294.311458) (xy 270.756282 -294.355035) (xy 270.771866 -294.401716) (xy 270.779761 -294.450293)
			(xy 270.780256 -294.4749) (xy 273.019024 -294.4749) (xy 273.022984 -294.425846) (xy 273.034761 -294.378062)
			(xy 273.054052 -294.332786) (xy 273.080355 -294.29119) (xy 273.11299 -294.254353) (xy 273.151111 -294.223228)
			(xy 273.193732 -294.198621) (xy 273.239748 -294.181169) (xy 273.287967 -294.171325) (xy 273.337142 -294.169344)
			(xy 273.385997 -294.175276) (xy 273.433268 -294.188968) (xy 273.47773 -294.210066) (xy 273.518233 -294.238022)
			(xy 273.553726 -294.272114) (xy 273.583291 -294.311458) (xy 273.606162 -294.355035) (xy 273.621746 -294.401716)
			(xy 273.629641 -294.450293) (xy 273.630136 -294.4749) (xy 273.629641 -294.499507) (xy 273.629309 -294.501549)
			(xy 273.919178 -294.501549) (xy 273.919178 -294.448251) (xy 273.927121 -294.395547) (xy 273.942831 -294.344617)
			(xy 273.965957 -294.296596) (xy 273.995981 -294.252559) (xy 274.032233 -294.213488) (xy 274.073904 -294.180257)
			(xy 274.120062 -294.153608) (xy 274.169676 -294.134136) (xy 274.221638 -294.122276) (xy 274.274788 -294.118293)
			(xy 274.327938 -294.122276) (xy 274.3799 -294.134136) (xy 274.429514 -294.153608) (xy 274.475672 -294.180257)
			(xy 274.517343 -294.213488) (xy 274.553595 -294.252559) (xy 274.583619 -294.296596) (xy 274.606745 -294.344617)
			(xy 274.622455 -294.395547) (xy 274.630398 -294.448251) (xy 274.630896 -294.4749) (xy 274.918944 -294.4749)
			(xy 274.922904 -294.425846) (xy 274.934681 -294.378062) (xy 274.953972 -294.332786) (xy 274.980275 -294.29119)
			(xy 275.01291 -294.254353) (xy 275.051031 -294.223228) (xy 275.093652 -294.198621) (xy 275.139668 -294.181169)
			(xy 275.187887 -294.171325) (xy 275.237062 -294.169344) (xy 275.285917 -294.175276) (xy 275.333188 -294.188968)
			(xy 275.37765 -294.210066) (xy 275.418153 -294.238022) (xy 275.453646 -294.272114) (xy 275.483211 -294.311458)
			(xy 275.506082 -294.355035) (xy 275.521666 -294.401716) (xy 275.529561 -294.450293) (xy 275.530056 -294.4749)
			(xy 275.868904 -294.4749) (xy 275.872864 -294.425846) (xy 275.884641 -294.378062) (xy 275.903932 -294.332786)
			(xy 275.930235 -294.29119) (xy 275.96287 -294.254353) (xy 276.000991 -294.223228) (xy 276.043612 -294.198621)
			(xy 276.089628 -294.181169) (xy 276.137847 -294.171325) (xy 276.187022 -294.169344) (xy 276.235877 -294.175276)
			(xy 276.283148 -294.188968) (xy 276.32761 -294.210066) (xy 276.368113 -294.238022) (xy 276.403606 -294.272114)
			(xy 276.433171 -294.311458) (xy 276.456042 -294.355035) (xy 276.471626 -294.401716) (xy 276.479521 -294.450293)
			(xy 276.480016 -294.4749) (xy 276.819118 -294.4749) (xy 276.823078 -294.425846) (xy 276.834855 -294.378062)
			(xy 276.854146 -294.332786) (xy 276.880449 -294.29119) (xy 276.913084 -294.254353) (xy 276.951205 -294.223228)
			(xy 276.993826 -294.198621) (xy 277.039842 -294.181169) (xy 277.088061 -294.171325) (xy 277.137236 -294.169344)
			(xy 277.186091 -294.175276) (xy 277.233362 -294.188968) (xy 277.277824 -294.210066) (xy 277.318327 -294.238022)
			(xy 277.35382 -294.272114) (xy 277.383385 -294.311458) (xy 277.406256 -294.355035) (xy 277.42184 -294.401716)
			(xy 277.429735 -294.450293) (xy 277.43023 -294.4749) (xy 277.769078 -294.4749) (xy 277.773038 -294.425846)
			(xy 277.784815 -294.378062) (xy 277.804106 -294.332786) (xy 277.830409 -294.29119) (xy 277.863044 -294.254353)
			(xy 277.901165 -294.223228) (xy 277.943786 -294.198621) (xy 277.989802 -294.181169) (xy 278.038021 -294.171325)
			(xy 278.087196 -294.169344) (xy 278.136051 -294.175276) (xy 278.183322 -294.188968) (xy 278.227784 -294.210066)
			(xy 278.268287 -294.238022) (xy 278.30378 -294.272114) (xy 278.333345 -294.311458) (xy 278.356216 -294.355035)
			(xy 278.3718 -294.401716) (xy 278.379695 -294.450293) (xy 278.38019 -294.4749) (xy 278.719038 -294.4749)
			(xy 278.722998 -294.425846) (xy 278.734775 -294.378062) (xy 278.754066 -294.332786) (xy 278.780369 -294.29119)
			(xy 278.813004 -294.254353) (xy 278.851125 -294.223228) (xy 278.893746 -294.198621) (xy 278.939762 -294.181169)
			(xy 278.987981 -294.171325) (xy 279.037156 -294.169344) (xy 279.086011 -294.175276) (xy 279.133282 -294.188968)
			(xy 279.177744 -294.210066) (xy 279.218247 -294.238022) (xy 279.25374 -294.272114) (xy 279.283305 -294.311458)
			(xy 279.306176 -294.355035) (xy 279.32176 -294.401716) (xy 279.329655 -294.450293) (xy 279.33015 -294.4749)
			(xy 279.668998 -294.4749) (xy 279.672958 -294.425846) (xy 279.684735 -294.378062) (xy 279.704026 -294.332786)
			(xy 279.730329 -294.29119) (xy 279.762964 -294.254353) (xy 279.801085 -294.223228) (xy 279.843706 -294.198621)
			(xy 279.889722 -294.181169) (xy 279.937941 -294.171325) (xy 279.987116 -294.169344) (xy 280.035971 -294.175276)
			(xy 280.083242 -294.188968) (xy 280.127704 -294.210066) (xy 280.168207 -294.238022) (xy 280.2037 -294.272114)
			(xy 280.233265 -294.311458) (xy 280.256136 -294.355035) (xy 280.27172 -294.401716) (xy 280.279615 -294.450293)
			(xy 280.28011 -294.4749) (xy 280.618958 -294.4749) (xy 280.622918 -294.425846) (xy 280.634695 -294.378062)
			(xy 280.653986 -294.332786) (xy 280.680289 -294.29119) (xy 280.712924 -294.254353) (xy 280.751045 -294.223228)
			(xy 280.793666 -294.198621) (xy 280.839682 -294.181169) (xy 280.887901 -294.171325) (xy 280.937076 -294.169344)
			(xy 280.985931 -294.175276) (xy 281.033202 -294.188968) (xy 281.077664 -294.210066) (xy 281.118167 -294.238022)
			(xy 281.15366 -294.272114) (xy 281.183225 -294.311458) (xy 281.206096 -294.355035) (xy 281.22168 -294.401716)
			(xy 281.229575 -294.450293) (xy 281.23007 -294.4749) (xy 281.568918 -294.4749) (xy 281.572878 -294.425846)
			(xy 281.584655 -294.378062) (xy 281.603946 -294.332786) (xy 281.630249 -294.29119) (xy 281.662884 -294.254353)
			(xy 281.701005 -294.223228) (xy 281.743626 -294.198621) (xy 281.789642 -294.181169) (xy 281.837861 -294.171325)
			(xy 281.887036 -294.169344) (xy 281.935891 -294.175276) (xy 281.983162 -294.188968) (xy 282.027624 -294.210066)
			(xy 282.068127 -294.238022) (xy 282.10362 -294.272114) (xy 282.133185 -294.311458) (xy 282.156056 -294.355035)
			(xy 282.17164 -294.401716) (xy 282.179535 -294.450293) (xy 282.18003 -294.4749) (xy 282.519132 -294.4749)
			(xy 282.523092 -294.425846) (xy 282.534869 -294.378062) (xy 282.55416 -294.332786) (xy 282.580463 -294.29119)
			(xy 282.613098 -294.254353) (xy 282.651219 -294.223228) (xy 282.69384 -294.198621) (xy 282.739856 -294.181169)
			(xy 282.788075 -294.171325) (xy 282.83725 -294.169344) (xy 282.886105 -294.175276) (xy 282.933376 -294.188968)
			(xy 282.977838 -294.210066) (xy 283.018341 -294.238022) (xy 283.053834 -294.272114) (xy 283.083399 -294.311458)
			(xy 283.10627 -294.355035) (xy 283.121854 -294.401716) (xy 283.129749 -294.450293) (xy 283.130244 -294.4749)
			(xy 283.469092 -294.4749) (xy 283.473052 -294.425846) (xy 283.484829 -294.378062) (xy 283.50412 -294.332786)
			(xy 283.530423 -294.29119) (xy 283.563058 -294.254353) (xy 283.601179 -294.223228) (xy 283.6438 -294.198621)
			(xy 283.689816 -294.181169) (xy 283.738035 -294.171325) (xy 283.78721 -294.169344) (xy 283.836065 -294.175276)
			(xy 283.883336 -294.188968) (xy 283.927798 -294.210066) (xy 283.968301 -294.238022) (xy 284.003794 -294.272114)
			(xy 284.033359 -294.311458) (xy 284.05623 -294.355035) (xy 284.071814 -294.401716) (xy 284.079709 -294.450293)
			(xy 284.080204 -294.4749) (xy 284.419052 -294.4749) (xy 284.423012 -294.425846) (xy 284.434789 -294.378062)
			(xy 284.45408 -294.332786) (xy 284.480383 -294.29119) (xy 284.513018 -294.254353) (xy 284.551139 -294.223228)
			(xy 284.59376 -294.198621) (xy 284.639776 -294.181169) (xy 284.687995 -294.171325) (xy 284.73717 -294.169344)
			(xy 284.786025 -294.175276) (xy 284.833296 -294.188968) (xy 284.877758 -294.210066) (xy 284.918261 -294.238022)
			(xy 284.953754 -294.272114) (xy 284.983319 -294.311458) (xy 285.00619 -294.355035) (xy 285.021774 -294.401716)
			(xy 285.029669 -294.450293) (xy 285.030164 -294.4749) (xy 285.369012 -294.4749) (xy 285.372972 -294.425846)
			(xy 285.384749 -294.378062) (xy 285.40404 -294.332786) (xy 285.430343 -294.29119) (xy 285.462978 -294.254353)
			(xy 285.501099 -294.223228) (xy 285.54372 -294.198621) (xy 285.589736 -294.181169) (xy 285.637955 -294.171325)
			(xy 285.68713 -294.169344) (xy 285.735985 -294.175276) (xy 285.783256 -294.188968) (xy 285.827718 -294.210066)
			(xy 285.868221 -294.238022) (xy 285.903714 -294.272114) (xy 285.933279 -294.311458) (xy 285.95615 -294.355035)
			(xy 285.971734 -294.401716) (xy 285.979629 -294.450293) (xy 285.980124 -294.4749) (xy 286.318972 -294.4749)
			(xy 286.322932 -294.425846) (xy 286.334709 -294.378062) (xy 286.354 -294.332786) (xy 286.380303 -294.29119)
			(xy 286.412938 -294.254353) (xy 286.451059 -294.223228) (xy 286.49368 -294.198621) (xy 286.539696 -294.181169)
			(xy 286.587915 -294.171325) (xy 286.63709 -294.169344) (xy 286.685945 -294.175276) (xy 286.733216 -294.188968)
			(xy 286.777678 -294.210066) (xy 286.818181 -294.238022) (xy 286.853674 -294.272114) (xy 286.883239 -294.311458)
			(xy 286.90611 -294.355035) (xy 286.921694 -294.401716) (xy 286.929589 -294.450293) (xy 286.930084 -294.4749)
			(xy 287.268932 -294.4749) (xy 287.272892 -294.425846) (xy 287.284669 -294.378062) (xy 287.30396 -294.332786)
			(xy 287.330263 -294.29119) (xy 287.362898 -294.254353) (xy 287.401019 -294.223228) (xy 287.44364 -294.198621)
			(xy 287.489656 -294.181169) (xy 287.537875 -294.171325) (xy 287.58705 -294.169344) (xy 287.635905 -294.175276)
			(xy 287.683176 -294.188968) (xy 287.727638 -294.210066) (xy 287.768141 -294.238022) (xy 287.803634 -294.272114)
			(xy 287.833199 -294.311458) (xy 287.85607 -294.355035) (xy 287.871654 -294.401716) (xy 287.879549 -294.450293)
			(xy 287.880044 -294.4749) (xy 288.218892 -294.4749) (xy 288.222852 -294.425846) (xy 288.234629 -294.378062)
			(xy 288.25392 -294.332786) (xy 288.280223 -294.29119) (xy 288.312858 -294.254353) (xy 288.350979 -294.223228)
			(xy 288.3936 -294.198621) (xy 288.439616 -294.181169) (xy 288.487835 -294.171325) (xy 288.53701 -294.169344)
			(xy 288.585865 -294.175276) (xy 288.633136 -294.188968) (xy 288.677598 -294.210066) (xy 288.718101 -294.238022)
			(xy 288.753594 -294.272114) (xy 288.783159 -294.311458) (xy 288.80603 -294.355035) (xy 288.821614 -294.401716)
			(xy 288.829509 -294.450293) (xy 288.830004 -294.4749) (xy 289.169106 -294.4749) (xy 289.173066 -294.425846)
			(xy 289.184843 -294.378062) (xy 289.204134 -294.332786) (xy 289.230437 -294.29119) (xy 289.263072 -294.254353)
			(xy 289.301193 -294.223228) (xy 289.343814 -294.198621) (xy 289.38983 -294.181169) (xy 289.438049 -294.171325)
			(xy 289.487224 -294.169344) (xy 289.536079 -294.175276) (xy 289.58335 -294.188968) (xy 289.627812 -294.210066)
			(xy 289.668315 -294.238022) (xy 289.703808 -294.272114) (xy 289.733373 -294.311458) (xy 289.756244 -294.355035)
			(xy 289.771828 -294.401716) (xy 289.779723 -294.450293) (xy 289.780218 -294.4749) (xy 290.119066 -294.4749)
			(xy 290.123026 -294.425846) (xy 290.134803 -294.378062) (xy 290.154094 -294.332786) (xy 290.180397 -294.29119)
			(xy 290.213032 -294.254353) (xy 290.251153 -294.223228) (xy 290.293774 -294.198621) (xy 290.33979 -294.181169)
			(xy 290.388009 -294.171325) (xy 290.437184 -294.169344) (xy 290.486039 -294.175276) (xy 290.53331 -294.188968)
			(xy 290.577772 -294.210066) (xy 290.618275 -294.238022) (xy 290.653768 -294.272114) (xy 290.683333 -294.311458)
			(xy 290.706204 -294.355035) (xy 290.721788 -294.401716) (xy 290.729683 -294.450293) (xy 290.730178 -294.4749)
			(xy 292.018986 -294.4749) (xy 292.022946 -294.425846) (xy 292.034723 -294.378062) (xy 292.054014 -294.332786)
			(xy 292.080317 -294.29119) (xy 292.112952 -294.254353) (xy 292.151073 -294.223228) (xy 292.193694 -294.198621)
			(xy 292.23971 -294.181169) (xy 292.287929 -294.171325) (xy 292.337104 -294.169344) (xy 292.385959 -294.175276)
			(xy 292.43323 -294.188968) (xy 292.477692 -294.210066) (xy 292.518195 -294.238022) (xy 292.553688 -294.272114)
			(xy 292.583253 -294.311458) (xy 292.606124 -294.355035) (xy 292.621708 -294.401716) (xy 292.629603 -294.450293)
			(xy 292.630098 -294.4749) (xy 292.968946 -294.4749) (xy 292.972906 -294.425846) (xy 292.984683 -294.378062)
			(xy 293.003974 -294.332786) (xy 293.030277 -294.29119) (xy 293.062912 -294.254353) (xy 293.101033 -294.223228)
			(xy 293.143654 -294.198621) (xy 293.18967 -294.181169) (xy 293.237889 -294.171325) (xy 293.287064 -294.169344)
			(xy 293.335919 -294.175276) (xy 293.38319 -294.188968) (xy 293.427652 -294.210066) (xy 293.468155 -294.238022)
			(xy 293.503648 -294.272114) (xy 293.533213 -294.311458) (xy 293.556084 -294.355035) (xy 293.571668 -294.401716)
			(xy 293.579563 -294.450293) (xy 293.580058 -294.4749) (xy 293.918906 -294.4749) (xy 293.922866 -294.425846)
			(xy 293.934643 -294.378062) (xy 293.953934 -294.332786) (xy 293.980237 -294.29119) (xy 294.012872 -294.254353)
			(xy 294.050993 -294.223228) (xy 294.093614 -294.198621) (xy 294.13963 -294.181169) (xy 294.187849 -294.171325)
			(xy 294.237024 -294.169344) (xy 294.285879 -294.175276) (xy 294.33315 -294.188968) (xy 294.377612 -294.210066)
			(xy 294.418115 -294.238022) (xy 294.453608 -294.272114) (xy 294.483173 -294.311458) (xy 294.506044 -294.355035)
			(xy 294.521628 -294.401716) (xy 294.529523 -294.450293) (xy 294.530018 -294.4749) (xy 294.86912 -294.4749)
			(xy 294.87308 -294.425846) (xy 294.884857 -294.378062) (xy 294.904148 -294.332786) (xy 294.930451 -294.29119)
			(xy 294.963086 -294.254353) (xy 295.001207 -294.223228) (xy 295.043828 -294.198621) (xy 295.089844 -294.181169)
			(xy 295.138063 -294.171325) (xy 295.187238 -294.169344) (xy 295.236093 -294.175276) (xy 295.283364 -294.188968)
			(xy 295.327826 -294.210066) (xy 295.368329 -294.238022) (xy 295.403822 -294.272114) (xy 295.433387 -294.311458)
			(xy 295.456258 -294.355035) (xy 295.471842 -294.401716) (xy 295.479737 -294.450293) (xy 295.480232 -294.4749)
			(xy 295.81908 -294.4749) (xy 295.82304 -294.425846) (xy 295.834817 -294.378062) (xy 295.854108 -294.332786)
			(xy 295.880411 -294.29119) (xy 295.913046 -294.254353) (xy 295.951167 -294.223228) (xy 295.993788 -294.198621)
			(xy 296.039804 -294.181169) (xy 296.088023 -294.171325) (xy 296.137198 -294.169344) (xy 296.186053 -294.175276)
			(xy 296.233324 -294.188968) (xy 296.277786 -294.210066) (xy 296.318289 -294.238022) (xy 296.353782 -294.272114)
			(xy 296.383347 -294.311458) (xy 296.406218 -294.355035) (xy 296.421802 -294.401716) (xy 296.429697 -294.450293)
			(xy 296.430192 -294.4749) (xy 296.76904 -294.4749) (xy 296.773 -294.425846) (xy 296.784777 -294.378062)
			(xy 296.804068 -294.332786) (xy 296.830371 -294.29119) (xy 296.863006 -294.254353) (xy 296.901127 -294.223228)
			(xy 296.943748 -294.198621) (xy 296.989764 -294.181169) (xy 297.037983 -294.171325) (xy 297.087158 -294.169344)
			(xy 297.136013 -294.175276) (xy 297.183284 -294.188968) (xy 297.227746 -294.210066) (xy 297.268249 -294.238022)
			(xy 297.303742 -294.272114) (xy 297.333307 -294.311458) (xy 297.356178 -294.355035) (xy 297.371762 -294.401716)
			(xy 297.379657 -294.450293) (xy 297.380152 -294.4749) (xy 297.719 -294.4749) (xy 297.72296 -294.425846)
			(xy 297.734737 -294.378062) (xy 297.754028 -294.332786) (xy 297.780331 -294.29119) (xy 297.812966 -294.254353)
			(xy 297.851087 -294.223228) (xy 297.893708 -294.198621) (xy 297.939724 -294.181169) (xy 297.987943 -294.171325)
			(xy 298.037118 -294.169344) (xy 298.085973 -294.175276) (xy 298.133244 -294.188968) (xy 298.177706 -294.210066)
			(xy 298.218209 -294.238022) (xy 298.253702 -294.272114) (xy 298.283267 -294.311458) (xy 298.306138 -294.355035)
			(xy 298.321722 -294.401716) (xy 298.329617 -294.450293) (xy 298.330112 -294.4749) (xy 298.66896 -294.4749)
			(xy 298.67292 -294.425846) (xy 298.684697 -294.378062) (xy 298.703988 -294.332786) (xy 298.730291 -294.29119)
			(xy 298.762926 -294.254353) (xy 298.801047 -294.223228) (xy 298.843668 -294.198621) (xy 298.889684 -294.181169)
			(xy 298.937903 -294.171325) (xy 298.987078 -294.169344) (xy 299.035933 -294.175276) (xy 299.083204 -294.188968)
			(xy 299.127666 -294.210066) (xy 299.168169 -294.238022) (xy 299.203662 -294.272114) (xy 299.233227 -294.311458)
			(xy 299.256098 -294.355035) (xy 299.271682 -294.401716) (xy 299.279577 -294.450293) (xy 299.280072 -294.4749)
			(xy 299.61892 -294.4749) (xy 299.62288 -294.425846) (xy 299.634657 -294.378062) (xy 299.653948 -294.332786)
			(xy 299.680251 -294.29119) (xy 299.712886 -294.254353) (xy 299.751007 -294.223228) (xy 299.793628 -294.198621)
			(xy 299.839644 -294.181169) (xy 299.887863 -294.171325) (xy 299.937038 -294.169344) (xy 299.985893 -294.175276)
			(xy 300.033164 -294.188968) (xy 300.077626 -294.210066) (xy 300.118129 -294.238022) (xy 300.153622 -294.272114)
			(xy 300.183187 -294.311458) (xy 300.206058 -294.355035) (xy 300.221642 -294.401716) (xy 300.229537 -294.450293)
			(xy 300.230032 -294.4749) (xy 300.56888 -294.4749) (xy 300.57284 -294.425846) (xy 300.584617 -294.378062)
			(xy 300.603908 -294.332786) (xy 300.630211 -294.29119) (xy 300.662846 -294.254353) (xy 300.700967 -294.223228)
			(xy 300.743588 -294.198621) (xy 300.789604 -294.181169) (xy 300.837823 -294.171325) (xy 300.886998 -294.169344)
			(xy 300.935853 -294.175276) (xy 300.983124 -294.188968) (xy 301.027586 -294.210066) (xy 301.068089 -294.238022)
			(xy 301.103582 -294.272114) (xy 301.133147 -294.311458) (xy 301.156018 -294.355035) (xy 301.171602 -294.401716)
			(xy 301.179497 -294.450293) (xy 301.179992 -294.4749) (xy 301.519094 -294.4749) (xy 301.523054 -294.425846)
			(xy 301.534831 -294.378062) (xy 301.554122 -294.332786) (xy 301.580425 -294.29119) (xy 301.61306 -294.254353)
			(xy 301.651181 -294.223228) (xy 301.693802 -294.198621) (xy 301.739818 -294.181169) (xy 301.788037 -294.171325)
			(xy 301.837212 -294.169344) (xy 301.886067 -294.175276) (xy 301.933338 -294.188968) (xy 301.9778 -294.210066)
			(xy 302.018303 -294.238022) (xy 302.053796 -294.272114) (xy 302.083361 -294.311458) (xy 302.106232 -294.355035)
			(xy 302.121816 -294.401716) (xy 302.129711 -294.450293) (xy 302.130206 -294.4749) (xy 303.419014 -294.4749)
			(xy 303.422974 -294.425846) (xy 303.434751 -294.378062) (xy 303.454042 -294.332786) (xy 303.480345 -294.29119)
			(xy 303.51298 -294.254353) (xy 303.551101 -294.223228) (xy 303.593722 -294.198621) (xy 303.639738 -294.181169)
			(xy 303.687957 -294.171325) (xy 303.737132 -294.169344) (xy 303.785987 -294.175276) (xy 303.833258 -294.188968)
			(xy 303.87772 -294.210066) (xy 303.918223 -294.238022) (xy 303.953716 -294.272114) (xy 303.983281 -294.311458)
			(xy 304.006152 -294.355035) (xy 304.021736 -294.401716) (xy 304.029631 -294.450293) (xy 304.030126 -294.4749)
			(xy 304.368974 -294.4749) (xy 304.372934 -294.425846) (xy 304.384711 -294.378062) (xy 304.404002 -294.332786)
			(xy 304.430305 -294.29119) (xy 304.46294 -294.254353) (xy 304.501061 -294.223228) (xy 304.543682 -294.198621)
			(xy 304.589698 -294.181169) (xy 304.637917 -294.171325) (xy 304.687092 -294.169344) (xy 304.735947 -294.175276)
			(xy 304.783218 -294.188968) (xy 304.82768 -294.210066) (xy 304.868183 -294.238022) (xy 304.903676 -294.272114)
			(xy 304.933241 -294.311458) (xy 304.956112 -294.355035) (xy 304.971696 -294.401716) (xy 304.979591 -294.450293)
			(xy 304.980086 -294.4749) (xy 305.318934 -294.4749) (xy 305.322894 -294.425846) (xy 305.334671 -294.378062)
			(xy 305.353962 -294.332786) (xy 305.380265 -294.29119) (xy 305.4129 -294.254353) (xy 305.451021 -294.223228)
			(xy 305.493642 -294.198621) (xy 305.539658 -294.181169) (xy 305.587877 -294.171325) (xy 305.637052 -294.169344)
			(xy 305.685907 -294.175276) (xy 305.733178 -294.188968) (xy 305.77764 -294.210066) (xy 305.818143 -294.238022)
			(xy 305.853636 -294.272114) (xy 305.883201 -294.311458) (xy 305.906072 -294.355035) (xy 305.921656 -294.401716)
			(xy 305.929551 -294.450293) (xy 305.930046 -294.4749) (xy 306.268894 -294.4749) (xy 306.272854 -294.425846)
			(xy 306.284631 -294.378062) (xy 306.303922 -294.332786) (xy 306.330225 -294.29119) (xy 306.36286 -294.254353)
			(xy 306.400981 -294.223228) (xy 306.443602 -294.198621) (xy 306.489618 -294.181169) (xy 306.537837 -294.171325)
			(xy 306.587012 -294.169344) (xy 306.635867 -294.175276) (xy 306.683138 -294.188968) (xy 306.7276 -294.210066)
			(xy 306.768103 -294.238022) (xy 306.803596 -294.272114) (xy 306.833161 -294.311458) (xy 306.856032 -294.355035)
			(xy 306.871616 -294.401716) (xy 306.879511 -294.450293) (xy 306.880006 -294.4749) (xy 307.219108 -294.4749)
			(xy 307.223068 -294.425846) (xy 307.234845 -294.378062) (xy 307.254136 -294.332786) (xy 307.280439 -294.29119)
			(xy 307.313074 -294.254353) (xy 307.351195 -294.223228) (xy 307.393816 -294.198621) (xy 307.439832 -294.181169)
			(xy 307.488051 -294.171325) (xy 307.537226 -294.169344) (xy 307.586081 -294.175276) (xy 307.633352 -294.188968)
			(xy 307.677814 -294.210066) (xy 307.718317 -294.238022) (xy 307.75381 -294.272114) (xy 307.783375 -294.311458)
			(xy 307.806246 -294.355035) (xy 307.82183 -294.401716) (xy 307.829725 -294.450293) (xy 307.83022 -294.4749)
			(xy 308.169068 -294.4749) (xy 308.173028 -294.425846) (xy 308.184805 -294.378062) (xy 308.204096 -294.332786)
			(xy 308.230399 -294.29119) (xy 308.263034 -294.254353) (xy 308.301155 -294.223228) (xy 308.343776 -294.198621)
			(xy 308.389792 -294.181169) (xy 308.438011 -294.171325) (xy 308.487186 -294.169344) (xy 308.536041 -294.175276)
			(xy 308.583312 -294.188968) (xy 308.627774 -294.210066) (xy 308.668277 -294.238022) (xy 308.70377 -294.272114)
			(xy 308.733335 -294.311458) (xy 308.756206 -294.355035) (xy 308.77179 -294.401716) (xy 308.779685 -294.450293)
			(xy 308.78018 -294.4749) (xy 310.068988 -294.4749) (xy 310.072948 -294.425846) (xy 310.084725 -294.378062)
			(xy 310.104016 -294.332786) (xy 310.130319 -294.29119) (xy 310.162954 -294.254353) (xy 310.201075 -294.223228)
			(xy 310.243696 -294.198621) (xy 310.289712 -294.181169) (xy 310.337931 -294.171325) (xy 310.387106 -294.169344)
			(xy 310.435961 -294.175276) (xy 310.483232 -294.188968) (xy 310.527694 -294.210066) (xy 310.568197 -294.238022)
			(xy 310.60369 -294.272114) (xy 310.633255 -294.311458) (xy 310.656126 -294.355035) (xy 310.67171 -294.401716)
			(xy 310.679605 -294.450293) (xy 310.6801 -294.4749) (xy 311.018948 -294.4749) (xy 311.022908 -294.425846)
			(xy 311.034685 -294.378062) (xy 311.053976 -294.332786) (xy 311.080279 -294.29119) (xy 311.112914 -294.254353)
			(xy 311.151035 -294.223228) (xy 311.193656 -294.198621) (xy 311.239672 -294.181169) (xy 311.287891 -294.171325)
			(xy 311.337066 -294.169344) (xy 311.385921 -294.175276) (xy 311.433192 -294.188968) (xy 311.477654 -294.210066)
			(xy 311.518157 -294.238022) (xy 311.55365 -294.272114) (xy 311.583215 -294.311458) (xy 311.606086 -294.355035)
			(xy 311.62167 -294.401716) (xy 311.629565 -294.450293) (xy 311.63006 -294.4749) (xy 311.968908 -294.4749)
			(xy 311.972868 -294.425846) (xy 311.984645 -294.378062) (xy 312.003936 -294.332786) (xy 312.030239 -294.29119)
			(xy 312.062874 -294.254353) (xy 312.100995 -294.223228) (xy 312.143616 -294.198621) (xy 312.189632 -294.181169)
			(xy 312.237851 -294.171325) (xy 312.287026 -294.169344) (xy 312.335881 -294.175276) (xy 312.383152 -294.188968)
			(xy 312.427614 -294.210066) (xy 312.468117 -294.238022) (xy 312.50361 -294.272114) (xy 312.533175 -294.311458)
			(xy 312.556046 -294.355035) (xy 312.57163 -294.401716) (xy 312.579525 -294.450293) (xy 312.58002 -294.4749)
			(xy 312.919122 -294.4749) (xy 312.923082 -294.425846) (xy 312.934859 -294.378062) (xy 312.95415 -294.332786)
			(xy 312.980453 -294.29119) (xy 313.013088 -294.254353) (xy 313.051209 -294.223228) (xy 313.09383 -294.198621)
			(xy 313.139846 -294.181169) (xy 313.188065 -294.171325) (xy 313.23724 -294.169344) (xy 313.286095 -294.175276)
			(xy 313.333366 -294.188968) (xy 313.377828 -294.210066) (xy 313.418331 -294.238022) (xy 313.453824 -294.272114)
			(xy 313.483389 -294.311458) (xy 313.50626 -294.355035) (xy 313.521844 -294.401716) (xy 313.529739 -294.450293)
			(xy 313.530234 -294.4749) (xy 313.869082 -294.4749) (xy 313.873042 -294.425846) (xy 313.884819 -294.378062)
			(xy 313.90411 -294.332786) (xy 313.930413 -294.29119) (xy 313.963048 -294.254353) (xy 314.001169 -294.223228)
			(xy 314.04379 -294.198621) (xy 314.089806 -294.181169) (xy 314.138025 -294.171325) (xy 314.1872 -294.169344)
			(xy 314.236055 -294.175276) (xy 314.283326 -294.188968) (xy 314.327788 -294.210066) (xy 314.368291 -294.238022)
			(xy 314.403784 -294.272114) (xy 314.433349 -294.311458) (xy 314.45622 -294.355035) (xy 314.471804 -294.401716)
			(xy 314.479699 -294.450293) (xy 314.480194 -294.4749) (xy 314.819042 -294.4749) (xy 314.823002 -294.425846)
			(xy 314.834779 -294.378062) (xy 314.85407 -294.332786) (xy 314.880373 -294.29119) (xy 314.913008 -294.254353)
			(xy 314.951129 -294.223228) (xy 314.99375 -294.198621) (xy 315.039766 -294.181169) (xy 315.087985 -294.171325)
			(xy 315.13716 -294.169344) (xy 315.186015 -294.175276) (xy 315.233286 -294.188968) (xy 315.277748 -294.210066)
			(xy 315.318251 -294.238022) (xy 315.353744 -294.272114) (xy 315.383309 -294.311458) (xy 315.40618 -294.355035)
			(xy 315.421764 -294.401716) (xy 315.429659 -294.450293) (xy 315.430154 -294.4749) (xy 315.429659 -294.499507)
			(xy 315.421764 -294.548084) (xy 315.40618 -294.594765) (xy 315.383309 -294.638342) (xy 315.353744 -294.677686)
			(xy 315.318251 -294.711778) (xy 315.277748 -294.739734) (xy 315.233286 -294.760832) (xy 315.186015 -294.774524)
			(xy 315.13716 -294.780456) (xy 315.087985 -294.778475) (xy 315.039766 -294.768631) (xy 314.99375 -294.751179)
			(xy 314.951129 -294.726572) (xy 314.913008 -294.695447) (xy 314.880373 -294.65861) (xy 314.85407 -294.617014)
			(xy 314.834779 -294.571738) (xy 314.823002 -294.523954) (xy 314.819042 -294.4749) (xy 314.480194 -294.4749)
			(xy 314.479699 -294.499507) (xy 314.471804 -294.548084) (xy 314.45622 -294.594765) (xy 314.433349 -294.638342)
			(xy 314.403784 -294.677686) (xy 314.368291 -294.711778) (xy 314.327788 -294.739734) (xy 314.283326 -294.760832)
			(xy 314.236055 -294.774524) (xy 314.1872 -294.780456) (xy 314.138025 -294.778475) (xy 314.089806 -294.768631)
			(xy 314.04379 -294.751179) (xy 314.001169 -294.726572) (xy 313.963048 -294.695447) (xy 313.930413 -294.65861)
			(xy 313.90411 -294.617014) (xy 313.884819 -294.571738) (xy 313.873042 -294.523954) (xy 313.869082 -294.4749)
			(xy 313.530234 -294.4749) (xy 313.529739 -294.499507) (xy 313.521844 -294.548084) (xy 313.50626 -294.594765)
			(xy 313.483389 -294.638342) (xy 313.453824 -294.677686) (xy 313.418331 -294.711778) (xy 313.377828 -294.739734)
			(xy 313.333366 -294.760832) (xy 313.286095 -294.774524) (xy 313.23724 -294.780456) (xy 313.188065 -294.778475)
			(xy 313.139846 -294.768631) (xy 313.09383 -294.751179) (xy 313.051209 -294.726572) (xy 313.013088 -294.695447)
			(xy 312.980453 -294.65861) (xy 312.95415 -294.617014) (xy 312.934859 -294.571738) (xy 312.923082 -294.523954)
			(xy 312.919122 -294.4749) (xy 312.58002 -294.4749) (xy 312.579525 -294.499507) (xy 312.57163 -294.548084)
			(xy 312.556046 -294.594765) (xy 312.533175 -294.638342) (xy 312.50361 -294.677686) (xy 312.468117 -294.711778)
			(xy 312.427614 -294.739734) (xy 312.383152 -294.760832) (xy 312.335881 -294.774524) (xy 312.287026 -294.780456)
			(xy 312.237851 -294.778475) (xy 312.189632 -294.768631) (xy 312.143616 -294.751179) (xy 312.100995 -294.726572)
			(xy 312.062874 -294.695447) (xy 312.030239 -294.65861) (xy 312.003936 -294.617014) (xy 311.984645 -294.571738)
			(xy 311.972868 -294.523954) (xy 311.968908 -294.4749) (xy 311.63006 -294.4749) (xy 311.629565 -294.499507)
			(xy 311.62167 -294.548084) (xy 311.606086 -294.594765) (xy 311.583215 -294.638342) (xy 311.55365 -294.677686)
			(xy 311.518157 -294.711778) (xy 311.477654 -294.739734) (xy 311.433192 -294.760832) (xy 311.385921 -294.774524)
			(xy 311.337066 -294.780456) (xy 311.287891 -294.778475) (xy 311.239672 -294.768631) (xy 311.193656 -294.751179)
			(xy 311.151035 -294.726572) (xy 311.112914 -294.695447) (xy 311.080279 -294.65861) (xy 311.053976 -294.617014)
			(xy 311.034685 -294.571738) (xy 311.022908 -294.523954) (xy 311.018948 -294.4749) (xy 310.6801 -294.4749)
			(xy 310.679605 -294.499507) (xy 310.67171 -294.548084) (xy 310.656126 -294.594765) (xy 310.633255 -294.638342)
			(xy 310.60369 -294.677686) (xy 310.568197 -294.711778) (xy 310.527694 -294.739734) (xy 310.483232 -294.760832)
			(xy 310.435961 -294.774524) (xy 310.387106 -294.780456) (xy 310.337931 -294.778475) (xy 310.289712 -294.768631)
			(xy 310.243696 -294.751179) (xy 310.201075 -294.726572) (xy 310.162954 -294.695447) (xy 310.130319 -294.65861)
			(xy 310.104016 -294.617014) (xy 310.084725 -294.571738) (xy 310.072948 -294.523954) (xy 310.068988 -294.4749)
			(xy 308.78018 -294.4749) (xy 308.779685 -294.499507) (xy 308.77179 -294.548084) (xy 308.756206 -294.594765)
			(xy 308.733335 -294.638342) (xy 308.70377 -294.677686) (xy 308.668277 -294.711778) (xy 308.627774 -294.739734)
			(xy 308.583312 -294.760832) (xy 308.536041 -294.774524) (xy 308.487186 -294.780456) (xy 308.438011 -294.778475)
			(xy 308.389792 -294.768631) (xy 308.343776 -294.751179) (xy 308.301155 -294.726572) (xy 308.263034 -294.695447)
			(xy 308.230399 -294.65861) (xy 308.204096 -294.617014) (xy 308.184805 -294.571738) (xy 308.173028 -294.523954)
			(xy 308.169068 -294.4749) (xy 307.83022 -294.4749) (xy 307.829725 -294.499507) (xy 307.82183 -294.548084)
			(xy 307.806246 -294.594765) (xy 307.783375 -294.638342) (xy 307.75381 -294.677686) (xy 307.718317 -294.711778)
			(xy 307.677814 -294.739734) (xy 307.633352 -294.760832) (xy 307.586081 -294.774524) (xy 307.537226 -294.780456)
			(xy 307.488051 -294.778475) (xy 307.439832 -294.768631) (xy 307.393816 -294.751179) (xy 307.351195 -294.726572)
			(xy 307.313074 -294.695447) (xy 307.280439 -294.65861) (xy 307.254136 -294.617014) (xy 307.234845 -294.571738)
			(xy 307.223068 -294.523954) (xy 307.219108 -294.4749) (xy 306.880006 -294.4749) (xy 306.879511 -294.499507)
			(xy 306.871616 -294.548084) (xy 306.856032 -294.594765) (xy 306.833161 -294.638342) (xy 306.803596 -294.677686)
			(xy 306.768103 -294.711778) (xy 306.7276 -294.739734) (xy 306.683138 -294.760832) (xy 306.635867 -294.774524)
			(xy 306.587012 -294.780456) (xy 306.537837 -294.778475) (xy 306.489618 -294.768631) (xy 306.443602 -294.751179)
			(xy 306.400981 -294.726572) (xy 306.36286 -294.695447) (xy 306.330225 -294.65861) (xy 306.303922 -294.617014)
			(xy 306.284631 -294.571738) (xy 306.272854 -294.523954) (xy 306.268894 -294.4749) (xy 305.930046 -294.4749)
			(xy 305.929551 -294.499507) (xy 305.921656 -294.548084) (xy 305.906072 -294.594765) (xy 305.883201 -294.638342)
			(xy 305.853636 -294.677686) (xy 305.818143 -294.711778) (xy 305.77764 -294.739734) (xy 305.733178 -294.760832)
			(xy 305.685907 -294.774524) (xy 305.637052 -294.780456) (xy 305.587877 -294.778475) (xy 305.539658 -294.768631)
			(xy 305.493642 -294.751179) (xy 305.451021 -294.726572) (xy 305.4129 -294.695447) (xy 305.380265 -294.65861)
			(xy 305.353962 -294.617014) (xy 305.334671 -294.571738) (xy 305.322894 -294.523954) (xy 305.318934 -294.4749)
			(xy 304.980086 -294.4749) (xy 304.979591 -294.499507) (xy 304.971696 -294.548084) (xy 304.956112 -294.594765)
			(xy 304.933241 -294.638342) (xy 304.903676 -294.677686) (xy 304.868183 -294.711778) (xy 304.82768 -294.739734)
			(xy 304.783218 -294.760832) (xy 304.735947 -294.774524) (xy 304.687092 -294.780456) (xy 304.637917 -294.778475)
			(xy 304.589698 -294.768631) (xy 304.543682 -294.751179) (xy 304.501061 -294.726572) (xy 304.46294 -294.695447)
			(xy 304.430305 -294.65861) (xy 304.404002 -294.617014) (xy 304.384711 -294.571738) (xy 304.372934 -294.523954)
			(xy 304.368974 -294.4749) (xy 304.030126 -294.4749) (xy 304.029631 -294.499507) (xy 304.021736 -294.548084)
			(xy 304.006152 -294.594765) (xy 303.983281 -294.638342) (xy 303.953716 -294.677686) (xy 303.918223 -294.711778)
			(xy 303.87772 -294.739734) (xy 303.833258 -294.760832) (xy 303.785987 -294.774524) (xy 303.737132 -294.780456)
			(xy 303.687957 -294.778475) (xy 303.639738 -294.768631) (xy 303.593722 -294.751179) (xy 303.551101 -294.726572)
			(xy 303.51298 -294.695447) (xy 303.480345 -294.65861) (xy 303.454042 -294.617014) (xy 303.434751 -294.571738)
			(xy 303.422974 -294.523954) (xy 303.419014 -294.4749) (xy 302.130206 -294.4749) (xy 302.129711 -294.499507)
			(xy 302.121816 -294.548084) (xy 302.106232 -294.594765) (xy 302.083361 -294.638342) (xy 302.053796 -294.677686)
			(xy 302.018303 -294.711778) (xy 301.9778 -294.739734) (xy 301.933338 -294.760832) (xy 301.886067 -294.774524)
			(xy 301.837212 -294.780456) (xy 301.788037 -294.778475) (xy 301.739818 -294.768631) (xy 301.693802 -294.751179)
			(xy 301.651181 -294.726572) (xy 301.61306 -294.695447) (xy 301.580425 -294.65861) (xy 301.554122 -294.617014)
			(xy 301.534831 -294.571738) (xy 301.523054 -294.523954) (xy 301.519094 -294.4749) (xy 301.179992 -294.4749)
			(xy 301.179497 -294.499507) (xy 301.171602 -294.548084) (xy 301.156018 -294.594765) (xy 301.133147 -294.638342)
			(xy 301.103582 -294.677686) (xy 301.068089 -294.711778) (xy 301.027586 -294.739734) (xy 300.983124 -294.760832)
			(xy 300.935853 -294.774524) (xy 300.886998 -294.780456) (xy 300.837823 -294.778475) (xy 300.789604 -294.768631)
			(xy 300.743588 -294.751179) (xy 300.700967 -294.726572) (xy 300.662846 -294.695447) (xy 300.630211 -294.65861)
			(xy 300.603908 -294.617014) (xy 300.584617 -294.571738) (xy 300.57284 -294.523954) (xy 300.56888 -294.4749)
			(xy 300.230032 -294.4749) (xy 300.229537 -294.499507) (xy 300.221642 -294.548084) (xy 300.206058 -294.594765)
			(xy 300.183187 -294.638342) (xy 300.153622 -294.677686) (xy 300.118129 -294.711778) (xy 300.077626 -294.739734)
			(xy 300.033164 -294.760832) (xy 299.985893 -294.774524) (xy 299.937038 -294.780456) (xy 299.887863 -294.778475)
			(xy 299.839644 -294.768631) (xy 299.793628 -294.751179) (xy 299.751007 -294.726572) (xy 299.712886 -294.695447)
			(xy 299.680251 -294.65861) (xy 299.653948 -294.617014) (xy 299.634657 -294.571738) (xy 299.62288 -294.523954)
			(xy 299.61892 -294.4749) (xy 299.280072 -294.4749) (xy 299.279577 -294.499507) (xy 299.271682 -294.548084)
			(xy 299.256098 -294.594765) (xy 299.233227 -294.638342) (xy 299.203662 -294.677686) (xy 299.168169 -294.711778)
			(xy 299.127666 -294.739734) (xy 299.083204 -294.760832) (xy 299.035933 -294.774524) (xy 298.987078 -294.780456)
			(xy 298.937903 -294.778475) (xy 298.889684 -294.768631) (xy 298.843668 -294.751179) (xy 298.801047 -294.726572)
			(xy 298.762926 -294.695447) (xy 298.730291 -294.65861) (xy 298.703988 -294.617014) (xy 298.684697 -294.571738)
			(xy 298.67292 -294.523954) (xy 298.66896 -294.4749) (xy 298.330112 -294.4749) (xy 298.329617 -294.499507)
			(xy 298.321722 -294.548084) (xy 298.306138 -294.594765) (xy 298.283267 -294.638342) (xy 298.253702 -294.677686)
			(xy 298.218209 -294.711778) (xy 298.177706 -294.739734) (xy 298.133244 -294.760832) (xy 298.085973 -294.774524)
			(xy 298.037118 -294.780456) (xy 297.987943 -294.778475) (xy 297.939724 -294.768631) (xy 297.893708 -294.751179)
			(xy 297.851087 -294.726572) (xy 297.812966 -294.695447) (xy 297.780331 -294.65861) (xy 297.754028 -294.617014)
			(xy 297.734737 -294.571738) (xy 297.72296 -294.523954) (xy 297.719 -294.4749) (xy 297.380152 -294.4749)
			(xy 297.379657 -294.499507) (xy 297.371762 -294.548084) (xy 297.356178 -294.594765) (xy 297.333307 -294.638342)
			(xy 297.303742 -294.677686) (xy 297.268249 -294.711778) (xy 297.227746 -294.739734) (xy 297.183284 -294.760832)
			(xy 297.136013 -294.774524) (xy 297.087158 -294.780456) (xy 297.037983 -294.778475) (xy 296.989764 -294.768631)
			(xy 296.943748 -294.751179) (xy 296.901127 -294.726572) (xy 296.863006 -294.695447) (xy 296.830371 -294.65861)
			(xy 296.804068 -294.617014) (xy 296.784777 -294.571738) (xy 296.773 -294.523954) (xy 296.76904 -294.4749)
			(xy 296.430192 -294.4749) (xy 296.429697 -294.499507) (xy 296.421802 -294.548084) (xy 296.406218 -294.594765)
			(xy 296.383347 -294.638342) (xy 296.353782 -294.677686) (xy 296.318289 -294.711778) (xy 296.277786 -294.739734)
			(xy 296.233324 -294.760832) (xy 296.186053 -294.774524) (xy 296.137198 -294.780456) (xy 296.088023 -294.778475)
			(xy 296.039804 -294.768631) (xy 295.993788 -294.751179) (xy 295.951167 -294.726572) (xy 295.913046 -294.695447)
			(xy 295.880411 -294.65861) (xy 295.854108 -294.617014) (xy 295.834817 -294.571738) (xy 295.82304 -294.523954)
			(xy 295.81908 -294.4749) (xy 295.480232 -294.4749) (xy 295.479737 -294.499507) (xy 295.471842 -294.548084)
			(xy 295.456258 -294.594765) (xy 295.433387 -294.638342) (xy 295.403822 -294.677686) (xy 295.368329 -294.711778)
			(xy 295.327826 -294.739734) (xy 295.283364 -294.760832) (xy 295.236093 -294.774524) (xy 295.187238 -294.780456)
			(xy 295.138063 -294.778475) (xy 295.089844 -294.768631) (xy 295.043828 -294.751179) (xy 295.001207 -294.726572)
			(xy 294.963086 -294.695447) (xy 294.930451 -294.65861) (xy 294.904148 -294.617014) (xy 294.884857 -294.571738)
			(xy 294.87308 -294.523954) (xy 294.86912 -294.4749) (xy 294.530018 -294.4749) (xy 294.529523 -294.499507)
			(xy 294.521628 -294.548084) (xy 294.506044 -294.594765) (xy 294.483173 -294.638342) (xy 294.453608 -294.677686)
			(xy 294.418115 -294.711778) (xy 294.377612 -294.739734) (xy 294.33315 -294.760832) (xy 294.285879 -294.774524)
			(xy 294.237024 -294.780456) (xy 294.187849 -294.778475) (xy 294.13963 -294.768631) (xy 294.093614 -294.751179)
			(xy 294.050993 -294.726572) (xy 294.012872 -294.695447) (xy 293.980237 -294.65861) (xy 293.953934 -294.617014)
			(xy 293.934643 -294.571738) (xy 293.922866 -294.523954) (xy 293.918906 -294.4749) (xy 293.580058 -294.4749)
			(xy 293.579563 -294.499507) (xy 293.571668 -294.548084) (xy 293.556084 -294.594765) (xy 293.533213 -294.638342)
			(xy 293.503648 -294.677686) (xy 293.468155 -294.711778) (xy 293.427652 -294.739734) (xy 293.38319 -294.760832)
			(xy 293.335919 -294.774524) (xy 293.287064 -294.780456) (xy 293.237889 -294.778475) (xy 293.18967 -294.768631)
			(xy 293.143654 -294.751179) (xy 293.101033 -294.726572) (xy 293.062912 -294.695447) (xy 293.030277 -294.65861)
			(xy 293.003974 -294.617014) (xy 292.984683 -294.571738) (xy 292.972906 -294.523954) (xy 292.968946 -294.4749)
			(xy 292.630098 -294.4749) (xy 292.629603 -294.499507) (xy 292.621708 -294.548084) (xy 292.606124 -294.594765)
			(xy 292.583253 -294.638342) (xy 292.553688 -294.677686) (xy 292.518195 -294.711778) (xy 292.477692 -294.739734)
			(xy 292.43323 -294.760832) (xy 292.385959 -294.774524) (xy 292.337104 -294.780456) (xy 292.287929 -294.778475)
			(xy 292.23971 -294.768631) (xy 292.193694 -294.751179) (xy 292.151073 -294.726572) (xy 292.112952 -294.695447)
			(xy 292.080317 -294.65861) (xy 292.054014 -294.617014) (xy 292.034723 -294.571738) (xy 292.022946 -294.523954)
			(xy 292.018986 -294.4749) (xy 290.730178 -294.4749) (xy 290.729683 -294.499507) (xy 290.721788 -294.548084)
			(xy 290.706204 -294.594765) (xy 290.683333 -294.638342) (xy 290.653768 -294.677686) (xy 290.618275 -294.711778)
			(xy 290.577772 -294.739734) (xy 290.53331 -294.760832) (xy 290.486039 -294.774524) (xy 290.437184 -294.780456)
			(xy 290.388009 -294.778475) (xy 290.33979 -294.768631) (xy 290.293774 -294.751179) (xy 290.251153 -294.726572)
			(xy 290.213032 -294.695447) (xy 290.180397 -294.65861) (xy 290.154094 -294.617014) (xy 290.134803 -294.571738)
			(xy 290.123026 -294.523954) (xy 290.119066 -294.4749) (xy 289.780218 -294.4749) (xy 289.779723 -294.499507)
			(xy 289.771828 -294.548084) (xy 289.756244 -294.594765) (xy 289.733373 -294.638342) (xy 289.703808 -294.677686)
			(xy 289.668315 -294.711778) (xy 289.627812 -294.739734) (xy 289.58335 -294.760832) (xy 289.536079 -294.774524)
			(xy 289.487224 -294.780456) (xy 289.438049 -294.778475) (xy 289.38983 -294.768631) (xy 289.343814 -294.751179)
			(xy 289.301193 -294.726572) (xy 289.263072 -294.695447) (xy 289.230437 -294.65861) (xy 289.204134 -294.617014)
			(xy 289.184843 -294.571738) (xy 289.173066 -294.523954) (xy 289.169106 -294.4749) (xy 288.830004 -294.4749)
			(xy 288.829509 -294.499507) (xy 288.821614 -294.548084) (xy 288.80603 -294.594765) (xy 288.783159 -294.638342)
			(xy 288.753594 -294.677686) (xy 288.718101 -294.711778) (xy 288.677598 -294.739734) (xy 288.633136 -294.760832)
			(xy 288.585865 -294.774524) (xy 288.53701 -294.780456) (xy 288.487835 -294.778475) (xy 288.439616 -294.768631)
			(xy 288.3936 -294.751179) (xy 288.350979 -294.726572) (xy 288.312858 -294.695447) (xy 288.280223 -294.65861)
			(xy 288.25392 -294.617014) (xy 288.234629 -294.571738) (xy 288.222852 -294.523954) (xy 288.218892 -294.4749)
			(xy 287.880044 -294.4749) (xy 287.879549 -294.499507) (xy 287.871654 -294.548084) (xy 287.85607 -294.594765)
			(xy 287.833199 -294.638342) (xy 287.803634 -294.677686) (xy 287.768141 -294.711778) (xy 287.727638 -294.739734)
			(xy 287.683176 -294.760832) (xy 287.635905 -294.774524) (xy 287.58705 -294.780456) (xy 287.537875 -294.778475)
			(xy 287.489656 -294.768631) (xy 287.44364 -294.751179) (xy 287.401019 -294.726572) (xy 287.362898 -294.695447)
			(xy 287.330263 -294.65861) (xy 287.30396 -294.617014) (xy 287.284669 -294.571738) (xy 287.272892 -294.523954)
			(xy 287.268932 -294.4749) (xy 286.930084 -294.4749) (xy 286.929589 -294.499507) (xy 286.921694 -294.548084)
			(xy 286.90611 -294.594765) (xy 286.883239 -294.638342) (xy 286.853674 -294.677686) (xy 286.818181 -294.711778)
			(xy 286.777678 -294.739734) (xy 286.733216 -294.760832) (xy 286.685945 -294.774524) (xy 286.63709 -294.780456)
			(xy 286.587915 -294.778475) (xy 286.539696 -294.768631) (xy 286.49368 -294.751179) (xy 286.451059 -294.726572)
			(xy 286.412938 -294.695447) (xy 286.380303 -294.65861) (xy 286.354 -294.617014) (xy 286.334709 -294.571738)
			(xy 286.322932 -294.523954) (xy 286.318972 -294.4749) (xy 285.980124 -294.4749) (xy 285.979629 -294.499507)
			(xy 285.971734 -294.548084) (xy 285.95615 -294.594765) (xy 285.933279 -294.638342) (xy 285.903714 -294.677686)
			(xy 285.868221 -294.711778) (xy 285.827718 -294.739734) (xy 285.783256 -294.760832) (xy 285.735985 -294.774524)
			(xy 285.68713 -294.780456) (xy 285.637955 -294.778475) (xy 285.589736 -294.768631) (xy 285.54372 -294.751179)
			(xy 285.501099 -294.726572) (xy 285.462978 -294.695447) (xy 285.430343 -294.65861) (xy 285.40404 -294.617014)
			(xy 285.384749 -294.571738) (xy 285.372972 -294.523954) (xy 285.369012 -294.4749) (xy 285.030164 -294.4749)
			(xy 285.029669 -294.499507) (xy 285.021774 -294.548084) (xy 285.00619 -294.594765) (xy 284.983319 -294.638342)
			(xy 284.953754 -294.677686) (xy 284.918261 -294.711778) (xy 284.877758 -294.739734) (xy 284.833296 -294.760832)
			(xy 284.786025 -294.774524) (xy 284.73717 -294.780456) (xy 284.687995 -294.778475) (xy 284.639776 -294.768631)
			(xy 284.59376 -294.751179) (xy 284.551139 -294.726572) (xy 284.513018 -294.695447) (xy 284.480383 -294.65861)
			(xy 284.45408 -294.617014) (xy 284.434789 -294.571738) (xy 284.423012 -294.523954) (xy 284.419052 -294.4749)
			(xy 284.080204 -294.4749) (xy 284.079709 -294.499507) (xy 284.071814 -294.548084) (xy 284.05623 -294.594765)
			(xy 284.033359 -294.638342) (xy 284.003794 -294.677686) (xy 283.968301 -294.711778) (xy 283.927798 -294.739734)
			(xy 283.883336 -294.760832) (xy 283.836065 -294.774524) (xy 283.78721 -294.780456) (xy 283.738035 -294.778475)
			(xy 283.689816 -294.768631) (xy 283.6438 -294.751179) (xy 283.601179 -294.726572) (xy 283.563058 -294.695447)
			(xy 283.530423 -294.65861) (xy 283.50412 -294.617014) (xy 283.484829 -294.571738) (xy 283.473052 -294.523954)
			(xy 283.469092 -294.4749) (xy 283.130244 -294.4749) (xy 283.129749 -294.499507) (xy 283.121854 -294.548084)
			(xy 283.10627 -294.594765) (xy 283.083399 -294.638342) (xy 283.053834 -294.677686) (xy 283.018341 -294.711778)
			(xy 282.977838 -294.739734) (xy 282.933376 -294.760832) (xy 282.886105 -294.774524) (xy 282.83725 -294.780456)
			(xy 282.788075 -294.778475) (xy 282.739856 -294.768631) (xy 282.69384 -294.751179) (xy 282.651219 -294.726572)
			(xy 282.613098 -294.695447) (xy 282.580463 -294.65861) (xy 282.55416 -294.617014) (xy 282.534869 -294.571738)
			(xy 282.523092 -294.523954) (xy 282.519132 -294.4749) (xy 282.18003 -294.4749) (xy 282.179535 -294.499507)
			(xy 282.17164 -294.548084) (xy 282.156056 -294.594765) (xy 282.133185 -294.638342) (xy 282.10362 -294.677686)
			(xy 282.068127 -294.711778) (xy 282.027624 -294.739734) (xy 281.983162 -294.760832) (xy 281.935891 -294.774524)
			(xy 281.887036 -294.780456) (xy 281.837861 -294.778475) (xy 281.789642 -294.768631) (xy 281.743626 -294.751179)
			(xy 281.701005 -294.726572) (xy 281.662884 -294.695447) (xy 281.630249 -294.65861) (xy 281.603946 -294.617014)
			(xy 281.584655 -294.571738) (xy 281.572878 -294.523954) (xy 281.568918 -294.4749) (xy 281.23007 -294.4749)
			(xy 281.229575 -294.499507) (xy 281.22168 -294.548084) (xy 281.206096 -294.594765) (xy 281.183225 -294.638342)
			(xy 281.15366 -294.677686) (xy 281.118167 -294.711778) (xy 281.077664 -294.739734) (xy 281.033202 -294.760832)
			(xy 280.985931 -294.774524) (xy 280.937076 -294.780456) (xy 280.887901 -294.778475) (xy 280.839682 -294.768631)
			(xy 280.793666 -294.751179) (xy 280.751045 -294.726572) (xy 280.712924 -294.695447) (xy 280.680289 -294.65861)
			(xy 280.653986 -294.617014) (xy 280.634695 -294.571738) (xy 280.622918 -294.523954) (xy 280.618958 -294.4749)
			(xy 280.28011 -294.4749) (xy 280.279615 -294.499507) (xy 280.27172 -294.548084) (xy 280.256136 -294.594765)
			(xy 280.233265 -294.638342) (xy 280.2037 -294.677686) (xy 280.168207 -294.711778) (xy 280.127704 -294.739734)
			(xy 280.083242 -294.760832) (xy 280.035971 -294.774524) (xy 279.987116 -294.780456) (xy 279.937941 -294.778475)
			(xy 279.889722 -294.768631) (xy 279.843706 -294.751179) (xy 279.801085 -294.726572) (xy 279.762964 -294.695447)
			(xy 279.730329 -294.65861) (xy 279.704026 -294.617014) (xy 279.684735 -294.571738) (xy 279.672958 -294.523954)
			(xy 279.668998 -294.4749) (xy 279.33015 -294.4749) (xy 279.329655 -294.499507) (xy 279.32176 -294.548084)
			(xy 279.306176 -294.594765) (xy 279.283305 -294.638342) (xy 279.25374 -294.677686) (xy 279.218247 -294.711778)
			(xy 279.177744 -294.739734) (xy 279.133282 -294.760832) (xy 279.086011 -294.774524) (xy 279.037156 -294.780456)
			(xy 278.987981 -294.778475) (xy 278.939762 -294.768631) (xy 278.893746 -294.751179) (xy 278.851125 -294.726572)
			(xy 278.813004 -294.695447) (xy 278.780369 -294.65861) (xy 278.754066 -294.617014) (xy 278.734775 -294.571738)
			(xy 278.722998 -294.523954) (xy 278.719038 -294.4749) (xy 278.38019 -294.4749) (xy 278.379695 -294.499507)
			(xy 278.3718 -294.548084) (xy 278.356216 -294.594765) (xy 278.333345 -294.638342) (xy 278.30378 -294.677686)
			(xy 278.268287 -294.711778) (xy 278.227784 -294.739734) (xy 278.183322 -294.760832) (xy 278.136051 -294.774524)
			(xy 278.087196 -294.780456) (xy 278.038021 -294.778475) (xy 277.989802 -294.768631) (xy 277.943786 -294.751179)
			(xy 277.901165 -294.726572) (xy 277.863044 -294.695447) (xy 277.830409 -294.65861) (xy 277.804106 -294.617014)
			(xy 277.784815 -294.571738) (xy 277.773038 -294.523954) (xy 277.769078 -294.4749) (xy 277.43023 -294.4749)
			(xy 277.429735 -294.499507) (xy 277.42184 -294.548084) (xy 277.406256 -294.594765) (xy 277.383385 -294.638342)
			(xy 277.35382 -294.677686) (xy 277.318327 -294.711778) (xy 277.277824 -294.739734) (xy 277.233362 -294.760832)
			(xy 277.186091 -294.774524) (xy 277.137236 -294.780456) (xy 277.088061 -294.778475) (xy 277.039842 -294.768631)
			(xy 276.993826 -294.751179) (xy 276.951205 -294.726572) (xy 276.913084 -294.695447) (xy 276.880449 -294.65861)
			(xy 276.854146 -294.617014) (xy 276.834855 -294.571738) (xy 276.823078 -294.523954) (xy 276.819118 -294.4749)
			(xy 276.480016 -294.4749) (xy 276.479521 -294.499507) (xy 276.471626 -294.548084) (xy 276.456042 -294.594765)
			(xy 276.433171 -294.638342) (xy 276.403606 -294.677686) (xy 276.368113 -294.711778) (xy 276.32761 -294.739734)
			(xy 276.283148 -294.760832) (xy 276.235877 -294.774524) (xy 276.187022 -294.780456) (xy 276.137847 -294.778475)
			(xy 276.089628 -294.768631) (xy 276.043612 -294.751179) (xy 276.000991 -294.726572) (xy 275.96287 -294.695447)
			(xy 275.930235 -294.65861) (xy 275.903932 -294.617014) (xy 275.884641 -294.571738) (xy 275.872864 -294.523954)
			(xy 275.868904 -294.4749) (xy 275.530056 -294.4749) (xy 275.529561 -294.499507) (xy 275.521666 -294.548084)
			(xy 275.506082 -294.594765) (xy 275.483211 -294.638342) (xy 275.453646 -294.677686) (xy 275.418153 -294.711778)
			(xy 275.37765 -294.739734) (xy 275.333188 -294.760832) (xy 275.285917 -294.774524) (xy 275.237062 -294.780456)
			(xy 275.187887 -294.778475) (xy 275.139668 -294.768631) (xy 275.093652 -294.751179) (xy 275.051031 -294.726572)
			(xy 275.01291 -294.695447) (xy 274.980275 -294.65861) (xy 274.953972 -294.617014) (xy 274.934681 -294.571738)
			(xy 274.922904 -294.523954) (xy 274.918944 -294.4749) (xy 274.630896 -294.4749) (xy 274.630398 -294.501549)
			(xy 274.622455 -294.554253) (xy 274.606745 -294.605183) (xy 274.583619 -294.653204) (xy 274.553595 -294.697241)
			(xy 274.517343 -294.736312) (xy 274.475672 -294.769543) (xy 274.429514 -294.796192) (xy 274.3799 -294.815664)
			(xy 274.327938 -294.827524) (xy 274.274788 -294.831508) (xy 274.221638 -294.827524) (xy 274.169676 -294.815664)
			(xy 274.120062 -294.796192) (xy 274.073904 -294.769543) (xy 274.032233 -294.736312) (xy 273.995981 -294.697241)
			(xy 273.965957 -294.653204) (xy 273.942831 -294.605183) (xy 273.927121 -294.554253) (xy 273.919178 -294.501549)
			(xy 273.629309 -294.501549) (xy 273.621746 -294.548084) (xy 273.606162 -294.594765) (xy 273.583291 -294.638342)
			(xy 273.553726 -294.677686) (xy 273.518233 -294.711778) (xy 273.47773 -294.739734) (xy 273.433268 -294.760832)
			(xy 273.385997 -294.774524) (xy 273.337142 -294.780456) (xy 273.287967 -294.778475) (xy 273.239748 -294.768631)
			(xy 273.193732 -294.751179) (xy 273.151111 -294.726572) (xy 273.11299 -294.695447) (xy 273.080355 -294.65861)
			(xy 273.054052 -294.617014) (xy 273.034761 -294.571738) (xy 273.022984 -294.523954) (xy 273.019024 -294.4749)
			(xy 270.780256 -294.4749) (xy 270.779761 -294.499507) (xy 270.771866 -294.548084) (xy 270.756282 -294.594765)
			(xy 270.733411 -294.638342) (xy 270.703846 -294.677686) (xy 270.668353 -294.711778) (xy 270.62785 -294.739734)
			(xy 270.583388 -294.760832) (xy 270.536117 -294.774524) (xy 270.487262 -294.780456) (xy 270.438087 -294.778475)
			(xy 270.389868 -294.768631) (xy 270.343852 -294.751179) (xy 270.301231 -294.726572) (xy 270.26311 -294.695447)
			(xy 270.230475 -294.65861) (xy 270.204172 -294.617014) (xy 270.184881 -294.571738) (xy 270.173104 -294.523954)
			(xy 270.169144 -294.4749) (xy 269.830042 -294.4749) (xy 269.829547 -294.499507) (xy 269.821652 -294.548084)
			(xy 269.806068 -294.594765) (xy 269.783197 -294.638342) (xy 269.753632 -294.677686) (xy 269.718139 -294.711778)
			(xy 269.677636 -294.739734) (xy 269.633174 -294.760832) (xy 269.585903 -294.774524) (xy 269.537048 -294.780456)
			(xy 269.487873 -294.778475) (xy 269.439654 -294.768631) (xy 269.393638 -294.751179) (xy 269.351017 -294.726572)
			(xy 269.312896 -294.695447) (xy 269.280261 -294.65861) (xy 269.253958 -294.617014) (xy 269.234667 -294.571738)
			(xy 269.22289 -294.523954) (xy 269.21893 -294.4749) (xy 268.880082 -294.4749) (xy 268.879587 -294.499507)
			(xy 268.871692 -294.548084) (xy 268.856108 -294.594765) (xy 268.833237 -294.638342) (xy 268.803672 -294.677686)
			(xy 268.768179 -294.711778) (xy 268.727676 -294.739734) (xy 268.683214 -294.760832) (xy 268.635943 -294.774524)
			(xy 268.587088 -294.780456) (xy 268.537913 -294.778475) (xy 268.489694 -294.768631) (xy 268.443678 -294.751179)
			(xy 268.401057 -294.726572) (xy 268.362936 -294.695447) (xy 268.330301 -294.65861) (xy 268.303998 -294.617014)
			(xy 268.284707 -294.571738) (xy 268.27293 -294.523954) (xy 268.26897 -294.4749) (xy 260.226252 -294.4749)
			(xy 260.235387 -294.494387) (xy 260.251455 -294.547794) (xy 260.259575 -294.60297) (xy 260.260084 -294.630856)
			(xy 260.259575 -294.658742) (xy 260.251455 -294.713918) (xy 260.235387 -294.767325) (xy 260.211715 -294.817822)
			(xy 260.180942 -294.864335) (xy 260.143725 -294.905872) (xy 260.100857 -294.941547) (xy 260.053251 -294.970601)
			(xy 260.001922 -294.992413) (xy 259.947965 -295.006519) (xy 259.892528 -295.012619) (xy 259.836794 -295.010582)
			(xy 259.781951 -295.000452) (xy 259.729167 -294.982445) (xy 259.679567 -294.956944) (xy 259.634209 -294.924493)
			(xy 259.59406 -294.885784) (xy 259.559974 -294.841641) (xy 259.532678 -294.793006) (xy 259.512755 -294.740915)
			(xy 259.500629 -294.686478) (xy 259.496558 -294.630856) (xy 258.774946 -294.630856) (xy 258.774437 -294.658742)
			(xy 258.766317 -294.713918) (xy 258.750249 -294.767325) (xy 258.726577 -294.817822) (xy 258.695804 -294.864335)
			(xy 258.658587 -294.905872) (xy 258.615719 -294.941547) (xy 258.568113 -294.970601) (xy 258.516784 -294.992413)
			(xy 258.462827 -295.006519) (xy 258.40739 -295.012619) (xy 258.351656 -295.010582) (xy 258.296813 -295.000452)
			(xy 258.244029 -294.982445) (xy 258.194429 -294.956944) (xy 258.149071 -294.924493) (xy 258.108922 -294.885784)
			(xy 258.074836 -294.841641) (xy 258.04754 -294.793006) (xy 258.027617 -294.740915) (xy 258.015491 -294.686478)
			(xy 258.01142 -294.630856) (xy 254.328378 -294.630856) (xy 254.447714 -294.720706) (xy 254.574214 -294.82598)
			(xy 254.695438 -294.937288) (xy 254.811099 -295.054366) (xy 254.920922 -295.176936) (xy 255.024648 -295.304708)
			(xy 255.12203 -295.437379) (xy 255.212837 -295.574634) (xy 255.296853 -295.716147) (xy 255.37388 -295.861583)
			(xy 255.407413 -295.933114) (xy 258.01142 -295.933114) (xy 258.015491 -295.877492) (xy 258.027617 -295.823055)
			(xy 258.04754 -295.770964) (xy 258.074836 -295.722329) (xy 258.108922 -295.678186) (xy 258.149071 -295.639477)
			(xy 258.194429 -295.607026) (xy 258.244029 -295.581525) (xy 258.296813 -295.563518) (xy 258.351656 -295.553388)
			(xy 258.40739 -295.551351) (xy 258.462827 -295.557451) (xy 258.516784 -295.571557) (xy 258.568113 -295.593369)
			(xy 258.615719 -295.622423) (xy 258.658587 -295.658098) (xy 258.695804 -295.699635) (xy 258.726577 -295.746148)
			(xy 258.750249 -295.796645) (xy 258.766317 -295.850052) (xy 258.774437 -295.905228) (xy 258.774946 -295.933114)
			(xy 259.486906 -295.933114) (xy 259.490977 -295.877492) (xy 259.503103 -295.823055) (xy 259.523026 -295.770964)
			(xy 259.550322 -295.722329) (xy 259.584408 -295.678186) (xy 259.624557 -295.639477) (xy 259.669915 -295.607026)
			(xy 259.719515 -295.581525) (xy 259.772299 -295.563518) (xy 259.827142 -295.553388) (xy 259.882876 -295.551351)
			(xy 259.938313 -295.557451) (xy 259.99227 -295.571557) (xy 260.043599 -295.593369) (xy 260.091205 -295.622423)
			(xy 260.134073 -295.658098) (xy 260.17129 -295.699635) (xy 260.202063 -295.746148) (xy 260.225735 -295.796645)
			(xy 260.241803 -295.850052) (xy 260.249923 -295.905228) (xy 260.250432 -295.933114) (xy 260.375906 -295.933114)
			(xy 260.379977 -295.877492) (xy 260.392103 -295.823055) (xy 260.412026 -295.770964) (xy 260.439322 -295.722329)
			(xy 260.473408 -295.678186) (xy 260.513557 -295.639477) (xy 260.558915 -295.607026) (xy 260.608515 -295.581525)
			(xy 260.661299 -295.563518) (xy 260.716142 -295.553388) (xy 260.771876 -295.551351) (xy 260.827313 -295.557451)
			(xy 260.88127 -295.571557) (xy 260.932599 -295.593369) (xy 260.980205 -295.622423) (xy 261.023073 -295.658098)
			(xy 261.06029 -295.699635) (xy 261.091063 -295.746148) (xy 261.114735 -295.796645) (xy 261.130803 -295.850052)
			(xy 261.138923 -295.905228) (xy 261.139432 -295.933114) (xy 261.138923 -295.961) (xy 261.130803 -296.016176)
			(xy 261.114735 -296.069583) (xy 261.091063 -296.12008) (xy 261.06029 -296.166593) (xy 261.023073 -296.20813)
			(xy 260.980205 -296.243805) (xy 260.932599 -296.272859) (xy 260.88127 -296.294671) (xy 260.827313 -296.308777)
			(xy 260.771876 -296.314877) (xy 260.716142 -296.31284) (xy 260.661299 -296.30271) (xy 260.608515 -296.284703)
			(xy 260.558915 -296.259202) (xy 260.513557 -296.226751) (xy 260.473408 -296.188042) (xy 260.439322 -296.143899)
			(xy 260.412026 -296.095264) (xy 260.392103 -296.043173) (xy 260.379977 -295.988736) (xy 260.375906 -295.933114)
			(xy 260.250432 -295.933114) (xy 260.249923 -295.961) (xy 260.241803 -296.016176) (xy 260.225735 -296.069583)
			(xy 260.202063 -296.12008) (xy 260.17129 -296.166593) (xy 260.134073 -296.20813) (xy 260.091205 -296.243805)
			(xy 260.043599 -296.272859) (xy 259.99227 -296.294671) (xy 259.938313 -296.308777) (xy 259.882876 -296.314877)
			(xy 259.827142 -296.31284) (xy 259.772299 -296.30271) (xy 259.719515 -296.284703) (xy 259.669915 -296.259202)
			(xy 259.624557 -296.226751) (xy 259.584408 -296.188042) (xy 259.550322 -296.143899) (xy 259.523026 -296.095264)
			(xy 259.503103 -296.043173) (xy 259.490977 -295.988736) (xy 259.486906 -295.933114) (xy 258.774946 -295.933114)
			(xy 258.774437 -295.961) (xy 258.766317 -296.016176) (xy 258.750249 -296.069583) (xy 258.726577 -296.12008)
			(xy 258.695804 -296.166593) (xy 258.658587 -296.20813) (xy 258.615719 -296.243805) (xy 258.568113 -296.272859)
			(xy 258.516784 -296.294671) (xy 258.462827 -296.308777) (xy 258.40739 -296.314877) (xy 258.351656 -296.31284)
			(xy 258.296813 -296.30271) (xy 258.244029 -296.284703) (xy 258.194429 -296.259202) (xy 258.149071 -296.226751)
			(xy 258.108922 -296.188042) (xy 258.074836 -296.143899) (xy 258.04754 -296.095264) (xy 258.027617 -296.043173)
			(xy 258.015491 -295.988736) (xy 258.01142 -295.933114) (xy 255.407413 -295.933114) (xy 255.443735 -296.010596)
			(xy 255.506252 -296.162834) (xy 255.561282 -296.317935) (xy 255.608696 -296.475532) (xy 255.64838 -296.63525)
			(xy 255.660193 -296.695114) (xy 263.537954 -296.695114) (xy 263.53852 -296.665733) (xy 263.547548 -296.607668)
			(xy 263.565376 -296.551675) (xy 263.591583 -296.49908) (xy 263.625547 -296.451128) (xy 263.666466 -296.408954)
			(xy 263.689592 -296.390822) (xy 263.69899 -296.383456) (xy 263.709404 -296.362882) (xy 263.710928 -296.258996)
			(xy 263.701022 -296.237914) (xy 263.691878 -296.230548) (xy 263.670018 -296.212356) (xy 263.63148 -296.170533)
			(xy 263.599575 -296.123455) (xy 263.57501 -296.072163) (xy 263.558329 -296.017793) (xy 263.549902 -295.96155)
			(xy 263.549384 -295.933114) (xy 263.54987 -295.905863) (xy 263.557626 -295.851915) (xy 263.572981 -295.79962)
			(xy 263.595623 -295.750043) (xy 263.625089 -295.704193) (xy 263.66078 -295.663002) (xy 263.701971 -295.627311)
			(xy 263.747821 -295.597845) (xy 263.797398 -295.575203) (xy 263.849693 -295.559848) (xy 263.903641 -295.552092)
			(xy 263.958143 -295.552092) (xy 264.012091 -295.559848) (xy 264.064386 -295.575203) (xy 264.113963 -295.597845)
			(xy 264.159813 -295.627311) (xy 264.201004 -295.663002) (xy 264.236695 -295.704193) (xy 264.266161 -295.750043)
			(xy 264.288803 -295.79962) (xy 264.304158 -295.851915) (xy 264.311914 -295.905863) (xy 264.3124 -295.933114)
			(xy 264.311872 -295.962497) (xy 264.302839 -296.020564) (xy 264.285005 -296.076559) (xy 264.258791 -296.129154)
			(xy 264.224818 -296.177105) (xy 264.183891 -296.219276) (xy 264.160762 -296.237406) (xy 264.151364 -296.244772)
			(xy 264.14095 -296.265346) (xy 264.139426 -296.369232) (xy 264.149332 -296.390314) (xy 264.158476 -296.39768)
			(xy 264.180292 -296.415923) (xy 264.218835 -296.457733) (xy 264.250747 -296.504801) (xy 264.275319 -296.556084)
			(xy 264.292009 -296.610445) (xy 264.300447 -296.666681) (xy 264.30097 -296.695114) (xy 264.934444 -296.695114)
			(xy 264.938515 -296.639492) (xy 264.950641 -296.585055) (xy 264.970564 -296.532964) (xy 264.99786 -296.484329)
			(xy 265.031946 -296.440186) (xy 265.072095 -296.401477) (xy 265.117453 -296.369026) (xy 265.167053 -296.343525)
			(xy 265.219837 -296.325518) (xy 265.27468 -296.315388) (xy 265.330414 -296.313351) (xy 265.385851 -296.319451)
			(xy 265.439808 -296.333557) (xy 265.491137 -296.355369) (xy 265.538743 -296.384423) (xy 265.581611 -296.420098)
			(xy 265.618828 -296.461635) (xy 265.649601 -296.508148) (xy 265.673273 -296.558645) (xy 265.689341 -296.612052)
			(xy 265.697461 -296.667228) (xy 265.69797 -296.695114) (xy 265.820904 -296.695114) (xy 265.824975 -296.639492)
			(xy 265.837101 -296.585055) (xy 265.857024 -296.532964) (xy 265.88432 -296.484329) (xy 265.918406 -296.440186)
			(xy 265.958555 -296.401477) (xy 266.003913 -296.369026) (xy 266.053513 -296.343525) (xy 266.106297 -296.325518)
			(xy 266.16114 -296.315388) (xy 266.216874 -296.313351) (xy 266.272311 -296.319451) (xy 266.326268 -296.333557)
			(xy 266.377597 -296.355369) (xy 266.409468 -296.37482) (xy 269.219184 -296.37482) (xy 269.223144 -296.325766)
			(xy 269.234921 -296.277982) (xy 269.254212 -296.232706) (xy 269.280515 -296.19111) (xy 269.31315 -296.154273)
			(xy 269.351271 -296.123148) (xy 269.393892 -296.098541) (xy 269.439908 -296.081089) (xy 269.488127 -296.071245)
			(xy 269.537302 -296.069264) (xy 269.586157 -296.075196) (xy 269.633428 -296.088888) (xy 269.67789 -296.109986)
			(xy 269.718393 -296.137942) (xy 269.753886 -296.172034) (xy 269.783451 -296.211378) (xy 269.806322 -296.254955)
			(xy 269.821906 -296.301636) (xy 269.829801 -296.350213) (xy 269.830296 -296.37482) (xy 270.16889 -296.37482)
			(xy 270.17285 -296.325766) (xy 270.184627 -296.277982) (xy 270.203918 -296.232706) (xy 270.230221 -296.19111)
			(xy 270.262856 -296.154273) (xy 270.300977 -296.123148) (xy 270.343598 -296.098541) (xy 270.389614 -296.081089)
			(xy 270.437833 -296.071245) (xy 270.487008 -296.069264) (xy 270.535863 -296.075196) (xy 270.583134 -296.088888)
			(xy 270.627596 -296.109986) (xy 270.668099 -296.137942) (xy 270.703592 -296.172034) (xy 270.733157 -296.211378)
			(xy 270.756028 -296.254955) (xy 270.771612 -296.301636) (xy 270.779507 -296.350213) (xy 270.780002 -296.37482)
			(xy 271.119104 -296.37482) (xy 271.123064 -296.325766) (xy 271.134841 -296.277982) (xy 271.154132 -296.232706)
			(xy 271.180435 -296.19111) (xy 271.21307 -296.154273) (xy 271.251191 -296.123148) (xy 271.293812 -296.098541)
			(xy 271.339828 -296.081089) (xy 271.388047 -296.071245) (xy 271.437222 -296.069264) (xy 271.486077 -296.075196)
			(xy 271.533348 -296.088888) (xy 271.57781 -296.109986) (xy 271.618313 -296.137942) (xy 271.653806 -296.172034)
			(xy 271.683371 -296.211378) (xy 271.706242 -296.254955) (xy 271.721826 -296.301636) (xy 271.729721 -296.350213)
			(xy 271.730216 -296.37482) (xy 272.069064 -296.37482) (xy 272.073024 -296.325766) (xy 272.084801 -296.277982)
			(xy 272.104092 -296.232706) (xy 272.130395 -296.19111) (xy 272.16303 -296.154273) (xy 272.201151 -296.123148)
			(xy 272.243772 -296.098541) (xy 272.289788 -296.081089) (xy 272.338007 -296.071245) (xy 272.387182 -296.069264)
			(xy 272.436037 -296.075196) (xy 272.483308 -296.088888) (xy 272.52777 -296.109986) (xy 272.568273 -296.137942)
			(xy 272.603766 -296.172034) (xy 272.633331 -296.211378) (xy 272.656202 -296.254955) (xy 272.671786 -296.301636)
			(xy 272.679681 -296.350213) (xy 272.680176 -296.37482) (xy 273.968984 -296.37482) (xy 273.972944 -296.325766)
			(xy 273.984721 -296.277982) (xy 274.004012 -296.232706) (xy 274.030315 -296.19111) (xy 274.06295 -296.154273)
			(xy 274.101071 -296.123148) (xy 274.143692 -296.098541) (xy 274.189708 -296.081089) (xy 274.237927 -296.071245)
			(xy 274.287102 -296.069264) (xy 274.335957 -296.075196) (xy 274.383228 -296.088888) (xy 274.42769 -296.109986)
			(xy 274.468193 -296.137942) (xy 274.503686 -296.172034) (xy 274.533251 -296.211378) (xy 274.556122 -296.254955)
			(xy 274.571706 -296.301636) (xy 274.579601 -296.350213) (xy 274.580096 -296.37482) (xy 275.868904 -296.37482)
			(xy 275.872864 -296.325766) (xy 275.884641 -296.277982) (xy 275.903932 -296.232706) (xy 275.930235 -296.19111)
			(xy 275.96287 -296.154273) (xy 276.000991 -296.123148) (xy 276.043612 -296.098541) (xy 276.089628 -296.081089)
			(xy 276.137847 -296.071245) (xy 276.187022 -296.069264) (xy 276.235877 -296.075196) (xy 276.283148 -296.088888)
			(xy 276.32761 -296.109986) (xy 276.368113 -296.137942) (xy 276.403606 -296.172034) (xy 276.433171 -296.211378)
			(xy 276.456042 -296.254955) (xy 276.471626 -296.301636) (xy 276.479521 -296.350213) (xy 276.480016 -296.37482)
			(xy 276.819118 -296.37482) (xy 276.823078 -296.325766) (xy 276.834855 -296.277982) (xy 276.854146 -296.232706)
			(xy 276.880449 -296.19111) (xy 276.913084 -296.154273) (xy 276.951205 -296.123148) (xy 276.993826 -296.098541)
			(xy 277.039842 -296.081089) (xy 277.088061 -296.071245) (xy 277.137236 -296.069264) (xy 277.186091 -296.075196)
			(xy 277.233362 -296.088888) (xy 277.277824 -296.109986) (xy 277.318327 -296.137942) (xy 277.35382 -296.172034)
			(xy 277.383385 -296.211378) (xy 277.406256 -296.254955) (xy 277.42184 -296.301636) (xy 277.429735 -296.350213)
			(xy 277.43023 -296.37482) (xy 277.769078 -296.37482) (xy 277.773038 -296.325766) (xy 277.784815 -296.277982)
			(xy 277.804106 -296.232706) (xy 277.830409 -296.19111) (xy 277.863044 -296.154273) (xy 277.901165 -296.123148)
			(xy 277.943786 -296.098541) (xy 277.989802 -296.081089) (xy 278.038021 -296.071245) (xy 278.087196 -296.069264)
			(xy 278.136051 -296.075196) (xy 278.183322 -296.088888) (xy 278.227784 -296.109986) (xy 278.268287 -296.137942)
			(xy 278.30378 -296.172034) (xy 278.333345 -296.211378) (xy 278.356216 -296.254955) (xy 278.3718 -296.301636)
			(xy 278.379695 -296.350213) (xy 278.38019 -296.37482) (xy 279.668998 -296.37482) (xy 279.672958 -296.325766)
			(xy 279.684735 -296.277982) (xy 279.704026 -296.232706) (xy 279.730329 -296.19111) (xy 279.762964 -296.154273)
			(xy 279.801085 -296.123148) (xy 279.843706 -296.098541) (xy 279.889722 -296.081089) (xy 279.937941 -296.071245)
			(xy 279.987116 -296.069264) (xy 280.035971 -296.075196) (xy 280.083242 -296.088888) (xy 280.127704 -296.109986)
			(xy 280.168207 -296.137942) (xy 280.2037 -296.172034) (xy 280.233265 -296.211378) (xy 280.256136 -296.254955)
			(xy 280.27172 -296.301636) (xy 280.279615 -296.350213) (xy 280.28011 -296.37482) (xy 280.618958 -296.37482)
			(xy 280.622918 -296.325766) (xy 280.634695 -296.277982) (xy 280.653986 -296.232706) (xy 280.680289 -296.19111)
			(xy 280.712924 -296.154273) (xy 280.751045 -296.123148) (xy 280.793666 -296.098541) (xy 280.839682 -296.081089)
			(xy 280.887901 -296.071245) (xy 280.937076 -296.069264) (xy 280.985931 -296.075196) (xy 281.033202 -296.088888)
			(xy 281.077664 -296.109986) (xy 281.118167 -296.137942) (xy 281.15366 -296.172034) (xy 281.183225 -296.211378)
			(xy 281.206096 -296.254955) (xy 281.22168 -296.301636) (xy 281.229575 -296.350213) (xy 281.23007 -296.37482)
			(xy 281.568918 -296.37482) (xy 281.572878 -296.325766) (xy 281.584655 -296.277982) (xy 281.603946 -296.232706)
			(xy 281.630249 -296.19111) (xy 281.662884 -296.154273) (xy 281.701005 -296.123148) (xy 281.743626 -296.098541)
			(xy 281.789642 -296.081089) (xy 281.837861 -296.071245) (xy 281.887036 -296.069264) (xy 281.935891 -296.075196)
			(xy 281.983162 -296.088888) (xy 282.027624 -296.109986) (xy 282.068127 -296.137942) (xy 282.10362 -296.172034)
			(xy 282.133185 -296.211378) (xy 282.156056 -296.254955) (xy 282.17164 -296.301636) (xy 282.179535 -296.350213)
			(xy 282.18003 -296.37482) (xy 282.519132 -296.37482) (xy 282.523092 -296.325766) (xy 282.534869 -296.277982)
			(xy 282.55416 -296.232706) (xy 282.580463 -296.19111) (xy 282.613098 -296.154273) (xy 282.651219 -296.123148)
			(xy 282.69384 -296.098541) (xy 282.739856 -296.081089) (xy 282.788075 -296.071245) (xy 282.83725 -296.069264)
			(xy 282.886105 -296.075196) (xy 282.933376 -296.088888) (xy 282.977838 -296.109986) (xy 283.018341 -296.137942)
			(xy 283.053834 -296.172034) (xy 283.083399 -296.211378) (xy 283.10627 -296.254955) (xy 283.121854 -296.301636)
			(xy 283.129749 -296.350213) (xy 283.130244 -296.37482) (xy 283.469092 -296.37482) (xy 283.473052 -296.325766)
			(xy 283.484829 -296.277982) (xy 283.50412 -296.232706) (xy 283.530423 -296.19111) (xy 283.563058 -296.154273)
			(xy 283.601179 -296.123148) (xy 283.6438 -296.098541) (xy 283.689816 -296.081089) (xy 283.738035 -296.071245)
			(xy 283.78721 -296.069264) (xy 283.836065 -296.075196) (xy 283.883336 -296.088888) (xy 283.927798 -296.109986)
			(xy 283.968301 -296.137942) (xy 284.003794 -296.172034) (xy 284.033359 -296.211378) (xy 284.05623 -296.254955)
			(xy 284.071814 -296.301636) (xy 284.079709 -296.350213) (xy 284.080204 -296.37482) (xy 284.419052 -296.37482)
			(xy 284.423012 -296.325766) (xy 284.434789 -296.277982) (xy 284.45408 -296.232706) (xy 284.480383 -296.19111)
			(xy 284.513018 -296.154273) (xy 284.551139 -296.123148) (xy 284.59376 -296.098541) (xy 284.639776 -296.081089)
			(xy 284.687995 -296.071245) (xy 284.73717 -296.069264) (xy 284.786025 -296.075196) (xy 284.833296 -296.088888)
			(xy 284.877758 -296.109986) (xy 284.918261 -296.137942) (xy 284.953754 -296.172034) (xy 284.983319 -296.211378)
			(xy 285.00619 -296.254955) (xy 285.021774 -296.301636) (xy 285.029669 -296.350213) (xy 285.030164 -296.37482)
			(xy 285.369012 -296.37482) (xy 285.372972 -296.325766) (xy 285.384749 -296.277982) (xy 285.40404 -296.232706)
			(xy 285.430343 -296.19111) (xy 285.462978 -296.154273) (xy 285.501099 -296.123148) (xy 285.54372 -296.098541)
			(xy 285.589736 -296.081089) (xy 285.637955 -296.071245) (xy 285.68713 -296.069264) (xy 285.735985 -296.075196)
			(xy 285.783256 -296.088888) (xy 285.827718 -296.109986) (xy 285.868221 -296.137942) (xy 285.903714 -296.172034)
			(xy 285.933279 -296.211378) (xy 285.95615 -296.254955) (xy 285.971734 -296.301636) (xy 285.979629 -296.350213)
			(xy 285.980124 -296.37482) (xy 286.318972 -296.37482) (xy 286.322932 -296.325766) (xy 286.334709 -296.277982)
			(xy 286.354 -296.232706) (xy 286.380303 -296.19111) (xy 286.412938 -296.154273) (xy 286.451059 -296.123148)
			(xy 286.49368 -296.098541) (xy 286.539696 -296.081089) (xy 286.587915 -296.071245) (xy 286.63709 -296.069264)
			(xy 286.685945 -296.075196) (xy 286.733216 -296.088888) (xy 286.777678 -296.109986) (xy 286.818181 -296.137942)
			(xy 286.853674 -296.172034) (xy 286.883239 -296.211378) (xy 286.90611 -296.254955) (xy 286.921694 -296.301636)
			(xy 286.929589 -296.350213) (xy 286.930084 -296.37482) (xy 287.268932 -296.37482) (xy 287.272892 -296.325766)
			(xy 287.284669 -296.277982) (xy 287.30396 -296.232706) (xy 287.330263 -296.19111) (xy 287.362898 -296.154273)
			(xy 287.401019 -296.123148) (xy 287.44364 -296.098541) (xy 287.489656 -296.081089) (xy 287.537875 -296.071245)
			(xy 287.58705 -296.069264) (xy 287.635905 -296.075196) (xy 287.683176 -296.088888) (xy 287.727638 -296.109986)
			(xy 287.768141 -296.137942) (xy 287.803634 -296.172034) (xy 287.833199 -296.211378) (xy 287.85607 -296.254955)
			(xy 287.871654 -296.301636) (xy 287.879549 -296.350213) (xy 287.880044 -296.37482) (xy 288.219146 -296.37482)
			(xy 288.223106 -296.325766) (xy 288.234883 -296.277982) (xy 288.254174 -296.232706) (xy 288.280477 -296.19111)
			(xy 288.313112 -296.154273) (xy 288.351233 -296.123148) (xy 288.393854 -296.098541) (xy 288.43987 -296.081089)
			(xy 288.488089 -296.071245) (xy 288.537264 -296.069264) (xy 288.586119 -296.075196) (xy 288.63339 -296.088888)
			(xy 288.677852 -296.109986) (xy 288.718355 -296.137942) (xy 288.753848 -296.172034) (xy 288.783413 -296.211378)
			(xy 288.806284 -296.254955) (xy 288.821868 -296.301636) (xy 288.829763 -296.350213) (xy 288.830258 -296.37482)
			(xy 289.169106 -296.37482) (xy 289.173066 -296.325766) (xy 289.184843 -296.277982) (xy 289.204134 -296.232706)
			(xy 289.230437 -296.19111) (xy 289.263072 -296.154273) (xy 289.301193 -296.123148) (xy 289.343814 -296.098541)
			(xy 289.38983 -296.081089) (xy 289.438049 -296.071245) (xy 289.487224 -296.069264) (xy 289.536079 -296.075196)
			(xy 289.58335 -296.088888) (xy 289.627812 -296.109986) (xy 289.668315 -296.137942) (xy 289.703808 -296.172034)
			(xy 289.733373 -296.211378) (xy 289.756244 -296.254955) (xy 289.771828 -296.301636) (xy 289.779723 -296.350213)
			(xy 289.780218 -296.37482) (xy 290.119066 -296.37482) (xy 290.123026 -296.325766) (xy 290.134803 -296.277982)
			(xy 290.154094 -296.232706) (xy 290.180397 -296.19111) (xy 290.213032 -296.154273) (xy 290.251153 -296.123148)
			(xy 290.293774 -296.098541) (xy 290.33979 -296.081089) (xy 290.388009 -296.071245) (xy 290.437184 -296.069264)
			(xy 290.486039 -296.075196) (xy 290.53331 -296.088888) (xy 290.577772 -296.109986) (xy 290.618275 -296.137942)
			(xy 290.653768 -296.172034) (xy 290.683333 -296.211378) (xy 290.706204 -296.254955) (xy 290.721788 -296.301636)
			(xy 290.729683 -296.350213) (xy 290.730178 -296.37482) (xy 292.018986 -296.37482) (xy 292.022946 -296.325766)
			(xy 292.034723 -296.277982) (xy 292.054014 -296.232706) (xy 292.080317 -296.19111) (xy 292.112952 -296.154273)
			(xy 292.151073 -296.123148) (xy 292.193694 -296.098541) (xy 292.23971 -296.081089) (xy 292.287929 -296.071245)
			(xy 292.337104 -296.069264) (xy 292.385959 -296.075196) (xy 292.43323 -296.088888) (xy 292.477692 -296.109986)
			(xy 292.518195 -296.137942) (xy 292.553688 -296.172034) (xy 292.583253 -296.211378) (xy 292.606124 -296.254955)
			(xy 292.621708 -296.301636) (xy 292.629603 -296.350213) (xy 292.630098 -296.37482) (xy 292.968946 -296.37482)
			(xy 292.972906 -296.325766) (xy 292.984683 -296.277982) (xy 293.003974 -296.232706) (xy 293.030277 -296.19111)
			(xy 293.062912 -296.154273) (xy 293.101033 -296.123148) (xy 293.143654 -296.098541) (xy 293.18967 -296.081089)
			(xy 293.237889 -296.071245) (xy 293.287064 -296.069264) (xy 293.335919 -296.075196) (xy 293.38319 -296.088888)
			(xy 293.427652 -296.109986) (xy 293.468155 -296.137942) (xy 293.503648 -296.172034) (xy 293.533213 -296.211378)
			(xy 293.556084 -296.254955) (xy 293.571668 -296.301636) (xy 293.579563 -296.350213) (xy 293.580058 -296.37482)
			(xy 293.918906 -296.37482) (xy 293.922866 -296.325766) (xy 293.934643 -296.277982) (xy 293.953934 -296.232706)
			(xy 293.980237 -296.19111) (xy 294.012872 -296.154273) (xy 294.050993 -296.123148) (xy 294.093614 -296.098541)
			(xy 294.13963 -296.081089) (xy 294.187849 -296.071245) (xy 294.237024 -296.069264) (xy 294.285879 -296.075196)
			(xy 294.33315 -296.088888) (xy 294.377612 -296.109986) (xy 294.418115 -296.137942) (xy 294.453608 -296.172034)
			(xy 294.483173 -296.211378) (xy 294.506044 -296.254955) (xy 294.521628 -296.301636) (xy 294.529523 -296.350213)
			(xy 294.530018 -296.37482) (xy 294.86912 -296.37482) (xy 294.87308 -296.325766) (xy 294.884857 -296.277982)
			(xy 294.904148 -296.232706) (xy 294.930451 -296.19111) (xy 294.963086 -296.154273) (xy 295.001207 -296.123148)
			(xy 295.043828 -296.098541) (xy 295.089844 -296.081089) (xy 295.138063 -296.071245) (xy 295.187238 -296.069264)
			(xy 295.236093 -296.075196) (xy 295.283364 -296.088888) (xy 295.327826 -296.109986) (xy 295.368329 -296.137942)
			(xy 295.403822 -296.172034) (xy 295.433387 -296.211378) (xy 295.456258 -296.254955) (xy 295.471842 -296.301636)
			(xy 295.479737 -296.350213) (xy 295.480232 -296.37482) (xy 295.81908 -296.37482) (xy 295.82304 -296.325766)
			(xy 295.834817 -296.277982) (xy 295.854108 -296.232706) (xy 295.880411 -296.19111) (xy 295.913046 -296.154273)
			(xy 295.951167 -296.123148) (xy 295.993788 -296.098541) (xy 296.039804 -296.081089) (xy 296.088023 -296.071245)
			(xy 296.137198 -296.069264) (xy 296.186053 -296.075196) (xy 296.233324 -296.088888) (xy 296.277786 -296.109986)
			(xy 296.318289 -296.137942) (xy 296.353782 -296.172034) (xy 296.383347 -296.211378) (xy 296.406218 -296.254955)
			(xy 296.421802 -296.301636) (xy 296.429697 -296.350213) (xy 296.430192 -296.37482) (xy 296.76904 -296.37482)
			(xy 296.773 -296.325766) (xy 296.784777 -296.277982) (xy 296.804068 -296.232706) (xy 296.830371 -296.19111)
			(xy 296.863006 -296.154273) (xy 296.901127 -296.123148) (xy 296.943748 -296.098541) (xy 296.989764 -296.081089)
			(xy 297.037983 -296.071245) (xy 297.087158 -296.069264) (xy 297.136013 -296.075196) (xy 297.183284 -296.088888)
			(xy 297.227746 -296.109986) (xy 297.268249 -296.137942) (xy 297.303742 -296.172034) (xy 297.333307 -296.211378)
			(xy 297.356178 -296.254955) (xy 297.371762 -296.301636) (xy 297.379657 -296.350213) (xy 297.380152 -296.37482)
			(xy 297.719 -296.37482) (xy 297.72296 -296.325766) (xy 297.734737 -296.277982) (xy 297.754028 -296.232706)
			(xy 297.780331 -296.19111) (xy 297.812966 -296.154273) (xy 297.851087 -296.123148) (xy 297.893708 -296.098541)
			(xy 297.939724 -296.081089) (xy 297.987943 -296.071245) (xy 298.037118 -296.069264) (xy 298.085973 -296.075196)
			(xy 298.133244 -296.088888) (xy 298.177706 -296.109986) (xy 298.218209 -296.137942) (xy 298.253702 -296.172034)
			(xy 298.283267 -296.211378) (xy 298.306138 -296.254955) (xy 298.321722 -296.301636) (xy 298.329617 -296.350213)
			(xy 298.330112 -296.37482) (xy 298.66896 -296.37482) (xy 298.67292 -296.325766) (xy 298.684697 -296.277982)
			(xy 298.703988 -296.232706) (xy 298.730291 -296.19111) (xy 298.762926 -296.154273) (xy 298.801047 -296.123148)
			(xy 298.843668 -296.098541) (xy 298.889684 -296.081089) (xy 298.937903 -296.071245) (xy 298.987078 -296.069264)
			(xy 299.035933 -296.075196) (xy 299.083204 -296.088888) (xy 299.127666 -296.109986) (xy 299.168169 -296.137942)
			(xy 299.203662 -296.172034) (xy 299.233227 -296.211378) (xy 299.256098 -296.254955) (xy 299.271682 -296.301636)
			(xy 299.279577 -296.350213) (xy 299.280072 -296.37482) (xy 299.61892 -296.37482) (xy 299.62288 -296.325766)
			(xy 299.634657 -296.277982) (xy 299.653948 -296.232706) (xy 299.680251 -296.19111) (xy 299.712886 -296.154273)
			(xy 299.751007 -296.123148) (xy 299.793628 -296.098541) (xy 299.839644 -296.081089) (xy 299.887863 -296.071245)
			(xy 299.937038 -296.069264) (xy 299.985893 -296.075196) (xy 300.033164 -296.088888) (xy 300.077626 -296.109986)
			(xy 300.118129 -296.137942) (xy 300.153622 -296.172034) (xy 300.183187 -296.211378) (xy 300.206058 -296.254955)
			(xy 300.221642 -296.301636) (xy 300.229537 -296.350213) (xy 300.230032 -296.37482) (xy 300.56888 -296.37482)
			(xy 300.57284 -296.325766) (xy 300.584617 -296.277982) (xy 300.603908 -296.232706) (xy 300.630211 -296.19111)
			(xy 300.662846 -296.154273) (xy 300.700967 -296.123148) (xy 300.743588 -296.098541) (xy 300.789604 -296.081089)
			(xy 300.837823 -296.071245) (xy 300.886998 -296.069264) (xy 300.935853 -296.075196) (xy 300.983124 -296.088888)
			(xy 301.027586 -296.109986) (xy 301.068089 -296.137942) (xy 301.103582 -296.172034) (xy 301.133147 -296.211378)
			(xy 301.156018 -296.254955) (xy 301.171602 -296.301636) (xy 301.179497 -296.350213) (xy 301.179992 -296.37482)
			(xy 301.519094 -296.37482) (xy 301.523054 -296.325766) (xy 301.534831 -296.277982) (xy 301.554122 -296.232706)
			(xy 301.580425 -296.19111) (xy 301.61306 -296.154273) (xy 301.651181 -296.123148) (xy 301.693802 -296.098541)
			(xy 301.739818 -296.081089) (xy 301.788037 -296.071245) (xy 301.837212 -296.069264) (xy 301.886067 -296.075196)
			(xy 301.933338 -296.088888) (xy 301.9778 -296.109986) (xy 302.018303 -296.137942) (xy 302.053796 -296.172034)
			(xy 302.083361 -296.211378) (xy 302.106232 -296.254955) (xy 302.121816 -296.301636) (xy 302.129711 -296.350213)
			(xy 302.130206 -296.37482) (xy 303.419014 -296.37482) (xy 303.422974 -296.325766) (xy 303.434751 -296.277982)
			(xy 303.454042 -296.232706) (xy 303.480345 -296.19111) (xy 303.51298 -296.154273) (xy 303.551101 -296.123148)
			(xy 303.593722 -296.098541) (xy 303.639738 -296.081089) (xy 303.687957 -296.071245) (xy 303.737132 -296.069264)
			(xy 303.785987 -296.075196) (xy 303.833258 -296.088888) (xy 303.87772 -296.109986) (xy 303.918223 -296.137942)
			(xy 303.953716 -296.172034) (xy 303.983281 -296.211378) (xy 304.006152 -296.254955) (xy 304.021736 -296.301636)
			(xy 304.029631 -296.350213) (xy 304.030126 -296.37482) (xy 304.368974 -296.37482) (xy 304.372934 -296.325766)
			(xy 304.384711 -296.277982) (xy 304.404002 -296.232706) (xy 304.430305 -296.19111) (xy 304.46294 -296.154273)
			(xy 304.501061 -296.123148) (xy 304.543682 -296.098541) (xy 304.589698 -296.081089) (xy 304.637917 -296.071245)
			(xy 304.687092 -296.069264) (xy 304.735947 -296.075196) (xy 304.783218 -296.088888) (xy 304.82768 -296.109986)
			(xy 304.868183 -296.137942) (xy 304.903676 -296.172034) (xy 304.933241 -296.211378) (xy 304.956112 -296.254955)
			(xy 304.971696 -296.301636) (xy 304.979591 -296.350213) (xy 304.980086 -296.37482) (xy 305.318934 -296.37482)
			(xy 305.322894 -296.325766) (xy 305.334671 -296.277982) (xy 305.353962 -296.232706) (xy 305.380265 -296.19111)
			(xy 305.4129 -296.154273) (xy 305.451021 -296.123148) (xy 305.493642 -296.098541) (xy 305.539658 -296.081089)
			(xy 305.587877 -296.071245) (xy 305.637052 -296.069264) (xy 305.685907 -296.075196) (xy 305.733178 -296.088888)
			(xy 305.77764 -296.109986) (xy 305.818143 -296.137942) (xy 305.853636 -296.172034) (xy 305.883201 -296.211378)
			(xy 305.906072 -296.254955) (xy 305.921656 -296.301636) (xy 305.929551 -296.350213) (xy 305.930046 -296.37482)
			(xy 306.268894 -296.37482) (xy 306.272854 -296.325766) (xy 306.284631 -296.277982) (xy 306.303922 -296.232706)
			(xy 306.330225 -296.19111) (xy 306.36286 -296.154273) (xy 306.400981 -296.123148) (xy 306.443602 -296.098541)
			(xy 306.489618 -296.081089) (xy 306.537837 -296.071245) (xy 306.587012 -296.069264) (xy 306.635867 -296.075196)
			(xy 306.683138 -296.088888) (xy 306.7276 -296.109986) (xy 306.768103 -296.137942) (xy 306.803596 -296.172034)
			(xy 306.833161 -296.211378) (xy 306.856032 -296.254955) (xy 306.871616 -296.301636) (xy 306.879511 -296.350213)
			(xy 306.880006 -296.37482) (xy 307.219108 -296.37482) (xy 307.223068 -296.325766) (xy 307.234845 -296.277982)
			(xy 307.254136 -296.232706) (xy 307.280439 -296.19111) (xy 307.313074 -296.154273) (xy 307.351195 -296.123148)
			(xy 307.393816 -296.098541) (xy 307.439832 -296.081089) (xy 307.488051 -296.071245) (xy 307.537226 -296.069264)
			(xy 307.586081 -296.075196) (xy 307.633352 -296.088888) (xy 307.677814 -296.109986) (xy 307.718317 -296.137942)
			(xy 307.75381 -296.172034) (xy 307.783375 -296.211378) (xy 307.806246 -296.254955) (xy 307.82183 -296.301636)
			(xy 307.829725 -296.350213) (xy 307.83022 -296.37482) (xy 308.169068 -296.37482) (xy 308.173028 -296.325766)
			(xy 308.184805 -296.277982) (xy 308.204096 -296.232706) (xy 308.230399 -296.19111) (xy 308.263034 -296.154273)
			(xy 308.301155 -296.123148) (xy 308.343776 -296.098541) (xy 308.389792 -296.081089) (xy 308.438011 -296.071245)
			(xy 308.487186 -296.069264) (xy 308.536041 -296.075196) (xy 308.583312 -296.088888) (xy 308.627774 -296.109986)
			(xy 308.668277 -296.137942) (xy 308.70377 -296.172034) (xy 308.733335 -296.211378) (xy 308.756206 -296.254955)
			(xy 308.77179 -296.301636) (xy 308.779685 -296.350213) (xy 308.78018 -296.37482) (xy 311.018948 -296.37482)
			(xy 311.022908 -296.325766) (xy 311.034685 -296.277982) (xy 311.053976 -296.232706) (xy 311.080279 -296.19111)
			(xy 311.112914 -296.154273) (xy 311.151035 -296.123148) (xy 311.193656 -296.098541) (xy 311.239672 -296.081089)
			(xy 311.287891 -296.071245) (xy 311.337066 -296.069264) (xy 311.385921 -296.075196) (xy 311.433192 -296.088888)
			(xy 311.477654 -296.109986) (xy 311.518157 -296.137942) (xy 311.55365 -296.172034) (xy 311.583215 -296.211378)
			(xy 311.606086 -296.254955) (xy 311.62167 -296.301636) (xy 311.629565 -296.350213) (xy 311.63006 -296.37482)
			(xy 311.968908 -296.37482) (xy 311.972868 -296.325766) (xy 311.984645 -296.277982) (xy 312.003936 -296.232706)
			(xy 312.030239 -296.19111) (xy 312.062874 -296.154273) (xy 312.100995 -296.123148) (xy 312.143616 -296.098541)
			(xy 312.189632 -296.081089) (xy 312.237851 -296.071245) (xy 312.287026 -296.069264) (xy 312.335881 -296.075196)
			(xy 312.383152 -296.088888) (xy 312.427614 -296.109986) (xy 312.468117 -296.137942) (xy 312.50361 -296.172034)
			(xy 312.533175 -296.211378) (xy 312.556046 -296.254955) (xy 312.57163 -296.301636) (xy 312.579525 -296.350213)
			(xy 312.58002 -296.37482) (xy 312.919122 -296.37482) (xy 312.923082 -296.325766) (xy 312.934859 -296.277982)
			(xy 312.95415 -296.232706) (xy 312.980453 -296.19111) (xy 313.013088 -296.154273) (xy 313.051209 -296.123148)
			(xy 313.09383 -296.098541) (xy 313.139846 -296.081089) (xy 313.188065 -296.071245) (xy 313.23724 -296.069264)
			(xy 313.286095 -296.075196) (xy 313.333366 -296.088888) (xy 313.377828 -296.109986) (xy 313.418331 -296.137942)
			(xy 313.453824 -296.172034) (xy 313.483389 -296.211378) (xy 313.50626 -296.254955) (xy 313.521844 -296.301636)
			(xy 313.529739 -296.350213) (xy 313.530234 -296.37482) (xy 313.869082 -296.37482) (xy 313.873042 -296.325766)
			(xy 313.884819 -296.277982) (xy 313.90411 -296.232706) (xy 313.930413 -296.19111) (xy 313.963048 -296.154273)
			(xy 314.001169 -296.123148) (xy 314.04379 -296.098541) (xy 314.089806 -296.081089) (xy 314.138025 -296.071245)
			(xy 314.1872 -296.069264) (xy 314.236055 -296.075196) (xy 314.283326 -296.088888) (xy 314.327788 -296.109986)
			(xy 314.368291 -296.137942) (xy 314.403784 -296.172034) (xy 314.433349 -296.211378) (xy 314.45622 -296.254955)
			(xy 314.471804 -296.301636) (xy 314.479699 -296.350213) (xy 314.480194 -296.37482) (xy 314.819042 -296.37482)
			(xy 314.823002 -296.325766) (xy 314.834779 -296.277982) (xy 314.85407 -296.232706) (xy 314.880373 -296.19111)
			(xy 314.913008 -296.154273) (xy 314.951129 -296.123148) (xy 314.99375 -296.098541) (xy 315.039766 -296.081089)
			(xy 315.087985 -296.071245) (xy 315.13716 -296.069264) (xy 315.186015 -296.075196) (xy 315.233286 -296.088888)
			(xy 315.277748 -296.109986) (xy 315.318251 -296.137942) (xy 315.353744 -296.172034) (xy 315.383309 -296.211378)
			(xy 315.40618 -296.254955) (xy 315.421764 -296.301636) (xy 315.429659 -296.350213) (xy 315.430154 -296.37482)
			(xy 315.429659 -296.399427) (xy 315.421764 -296.448004) (xy 315.40618 -296.494685) (xy 315.383309 -296.538262)
			(xy 315.353744 -296.577606) (xy 315.318251 -296.611698) (xy 315.277748 -296.639654) (xy 315.233286 -296.660752)
			(xy 315.186015 -296.674444) (xy 315.13716 -296.680376) (xy 315.087985 -296.678395) (xy 315.039766 -296.668551)
			(xy 314.99375 -296.651099) (xy 314.951129 -296.626492) (xy 314.913008 -296.595367) (xy 314.880373 -296.55853)
			(xy 314.85407 -296.516934) (xy 314.834779 -296.471658) (xy 314.823002 -296.423874) (xy 314.819042 -296.37482)
			(xy 314.480194 -296.37482) (xy 314.479699 -296.399427) (xy 314.471804 -296.448004) (xy 314.45622 -296.494685)
			(xy 314.433349 -296.538262) (xy 314.403784 -296.577606) (xy 314.368291 -296.611698) (xy 314.327788 -296.639654)
			(xy 314.283326 -296.660752) (xy 314.236055 -296.674444) (xy 314.1872 -296.680376) (xy 314.138025 -296.678395)
			(xy 314.089806 -296.668551) (xy 314.04379 -296.651099) (xy 314.001169 -296.626492) (xy 313.963048 -296.595367)
			(xy 313.930413 -296.55853) (xy 313.90411 -296.516934) (xy 313.884819 -296.471658) (xy 313.873042 -296.423874)
			(xy 313.869082 -296.37482) (xy 313.530234 -296.37482) (xy 313.529739 -296.399427) (xy 313.521844 -296.448004)
			(xy 313.50626 -296.494685) (xy 313.483389 -296.538262) (xy 313.453824 -296.577606) (xy 313.418331 -296.611698)
			(xy 313.377828 -296.639654) (xy 313.333366 -296.660752) (xy 313.286095 -296.674444) (xy 313.23724 -296.680376)
			(xy 313.188065 -296.678395) (xy 313.139846 -296.668551) (xy 313.09383 -296.651099) (xy 313.051209 -296.626492)
			(xy 313.013088 -296.595367) (xy 312.980453 -296.55853) (xy 312.95415 -296.516934) (xy 312.934859 -296.471658)
			(xy 312.923082 -296.423874) (xy 312.919122 -296.37482) (xy 312.58002 -296.37482) (xy 312.579525 -296.399427)
			(xy 312.57163 -296.448004) (xy 312.556046 -296.494685) (xy 312.533175 -296.538262) (xy 312.50361 -296.577606)
			(xy 312.468117 -296.611698) (xy 312.427614 -296.639654) (xy 312.383152 -296.660752) (xy 312.335881 -296.674444)
			(xy 312.287026 -296.680376) (xy 312.237851 -296.678395) (xy 312.189632 -296.668551) (xy 312.143616 -296.651099)
			(xy 312.100995 -296.626492) (xy 312.062874 -296.595367) (xy 312.030239 -296.55853) (xy 312.003936 -296.516934)
			(xy 311.984645 -296.471658) (xy 311.972868 -296.423874) (xy 311.968908 -296.37482) (xy 311.63006 -296.37482)
			(xy 311.629565 -296.399427) (xy 311.62167 -296.448004) (xy 311.606086 -296.494685) (xy 311.583215 -296.538262)
			(xy 311.55365 -296.577606) (xy 311.518157 -296.611698) (xy 311.477654 -296.639654) (xy 311.433192 -296.660752)
			(xy 311.385921 -296.674444) (xy 311.337066 -296.680376) (xy 311.287891 -296.678395) (xy 311.239672 -296.668551)
			(xy 311.193656 -296.651099) (xy 311.151035 -296.626492) (xy 311.112914 -296.595367) (xy 311.080279 -296.55853)
			(xy 311.053976 -296.516934) (xy 311.034685 -296.471658) (xy 311.022908 -296.423874) (xy 311.018948 -296.37482)
			(xy 308.78018 -296.37482) (xy 308.779685 -296.399427) (xy 308.77179 -296.448004) (xy 308.756206 -296.494685)
			(xy 308.733335 -296.538262) (xy 308.70377 -296.577606) (xy 308.668277 -296.611698) (xy 308.627774 -296.639654)
			(xy 308.583312 -296.660752) (xy 308.536041 -296.674444) (xy 308.487186 -296.680376) (xy 308.438011 -296.678395)
			(xy 308.389792 -296.668551) (xy 308.343776 -296.651099) (xy 308.301155 -296.626492) (xy 308.263034 -296.595367)
			(xy 308.230399 -296.55853) (xy 308.204096 -296.516934) (xy 308.184805 -296.471658) (xy 308.173028 -296.423874)
			(xy 308.169068 -296.37482) (xy 307.83022 -296.37482) (xy 307.829725 -296.399427) (xy 307.82183 -296.448004)
			(xy 307.806246 -296.494685) (xy 307.783375 -296.538262) (xy 307.75381 -296.577606) (xy 307.718317 -296.611698)
			(xy 307.677814 -296.639654) (xy 307.633352 -296.660752) (xy 307.586081 -296.674444) (xy 307.537226 -296.680376)
			(xy 307.488051 -296.678395) (xy 307.439832 -296.668551) (xy 307.393816 -296.651099) (xy 307.351195 -296.626492)
			(xy 307.313074 -296.595367) (xy 307.280439 -296.55853) (xy 307.254136 -296.516934) (xy 307.234845 -296.471658)
			(xy 307.223068 -296.423874) (xy 307.219108 -296.37482) (xy 306.880006 -296.37482) (xy 306.879511 -296.399427)
			(xy 306.871616 -296.448004) (xy 306.856032 -296.494685) (xy 306.833161 -296.538262) (xy 306.803596 -296.577606)
			(xy 306.768103 -296.611698) (xy 306.7276 -296.639654) (xy 306.683138 -296.660752) (xy 306.635867 -296.674444)
			(xy 306.587012 -296.680376) (xy 306.537837 -296.678395) (xy 306.489618 -296.668551) (xy 306.443602 -296.651099)
			(xy 306.400981 -296.626492) (xy 306.36286 -296.595367) (xy 306.330225 -296.55853) (xy 306.303922 -296.516934)
			(xy 306.284631 -296.471658) (xy 306.272854 -296.423874) (xy 306.268894 -296.37482) (xy 305.930046 -296.37482)
			(xy 305.929551 -296.399427) (xy 305.921656 -296.448004) (xy 305.906072 -296.494685) (xy 305.883201 -296.538262)
			(xy 305.853636 -296.577606) (xy 305.818143 -296.611698) (xy 305.77764 -296.639654) (xy 305.733178 -296.660752)
			(xy 305.685907 -296.674444) (xy 305.637052 -296.680376) (xy 305.587877 -296.678395) (xy 305.539658 -296.668551)
			(xy 305.493642 -296.651099) (xy 305.451021 -296.626492) (xy 305.4129 -296.595367) (xy 305.380265 -296.55853)
			(xy 305.353962 -296.516934) (xy 305.334671 -296.471658) (xy 305.322894 -296.423874) (xy 305.318934 -296.37482)
			(xy 304.980086 -296.37482) (xy 304.979591 -296.399427) (xy 304.971696 -296.448004) (xy 304.956112 -296.494685)
			(xy 304.933241 -296.538262) (xy 304.903676 -296.577606) (xy 304.868183 -296.611698) (xy 304.82768 -296.639654)
			(xy 304.783218 -296.660752) (xy 304.735947 -296.674444) (xy 304.687092 -296.680376) (xy 304.637917 -296.678395)
			(xy 304.589698 -296.668551) (xy 304.543682 -296.651099) (xy 304.501061 -296.626492) (xy 304.46294 -296.595367)
			(xy 304.430305 -296.55853) (xy 304.404002 -296.516934) (xy 304.384711 -296.471658) (xy 304.372934 -296.423874)
			(xy 304.368974 -296.37482) (xy 304.030126 -296.37482) (xy 304.029631 -296.399427) (xy 304.021736 -296.448004)
			(xy 304.006152 -296.494685) (xy 303.983281 -296.538262) (xy 303.953716 -296.577606) (xy 303.918223 -296.611698)
			(xy 303.87772 -296.639654) (xy 303.833258 -296.660752) (xy 303.785987 -296.674444) (xy 303.737132 -296.680376)
			(xy 303.687957 -296.678395) (xy 303.639738 -296.668551) (xy 303.593722 -296.651099) (xy 303.551101 -296.626492)
			(xy 303.51298 -296.595367) (xy 303.480345 -296.55853) (xy 303.454042 -296.516934) (xy 303.434751 -296.471658)
			(xy 303.422974 -296.423874) (xy 303.419014 -296.37482) (xy 302.130206 -296.37482) (xy 302.129711 -296.399427)
			(xy 302.121816 -296.448004) (xy 302.106232 -296.494685) (xy 302.083361 -296.538262) (xy 302.053796 -296.577606)
			(xy 302.018303 -296.611698) (xy 301.9778 -296.639654) (xy 301.933338 -296.660752) (xy 301.886067 -296.674444)
			(xy 301.837212 -296.680376) (xy 301.788037 -296.678395) (xy 301.739818 -296.668551) (xy 301.693802 -296.651099)
			(xy 301.651181 -296.626492) (xy 301.61306 -296.595367) (xy 301.580425 -296.55853) (xy 301.554122 -296.516934)
			(xy 301.534831 -296.471658) (xy 301.523054 -296.423874) (xy 301.519094 -296.37482) (xy 301.179992 -296.37482)
			(xy 301.179497 -296.399427) (xy 301.171602 -296.448004) (xy 301.156018 -296.494685) (xy 301.133147 -296.538262)
			(xy 301.103582 -296.577606) (xy 301.068089 -296.611698) (xy 301.027586 -296.639654) (xy 300.983124 -296.660752)
			(xy 300.935853 -296.674444) (xy 300.886998 -296.680376) (xy 300.837823 -296.678395) (xy 300.789604 -296.668551)
			(xy 300.743588 -296.651099) (xy 300.700967 -296.626492) (xy 300.662846 -296.595367) (xy 300.630211 -296.55853)
			(xy 300.603908 -296.516934) (xy 300.584617 -296.471658) (xy 300.57284 -296.423874) (xy 300.56888 -296.37482)
			(xy 300.230032 -296.37482) (xy 300.229537 -296.399427) (xy 300.221642 -296.448004) (xy 300.206058 -296.494685)
			(xy 300.183187 -296.538262) (xy 300.153622 -296.577606) (xy 300.118129 -296.611698) (xy 300.077626 -296.639654)
			(xy 300.033164 -296.660752) (xy 299.985893 -296.674444) (xy 299.937038 -296.680376) (xy 299.887863 -296.678395)
			(xy 299.839644 -296.668551) (xy 299.793628 -296.651099) (xy 299.751007 -296.626492) (xy 299.712886 -296.595367)
			(xy 299.680251 -296.55853) (xy 299.653948 -296.516934) (xy 299.634657 -296.471658) (xy 299.62288 -296.423874)
			(xy 299.61892 -296.37482) (xy 299.280072 -296.37482) (xy 299.279577 -296.399427) (xy 299.271682 -296.448004)
			(xy 299.256098 -296.494685) (xy 299.233227 -296.538262) (xy 299.203662 -296.577606) (xy 299.168169 -296.611698)
			(xy 299.127666 -296.639654) (xy 299.083204 -296.660752) (xy 299.035933 -296.674444) (xy 298.987078 -296.680376)
			(xy 298.937903 -296.678395) (xy 298.889684 -296.668551) (xy 298.843668 -296.651099) (xy 298.801047 -296.626492)
			(xy 298.762926 -296.595367) (xy 298.730291 -296.55853) (xy 298.703988 -296.516934) (xy 298.684697 -296.471658)
			(xy 298.67292 -296.423874) (xy 298.66896 -296.37482) (xy 298.330112 -296.37482) (xy 298.329617 -296.399427)
			(xy 298.321722 -296.448004) (xy 298.306138 -296.494685) (xy 298.283267 -296.538262) (xy 298.253702 -296.577606)
			(xy 298.218209 -296.611698) (xy 298.177706 -296.639654) (xy 298.133244 -296.660752) (xy 298.085973 -296.674444)
			(xy 298.037118 -296.680376) (xy 297.987943 -296.678395) (xy 297.939724 -296.668551) (xy 297.893708 -296.651099)
			(xy 297.851087 -296.626492) (xy 297.812966 -296.595367) (xy 297.780331 -296.55853) (xy 297.754028 -296.516934)
			(xy 297.734737 -296.471658) (xy 297.72296 -296.423874) (xy 297.719 -296.37482) (xy 297.380152 -296.37482)
			(xy 297.379657 -296.399427) (xy 297.371762 -296.448004) (xy 297.356178 -296.494685) (xy 297.333307 -296.538262)
			(xy 297.303742 -296.577606) (xy 297.268249 -296.611698) (xy 297.227746 -296.639654) (xy 297.183284 -296.660752)
			(xy 297.136013 -296.674444) (xy 297.087158 -296.680376) (xy 297.037983 -296.678395) (xy 296.989764 -296.668551)
			(xy 296.943748 -296.651099) (xy 296.901127 -296.626492) (xy 296.863006 -296.595367) (xy 296.830371 -296.55853)
			(xy 296.804068 -296.516934) (xy 296.784777 -296.471658) (xy 296.773 -296.423874) (xy 296.76904 -296.37482)
			(xy 296.430192 -296.37482) (xy 296.429697 -296.399427) (xy 296.421802 -296.448004) (xy 296.406218 -296.494685)
			(xy 296.383347 -296.538262) (xy 296.353782 -296.577606) (xy 296.318289 -296.611698) (xy 296.277786 -296.639654)
			(xy 296.233324 -296.660752) (xy 296.186053 -296.674444) (xy 296.137198 -296.680376) (xy 296.088023 -296.678395)
			(xy 296.039804 -296.668551) (xy 295.993788 -296.651099) (xy 295.951167 -296.626492) (xy 295.913046 -296.595367)
			(xy 295.880411 -296.55853) (xy 295.854108 -296.516934) (xy 295.834817 -296.471658) (xy 295.82304 -296.423874)
			(xy 295.81908 -296.37482) (xy 295.480232 -296.37482) (xy 295.479737 -296.399427) (xy 295.471842 -296.448004)
			(xy 295.456258 -296.494685) (xy 295.433387 -296.538262) (xy 295.403822 -296.577606) (xy 295.368329 -296.611698)
			(xy 295.327826 -296.639654) (xy 295.283364 -296.660752) (xy 295.236093 -296.674444) (xy 295.187238 -296.680376)
			(xy 295.138063 -296.678395) (xy 295.089844 -296.668551) (xy 295.043828 -296.651099) (xy 295.001207 -296.626492)
			(xy 294.963086 -296.595367) (xy 294.930451 -296.55853) (xy 294.904148 -296.516934) (xy 294.884857 -296.471658)
			(xy 294.87308 -296.423874) (xy 294.86912 -296.37482) (xy 294.530018 -296.37482) (xy 294.529523 -296.399427)
			(xy 294.521628 -296.448004) (xy 294.506044 -296.494685) (xy 294.483173 -296.538262) (xy 294.453608 -296.577606)
			(xy 294.418115 -296.611698) (xy 294.377612 -296.639654) (xy 294.33315 -296.660752) (xy 294.285879 -296.674444)
			(xy 294.237024 -296.680376) (xy 294.187849 -296.678395) (xy 294.13963 -296.668551) (xy 294.093614 -296.651099)
			(xy 294.050993 -296.626492) (xy 294.012872 -296.595367) (xy 293.980237 -296.55853) (xy 293.953934 -296.516934)
			(xy 293.934643 -296.471658) (xy 293.922866 -296.423874) (xy 293.918906 -296.37482) (xy 293.580058 -296.37482)
			(xy 293.579563 -296.399427) (xy 293.571668 -296.448004) (xy 293.556084 -296.494685) (xy 293.533213 -296.538262)
			(xy 293.503648 -296.577606) (xy 293.468155 -296.611698) (xy 293.427652 -296.639654) (xy 293.38319 -296.660752)
			(xy 293.335919 -296.674444) (xy 293.287064 -296.680376) (xy 293.237889 -296.678395) (xy 293.18967 -296.668551)
			(xy 293.143654 -296.651099) (xy 293.101033 -296.626492) (xy 293.062912 -296.595367) (xy 293.030277 -296.55853)
			(xy 293.003974 -296.516934) (xy 292.984683 -296.471658) (xy 292.972906 -296.423874) (xy 292.968946 -296.37482)
			(xy 292.630098 -296.37482) (xy 292.629603 -296.399427) (xy 292.621708 -296.448004) (xy 292.606124 -296.494685)
			(xy 292.583253 -296.538262) (xy 292.553688 -296.577606) (xy 292.518195 -296.611698) (xy 292.477692 -296.639654)
			(xy 292.43323 -296.660752) (xy 292.385959 -296.674444) (xy 292.337104 -296.680376) (xy 292.287929 -296.678395)
			(xy 292.23971 -296.668551) (xy 292.193694 -296.651099) (xy 292.151073 -296.626492) (xy 292.112952 -296.595367)
			(xy 292.080317 -296.55853) (xy 292.054014 -296.516934) (xy 292.034723 -296.471658) (xy 292.022946 -296.423874)
			(xy 292.018986 -296.37482) (xy 290.730178 -296.37482) (xy 290.729683 -296.399427) (xy 290.721788 -296.448004)
			(xy 290.706204 -296.494685) (xy 290.683333 -296.538262) (xy 290.653768 -296.577606) (xy 290.618275 -296.611698)
			(xy 290.577772 -296.639654) (xy 290.53331 -296.660752) (xy 290.486039 -296.674444) (xy 290.437184 -296.680376)
			(xy 290.388009 -296.678395) (xy 290.33979 -296.668551) (xy 290.293774 -296.651099) (xy 290.251153 -296.626492)
			(xy 290.213032 -296.595367) (xy 290.180397 -296.55853) (xy 290.154094 -296.516934) (xy 290.134803 -296.471658)
			(xy 290.123026 -296.423874) (xy 290.119066 -296.37482) (xy 289.780218 -296.37482) (xy 289.779723 -296.399427)
			(xy 289.771828 -296.448004) (xy 289.756244 -296.494685) (xy 289.733373 -296.538262) (xy 289.703808 -296.577606)
			(xy 289.668315 -296.611698) (xy 289.627812 -296.639654) (xy 289.58335 -296.660752) (xy 289.536079 -296.674444)
			(xy 289.487224 -296.680376) (xy 289.438049 -296.678395) (xy 289.38983 -296.668551) (xy 289.343814 -296.651099)
			(xy 289.301193 -296.626492) (xy 289.263072 -296.595367) (xy 289.230437 -296.55853) (xy 289.204134 -296.516934)
			(xy 289.184843 -296.471658) (xy 289.173066 -296.423874) (xy 289.169106 -296.37482) (xy 288.830258 -296.37482)
			(xy 288.829763 -296.399427) (xy 288.821868 -296.448004) (xy 288.806284 -296.494685) (xy 288.783413 -296.538262)
			(xy 288.753848 -296.577606) (xy 288.718355 -296.611698) (xy 288.677852 -296.639654) (xy 288.63339 -296.660752)
			(xy 288.586119 -296.674444) (xy 288.537264 -296.680376) (xy 288.488089 -296.678395) (xy 288.43987 -296.668551)
			(xy 288.393854 -296.651099) (xy 288.351233 -296.626492) (xy 288.313112 -296.595367) (xy 288.280477 -296.55853)
			(xy 288.254174 -296.516934) (xy 288.234883 -296.471658) (xy 288.223106 -296.423874) (xy 288.219146 -296.37482)
			(xy 287.880044 -296.37482) (xy 287.879549 -296.399427) (xy 287.871654 -296.448004) (xy 287.85607 -296.494685)
			(xy 287.833199 -296.538262) (xy 287.803634 -296.577606) (xy 287.768141 -296.611698) (xy 287.727638 -296.639654)
			(xy 287.683176 -296.660752) (xy 287.635905 -296.674444) (xy 287.58705 -296.680376) (xy 287.537875 -296.678395)
			(xy 287.489656 -296.668551) (xy 287.44364 -296.651099) (xy 287.401019 -296.626492) (xy 287.362898 -296.595367)
			(xy 287.330263 -296.55853) (xy 287.30396 -296.516934) (xy 287.284669 -296.471658) (xy 287.272892 -296.423874)
			(xy 287.268932 -296.37482) (xy 286.930084 -296.37482) (xy 286.929589 -296.399427) (xy 286.921694 -296.448004)
			(xy 286.90611 -296.494685) (xy 286.883239 -296.538262) (xy 286.853674 -296.577606) (xy 286.818181 -296.611698)
			(xy 286.777678 -296.639654) (xy 286.733216 -296.660752) (xy 286.685945 -296.674444) (xy 286.63709 -296.680376)
			(xy 286.587915 -296.678395) (xy 286.539696 -296.668551) (xy 286.49368 -296.651099) (xy 286.451059 -296.626492)
			(xy 286.412938 -296.595367) (xy 286.380303 -296.55853) (xy 286.354 -296.516934) (xy 286.334709 -296.471658)
			(xy 286.322932 -296.423874) (xy 286.318972 -296.37482) (xy 285.980124 -296.37482) (xy 285.979629 -296.399427)
			(xy 285.971734 -296.448004) (xy 285.95615 -296.494685) (xy 285.933279 -296.538262) (xy 285.903714 -296.577606)
			(xy 285.868221 -296.611698) (xy 285.827718 -296.639654) (xy 285.783256 -296.660752) (xy 285.735985 -296.674444)
			(xy 285.68713 -296.680376) (xy 285.637955 -296.678395) (xy 285.589736 -296.668551) (xy 285.54372 -296.651099)
			(xy 285.501099 -296.626492) (xy 285.462978 -296.595367) (xy 285.430343 -296.55853) (xy 285.40404 -296.516934)
			(xy 285.384749 -296.471658) (xy 285.372972 -296.423874) (xy 285.369012 -296.37482) (xy 285.030164 -296.37482)
			(xy 285.029669 -296.399427) (xy 285.021774 -296.448004) (xy 285.00619 -296.494685) (xy 284.983319 -296.538262)
			(xy 284.953754 -296.577606) (xy 284.918261 -296.611698) (xy 284.877758 -296.639654) (xy 284.833296 -296.660752)
			(xy 284.786025 -296.674444) (xy 284.73717 -296.680376) (xy 284.687995 -296.678395) (xy 284.639776 -296.668551)
			(xy 284.59376 -296.651099) (xy 284.551139 -296.626492) (xy 284.513018 -296.595367) (xy 284.480383 -296.55853)
			(xy 284.45408 -296.516934) (xy 284.434789 -296.471658) (xy 284.423012 -296.423874) (xy 284.419052 -296.37482)
			(xy 284.080204 -296.37482) (xy 284.079709 -296.399427) (xy 284.071814 -296.448004) (xy 284.05623 -296.494685)
			(xy 284.033359 -296.538262) (xy 284.003794 -296.577606) (xy 283.968301 -296.611698) (xy 283.927798 -296.639654)
			(xy 283.883336 -296.660752) (xy 283.836065 -296.674444) (xy 283.78721 -296.680376) (xy 283.738035 -296.678395)
			(xy 283.689816 -296.668551) (xy 283.6438 -296.651099) (xy 283.601179 -296.626492) (xy 283.563058 -296.595367)
			(xy 283.530423 -296.55853) (xy 283.50412 -296.516934) (xy 283.484829 -296.471658) (xy 283.473052 -296.423874)
			(xy 283.469092 -296.37482) (xy 283.130244 -296.37482) (xy 283.129749 -296.399427) (xy 283.121854 -296.448004)
			(xy 283.10627 -296.494685) (xy 283.083399 -296.538262) (xy 283.053834 -296.577606) (xy 283.018341 -296.611698)
			(xy 282.977838 -296.639654) (xy 282.933376 -296.660752) (xy 282.886105 -296.674444) (xy 282.83725 -296.680376)
			(xy 282.788075 -296.678395) (xy 282.739856 -296.668551) (xy 282.69384 -296.651099) (xy 282.651219 -296.626492)
			(xy 282.613098 -296.595367) (xy 282.580463 -296.55853) (xy 282.55416 -296.516934) (xy 282.534869 -296.471658)
			(xy 282.523092 -296.423874) (xy 282.519132 -296.37482) (xy 282.18003 -296.37482) (xy 282.179535 -296.399427)
			(xy 282.17164 -296.448004) (xy 282.156056 -296.494685) (xy 282.133185 -296.538262) (xy 282.10362 -296.577606)
			(xy 282.068127 -296.611698) (xy 282.027624 -296.639654) (xy 281.983162 -296.660752) (xy 281.935891 -296.674444)
			(xy 281.887036 -296.680376) (xy 281.837861 -296.678395) (xy 281.789642 -296.668551) (xy 281.743626 -296.651099)
			(xy 281.701005 -296.626492) (xy 281.662884 -296.595367) (xy 281.630249 -296.55853) (xy 281.603946 -296.516934)
			(xy 281.584655 -296.471658) (xy 281.572878 -296.423874) (xy 281.568918 -296.37482) (xy 281.23007 -296.37482)
			(xy 281.229575 -296.399427) (xy 281.22168 -296.448004) (xy 281.206096 -296.494685) (xy 281.183225 -296.538262)
			(xy 281.15366 -296.577606) (xy 281.118167 -296.611698) (xy 281.077664 -296.639654) (xy 281.033202 -296.660752)
			(xy 280.985931 -296.674444) (xy 280.937076 -296.680376) (xy 280.887901 -296.678395) (xy 280.839682 -296.668551)
			(xy 280.793666 -296.651099) (xy 280.751045 -296.626492) (xy 280.712924 -296.595367) (xy 280.680289 -296.55853)
			(xy 280.653986 -296.516934) (xy 280.634695 -296.471658) (xy 280.622918 -296.423874) (xy 280.618958 -296.37482)
			(xy 280.28011 -296.37482) (xy 280.279615 -296.399427) (xy 280.27172 -296.448004) (xy 280.256136 -296.494685)
			(xy 280.233265 -296.538262) (xy 280.2037 -296.577606) (xy 280.168207 -296.611698) (xy 280.127704 -296.639654)
			(xy 280.083242 -296.660752) (xy 280.035971 -296.674444) (xy 279.987116 -296.680376) (xy 279.937941 -296.678395)
			(xy 279.889722 -296.668551) (xy 279.843706 -296.651099) (xy 279.801085 -296.626492) (xy 279.762964 -296.595367)
			(xy 279.730329 -296.55853) (xy 279.704026 -296.516934) (xy 279.684735 -296.471658) (xy 279.672958 -296.423874)
			(xy 279.668998 -296.37482) (xy 278.38019 -296.37482) (xy 278.379695 -296.399427) (xy 278.3718 -296.448004)
			(xy 278.356216 -296.494685) (xy 278.333345 -296.538262) (xy 278.30378 -296.577606) (xy 278.268287 -296.611698)
			(xy 278.227784 -296.639654) (xy 278.183322 -296.660752) (xy 278.136051 -296.674444) (xy 278.087196 -296.680376)
			(xy 278.038021 -296.678395) (xy 277.989802 -296.668551) (xy 277.943786 -296.651099) (xy 277.901165 -296.626492)
			(xy 277.863044 -296.595367) (xy 277.830409 -296.55853) (xy 277.804106 -296.516934) (xy 277.784815 -296.471658)
			(xy 277.773038 -296.423874) (xy 277.769078 -296.37482) (xy 277.43023 -296.37482) (xy 277.429735 -296.399427)
			(xy 277.42184 -296.448004) (xy 277.406256 -296.494685) (xy 277.383385 -296.538262) (xy 277.35382 -296.577606)
			(xy 277.318327 -296.611698) (xy 277.277824 -296.639654) (xy 277.233362 -296.660752) (xy 277.186091 -296.674444)
			(xy 277.137236 -296.680376) (xy 277.088061 -296.678395) (xy 277.039842 -296.668551) (xy 276.993826 -296.651099)
			(xy 276.951205 -296.626492) (xy 276.913084 -296.595367) (xy 276.880449 -296.55853) (xy 276.854146 -296.516934)
			(xy 276.834855 -296.471658) (xy 276.823078 -296.423874) (xy 276.819118 -296.37482) (xy 276.480016 -296.37482)
			(xy 276.479521 -296.399427) (xy 276.471626 -296.448004) (xy 276.456042 -296.494685) (xy 276.433171 -296.538262)
			(xy 276.403606 -296.577606) (xy 276.368113 -296.611698) (xy 276.32761 -296.639654) (xy 276.283148 -296.660752)
			(xy 276.235877 -296.674444) (xy 276.187022 -296.680376) (xy 276.137847 -296.678395) (xy 276.089628 -296.668551)
			(xy 276.043612 -296.651099) (xy 276.000991 -296.626492) (xy 275.96287 -296.595367) (xy 275.930235 -296.55853)
			(xy 275.903932 -296.516934) (xy 275.884641 -296.471658) (xy 275.872864 -296.423874) (xy 275.868904 -296.37482)
			(xy 274.580096 -296.37482) (xy 274.579601 -296.399427) (xy 274.571706 -296.448004) (xy 274.556122 -296.494685)
			(xy 274.533251 -296.538262) (xy 274.503686 -296.577606) (xy 274.468193 -296.611698) (xy 274.42769 -296.639654)
			(xy 274.383228 -296.660752) (xy 274.335957 -296.674444) (xy 274.287102 -296.680376) (xy 274.237927 -296.678395)
			(xy 274.189708 -296.668551) (xy 274.143692 -296.651099) (xy 274.101071 -296.626492) (xy 274.06295 -296.595367)
			(xy 274.030315 -296.55853) (xy 274.004012 -296.516934) (xy 273.984721 -296.471658) (xy 273.972944 -296.423874)
			(xy 273.968984 -296.37482) (xy 272.680176 -296.37482) (xy 272.679681 -296.399427) (xy 272.671786 -296.448004)
			(xy 272.656202 -296.494685) (xy 272.633331 -296.538262) (xy 272.603766 -296.577606) (xy 272.568273 -296.611698)
			(xy 272.52777 -296.639654) (xy 272.483308 -296.660752) (xy 272.436037 -296.674444) (xy 272.387182 -296.680376)
			(xy 272.338007 -296.678395) (xy 272.289788 -296.668551) (xy 272.243772 -296.651099) (xy 272.201151 -296.626492)
			(xy 272.16303 -296.595367) (xy 272.130395 -296.55853) (xy 272.104092 -296.516934) (xy 272.084801 -296.471658)
			(xy 272.073024 -296.423874) (xy 272.069064 -296.37482) (xy 271.730216 -296.37482) (xy 271.729721 -296.399427)
			(xy 271.721826 -296.448004) (xy 271.706242 -296.494685) (xy 271.683371 -296.538262) (xy 271.653806 -296.577606)
			(xy 271.618313 -296.611698) (xy 271.57781 -296.639654) (xy 271.533348 -296.660752) (xy 271.486077 -296.674444)
			(xy 271.437222 -296.680376) (xy 271.388047 -296.678395) (xy 271.339828 -296.668551) (xy 271.293812 -296.651099)
			(xy 271.251191 -296.626492) (xy 271.21307 -296.595367) (xy 271.180435 -296.55853) (xy 271.154132 -296.516934)
			(xy 271.134841 -296.471658) (xy 271.123064 -296.423874) (xy 271.119104 -296.37482) (xy 270.780002 -296.37482)
			(xy 270.779507 -296.399427) (xy 270.771612 -296.448004) (xy 270.756028 -296.494685) (xy 270.733157 -296.538262)
			(xy 270.703592 -296.577606) (xy 270.668099 -296.611698) (xy 270.627596 -296.639654) (xy 270.583134 -296.660752)
			(xy 270.535863 -296.674444) (xy 270.487008 -296.680376) (xy 270.437833 -296.678395) (xy 270.389614 -296.668551)
			(xy 270.343598 -296.651099) (xy 270.300977 -296.626492) (xy 270.262856 -296.595367) (xy 270.230221 -296.55853)
			(xy 270.203918 -296.516934) (xy 270.184627 -296.471658) (xy 270.17285 -296.423874) (xy 270.16889 -296.37482)
			(xy 269.830296 -296.37482) (xy 269.829801 -296.399427) (xy 269.821906 -296.448004) (xy 269.806322 -296.494685)
			(xy 269.783451 -296.538262) (xy 269.753886 -296.577606) (xy 269.718393 -296.611698) (xy 269.67789 -296.639654)
			(xy 269.633428 -296.660752) (xy 269.586157 -296.674444) (xy 269.537302 -296.680376) (xy 269.488127 -296.678395)
			(xy 269.439908 -296.668551) (xy 269.393892 -296.651099) (xy 269.351271 -296.626492) (xy 269.31315 -296.595367)
			(xy 269.280515 -296.55853) (xy 269.254212 -296.516934) (xy 269.234921 -296.471658) (xy 269.223144 -296.423874)
			(xy 269.219184 -296.37482) (xy 266.409468 -296.37482) (xy 266.425203 -296.384423) (xy 266.468071 -296.420098)
			(xy 266.505288 -296.461635) (xy 266.536061 -296.508148) (xy 266.559733 -296.558645) (xy 266.575801 -296.612052)
			(xy 266.583921 -296.667228) (xy 266.58443 -296.695114) (xy 266.583921 -296.723) (xy 266.575801 -296.778176)
			(xy 266.559733 -296.831583) (xy 266.536061 -296.88208) (xy 266.505288 -296.928593) (xy 266.468071 -296.97013)
			(xy 266.425203 -297.005805) (xy 266.377597 -297.034859) (xy 266.326268 -297.056671) (xy 266.272311 -297.070777)
			(xy 266.216874 -297.076877) (xy 266.16114 -297.07484) (xy 266.106297 -297.06471) (xy 266.053513 -297.046703)
			(xy 266.003913 -297.021202) (xy 265.958555 -296.988751) (xy 265.918406 -296.950042) (xy 265.88432 -296.905899)
			(xy 265.857024 -296.857264) (xy 265.837101 -296.805173) (xy 265.824975 -296.750736) (xy 265.820904 -296.695114)
			(xy 265.69797 -296.695114) (xy 265.697461 -296.723) (xy 265.689341 -296.778176) (xy 265.673273 -296.831583)
			(xy 265.649601 -296.88208) (xy 265.618828 -296.928593) (xy 265.581611 -296.97013) (xy 265.538743 -297.005805)
			(xy 265.491137 -297.034859) (xy 265.439808 -297.056671) (xy 265.385851 -297.070777) (xy 265.330414 -297.076877)
			(xy 265.27468 -297.07484) (xy 265.219837 -297.06471) (xy 265.167053 -297.046703) (xy 265.117453 -297.021202)
			(xy 265.072095 -296.988751) (xy 265.031946 -296.950042) (xy 264.99786 -296.905899) (xy 264.970564 -296.857264)
			(xy 264.950641 -296.805173) (xy 264.938515 -296.750736) (xy 264.934444 -296.695114) (xy 264.30097 -296.695114)
			(xy 264.300484 -296.722365) (xy 264.292728 -296.776313) (xy 264.277373 -296.828608) (xy 264.254731 -296.878185)
			(xy 264.225265 -296.924035) (xy 264.189574 -296.965226) (xy 264.148383 -297.000917) (xy 264.102533 -297.030383)
			(xy 264.052956 -297.053025) (xy 264.000661 -297.06838) (xy 263.946713 -297.076136) (xy 263.892211 -297.076136)
			(xy 263.838263 -297.06838) (xy 263.785968 -297.053025) (xy 263.736391 -297.030383) (xy 263.690541 -297.000917)
			(xy 263.64935 -296.965226) (xy 263.613659 -296.924035) (xy 263.584193 -296.878185) (xy 263.561551 -296.828608)
			(xy 263.546196 -296.776313) (xy 263.53844 -296.722365) (xy 263.537954 -296.695114) (xy 255.660193 -296.695114)
			(xy 255.680242 -296.796711) (xy 255.704204 -296.959531) (xy 255.72021 -297.123326) (xy 255.728223 -297.287705)
			(xy 255.728449 -297.3248) (xy 267.633949 -297.3248) (xy 267.63812 -297.274461) (xy 267.650519 -297.225496)
			(xy 267.670808 -297.179238) (xy 267.698434 -297.136951) (xy 267.732643 -297.099787) (xy 267.772502 -297.068761)
			(xy 267.816923 -297.044718) (xy 267.864697 -297.028313) (xy 267.914518 -297.019996) (xy 267.939774 -297.019472)
			(xy 267.965169 -297.019983) (xy 268.015259 -297.028397) (xy 268.063266 -297.044981) (xy 268.107868 -297.069279)
			(xy 268.147837 -297.100619) (xy 268.165326 -297.11904) (xy 268.172946 -297.127168) (xy 268.192758 -297.135804)
			(xy 268.292072 -297.13301) (xy 268.31163 -297.123612) (xy 268.318742 -297.114976) (xy 268.334531 -297.096404)
			(xy 268.370664 -297.063685) (xy 268.411205 -297.036618) (xy 268.455277 -297.01579) (xy 268.501928 -297.00165)
			(xy 268.550147 -296.994504) (xy 268.57452 -296.994072) (xy 269.52448 -296.994072) (xy 269.550469 -296.994594)
			(xy 269.601807 -297.002722) (xy 269.651241 -297.018781) (xy 269.697554 -297.042377) (xy 269.739606 -297.072927)
			(xy 269.77636 -297.109679) (xy 269.806913 -297.151729) (xy 269.830511 -297.198041) (xy 269.846573 -297.247474)
			(xy 269.854705 -297.298811) (xy 269.854705 -297.32478) (xy 270.16889 -297.32478) (xy 270.17285 -297.275726)
			(xy 270.184627 -297.227942) (xy 270.203918 -297.182666) (xy 270.230221 -297.14107) (xy 270.262856 -297.104233)
			(xy 270.300977 -297.073108) (xy 270.343598 -297.048501) (xy 270.389614 -297.031049) (xy 270.437833 -297.021205)
			(xy 270.487008 -297.019224) (xy 270.535863 -297.025156) (xy 270.583134 -297.038848) (xy 270.627596 -297.059946)
			(xy 270.668099 -297.087902) (xy 270.703592 -297.121994) (xy 270.733157 -297.161338) (xy 270.756028 -297.204915)
			(xy 270.771612 -297.251596) (xy 270.779507 -297.300173) (xy 270.780002 -297.32478) (xy 271.119104 -297.32478)
			(xy 271.123064 -297.275726) (xy 271.134841 -297.227942) (xy 271.154132 -297.182666) (xy 271.180435 -297.14107)
			(xy 271.21307 -297.104233) (xy 271.251191 -297.073108) (xy 271.293812 -297.048501) (xy 271.339828 -297.031049)
			(xy 271.388047 -297.021205) (xy 271.437222 -297.019224) (xy 271.486077 -297.025156) (xy 271.533348 -297.038848)
			(xy 271.57781 -297.059946) (xy 271.618313 -297.087902) (xy 271.653806 -297.121994) (xy 271.683371 -297.161338)
			(xy 271.706242 -297.204915) (xy 271.721826 -297.251596) (xy 271.729721 -297.300173) (xy 271.730216 -297.32478)
			(xy 273.968984 -297.32478) (xy 273.972944 -297.275726) (xy 273.984721 -297.227942) (xy 274.004012 -297.182666)
			(xy 274.030315 -297.14107) (xy 274.06295 -297.104233) (xy 274.101071 -297.073108) (xy 274.143692 -297.048501)
			(xy 274.189708 -297.031049) (xy 274.237927 -297.021205) (xy 274.287102 -297.019224) (xy 274.335957 -297.025156)
			(xy 274.383228 -297.038848) (xy 274.42769 -297.059946) (xy 274.468193 -297.087902) (xy 274.503686 -297.121994)
			(xy 274.533251 -297.161338) (xy 274.556122 -297.204915) (xy 274.571706 -297.251596) (xy 274.579601 -297.300173)
			(xy 274.580096 -297.32478) (xy 275.868904 -297.32478) (xy 275.872864 -297.275726) (xy 275.884641 -297.227942)
			(xy 275.903932 -297.182666) (xy 275.930235 -297.14107) (xy 275.96287 -297.104233) (xy 276.000991 -297.073108)
			(xy 276.043612 -297.048501) (xy 276.089628 -297.031049) (xy 276.137847 -297.021205) (xy 276.187022 -297.019224)
			(xy 276.235877 -297.025156) (xy 276.283148 -297.038848) (xy 276.32761 -297.059946) (xy 276.368113 -297.087902)
			(xy 276.403606 -297.121994) (xy 276.433171 -297.161338) (xy 276.456042 -297.204915) (xy 276.471626 -297.251596)
			(xy 276.479521 -297.300173) (xy 276.480016 -297.32478) (xy 276.819118 -297.32478) (xy 276.823078 -297.275726)
			(xy 276.834855 -297.227942) (xy 276.854146 -297.182666) (xy 276.880449 -297.14107) (xy 276.913084 -297.104233)
			(xy 276.951205 -297.073108) (xy 276.993826 -297.048501) (xy 277.039842 -297.031049) (xy 277.088061 -297.021205)
			(xy 277.137236 -297.019224) (xy 277.186091 -297.025156) (xy 277.233362 -297.038848) (xy 277.277824 -297.059946)
			(xy 277.318327 -297.087902) (xy 277.35382 -297.121994) (xy 277.383385 -297.161338) (xy 277.406256 -297.204915)
			(xy 277.42184 -297.251596) (xy 277.429735 -297.300173) (xy 277.43023 -297.32478) (xy 277.769078 -297.32478)
			(xy 277.773038 -297.275726) (xy 277.784815 -297.227942) (xy 277.804106 -297.182666) (xy 277.830409 -297.14107)
			(xy 277.863044 -297.104233) (xy 277.901165 -297.073108) (xy 277.943786 -297.048501) (xy 277.989802 -297.031049)
			(xy 278.038021 -297.021205) (xy 278.087196 -297.019224) (xy 278.136051 -297.025156) (xy 278.183322 -297.038848)
			(xy 278.227784 -297.059946) (xy 278.268287 -297.087902) (xy 278.30378 -297.121994) (xy 278.333345 -297.161338)
			(xy 278.356216 -297.204915) (xy 278.3718 -297.251596) (xy 278.379695 -297.300173) (xy 278.38019 -297.32478)
			(xy 278.719038 -297.32478) (xy 278.722998 -297.275726) (xy 278.734775 -297.227942) (xy 278.754066 -297.182666)
			(xy 278.780369 -297.14107) (xy 278.813004 -297.104233) (xy 278.851125 -297.073108) (xy 278.893746 -297.048501)
			(xy 278.939762 -297.031049) (xy 278.987981 -297.021205) (xy 279.037156 -297.019224) (xy 279.086011 -297.025156)
			(xy 279.133282 -297.038848) (xy 279.177744 -297.059946) (xy 279.218247 -297.087902) (xy 279.25374 -297.121994)
			(xy 279.283305 -297.161338) (xy 279.306176 -297.204915) (xy 279.32176 -297.251596) (xy 279.329655 -297.300173)
			(xy 279.33015 -297.32478) (xy 279.668998 -297.32478) (xy 279.672958 -297.275726) (xy 279.684735 -297.227942)
			(xy 279.704026 -297.182666) (xy 279.730329 -297.14107) (xy 279.762964 -297.104233) (xy 279.801085 -297.073108)
			(xy 279.843706 -297.048501) (xy 279.889722 -297.031049) (xy 279.937941 -297.021205) (xy 279.987116 -297.019224)
			(xy 280.035971 -297.025156) (xy 280.083242 -297.038848) (xy 280.127704 -297.059946) (xy 280.168207 -297.087902)
			(xy 280.2037 -297.121994) (xy 280.233265 -297.161338) (xy 280.256136 -297.204915) (xy 280.27172 -297.251596)
			(xy 280.279615 -297.300173) (xy 280.28011 -297.32478) (xy 280.618958 -297.32478) (xy 280.622918 -297.275726)
			(xy 280.634695 -297.227942) (xy 280.653986 -297.182666) (xy 280.680289 -297.14107) (xy 280.712924 -297.104233)
			(xy 280.751045 -297.073108) (xy 280.793666 -297.048501) (xy 280.839682 -297.031049) (xy 280.887901 -297.021205)
			(xy 280.937076 -297.019224) (xy 280.985931 -297.025156) (xy 281.033202 -297.038848) (xy 281.077664 -297.059946)
			(xy 281.118167 -297.087902) (xy 281.15366 -297.121994) (xy 281.183225 -297.161338) (xy 281.206096 -297.204915)
			(xy 281.22168 -297.251596) (xy 281.229575 -297.300173) (xy 281.23007 -297.32478) (xy 281.568918 -297.32478)
			(xy 281.572878 -297.275726) (xy 281.584655 -297.227942) (xy 281.603946 -297.182666) (xy 281.630249 -297.14107)
			(xy 281.662884 -297.104233) (xy 281.701005 -297.073108) (xy 281.743626 -297.048501) (xy 281.789642 -297.031049)
			(xy 281.837861 -297.021205) (xy 281.887036 -297.019224) (xy 281.935891 -297.025156) (xy 281.983162 -297.038848)
			(xy 282.027624 -297.059946) (xy 282.068127 -297.087902) (xy 282.10362 -297.121994) (xy 282.133185 -297.161338)
			(xy 282.156056 -297.204915) (xy 282.17164 -297.251596) (xy 282.179535 -297.300173) (xy 282.18003 -297.32478)
			(xy 282.519132 -297.32478) (xy 282.523092 -297.275726) (xy 282.534869 -297.227942) (xy 282.55416 -297.182666)
			(xy 282.580463 -297.14107) (xy 282.613098 -297.104233) (xy 282.651219 -297.073108) (xy 282.69384 -297.048501)
			(xy 282.739856 -297.031049) (xy 282.788075 -297.021205) (xy 282.83725 -297.019224) (xy 282.886105 -297.025156)
			(xy 282.933376 -297.038848) (xy 282.977838 -297.059946) (xy 283.018341 -297.087902) (xy 283.053834 -297.121994)
			(xy 283.083399 -297.161338) (xy 283.10627 -297.204915) (xy 283.121854 -297.251596) (xy 283.129749 -297.300173)
			(xy 283.130244 -297.32478) (xy 283.469092 -297.32478) (xy 283.473052 -297.275726) (xy 283.484829 -297.227942)
			(xy 283.50412 -297.182666) (xy 283.530423 -297.14107) (xy 283.563058 -297.104233) (xy 283.601179 -297.073108)
			(xy 283.6438 -297.048501) (xy 283.689816 -297.031049) (xy 283.738035 -297.021205) (xy 283.78721 -297.019224)
			(xy 283.836065 -297.025156) (xy 283.883336 -297.038848) (xy 283.927798 -297.059946) (xy 283.968301 -297.087902)
			(xy 284.003794 -297.121994) (xy 284.033359 -297.161338) (xy 284.05623 -297.204915) (xy 284.071814 -297.251596)
			(xy 284.079709 -297.300173) (xy 284.080204 -297.32478) (xy 284.419052 -297.32478) (xy 284.423012 -297.275726)
			(xy 284.434789 -297.227942) (xy 284.45408 -297.182666) (xy 284.480383 -297.14107) (xy 284.513018 -297.104233)
			(xy 284.551139 -297.073108) (xy 284.59376 -297.048501) (xy 284.639776 -297.031049) (xy 284.687995 -297.021205)
			(xy 284.73717 -297.019224) (xy 284.786025 -297.025156) (xy 284.833296 -297.038848) (xy 284.877758 -297.059946)
			(xy 284.918261 -297.087902) (xy 284.953754 -297.121994) (xy 284.983319 -297.161338) (xy 285.00619 -297.204915)
			(xy 285.021774 -297.251596) (xy 285.029669 -297.300173) (xy 285.030164 -297.32478) (xy 285.369012 -297.32478)
			(xy 285.372972 -297.275726) (xy 285.384749 -297.227942) (xy 285.40404 -297.182666) (xy 285.430343 -297.14107)
			(xy 285.462978 -297.104233) (xy 285.501099 -297.073108) (xy 285.54372 -297.048501) (xy 285.589736 -297.031049)
			(xy 285.637955 -297.021205) (xy 285.68713 -297.019224) (xy 285.735985 -297.025156) (xy 285.783256 -297.038848)
			(xy 285.827718 -297.059946) (xy 285.868221 -297.087902) (xy 285.903714 -297.121994) (xy 285.933279 -297.161338)
			(xy 285.95615 -297.204915) (xy 285.971734 -297.251596) (xy 285.979629 -297.300173) (xy 285.980124 -297.32478)
			(xy 286.318972 -297.32478) (xy 286.322932 -297.275726) (xy 286.334709 -297.227942) (xy 286.354 -297.182666)
			(xy 286.380303 -297.14107) (xy 286.412938 -297.104233) (xy 286.451059 -297.073108) (xy 286.49368 -297.048501)
			(xy 286.539696 -297.031049) (xy 286.587915 -297.021205) (xy 286.63709 -297.019224) (xy 286.685945 -297.025156)
			(xy 286.733216 -297.038848) (xy 286.777678 -297.059946) (xy 286.818181 -297.087902) (xy 286.853674 -297.121994)
			(xy 286.883239 -297.161338) (xy 286.90611 -297.204915) (xy 286.921694 -297.251596) (xy 286.929589 -297.300173)
			(xy 286.930084 -297.32478) (xy 287.268932 -297.32478) (xy 287.272892 -297.275726) (xy 287.284669 -297.227942)
			(xy 287.30396 -297.182666) (xy 287.330263 -297.14107) (xy 287.362898 -297.104233) (xy 287.401019 -297.073108)
			(xy 287.44364 -297.048501) (xy 287.489656 -297.031049) (xy 287.537875 -297.021205) (xy 287.58705 -297.019224)
			(xy 287.635905 -297.025156) (xy 287.683176 -297.038848) (xy 287.727638 -297.059946) (xy 287.768141 -297.087902)
			(xy 287.803634 -297.121994) (xy 287.833199 -297.161338) (xy 287.85607 -297.204915) (xy 287.871654 -297.251596)
			(xy 287.879549 -297.300173) (xy 287.880044 -297.32478) (xy 288.218892 -297.32478) (xy 288.222852 -297.275726)
			(xy 288.234629 -297.227942) (xy 288.25392 -297.182666) (xy 288.280223 -297.14107) (xy 288.312858 -297.104233)
			(xy 288.350979 -297.073108) (xy 288.3936 -297.048501) (xy 288.439616 -297.031049) (xy 288.487835 -297.021205)
			(xy 288.53701 -297.019224) (xy 288.585865 -297.025156) (xy 288.633136 -297.038848) (xy 288.677598 -297.059946)
			(xy 288.718101 -297.087902) (xy 288.753594 -297.121994) (xy 288.783159 -297.161338) (xy 288.80603 -297.204915)
			(xy 288.821614 -297.251596) (xy 288.829509 -297.300173) (xy 288.830004 -297.32478) (xy 289.169106 -297.32478)
			(xy 289.173066 -297.275726) (xy 289.184843 -297.227942) (xy 289.204134 -297.182666) (xy 289.230437 -297.14107)
			(xy 289.263072 -297.104233) (xy 289.301193 -297.073108) (xy 289.343814 -297.048501) (xy 289.38983 -297.031049)
			(xy 289.438049 -297.021205) (xy 289.487224 -297.019224) (xy 289.536079 -297.025156) (xy 289.58335 -297.038848)
			(xy 289.627812 -297.059946) (xy 289.668315 -297.087902) (xy 289.703808 -297.121994) (xy 289.733373 -297.161338)
			(xy 289.756244 -297.204915) (xy 289.771828 -297.251596) (xy 289.779723 -297.300173) (xy 289.780218 -297.32478)
			(xy 290.119066 -297.32478) (xy 290.123026 -297.275726) (xy 290.134803 -297.227942) (xy 290.154094 -297.182666)
			(xy 290.180397 -297.14107) (xy 290.213032 -297.104233) (xy 290.251153 -297.073108) (xy 290.293774 -297.048501)
			(xy 290.33979 -297.031049) (xy 290.388009 -297.021205) (xy 290.437184 -297.019224) (xy 290.486039 -297.025156)
			(xy 290.53331 -297.038848) (xy 290.577772 -297.059946) (xy 290.618275 -297.087902) (xy 290.653768 -297.121994)
			(xy 290.683333 -297.161338) (xy 290.706204 -297.204915) (xy 290.721788 -297.251596) (xy 290.729683 -297.300173)
			(xy 290.730178 -297.32478) (xy 292.018986 -297.32478) (xy 292.022946 -297.275726) (xy 292.034723 -297.227942)
			(xy 292.054014 -297.182666) (xy 292.080317 -297.14107) (xy 292.112952 -297.104233) (xy 292.151073 -297.073108)
			(xy 292.193694 -297.048501) (xy 292.23971 -297.031049) (xy 292.287929 -297.021205) (xy 292.337104 -297.019224)
			(xy 292.385959 -297.025156) (xy 292.43323 -297.038848) (xy 292.477692 -297.059946) (xy 292.518195 -297.087902)
			(xy 292.553688 -297.121994) (xy 292.583253 -297.161338) (xy 292.606124 -297.204915) (xy 292.621708 -297.251596)
			(xy 292.629603 -297.300173) (xy 292.630098 -297.32478) (xy 292.968946 -297.32478) (xy 292.972906 -297.275726)
			(xy 292.984683 -297.227942) (xy 293.003974 -297.182666) (xy 293.030277 -297.14107) (xy 293.062912 -297.104233)
			(xy 293.101033 -297.073108) (xy 293.143654 -297.048501) (xy 293.18967 -297.031049) (xy 293.237889 -297.021205)
			(xy 293.287064 -297.019224) (xy 293.335919 -297.025156) (xy 293.38319 -297.038848) (xy 293.427652 -297.059946)
			(xy 293.468155 -297.087902) (xy 293.503648 -297.121994) (xy 293.533213 -297.161338) (xy 293.556084 -297.204915)
			(xy 293.571668 -297.251596) (xy 293.579563 -297.300173) (xy 293.580058 -297.32478) (xy 293.918906 -297.32478)
			(xy 293.922866 -297.275726) (xy 293.934643 -297.227942) (xy 293.953934 -297.182666) (xy 293.980237 -297.14107)
			(xy 294.012872 -297.104233) (xy 294.050993 -297.073108) (xy 294.093614 -297.048501) (xy 294.13963 -297.031049)
			(xy 294.187849 -297.021205) (xy 294.237024 -297.019224) (xy 294.285879 -297.025156) (xy 294.33315 -297.038848)
			(xy 294.377612 -297.059946) (xy 294.418115 -297.087902) (xy 294.453608 -297.121994) (xy 294.483173 -297.161338)
			(xy 294.506044 -297.204915) (xy 294.521628 -297.251596) (xy 294.529523 -297.300173) (xy 294.530018 -297.32478)
			(xy 294.86912 -297.32478) (xy 294.87308 -297.275726) (xy 294.884857 -297.227942) (xy 294.904148 -297.182666)
			(xy 294.930451 -297.14107) (xy 294.963086 -297.104233) (xy 295.001207 -297.073108) (xy 295.043828 -297.048501)
			(xy 295.089844 -297.031049) (xy 295.138063 -297.021205) (xy 295.187238 -297.019224) (xy 295.236093 -297.025156)
			(xy 295.283364 -297.038848) (xy 295.327826 -297.059946) (xy 295.368329 -297.087902) (xy 295.403822 -297.121994)
			(xy 295.433387 -297.161338) (xy 295.456258 -297.204915) (xy 295.471842 -297.251596) (xy 295.479737 -297.300173)
			(xy 295.480232 -297.32478) (xy 295.81908 -297.32478) (xy 295.82304 -297.275726) (xy 295.834817 -297.227942)
			(xy 295.854108 -297.182666) (xy 295.880411 -297.14107) (xy 295.913046 -297.104233) (xy 295.951167 -297.073108)
			(xy 295.993788 -297.048501) (xy 296.039804 -297.031049) (xy 296.088023 -297.021205) (xy 296.137198 -297.019224)
			(xy 296.186053 -297.025156) (xy 296.233324 -297.038848) (xy 296.277786 -297.059946) (xy 296.318289 -297.087902)
			(xy 296.353782 -297.121994) (xy 296.383347 -297.161338) (xy 296.406218 -297.204915) (xy 296.421802 -297.251596)
			(xy 296.429697 -297.300173) (xy 296.430192 -297.32478) (xy 296.76904 -297.32478) (xy 296.773 -297.275726)
			(xy 296.784777 -297.227942) (xy 296.804068 -297.182666) (xy 296.830371 -297.14107) (xy 296.863006 -297.104233)
			(xy 296.901127 -297.073108) (xy 296.943748 -297.048501) (xy 296.989764 -297.031049) (xy 297.037983 -297.021205)
			(xy 297.087158 -297.019224) (xy 297.136013 -297.025156) (xy 297.183284 -297.038848) (xy 297.227746 -297.059946)
			(xy 297.268249 -297.087902) (xy 297.303742 -297.121994) (xy 297.333307 -297.161338) (xy 297.356178 -297.204915)
			(xy 297.371762 -297.251596) (xy 297.379657 -297.300173) (xy 297.380152 -297.32478) (xy 297.719 -297.32478)
			(xy 297.72296 -297.275726) (xy 297.734737 -297.227942) (xy 297.754028 -297.182666) (xy 297.780331 -297.14107)
			(xy 297.812966 -297.104233) (xy 297.851087 -297.073108) (xy 297.893708 -297.048501) (xy 297.939724 -297.031049)
			(xy 297.987943 -297.021205) (xy 298.037118 -297.019224) (xy 298.085973 -297.025156) (xy 298.133244 -297.038848)
			(xy 298.177706 -297.059946) (xy 298.218209 -297.087902) (xy 298.253702 -297.121994) (xy 298.283267 -297.161338)
			(xy 298.306138 -297.204915) (xy 298.321722 -297.251596) (xy 298.329617 -297.300173) (xy 298.330112 -297.32478)
			(xy 298.66896 -297.32478) (xy 298.67292 -297.275726) (xy 298.684697 -297.227942) (xy 298.703988 -297.182666)
			(xy 298.730291 -297.14107) (xy 298.762926 -297.104233) (xy 298.801047 -297.073108) (xy 298.843668 -297.048501)
			(xy 298.889684 -297.031049) (xy 298.937903 -297.021205) (xy 298.987078 -297.019224) (xy 299.035933 -297.025156)
			(xy 299.083204 -297.038848) (xy 299.127666 -297.059946) (xy 299.168169 -297.087902) (xy 299.203662 -297.121994)
			(xy 299.233227 -297.161338) (xy 299.256098 -297.204915) (xy 299.271682 -297.251596) (xy 299.279577 -297.300173)
			(xy 299.280072 -297.32478) (xy 299.61892 -297.32478) (xy 299.62288 -297.275726) (xy 299.634657 -297.227942)
			(xy 299.653948 -297.182666) (xy 299.680251 -297.14107) (xy 299.712886 -297.104233) (xy 299.751007 -297.073108)
			(xy 299.793628 -297.048501) (xy 299.839644 -297.031049) (xy 299.887863 -297.021205) (xy 299.937038 -297.019224)
			(xy 299.985893 -297.025156) (xy 300.033164 -297.038848) (xy 300.077626 -297.059946) (xy 300.118129 -297.087902)
			(xy 300.153622 -297.121994) (xy 300.183187 -297.161338) (xy 300.206058 -297.204915) (xy 300.221642 -297.251596)
			(xy 300.229537 -297.300173) (xy 300.230032 -297.32478) (xy 300.56888 -297.32478) (xy 300.57284 -297.275726)
			(xy 300.584617 -297.227942) (xy 300.603908 -297.182666) (xy 300.630211 -297.14107) (xy 300.662846 -297.104233)
			(xy 300.700967 -297.073108) (xy 300.743588 -297.048501) (xy 300.789604 -297.031049) (xy 300.837823 -297.021205)
			(xy 300.886998 -297.019224) (xy 300.935853 -297.025156) (xy 300.983124 -297.038848) (xy 301.027586 -297.059946)
			(xy 301.068089 -297.087902) (xy 301.103582 -297.121994) (xy 301.133147 -297.161338) (xy 301.156018 -297.204915)
			(xy 301.171602 -297.251596) (xy 301.179497 -297.300173) (xy 301.179992 -297.32478) (xy 301.519094 -297.32478)
			(xy 301.523054 -297.275726) (xy 301.534831 -297.227942) (xy 301.554122 -297.182666) (xy 301.580425 -297.14107)
			(xy 301.61306 -297.104233) (xy 301.651181 -297.073108) (xy 301.693802 -297.048501) (xy 301.739818 -297.031049)
			(xy 301.788037 -297.021205) (xy 301.837212 -297.019224) (xy 301.886067 -297.025156) (xy 301.933338 -297.038848)
			(xy 301.9778 -297.059946) (xy 302.018303 -297.087902) (xy 302.053796 -297.121994) (xy 302.083361 -297.161338)
			(xy 302.106232 -297.204915) (xy 302.121816 -297.251596) (xy 302.129711 -297.300173) (xy 302.130206 -297.32478)
			(xy 303.419014 -297.32478) (xy 303.422974 -297.275726) (xy 303.434751 -297.227942) (xy 303.454042 -297.182666)
			(xy 303.480345 -297.14107) (xy 303.51298 -297.104233) (xy 303.551101 -297.073108) (xy 303.593722 -297.048501)
			(xy 303.639738 -297.031049) (xy 303.687957 -297.021205) (xy 303.737132 -297.019224) (xy 303.785987 -297.025156)
			(xy 303.833258 -297.038848) (xy 303.87772 -297.059946) (xy 303.918223 -297.087902) (xy 303.953716 -297.121994)
			(xy 303.983281 -297.161338) (xy 304.006152 -297.204915) (xy 304.021736 -297.251596) (xy 304.029631 -297.300173)
			(xy 304.030126 -297.32478) (xy 304.368974 -297.32478) (xy 304.372934 -297.275726) (xy 304.384711 -297.227942)
			(xy 304.404002 -297.182666) (xy 304.430305 -297.14107) (xy 304.46294 -297.104233) (xy 304.501061 -297.073108)
			(xy 304.543682 -297.048501) (xy 304.589698 -297.031049) (xy 304.637917 -297.021205) (xy 304.687092 -297.019224)
			(xy 304.735947 -297.025156) (xy 304.783218 -297.038848) (xy 304.82768 -297.059946) (xy 304.868183 -297.087902)
			(xy 304.903676 -297.121994) (xy 304.933241 -297.161338) (xy 304.956112 -297.204915) (xy 304.971696 -297.251596)
			(xy 304.979591 -297.300173) (xy 304.980086 -297.32478) (xy 305.318934 -297.32478) (xy 305.322894 -297.275726)
			(xy 305.334671 -297.227942) (xy 305.353962 -297.182666) (xy 305.380265 -297.14107) (xy 305.4129 -297.104233)
			(xy 305.451021 -297.073108) (xy 305.493642 -297.048501) (xy 305.539658 -297.031049) (xy 305.587877 -297.021205)
			(xy 305.637052 -297.019224) (xy 305.685907 -297.025156) (xy 305.733178 -297.038848) (xy 305.77764 -297.059946)
			(xy 305.818143 -297.087902) (xy 305.853636 -297.121994) (xy 305.883201 -297.161338) (xy 305.906072 -297.204915)
			(xy 305.921656 -297.251596) (xy 305.929551 -297.300173) (xy 305.930046 -297.32478) (xy 306.269148 -297.32478)
			(xy 306.273108 -297.275726) (xy 306.284885 -297.227942) (xy 306.304176 -297.182666) (xy 306.330479 -297.14107)
			(xy 306.363114 -297.104233) (xy 306.401235 -297.073108) (xy 306.443856 -297.048501) (xy 306.489872 -297.031049)
			(xy 306.538091 -297.021205) (xy 306.587266 -297.019224) (xy 306.636121 -297.025156) (xy 306.683392 -297.038848)
			(xy 306.727854 -297.059946) (xy 306.768357 -297.087902) (xy 306.80385 -297.121994) (xy 306.833415 -297.161338)
			(xy 306.856286 -297.204915) (xy 306.87187 -297.251596) (xy 306.879765 -297.300173) (xy 306.88026 -297.32478)
			(xy 307.219108 -297.32478) (xy 307.223068 -297.275726) (xy 307.234845 -297.227942) (xy 307.254136 -297.182666)
			(xy 307.280439 -297.14107) (xy 307.313074 -297.104233) (xy 307.351195 -297.073108) (xy 307.393816 -297.048501)
			(xy 307.439832 -297.031049) (xy 307.488051 -297.021205) (xy 307.537226 -297.019224) (xy 307.586081 -297.025156)
			(xy 307.633352 -297.038848) (xy 307.677814 -297.059946) (xy 307.718317 -297.087902) (xy 307.75381 -297.121994)
			(xy 307.783375 -297.161338) (xy 307.806246 -297.204915) (xy 307.82183 -297.251596) (xy 307.829725 -297.300173)
			(xy 307.83022 -297.32478) (xy 308.169068 -297.32478) (xy 308.173028 -297.275726) (xy 308.184805 -297.227942)
			(xy 308.204096 -297.182666) (xy 308.230399 -297.14107) (xy 308.263034 -297.104233) (xy 308.301155 -297.073108)
			(xy 308.343776 -297.048501) (xy 308.389792 -297.031049) (xy 308.438011 -297.021205) (xy 308.487186 -297.019224)
			(xy 308.536041 -297.025156) (xy 308.583312 -297.038848) (xy 308.627774 -297.059946) (xy 308.668277 -297.087902)
			(xy 308.70377 -297.121994) (xy 308.733335 -297.161338) (xy 308.756206 -297.204915) (xy 308.77179 -297.251596)
			(xy 308.779685 -297.300173) (xy 308.78018 -297.32478) (xy 309.119028 -297.32478) (xy 309.122988 -297.275726)
			(xy 309.134765 -297.227942) (xy 309.154056 -297.182666) (xy 309.180359 -297.14107) (xy 309.212994 -297.104233)
			(xy 309.251115 -297.073108) (xy 309.293736 -297.048501) (xy 309.339752 -297.031049) (xy 309.387971 -297.021205)
			(xy 309.437146 -297.019224) (xy 309.486001 -297.025156) (xy 309.533272 -297.038848) (xy 309.577734 -297.059946)
			(xy 309.618237 -297.087902) (xy 309.65373 -297.121994) (xy 309.683295 -297.161338) (xy 309.706166 -297.204915)
			(xy 309.72175 -297.251596) (xy 309.729645 -297.300173) (xy 309.73014 -297.32478) (xy 310.068988 -297.32478)
			(xy 310.072948 -297.275726) (xy 310.084725 -297.227942) (xy 310.104016 -297.182666) (xy 310.130319 -297.14107)
			(xy 310.162954 -297.104233) (xy 310.201075 -297.073108) (xy 310.243696 -297.048501) (xy 310.289712 -297.031049)
			(xy 310.337931 -297.021205) (xy 310.387106 -297.019224) (xy 310.435961 -297.025156) (xy 310.483232 -297.038848)
			(xy 310.527694 -297.059946) (xy 310.568197 -297.087902) (xy 310.60369 -297.121994) (xy 310.633255 -297.161338)
			(xy 310.656126 -297.204915) (xy 310.67171 -297.251596) (xy 310.679605 -297.300173) (xy 310.6801 -297.32478)
			(xy 311.018948 -297.32478) (xy 311.022908 -297.275726) (xy 311.034685 -297.227942) (xy 311.053976 -297.182666)
			(xy 311.080279 -297.14107) (xy 311.112914 -297.104233) (xy 311.151035 -297.073108) (xy 311.193656 -297.048501)
			(xy 311.239672 -297.031049) (xy 311.287891 -297.021205) (xy 311.337066 -297.019224) (xy 311.385921 -297.025156)
			(xy 311.433192 -297.038848) (xy 311.477654 -297.059946) (xy 311.518157 -297.087902) (xy 311.55365 -297.121994)
			(xy 311.583215 -297.161338) (xy 311.606086 -297.204915) (xy 311.62167 -297.251596) (xy 311.629565 -297.300173)
			(xy 311.63006 -297.32478) (xy 311.968908 -297.32478) (xy 311.972868 -297.275726) (xy 311.984645 -297.227942)
			(xy 312.003936 -297.182666) (xy 312.030239 -297.14107) (xy 312.062874 -297.104233) (xy 312.100995 -297.073108)
			(xy 312.143616 -297.048501) (xy 312.189632 -297.031049) (xy 312.237851 -297.021205) (xy 312.287026 -297.019224)
			(xy 312.335881 -297.025156) (xy 312.383152 -297.038848) (xy 312.427614 -297.059946) (xy 312.468117 -297.087902)
			(xy 312.50361 -297.121994) (xy 312.533175 -297.161338) (xy 312.556046 -297.204915) (xy 312.57163 -297.251596)
			(xy 312.579525 -297.300173) (xy 312.58002 -297.32478) (xy 312.919122 -297.32478) (xy 312.923082 -297.275726)
			(xy 312.934859 -297.227942) (xy 312.95415 -297.182666) (xy 312.980453 -297.14107) (xy 313.013088 -297.104233)
			(xy 313.051209 -297.073108) (xy 313.09383 -297.048501) (xy 313.139846 -297.031049) (xy 313.188065 -297.021205)
			(xy 313.23724 -297.019224) (xy 313.286095 -297.025156) (xy 313.333366 -297.038848) (xy 313.377828 -297.059946)
			(xy 313.418331 -297.087902) (xy 313.453824 -297.121994) (xy 313.483389 -297.161338) (xy 313.50626 -297.204915)
			(xy 313.521844 -297.251596) (xy 313.529739 -297.300173) (xy 313.530234 -297.32478) (xy 313.869082 -297.32478)
			(xy 313.873042 -297.275726) (xy 313.884819 -297.227942) (xy 313.90411 -297.182666) (xy 313.930413 -297.14107)
			(xy 313.963048 -297.104233) (xy 314.001169 -297.073108) (xy 314.04379 -297.048501) (xy 314.089806 -297.031049)
			(xy 314.138025 -297.021205) (xy 314.1872 -297.019224) (xy 314.236055 -297.025156) (xy 314.283326 -297.038848)
			(xy 314.327788 -297.059946) (xy 314.368291 -297.087902) (xy 314.403784 -297.121994) (xy 314.433349 -297.161338)
			(xy 314.45622 -297.204915) (xy 314.471804 -297.251596) (xy 314.479699 -297.300173) (xy 314.480194 -297.32478)
			(xy 314.819042 -297.32478) (xy 314.823002 -297.275726) (xy 314.834779 -297.227942) (xy 314.85407 -297.182666)
			(xy 314.880373 -297.14107) (xy 314.913008 -297.104233) (xy 314.951129 -297.073108) (xy 314.99375 -297.048501)
			(xy 315.039766 -297.031049) (xy 315.087985 -297.021205) (xy 315.13716 -297.019224) (xy 315.186015 -297.025156)
			(xy 315.233286 -297.038848) (xy 315.277748 -297.059946) (xy 315.318251 -297.087902) (xy 315.353744 -297.121994)
			(xy 315.383309 -297.161338) (xy 315.40618 -297.204915) (xy 315.421764 -297.251596) (xy 315.429659 -297.300173)
			(xy 315.430154 -297.32478) (xy 315.429659 -297.349387) (xy 315.421764 -297.397964) (xy 315.40618 -297.444645)
			(xy 315.383309 -297.488222) (xy 315.353744 -297.527566) (xy 315.318251 -297.561658) (xy 315.277748 -297.589614)
			(xy 315.233286 -297.610712) (xy 315.186015 -297.624404) (xy 315.13716 -297.630336) (xy 315.087985 -297.628355)
			(xy 315.039766 -297.618511) (xy 314.99375 -297.601059) (xy 314.951129 -297.576452) (xy 314.913008 -297.545327)
			(xy 314.880373 -297.50849) (xy 314.85407 -297.466894) (xy 314.834779 -297.421618) (xy 314.823002 -297.373834)
			(xy 314.819042 -297.32478) (xy 314.480194 -297.32478) (xy 314.479699 -297.349387) (xy 314.471804 -297.397964)
			(xy 314.45622 -297.444645) (xy 314.433349 -297.488222) (xy 314.403784 -297.527566) (xy 314.368291 -297.561658)
			(xy 314.327788 -297.589614) (xy 314.283326 -297.610712) (xy 314.236055 -297.624404) (xy 314.1872 -297.630336)
			(xy 314.138025 -297.628355) (xy 314.089806 -297.618511) (xy 314.04379 -297.601059) (xy 314.001169 -297.576452)
			(xy 313.963048 -297.545327) (xy 313.930413 -297.50849) (xy 313.90411 -297.466894) (xy 313.884819 -297.421618)
			(xy 313.873042 -297.373834) (xy 313.869082 -297.32478) (xy 313.530234 -297.32478) (xy 313.529739 -297.349387)
			(xy 313.521844 -297.397964) (xy 313.50626 -297.444645) (xy 313.483389 -297.488222) (xy 313.453824 -297.527566)
			(xy 313.418331 -297.561658) (xy 313.377828 -297.589614) (xy 313.333366 -297.610712) (xy 313.286095 -297.624404)
			(xy 313.23724 -297.630336) (xy 313.188065 -297.628355) (xy 313.139846 -297.618511) (xy 313.09383 -297.601059)
			(xy 313.051209 -297.576452) (xy 313.013088 -297.545327) (xy 312.980453 -297.50849) (xy 312.95415 -297.466894)
			(xy 312.934859 -297.421618) (xy 312.923082 -297.373834) (xy 312.919122 -297.32478) (xy 312.58002 -297.32478)
			(xy 312.579525 -297.349387) (xy 312.57163 -297.397964) (xy 312.556046 -297.444645) (xy 312.533175 -297.488222)
			(xy 312.50361 -297.527566) (xy 312.468117 -297.561658) (xy 312.427614 -297.589614) (xy 312.383152 -297.610712)
			(xy 312.335881 -297.624404) (xy 312.287026 -297.630336) (xy 312.237851 -297.628355) (xy 312.189632 -297.618511)
			(xy 312.143616 -297.601059) (xy 312.100995 -297.576452) (xy 312.062874 -297.545327) (xy 312.030239 -297.50849)
			(xy 312.003936 -297.466894) (xy 311.984645 -297.421618) (xy 311.972868 -297.373834) (xy 311.968908 -297.32478)
			(xy 311.63006 -297.32478) (xy 311.629565 -297.349387) (xy 311.62167 -297.397964) (xy 311.606086 -297.444645)
			(xy 311.583215 -297.488222) (xy 311.55365 -297.527566) (xy 311.518157 -297.561658) (xy 311.477654 -297.589614)
			(xy 311.433192 -297.610712) (xy 311.385921 -297.624404) (xy 311.337066 -297.630336) (xy 311.287891 -297.628355)
			(xy 311.239672 -297.618511) (xy 311.193656 -297.601059) (xy 311.151035 -297.576452) (xy 311.112914 -297.545327)
			(xy 311.080279 -297.50849) (xy 311.053976 -297.466894) (xy 311.034685 -297.421618) (xy 311.022908 -297.373834)
			(xy 311.018948 -297.32478) (xy 310.6801 -297.32478) (xy 310.679605 -297.349387) (xy 310.67171 -297.397964)
			(xy 310.656126 -297.444645) (xy 310.633255 -297.488222) (xy 310.60369 -297.527566) (xy 310.568197 -297.561658)
			(xy 310.527694 -297.589614) (xy 310.483232 -297.610712) (xy 310.435961 -297.624404) (xy 310.387106 -297.630336)
			(xy 310.337931 -297.628355) (xy 310.289712 -297.618511) (xy 310.243696 -297.601059) (xy 310.201075 -297.576452)
			(xy 310.162954 -297.545327) (xy 310.130319 -297.50849) (xy 310.104016 -297.466894) (xy 310.084725 -297.421618)
			(xy 310.072948 -297.373834) (xy 310.068988 -297.32478) (xy 309.73014 -297.32478) (xy 309.729645 -297.349387)
			(xy 309.72175 -297.397964) (xy 309.706166 -297.444645) (xy 309.683295 -297.488222) (xy 309.65373 -297.527566)
			(xy 309.618237 -297.561658) (xy 309.577734 -297.589614) (xy 309.533272 -297.610712) (xy 309.486001 -297.624404)
			(xy 309.437146 -297.630336) (xy 309.387971 -297.628355) (xy 309.339752 -297.618511) (xy 309.293736 -297.601059)
			(xy 309.251115 -297.576452) (xy 309.212994 -297.545327) (xy 309.180359 -297.50849) (xy 309.154056 -297.466894)
			(xy 309.134765 -297.421618) (xy 309.122988 -297.373834) (xy 309.119028 -297.32478) (xy 308.78018 -297.32478)
			(xy 308.779685 -297.349387) (xy 308.77179 -297.397964) (xy 308.756206 -297.444645) (xy 308.733335 -297.488222)
			(xy 308.70377 -297.527566) (xy 308.668277 -297.561658) (xy 308.627774 -297.589614) (xy 308.583312 -297.610712)
			(xy 308.536041 -297.624404) (xy 308.487186 -297.630336) (xy 308.438011 -297.628355) (xy 308.389792 -297.618511)
			(xy 308.343776 -297.601059) (xy 308.301155 -297.576452) (xy 308.263034 -297.545327) (xy 308.230399 -297.50849)
			(xy 308.204096 -297.466894) (xy 308.184805 -297.421618) (xy 308.173028 -297.373834) (xy 308.169068 -297.32478)
			(xy 307.83022 -297.32478) (xy 307.829725 -297.349387) (xy 307.82183 -297.397964) (xy 307.806246 -297.444645)
			(xy 307.783375 -297.488222) (xy 307.75381 -297.527566) (xy 307.718317 -297.561658) (xy 307.677814 -297.589614)
			(xy 307.633352 -297.610712) (xy 307.586081 -297.624404) (xy 307.537226 -297.630336) (xy 307.488051 -297.628355)
			(xy 307.439832 -297.618511) (xy 307.393816 -297.601059) (xy 307.351195 -297.576452) (xy 307.313074 -297.545327)
			(xy 307.280439 -297.50849) (xy 307.254136 -297.466894) (xy 307.234845 -297.421618) (xy 307.223068 -297.373834)
			(xy 307.219108 -297.32478) (xy 306.88026 -297.32478) (xy 306.879765 -297.349387) (xy 306.87187 -297.397964)
			(xy 306.856286 -297.444645) (xy 306.833415 -297.488222) (xy 306.80385 -297.527566) (xy 306.768357 -297.561658)
			(xy 306.727854 -297.589614) (xy 306.683392 -297.610712) (xy 306.636121 -297.624404) (xy 306.587266 -297.630336)
			(xy 306.538091 -297.628355) (xy 306.489872 -297.618511) (xy 306.443856 -297.601059) (xy 306.401235 -297.576452)
			(xy 306.363114 -297.545327) (xy 306.330479 -297.50849) (xy 306.304176 -297.466894) (xy 306.284885 -297.421618)
			(xy 306.273108 -297.373834) (xy 306.269148 -297.32478) (xy 305.930046 -297.32478) (xy 305.929551 -297.349387)
			(xy 305.921656 -297.397964) (xy 305.906072 -297.444645) (xy 305.883201 -297.488222) (xy 305.853636 -297.527566)
			(xy 305.818143 -297.561658) (xy 305.77764 -297.589614) (xy 305.733178 -297.610712) (xy 305.685907 -297.624404)
			(xy 305.637052 -297.630336) (xy 305.587877 -297.628355) (xy 305.539658 -297.618511) (xy 305.493642 -297.601059)
			(xy 305.451021 -297.576452) (xy 305.4129 -297.545327) (xy 305.380265 -297.50849) (xy 305.353962 -297.466894)
			(xy 305.334671 -297.421618) (xy 305.322894 -297.373834) (xy 305.318934 -297.32478) (xy 304.980086 -297.32478)
			(xy 304.979591 -297.349387) (xy 304.971696 -297.397964) (xy 304.956112 -297.444645) (xy 304.933241 -297.488222)
			(xy 304.903676 -297.527566) (xy 304.868183 -297.561658) (xy 304.82768 -297.589614) (xy 304.783218 -297.610712)
			(xy 304.735947 -297.624404) (xy 304.687092 -297.630336) (xy 304.637917 -297.628355) (xy 304.589698 -297.618511)
			(xy 304.543682 -297.601059) (xy 304.501061 -297.576452) (xy 304.46294 -297.545327) (xy 304.430305 -297.50849)
			(xy 304.404002 -297.466894) (xy 304.384711 -297.421618) (xy 304.372934 -297.373834) (xy 304.368974 -297.32478)
			(xy 304.030126 -297.32478) (xy 304.029631 -297.349387) (xy 304.021736 -297.397964) (xy 304.006152 -297.444645)
			(xy 303.983281 -297.488222) (xy 303.953716 -297.527566) (xy 303.918223 -297.561658) (xy 303.87772 -297.589614)
			(xy 303.833258 -297.610712) (xy 303.785987 -297.624404) (xy 303.737132 -297.630336) (xy 303.687957 -297.628355)
			(xy 303.639738 -297.618511) (xy 303.593722 -297.601059) (xy 303.551101 -297.576452) (xy 303.51298 -297.545327)
			(xy 303.480345 -297.50849) (xy 303.454042 -297.466894) (xy 303.434751 -297.421618) (xy 303.422974 -297.373834)
			(xy 303.419014 -297.32478) (xy 302.130206 -297.32478) (xy 302.129711 -297.349387) (xy 302.121816 -297.397964)
			(xy 302.106232 -297.444645) (xy 302.083361 -297.488222) (xy 302.053796 -297.527566) (xy 302.018303 -297.561658)
			(xy 301.9778 -297.589614) (xy 301.933338 -297.610712) (xy 301.886067 -297.624404) (xy 301.837212 -297.630336)
			(xy 301.788037 -297.628355) (xy 301.739818 -297.618511) (xy 301.693802 -297.601059) (xy 301.651181 -297.576452)
			(xy 301.61306 -297.545327) (xy 301.580425 -297.50849) (xy 301.554122 -297.466894) (xy 301.534831 -297.421618)
			(xy 301.523054 -297.373834) (xy 301.519094 -297.32478) (xy 301.179992 -297.32478) (xy 301.179497 -297.349387)
			(xy 301.171602 -297.397964) (xy 301.156018 -297.444645) (xy 301.133147 -297.488222) (xy 301.103582 -297.527566)
			(xy 301.068089 -297.561658) (xy 301.027586 -297.589614) (xy 300.983124 -297.610712) (xy 300.935853 -297.624404)
			(xy 300.886998 -297.630336) (xy 300.837823 -297.628355) (xy 300.789604 -297.618511) (xy 300.743588 -297.601059)
			(xy 300.700967 -297.576452) (xy 300.662846 -297.545327) (xy 300.630211 -297.50849) (xy 300.603908 -297.466894)
			(xy 300.584617 -297.421618) (xy 300.57284 -297.373834) (xy 300.56888 -297.32478) (xy 300.230032 -297.32478)
			(xy 300.229537 -297.349387) (xy 300.221642 -297.397964) (xy 300.206058 -297.444645) (xy 300.183187 -297.488222)
			(xy 300.153622 -297.527566) (xy 300.118129 -297.561658) (xy 300.077626 -297.589614) (xy 300.033164 -297.610712)
			(xy 299.985893 -297.624404) (xy 299.937038 -297.630336) (xy 299.887863 -297.628355) (xy 299.839644 -297.618511)
			(xy 299.793628 -297.601059) (xy 299.751007 -297.576452) (xy 299.712886 -297.545327) (xy 299.680251 -297.50849)
			(xy 299.653948 -297.466894) (xy 299.634657 -297.421618) (xy 299.62288 -297.373834) (xy 299.61892 -297.32478)
			(xy 299.280072 -297.32478) (xy 299.279577 -297.349387) (xy 299.271682 -297.397964) (xy 299.256098 -297.444645)
			(xy 299.233227 -297.488222) (xy 299.203662 -297.527566) (xy 299.168169 -297.561658) (xy 299.127666 -297.589614)
			(xy 299.083204 -297.610712) (xy 299.035933 -297.624404) (xy 298.987078 -297.630336) (xy 298.937903 -297.628355)
			(xy 298.889684 -297.618511) (xy 298.843668 -297.601059) (xy 298.801047 -297.576452) (xy 298.762926 -297.545327)
			(xy 298.730291 -297.50849) (xy 298.703988 -297.466894) (xy 298.684697 -297.421618) (xy 298.67292 -297.373834)
			(xy 298.66896 -297.32478) (xy 298.330112 -297.32478) (xy 298.329617 -297.349387) (xy 298.321722 -297.397964)
			(xy 298.306138 -297.444645) (xy 298.283267 -297.488222) (xy 298.253702 -297.527566) (xy 298.218209 -297.561658)
			(xy 298.177706 -297.589614) (xy 298.133244 -297.610712) (xy 298.085973 -297.624404) (xy 298.037118 -297.630336)
			(xy 297.987943 -297.628355) (xy 297.939724 -297.618511) (xy 297.893708 -297.601059) (xy 297.851087 -297.576452)
			(xy 297.812966 -297.545327) (xy 297.780331 -297.50849) (xy 297.754028 -297.466894) (xy 297.734737 -297.421618)
			(xy 297.72296 -297.373834) (xy 297.719 -297.32478) (xy 297.380152 -297.32478) (xy 297.379657 -297.349387)
			(xy 297.371762 -297.397964) (xy 297.356178 -297.444645) (xy 297.333307 -297.488222) (xy 297.303742 -297.527566)
			(xy 297.268249 -297.561658) (xy 297.227746 -297.589614) (xy 297.183284 -297.610712) (xy 297.136013 -297.624404)
			(xy 297.087158 -297.630336) (xy 297.037983 -297.628355) (xy 296.989764 -297.618511) (xy 296.943748 -297.601059)
			(xy 296.901127 -297.576452) (xy 296.863006 -297.545327) (xy 296.830371 -297.50849) (xy 296.804068 -297.466894)
			(xy 296.784777 -297.421618) (xy 296.773 -297.373834) (xy 296.76904 -297.32478) (xy 296.430192 -297.32478)
			(xy 296.429697 -297.349387) (xy 296.421802 -297.397964) (xy 296.406218 -297.444645) (xy 296.383347 -297.488222)
			(xy 296.353782 -297.527566) (xy 296.318289 -297.561658) (xy 296.277786 -297.589614) (xy 296.233324 -297.610712)
			(xy 296.186053 -297.624404) (xy 296.137198 -297.630336) (xy 296.088023 -297.628355) (xy 296.039804 -297.618511)
			(xy 295.993788 -297.601059) (xy 295.951167 -297.576452) (xy 295.913046 -297.545327) (xy 295.880411 -297.50849)
			(xy 295.854108 -297.466894) (xy 295.834817 -297.421618) (xy 295.82304 -297.373834) (xy 295.81908 -297.32478)
			(xy 295.480232 -297.32478) (xy 295.479737 -297.349387) (xy 295.471842 -297.397964) (xy 295.456258 -297.444645)
			(xy 295.433387 -297.488222) (xy 295.403822 -297.527566) (xy 295.368329 -297.561658) (xy 295.327826 -297.589614)
			(xy 295.283364 -297.610712) (xy 295.236093 -297.624404) (xy 295.187238 -297.630336) (xy 295.138063 -297.628355)
			(xy 295.089844 -297.618511) (xy 295.043828 -297.601059) (xy 295.001207 -297.576452) (xy 294.963086 -297.545327)
			(xy 294.930451 -297.50849) (xy 294.904148 -297.466894) (xy 294.884857 -297.421618) (xy 294.87308 -297.373834)
			(xy 294.86912 -297.32478) (xy 294.530018 -297.32478) (xy 294.529523 -297.349387) (xy 294.521628 -297.397964)
			(xy 294.506044 -297.444645) (xy 294.483173 -297.488222) (xy 294.453608 -297.527566) (xy 294.418115 -297.561658)
			(xy 294.377612 -297.589614) (xy 294.33315 -297.610712) (xy 294.285879 -297.624404) (xy 294.237024 -297.630336)
			(xy 294.187849 -297.628355) (xy 294.13963 -297.618511) (xy 294.093614 -297.601059) (xy 294.050993 -297.576452)
			(xy 294.012872 -297.545327) (xy 293.980237 -297.50849) (xy 293.953934 -297.466894) (xy 293.934643 -297.421618)
			(xy 293.922866 -297.373834) (xy 293.918906 -297.32478) (xy 293.580058 -297.32478) (xy 293.579563 -297.349387)
			(xy 293.571668 -297.397964) (xy 293.556084 -297.444645) (xy 293.533213 -297.488222) (xy 293.503648 -297.527566)
			(xy 293.468155 -297.561658) (xy 293.427652 -297.589614) (xy 293.38319 -297.610712) (xy 293.335919 -297.624404)
			(xy 293.287064 -297.630336) (xy 293.237889 -297.628355) (xy 293.18967 -297.618511) (xy 293.143654 -297.601059)
			(xy 293.101033 -297.576452) (xy 293.062912 -297.545327) (xy 293.030277 -297.50849) (xy 293.003974 -297.466894)
			(xy 292.984683 -297.421618) (xy 292.972906 -297.373834) (xy 292.968946 -297.32478) (xy 292.630098 -297.32478)
			(xy 292.629603 -297.349387) (xy 292.621708 -297.397964) (xy 292.606124 -297.444645) (xy 292.583253 -297.488222)
			(xy 292.553688 -297.527566) (xy 292.518195 -297.561658) (xy 292.477692 -297.589614) (xy 292.43323 -297.610712)
			(xy 292.385959 -297.624404) (xy 292.337104 -297.630336) (xy 292.287929 -297.628355) (xy 292.23971 -297.618511)
			(xy 292.193694 -297.601059) (xy 292.151073 -297.576452) (xy 292.112952 -297.545327) (xy 292.080317 -297.50849)
			(xy 292.054014 -297.466894) (xy 292.034723 -297.421618) (xy 292.022946 -297.373834) (xy 292.018986 -297.32478)
			(xy 290.730178 -297.32478) (xy 290.729683 -297.349387) (xy 290.721788 -297.397964) (xy 290.706204 -297.444645)
			(xy 290.683333 -297.488222) (xy 290.653768 -297.527566) (xy 290.618275 -297.561658) (xy 290.577772 -297.589614)
			(xy 290.53331 -297.610712) (xy 290.486039 -297.624404) (xy 290.437184 -297.630336) (xy 290.388009 -297.628355)
			(xy 290.33979 -297.618511) (xy 290.293774 -297.601059) (xy 290.251153 -297.576452) (xy 290.213032 -297.545327)
			(xy 290.180397 -297.50849) (xy 290.154094 -297.466894) (xy 290.134803 -297.421618) (xy 290.123026 -297.373834)
			(xy 290.119066 -297.32478) (xy 289.780218 -297.32478) (xy 289.779723 -297.349387) (xy 289.771828 -297.397964)
			(xy 289.756244 -297.444645) (xy 289.733373 -297.488222) (xy 289.703808 -297.527566) (xy 289.668315 -297.561658)
			(xy 289.627812 -297.589614) (xy 289.58335 -297.610712) (xy 289.536079 -297.624404) (xy 289.487224 -297.630336)
			(xy 289.438049 -297.628355) (xy 289.38983 -297.618511) (xy 289.343814 -297.601059) (xy 289.301193 -297.576452)
			(xy 289.263072 -297.545327) (xy 289.230437 -297.50849) (xy 289.204134 -297.466894) (xy 289.184843 -297.421618)
			(xy 289.173066 -297.373834) (xy 289.169106 -297.32478) (xy 288.830004 -297.32478) (xy 288.829509 -297.349387)
			(xy 288.821614 -297.397964) (xy 288.80603 -297.444645) (xy 288.783159 -297.488222) (xy 288.753594 -297.527566)
			(xy 288.718101 -297.561658) (xy 288.677598 -297.589614) (xy 288.633136 -297.610712) (xy 288.585865 -297.624404)
			(xy 288.53701 -297.630336) (xy 288.487835 -297.628355) (xy 288.439616 -297.618511) (xy 288.3936 -297.601059)
			(xy 288.350979 -297.576452) (xy 288.312858 -297.545327) (xy 288.280223 -297.50849) (xy 288.25392 -297.466894)
			(xy 288.234629 -297.421618) (xy 288.222852 -297.373834) (xy 288.218892 -297.32478) (xy 287.880044 -297.32478)
			(xy 287.879549 -297.349387) (xy 287.871654 -297.397964) (xy 287.85607 -297.444645) (xy 287.833199 -297.488222)
			(xy 287.803634 -297.527566) (xy 287.768141 -297.561658) (xy 287.727638 -297.589614) (xy 287.683176 -297.610712)
			(xy 287.635905 -297.624404) (xy 287.58705 -297.630336) (xy 287.537875 -297.628355) (xy 287.489656 -297.618511)
			(xy 287.44364 -297.601059) (xy 287.401019 -297.576452) (xy 287.362898 -297.545327) (xy 287.330263 -297.50849)
			(xy 287.30396 -297.466894) (xy 287.284669 -297.421618) (xy 287.272892 -297.373834) (xy 287.268932 -297.32478)
			(xy 286.930084 -297.32478) (xy 286.929589 -297.349387) (xy 286.921694 -297.397964) (xy 286.90611 -297.444645)
			(xy 286.883239 -297.488222) (xy 286.853674 -297.527566) (xy 286.818181 -297.561658) (xy 286.777678 -297.589614)
			(xy 286.733216 -297.610712) (xy 286.685945 -297.624404) (xy 286.63709 -297.630336) (xy 286.587915 -297.628355)
			(xy 286.539696 -297.618511) (xy 286.49368 -297.601059) (xy 286.451059 -297.576452) (xy 286.412938 -297.545327)
			(xy 286.380303 -297.50849) (xy 286.354 -297.466894) (xy 286.334709 -297.421618) (xy 286.322932 -297.373834)
			(xy 286.318972 -297.32478) (xy 285.980124 -297.32478) (xy 285.979629 -297.349387) (xy 285.971734 -297.397964)
			(xy 285.95615 -297.444645) (xy 285.933279 -297.488222) (xy 285.903714 -297.527566) (xy 285.868221 -297.561658)
			(xy 285.827718 -297.589614) (xy 285.783256 -297.610712) (xy 285.735985 -297.624404) (xy 285.68713 -297.630336)
			(xy 285.637955 -297.628355) (xy 285.589736 -297.618511) (xy 285.54372 -297.601059) (xy 285.501099 -297.576452)
			(xy 285.462978 -297.545327) (xy 285.430343 -297.50849) (xy 285.40404 -297.466894) (xy 285.384749 -297.421618)
			(xy 285.372972 -297.373834) (xy 285.369012 -297.32478) (xy 285.030164 -297.32478) (xy 285.029669 -297.349387)
			(xy 285.021774 -297.397964) (xy 285.00619 -297.444645) (xy 284.983319 -297.488222) (xy 284.953754 -297.527566)
			(xy 284.918261 -297.561658) (xy 284.877758 -297.589614) (xy 284.833296 -297.610712) (xy 284.786025 -297.624404)
			(xy 284.73717 -297.630336) (xy 284.687995 -297.628355) (xy 284.639776 -297.618511) (xy 284.59376 -297.601059)
			(xy 284.551139 -297.576452) (xy 284.513018 -297.545327) (xy 284.480383 -297.50849) (xy 284.45408 -297.466894)
			(xy 284.434789 -297.421618) (xy 284.423012 -297.373834) (xy 284.419052 -297.32478) (xy 284.080204 -297.32478)
			(xy 284.079709 -297.349387) (xy 284.071814 -297.397964) (xy 284.05623 -297.444645) (xy 284.033359 -297.488222)
			(xy 284.003794 -297.527566) (xy 283.968301 -297.561658) (xy 283.927798 -297.589614) (xy 283.883336 -297.610712)
			(xy 283.836065 -297.624404) (xy 283.78721 -297.630336) (xy 283.738035 -297.628355) (xy 283.689816 -297.618511)
			(xy 283.6438 -297.601059) (xy 283.601179 -297.576452) (xy 283.563058 -297.545327) (xy 283.530423 -297.50849)
			(xy 283.50412 -297.466894) (xy 283.484829 -297.421618) (xy 283.473052 -297.373834) (xy 283.469092 -297.32478)
			(xy 283.130244 -297.32478) (xy 283.129749 -297.349387) (xy 283.121854 -297.397964) (xy 283.10627 -297.444645)
			(xy 283.083399 -297.488222) (xy 283.053834 -297.527566) (xy 283.018341 -297.561658) (xy 282.977838 -297.589614)
			(xy 282.933376 -297.610712) (xy 282.886105 -297.624404) (xy 282.83725 -297.630336) (xy 282.788075 -297.628355)
			(xy 282.739856 -297.618511) (xy 282.69384 -297.601059) (xy 282.651219 -297.576452) (xy 282.613098 -297.545327)
			(xy 282.580463 -297.50849) (xy 282.55416 -297.466894) (xy 282.534869 -297.421618) (xy 282.523092 -297.373834)
			(xy 282.519132 -297.32478) (xy 282.18003 -297.32478) (xy 282.179535 -297.349387) (xy 282.17164 -297.397964)
			(xy 282.156056 -297.444645) (xy 282.133185 -297.488222) (xy 282.10362 -297.527566) (xy 282.068127 -297.561658)
			(xy 282.027624 -297.589614) (xy 281.983162 -297.610712) (xy 281.935891 -297.624404) (xy 281.887036 -297.630336)
			(xy 281.837861 -297.628355) (xy 281.789642 -297.618511) (xy 281.743626 -297.601059) (xy 281.701005 -297.576452)
			(xy 281.662884 -297.545327) (xy 281.630249 -297.50849) (xy 281.603946 -297.466894) (xy 281.584655 -297.421618)
			(xy 281.572878 -297.373834) (xy 281.568918 -297.32478) (xy 281.23007 -297.32478) (xy 281.229575 -297.349387)
			(xy 281.22168 -297.397964) (xy 281.206096 -297.444645) (xy 281.183225 -297.488222) (xy 281.15366 -297.527566)
			(xy 281.118167 -297.561658) (xy 281.077664 -297.589614) (xy 281.033202 -297.610712) (xy 280.985931 -297.624404)
			(xy 280.937076 -297.630336) (xy 280.887901 -297.628355) (xy 280.839682 -297.618511) (xy 280.793666 -297.601059)
			(xy 280.751045 -297.576452) (xy 280.712924 -297.545327) (xy 280.680289 -297.50849) (xy 280.653986 -297.466894)
			(xy 280.634695 -297.421618) (xy 280.622918 -297.373834) (xy 280.618958 -297.32478) (xy 280.28011 -297.32478)
			(xy 280.279615 -297.349387) (xy 280.27172 -297.397964) (xy 280.256136 -297.444645) (xy 280.233265 -297.488222)
			(xy 280.2037 -297.527566) (xy 280.168207 -297.561658) (xy 280.127704 -297.589614) (xy 280.083242 -297.610712)
			(xy 280.035971 -297.624404) (xy 279.987116 -297.630336) (xy 279.937941 -297.628355) (xy 279.889722 -297.618511)
			(xy 279.843706 -297.601059) (xy 279.801085 -297.576452) (xy 279.762964 -297.545327) (xy 279.730329 -297.50849)
			(xy 279.704026 -297.466894) (xy 279.684735 -297.421618) (xy 279.672958 -297.373834) (xy 279.668998 -297.32478)
			(xy 279.33015 -297.32478) (xy 279.329655 -297.349387) (xy 279.32176 -297.397964) (xy 279.306176 -297.444645)
			(xy 279.283305 -297.488222) (xy 279.25374 -297.527566) (xy 279.218247 -297.561658) (xy 279.177744 -297.589614)
			(xy 279.133282 -297.610712) (xy 279.086011 -297.624404) (xy 279.037156 -297.630336) (xy 278.987981 -297.628355)
			(xy 278.939762 -297.618511) (xy 278.893746 -297.601059) (xy 278.851125 -297.576452) (xy 278.813004 -297.545327)
			(xy 278.780369 -297.50849) (xy 278.754066 -297.466894) (xy 278.734775 -297.421618) (xy 278.722998 -297.373834)
			(xy 278.719038 -297.32478) (xy 278.38019 -297.32478) (xy 278.379695 -297.349387) (xy 278.3718 -297.397964)
			(xy 278.356216 -297.444645) (xy 278.333345 -297.488222) (xy 278.30378 -297.527566) (xy 278.268287 -297.561658)
			(xy 278.227784 -297.589614) (xy 278.183322 -297.610712) (xy 278.136051 -297.624404) (xy 278.087196 -297.630336)
			(xy 278.038021 -297.628355) (xy 277.989802 -297.618511) (xy 277.943786 -297.601059) (xy 277.901165 -297.576452)
			(xy 277.863044 -297.545327) (xy 277.830409 -297.50849) (xy 277.804106 -297.466894) (xy 277.784815 -297.421618)
			(xy 277.773038 -297.373834) (xy 277.769078 -297.32478) (xy 277.43023 -297.32478) (xy 277.429735 -297.349387)
			(xy 277.42184 -297.397964) (xy 277.406256 -297.444645) (xy 277.383385 -297.488222) (xy 277.35382 -297.527566)
			(xy 277.318327 -297.561658) (xy 277.277824 -297.589614) (xy 277.233362 -297.610712) (xy 277.186091 -297.624404)
			(xy 277.137236 -297.630336) (xy 277.088061 -297.628355) (xy 277.039842 -297.618511) (xy 276.993826 -297.601059)
			(xy 276.951205 -297.576452) (xy 276.913084 -297.545327) (xy 276.880449 -297.50849) (xy 276.854146 -297.466894)
			(xy 276.834855 -297.421618) (xy 276.823078 -297.373834) (xy 276.819118 -297.32478) (xy 276.480016 -297.32478)
			(xy 276.479521 -297.349387) (xy 276.471626 -297.397964) (xy 276.456042 -297.444645) (xy 276.433171 -297.488222)
			(xy 276.403606 -297.527566) (xy 276.368113 -297.561658) (xy 276.32761 -297.589614) (xy 276.283148 -297.610712)
			(xy 276.235877 -297.624404) (xy 276.187022 -297.630336) (xy 276.137847 -297.628355) (xy 276.089628 -297.618511)
			(xy 276.043612 -297.601059) (xy 276.000991 -297.576452) (xy 275.96287 -297.545327) (xy 275.930235 -297.50849)
			(xy 275.903932 -297.466894) (xy 275.884641 -297.421618) (xy 275.872864 -297.373834) (xy 275.868904 -297.32478)
			(xy 274.580096 -297.32478) (xy 274.579601 -297.349387) (xy 274.571706 -297.397964) (xy 274.556122 -297.444645)
			(xy 274.533251 -297.488222) (xy 274.503686 -297.527566) (xy 274.468193 -297.561658) (xy 274.42769 -297.589614)
			(xy 274.383228 -297.610712) (xy 274.335957 -297.624404) (xy 274.287102 -297.630336) (xy 274.237927 -297.628355)
			(xy 274.189708 -297.618511) (xy 274.143692 -297.601059) (xy 274.101071 -297.576452) (xy 274.06295 -297.545327)
			(xy 274.030315 -297.50849) (xy 274.004012 -297.466894) (xy 273.984721 -297.421618) (xy 273.972944 -297.373834)
			(xy 273.968984 -297.32478) (xy 271.730216 -297.32478) (xy 271.729721 -297.349387) (xy 271.721826 -297.397964)
			(xy 271.706242 -297.444645) (xy 271.683371 -297.488222) (xy 271.653806 -297.527566) (xy 271.618313 -297.561658)
			(xy 271.57781 -297.589614) (xy 271.533348 -297.610712) (xy 271.486077 -297.624404) (xy 271.437222 -297.630336)
			(xy 271.388047 -297.628355) (xy 271.339828 -297.618511) (xy 271.293812 -297.601059) (xy 271.251191 -297.576452)
			(xy 271.21307 -297.545327) (xy 271.180435 -297.50849) (xy 271.154132 -297.466894) (xy 271.134841 -297.421618)
			(xy 271.123064 -297.373834) (xy 271.119104 -297.32478) (xy 270.780002 -297.32478) (xy 270.779507 -297.349387)
			(xy 270.771612 -297.397964) (xy 270.756028 -297.444645) (xy 270.733157 -297.488222) (xy 270.703592 -297.527566)
			(xy 270.668099 -297.561658) (xy 270.627596 -297.589614) (xy 270.583134 -297.610712) (xy 270.535863 -297.624404)
			(xy 270.487008 -297.630336) (xy 270.437833 -297.628355) (xy 270.389614 -297.618511) (xy 270.343598 -297.601059)
			(xy 270.300977 -297.576452) (xy 270.262856 -297.545327) (xy 270.230221 -297.50849) (xy 270.203918 -297.466894)
			(xy 270.184627 -297.421618) (xy 270.17285 -297.373834) (xy 270.16889 -297.32478) (xy 269.854705 -297.32478)
			(xy 269.854705 -297.350789) (xy 269.846573 -297.402126) (xy 269.830511 -297.451559) (xy 269.806913 -297.497871)
			(xy 269.77636 -297.539921) (xy 269.739606 -297.576673) (xy 269.697554 -297.607223) (xy 269.651241 -297.630819)
			(xy 269.601807 -297.646878) (xy 269.550469 -297.655006) (xy 269.52448 -297.655488) (xy 268.57452 -297.655488)
			(xy 268.550146 -297.655084) (xy 268.501926 -297.647935) (xy 268.455276 -297.63379) (xy 268.411206 -297.612953)
			(xy 268.370669 -297.585877) (xy 268.334544 -297.553147) (xy 268.318742 -297.534584) (xy 268.31163 -297.525948)
			(xy 268.292072 -297.51655) (xy 268.192758 -297.513756) (xy 268.172946 -297.522392) (xy 268.165326 -297.53052)
			(xy 268.14784 -297.548945) (xy 268.107876 -297.580296) (xy 268.063274 -297.604598) (xy 268.015264 -297.62118)
			(xy 267.965171 -297.629585) (xy 267.939774 -297.630088) (xy 267.914518 -297.629604) (xy 267.864697 -297.621287)
			(xy 267.816923 -297.604882) (xy 267.772502 -297.580839) (xy 267.732643 -297.549813) (xy 267.698434 -297.512649)
			(xy 267.670808 -297.470362) (xy 267.650519 -297.424104) (xy 267.63812 -297.375139) (xy 267.633949 -297.3248)
			(xy 255.728449 -297.3248) (xy 255.728724 -297.369992) (xy 255.728223 -297.452279) (xy 255.72021 -297.616658)
			(xy 255.704204 -297.780453) (xy 255.696727 -297.831256) (xy 258.01142 -297.831256) (xy 258.015491 -297.775634)
			(xy 258.027617 -297.721197) (xy 258.04754 -297.669106) (xy 258.074836 -297.620471) (xy 258.108922 -297.576328)
			(xy 258.149071 -297.537619) (xy 258.194429 -297.505168) (xy 258.244029 -297.479667) (xy 258.296813 -297.46166)
			(xy 258.351656 -297.45153) (xy 258.40739 -297.449493) (xy 258.462827 -297.455593) (xy 258.516784 -297.469699)
			(xy 258.568113 -297.491511) (xy 258.615719 -297.520565) (xy 258.658587 -297.55624) (xy 258.695804 -297.597777)
			(xy 258.726577 -297.64429) (xy 258.750249 -297.694787) (xy 258.766317 -297.748194) (xy 258.774437 -297.80337)
			(xy 258.774946 -297.831256) (xy 258.774437 -297.859142) (xy 258.766317 -297.914318) (xy 258.750249 -297.967725)
			(xy 258.726577 -298.018222) (xy 258.695804 -298.064735) (xy 258.658587 -298.106272) (xy 258.615719 -298.141947)
			(xy 258.568113 -298.171001) (xy 258.516784 -298.192813) (xy 258.462827 -298.206919) (xy 258.40739 -298.213019)
			(xy 258.351656 -298.210982) (xy 258.296813 -298.200852) (xy 258.244029 -298.182845) (xy 258.194429 -298.157344)
			(xy 258.149071 -298.124893) (xy 258.108922 -298.086184) (xy 258.074836 -298.042041) (xy 258.04754 -297.993406)
			(xy 258.027617 -297.941315) (xy 258.015491 -297.886878) (xy 258.01142 -297.831256) (xy 255.696727 -297.831256)
			(xy 255.680242 -297.943273) (xy 255.64838 -298.104734) (xy 255.608696 -298.264452) (xy 255.561282 -298.422049)
			(xy 255.506252 -298.57715) (xy 255.443735 -298.729388) (xy 255.37388 -298.878401) (xy 255.296853 -299.023837)
			(xy 255.231738 -299.133514) (xy 258.01142 -299.133514) (xy 258.015491 -299.077892) (xy 258.027617 -299.023455)
			(xy 258.04754 -298.971364) (xy 258.074836 -298.922729) (xy 258.108922 -298.878586) (xy 258.149071 -298.839877)
			(xy 258.194429 -298.807426) (xy 258.244029 -298.781925) (xy 258.296813 -298.763918) (xy 258.351656 -298.753788)
			(xy 258.40739 -298.751751) (xy 258.462827 -298.757851) (xy 258.516784 -298.771957) (xy 258.568113 -298.793769)
			(xy 258.615719 -298.822823) (xy 258.658587 -298.858498) (xy 258.695804 -298.900035) (xy 258.726577 -298.946548)
			(xy 258.750249 -298.997045) (xy 258.766317 -299.050452) (xy 258.774437 -299.105628) (xy 258.774946 -299.133514)
			(xy 259.487416 -299.133514) (xy 259.487921 -299.105172) (xy 259.496306 -299.049112) (xy 259.512894 -298.994909)
			(xy 259.53732 -298.943758) (xy 259.569045 -298.896784) (xy 259.607372 -298.855021) (xy 259.651457 -298.819389)
			(xy 259.67563 -298.804584) (xy 259.68821 -298.796603) (xy 259.708492 -298.774803) (xy 259.721622 -298.748078)
			(xy 259.726483 -298.718702) (xy 259.722662 -298.689172) (xy 259.710483 -298.662001) (xy 259.690983 -298.639499)
			(xy 259.678678 -298.631102) (xy 259.655814 -298.615989) (xy 259.614221 -298.580303) (xy 259.578163 -298.539032)
			(xy 259.548382 -298.493025) (xy 259.525492 -298.44323) (xy 259.509964 -298.390672) (xy 259.502116 -298.336432)
			(xy 259.50164 -298.30903) (xy 259.502126 -298.281779) (xy 259.509882 -298.227831) (xy 259.525237 -298.175536)
			(xy 259.547879 -298.125959) (xy 259.577345 -298.080109) (xy 259.613036 -298.038918) (xy 259.654227 -298.003227)
			(xy 259.700077 -297.973761) (xy 259.749654 -297.951119) (xy 259.801949 -297.935764) (xy 259.855897 -297.928008)
			(xy 259.910399 -297.928008) (xy 259.964347 -297.935764) (xy 260.016642 -297.951119) (xy 260.066219 -297.973761)
			(xy 260.112069 -298.003227) (xy 260.15326 -298.038918) (xy 260.188951 -298.080109) (xy 260.218417 -298.125959)
			(xy 260.241059 -298.175536) (xy 260.256414 -298.227831) (xy 260.263158 -298.27474) (xy 269.218676 -298.27474)
			(xy 269.222636 -298.225686) (xy 269.234413 -298.177902) (xy 269.253704 -298.132626) (xy 269.280007 -298.09103)
			(xy 269.312642 -298.054193) (xy 269.350763 -298.023068) (xy 269.393384 -297.998461) (xy 269.4394 -297.981009)
			(xy 269.487619 -297.971165) (xy 269.536794 -297.969184) (xy 269.585649 -297.975116) (xy 269.63292 -297.988808)
			(xy 269.677382 -298.009906) (xy 269.717885 -298.037862) (xy 269.753378 -298.071954) (xy 269.782943 -298.111298)
			(xy 269.805814 -298.154875) (xy 269.821398 -298.201556) (xy 269.829293 -298.250133) (xy 269.829788 -298.27474)
			(xy 270.16889 -298.27474) (xy 270.17285 -298.225686) (xy 270.184627 -298.177902) (xy 270.203918 -298.132626)
			(xy 270.230221 -298.09103) (xy 270.262856 -298.054193) (xy 270.300977 -298.023068) (xy 270.343598 -297.998461)
			(xy 270.389614 -297.981009) (xy 270.437833 -297.971165) (xy 270.487008 -297.969184) (xy 270.535863 -297.975116)
			(xy 270.583134 -297.988808) (xy 270.627596 -298.009906) (xy 270.668099 -298.037862) (xy 270.703592 -298.071954)
			(xy 270.733157 -298.111298) (xy 270.756028 -298.154875) (xy 270.771612 -298.201556) (xy 270.779507 -298.250133)
			(xy 270.780002 -298.27474) (xy 271.119104 -298.27474) (xy 271.123064 -298.225686) (xy 271.134841 -298.177902)
			(xy 271.154132 -298.132626) (xy 271.180435 -298.09103) (xy 271.21307 -298.054193) (xy 271.251191 -298.023068)
			(xy 271.293812 -297.998461) (xy 271.339828 -297.981009) (xy 271.388047 -297.971165) (xy 271.437222 -297.969184)
			(xy 271.486077 -297.975116) (xy 271.533348 -297.988808) (xy 271.57781 -298.009906) (xy 271.618313 -298.037862)
			(xy 271.653806 -298.071954) (xy 271.683371 -298.111298) (xy 271.706242 -298.154875) (xy 271.721826 -298.201556)
			(xy 271.729721 -298.250133) (xy 271.730216 -298.27474) (xy 272.069064 -298.27474) (xy 272.073024 -298.225686)
			(xy 272.084801 -298.177902) (xy 272.104092 -298.132626) (xy 272.130395 -298.09103) (xy 272.16303 -298.054193)
			(xy 272.201151 -298.023068) (xy 272.243772 -297.998461) (xy 272.289788 -297.981009) (xy 272.338007 -297.971165)
			(xy 272.387182 -297.969184) (xy 272.436037 -297.975116) (xy 272.483308 -297.988808) (xy 272.52777 -298.009906)
			(xy 272.568273 -298.037862) (xy 272.603766 -298.071954) (xy 272.633331 -298.111298) (xy 272.656202 -298.154875)
			(xy 272.671786 -298.201556) (xy 272.679681 -298.250133) (xy 272.680176 -298.27474) (xy 273.019024 -298.27474)
			(xy 273.022984 -298.225686) (xy 273.034761 -298.177902) (xy 273.054052 -298.132626) (xy 273.080355 -298.09103)
			(xy 273.11299 -298.054193) (xy 273.151111 -298.023068) (xy 273.193732 -297.998461) (xy 273.239748 -297.981009)
			(xy 273.287967 -297.971165) (xy 273.337142 -297.969184) (xy 273.385997 -297.975116) (xy 273.433268 -297.988808)
			(xy 273.47773 -298.009906) (xy 273.518233 -298.037862) (xy 273.553726 -298.071954) (xy 273.583291 -298.111298)
			(xy 273.606162 -298.154875) (xy 273.621746 -298.201556) (xy 273.629641 -298.250133) (xy 273.630136 -298.27474)
			(xy 273.968984 -298.27474) (xy 273.972944 -298.225686) (xy 273.984721 -298.177902) (xy 274.004012 -298.132626)
			(xy 274.030315 -298.09103) (xy 274.06295 -298.054193) (xy 274.101071 -298.023068) (xy 274.143692 -297.998461)
			(xy 274.189708 -297.981009) (xy 274.237927 -297.971165) (xy 274.287102 -297.969184) (xy 274.335957 -297.975116)
			(xy 274.383228 -297.988808) (xy 274.42769 -298.009906) (xy 274.468193 -298.037862) (xy 274.503686 -298.071954)
			(xy 274.533251 -298.111298) (xy 274.556122 -298.154875) (xy 274.571706 -298.201556) (xy 274.579601 -298.250133)
			(xy 274.580096 -298.27474) (xy 275.868904 -298.27474) (xy 275.872864 -298.225686) (xy 275.884641 -298.177902)
			(xy 275.903932 -298.132626) (xy 275.930235 -298.09103) (xy 275.96287 -298.054193) (xy 276.000991 -298.023068)
			(xy 276.043612 -297.998461) (xy 276.089628 -297.981009) (xy 276.137847 -297.971165) (xy 276.187022 -297.969184)
			(xy 276.235877 -297.975116) (xy 276.283148 -297.988808) (xy 276.32761 -298.009906) (xy 276.368113 -298.037862)
			(xy 276.403606 -298.071954) (xy 276.433171 -298.111298) (xy 276.456042 -298.154875) (xy 276.471626 -298.201556)
			(xy 276.479521 -298.250133) (xy 276.480016 -298.27474) (xy 276.819118 -298.27474) (xy 276.823078 -298.225686)
			(xy 276.834855 -298.177902) (xy 276.854146 -298.132626) (xy 276.880449 -298.09103) (xy 276.913084 -298.054193)
			(xy 276.951205 -298.023068) (xy 276.993826 -297.998461) (xy 277.039842 -297.981009) (xy 277.088061 -297.971165)
			(xy 277.137236 -297.969184) (xy 277.186091 -297.975116) (xy 277.233362 -297.988808) (xy 277.277824 -298.009906)
			(xy 277.318327 -298.037862) (xy 277.35382 -298.071954) (xy 277.383385 -298.111298) (xy 277.406256 -298.154875)
			(xy 277.42184 -298.201556) (xy 277.429735 -298.250133) (xy 277.43023 -298.27474) (xy 277.769078 -298.27474)
			(xy 277.773038 -298.225686) (xy 277.784815 -298.177902) (xy 277.804106 -298.132626) (xy 277.830409 -298.09103)
			(xy 277.863044 -298.054193) (xy 277.901165 -298.023068) (xy 277.943786 -297.998461) (xy 277.989802 -297.981009)
			(xy 278.038021 -297.971165) (xy 278.087196 -297.969184) (xy 278.136051 -297.975116) (xy 278.183322 -297.988808)
			(xy 278.227784 -298.009906) (xy 278.268287 -298.037862) (xy 278.30378 -298.071954) (xy 278.333345 -298.111298)
			(xy 278.356216 -298.154875) (xy 278.3718 -298.201556) (xy 278.379695 -298.250133) (xy 278.38019 -298.27474)
			(xy 279.668998 -298.27474) (xy 279.672958 -298.225686) (xy 279.684735 -298.177902) (xy 279.704026 -298.132626)
			(xy 279.730329 -298.09103) (xy 279.762964 -298.054193) (xy 279.801085 -298.023068) (xy 279.843706 -297.998461)
			(xy 279.889722 -297.981009) (xy 279.937941 -297.971165) (xy 279.987116 -297.969184) (xy 280.035971 -297.975116)
			(xy 280.083242 -297.988808) (xy 280.127704 -298.009906) (xy 280.168207 -298.037862) (xy 280.2037 -298.071954)
			(xy 280.233265 -298.111298) (xy 280.256136 -298.154875) (xy 280.27172 -298.201556) (xy 280.279615 -298.250133)
			(xy 280.28011 -298.27474) (xy 280.618958 -298.27474) (xy 280.622918 -298.225686) (xy 280.634695 -298.177902)
			(xy 280.653986 -298.132626) (xy 280.680289 -298.09103) (xy 280.712924 -298.054193) (xy 280.751045 -298.023068)
			(xy 280.793666 -297.998461) (xy 280.839682 -297.981009) (xy 280.887901 -297.971165) (xy 280.937076 -297.969184)
			(xy 280.985931 -297.975116) (xy 281.033202 -297.988808) (xy 281.077664 -298.009906) (xy 281.118167 -298.037862)
			(xy 281.15366 -298.071954) (xy 281.183225 -298.111298) (xy 281.206096 -298.154875) (xy 281.22168 -298.201556)
			(xy 281.229575 -298.250133) (xy 281.23007 -298.27474) (xy 281.568918 -298.27474) (xy 281.572878 -298.225686)
			(xy 281.584655 -298.177902) (xy 281.603946 -298.132626) (xy 281.630249 -298.09103) (xy 281.662884 -298.054193)
			(xy 281.701005 -298.023068) (xy 281.743626 -297.998461) (xy 281.789642 -297.981009) (xy 281.837861 -297.971165)
			(xy 281.887036 -297.969184) (xy 281.935891 -297.975116) (xy 281.983162 -297.988808) (xy 282.027624 -298.009906)
			(xy 282.068127 -298.037862) (xy 282.10362 -298.071954) (xy 282.133185 -298.111298) (xy 282.156056 -298.154875)
			(xy 282.17164 -298.201556) (xy 282.179535 -298.250133) (xy 282.18003 -298.27474) (xy 282.519132 -298.27474)
			(xy 282.523092 -298.225686) (xy 282.534869 -298.177902) (xy 282.55416 -298.132626) (xy 282.580463 -298.09103)
			(xy 282.613098 -298.054193) (xy 282.651219 -298.023068) (xy 282.69384 -297.998461) (xy 282.739856 -297.981009)
			(xy 282.788075 -297.971165) (xy 282.83725 -297.969184) (xy 282.886105 -297.975116) (xy 282.933376 -297.988808)
			(xy 282.977838 -298.009906) (xy 283.018341 -298.037862) (xy 283.053834 -298.071954) (xy 283.083399 -298.111298)
			(xy 283.10627 -298.154875) (xy 283.121854 -298.201556) (xy 283.129749 -298.250133) (xy 283.130244 -298.27474)
			(xy 283.469092 -298.27474) (xy 283.473052 -298.225686) (xy 283.484829 -298.177902) (xy 283.50412 -298.132626)
			(xy 283.530423 -298.09103) (xy 283.563058 -298.054193) (xy 283.601179 -298.023068) (xy 283.6438 -297.998461)
			(xy 283.689816 -297.981009) (xy 283.738035 -297.971165) (xy 283.78721 -297.969184) (xy 283.836065 -297.975116)
			(xy 283.883336 -297.988808) (xy 283.927798 -298.009906) (xy 283.968301 -298.037862) (xy 284.003794 -298.071954)
			(xy 284.033359 -298.111298) (xy 284.05623 -298.154875) (xy 284.071814 -298.201556) (xy 284.079709 -298.250133)
			(xy 284.080204 -298.27474) (xy 284.419052 -298.27474) (xy 284.423012 -298.225686) (xy 284.434789 -298.177902)
			(xy 284.45408 -298.132626) (xy 284.480383 -298.09103) (xy 284.513018 -298.054193) (xy 284.551139 -298.023068)
			(xy 284.59376 -297.998461) (xy 284.639776 -297.981009) (xy 284.687995 -297.971165) (xy 284.73717 -297.969184)
			(xy 284.786025 -297.975116) (xy 284.833296 -297.988808) (xy 284.877758 -298.009906) (xy 284.918261 -298.037862)
			(xy 284.953754 -298.071954) (xy 284.983319 -298.111298) (xy 285.00619 -298.154875) (xy 285.021774 -298.201556)
			(xy 285.029669 -298.250133) (xy 285.030164 -298.27474) (xy 285.369012 -298.27474) (xy 285.372972 -298.225686)
			(xy 285.384749 -298.177902) (xy 285.40404 -298.132626) (xy 285.430343 -298.09103) (xy 285.462978 -298.054193)
			(xy 285.501099 -298.023068) (xy 285.54372 -297.998461) (xy 285.589736 -297.981009) (xy 285.637955 -297.971165)
			(xy 285.68713 -297.969184) (xy 285.735985 -297.975116) (xy 285.783256 -297.988808) (xy 285.827718 -298.009906)
			(xy 285.868221 -298.037862) (xy 285.903714 -298.071954) (xy 285.933279 -298.111298) (xy 285.95615 -298.154875)
			(xy 285.971734 -298.201556) (xy 285.979629 -298.250133) (xy 285.980124 -298.27474) (xy 286.318972 -298.27474)
			(xy 286.322932 -298.225686) (xy 286.334709 -298.177902) (xy 286.354 -298.132626) (xy 286.380303 -298.09103)
			(xy 286.412938 -298.054193) (xy 286.451059 -298.023068) (xy 286.49368 -297.998461) (xy 286.539696 -297.981009)
			(xy 286.587915 -297.971165) (xy 286.63709 -297.969184) (xy 286.685945 -297.975116) (xy 286.733216 -297.988808)
			(xy 286.777678 -298.009906) (xy 286.818181 -298.037862) (xy 286.853674 -298.071954) (xy 286.883239 -298.111298)
			(xy 286.90611 -298.154875) (xy 286.921694 -298.201556) (xy 286.929589 -298.250133) (xy 286.930084 -298.27474)
			(xy 287.268932 -298.27474) (xy 287.272892 -298.225686) (xy 287.284669 -298.177902) (xy 287.30396 -298.132626)
			(xy 287.330263 -298.09103) (xy 287.362898 -298.054193) (xy 287.401019 -298.023068) (xy 287.44364 -297.998461)
			(xy 287.489656 -297.981009) (xy 287.537875 -297.971165) (xy 287.58705 -297.969184) (xy 287.635905 -297.975116)
			(xy 287.683176 -297.988808) (xy 287.727638 -298.009906) (xy 287.768141 -298.037862) (xy 287.803634 -298.071954)
			(xy 287.833199 -298.111298) (xy 287.85607 -298.154875) (xy 287.871654 -298.201556) (xy 287.879549 -298.250133)
			(xy 287.880044 -298.27474) (xy 288.218892 -298.27474) (xy 288.222852 -298.225686) (xy 288.234629 -298.177902)
			(xy 288.25392 -298.132626) (xy 288.280223 -298.09103) (xy 288.312858 -298.054193) (xy 288.350979 -298.023068)
			(xy 288.3936 -297.998461) (xy 288.439616 -297.981009) (xy 288.487835 -297.971165) (xy 288.53701 -297.969184)
			(xy 288.585865 -297.975116) (xy 288.633136 -297.988808) (xy 288.677598 -298.009906) (xy 288.718101 -298.037862)
			(xy 288.753594 -298.071954) (xy 288.783159 -298.111298) (xy 288.80603 -298.154875) (xy 288.821614 -298.201556)
			(xy 288.829509 -298.250133) (xy 288.830004 -298.27474) (xy 289.169106 -298.27474) (xy 289.173066 -298.225686)
			(xy 289.184843 -298.177902) (xy 289.204134 -298.132626) (xy 289.230437 -298.09103) (xy 289.263072 -298.054193)
			(xy 289.301193 -298.023068) (xy 289.343814 -297.998461) (xy 289.38983 -297.981009) (xy 289.438049 -297.971165)
			(xy 289.487224 -297.969184) (xy 289.536079 -297.975116) (xy 289.58335 -297.988808) (xy 289.627812 -298.009906)
			(xy 289.668315 -298.037862) (xy 289.703808 -298.071954) (xy 289.733373 -298.111298) (xy 289.756244 -298.154875)
			(xy 289.771828 -298.201556) (xy 289.779723 -298.250133) (xy 289.780218 -298.27474) (xy 290.119066 -298.27474)
			(xy 290.123026 -298.225686) (xy 290.134803 -298.177902) (xy 290.154094 -298.132626) (xy 290.180397 -298.09103)
			(xy 290.213032 -298.054193) (xy 290.251153 -298.023068) (xy 290.293774 -297.998461) (xy 290.33979 -297.981009)
			(xy 290.388009 -297.971165) (xy 290.437184 -297.969184) (xy 290.486039 -297.975116) (xy 290.53331 -297.988808)
			(xy 290.577772 -298.009906) (xy 290.618275 -298.037862) (xy 290.653768 -298.071954) (xy 290.683333 -298.111298)
			(xy 290.706204 -298.154875) (xy 290.721788 -298.201556) (xy 290.729683 -298.250133) (xy 290.730178 -298.27474)
			(xy 292.018986 -298.27474) (xy 292.022946 -298.225686) (xy 292.034723 -298.177902) (xy 292.054014 -298.132626)
			(xy 292.080317 -298.09103) (xy 292.112952 -298.054193) (xy 292.151073 -298.023068) (xy 292.193694 -297.998461)
			(xy 292.23971 -297.981009) (xy 292.287929 -297.971165) (xy 292.337104 -297.969184) (xy 292.385959 -297.975116)
			(xy 292.43323 -297.988808) (xy 292.477692 -298.009906) (xy 292.518195 -298.037862) (xy 292.553688 -298.071954)
			(xy 292.583253 -298.111298) (xy 292.606124 -298.154875) (xy 292.621708 -298.201556) (xy 292.629603 -298.250133)
			(xy 292.630098 -298.27474) (xy 292.968946 -298.27474) (xy 292.972906 -298.225686) (xy 292.984683 -298.177902)
			(xy 293.003974 -298.132626) (xy 293.030277 -298.09103) (xy 293.062912 -298.054193) (xy 293.101033 -298.023068)
			(xy 293.143654 -297.998461) (xy 293.18967 -297.981009) (xy 293.237889 -297.971165) (xy 293.287064 -297.969184)
			(xy 293.335919 -297.975116) (xy 293.38319 -297.988808) (xy 293.427652 -298.009906) (xy 293.468155 -298.037862)
			(xy 293.503648 -298.071954) (xy 293.533213 -298.111298) (xy 293.556084 -298.154875) (xy 293.571668 -298.201556)
			(xy 293.579563 -298.250133) (xy 293.580058 -298.27474) (xy 293.918906 -298.27474) (xy 293.922866 -298.225686)
			(xy 293.934643 -298.177902) (xy 293.953934 -298.132626) (xy 293.980237 -298.09103) (xy 294.012872 -298.054193)
			(xy 294.050993 -298.023068) (xy 294.093614 -297.998461) (xy 294.13963 -297.981009) (xy 294.187849 -297.971165)
			(xy 294.237024 -297.969184) (xy 294.285879 -297.975116) (xy 294.33315 -297.988808) (xy 294.377612 -298.009906)
			(xy 294.418115 -298.037862) (xy 294.453608 -298.071954) (xy 294.483173 -298.111298) (xy 294.506044 -298.154875)
			(xy 294.521628 -298.201556) (xy 294.529523 -298.250133) (xy 294.530018 -298.27474) (xy 294.86912 -298.27474)
			(xy 294.87308 -298.225686) (xy 294.884857 -298.177902) (xy 294.904148 -298.132626) (xy 294.930451 -298.09103)
			(xy 294.963086 -298.054193) (xy 295.001207 -298.023068) (xy 295.043828 -297.998461) (xy 295.089844 -297.981009)
			(xy 295.138063 -297.971165) (xy 295.187238 -297.969184) (xy 295.236093 -297.975116) (xy 295.283364 -297.988808)
			(xy 295.327826 -298.009906) (xy 295.368329 -298.037862) (xy 295.403822 -298.071954) (xy 295.433387 -298.111298)
			(xy 295.456258 -298.154875) (xy 295.471842 -298.201556) (xy 295.479737 -298.250133) (xy 295.480232 -298.27474)
			(xy 295.81908 -298.27474) (xy 295.82304 -298.225686) (xy 295.834817 -298.177902) (xy 295.854108 -298.132626)
			(xy 295.880411 -298.09103) (xy 295.913046 -298.054193) (xy 295.951167 -298.023068) (xy 295.993788 -297.998461)
			(xy 296.039804 -297.981009) (xy 296.088023 -297.971165) (xy 296.137198 -297.969184) (xy 296.186053 -297.975116)
			(xy 296.233324 -297.988808) (xy 296.277786 -298.009906) (xy 296.318289 -298.037862) (xy 296.353782 -298.071954)
			(xy 296.383347 -298.111298) (xy 296.406218 -298.154875) (xy 296.421802 -298.201556) (xy 296.429697 -298.250133)
			(xy 296.430192 -298.27474) (xy 296.76904 -298.27474) (xy 296.773 -298.225686) (xy 296.784777 -298.177902)
			(xy 296.804068 -298.132626) (xy 296.830371 -298.09103) (xy 296.863006 -298.054193) (xy 296.901127 -298.023068)
			(xy 296.943748 -297.998461) (xy 296.989764 -297.981009) (xy 297.037983 -297.971165) (xy 297.087158 -297.969184)
			(xy 297.136013 -297.975116) (xy 297.183284 -297.988808) (xy 297.227746 -298.009906) (xy 297.268249 -298.037862)
			(xy 297.303742 -298.071954) (xy 297.333307 -298.111298) (xy 297.356178 -298.154875) (xy 297.371762 -298.201556)
			(xy 297.379657 -298.250133) (xy 297.380152 -298.27474) (xy 297.719 -298.27474) (xy 297.72296 -298.225686)
			(xy 297.734737 -298.177902) (xy 297.754028 -298.132626) (xy 297.780331 -298.09103) (xy 297.812966 -298.054193)
			(xy 297.851087 -298.023068) (xy 297.893708 -297.998461) (xy 297.939724 -297.981009) (xy 297.987943 -297.971165)
			(xy 298.037118 -297.969184) (xy 298.085973 -297.975116) (xy 298.133244 -297.988808) (xy 298.177706 -298.009906)
			(xy 298.218209 -298.037862) (xy 298.253702 -298.071954) (xy 298.283267 -298.111298) (xy 298.306138 -298.154875)
			(xy 298.321722 -298.201556) (xy 298.329617 -298.250133) (xy 298.330112 -298.27474) (xy 298.66896 -298.27474)
			(xy 298.67292 -298.225686) (xy 298.684697 -298.177902) (xy 298.703988 -298.132626) (xy 298.730291 -298.09103)
			(xy 298.762926 -298.054193) (xy 298.801047 -298.023068) (xy 298.843668 -297.998461) (xy 298.889684 -297.981009)
			(xy 298.937903 -297.971165) (xy 298.987078 -297.969184) (xy 299.035933 -297.975116) (xy 299.083204 -297.988808)
			(xy 299.127666 -298.009906) (xy 299.168169 -298.037862) (xy 299.203662 -298.071954) (xy 299.233227 -298.111298)
			(xy 299.256098 -298.154875) (xy 299.271682 -298.201556) (xy 299.279577 -298.250133) (xy 299.280072 -298.27474)
			(xy 299.61892 -298.27474) (xy 299.62288 -298.225686) (xy 299.634657 -298.177902) (xy 299.653948 -298.132626)
			(xy 299.680251 -298.09103) (xy 299.712886 -298.054193) (xy 299.751007 -298.023068) (xy 299.793628 -297.998461)
			(xy 299.839644 -297.981009) (xy 299.887863 -297.971165) (xy 299.937038 -297.969184) (xy 299.985893 -297.975116)
			(xy 300.033164 -297.988808) (xy 300.077626 -298.009906) (xy 300.118129 -298.037862) (xy 300.153622 -298.071954)
			(xy 300.183187 -298.111298) (xy 300.206058 -298.154875) (xy 300.221642 -298.201556) (xy 300.229537 -298.250133)
			(xy 300.230032 -298.27474) (xy 300.56888 -298.27474) (xy 300.57284 -298.225686) (xy 300.584617 -298.177902)
			(xy 300.603908 -298.132626) (xy 300.630211 -298.09103) (xy 300.662846 -298.054193) (xy 300.700967 -298.023068)
			(xy 300.743588 -297.998461) (xy 300.789604 -297.981009) (xy 300.837823 -297.971165) (xy 300.886998 -297.969184)
			(xy 300.935853 -297.975116) (xy 300.983124 -297.988808) (xy 301.027586 -298.009906) (xy 301.068089 -298.037862)
			(xy 301.103582 -298.071954) (xy 301.133147 -298.111298) (xy 301.156018 -298.154875) (xy 301.171602 -298.201556)
			(xy 301.179497 -298.250133) (xy 301.179992 -298.27474) (xy 301.519094 -298.27474) (xy 301.523054 -298.225686)
			(xy 301.534831 -298.177902) (xy 301.554122 -298.132626) (xy 301.580425 -298.09103) (xy 301.61306 -298.054193)
			(xy 301.651181 -298.023068) (xy 301.693802 -297.998461) (xy 301.739818 -297.981009) (xy 301.788037 -297.971165)
			(xy 301.837212 -297.969184) (xy 301.886067 -297.975116) (xy 301.933338 -297.988808) (xy 301.9778 -298.009906)
			(xy 302.018303 -298.037862) (xy 302.053796 -298.071954) (xy 302.083361 -298.111298) (xy 302.106232 -298.154875)
			(xy 302.121816 -298.201556) (xy 302.129711 -298.250133) (xy 302.130206 -298.27474) (xy 303.419014 -298.27474)
			(xy 303.422974 -298.225686) (xy 303.434751 -298.177902) (xy 303.454042 -298.132626) (xy 303.480345 -298.09103)
			(xy 303.51298 -298.054193) (xy 303.551101 -298.023068) (xy 303.593722 -297.998461) (xy 303.639738 -297.981009)
			(xy 303.687957 -297.971165) (xy 303.737132 -297.969184) (xy 303.785987 -297.975116) (xy 303.833258 -297.988808)
			(xy 303.87772 -298.009906) (xy 303.918223 -298.037862) (xy 303.953716 -298.071954) (xy 303.983281 -298.111298)
			(xy 304.006152 -298.154875) (xy 304.021736 -298.201556) (xy 304.029631 -298.250133) (xy 304.030126 -298.27474)
			(xy 304.368974 -298.27474) (xy 304.372934 -298.225686) (xy 304.384711 -298.177902) (xy 304.404002 -298.132626)
			(xy 304.430305 -298.09103) (xy 304.46294 -298.054193) (xy 304.501061 -298.023068) (xy 304.543682 -297.998461)
			(xy 304.589698 -297.981009) (xy 304.637917 -297.971165) (xy 304.687092 -297.969184) (xy 304.735947 -297.975116)
			(xy 304.783218 -297.988808) (xy 304.82768 -298.009906) (xy 304.868183 -298.037862) (xy 304.903676 -298.071954)
			(xy 304.933241 -298.111298) (xy 304.956112 -298.154875) (xy 304.971696 -298.201556) (xy 304.979591 -298.250133)
			(xy 304.980086 -298.27474) (xy 305.318934 -298.27474) (xy 305.322894 -298.225686) (xy 305.334671 -298.177902)
			(xy 305.353962 -298.132626) (xy 305.380265 -298.09103) (xy 305.4129 -298.054193) (xy 305.451021 -298.023068)
			(xy 305.493642 -297.998461) (xy 305.539658 -297.981009) (xy 305.587877 -297.971165) (xy 305.637052 -297.969184)
			(xy 305.685907 -297.975116) (xy 305.733178 -297.988808) (xy 305.77764 -298.009906) (xy 305.818143 -298.037862)
			(xy 305.853636 -298.071954) (xy 305.883201 -298.111298) (xy 305.906072 -298.154875) (xy 305.921656 -298.201556)
			(xy 305.929551 -298.250133) (xy 305.930046 -298.27474) (xy 306.268894 -298.27474) (xy 306.272854 -298.225686)
			(xy 306.284631 -298.177902) (xy 306.303922 -298.132626) (xy 306.330225 -298.09103) (xy 306.36286 -298.054193)
			(xy 306.400981 -298.023068) (xy 306.443602 -297.998461) (xy 306.489618 -297.981009) (xy 306.537837 -297.971165)
			(xy 306.587012 -297.969184) (xy 306.635867 -297.975116) (xy 306.683138 -297.988808) (xy 306.7276 -298.009906)
			(xy 306.768103 -298.037862) (xy 306.803596 -298.071954) (xy 306.833161 -298.111298) (xy 306.856032 -298.154875)
			(xy 306.871616 -298.201556) (xy 306.879511 -298.250133) (xy 306.880006 -298.27474) (xy 307.219108 -298.27474)
			(xy 307.223068 -298.225686) (xy 307.234845 -298.177902) (xy 307.254136 -298.132626) (xy 307.280439 -298.09103)
			(xy 307.313074 -298.054193) (xy 307.351195 -298.023068) (xy 307.393816 -297.998461) (xy 307.439832 -297.981009)
			(xy 307.488051 -297.971165) (xy 307.537226 -297.969184) (xy 307.586081 -297.975116) (xy 307.633352 -297.988808)
			(xy 307.677814 -298.009906) (xy 307.718317 -298.037862) (xy 307.75381 -298.071954) (xy 307.783375 -298.111298)
			(xy 307.806246 -298.154875) (xy 307.82183 -298.201556) (xy 307.829725 -298.250133) (xy 307.83022 -298.27474)
			(xy 308.169068 -298.27474) (xy 308.173028 -298.225686) (xy 308.184805 -298.177902) (xy 308.204096 -298.132626)
			(xy 308.230399 -298.09103) (xy 308.263034 -298.054193) (xy 308.301155 -298.023068) (xy 308.343776 -297.998461)
			(xy 308.389792 -297.981009) (xy 308.438011 -297.971165) (xy 308.487186 -297.969184) (xy 308.536041 -297.975116)
			(xy 308.583312 -297.988808) (xy 308.627774 -298.009906) (xy 308.668277 -298.037862) (xy 308.70377 -298.071954)
			(xy 308.733335 -298.111298) (xy 308.756206 -298.154875) (xy 308.77179 -298.201556) (xy 308.779685 -298.250133)
			(xy 308.78018 -298.27474) (xy 309.119028 -298.27474) (xy 309.122988 -298.225686) (xy 309.134765 -298.177902)
			(xy 309.154056 -298.132626) (xy 309.180359 -298.09103) (xy 309.212994 -298.054193) (xy 309.251115 -298.023068)
			(xy 309.293736 -297.998461) (xy 309.339752 -297.981009) (xy 309.387971 -297.971165) (xy 309.437146 -297.969184)
			(xy 309.486001 -297.975116) (xy 309.533272 -297.988808) (xy 309.577734 -298.009906) (xy 309.618237 -298.037862)
			(xy 309.65373 -298.071954) (xy 309.683295 -298.111298) (xy 309.706166 -298.154875) (xy 309.72175 -298.201556)
			(xy 309.729645 -298.250133) (xy 309.73014 -298.27474) (xy 310.068988 -298.27474) (xy 310.072948 -298.225686)
			(xy 310.084725 -298.177902) (xy 310.104016 -298.132626) (xy 310.130319 -298.09103) (xy 310.162954 -298.054193)
			(xy 310.201075 -298.023068) (xy 310.243696 -297.998461) (xy 310.289712 -297.981009) (xy 310.337931 -297.971165)
			(xy 310.387106 -297.969184) (xy 310.435961 -297.975116) (xy 310.483232 -297.988808) (xy 310.527694 -298.009906)
			(xy 310.568197 -298.037862) (xy 310.60369 -298.071954) (xy 310.633255 -298.111298) (xy 310.656126 -298.154875)
			(xy 310.67171 -298.201556) (xy 310.679605 -298.250133) (xy 310.6801 -298.27474) (xy 311.018948 -298.27474)
			(xy 311.022908 -298.225686) (xy 311.034685 -298.177902) (xy 311.053976 -298.132626) (xy 311.080279 -298.09103)
			(xy 311.112914 -298.054193) (xy 311.151035 -298.023068) (xy 311.193656 -297.998461) (xy 311.239672 -297.981009)
			(xy 311.287891 -297.971165) (xy 311.337066 -297.969184) (xy 311.385921 -297.975116) (xy 311.433192 -297.988808)
			(xy 311.477654 -298.009906) (xy 311.518157 -298.037862) (xy 311.55365 -298.071954) (xy 311.583215 -298.111298)
			(xy 311.606086 -298.154875) (xy 311.62167 -298.201556) (xy 311.629565 -298.250133) (xy 311.63006 -298.27474)
			(xy 311.968908 -298.27474) (xy 311.972868 -298.225686) (xy 311.984645 -298.177902) (xy 312.003936 -298.132626)
			(xy 312.030239 -298.09103) (xy 312.062874 -298.054193) (xy 312.100995 -298.023068) (xy 312.143616 -297.998461)
			(xy 312.189632 -297.981009) (xy 312.237851 -297.971165) (xy 312.287026 -297.969184) (xy 312.335881 -297.975116)
			(xy 312.383152 -297.988808) (xy 312.427614 -298.009906) (xy 312.468117 -298.037862) (xy 312.50361 -298.071954)
			(xy 312.533175 -298.111298) (xy 312.556046 -298.154875) (xy 312.57163 -298.201556) (xy 312.579525 -298.250133)
			(xy 312.58002 -298.27474) (xy 312.919122 -298.27474) (xy 312.923082 -298.225686) (xy 312.934859 -298.177902)
			(xy 312.95415 -298.132626) (xy 312.980453 -298.09103) (xy 313.013088 -298.054193) (xy 313.051209 -298.023068)
			(xy 313.09383 -297.998461) (xy 313.139846 -297.981009) (xy 313.188065 -297.971165) (xy 313.23724 -297.969184)
			(xy 313.286095 -297.975116) (xy 313.333366 -297.988808) (xy 313.377828 -298.009906) (xy 313.418331 -298.037862)
			(xy 313.453824 -298.071954) (xy 313.483389 -298.111298) (xy 313.50626 -298.154875) (xy 313.521844 -298.201556)
			(xy 313.529739 -298.250133) (xy 313.530234 -298.27474) (xy 313.869082 -298.27474) (xy 313.873042 -298.225686)
			(xy 313.884819 -298.177902) (xy 313.90411 -298.132626) (xy 313.930413 -298.09103) (xy 313.963048 -298.054193)
			(xy 314.001169 -298.023068) (xy 314.04379 -297.998461) (xy 314.089806 -297.981009) (xy 314.138025 -297.971165)
			(xy 314.1872 -297.969184) (xy 314.236055 -297.975116) (xy 314.283326 -297.988808) (xy 314.327788 -298.009906)
			(xy 314.368291 -298.037862) (xy 314.403784 -298.071954) (xy 314.433349 -298.111298) (xy 314.45622 -298.154875)
			(xy 314.471804 -298.201556) (xy 314.479699 -298.250133) (xy 314.480194 -298.27474) (xy 314.819042 -298.27474)
			(xy 314.823002 -298.225686) (xy 314.834779 -298.177902) (xy 314.85407 -298.132626) (xy 314.880373 -298.09103)
			(xy 314.913008 -298.054193) (xy 314.951129 -298.023068) (xy 314.99375 -297.998461) (xy 315.039766 -297.981009)
			(xy 315.087985 -297.971165) (xy 315.13716 -297.969184) (xy 315.186015 -297.975116) (xy 315.233286 -297.988808)
			(xy 315.277748 -298.009906) (xy 315.318251 -298.037862) (xy 315.353744 -298.071954) (xy 315.383309 -298.111298)
			(xy 315.40618 -298.154875) (xy 315.421764 -298.201556) (xy 315.429659 -298.250133) (xy 315.430154 -298.27474)
			(xy 315.429659 -298.299347) (xy 315.421764 -298.347924) (xy 315.40618 -298.394605) (xy 315.383309 -298.438182)
			(xy 315.353744 -298.477526) (xy 315.318251 -298.511618) (xy 315.277748 -298.539574) (xy 315.233286 -298.560672)
			(xy 315.186015 -298.574364) (xy 315.13716 -298.580296) (xy 315.087985 -298.578315) (xy 315.039766 -298.568471)
			(xy 314.99375 -298.551019) (xy 314.951129 -298.526412) (xy 314.913008 -298.495287) (xy 314.880373 -298.45845)
			(xy 314.85407 -298.416854) (xy 314.834779 -298.371578) (xy 314.823002 -298.323794) (xy 314.819042 -298.27474)
			(xy 314.480194 -298.27474) (xy 314.479699 -298.299347) (xy 314.471804 -298.347924) (xy 314.45622 -298.394605)
			(xy 314.433349 -298.438182) (xy 314.403784 -298.477526) (xy 314.368291 -298.511618) (xy 314.327788 -298.539574)
			(xy 314.283326 -298.560672) (xy 314.236055 -298.574364) (xy 314.1872 -298.580296) (xy 314.138025 -298.578315)
			(xy 314.089806 -298.568471) (xy 314.04379 -298.551019) (xy 314.001169 -298.526412) (xy 313.963048 -298.495287)
			(xy 313.930413 -298.45845) (xy 313.90411 -298.416854) (xy 313.884819 -298.371578) (xy 313.873042 -298.323794)
			(xy 313.869082 -298.27474) (xy 313.530234 -298.27474) (xy 313.529739 -298.299347) (xy 313.521844 -298.347924)
			(xy 313.50626 -298.394605) (xy 313.483389 -298.438182) (xy 313.453824 -298.477526) (xy 313.418331 -298.511618)
			(xy 313.377828 -298.539574) (xy 313.333366 -298.560672) (xy 313.286095 -298.574364) (xy 313.23724 -298.580296)
			(xy 313.188065 -298.578315) (xy 313.139846 -298.568471) (xy 313.09383 -298.551019) (xy 313.051209 -298.526412)
			(xy 313.013088 -298.495287) (xy 312.980453 -298.45845) (xy 312.95415 -298.416854) (xy 312.934859 -298.371578)
			(xy 312.923082 -298.323794) (xy 312.919122 -298.27474) (xy 312.58002 -298.27474) (xy 312.579525 -298.299347)
			(xy 312.57163 -298.347924) (xy 312.556046 -298.394605) (xy 312.533175 -298.438182) (xy 312.50361 -298.477526)
			(xy 312.468117 -298.511618) (xy 312.427614 -298.539574) (xy 312.383152 -298.560672) (xy 312.335881 -298.574364)
			(xy 312.287026 -298.580296) (xy 312.237851 -298.578315) (xy 312.189632 -298.568471) (xy 312.143616 -298.551019)
			(xy 312.100995 -298.526412) (xy 312.062874 -298.495287) (xy 312.030239 -298.45845) (xy 312.003936 -298.416854)
			(xy 311.984645 -298.371578) (xy 311.972868 -298.323794) (xy 311.968908 -298.27474) (xy 311.63006 -298.27474)
			(xy 311.629565 -298.299347) (xy 311.62167 -298.347924) (xy 311.606086 -298.394605) (xy 311.583215 -298.438182)
			(xy 311.55365 -298.477526) (xy 311.518157 -298.511618) (xy 311.477654 -298.539574) (xy 311.433192 -298.560672)
			(xy 311.385921 -298.574364) (xy 311.337066 -298.580296) (xy 311.287891 -298.578315) (xy 311.239672 -298.568471)
			(xy 311.193656 -298.551019) (xy 311.151035 -298.526412) (xy 311.112914 -298.495287) (xy 311.080279 -298.45845)
			(xy 311.053976 -298.416854) (xy 311.034685 -298.371578) (xy 311.022908 -298.323794) (xy 311.018948 -298.27474)
			(xy 310.6801 -298.27474) (xy 310.679605 -298.299347) (xy 310.67171 -298.347924) (xy 310.656126 -298.394605)
			(xy 310.633255 -298.438182) (xy 310.60369 -298.477526) (xy 310.568197 -298.511618) (xy 310.527694 -298.539574)
			(xy 310.483232 -298.560672) (xy 310.435961 -298.574364) (xy 310.387106 -298.580296) (xy 310.337931 -298.578315)
			(xy 310.289712 -298.568471) (xy 310.243696 -298.551019) (xy 310.201075 -298.526412) (xy 310.162954 -298.495287)
			(xy 310.130319 -298.45845) (xy 310.104016 -298.416854) (xy 310.084725 -298.371578) (xy 310.072948 -298.323794)
			(xy 310.068988 -298.27474) (xy 309.73014 -298.27474) (xy 309.729645 -298.299347) (xy 309.72175 -298.347924)
			(xy 309.706166 -298.394605) (xy 309.683295 -298.438182) (xy 309.65373 -298.477526) (xy 309.618237 -298.511618)
			(xy 309.577734 -298.539574) (xy 309.533272 -298.560672) (xy 309.486001 -298.574364) (xy 309.437146 -298.580296)
			(xy 309.387971 -298.578315) (xy 309.339752 -298.568471) (xy 309.293736 -298.551019) (xy 309.251115 -298.526412)
			(xy 309.212994 -298.495287) (xy 309.180359 -298.45845) (xy 309.154056 -298.416854) (xy 309.134765 -298.371578)
			(xy 309.122988 -298.323794) (xy 309.119028 -298.27474) (xy 308.78018 -298.27474) (xy 308.779685 -298.299347)
			(xy 308.77179 -298.347924) (xy 308.756206 -298.394605) (xy 308.733335 -298.438182) (xy 308.70377 -298.477526)
			(xy 308.668277 -298.511618) (xy 308.627774 -298.539574) (xy 308.583312 -298.560672) (xy 308.536041 -298.574364)
			(xy 308.487186 -298.580296) (xy 308.438011 -298.578315) (xy 308.389792 -298.568471) (xy 308.343776 -298.551019)
			(xy 308.301155 -298.526412) (xy 308.263034 -298.495287) (xy 308.230399 -298.45845) (xy 308.204096 -298.416854)
			(xy 308.184805 -298.371578) (xy 308.173028 -298.323794) (xy 308.169068 -298.27474) (xy 307.83022 -298.27474)
			(xy 307.829725 -298.299347) (xy 307.82183 -298.347924) (xy 307.806246 -298.394605) (xy 307.783375 -298.438182)
			(xy 307.75381 -298.477526) (xy 307.718317 -298.511618) (xy 307.677814 -298.539574) (xy 307.633352 -298.560672)
			(xy 307.586081 -298.574364) (xy 307.537226 -298.580296) (xy 307.488051 -298.578315) (xy 307.439832 -298.568471)
			(xy 307.393816 -298.551019) (xy 307.351195 -298.526412) (xy 307.313074 -298.495287) (xy 307.280439 -298.45845)
			(xy 307.254136 -298.416854) (xy 307.234845 -298.371578) (xy 307.223068 -298.323794) (xy 307.219108 -298.27474)
			(xy 306.880006 -298.27474) (xy 306.879511 -298.299347) (xy 306.871616 -298.347924) (xy 306.856032 -298.394605)
			(xy 306.833161 -298.438182) (xy 306.803596 -298.477526) (xy 306.768103 -298.511618) (xy 306.7276 -298.539574)
			(xy 306.683138 -298.560672) (xy 306.635867 -298.574364) (xy 306.587012 -298.580296) (xy 306.537837 -298.578315)
			(xy 306.489618 -298.568471) (xy 306.443602 -298.551019) (xy 306.400981 -298.526412) (xy 306.36286 -298.495287)
			(xy 306.330225 -298.45845) (xy 306.303922 -298.416854) (xy 306.284631 -298.371578) (xy 306.272854 -298.323794)
			(xy 306.268894 -298.27474) (xy 305.930046 -298.27474) (xy 305.929551 -298.299347) (xy 305.921656 -298.347924)
			(xy 305.906072 -298.394605) (xy 305.883201 -298.438182) (xy 305.853636 -298.477526) (xy 305.818143 -298.511618)
			(xy 305.77764 -298.539574) (xy 305.733178 -298.560672) (xy 305.685907 -298.574364) (xy 305.637052 -298.580296)
			(xy 305.587877 -298.578315) (xy 305.539658 -298.568471) (xy 305.493642 -298.551019) (xy 305.451021 -298.526412)
			(xy 305.4129 -298.495287) (xy 305.380265 -298.45845) (xy 305.353962 -298.416854) (xy 305.334671 -298.371578)
			(xy 305.322894 -298.323794) (xy 305.318934 -298.27474) (xy 304.980086 -298.27474) (xy 304.979591 -298.299347)
			(xy 304.971696 -298.347924) (xy 304.956112 -298.394605) (xy 304.933241 -298.438182) (xy 304.903676 -298.477526)
			(xy 304.868183 -298.511618) (xy 304.82768 -298.539574) (xy 304.783218 -298.560672) (xy 304.735947 -298.574364)
			(xy 304.687092 -298.580296) (xy 304.637917 -298.578315) (xy 304.589698 -298.568471) (xy 304.543682 -298.551019)
			(xy 304.501061 -298.526412) (xy 304.46294 -298.495287) (xy 304.430305 -298.45845) (xy 304.404002 -298.416854)
			(xy 304.384711 -298.371578) (xy 304.372934 -298.323794) (xy 304.368974 -298.27474) (xy 304.030126 -298.27474)
			(xy 304.029631 -298.299347) (xy 304.021736 -298.347924) (xy 304.006152 -298.394605) (xy 303.983281 -298.438182)
			(xy 303.953716 -298.477526) (xy 303.918223 -298.511618) (xy 303.87772 -298.539574) (xy 303.833258 -298.560672)
			(xy 303.785987 -298.574364) (xy 303.737132 -298.580296) (xy 303.687957 -298.578315) (xy 303.639738 -298.568471)
			(xy 303.593722 -298.551019) (xy 303.551101 -298.526412) (xy 303.51298 -298.495287) (xy 303.480345 -298.45845)
			(xy 303.454042 -298.416854) (xy 303.434751 -298.371578) (xy 303.422974 -298.323794) (xy 303.419014 -298.27474)
			(xy 302.130206 -298.27474) (xy 302.129711 -298.299347) (xy 302.121816 -298.347924) (xy 302.106232 -298.394605)
			(xy 302.083361 -298.438182) (xy 302.053796 -298.477526) (xy 302.018303 -298.511618) (xy 301.9778 -298.539574)
			(xy 301.933338 -298.560672) (xy 301.886067 -298.574364) (xy 301.837212 -298.580296) (xy 301.788037 -298.578315)
			(xy 301.739818 -298.568471) (xy 301.693802 -298.551019) (xy 301.651181 -298.526412) (xy 301.61306 -298.495287)
			(xy 301.580425 -298.45845) (xy 301.554122 -298.416854) (xy 301.534831 -298.371578) (xy 301.523054 -298.323794)
			(xy 301.519094 -298.27474) (xy 301.179992 -298.27474) (xy 301.179497 -298.299347) (xy 301.171602 -298.347924)
			(xy 301.156018 -298.394605) (xy 301.133147 -298.438182) (xy 301.103582 -298.477526) (xy 301.068089 -298.511618)
			(xy 301.027586 -298.539574) (xy 300.983124 -298.560672) (xy 300.935853 -298.574364) (xy 300.886998 -298.580296)
			(xy 300.837823 -298.578315) (xy 300.789604 -298.568471) (xy 300.743588 -298.551019) (xy 300.700967 -298.526412)
			(xy 300.662846 -298.495287) (xy 300.630211 -298.45845) (xy 300.603908 -298.416854) (xy 300.584617 -298.371578)
			(xy 300.57284 -298.323794) (xy 300.56888 -298.27474) (xy 300.230032 -298.27474) (xy 300.229537 -298.299347)
			(xy 300.221642 -298.347924) (xy 300.206058 -298.394605) (xy 300.183187 -298.438182) (xy 300.153622 -298.477526)
			(xy 300.118129 -298.511618) (xy 300.077626 -298.539574) (xy 300.033164 -298.560672) (xy 299.985893 -298.574364)
			(xy 299.937038 -298.580296) (xy 299.887863 -298.578315) (xy 299.839644 -298.568471) (xy 299.793628 -298.551019)
			(xy 299.751007 -298.526412) (xy 299.712886 -298.495287) (xy 299.680251 -298.45845) (xy 299.653948 -298.416854)
			(xy 299.634657 -298.371578) (xy 299.62288 -298.323794) (xy 299.61892 -298.27474) (xy 299.280072 -298.27474)
			(xy 299.279577 -298.299347) (xy 299.271682 -298.347924) (xy 299.256098 -298.394605) (xy 299.233227 -298.438182)
			(xy 299.203662 -298.477526) (xy 299.168169 -298.511618) (xy 299.127666 -298.539574) (xy 299.083204 -298.560672)
			(xy 299.035933 -298.574364) (xy 298.987078 -298.580296) (xy 298.937903 -298.578315) (xy 298.889684 -298.568471)
			(xy 298.843668 -298.551019) (xy 298.801047 -298.526412) (xy 298.762926 -298.495287) (xy 298.730291 -298.45845)
			(xy 298.703988 -298.416854) (xy 298.684697 -298.371578) (xy 298.67292 -298.323794) (xy 298.66896 -298.27474)
			(xy 298.330112 -298.27474) (xy 298.329617 -298.299347) (xy 298.321722 -298.347924) (xy 298.306138 -298.394605)
			(xy 298.283267 -298.438182) (xy 298.253702 -298.477526) (xy 298.218209 -298.511618) (xy 298.177706 -298.539574)
			(xy 298.133244 -298.560672) (xy 298.085973 -298.574364) (xy 298.037118 -298.580296) (xy 297.987943 -298.578315)
			(xy 297.939724 -298.568471) (xy 297.893708 -298.551019) (xy 297.851087 -298.526412) (xy 297.812966 -298.495287)
			(xy 297.780331 -298.45845) (xy 297.754028 -298.416854) (xy 297.734737 -298.371578) (xy 297.72296 -298.323794)
			(xy 297.719 -298.27474) (xy 297.380152 -298.27474) (xy 297.379657 -298.299347) (xy 297.371762 -298.347924)
			(xy 297.356178 -298.394605) (xy 297.333307 -298.438182) (xy 297.303742 -298.477526) (xy 297.268249 -298.511618)
			(xy 297.227746 -298.539574) (xy 297.183284 -298.560672) (xy 297.136013 -298.574364) (xy 297.087158 -298.580296)
			(xy 297.037983 -298.578315) (xy 296.989764 -298.568471) (xy 296.943748 -298.551019) (xy 296.901127 -298.526412)
			(xy 296.863006 -298.495287) (xy 296.830371 -298.45845) (xy 296.804068 -298.416854) (xy 296.784777 -298.371578)
			(xy 296.773 -298.323794) (xy 296.76904 -298.27474) (xy 296.430192 -298.27474) (xy 296.429697 -298.299347)
			(xy 296.421802 -298.347924) (xy 296.406218 -298.394605) (xy 296.383347 -298.438182) (xy 296.353782 -298.477526)
			(xy 296.318289 -298.511618) (xy 296.277786 -298.539574) (xy 296.233324 -298.560672) (xy 296.186053 -298.574364)
			(xy 296.137198 -298.580296) (xy 296.088023 -298.578315) (xy 296.039804 -298.568471) (xy 295.993788 -298.551019)
			(xy 295.951167 -298.526412) (xy 295.913046 -298.495287) (xy 295.880411 -298.45845) (xy 295.854108 -298.416854)
			(xy 295.834817 -298.371578) (xy 295.82304 -298.323794) (xy 295.81908 -298.27474) (xy 295.480232 -298.27474)
			(xy 295.479737 -298.299347) (xy 295.471842 -298.347924) (xy 295.456258 -298.394605) (xy 295.433387 -298.438182)
			(xy 295.403822 -298.477526) (xy 295.368329 -298.511618) (xy 295.327826 -298.539574) (xy 295.283364 -298.560672)
			(xy 295.236093 -298.574364) (xy 295.187238 -298.580296) (xy 295.138063 -298.578315) (xy 295.089844 -298.568471)
			(xy 295.043828 -298.551019) (xy 295.001207 -298.526412) (xy 294.963086 -298.495287) (xy 294.930451 -298.45845)
			(xy 294.904148 -298.416854) (xy 294.884857 -298.371578) (xy 294.87308 -298.323794) (xy 294.86912 -298.27474)
			(xy 294.530018 -298.27474) (xy 294.529523 -298.299347) (xy 294.521628 -298.347924) (xy 294.506044 -298.394605)
			(xy 294.483173 -298.438182) (xy 294.453608 -298.477526) (xy 294.418115 -298.511618) (xy 294.377612 -298.539574)
			(xy 294.33315 -298.560672) (xy 294.285879 -298.574364) (xy 294.237024 -298.580296) (xy 294.187849 -298.578315)
			(xy 294.13963 -298.568471) (xy 294.093614 -298.551019) (xy 294.050993 -298.526412) (xy 294.012872 -298.495287)
			(xy 293.980237 -298.45845) (xy 293.953934 -298.416854) (xy 293.934643 -298.371578) (xy 293.922866 -298.323794)
			(xy 293.918906 -298.27474) (xy 293.580058 -298.27474) (xy 293.579563 -298.299347) (xy 293.571668 -298.347924)
			(xy 293.556084 -298.394605) (xy 293.533213 -298.438182) (xy 293.503648 -298.477526) (xy 293.468155 -298.511618)
			(xy 293.427652 -298.539574) (xy 293.38319 -298.560672) (xy 293.335919 -298.574364) (xy 293.287064 -298.580296)
			(xy 293.237889 -298.578315) (xy 293.18967 -298.568471) (xy 293.143654 -298.551019) (xy 293.101033 -298.526412)
			(xy 293.062912 -298.495287) (xy 293.030277 -298.45845) (xy 293.003974 -298.416854) (xy 292.984683 -298.371578)
			(xy 292.972906 -298.323794) (xy 292.968946 -298.27474) (xy 292.630098 -298.27474) (xy 292.629603 -298.299347)
			(xy 292.621708 -298.347924) (xy 292.606124 -298.394605) (xy 292.583253 -298.438182) (xy 292.553688 -298.477526)
			(xy 292.518195 -298.511618) (xy 292.477692 -298.539574) (xy 292.43323 -298.560672) (xy 292.385959 -298.574364)
			(xy 292.337104 -298.580296) (xy 292.287929 -298.578315) (xy 292.23971 -298.568471) (xy 292.193694 -298.551019)
			(xy 292.151073 -298.526412) (xy 292.112952 -298.495287) (xy 292.080317 -298.45845) (xy 292.054014 -298.416854)
			(xy 292.034723 -298.371578) (xy 292.022946 -298.323794) (xy 292.018986 -298.27474) (xy 290.730178 -298.27474)
			(xy 290.729683 -298.299347) (xy 290.721788 -298.347924) (xy 290.706204 -298.394605) (xy 290.683333 -298.438182)
			(xy 290.653768 -298.477526) (xy 290.618275 -298.511618) (xy 290.577772 -298.539574) (xy 290.53331 -298.560672)
			(xy 290.486039 -298.574364) (xy 290.437184 -298.580296) (xy 290.388009 -298.578315) (xy 290.33979 -298.568471)
			(xy 290.293774 -298.551019) (xy 290.251153 -298.526412) (xy 290.213032 -298.495287) (xy 290.180397 -298.45845)
			(xy 290.154094 -298.416854) (xy 290.134803 -298.371578) (xy 290.123026 -298.323794) (xy 290.119066 -298.27474)
			(xy 289.780218 -298.27474) (xy 289.779723 -298.299347) (xy 289.771828 -298.347924) (xy 289.756244 -298.394605)
			(xy 289.733373 -298.438182) (xy 289.703808 -298.477526) (xy 289.668315 -298.511618) (xy 289.627812 -298.539574)
			(xy 289.58335 -298.560672) (xy 289.536079 -298.574364) (xy 289.487224 -298.580296) (xy 289.438049 -298.578315)
			(xy 289.38983 -298.568471) (xy 289.343814 -298.551019) (xy 289.301193 -298.526412) (xy 289.263072 -298.495287)
			(xy 289.230437 -298.45845) (xy 289.204134 -298.416854) (xy 289.184843 -298.371578) (xy 289.173066 -298.323794)
			(xy 289.169106 -298.27474) (xy 288.830004 -298.27474) (xy 288.829509 -298.299347) (xy 288.821614 -298.347924)
			(xy 288.80603 -298.394605) (xy 288.783159 -298.438182) (xy 288.753594 -298.477526) (xy 288.718101 -298.511618)
			(xy 288.677598 -298.539574) (xy 288.633136 -298.560672) (xy 288.585865 -298.574364) (xy 288.53701 -298.580296)
			(xy 288.487835 -298.578315) (xy 288.439616 -298.568471) (xy 288.3936 -298.551019) (xy 288.350979 -298.526412)
			(xy 288.312858 -298.495287) (xy 288.280223 -298.45845) (xy 288.25392 -298.416854) (xy 288.234629 -298.371578)
			(xy 288.222852 -298.323794) (xy 288.218892 -298.27474) (xy 287.880044 -298.27474) (xy 287.879549 -298.299347)
			(xy 287.871654 -298.347924) (xy 287.85607 -298.394605) (xy 287.833199 -298.438182) (xy 287.803634 -298.477526)
			(xy 287.768141 -298.511618) (xy 287.727638 -298.539574) (xy 287.683176 -298.560672) (xy 287.635905 -298.574364)
			(xy 287.58705 -298.580296) (xy 287.537875 -298.578315) (xy 287.489656 -298.568471) (xy 287.44364 -298.551019)
			(xy 287.401019 -298.526412) (xy 287.362898 -298.495287) (xy 287.330263 -298.45845) (xy 287.30396 -298.416854)
			(xy 287.284669 -298.371578) (xy 287.272892 -298.323794) (xy 287.268932 -298.27474) (xy 286.930084 -298.27474)
			(xy 286.929589 -298.299347) (xy 286.921694 -298.347924) (xy 286.90611 -298.394605) (xy 286.883239 -298.438182)
			(xy 286.853674 -298.477526) (xy 286.818181 -298.511618) (xy 286.777678 -298.539574) (xy 286.733216 -298.560672)
			(xy 286.685945 -298.574364) (xy 286.63709 -298.580296) (xy 286.587915 -298.578315) (xy 286.539696 -298.568471)
			(xy 286.49368 -298.551019) (xy 286.451059 -298.526412) (xy 286.412938 -298.495287) (xy 286.380303 -298.45845)
			(xy 286.354 -298.416854) (xy 286.334709 -298.371578) (xy 286.322932 -298.323794) (xy 286.318972 -298.27474)
			(xy 285.980124 -298.27474) (xy 285.979629 -298.299347) (xy 285.971734 -298.347924) (xy 285.95615 -298.394605)
			(xy 285.933279 -298.438182) (xy 285.903714 -298.477526) (xy 285.868221 -298.511618) (xy 285.827718 -298.539574)
			(xy 285.783256 -298.560672) (xy 285.735985 -298.574364) (xy 285.68713 -298.580296) (xy 285.637955 -298.578315)
			(xy 285.589736 -298.568471) (xy 285.54372 -298.551019) (xy 285.501099 -298.526412) (xy 285.462978 -298.495287)
			(xy 285.430343 -298.45845) (xy 285.40404 -298.416854) (xy 285.384749 -298.371578) (xy 285.372972 -298.323794)
			(xy 285.369012 -298.27474) (xy 285.030164 -298.27474) (xy 285.029669 -298.299347) (xy 285.021774 -298.347924)
			(xy 285.00619 -298.394605) (xy 284.983319 -298.438182) (xy 284.953754 -298.477526) (xy 284.918261 -298.511618)
			(xy 284.877758 -298.539574) (xy 284.833296 -298.560672) (xy 284.786025 -298.574364) (xy 284.73717 -298.580296)
			(xy 284.687995 -298.578315) (xy 284.639776 -298.568471) (xy 284.59376 -298.551019) (xy 284.551139 -298.526412)
			(xy 284.513018 -298.495287) (xy 284.480383 -298.45845) (xy 284.45408 -298.416854) (xy 284.434789 -298.371578)
			(xy 284.423012 -298.323794) (xy 284.419052 -298.27474) (xy 284.080204 -298.27474) (xy 284.079709 -298.299347)
			(xy 284.071814 -298.347924) (xy 284.05623 -298.394605) (xy 284.033359 -298.438182) (xy 284.003794 -298.477526)
			(xy 283.968301 -298.511618) (xy 283.927798 -298.539574) (xy 283.883336 -298.560672) (xy 283.836065 -298.574364)
			(xy 283.78721 -298.580296) (xy 283.738035 -298.578315) (xy 283.689816 -298.568471) (xy 283.6438 -298.551019)
			(xy 283.601179 -298.526412) (xy 283.563058 -298.495287) (xy 283.530423 -298.45845) (xy 283.50412 -298.416854)
			(xy 283.484829 -298.371578) (xy 283.473052 -298.323794) (xy 283.469092 -298.27474) (xy 283.130244 -298.27474)
			(xy 283.129749 -298.299347) (xy 283.121854 -298.347924) (xy 283.10627 -298.394605) (xy 283.083399 -298.438182)
			(xy 283.053834 -298.477526) (xy 283.018341 -298.511618) (xy 282.977838 -298.539574) (xy 282.933376 -298.560672)
			(xy 282.886105 -298.574364) (xy 282.83725 -298.580296) (xy 282.788075 -298.578315) (xy 282.739856 -298.568471)
			(xy 282.69384 -298.551019) (xy 282.651219 -298.526412) (xy 282.613098 -298.495287) (xy 282.580463 -298.45845)
			(xy 282.55416 -298.416854) (xy 282.534869 -298.371578) (xy 282.523092 -298.323794) (xy 282.519132 -298.27474)
			(xy 282.18003 -298.27474) (xy 282.179535 -298.299347) (xy 282.17164 -298.347924) (xy 282.156056 -298.394605)
			(xy 282.133185 -298.438182) (xy 282.10362 -298.477526) (xy 282.068127 -298.511618) (xy 282.027624 -298.539574)
			(xy 281.983162 -298.560672) (xy 281.935891 -298.574364) (xy 281.887036 -298.580296) (xy 281.837861 -298.578315)
			(xy 281.789642 -298.568471) (xy 281.743626 -298.551019) (xy 281.701005 -298.526412) (xy 281.662884 -298.495287)
			(xy 281.630249 -298.45845) (xy 281.603946 -298.416854) (xy 281.584655 -298.371578) (xy 281.572878 -298.323794)
			(xy 281.568918 -298.27474) (xy 281.23007 -298.27474) (xy 281.229575 -298.299347) (xy 281.22168 -298.347924)
			(xy 281.206096 -298.394605) (xy 281.183225 -298.438182) (xy 281.15366 -298.477526) (xy 281.118167 -298.511618)
			(xy 281.077664 -298.539574) (xy 281.033202 -298.560672) (xy 280.985931 -298.574364) (xy 280.937076 -298.580296)
			(xy 280.887901 -298.578315) (xy 280.839682 -298.568471) (xy 280.793666 -298.551019) (xy 280.751045 -298.526412)
			(xy 280.712924 -298.495287) (xy 280.680289 -298.45845) (xy 280.653986 -298.416854) (xy 280.634695 -298.371578)
			(xy 280.622918 -298.323794) (xy 280.618958 -298.27474) (xy 280.28011 -298.27474) (xy 280.279615 -298.299347)
			(xy 280.27172 -298.347924) (xy 280.256136 -298.394605) (xy 280.233265 -298.438182) (xy 280.2037 -298.477526)
			(xy 280.168207 -298.511618) (xy 280.127704 -298.539574) (xy 280.083242 -298.560672) (xy 280.035971 -298.574364)
			(xy 279.987116 -298.580296) (xy 279.937941 -298.578315) (xy 279.889722 -298.568471) (xy 279.843706 -298.551019)
			(xy 279.801085 -298.526412) (xy 279.762964 -298.495287) (xy 279.730329 -298.45845) (xy 279.704026 -298.416854)
			(xy 279.684735 -298.371578) (xy 279.672958 -298.323794) (xy 279.668998 -298.27474) (xy 278.38019 -298.27474)
			(xy 278.379695 -298.299347) (xy 278.3718 -298.347924) (xy 278.356216 -298.394605) (xy 278.333345 -298.438182)
			(xy 278.30378 -298.477526) (xy 278.268287 -298.511618) (xy 278.227784 -298.539574) (xy 278.183322 -298.560672)
			(xy 278.136051 -298.574364) (xy 278.087196 -298.580296) (xy 278.038021 -298.578315) (xy 277.989802 -298.568471)
			(xy 277.943786 -298.551019) (xy 277.901165 -298.526412) (xy 277.863044 -298.495287) (xy 277.830409 -298.45845)
			(xy 277.804106 -298.416854) (xy 277.784815 -298.371578) (xy 277.773038 -298.323794) (xy 277.769078 -298.27474)
			(xy 277.43023 -298.27474) (xy 277.429735 -298.299347) (xy 277.42184 -298.347924) (xy 277.406256 -298.394605)
			(xy 277.383385 -298.438182) (xy 277.35382 -298.477526) (xy 277.318327 -298.511618) (xy 277.277824 -298.539574)
			(xy 277.233362 -298.560672) (xy 277.186091 -298.574364) (xy 277.137236 -298.580296) (xy 277.088061 -298.578315)
			(xy 277.039842 -298.568471) (xy 276.993826 -298.551019) (xy 276.951205 -298.526412) (xy 276.913084 -298.495287)
			(xy 276.880449 -298.45845) (xy 276.854146 -298.416854) (xy 276.834855 -298.371578) (xy 276.823078 -298.323794)
			(xy 276.819118 -298.27474) (xy 276.480016 -298.27474) (xy 276.479521 -298.299347) (xy 276.471626 -298.347924)
			(xy 276.456042 -298.394605) (xy 276.433171 -298.438182) (xy 276.403606 -298.477526) (xy 276.368113 -298.511618)
			(xy 276.32761 -298.539574) (xy 276.283148 -298.560672) (xy 276.235877 -298.574364) (xy 276.187022 -298.580296)
			(xy 276.137847 -298.578315) (xy 276.089628 -298.568471) (xy 276.043612 -298.551019) (xy 276.000991 -298.526412)
			(xy 275.96287 -298.495287) (xy 275.930235 -298.45845) (xy 275.903932 -298.416854) (xy 275.884641 -298.371578)
			(xy 275.872864 -298.323794) (xy 275.868904 -298.27474) (xy 274.580096 -298.27474) (xy 274.579601 -298.299347)
			(xy 274.571706 -298.347924) (xy 274.556122 -298.394605) (xy 274.533251 -298.438182) (xy 274.503686 -298.477526)
			(xy 274.468193 -298.511618) (xy 274.42769 -298.539574) (xy 274.383228 -298.560672) (xy 274.335957 -298.574364)
			(xy 274.287102 -298.580296) (xy 274.237927 -298.578315) (xy 274.189708 -298.568471) (xy 274.143692 -298.551019)
			(xy 274.101071 -298.526412) (xy 274.06295 -298.495287) (xy 274.030315 -298.45845) (xy 274.004012 -298.416854)
			(xy 273.984721 -298.371578) (xy 273.972944 -298.323794) (xy 273.968984 -298.27474) (xy 273.630136 -298.27474)
			(xy 273.629641 -298.299347) (xy 273.621746 -298.347924) (xy 273.606162 -298.394605) (xy 273.583291 -298.438182)
			(xy 273.553726 -298.477526) (xy 273.518233 -298.511618) (xy 273.47773 -298.539574) (xy 273.433268 -298.560672)
			(xy 273.385997 -298.574364) (xy 273.337142 -298.580296) (xy 273.287967 -298.578315) (xy 273.239748 -298.568471)
			(xy 273.193732 -298.551019) (xy 273.151111 -298.526412) (xy 273.11299 -298.495287) (xy 273.080355 -298.45845)
			(xy 273.054052 -298.416854) (xy 273.034761 -298.371578) (xy 273.022984 -298.323794) (xy 273.019024 -298.27474)
			(xy 272.680176 -298.27474) (xy 272.679681 -298.299347) (xy 272.671786 -298.347924) (xy 272.656202 -298.394605)
			(xy 272.633331 -298.438182) (xy 272.603766 -298.477526) (xy 272.568273 -298.511618) (xy 272.52777 -298.539574)
			(xy 272.483308 -298.560672) (xy 272.436037 -298.574364) (xy 272.387182 -298.580296) (xy 272.338007 -298.578315)
			(xy 272.289788 -298.568471) (xy 272.243772 -298.551019) (xy 272.201151 -298.526412) (xy 272.16303 -298.495287)
			(xy 272.130395 -298.45845) (xy 272.104092 -298.416854) (xy 272.084801 -298.371578) (xy 272.073024 -298.323794)
			(xy 272.069064 -298.27474) (xy 271.730216 -298.27474) (xy 271.729721 -298.299347) (xy 271.721826 -298.347924)
			(xy 271.706242 -298.394605) (xy 271.683371 -298.438182) (xy 271.653806 -298.477526) (xy 271.618313 -298.511618)
			(xy 271.57781 -298.539574) (xy 271.533348 -298.560672) (xy 271.486077 -298.574364) (xy 271.437222 -298.580296)
			(xy 271.388047 -298.578315) (xy 271.339828 -298.568471) (xy 271.293812 -298.551019) (xy 271.251191 -298.526412)
			(xy 271.21307 -298.495287) (xy 271.180435 -298.45845) (xy 271.154132 -298.416854) (xy 271.134841 -298.371578)
			(xy 271.123064 -298.323794) (xy 271.119104 -298.27474) (xy 270.780002 -298.27474) (xy 270.779507 -298.299347)
			(xy 270.771612 -298.347924) (xy 270.756028 -298.394605) (xy 270.733157 -298.438182) (xy 270.703592 -298.477526)
			(xy 270.668099 -298.511618) (xy 270.627596 -298.539574) (xy 270.583134 -298.560672) (xy 270.535863 -298.574364)
			(xy 270.487008 -298.580296) (xy 270.437833 -298.578315) (xy 270.389614 -298.568471) (xy 270.343598 -298.551019)
			(xy 270.300977 -298.526412) (xy 270.262856 -298.495287) (xy 270.230221 -298.45845) (xy 270.203918 -298.416854)
			(xy 270.184627 -298.371578) (xy 270.17285 -298.323794) (xy 270.16889 -298.27474) (xy 269.829788 -298.27474)
			(xy 269.829293 -298.299347) (xy 269.821398 -298.347924) (xy 269.805814 -298.394605) (xy 269.782943 -298.438182)
			(xy 269.753378 -298.477526) (xy 269.717885 -298.511618) (xy 269.677382 -298.539574) (xy 269.63292 -298.560672)
			(xy 269.585649 -298.574364) (xy 269.536794 -298.580296) (xy 269.487619 -298.578315) (xy 269.4394 -298.568471)
			(xy 269.393384 -298.551019) (xy 269.350763 -298.526412) (xy 269.312642 -298.495287) (xy 269.280007 -298.45845)
			(xy 269.253704 -298.416854) (xy 269.234413 -298.371578) (xy 269.222636 -298.323794) (xy 269.218676 -298.27474)
			(xy 260.263158 -298.27474) (xy 260.26417 -298.281779) (xy 260.264656 -298.30903) (xy 260.264121 -298.337371)
			(xy 260.255743 -298.393431) (xy 260.239161 -298.447633) (xy 260.214741 -298.498785) (xy 260.18302 -298.54576)
			(xy 260.144696 -298.587523) (xy 260.100614 -298.623155) (xy 260.076442 -298.63796) (xy 260.063824 -298.645884)
			(xy 260.043544 -298.667698) (xy 260.030419 -298.694434) (xy 260.025564 -298.72382) (xy 260.029393 -298.753358)
			(xy 260.041578 -298.780535) (xy 260.061086 -298.803043) (xy 260.073394 -298.811442) (xy 260.096271 -298.826535)
			(xy 260.137866 -298.862224) (xy 260.173924 -298.903498) (xy 260.203704 -298.949508) (xy 260.226592 -298.999306)
			(xy 260.242117 -299.051868) (xy 260.249959 -299.106111) (xy 260.250432 -299.133514) (xy 260.375906 -299.133514)
			(xy 260.379977 -299.077892) (xy 260.392103 -299.023455) (xy 260.412026 -298.971364) (xy 260.439322 -298.922729)
			(xy 260.473408 -298.878586) (xy 260.513557 -298.839877) (xy 260.558915 -298.807426) (xy 260.608515 -298.781925)
			(xy 260.661299 -298.763918) (xy 260.716142 -298.753788) (xy 260.771876 -298.751751) (xy 260.827313 -298.757851)
			(xy 260.88127 -298.771957) (xy 260.932599 -298.793769) (xy 260.980205 -298.822823) (xy 261.023073 -298.858498)
			(xy 261.06029 -298.900035) (xy 261.091063 -298.946548) (xy 261.114735 -298.997045) (xy 261.130803 -299.050452)
			(xy 261.138923 -299.105628) (xy 261.139432 -299.133514) (xy 261.138923 -299.1614) (xy 261.130803 -299.216576)
			(xy 261.114735 -299.269983) (xy 261.091063 -299.32048) (xy 261.06029 -299.366993) (xy 261.023073 -299.40853)
			(xy 260.980205 -299.444205) (xy 260.932599 -299.473259) (xy 260.88127 -299.495071) (xy 260.827313 -299.509177)
			(xy 260.771876 -299.515277) (xy 260.716142 -299.51324) (xy 260.661299 -299.50311) (xy 260.608515 -299.485103)
			(xy 260.558915 -299.459602) (xy 260.513557 -299.427151) (xy 260.473408 -299.388442) (xy 260.439322 -299.344299)
			(xy 260.412026 -299.295664) (xy 260.392103 -299.243573) (xy 260.379977 -299.189136) (xy 260.375906 -299.133514)
			(xy 260.250432 -299.133514) (xy 260.249946 -299.160765) (xy 260.24219 -299.214713) (xy 260.226835 -299.267008)
			(xy 260.204193 -299.316585) (xy 260.174727 -299.362435) (xy 260.139036 -299.403626) (xy 260.097845 -299.439317)
			(xy 260.051995 -299.468783) (xy 260.002418 -299.491425) (xy 259.950123 -299.50678) (xy 259.896175 -299.514536)
			(xy 259.841673 -299.514536) (xy 259.787725 -299.50678) (xy 259.73543 -299.491425) (xy 259.685853 -299.468783)
			(xy 259.640003 -299.439317) (xy 259.598812 -299.403626) (xy 259.563121 -299.362435) (xy 259.533655 -299.316585)
			(xy 259.511013 -299.267008) (xy 259.495658 -299.214713) (xy 259.487902 -299.160765) (xy 259.487416 -299.133514)
			(xy 258.774946 -299.133514) (xy 258.774437 -299.1614) (xy 258.766317 -299.216576) (xy 258.750249 -299.269983)
			(xy 258.726577 -299.32048) (xy 258.695804 -299.366993) (xy 258.658587 -299.40853) (xy 258.615719 -299.444205)
			(xy 258.568113 -299.473259) (xy 258.516784 -299.495071) (xy 258.462827 -299.509177) (xy 258.40739 -299.515277)
			(xy 258.351656 -299.51324) (xy 258.296813 -299.50311) (xy 258.244029 -299.485103) (xy 258.194429 -299.459602)
			(xy 258.149071 -299.427151) (xy 258.108922 -299.388442) (xy 258.074836 -299.344299) (xy 258.04754 -299.295664)
			(xy 258.027617 -299.243573) (xy 258.015491 -299.189136) (xy 258.01142 -299.133514) (xy 255.231738 -299.133514)
			(xy 255.212837 -299.16535) (xy 255.12203 -299.302605) (xy 255.024648 -299.435276) (xy 254.920922 -299.563048)
			(xy 254.811099 -299.685618) (xy 254.695438 -299.802696) (xy 254.594351 -299.895514) (xy 263.537954 -299.895514)
			(xy 263.53852 -299.866133) (xy 263.547548 -299.808068) (xy 263.565376 -299.752075) (xy 263.591583 -299.69948)
			(xy 263.625547 -299.651528) (xy 263.666466 -299.609354) (xy 263.689592 -299.591222) (xy 263.69899 -299.583856)
			(xy 263.709404 -299.563282) (xy 263.710928 -299.459396) (xy 263.701022 -299.438314) (xy 263.691878 -299.430948)
			(xy 263.670018 -299.412756) (xy 263.63148 -299.370933) (xy 263.599575 -299.323855) (xy 263.57501 -299.272563)
			(xy 263.558329 -299.218193) (xy 263.549902 -299.16195) (xy 263.549384 -299.133514) (xy 263.54987 -299.106263)
			(xy 263.557626 -299.052315) (xy 263.572981 -299.00002) (xy 263.595623 -298.950443) (xy 263.625089 -298.904593)
			(xy 263.66078 -298.863402) (xy 263.701971 -298.827711) (xy 263.747821 -298.798245) (xy 263.797398 -298.775603)
			(xy 263.849693 -298.760248) (xy 263.903641 -298.752492) (xy 263.958143 -298.752492) (xy 264.012091 -298.760248)
			(xy 264.064386 -298.775603) (xy 264.113963 -298.798245) (xy 264.159813 -298.827711) (xy 264.201004 -298.863402)
			(xy 264.236695 -298.904593) (xy 264.266161 -298.950443) (xy 264.288803 -299.00002) (xy 264.304158 -299.052315)
			(xy 264.311914 -299.106263) (xy 264.3124 -299.133514) (xy 264.311872 -299.162897) (xy 264.302839 -299.220964)
			(xy 264.301649 -299.2247) (xy 267.633969 -299.2247) (xy 267.63814 -299.174365) (xy 267.650538 -299.125402)
			(xy 267.670826 -299.079148) (xy 267.69845 -299.036863) (xy 267.732656 -298.999702) (xy 267.772513 -298.968678)
			(xy 267.816932 -298.944636) (xy 267.864702 -298.928233) (xy 267.91452 -298.919916) (xy 267.939774 -298.919392)
			(xy 267.96517 -298.919897) (xy 268.01526 -298.928312) (xy 268.063267 -298.944897) (xy 268.10787 -298.969196)
			(xy 268.147838 -299.000538) (xy 268.165326 -299.01896) (xy 268.172946 -299.027342) (xy 268.193012 -299.035724)
			(xy 268.292326 -299.033184) (xy 268.31163 -299.023786) (xy 268.318996 -299.014896) (xy 268.3348 -298.996366)
			(xy 268.370891 -298.963667) (xy 268.411384 -298.93661) (xy 268.455404 -298.915778) (xy 268.502001 -298.901621)
			(xy 268.55017 -298.894444) (xy 268.57452 -298.893992) (xy 269.52448 -298.893992) (xy 269.550487 -298.894566)
			(xy 269.60186 -298.9027) (xy 269.651328 -298.91877) (xy 269.697673 -298.942382) (xy 269.739754 -298.972953)
			(xy 269.776534 -299.009731) (xy 269.807108 -299.05181) (xy 269.830722 -299.098153) (xy 269.846796 -299.147621)
			(xy 269.854933 -299.198993) (xy 269.854933 -299.224954) (xy 270.16889 -299.224954) (xy 270.17285 -299.1759)
			(xy 270.184627 -299.128116) (xy 270.203918 -299.08284) (xy 270.230221 -299.041244) (xy 270.262856 -299.004407)
			(xy 270.300977 -298.973282) (xy 270.343598 -298.948675) (xy 270.389614 -298.931223) (xy 270.437833 -298.921379)
			(xy 270.487008 -298.919398) (xy 270.535863 -298.92533) (xy 270.583134 -298.939022) (xy 270.627596 -298.96012)
			(xy 270.668099 -298.988076) (xy 270.703592 -299.022168) (xy 270.733157 -299.061512) (xy 270.756028 -299.105089)
			(xy 270.771612 -299.15177) (xy 270.779507 -299.200347) (xy 270.780002 -299.224954) (xy 270.779507 -299.249561)
			(xy 270.779271 -299.251013) (xy 271.094376 -299.251013) (xy 271.094376 -299.198987) (xy 271.102514 -299.147601)
			(xy 271.118592 -299.098121) (xy 271.142212 -299.051765) (xy 271.172792 -299.009675) (xy 271.209581 -298.972887)
			(xy 271.251672 -298.942307) (xy 271.298028 -298.918689) (xy 271.347509 -298.902613) (xy 271.398895 -298.894475)
			(xy 271.424908 -298.893992) (xy 272.374868 -298.893992) (xy 272.400875 -298.894565) (xy 272.45225 -298.902697)
			(xy 272.50172 -298.918767) (xy 272.548067 -298.942378) (xy 272.590149 -298.972949) (xy 272.626931 -299.009727)
			(xy 272.657506 -299.051806) (xy 272.681121 -299.09815) (xy 272.697195 -299.147619) (xy 272.705333 -299.198993)
			(xy 272.705333 -299.224954) (xy 273.019024 -299.224954) (xy 273.022984 -299.1759) (xy 273.034761 -299.128116)
			(xy 273.054052 -299.08284) (xy 273.080355 -299.041244) (xy 273.11299 -299.004407) (xy 273.151111 -298.973282)
			(xy 273.193732 -298.948675) (xy 273.239748 -298.931223) (xy 273.287967 -298.921379) (xy 273.337142 -298.919398)
			(xy 273.385997 -298.92533) (xy 273.433268 -298.939022) (xy 273.47773 -298.96012) (xy 273.518233 -298.988076)
			(xy 273.553726 -299.022168) (xy 273.583291 -299.061512) (xy 273.606162 -299.105089) (xy 273.621746 -299.15177)
			(xy 273.629641 -299.200347) (xy 273.630136 -299.224954) (xy 273.629975 -299.232973) (xy 273.969093 -299.232973)
			(xy 273.971782 -299.183407) (xy 273.982454 -299.134928) (xy 274.000828 -299.088815) (xy 274.026421 -299.046282)
			(xy 274.058558 -299.008449) (xy 274.096391 -298.976314) (xy 274.138926 -298.950723) (xy 274.18504 -298.93235)
			(xy 274.233519 -298.92168) (xy 274.283085 -298.918993) (xy 274.332434 -298.924361) (xy 274.380263 -298.937641)
			(xy 274.425315 -298.958485) (xy 274.4664 -298.986342) (xy 274.502438 -299.020479) (xy 274.532478 -299.059997)
			(xy 274.55573 -299.103854) (xy 274.571579 -299.150895) (xy 274.57961 -299.19988) (xy 274.580096 -299.2247)
			(xy 274.580093 -299.224954) (xy 275.868904 -299.224954) (xy 275.872864 -299.1759) (xy 275.884641 -299.128116)
			(xy 275.903932 -299.08284) (xy 275.930235 -299.041244) (xy 275.96287 -299.004407) (xy 276.000991 -298.973282)
			(xy 276.043612 -298.948675) (xy 276.089628 -298.931223) (xy 276.137847 -298.921379) (xy 276.187022 -298.919398)
			(xy 276.235877 -298.92533) (xy 276.283148 -298.939022) (xy 276.32761 -298.96012) (xy 276.368113 -298.988076)
			(xy 276.403606 -299.022168) (xy 276.433171 -299.061512) (xy 276.456042 -299.105089) (xy 276.471626 -299.15177)
			(xy 276.479521 -299.200347) (xy 276.480016 -299.224954) (xy 276.819118 -299.224954) (xy 276.823078 -299.1759)
			(xy 276.834855 -299.128116) (xy 276.854146 -299.08284) (xy 276.880449 -299.041244) (xy 276.913084 -299.004407)
			(xy 276.951205 -298.973282) (xy 276.993826 -298.948675) (xy 277.039842 -298.931223) (xy 277.088061 -298.921379)
			(xy 277.137236 -298.919398) (xy 277.186091 -298.92533) (xy 277.233362 -298.939022) (xy 277.277824 -298.96012)
			(xy 277.318327 -298.988076) (xy 277.35382 -299.022168) (xy 277.383385 -299.061512) (xy 277.406256 -299.105089)
			(xy 277.42184 -299.15177) (xy 277.429735 -299.200347) (xy 277.43023 -299.224954) (xy 277.769078 -299.224954)
			(xy 277.773038 -299.1759) (xy 277.784815 -299.128116) (xy 277.804106 -299.08284) (xy 277.830409 -299.041244)
			(xy 277.863044 -299.004407) (xy 277.901165 -298.973282) (xy 277.943786 -298.948675) (xy 277.989802 -298.931223)
			(xy 278.038021 -298.921379) (xy 278.087196 -298.919398) (xy 278.136051 -298.92533) (xy 278.183322 -298.939022)
			(xy 278.227784 -298.96012) (xy 278.268287 -298.988076) (xy 278.30378 -299.022168) (xy 278.333345 -299.061512)
			(xy 278.356216 -299.105089) (xy 278.3718 -299.15177) (xy 278.379695 -299.200347) (xy 278.38019 -299.224954)
			(xy 278.719038 -299.224954) (xy 278.722998 -299.1759) (xy 278.734775 -299.128116) (xy 278.754066 -299.08284)
			(xy 278.780369 -299.041244) (xy 278.813004 -299.004407) (xy 278.851125 -298.973282) (xy 278.893746 -298.948675)
			(xy 278.939762 -298.931223) (xy 278.987981 -298.921379) (xy 279.037156 -298.919398) (xy 279.086011 -298.92533)
			(xy 279.133282 -298.939022) (xy 279.177744 -298.96012) (xy 279.218247 -298.988076) (xy 279.25374 -299.022168)
			(xy 279.283305 -299.061512) (xy 279.306176 -299.105089) (xy 279.32176 -299.15177) (xy 279.329655 -299.200347)
			(xy 279.33015 -299.224954) (xy 279.668998 -299.224954) (xy 279.672958 -299.1759) (xy 279.684735 -299.128116)
			(xy 279.704026 -299.08284) (xy 279.730329 -299.041244) (xy 279.762964 -299.004407) (xy 279.801085 -298.973282)
			(xy 279.843706 -298.948675) (xy 279.889722 -298.931223) (xy 279.937941 -298.921379) (xy 279.987116 -298.919398)
			(xy 280.035971 -298.92533) (xy 280.083242 -298.939022) (xy 280.127704 -298.96012) (xy 280.168207 -298.988076)
			(xy 280.2037 -299.022168) (xy 280.233265 -299.061512) (xy 280.256136 -299.105089) (xy 280.27172 -299.15177)
			(xy 280.279615 -299.200347) (xy 280.28011 -299.224954) (xy 280.618958 -299.224954) (xy 280.622918 -299.1759)
			(xy 280.634695 -299.128116) (xy 280.653986 -299.08284) (xy 280.680289 -299.041244) (xy 280.712924 -299.004407)
			(xy 280.751045 -298.973282) (xy 280.793666 -298.948675) (xy 280.839682 -298.931223) (xy 280.887901 -298.921379)
			(xy 280.937076 -298.919398) (xy 280.985931 -298.92533) (xy 281.033202 -298.939022) (xy 281.077664 -298.96012)
			(xy 281.118167 -298.988076) (xy 281.15366 -299.022168) (xy 281.183225 -299.061512) (xy 281.206096 -299.105089)
			(xy 281.22168 -299.15177) (xy 281.229575 -299.200347) (xy 281.23007 -299.224954) (xy 281.568918 -299.224954)
			(xy 281.572878 -299.1759) (xy 281.584655 -299.128116) (xy 281.603946 -299.08284) (xy 281.630249 -299.041244)
			(xy 281.662884 -299.004407) (xy 281.701005 -298.973282) (xy 281.743626 -298.948675) (xy 281.789642 -298.931223)
			(xy 281.837861 -298.921379) (xy 281.887036 -298.919398) (xy 281.935891 -298.92533) (xy 281.983162 -298.939022)
			(xy 282.027624 -298.96012) (xy 282.068127 -298.988076) (xy 282.10362 -299.022168) (xy 282.133185 -299.061512)
			(xy 282.156056 -299.105089) (xy 282.17164 -299.15177) (xy 282.179535 -299.200347) (xy 282.18003 -299.224954)
			(xy 282.519132 -299.224954) (xy 282.523092 -299.1759) (xy 282.534869 -299.128116) (xy 282.55416 -299.08284)
			(xy 282.580463 -299.041244) (xy 282.613098 -299.004407) (xy 282.651219 -298.973282) (xy 282.69384 -298.948675)
			(xy 282.739856 -298.931223) (xy 282.788075 -298.921379) (xy 282.83725 -298.919398) (xy 282.886105 -298.92533)
			(xy 282.933376 -298.939022) (xy 282.977838 -298.96012) (xy 283.018341 -298.988076) (xy 283.053834 -299.022168)
			(xy 283.083399 -299.061512) (xy 283.10627 -299.105089) (xy 283.121854 -299.15177) (xy 283.129749 -299.200347)
			(xy 283.130244 -299.224954) (xy 283.469092 -299.224954) (xy 283.473052 -299.1759) (xy 283.484829 -299.128116)
			(xy 283.50412 -299.08284) (xy 283.530423 -299.041244) (xy 283.563058 -299.004407) (xy 283.601179 -298.973282)
			(xy 283.6438 -298.948675) (xy 283.689816 -298.931223) (xy 283.738035 -298.921379) (xy 283.78721 -298.919398)
			(xy 283.836065 -298.92533) (xy 283.883336 -298.939022) (xy 283.927798 -298.96012) (xy 283.968301 -298.988076)
			(xy 284.003794 -299.022168) (xy 284.033359 -299.061512) (xy 284.05623 -299.105089) (xy 284.071814 -299.15177)
			(xy 284.079709 -299.200347) (xy 284.080204 -299.224954) (xy 284.419052 -299.224954) (xy 284.423012 -299.1759)
			(xy 284.434789 -299.128116) (xy 284.45408 -299.08284) (xy 284.480383 -299.041244) (xy 284.513018 -299.004407)
			(xy 284.551139 -298.973282) (xy 284.59376 -298.948675) (xy 284.639776 -298.931223) (xy 284.687995 -298.921379)
			(xy 284.73717 -298.919398) (xy 284.786025 -298.92533) (xy 284.833296 -298.939022) (xy 284.877758 -298.96012)
			(xy 284.918261 -298.988076) (xy 284.953754 -299.022168) (xy 284.983319 -299.061512) (xy 285.00619 -299.105089)
			(xy 285.021774 -299.15177) (xy 285.029669 -299.200347) (xy 285.030164 -299.224954) (xy 285.369012 -299.224954)
			(xy 285.372972 -299.1759) (xy 285.384749 -299.128116) (xy 285.40404 -299.08284) (xy 285.430343 -299.041244)
			(xy 285.462978 -299.004407) (xy 285.501099 -298.973282) (xy 285.54372 -298.948675) (xy 285.589736 -298.931223)
			(xy 285.637955 -298.921379) (xy 285.68713 -298.919398) (xy 285.735985 -298.92533) (xy 285.783256 -298.939022)
			(xy 285.827718 -298.96012) (xy 285.868221 -298.988076) (xy 285.903714 -299.022168) (xy 285.933279 -299.061512)
			(xy 285.95615 -299.105089) (xy 285.971734 -299.15177) (xy 285.979629 -299.200347) (xy 285.980124 -299.224954)
			(xy 286.318972 -299.224954) (xy 286.322932 -299.1759) (xy 286.334709 -299.128116) (xy 286.354 -299.08284)
			(xy 286.380303 -299.041244) (xy 286.412938 -299.004407) (xy 286.451059 -298.973282) (xy 286.49368 -298.948675)
			(xy 286.539696 -298.931223) (xy 286.587915 -298.921379) (xy 286.63709 -298.919398) (xy 286.685945 -298.92533)
			(xy 286.733216 -298.939022) (xy 286.777678 -298.96012) (xy 286.818181 -298.988076) (xy 286.853674 -299.022168)
			(xy 286.883239 -299.061512) (xy 286.90611 -299.105089) (xy 286.921694 -299.15177) (xy 286.929589 -299.200347)
			(xy 286.930084 -299.224954) (xy 287.268932 -299.224954) (xy 287.272892 -299.1759) (xy 287.284669 -299.128116)
			(xy 287.30396 -299.08284) (xy 287.330263 -299.041244) (xy 287.362898 -299.004407) (xy 287.401019 -298.973282)
			(xy 287.44364 -298.948675) (xy 287.489656 -298.931223) (xy 287.537875 -298.921379) (xy 287.58705 -298.919398)
			(xy 287.635905 -298.92533) (xy 287.683176 -298.939022) (xy 287.727638 -298.96012) (xy 287.768141 -298.988076)
			(xy 287.803634 -299.022168) (xy 287.833199 -299.061512) (xy 287.85607 -299.105089) (xy 287.871654 -299.15177)
			(xy 287.879549 -299.200347) (xy 287.880044 -299.224954) (xy 288.218892 -299.224954) (xy 288.222852 -299.1759)
			(xy 288.234629 -299.128116) (xy 288.25392 -299.08284) (xy 288.280223 -299.041244) (xy 288.312858 -299.004407)
			(xy 288.350979 -298.973282) (xy 288.3936 -298.948675) (xy 288.439616 -298.931223) (xy 288.487835 -298.921379)
			(xy 288.53701 -298.919398) (xy 288.585865 -298.92533) (xy 288.633136 -298.939022) (xy 288.677598 -298.96012)
			(xy 288.718101 -298.988076) (xy 288.753594 -299.022168) (xy 288.783159 -299.061512) (xy 288.80603 -299.105089)
			(xy 288.821614 -299.15177) (xy 288.829509 -299.200347) (xy 288.830004 -299.224954) (xy 289.169106 -299.224954)
			(xy 289.173066 -299.1759) (xy 289.184843 -299.128116) (xy 289.204134 -299.08284) (xy 289.230437 -299.041244)
			(xy 289.263072 -299.004407) (xy 289.301193 -298.973282) (xy 289.343814 -298.948675) (xy 289.38983 -298.931223)
			(xy 289.438049 -298.921379) (xy 289.487224 -298.919398) (xy 289.536079 -298.92533) (xy 289.58335 -298.939022)
			(xy 289.627812 -298.96012) (xy 289.668315 -298.988076) (xy 289.703808 -299.022168) (xy 289.733373 -299.061512)
			(xy 289.756244 -299.105089) (xy 289.771828 -299.15177) (xy 289.779723 -299.200347) (xy 289.780218 -299.224954)
			(xy 290.119066 -299.224954) (xy 290.123026 -299.1759) (xy 290.134803 -299.128116) (xy 290.154094 -299.08284)
			(xy 290.180397 -299.041244) (xy 290.213032 -299.004407) (xy 290.251153 -298.973282) (xy 290.293774 -298.948675)
			(xy 290.33979 -298.931223) (xy 290.388009 -298.921379) (xy 290.437184 -298.919398) (xy 290.486039 -298.92533)
			(xy 290.53331 -298.939022) (xy 290.577772 -298.96012) (xy 290.618275 -298.988076) (xy 290.653768 -299.022168)
			(xy 290.683333 -299.061512) (xy 290.706204 -299.105089) (xy 290.721788 -299.15177) (xy 290.729683 -299.200347)
			(xy 290.730178 -299.224954) (xy 292.018986 -299.224954) (xy 292.022946 -299.1759) (xy 292.034723 -299.128116)
			(xy 292.054014 -299.08284) (xy 292.080317 -299.041244) (xy 292.112952 -299.004407) (xy 292.151073 -298.973282)
			(xy 292.193694 -298.948675) (xy 292.23971 -298.931223) (xy 292.287929 -298.921379) (xy 292.337104 -298.919398)
			(xy 292.385959 -298.92533) (xy 292.43323 -298.939022) (xy 292.477692 -298.96012) (xy 292.518195 -298.988076)
			(xy 292.553688 -299.022168) (xy 292.583253 -299.061512) (xy 292.606124 -299.105089) (xy 292.621708 -299.15177)
			(xy 292.629603 -299.200347) (xy 292.630098 -299.224954) (xy 292.968946 -299.224954) (xy 292.972906 -299.1759)
			(xy 292.984683 -299.128116) (xy 293.003974 -299.08284) (xy 293.030277 -299.041244) (xy 293.062912 -299.004407)
			(xy 293.101033 -298.973282) (xy 293.143654 -298.948675) (xy 293.18967 -298.931223) (xy 293.237889 -298.921379)
			(xy 293.287064 -298.919398) (xy 293.335919 -298.92533) (xy 293.38319 -298.939022) (xy 293.427652 -298.96012)
			(xy 293.468155 -298.988076) (xy 293.503648 -299.022168) (xy 293.533213 -299.061512) (xy 293.556084 -299.105089)
			(xy 293.571668 -299.15177) (xy 293.579563 -299.200347) (xy 293.580058 -299.224954) (xy 293.918906 -299.224954)
			(xy 293.922866 -299.1759) (xy 293.934643 -299.128116) (xy 293.953934 -299.08284) (xy 293.980237 -299.041244)
			(xy 294.012872 -299.004407) (xy 294.050993 -298.973282) (xy 294.093614 -298.948675) (xy 294.13963 -298.931223)
			(xy 294.187849 -298.921379) (xy 294.237024 -298.919398) (xy 294.285879 -298.92533) (xy 294.33315 -298.939022)
			(xy 294.377612 -298.96012) (xy 294.418115 -298.988076) (xy 294.453608 -299.022168) (xy 294.483173 -299.061512)
			(xy 294.506044 -299.105089) (xy 294.521628 -299.15177) (xy 294.529523 -299.200347) (xy 294.530018 -299.224954)
			(xy 294.86912 -299.224954) (xy 294.87308 -299.1759) (xy 294.884857 -299.128116) (xy 294.904148 -299.08284)
			(xy 294.930451 -299.041244) (xy 294.963086 -299.004407) (xy 295.001207 -298.973282) (xy 295.043828 -298.948675)
			(xy 295.089844 -298.931223) (xy 295.138063 -298.921379) (xy 295.187238 -298.919398) (xy 295.236093 -298.92533)
			(xy 295.283364 -298.939022) (xy 295.327826 -298.96012) (xy 295.368329 -298.988076) (xy 295.403822 -299.022168)
			(xy 295.433387 -299.061512) (xy 295.456258 -299.105089) (xy 295.471842 -299.15177) (xy 295.479737 -299.200347)
			(xy 295.480232 -299.224954) (xy 295.81908 -299.224954) (xy 295.82304 -299.1759) (xy 295.834817 -299.128116)
			(xy 295.854108 -299.08284) (xy 295.880411 -299.041244) (xy 295.913046 -299.004407) (xy 295.951167 -298.973282)
			(xy 295.993788 -298.948675) (xy 296.039804 -298.931223) (xy 296.088023 -298.921379) (xy 296.137198 -298.919398)
			(xy 296.186053 -298.92533) (xy 296.233324 -298.939022) (xy 296.277786 -298.96012) (xy 296.318289 -298.988076)
			(xy 296.353782 -299.022168) (xy 296.383347 -299.061512) (xy 296.406218 -299.105089) (xy 296.421802 -299.15177)
			(xy 296.429697 -299.200347) (xy 296.430192 -299.224954) (xy 296.76904 -299.224954) (xy 296.773 -299.1759)
			(xy 296.784777 -299.128116) (xy 296.804068 -299.08284) (xy 296.830371 -299.041244) (xy 296.863006 -299.004407)
			(xy 296.901127 -298.973282) (xy 296.943748 -298.948675) (xy 296.989764 -298.931223) (xy 297.037983 -298.921379)
			(xy 297.087158 -298.919398) (xy 297.136013 -298.92533) (xy 297.183284 -298.939022) (xy 297.227746 -298.96012)
			(xy 297.268249 -298.988076) (xy 297.303742 -299.022168) (xy 297.333307 -299.061512) (xy 297.356178 -299.105089)
			(xy 297.371762 -299.15177) (xy 297.379657 -299.200347) (xy 297.380152 -299.224954) (xy 297.719 -299.224954)
			(xy 297.72296 -299.1759) (xy 297.734737 -299.128116) (xy 297.754028 -299.08284) (xy 297.780331 -299.041244)
			(xy 297.812966 -299.004407) (xy 297.851087 -298.973282) (xy 297.893708 -298.948675) (xy 297.939724 -298.931223)
			(xy 297.987943 -298.921379) (xy 298.037118 -298.919398) (xy 298.085973 -298.92533) (xy 298.133244 -298.939022)
			(xy 298.177706 -298.96012) (xy 298.218209 -298.988076) (xy 298.253702 -299.022168) (xy 298.283267 -299.061512)
			(xy 298.306138 -299.105089) (xy 298.321722 -299.15177) (xy 298.329617 -299.200347) (xy 298.330112 -299.224954)
			(xy 298.66896 -299.224954) (xy 298.67292 -299.1759) (xy 298.684697 -299.128116) (xy 298.703988 -299.08284)
			(xy 298.730291 -299.041244) (xy 298.762926 -299.004407) (xy 298.801047 -298.973282) (xy 298.843668 -298.948675)
			(xy 298.889684 -298.931223) (xy 298.937903 -298.921379) (xy 298.987078 -298.919398) (xy 299.035933 -298.92533)
			(xy 299.083204 -298.939022) (xy 299.127666 -298.96012) (xy 299.168169 -298.988076) (xy 299.203662 -299.022168)
			(xy 299.233227 -299.061512) (xy 299.256098 -299.105089) (xy 299.271682 -299.15177) (xy 299.279577 -299.200347)
			(xy 299.280072 -299.224954) (xy 299.61892 -299.224954) (xy 299.62288 -299.1759) (xy 299.634657 -299.128116)
			(xy 299.653948 -299.08284) (xy 299.680251 -299.041244) (xy 299.712886 -299.004407) (xy 299.751007 -298.973282)
			(xy 299.793628 -298.948675) (xy 299.839644 -298.931223) (xy 299.887863 -298.921379) (xy 299.937038 -298.919398)
			(xy 299.985893 -298.92533) (xy 300.033164 -298.939022) (xy 300.077626 -298.96012) (xy 300.118129 -298.988076)
			(xy 300.153622 -299.022168) (xy 300.183187 -299.061512) (xy 300.206058 -299.105089) (xy 300.221642 -299.15177)
			(xy 300.229537 -299.200347) (xy 300.230032 -299.224954) (xy 300.56888 -299.224954) (xy 300.57284 -299.1759)
			(xy 300.584617 -299.128116) (xy 300.603908 -299.08284) (xy 300.630211 -299.041244) (xy 300.662846 -299.004407)
			(xy 300.700967 -298.973282) (xy 300.743588 -298.948675) (xy 300.789604 -298.931223) (xy 300.837823 -298.921379)
			(xy 300.886998 -298.919398) (xy 300.935853 -298.92533) (xy 300.983124 -298.939022) (xy 301.027586 -298.96012)
			(xy 301.068089 -298.988076) (xy 301.103582 -299.022168) (xy 301.133147 -299.061512) (xy 301.156018 -299.105089)
			(xy 301.171602 -299.15177) (xy 301.179497 -299.200347) (xy 301.179992 -299.224954) (xy 301.519094 -299.224954)
			(xy 301.523054 -299.1759) (xy 301.534831 -299.128116) (xy 301.554122 -299.08284) (xy 301.580425 -299.041244)
			(xy 301.61306 -299.004407) (xy 301.651181 -298.973282) (xy 301.693802 -298.948675) (xy 301.739818 -298.931223)
			(xy 301.788037 -298.921379) (xy 301.837212 -298.919398) (xy 301.886067 -298.92533) (xy 301.933338 -298.939022)
			(xy 301.9778 -298.96012) (xy 302.018303 -298.988076) (xy 302.053796 -299.022168) (xy 302.083361 -299.061512)
			(xy 302.106232 -299.105089) (xy 302.121816 -299.15177) (xy 302.129711 -299.200347) (xy 302.130206 -299.224954)
			(xy 302.469054 -299.224954) (xy 302.473014 -299.1759) (xy 302.484791 -299.128116) (xy 302.504082 -299.08284)
			(xy 302.530385 -299.041244) (xy 302.56302 -299.004407) (xy 302.601141 -298.973282) (xy 302.643762 -298.948675)
			(xy 302.689778 -298.931223) (xy 302.737997 -298.921379) (xy 302.787172 -298.919398) (xy 302.836027 -298.92533)
			(xy 302.883298 -298.939022) (xy 302.92776 -298.96012) (xy 302.968263 -298.988076) (xy 303.003756 -299.022168)
			(xy 303.033321 -299.061512) (xy 303.056192 -299.105089) (xy 303.071776 -299.15177) (xy 303.079671 -299.200347)
			(xy 303.080166 -299.224954) (xy 303.419014 -299.224954) (xy 303.422974 -299.1759) (xy 303.434751 -299.128116)
			(xy 303.454042 -299.08284) (xy 303.480345 -299.041244) (xy 303.51298 -299.004407) (xy 303.551101 -298.973282)
			(xy 303.593722 -298.948675) (xy 303.639738 -298.931223) (xy 303.687957 -298.921379) (xy 303.737132 -298.919398)
			(xy 303.785987 -298.92533) (xy 303.833258 -298.939022) (xy 303.87772 -298.96012) (xy 303.918223 -298.988076)
			(xy 303.953716 -299.022168) (xy 303.983281 -299.061512) (xy 304.006152 -299.105089) (xy 304.021736 -299.15177)
			(xy 304.029631 -299.200347) (xy 304.030126 -299.224954) (xy 304.368974 -299.224954) (xy 304.372934 -299.1759)
			(xy 304.384711 -299.128116) (xy 304.404002 -299.08284) (xy 304.430305 -299.041244) (xy 304.46294 -299.004407)
			(xy 304.501061 -298.973282) (xy 304.543682 -298.948675) (xy 304.589698 -298.931223) (xy 304.637917 -298.921379)
			(xy 304.687092 -298.919398) (xy 304.735947 -298.92533) (xy 304.783218 -298.939022) (xy 304.82768 -298.96012)
			(xy 304.868183 -298.988076) (xy 304.903676 -299.022168) (xy 304.933241 -299.061512) (xy 304.956112 -299.105089)
			(xy 304.971696 -299.15177) (xy 304.979591 -299.200347) (xy 304.980086 -299.224954) (xy 305.318934 -299.224954)
			(xy 305.322894 -299.1759) (xy 305.334671 -299.128116) (xy 305.353962 -299.08284) (xy 305.380265 -299.041244)
			(xy 305.4129 -299.004407) (xy 305.451021 -298.973282) (xy 305.493642 -298.948675) (xy 305.539658 -298.931223)
			(xy 305.587877 -298.921379) (xy 305.637052 -298.919398) (xy 305.685907 -298.92533) (xy 305.733178 -298.939022)
			(xy 305.77764 -298.96012) (xy 305.818143 -298.988076) (xy 305.853636 -299.022168) (xy 305.883201 -299.061512)
			(xy 305.906072 -299.105089) (xy 305.921656 -299.15177) (xy 305.929551 -299.200347) (xy 305.930046 -299.224954)
			(xy 308.169068 -299.224954) (xy 308.173028 -299.1759) (xy 308.184805 -299.128116) (xy 308.204096 -299.08284)
			(xy 308.230399 -299.041244) (xy 308.263034 -299.004407) (xy 308.301155 -298.973282) (xy 308.343776 -298.948675)
			(xy 308.389792 -298.931223) (xy 308.438011 -298.921379) (xy 308.487186 -298.919398) (xy 308.536041 -298.92533)
			(xy 308.583312 -298.939022) (xy 308.627774 -298.96012) (xy 308.668277 -298.988076) (xy 308.70377 -299.022168)
			(xy 308.733335 -299.061512) (xy 308.756206 -299.105089) (xy 308.77179 -299.15177) (xy 308.779685 -299.200347)
			(xy 308.78018 -299.224954) (xy 309.119028 -299.224954) (xy 309.122988 -299.1759) (xy 309.134765 -299.128116)
			(xy 309.154056 -299.08284) (xy 309.180359 -299.041244) (xy 309.212994 -299.004407) (xy 309.251115 -298.973282)
			(xy 309.293736 -298.948675) (xy 309.339752 -298.931223) (xy 309.387971 -298.921379) (xy 309.437146 -298.919398)
			(xy 309.486001 -298.92533) (xy 309.533272 -298.939022) (xy 309.577734 -298.96012) (xy 309.618237 -298.988076)
			(xy 309.65373 -299.022168) (xy 309.683295 -299.061512) (xy 309.706166 -299.105089) (xy 309.72175 -299.15177)
			(xy 309.729645 -299.200347) (xy 309.73014 -299.224954) (xy 310.068988 -299.224954) (xy 310.072948 -299.1759)
			(xy 310.084725 -299.128116) (xy 310.104016 -299.08284) (xy 310.130319 -299.041244) (xy 310.162954 -299.004407)
			(xy 310.201075 -298.973282) (xy 310.243696 -298.948675) (xy 310.289712 -298.931223) (xy 310.337931 -298.921379)
			(xy 310.387106 -298.919398) (xy 310.435961 -298.92533) (xy 310.483232 -298.939022) (xy 310.527694 -298.96012)
			(xy 310.568197 -298.988076) (xy 310.60369 -299.022168) (xy 310.633255 -299.061512) (xy 310.656126 -299.105089)
			(xy 310.67171 -299.15177) (xy 310.679605 -299.200347) (xy 310.6801 -299.224954) (xy 311.018948 -299.224954)
			(xy 311.022908 -299.1759) (xy 311.034685 -299.128116) (xy 311.053976 -299.08284) (xy 311.080279 -299.041244)
			(xy 311.112914 -299.004407) (xy 311.151035 -298.973282) (xy 311.193656 -298.948675) (xy 311.239672 -298.931223)
			(xy 311.287891 -298.921379) (xy 311.337066 -298.919398) (xy 311.385921 -298.92533) (xy 311.433192 -298.939022)
			(xy 311.477654 -298.96012) (xy 311.518157 -298.988076) (xy 311.55365 -299.022168) (xy 311.583215 -299.061512)
			(xy 311.606086 -299.105089) (xy 311.62167 -299.15177) (xy 311.629565 -299.200347) (xy 311.63006 -299.224954)
			(xy 311.968908 -299.224954) (xy 311.972868 -299.1759) (xy 311.984645 -299.128116) (xy 312.003936 -299.08284)
			(xy 312.030239 -299.041244) (xy 312.062874 -299.004407) (xy 312.100995 -298.973282) (xy 312.143616 -298.948675)
			(xy 312.189632 -298.931223) (xy 312.237851 -298.921379) (xy 312.287026 -298.919398) (xy 312.335881 -298.92533)
			(xy 312.383152 -298.939022) (xy 312.427614 -298.96012) (xy 312.468117 -298.988076) (xy 312.50361 -299.022168)
			(xy 312.533175 -299.061512) (xy 312.556046 -299.105089) (xy 312.57163 -299.15177) (xy 312.579525 -299.200347)
			(xy 312.58002 -299.224954) (xy 312.919122 -299.224954) (xy 312.923082 -299.1759) (xy 312.934859 -299.128116)
			(xy 312.95415 -299.08284) (xy 312.980453 -299.041244) (xy 313.013088 -299.004407) (xy 313.051209 -298.973282)
			(xy 313.09383 -298.948675) (xy 313.139846 -298.931223) (xy 313.188065 -298.921379) (xy 313.23724 -298.919398)
			(xy 313.286095 -298.92533) (xy 313.333366 -298.939022) (xy 313.377828 -298.96012) (xy 313.418331 -298.988076)
			(xy 313.453824 -299.022168) (xy 313.483389 -299.061512) (xy 313.50626 -299.105089) (xy 313.521844 -299.15177)
			(xy 313.529739 -299.200347) (xy 313.530234 -299.224954) (xy 313.869082 -299.224954) (xy 313.873042 -299.1759)
			(xy 313.884819 -299.128116) (xy 313.90411 -299.08284) (xy 313.930413 -299.041244) (xy 313.963048 -299.004407)
			(xy 314.001169 -298.973282) (xy 314.04379 -298.948675) (xy 314.089806 -298.931223) (xy 314.138025 -298.921379)
			(xy 314.1872 -298.919398) (xy 314.236055 -298.92533) (xy 314.283326 -298.939022) (xy 314.327788 -298.96012)
			(xy 314.368291 -298.988076) (xy 314.403784 -299.022168) (xy 314.433349 -299.061512) (xy 314.45622 -299.105089)
			(xy 314.471804 -299.15177) (xy 314.479699 -299.200347) (xy 314.480194 -299.224954) (xy 314.819042 -299.224954)
			(xy 314.823002 -299.1759) (xy 314.834779 -299.128116) (xy 314.85407 -299.08284) (xy 314.880373 -299.041244)
			(xy 314.913008 -299.004407) (xy 314.951129 -298.973282) (xy 314.99375 -298.948675) (xy 315.039766 -298.931223)
			(xy 315.087985 -298.921379) (xy 315.13716 -298.919398) (xy 315.186015 -298.92533) (xy 315.233286 -298.939022)
			(xy 315.277748 -298.96012) (xy 315.318251 -298.988076) (xy 315.353744 -299.022168) (xy 315.383309 -299.061512)
			(xy 315.40618 -299.105089) (xy 315.421764 -299.15177) (xy 315.429659 -299.200347) (xy 315.430154 -299.224954)
			(xy 315.429659 -299.249561) (xy 315.421764 -299.298138) (xy 315.40618 -299.344819) (xy 315.383309 -299.388396)
			(xy 315.353744 -299.42774) (xy 315.318251 -299.461832) (xy 315.277748 -299.489788) (xy 315.233286 -299.510886)
			(xy 315.186015 -299.524578) (xy 315.13716 -299.53051) (xy 315.087985 -299.528529) (xy 315.039766 -299.518685)
			(xy 314.99375 -299.501233) (xy 314.951129 -299.476626) (xy 314.913008 -299.445501) (xy 314.880373 -299.408664)
			(xy 314.85407 -299.367068) (xy 314.834779 -299.321792) (xy 314.823002 -299.274008) (xy 314.819042 -299.224954)
			(xy 314.480194 -299.224954) (xy 314.479699 -299.249561) (xy 314.471804 -299.298138) (xy 314.45622 -299.344819)
			(xy 314.433349 -299.388396) (xy 314.403784 -299.42774) (xy 314.368291 -299.461832) (xy 314.327788 -299.489788)
			(xy 314.283326 -299.510886) (xy 314.236055 -299.524578) (xy 314.1872 -299.53051) (xy 314.138025 -299.528529)
			(xy 314.089806 -299.518685) (xy 314.04379 -299.501233) (xy 314.001169 -299.476626) (xy 313.963048 -299.445501)
			(xy 313.930413 -299.408664) (xy 313.90411 -299.367068) (xy 313.884819 -299.321792) (xy 313.873042 -299.274008)
			(xy 313.869082 -299.224954) (xy 313.530234 -299.224954) (xy 313.529739 -299.249561) (xy 313.521844 -299.298138)
			(xy 313.50626 -299.344819) (xy 313.483389 -299.388396) (xy 313.453824 -299.42774) (xy 313.418331 -299.461832)
			(xy 313.377828 -299.489788) (xy 313.333366 -299.510886) (xy 313.286095 -299.524578) (xy 313.23724 -299.53051)
			(xy 313.188065 -299.528529) (xy 313.139846 -299.518685) (xy 313.09383 -299.501233) (xy 313.051209 -299.476626)
			(xy 313.013088 -299.445501) (xy 312.980453 -299.408664) (xy 312.95415 -299.367068) (xy 312.934859 -299.321792)
			(xy 312.923082 -299.274008) (xy 312.919122 -299.224954) (xy 312.58002 -299.224954) (xy 312.579525 -299.249561)
			(xy 312.57163 -299.298138) (xy 312.556046 -299.344819) (xy 312.533175 -299.388396) (xy 312.50361 -299.42774)
			(xy 312.468117 -299.461832) (xy 312.427614 -299.489788) (xy 312.383152 -299.510886) (xy 312.335881 -299.524578)
			(xy 312.287026 -299.53051) (xy 312.237851 -299.528529) (xy 312.189632 -299.518685) (xy 312.143616 -299.501233)
			(xy 312.100995 -299.476626) (xy 312.062874 -299.445501) (xy 312.030239 -299.408664) (xy 312.003936 -299.367068)
			(xy 311.984645 -299.321792) (xy 311.972868 -299.274008) (xy 311.968908 -299.224954) (xy 311.63006 -299.224954)
			(xy 311.629565 -299.249561) (xy 311.62167 -299.298138) (xy 311.606086 -299.344819) (xy 311.583215 -299.388396)
			(xy 311.55365 -299.42774) (xy 311.518157 -299.461832) (xy 311.477654 -299.489788) (xy 311.433192 -299.510886)
			(xy 311.385921 -299.524578) (xy 311.337066 -299.53051) (xy 311.287891 -299.528529) (xy 311.239672 -299.518685)
			(xy 311.193656 -299.501233) (xy 311.151035 -299.476626) (xy 311.112914 -299.445501) (xy 311.080279 -299.408664)
			(xy 311.053976 -299.367068) (xy 311.034685 -299.321792) (xy 311.022908 -299.274008) (xy 311.018948 -299.224954)
			(xy 310.6801 -299.224954) (xy 310.679605 -299.249561) (xy 310.67171 -299.298138) (xy 310.656126 -299.344819)
			(xy 310.633255 -299.388396) (xy 310.60369 -299.42774) (xy 310.568197 -299.461832) (xy 310.527694 -299.489788)
			(xy 310.483232 -299.510886) (xy 310.435961 -299.524578) (xy 310.387106 -299.53051) (xy 310.337931 -299.528529)
			(xy 310.289712 -299.518685) (xy 310.243696 -299.501233) (xy 310.201075 -299.476626) (xy 310.162954 -299.445501)
			(xy 310.130319 -299.408664) (xy 310.104016 -299.367068) (xy 310.084725 -299.321792) (xy 310.072948 -299.274008)
			(xy 310.068988 -299.224954) (xy 309.73014 -299.224954) (xy 309.729645 -299.249561) (xy 309.72175 -299.298138)
			(xy 309.706166 -299.344819) (xy 309.683295 -299.388396) (xy 309.65373 -299.42774) (xy 309.618237 -299.461832)
			(xy 309.577734 -299.489788) (xy 309.533272 -299.510886) (xy 309.486001 -299.524578) (xy 309.437146 -299.53051)
			(xy 309.387971 -299.528529) (xy 309.339752 -299.518685) (xy 309.293736 -299.501233) (xy 309.251115 -299.476626)
			(xy 309.212994 -299.445501) (xy 309.180359 -299.408664) (xy 309.154056 -299.367068) (xy 309.134765 -299.321792)
			(xy 309.122988 -299.274008) (xy 309.119028 -299.224954) (xy 308.78018 -299.224954) (xy 308.779685 -299.249561)
			(xy 308.77179 -299.298138) (xy 308.756206 -299.344819) (xy 308.733335 -299.388396) (xy 308.70377 -299.42774)
			(xy 308.668277 -299.461832) (xy 308.627774 -299.489788) (xy 308.583312 -299.510886) (xy 308.536041 -299.524578)
			(xy 308.487186 -299.53051) (xy 308.438011 -299.528529) (xy 308.389792 -299.518685) (xy 308.343776 -299.501233)
			(xy 308.301155 -299.476626) (xy 308.263034 -299.445501) (xy 308.230399 -299.408664) (xy 308.204096 -299.367068)
			(xy 308.184805 -299.321792) (xy 308.173028 -299.274008) (xy 308.169068 -299.224954) (xy 305.930046 -299.224954)
			(xy 305.929551 -299.249561) (xy 305.921656 -299.298138) (xy 305.906072 -299.344819) (xy 305.883201 -299.388396)
			(xy 305.853636 -299.42774) (xy 305.818143 -299.461832) (xy 305.77764 -299.489788) (xy 305.733178 -299.510886)
			(xy 305.685907 -299.524578) (xy 305.637052 -299.53051) (xy 305.587877 -299.528529) (xy 305.539658 -299.518685)
			(xy 305.493642 -299.501233) (xy 305.451021 -299.476626) (xy 305.4129 -299.445501) (xy 305.380265 -299.408664)
			(xy 305.353962 -299.367068) (xy 305.334671 -299.321792) (xy 305.322894 -299.274008) (xy 305.318934 -299.224954)
			(xy 304.980086 -299.224954) (xy 304.979591 -299.249561) (xy 304.971696 -299.298138) (xy 304.956112 -299.344819)
			(xy 304.933241 -299.388396) (xy 304.903676 -299.42774) (xy 304.868183 -299.461832) (xy 304.82768 -299.489788)
			(xy 304.783218 -299.510886) (xy 304.735947 -299.524578) (xy 304.687092 -299.53051) (xy 304.637917 -299.528529)
			(xy 304.589698 -299.518685) (xy 304.543682 -299.501233) (xy 304.501061 -299.476626) (xy 304.46294 -299.445501)
			(xy 304.430305 -299.408664) (xy 304.404002 -299.367068) (xy 304.384711 -299.321792) (xy 304.372934 -299.274008)
			(xy 304.368974 -299.224954) (xy 304.030126 -299.224954) (xy 304.029631 -299.249561) (xy 304.021736 -299.298138)
			(xy 304.006152 -299.344819) (xy 303.983281 -299.388396) (xy 303.953716 -299.42774) (xy 303.918223 -299.461832)
			(xy 303.87772 -299.489788) (xy 303.833258 -299.510886) (xy 303.785987 -299.524578) (xy 303.737132 -299.53051)
			(xy 303.687957 -299.528529) (xy 303.639738 -299.518685) (xy 303.593722 -299.501233) (xy 303.551101 -299.476626)
			(xy 303.51298 -299.445501) (xy 303.480345 -299.408664) (xy 303.454042 -299.367068) (xy 303.434751 -299.321792)
			(xy 303.422974 -299.274008) (xy 303.419014 -299.224954) (xy 303.080166 -299.224954) (xy 303.079671 -299.249561)
			(xy 303.071776 -299.298138) (xy 303.056192 -299.344819) (xy 303.033321 -299.388396) (xy 303.003756 -299.42774)
			(xy 302.968263 -299.461832) (xy 302.92776 -299.489788) (xy 302.883298 -299.510886) (xy 302.836027 -299.524578)
			(xy 302.787172 -299.53051) (xy 302.737997 -299.528529) (xy 302.689778 -299.518685) (xy 302.643762 -299.501233)
			(xy 302.601141 -299.476626) (xy 302.56302 -299.445501) (xy 302.530385 -299.408664) (xy 302.504082 -299.367068)
			(xy 302.484791 -299.321792) (xy 302.473014 -299.274008) (xy 302.469054 -299.224954) (xy 302.130206 -299.224954)
			(xy 302.129711 -299.249561) (xy 302.121816 -299.298138) (xy 302.106232 -299.344819) (xy 302.083361 -299.388396)
			(xy 302.053796 -299.42774) (xy 302.018303 -299.461832) (xy 301.9778 -299.489788) (xy 301.933338 -299.510886)
			(xy 301.886067 -299.524578) (xy 301.837212 -299.53051) (xy 301.788037 -299.528529) (xy 301.739818 -299.518685)
			(xy 301.693802 -299.501233) (xy 301.651181 -299.476626) (xy 301.61306 -299.445501) (xy 301.580425 -299.408664)
			(xy 301.554122 -299.367068) (xy 301.534831 -299.321792) (xy 301.523054 -299.274008) (xy 301.519094 -299.224954)
			(xy 301.179992 -299.224954) (xy 301.179497 -299.249561) (xy 301.171602 -299.298138) (xy 301.156018 -299.344819)
			(xy 301.133147 -299.388396) (xy 301.103582 -299.42774) (xy 301.068089 -299.461832) (xy 301.027586 -299.489788)
			(xy 300.983124 -299.510886) (xy 300.935853 -299.524578) (xy 300.886998 -299.53051) (xy 300.837823 -299.528529)
			(xy 300.789604 -299.518685) (xy 300.743588 -299.501233) (xy 300.700967 -299.476626) (xy 300.662846 -299.445501)
			(xy 300.630211 -299.408664) (xy 300.603908 -299.367068) (xy 300.584617 -299.321792) (xy 300.57284 -299.274008)
			(xy 300.56888 -299.224954) (xy 300.230032 -299.224954) (xy 300.229537 -299.249561) (xy 300.221642 -299.298138)
			(xy 300.206058 -299.344819) (xy 300.183187 -299.388396) (xy 300.153622 -299.42774) (xy 300.118129 -299.461832)
			(xy 300.077626 -299.489788) (xy 300.033164 -299.510886) (xy 299.985893 -299.524578) (xy 299.937038 -299.53051)
			(xy 299.887863 -299.528529) (xy 299.839644 -299.518685) (xy 299.793628 -299.501233) (xy 299.751007 -299.476626)
			(xy 299.712886 -299.445501) (xy 299.680251 -299.408664) (xy 299.653948 -299.367068) (xy 299.634657 -299.321792)
			(xy 299.62288 -299.274008) (xy 299.61892 -299.224954) (xy 299.280072 -299.224954) (xy 299.279577 -299.249561)
			(xy 299.271682 -299.298138) (xy 299.256098 -299.344819) (xy 299.233227 -299.388396) (xy 299.203662 -299.42774)
			(xy 299.168169 -299.461832) (xy 299.127666 -299.489788) (xy 299.083204 -299.510886) (xy 299.035933 -299.524578)
			(xy 298.987078 -299.53051) (xy 298.937903 -299.528529) (xy 298.889684 -299.518685) (xy 298.843668 -299.501233)
			(xy 298.801047 -299.476626) (xy 298.762926 -299.445501) (xy 298.730291 -299.408664) (xy 298.703988 -299.367068)
			(xy 298.684697 -299.321792) (xy 298.67292 -299.274008) (xy 298.66896 -299.224954) (xy 298.330112 -299.224954)
			(xy 298.329617 -299.249561) (xy 298.321722 -299.298138) (xy 298.306138 -299.344819) (xy 298.283267 -299.388396)
			(xy 298.253702 -299.42774) (xy 298.218209 -299.461832) (xy 298.177706 -299.489788) (xy 298.133244 -299.510886)
			(xy 298.085973 -299.524578) (xy 298.037118 -299.53051) (xy 297.987943 -299.528529) (xy 297.939724 -299.518685)
			(xy 297.893708 -299.501233) (xy 297.851087 -299.476626) (xy 297.812966 -299.445501) (xy 297.780331 -299.408664)
			(xy 297.754028 -299.367068) (xy 297.734737 -299.321792) (xy 297.72296 -299.274008) (xy 297.719 -299.224954)
			(xy 297.380152 -299.224954) (xy 297.379657 -299.249561) (xy 297.371762 -299.298138) (xy 297.356178 -299.344819)
			(xy 297.333307 -299.388396) (xy 297.303742 -299.42774) (xy 297.268249 -299.461832) (xy 297.227746 -299.489788)
			(xy 297.183284 -299.510886) (xy 297.136013 -299.524578) (xy 297.087158 -299.53051) (xy 297.037983 -299.528529)
			(xy 296.989764 -299.518685) (xy 296.943748 -299.501233) (xy 296.901127 -299.476626) (xy 296.863006 -299.445501)
			(xy 296.830371 -299.408664) (xy 296.804068 -299.367068) (xy 296.784777 -299.321792) (xy 296.773 -299.274008)
			(xy 296.76904 -299.224954) (xy 296.430192 -299.224954) (xy 296.429697 -299.249561) (xy 296.421802 -299.298138)
			(xy 296.406218 -299.344819) (xy 296.383347 -299.388396) (xy 296.353782 -299.42774) (xy 296.318289 -299.461832)
			(xy 296.277786 -299.489788) (xy 296.233324 -299.510886) (xy 296.186053 -299.524578) (xy 296.137198 -299.53051)
			(xy 296.088023 -299.528529) (xy 296.039804 -299.518685) (xy 295.993788 -299.501233) (xy 295.951167 -299.476626)
			(xy 295.913046 -299.445501) (xy 295.880411 -299.408664) (xy 295.854108 -299.367068) (xy 295.834817 -299.321792)
			(xy 295.82304 -299.274008) (xy 295.81908 -299.224954) (xy 295.480232 -299.224954) (xy 295.479737 -299.249561)
			(xy 295.471842 -299.298138) (xy 295.456258 -299.344819) (xy 295.433387 -299.388396) (xy 295.403822 -299.42774)
			(xy 295.368329 -299.461832) (xy 295.327826 -299.489788) (xy 295.283364 -299.510886) (xy 295.236093 -299.524578)
			(xy 295.187238 -299.53051) (xy 295.138063 -299.528529) (xy 295.089844 -299.518685) (xy 295.043828 -299.501233)
			(xy 295.001207 -299.476626) (xy 294.963086 -299.445501) (xy 294.930451 -299.408664) (xy 294.904148 -299.367068)
			(xy 294.884857 -299.321792) (xy 294.87308 -299.274008) (xy 294.86912 -299.224954) (xy 294.530018 -299.224954)
			(xy 294.529523 -299.249561) (xy 294.521628 -299.298138) (xy 294.506044 -299.344819) (xy 294.483173 -299.388396)
			(xy 294.453608 -299.42774) (xy 294.418115 -299.461832) (xy 294.377612 -299.489788) (xy 294.33315 -299.510886)
			(xy 294.285879 -299.524578) (xy 294.237024 -299.53051) (xy 294.187849 -299.528529) (xy 294.13963 -299.518685)
			(xy 294.093614 -299.501233) (xy 294.050993 -299.476626) (xy 294.012872 -299.445501) (xy 293.980237 -299.408664)
			(xy 293.953934 -299.367068) (xy 293.934643 -299.321792) (xy 293.922866 -299.274008) (xy 293.918906 -299.224954)
			(xy 293.580058 -299.224954) (xy 293.579563 -299.249561) (xy 293.571668 -299.298138) (xy 293.556084 -299.344819)
			(xy 293.533213 -299.388396) (xy 293.503648 -299.42774) (xy 293.468155 -299.461832) (xy 293.427652 -299.489788)
			(xy 293.38319 -299.510886) (xy 293.335919 -299.524578) (xy 293.287064 -299.53051) (xy 293.237889 -299.528529)
			(xy 293.18967 -299.518685) (xy 293.143654 -299.501233) (xy 293.101033 -299.476626) (xy 293.062912 -299.445501)
			(xy 293.030277 -299.408664) (xy 293.003974 -299.367068) (xy 292.984683 -299.321792) (xy 292.972906 -299.274008)
			(xy 292.968946 -299.224954) (xy 292.630098 -299.224954) (xy 292.629603 -299.249561) (xy 292.621708 -299.298138)
			(xy 292.606124 -299.344819) (xy 292.583253 -299.388396) (xy 292.553688 -299.42774) (xy 292.518195 -299.461832)
			(xy 292.477692 -299.489788) (xy 292.43323 -299.510886) (xy 292.385959 -299.524578) (xy 292.337104 -299.53051)
			(xy 292.287929 -299.528529) (xy 292.23971 -299.518685) (xy 292.193694 -299.501233) (xy 292.151073 -299.476626)
			(xy 292.112952 -299.445501) (xy 292.080317 -299.408664) (xy 292.054014 -299.367068) (xy 292.034723 -299.321792)
			(xy 292.022946 -299.274008) (xy 292.018986 -299.224954) (xy 290.730178 -299.224954) (xy 290.729683 -299.249561)
			(xy 290.721788 -299.298138) (xy 290.706204 -299.344819) (xy 290.683333 -299.388396) (xy 290.653768 -299.42774)
			(xy 290.618275 -299.461832) (xy 290.577772 -299.489788) (xy 290.53331 -299.510886) (xy 290.486039 -299.524578)
			(xy 290.437184 -299.53051) (xy 290.388009 -299.528529) (xy 290.33979 -299.518685) (xy 290.293774 -299.501233)
			(xy 290.251153 -299.476626) (xy 290.213032 -299.445501) (xy 290.180397 -299.408664) (xy 290.154094 -299.367068)
			(xy 290.134803 -299.321792) (xy 290.123026 -299.274008) (xy 290.119066 -299.224954) (xy 289.780218 -299.224954)
			(xy 289.779723 -299.249561) (xy 289.771828 -299.298138) (xy 289.756244 -299.344819) (xy 289.733373 -299.388396)
			(xy 289.703808 -299.42774) (xy 289.668315 -299.461832) (xy 289.627812 -299.489788) (xy 289.58335 -299.510886)
			(xy 289.536079 -299.524578) (xy 289.487224 -299.53051) (xy 289.438049 -299.528529) (xy 289.38983 -299.518685)
			(xy 289.343814 -299.501233) (xy 289.301193 -299.476626) (xy 289.263072 -299.445501) (xy 289.230437 -299.408664)
			(xy 289.204134 -299.367068) (xy 289.184843 -299.321792) (xy 289.173066 -299.274008) (xy 289.169106 -299.224954)
			(xy 288.830004 -299.224954) (xy 288.829509 -299.249561) (xy 288.821614 -299.298138) (xy 288.80603 -299.344819)
			(xy 288.783159 -299.388396) (xy 288.753594 -299.42774) (xy 288.718101 -299.461832) (xy 288.677598 -299.489788)
			(xy 288.633136 -299.510886) (xy 288.585865 -299.524578) (xy 288.53701 -299.53051) (xy 288.487835 -299.528529)
			(xy 288.439616 -299.518685) (xy 288.3936 -299.501233) (xy 288.350979 -299.476626) (xy 288.312858 -299.445501)
			(xy 288.280223 -299.408664) (xy 288.25392 -299.367068) (xy 288.234629 -299.321792) (xy 288.222852 -299.274008)
			(xy 288.218892 -299.224954) (xy 287.880044 -299.224954) (xy 287.879549 -299.249561) (xy 287.871654 -299.298138)
			(xy 287.85607 -299.344819) (xy 287.833199 -299.388396) (xy 287.803634 -299.42774) (xy 287.768141 -299.461832)
			(xy 287.727638 -299.489788) (xy 287.683176 -299.510886) (xy 287.635905 -299.524578) (xy 287.58705 -299.53051)
			(xy 287.537875 -299.528529) (xy 287.489656 -299.518685) (xy 287.44364 -299.501233) (xy 287.401019 -299.476626)
			(xy 287.362898 -299.445501) (xy 287.330263 -299.408664) (xy 287.30396 -299.367068) (xy 287.284669 -299.321792)
			(xy 287.272892 -299.274008) (xy 287.268932 -299.224954) (xy 286.930084 -299.224954) (xy 286.929589 -299.249561)
			(xy 286.921694 -299.298138) (xy 286.90611 -299.344819) (xy 286.883239 -299.388396) (xy 286.853674 -299.42774)
			(xy 286.818181 -299.461832) (xy 286.777678 -299.489788) (xy 286.733216 -299.510886) (xy 286.685945 -299.524578)
			(xy 286.63709 -299.53051) (xy 286.587915 -299.528529) (xy 286.539696 -299.518685) (xy 286.49368 -299.501233)
			(xy 286.451059 -299.476626) (xy 286.412938 -299.445501) (xy 286.380303 -299.408664) (xy 286.354 -299.367068)
			(xy 286.334709 -299.321792) (xy 286.322932 -299.274008) (xy 286.318972 -299.224954) (xy 285.980124 -299.224954)
			(xy 285.979629 -299.249561) (xy 285.971734 -299.298138) (xy 285.95615 -299.344819) (xy 285.933279 -299.388396)
			(xy 285.903714 -299.42774) (xy 285.868221 -299.461832) (xy 285.827718 -299.489788) (xy 285.783256 -299.510886)
			(xy 285.735985 -299.524578) (xy 285.68713 -299.53051) (xy 285.637955 -299.528529) (xy 285.589736 -299.518685)
			(xy 285.54372 -299.501233) (xy 285.501099 -299.476626) (xy 285.462978 -299.445501) (xy 285.430343 -299.408664)
			(xy 285.40404 -299.367068) (xy 285.384749 -299.321792) (xy 285.372972 -299.274008) (xy 285.369012 -299.224954)
			(xy 285.030164 -299.224954) (xy 285.029669 -299.249561) (xy 285.021774 -299.298138) (xy 285.00619 -299.344819)
			(xy 284.983319 -299.388396) (xy 284.953754 -299.42774) (xy 284.918261 -299.461832) (xy 284.877758 -299.489788)
			(xy 284.833296 -299.510886) (xy 284.786025 -299.524578) (xy 284.73717 -299.53051) (xy 284.687995 -299.528529)
			(xy 284.639776 -299.518685) (xy 284.59376 -299.501233) (xy 284.551139 -299.476626) (xy 284.513018 -299.445501)
			(xy 284.480383 -299.408664) (xy 284.45408 -299.367068) (xy 284.434789 -299.321792) (xy 284.423012 -299.274008)
			(xy 284.419052 -299.224954) (xy 284.080204 -299.224954) (xy 284.079709 -299.249561) (xy 284.071814 -299.298138)
			(xy 284.05623 -299.344819) (xy 284.033359 -299.388396) (xy 284.003794 -299.42774) (xy 283.968301 -299.461832)
			(xy 283.927798 -299.489788) (xy 283.883336 -299.510886) (xy 283.836065 -299.524578) (xy 283.78721 -299.53051)
			(xy 283.738035 -299.528529) (xy 283.689816 -299.518685) (xy 283.6438 -299.501233) (xy 283.601179 -299.476626)
			(xy 283.563058 -299.445501) (xy 283.530423 -299.408664) (xy 283.50412 -299.367068) (xy 283.484829 -299.321792)
			(xy 283.473052 -299.274008) (xy 283.469092 -299.224954) (xy 283.130244 -299.224954) (xy 283.129749 -299.249561)
			(xy 283.121854 -299.298138) (xy 283.10627 -299.344819) (xy 283.083399 -299.388396) (xy 283.053834 -299.42774)
			(xy 283.018341 -299.461832) (xy 282.977838 -299.489788) (xy 282.933376 -299.510886) (xy 282.886105 -299.524578)
			(xy 282.83725 -299.53051) (xy 282.788075 -299.528529) (xy 282.739856 -299.518685) (xy 282.69384 -299.501233)
			(xy 282.651219 -299.476626) (xy 282.613098 -299.445501) (xy 282.580463 -299.408664) (xy 282.55416 -299.367068)
			(xy 282.534869 -299.321792) (xy 282.523092 -299.274008) (xy 282.519132 -299.224954) (xy 282.18003 -299.224954)
			(xy 282.179535 -299.249561) (xy 282.17164 -299.298138) (xy 282.156056 -299.344819) (xy 282.133185 -299.388396)
			(xy 282.10362 -299.42774) (xy 282.068127 -299.461832) (xy 282.027624 -299.489788) (xy 281.983162 -299.510886)
			(xy 281.935891 -299.524578) (xy 281.887036 -299.53051) (xy 281.837861 -299.528529) (xy 281.789642 -299.518685)
			(xy 281.743626 -299.501233) (xy 281.701005 -299.476626) (xy 281.662884 -299.445501) (xy 281.630249 -299.408664)
			(xy 281.603946 -299.367068) (xy 281.584655 -299.321792) (xy 281.572878 -299.274008) (xy 281.568918 -299.224954)
			(xy 281.23007 -299.224954) (xy 281.229575 -299.249561) (xy 281.22168 -299.298138) (xy 281.206096 -299.344819)
			(xy 281.183225 -299.388396) (xy 281.15366 -299.42774) (xy 281.118167 -299.461832) (xy 281.077664 -299.489788)
			(xy 281.033202 -299.510886) (xy 280.985931 -299.524578) (xy 280.937076 -299.53051) (xy 280.887901 -299.528529)
			(xy 280.839682 -299.518685) (xy 280.793666 -299.501233) (xy 280.751045 -299.476626) (xy 280.712924 -299.445501)
			(xy 280.680289 -299.408664) (xy 280.653986 -299.367068) (xy 280.634695 -299.321792) (xy 280.622918 -299.274008)
			(xy 280.618958 -299.224954) (xy 280.28011 -299.224954) (xy 280.279615 -299.249561) (xy 280.27172 -299.298138)
			(xy 280.256136 -299.344819) (xy 280.233265 -299.388396) (xy 280.2037 -299.42774) (xy 280.168207 -299.461832)
			(xy 280.127704 -299.489788) (xy 280.083242 -299.510886) (xy 280.035971 -299.524578) (xy 279.987116 -299.53051)
			(xy 279.937941 -299.528529) (xy 279.889722 -299.518685) (xy 279.843706 -299.501233) (xy 279.801085 -299.476626)
			(xy 279.762964 -299.445501) (xy 279.730329 -299.408664) (xy 279.704026 -299.367068) (xy 279.684735 -299.321792)
			(xy 279.672958 -299.274008) (xy 279.668998 -299.224954) (xy 279.33015 -299.224954) (xy 279.329655 -299.249561)
			(xy 279.32176 -299.298138) (xy 279.306176 -299.344819) (xy 279.283305 -299.388396) (xy 279.25374 -299.42774)
			(xy 279.218247 -299.461832) (xy 279.177744 -299.489788) (xy 279.133282 -299.510886) (xy 279.086011 -299.524578)
			(xy 279.037156 -299.53051) (xy 278.987981 -299.528529) (xy 278.939762 -299.518685) (xy 278.893746 -299.501233)
			(xy 278.851125 -299.476626) (xy 278.813004 -299.445501) (xy 278.780369 -299.408664) (xy 278.754066 -299.367068)
			(xy 278.734775 -299.321792) (xy 278.722998 -299.274008) (xy 278.719038 -299.224954) (xy 278.38019 -299.224954)
			(xy 278.379695 -299.249561) (xy 278.3718 -299.298138) (xy 278.356216 -299.344819) (xy 278.333345 -299.388396)
			(xy 278.30378 -299.42774) (xy 278.268287 -299.461832) (xy 278.227784 -299.489788) (xy 278.183322 -299.510886)
			(xy 278.136051 -299.524578) (xy 278.087196 -299.53051) (xy 278.038021 -299.528529) (xy 277.989802 -299.518685)
			(xy 277.943786 -299.501233) (xy 277.901165 -299.476626) (xy 277.863044 -299.445501) (xy 277.830409 -299.408664)
			(xy 277.804106 -299.367068) (xy 277.784815 -299.321792) (xy 277.773038 -299.274008) (xy 277.769078 -299.224954)
			(xy 277.43023 -299.224954) (xy 277.429735 -299.249561) (xy 277.42184 -299.298138) (xy 277.406256 -299.344819)
			(xy 277.383385 -299.388396) (xy 277.35382 -299.42774) (xy 277.318327 -299.461832) (xy 277.277824 -299.489788)
			(xy 277.233362 -299.510886) (xy 277.186091 -299.524578) (xy 277.137236 -299.53051) (xy 277.088061 -299.528529)
			(xy 277.039842 -299.518685) (xy 276.993826 -299.501233) (xy 276.951205 -299.476626) (xy 276.913084 -299.445501)
			(xy 276.880449 -299.408664) (xy 276.854146 -299.367068) (xy 276.834855 -299.321792) (xy 276.823078 -299.274008)
			(xy 276.819118 -299.224954) (xy 276.480016 -299.224954) (xy 276.479521 -299.249561) (xy 276.471626 -299.298138)
			(xy 276.456042 -299.344819) (xy 276.433171 -299.388396) (xy 276.403606 -299.42774) (xy 276.368113 -299.461832)
			(xy 276.32761 -299.489788) (xy 276.283148 -299.510886) (xy 276.235877 -299.524578) (xy 276.187022 -299.53051)
			(xy 276.137847 -299.528529) (xy 276.089628 -299.518685) (xy 276.043612 -299.501233) (xy 276.000991 -299.476626)
			(xy 275.96287 -299.445501) (xy 275.930235 -299.408664) (xy 275.903932 -299.367068) (xy 275.884641 -299.321792)
			(xy 275.872864 -299.274008) (xy 275.868904 -299.224954) (xy 274.580093 -299.224954) (xy 274.579922 -299.238946)
			(xy 274.577254 -299.267314) (xy 274.574762 -299.281342) (xy 274.572476 -299.293534) (xy 274.579842 -299.317664)
			(xy 274.657058 -299.39488) (xy 274.680934 -299.402246) (xy 274.69338 -299.39996) (xy 274.707345 -299.397477)
			(xy 274.735585 -299.394809) (xy 274.749768 -299.394626) (xy 274.773762 -299.395068) (xy 274.82116 -299.402571)
			(xy 274.8668 -299.417397) (xy 274.909558 -299.439181) (xy 274.948382 -299.467387) (xy 274.982314 -299.50132)
			(xy 275.01052 -299.540144) (xy 275.032304 -299.582902) (xy 275.04713 -299.628542) (xy 275.054632 -299.67594)
			(xy 275.055076 -299.699934) (xy 275.054905 -299.714117) (xy 275.052229 -299.742357) (xy 275.049742 -299.756322)
			(xy 275.047456 -299.768768) (xy 275.054822 -299.79239) (xy 275.132292 -299.86986) (xy 275.155914 -299.877226)
			(xy 275.16836 -299.87494) (xy 275.182325 -299.87246) (xy 275.210565 -299.86979) (xy 275.224748 -299.869606)
			(xy 275.248741 -299.870018) (xy 275.296136 -299.877532) (xy 275.341772 -299.892367) (xy 275.384526 -299.914158)
			(xy 275.423344 -299.942368) (xy 275.457272 -299.976303) (xy 275.485475 -300.015127) (xy 275.507257 -300.057886)
			(xy 275.522082 -300.103524) (xy 275.529586 -300.150921) (xy 275.530056 -300.174914) (xy 275.529882 -300.189097)
			(xy 275.527208 -300.217337) (xy 275.524722 -300.231302) (xy 275.522436 -300.243748) (xy 275.529802 -300.26737)
			(xy 275.607272 -300.34484) (xy 275.630894 -300.352206) (xy 275.64334 -300.34992) (xy 275.657306 -300.347442)
			(xy 275.685545 -300.344771) (xy 275.699728 -300.344586) (xy 275.713911 -300.344759) (xy 275.742151 -300.347433)
			(xy 275.756116 -300.34992) (xy 275.768562 -300.352206) (xy 275.792184 -300.34484) (xy 275.869654 -300.26737)
			(xy 275.87702 -300.243748) (xy 275.874734 -300.231302) (xy 275.872262 -300.217335) (xy 275.869587 -300.189096)
			(xy 275.8694 -300.174914) (xy 275.869863 -300.150092) (xy 275.877892 -300.101101) (xy 275.893741 -300.054055)
			(xy 275.916993 -300.010193) (xy 275.947035 -299.97067) (xy 275.983075 -299.936528) (xy 276.024164 -299.908667)
			(xy 276.069219 -299.88782) (xy 276.117053 -299.874537) (xy 276.166406 -299.869167) (xy 276.215977 -299.871853)
			(xy 276.264461 -299.882523) (xy 276.31058 -299.900897) (xy 276.353119 -299.92649) (xy 276.390957 -299.958627)
			(xy 276.423098 -299.996463) (xy 276.448693 -300.039) (xy 276.46707 -300.085118) (xy 276.477744 -300.133601)
			(xy 276.479985 -300.174914) (xy 276.819118 -300.174914) (xy 276.823078 -300.12586) (xy 276.834855 -300.078076)
			(xy 276.854146 -300.0328) (xy 276.880449 -299.991204) (xy 276.913084 -299.954367) (xy 276.951205 -299.923242)
			(xy 276.993826 -299.898635) (xy 277.039842 -299.881183) (xy 277.088061 -299.871339) (xy 277.137236 -299.869358)
			(xy 277.186091 -299.87529) (xy 277.233362 -299.888982) (xy 277.277824 -299.91008) (xy 277.318327 -299.938036)
			(xy 277.35382 -299.972128) (xy 277.383385 -300.011472) (xy 277.406256 -300.055049) (xy 277.42184 -300.10173)
			(xy 277.429735 -300.150307) (xy 277.43023 -300.174914) (xy 277.769078 -300.174914) (xy 277.773038 -300.12586)
			(xy 277.784815 -300.078076) (xy 277.804106 -300.0328) (xy 277.830409 -299.991204) (xy 277.863044 -299.954367)
			(xy 277.901165 -299.923242) (xy 277.943786 -299.898635) (xy 277.989802 -299.881183) (xy 278.038021 -299.871339)
			(xy 278.087196 -299.869358) (xy 278.136051 -299.87529) (xy 278.183322 -299.888982) (xy 278.227784 -299.91008)
			(xy 278.268287 -299.938036) (xy 278.30378 -299.972128) (xy 278.333345 -300.011472) (xy 278.356216 -300.055049)
			(xy 278.3718 -300.10173) (xy 278.379695 -300.150307) (xy 278.38019 -300.174914) (xy 279.668998 -300.174914)
			(xy 279.672958 -300.12586) (xy 279.684735 -300.078076) (xy 279.704026 -300.0328) (xy 279.730329 -299.991204)
			(xy 279.762964 -299.954367) (xy 279.801085 -299.923242) (xy 279.843706 -299.898635) (xy 279.889722 -299.881183)
			(xy 279.937941 -299.871339) (xy 279.987116 -299.869358) (xy 280.035971 -299.87529) (xy 280.083242 -299.888982)
			(xy 280.127704 -299.91008) (xy 280.168207 -299.938036) (xy 280.2037 -299.972128) (xy 280.233265 -300.011472)
			(xy 280.256136 -300.055049) (xy 280.27172 -300.10173) (xy 280.279615 -300.150307) (xy 280.28011 -300.174914)
			(xy 280.618958 -300.174914) (xy 280.622918 -300.12586) (xy 280.634695 -300.078076) (xy 280.653986 -300.0328)
			(xy 280.680289 -299.991204) (xy 280.712924 -299.954367) (xy 280.751045 -299.923242) (xy 280.793666 -299.898635)
			(xy 280.839682 -299.881183) (xy 280.887901 -299.871339) (xy 280.937076 -299.869358) (xy 280.985931 -299.87529)
			(xy 281.033202 -299.888982) (xy 281.077664 -299.91008) (xy 281.118167 -299.938036) (xy 281.15366 -299.972128)
			(xy 281.183225 -300.011472) (xy 281.206096 -300.055049) (xy 281.22168 -300.10173) (xy 281.229575 -300.150307)
			(xy 281.23007 -300.174914) (xy 281.568918 -300.174914) (xy 281.572878 -300.12586) (xy 281.584655 -300.078076)
			(xy 281.603946 -300.0328) (xy 281.630249 -299.991204) (xy 281.662884 -299.954367) (xy 281.701005 -299.923242)
			(xy 281.743626 -299.898635) (xy 281.789642 -299.881183) (xy 281.837861 -299.871339) (xy 281.887036 -299.869358)
			(xy 281.935891 -299.87529) (xy 281.983162 -299.888982) (xy 282.027624 -299.91008) (xy 282.068127 -299.938036)
			(xy 282.10362 -299.972128) (xy 282.133185 -300.011472) (xy 282.156056 -300.055049) (xy 282.17164 -300.10173)
			(xy 282.179535 -300.150307) (xy 282.18003 -300.174914) (xy 282.519132 -300.174914) (xy 282.523092 -300.12586)
			(xy 282.534869 -300.078076) (xy 282.55416 -300.0328) (xy 282.580463 -299.991204) (xy 282.613098 -299.954367)
			(xy 282.651219 -299.923242) (xy 282.69384 -299.898635) (xy 282.739856 -299.881183) (xy 282.788075 -299.871339)
			(xy 282.83725 -299.869358) (xy 282.886105 -299.87529) (xy 282.933376 -299.888982) (xy 282.977838 -299.91008)
			(xy 283.018341 -299.938036) (xy 283.053834 -299.972128) (xy 283.083399 -300.011472) (xy 283.10627 -300.055049)
			(xy 283.121854 -300.10173) (xy 283.129749 -300.150307) (xy 283.130244 -300.174914) (xy 283.469092 -300.174914)
			(xy 283.473052 -300.12586) (xy 283.484829 -300.078076) (xy 283.50412 -300.0328) (xy 283.530423 -299.991204)
			(xy 283.563058 -299.954367) (xy 283.601179 -299.923242) (xy 283.6438 -299.898635) (xy 283.689816 -299.881183)
			(xy 283.738035 -299.871339) (xy 283.78721 -299.869358) (xy 283.836065 -299.87529) (xy 283.883336 -299.888982)
			(xy 283.927798 -299.91008) (xy 283.968301 -299.938036) (xy 284.003794 -299.972128) (xy 284.033359 -300.011472)
			(xy 284.05623 -300.055049) (xy 284.071814 -300.10173) (xy 284.079709 -300.150307) (xy 284.080204 -300.174914)
			(xy 284.419052 -300.174914) (xy 284.423012 -300.12586) (xy 284.434789 -300.078076) (xy 284.45408 -300.0328)
			(xy 284.480383 -299.991204) (xy 284.513018 -299.954367) (xy 284.551139 -299.923242) (xy 284.59376 -299.898635)
			(xy 284.639776 -299.881183) (xy 284.687995 -299.871339) (xy 284.73717 -299.869358) (xy 284.786025 -299.87529)
			(xy 284.833296 -299.888982) (xy 284.877758 -299.91008) (xy 284.918261 -299.938036) (xy 284.953754 -299.972128)
			(xy 284.983319 -300.011472) (xy 285.00619 -300.055049) (xy 285.021774 -300.10173) (xy 285.029669 -300.150307)
			(xy 285.030164 -300.174914) (xy 285.369012 -300.174914) (xy 285.372972 -300.12586) (xy 285.384749 -300.078076)
			(xy 285.40404 -300.0328) (xy 285.430343 -299.991204) (xy 285.462978 -299.954367) (xy 285.501099 -299.923242)
			(xy 285.54372 -299.898635) (xy 285.589736 -299.881183) (xy 285.637955 -299.871339) (xy 285.68713 -299.869358)
			(xy 285.735985 -299.87529) (xy 285.783256 -299.888982) (xy 285.827718 -299.91008) (xy 285.868221 -299.938036)
			(xy 285.903714 -299.972128) (xy 285.933279 -300.011472) (xy 285.95615 -300.055049) (xy 285.971734 -300.10173)
			(xy 285.979629 -300.150307) (xy 285.980124 -300.174914) (xy 286.318972 -300.174914) (xy 286.322932 -300.12586)
			(xy 286.334709 -300.078076) (xy 286.354 -300.0328) (xy 286.380303 -299.991204) (xy 286.412938 -299.954367)
			(xy 286.451059 -299.923242) (xy 286.49368 -299.898635) (xy 286.539696 -299.881183) (xy 286.587915 -299.871339)
			(xy 286.63709 -299.869358) (xy 286.685945 -299.87529) (xy 286.733216 -299.888982) (xy 286.777678 -299.91008)
			(xy 286.818181 -299.938036) (xy 286.853674 -299.972128) (xy 286.883239 -300.011472) (xy 286.90611 -300.055049)
			(xy 286.921694 -300.10173) (xy 286.929589 -300.150307) (xy 286.930084 -300.174914) (xy 287.268932 -300.174914)
			(xy 287.272892 -300.12586) (xy 287.284669 -300.078076) (xy 287.30396 -300.0328) (xy 287.330263 -299.991204)
			(xy 287.362898 -299.954367) (xy 287.401019 -299.923242) (xy 287.44364 -299.898635) (xy 287.489656 -299.881183)
			(xy 287.537875 -299.871339) (xy 287.58705 -299.869358) (xy 287.635905 -299.87529) (xy 287.683176 -299.888982)
			(xy 287.727638 -299.91008) (xy 287.768141 -299.938036) (xy 287.803634 -299.972128) (xy 287.833199 -300.011472)
			(xy 287.85607 -300.055049) (xy 287.871654 -300.10173) (xy 287.879549 -300.150307) (xy 287.880044 -300.174914)
			(xy 288.218892 -300.174914) (xy 288.222852 -300.12586) (xy 288.234629 -300.078076) (xy 288.25392 -300.0328)
			(xy 288.280223 -299.991204) (xy 288.312858 -299.954367) (xy 288.350979 -299.923242) (xy 288.3936 -299.898635)
			(xy 288.439616 -299.881183) (xy 288.487835 -299.871339) (xy 288.53701 -299.869358) (xy 288.585865 -299.87529)
			(xy 288.633136 -299.888982) (xy 288.677598 -299.91008) (xy 288.718101 -299.938036) (xy 288.753594 -299.972128)
			(xy 288.783159 -300.011472) (xy 288.80603 -300.055049) (xy 288.821614 -300.10173) (xy 288.829509 -300.150307)
			(xy 288.830004 -300.174914) (xy 289.169106 -300.174914) (xy 289.173066 -300.12586) (xy 289.184843 -300.078076)
			(xy 289.204134 -300.0328) (xy 289.230437 -299.991204) (xy 289.263072 -299.954367) (xy 289.301193 -299.923242)
			(xy 289.343814 -299.898635) (xy 289.38983 -299.881183) (xy 289.438049 -299.871339) (xy 289.487224 -299.869358)
			(xy 289.536079 -299.87529) (xy 289.58335 -299.888982) (xy 289.627812 -299.91008) (xy 289.668315 -299.938036)
			(xy 289.703808 -299.972128) (xy 289.733373 -300.011472) (xy 289.756244 -300.055049) (xy 289.771828 -300.10173)
			(xy 289.779723 -300.150307) (xy 289.780218 -300.174914) (xy 290.119066 -300.174914) (xy 290.123026 -300.12586)
			(xy 290.134803 -300.078076) (xy 290.154094 -300.0328) (xy 290.180397 -299.991204) (xy 290.213032 -299.954367)
			(xy 290.251153 -299.923242) (xy 290.293774 -299.898635) (xy 290.33979 -299.881183) (xy 290.388009 -299.871339)
			(xy 290.437184 -299.869358) (xy 290.486039 -299.87529) (xy 290.53331 -299.888982) (xy 290.577772 -299.91008)
			(xy 290.618275 -299.938036) (xy 290.653768 -299.972128) (xy 290.683333 -300.011472) (xy 290.706204 -300.055049)
			(xy 290.721788 -300.10173) (xy 290.729683 -300.150307) (xy 290.730178 -300.174914) (xy 292.018986 -300.174914)
			(xy 292.022946 -300.12586) (xy 292.034723 -300.078076) (xy 292.054014 -300.0328) (xy 292.080317 -299.991204)
			(xy 292.112952 -299.954367) (xy 292.151073 -299.923242) (xy 292.193694 -299.898635) (xy 292.23971 -299.881183)
			(xy 292.287929 -299.871339) (xy 292.337104 -299.869358) (xy 292.385959 -299.87529) (xy 292.43323 -299.888982)
			(xy 292.477692 -299.91008) (xy 292.518195 -299.938036) (xy 292.553688 -299.972128) (xy 292.583253 -300.011472)
			(xy 292.606124 -300.055049) (xy 292.621708 -300.10173) (xy 292.629603 -300.150307) (xy 292.630098 -300.174914)
			(xy 292.968946 -300.174914) (xy 292.972906 -300.12586) (xy 292.984683 -300.078076) (xy 293.003974 -300.0328)
			(xy 293.030277 -299.991204) (xy 293.062912 -299.954367) (xy 293.101033 -299.923242) (xy 293.143654 -299.898635)
			(xy 293.18967 -299.881183) (xy 293.237889 -299.871339) (xy 293.287064 -299.869358) (xy 293.335919 -299.87529)
			(xy 293.38319 -299.888982) (xy 293.427652 -299.91008) (xy 293.468155 -299.938036) (xy 293.503648 -299.972128)
			(xy 293.533213 -300.011472) (xy 293.556084 -300.055049) (xy 293.571668 -300.10173) (xy 293.579563 -300.150307)
			(xy 293.580058 -300.174914) (xy 293.918906 -300.174914) (xy 293.922866 -300.12586) (xy 293.934643 -300.078076)
			(xy 293.953934 -300.0328) (xy 293.980237 -299.991204) (xy 294.012872 -299.954367) (xy 294.050993 -299.923242)
			(xy 294.093614 -299.898635) (xy 294.13963 -299.881183) (xy 294.187849 -299.871339) (xy 294.237024 -299.869358)
			(xy 294.285879 -299.87529) (xy 294.33315 -299.888982) (xy 294.377612 -299.91008) (xy 294.418115 -299.938036)
			(xy 294.453608 -299.972128) (xy 294.483173 -300.011472) (xy 294.506044 -300.055049) (xy 294.521628 -300.10173)
			(xy 294.529523 -300.150307) (xy 294.530018 -300.174914) (xy 294.86912 -300.174914) (xy 294.87308 -300.12586)
			(xy 294.884857 -300.078076) (xy 294.904148 -300.0328) (xy 294.930451 -299.991204) (xy 294.963086 -299.954367)
			(xy 295.001207 -299.923242) (xy 295.043828 -299.898635) (xy 295.089844 -299.881183) (xy 295.138063 -299.871339)
			(xy 295.187238 -299.869358) (xy 295.236093 -299.87529) (xy 295.283364 -299.888982) (xy 295.327826 -299.91008)
			(xy 295.368329 -299.938036) (xy 295.403822 -299.972128) (xy 295.433387 -300.011472) (xy 295.456258 -300.055049)
			(xy 295.471842 -300.10173) (xy 295.479737 -300.150307) (xy 295.480232 -300.174914) (xy 295.81908 -300.174914)
			(xy 295.82304 -300.12586) (xy 295.834817 -300.078076) (xy 295.854108 -300.0328) (xy 295.880411 -299.991204)
			(xy 295.913046 -299.954367) (xy 295.951167 -299.923242) (xy 295.993788 -299.898635) (xy 296.039804 -299.881183)
			(xy 296.088023 -299.871339) (xy 296.137198 -299.869358) (xy 296.186053 -299.87529) (xy 296.233324 -299.888982)
			(xy 296.277786 -299.91008) (xy 296.318289 -299.938036) (xy 296.353782 -299.972128) (xy 296.383347 -300.011472)
			(xy 296.406218 -300.055049) (xy 296.421802 -300.10173) (xy 296.429697 -300.150307) (xy 296.430192 -300.174914)
			(xy 296.76904 -300.174914) (xy 296.773 -300.12586) (xy 296.784777 -300.078076) (xy 296.804068 -300.0328)
			(xy 296.830371 -299.991204) (xy 296.863006 -299.954367) (xy 296.901127 -299.923242) (xy 296.943748 -299.898635)
			(xy 296.989764 -299.881183) (xy 297.037983 -299.871339) (xy 297.087158 -299.869358) (xy 297.136013 -299.87529)
			(xy 297.183284 -299.888982) (xy 297.227746 -299.91008) (xy 297.268249 -299.938036) (xy 297.303742 -299.972128)
			(xy 297.333307 -300.011472) (xy 297.356178 -300.055049) (xy 297.371762 -300.10173) (xy 297.379657 -300.150307)
			(xy 297.380152 -300.174914) (xy 297.719 -300.174914) (xy 297.72296 -300.12586) (xy 297.734737 -300.078076)
			(xy 297.754028 -300.0328) (xy 297.780331 -299.991204) (xy 297.812966 -299.954367) (xy 297.851087 -299.923242)
			(xy 297.893708 -299.898635) (xy 297.939724 -299.881183) (xy 297.987943 -299.871339) (xy 298.037118 -299.869358)
			(xy 298.085973 -299.87529) (xy 298.133244 -299.888982) (xy 298.177706 -299.91008) (xy 298.218209 -299.938036)
			(xy 298.253702 -299.972128) (xy 298.283267 -300.011472) (xy 298.306138 -300.055049) (xy 298.321722 -300.10173)
			(xy 298.329617 -300.150307) (xy 298.330112 -300.174914) (xy 298.66896 -300.174914) (xy 298.67292 -300.12586)
			(xy 298.684697 -300.078076) (xy 298.703988 -300.0328) (xy 298.730291 -299.991204) (xy 298.762926 -299.954367)
			(xy 298.801047 -299.923242) (xy 298.843668 -299.898635) (xy 298.889684 -299.881183) (xy 298.937903 -299.871339)
			(xy 298.987078 -299.869358) (xy 299.035933 -299.87529) (xy 299.083204 -299.888982) (xy 299.127666 -299.91008)
			(xy 299.168169 -299.938036) (xy 299.203662 -299.972128) (xy 299.233227 -300.011472) (xy 299.256098 -300.055049)
			(xy 299.271682 -300.10173) (xy 299.279577 -300.150307) (xy 299.280072 -300.174914) (xy 299.61892 -300.174914)
			(xy 299.62288 -300.12586) (xy 299.634657 -300.078076) (xy 299.653948 -300.0328) (xy 299.680251 -299.991204)
			(xy 299.712886 -299.954367) (xy 299.751007 -299.923242) (xy 299.793628 -299.898635) (xy 299.839644 -299.881183)
			(xy 299.887863 -299.871339) (xy 299.937038 -299.869358) (xy 299.985893 -299.87529) (xy 300.033164 -299.888982)
			(xy 300.077626 -299.91008) (xy 300.118129 -299.938036) (xy 300.153622 -299.972128) (xy 300.183187 -300.011472)
			(xy 300.206058 -300.055049) (xy 300.221642 -300.10173) (xy 300.229537 -300.150307) (xy 300.230032 -300.174914)
			(xy 300.56888 -300.174914) (xy 300.57284 -300.12586) (xy 300.584617 -300.078076) (xy 300.603908 -300.0328)
			(xy 300.630211 -299.991204) (xy 300.662846 -299.954367) (xy 300.700967 -299.923242) (xy 300.743588 -299.898635)
			(xy 300.789604 -299.881183) (xy 300.837823 -299.871339) (xy 300.886998 -299.869358) (xy 300.935853 -299.87529)
			(xy 300.983124 -299.888982) (xy 301.027586 -299.91008) (xy 301.068089 -299.938036) (xy 301.103582 -299.972128)
			(xy 301.133147 -300.011472) (xy 301.156018 -300.055049) (xy 301.171602 -300.10173) (xy 301.179497 -300.150307)
			(xy 301.179992 -300.174914) (xy 301.519094 -300.174914) (xy 301.523054 -300.12586) (xy 301.534831 -300.078076)
			(xy 301.554122 -300.0328) (xy 301.580425 -299.991204) (xy 301.61306 -299.954367) (xy 301.651181 -299.923242)
			(xy 301.693802 -299.898635) (xy 301.739818 -299.881183) (xy 301.788037 -299.871339) (xy 301.837212 -299.869358)
			(xy 301.886067 -299.87529) (xy 301.933338 -299.888982) (xy 301.9778 -299.91008) (xy 302.018303 -299.938036)
			(xy 302.053796 -299.972128) (xy 302.083361 -300.011472) (xy 302.106232 -300.055049) (xy 302.121816 -300.10173)
			(xy 302.129711 -300.150307) (xy 302.130206 -300.174914) (xy 302.469054 -300.174914) (xy 302.473014 -300.12586)
			(xy 302.484791 -300.078076) (xy 302.504082 -300.0328) (xy 302.530385 -299.991204) (xy 302.56302 -299.954367)
			(xy 302.601141 -299.923242) (xy 302.643762 -299.898635) (xy 302.689778 -299.881183) (xy 302.737997 -299.871339)
			(xy 302.787172 -299.869358) (xy 302.836027 -299.87529) (xy 302.883298 -299.888982) (xy 302.92776 -299.91008)
			(xy 302.968263 -299.938036) (xy 303.003756 -299.972128) (xy 303.033321 -300.011472) (xy 303.056192 -300.055049)
			(xy 303.071776 -300.10173) (xy 303.079671 -300.150307) (xy 303.080166 -300.174914) (xy 303.419014 -300.174914)
			(xy 303.422974 -300.12586) (xy 303.434751 -300.078076) (xy 303.454042 -300.0328) (xy 303.480345 -299.991204)
			(xy 303.51298 -299.954367) (xy 303.551101 -299.923242) (xy 303.593722 -299.898635) (xy 303.639738 -299.881183)
			(xy 303.687957 -299.871339) (xy 303.737132 -299.869358) (xy 303.785987 -299.87529) (xy 303.833258 -299.888982)
			(xy 303.87772 -299.91008) (xy 303.918223 -299.938036) (xy 303.953716 -299.972128) (xy 303.983281 -300.011472)
			(xy 304.006152 -300.055049) (xy 304.021736 -300.10173) (xy 304.029631 -300.150307) (xy 304.030126 -300.174914)
			(xy 304.368974 -300.174914) (xy 304.372934 -300.12586) (xy 304.384711 -300.078076) (xy 304.404002 -300.0328)
			(xy 304.430305 -299.991204) (xy 304.46294 -299.954367) (xy 304.501061 -299.923242) (xy 304.543682 -299.898635)
			(xy 304.589698 -299.881183) (xy 304.637917 -299.871339) (xy 304.687092 -299.869358) (xy 304.735947 -299.87529)
			(xy 304.783218 -299.888982) (xy 304.82768 -299.91008) (xy 304.868183 -299.938036) (xy 304.903676 -299.972128)
			(xy 304.933241 -300.011472) (xy 304.956112 -300.055049) (xy 304.971696 -300.10173) (xy 304.979591 -300.150307)
			(xy 304.980086 -300.174914) (xy 305.318934 -300.174914) (xy 305.322894 -300.12586) (xy 305.334671 -300.078076)
			(xy 305.353962 -300.0328) (xy 305.380265 -299.991204) (xy 305.4129 -299.954367) (xy 305.451021 -299.923242)
			(xy 305.493642 -299.898635) (xy 305.539658 -299.881183) (xy 305.587877 -299.871339) (xy 305.637052 -299.869358)
			(xy 305.685907 -299.87529) (xy 305.733178 -299.888982) (xy 305.77764 -299.91008) (xy 305.818143 -299.938036)
			(xy 305.853636 -299.972128) (xy 305.883201 -300.011472) (xy 305.906072 -300.055049) (xy 305.921656 -300.10173)
			(xy 305.929551 -300.150307) (xy 305.930046 -300.174914) (xy 306.268894 -300.174914) (xy 306.272854 -300.12586)
			(xy 306.284631 -300.078076) (xy 306.303922 -300.0328) (xy 306.330225 -299.991204) (xy 306.36286 -299.954367)
			(xy 306.400981 -299.923242) (xy 306.443602 -299.898635) (xy 306.489618 -299.881183) (xy 306.537837 -299.871339)
			(xy 306.587012 -299.869358) (xy 306.635867 -299.87529) (xy 306.683138 -299.888982) (xy 306.7276 -299.91008)
			(xy 306.768103 -299.938036) (xy 306.803596 -299.972128) (xy 306.833161 -300.011472) (xy 306.856032 -300.055049)
			(xy 306.871616 -300.10173) (xy 306.879511 -300.150307) (xy 306.880006 -300.174914) (xy 307.219108 -300.174914)
			(xy 307.223068 -300.12586) (xy 307.234845 -300.078076) (xy 307.254136 -300.0328) (xy 307.280439 -299.991204)
			(xy 307.313074 -299.954367) (xy 307.351195 -299.923242) (xy 307.393816 -299.898635) (xy 307.439832 -299.881183)
			(xy 307.488051 -299.871339) (xy 307.537226 -299.869358) (xy 307.586081 -299.87529) (xy 307.633352 -299.888982)
			(xy 307.677814 -299.91008) (xy 307.718317 -299.938036) (xy 307.75381 -299.972128) (xy 307.783375 -300.011472)
			(xy 307.806246 -300.055049) (xy 307.82183 -300.10173) (xy 307.829725 -300.150307) (xy 307.83022 -300.174914)
			(xy 308.169068 -300.174914) (xy 308.173028 -300.12586) (xy 308.184805 -300.078076) (xy 308.204096 -300.0328)
			(xy 308.230399 -299.991204) (xy 308.263034 -299.954367) (xy 308.301155 -299.923242) (xy 308.343776 -299.898635)
			(xy 308.389792 -299.881183) (xy 308.438011 -299.871339) (xy 308.487186 -299.869358) (xy 308.536041 -299.87529)
			(xy 308.583312 -299.888982) (xy 308.627774 -299.91008) (xy 308.668277 -299.938036) (xy 308.70377 -299.972128)
			(xy 308.733335 -300.011472) (xy 308.756206 -300.055049) (xy 308.77179 -300.10173) (xy 308.779685 -300.150307)
			(xy 308.78018 -300.174914) (xy 309.119028 -300.174914) (xy 309.122988 -300.12586) (xy 309.134765 -300.078076)
			(xy 309.154056 -300.0328) (xy 309.180359 -299.991204) (xy 309.212994 -299.954367) (xy 309.251115 -299.923242)
			(xy 309.293736 -299.898635) (xy 309.339752 -299.881183) (xy 309.387971 -299.871339) (xy 309.437146 -299.869358)
			(xy 309.486001 -299.87529) (xy 309.533272 -299.888982) (xy 309.577734 -299.91008) (xy 309.618237 -299.938036)
			(xy 309.65373 -299.972128) (xy 309.683295 -300.011472) (xy 309.706166 -300.055049) (xy 309.72175 -300.10173)
			(xy 309.729645 -300.150307) (xy 309.73014 -300.174914) (xy 310.068988 -300.174914) (xy 310.072948 -300.12586)
			(xy 310.084725 -300.078076) (xy 310.104016 -300.0328) (xy 310.130319 -299.991204) (xy 310.162954 -299.954367)
			(xy 310.201075 -299.923242) (xy 310.243696 -299.898635) (xy 310.289712 -299.881183) (xy 310.337931 -299.871339)
			(xy 310.387106 -299.869358) (xy 310.435961 -299.87529) (xy 310.483232 -299.888982) (xy 310.527694 -299.91008)
			(xy 310.568197 -299.938036) (xy 310.60369 -299.972128) (xy 310.633255 -300.011472) (xy 310.656126 -300.055049)
			(xy 310.67171 -300.10173) (xy 310.679605 -300.150307) (xy 310.6801 -300.174914) (xy 311.018948 -300.174914)
			(xy 311.022908 -300.12586) (xy 311.034685 -300.078076) (xy 311.053976 -300.0328) (xy 311.080279 -299.991204)
			(xy 311.112914 -299.954367) (xy 311.151035 -299.923242) (xy 311.193656 -299.898635) (xy 311.239672 -299.881183)
			(xy 311.287891 -299.871339) (xy 311.337066 -299.869358) (xy 311.385921 -299.87529) (xy 311.433192 -299.888982)
			(xy 311.477654 -299.91008) (xy 311.518157 -299.938036) (xy 311.55365 -299.972128) (xy 311.583215 -300.011472)
			(xy 311.606086 -300.055049) (xy 311.62167 -300.10173) (xy 311.629565 -300.150307) (xy 311.63006 -300.174914)
			(xy 311.968908 -300.174914) (xy 311.972868 -300.12586) (xy 311.984645 -300.078076) (xy 312.003936 -300.0328)
			(xy 312.030239 -299.991204) (xy 312.062874 -299.954367) (xy 312.100995 -299.923242) (xy 312.143616 -299.898635)
			(xy 312.189632 -299.881183) (xy 312.237851 -299.871339) (xy 312.287026 -299.869358) (xy 312.335881 -299.87529)
			(xy 312.383152 -299.888982) (xy 312.427614 -299.91008) (xy 312.468117 -299.938036) (xy 312.50361 -299.972128)
			(xy 312.533175 -300.011472) (xy 312.556046 -300.055049) (xy 312.57163 -300.10173) (xy 312.579525 -300.150307)
			(xy 312.58002 -300.174914) (xy 312.919122 -300.174914) (xy 312.923082 -300.12586) (xy 312.934859 -300.078076)
			(xy 312.95415 -300.0328) (xy 312.980453 -299.991204) (xy 313.013088 -299.954367) (xy 313.051209 -299.923242)
			(xy 313.09383 -299.898635) (xy 313.139846 -299.881183) (xy 313.188065 -299.871339) (xy 313.23724 -299.869358)
			(xy 313.286095 -299.87529) (xy 313.333366 -299.888982) (xy 313.377828 -299.91008) (xy 313.418331 -299.938036)
			(xy 313.453824 -299.972128) (xy 313.483389 -300.011472) (xy 313.50626 -300.055049) (xy 313.521844 -300.10173)
			(xy 313.529739 -300.150307) (xy 313.530234 -300.174914) (xy 313.869082 -300.174914) (xy 313.873042 -300.12586)
			(xy 313.884819 -300.078076) (xy 313.90411 -300.0328) (xy 313.930413 -299.991204) (xy 313.963048 -299.954367)
			(xy 314.001169 -299.923242) (xy 314.04379 -299.898635) (xy 314.089806 -299.881183) (xy 314.138025 -299.871339)
			(xy 314.1872 -299.869358) (xy 314.236055 -299.87529) (xy 314.283326 -299.888982) (xy 314.327788 -299.91008)
			(xy 314.368291 -299.938036) (xy 314.403784 -299.972128) (xy 314.433349 -300.011472) (xy 314.45622 -300.055049)
			(xy 314.471804 -300.10173) (xy 314.479699 -300.150307) (xy 314.480194 -300.174914) (xy 314.819042 -300.174914)
			(xy 314.823002 -300.12586) (xy 314.834779 -300.078076) (xy 314.85407 -300.0328) (xy 314.880373 -299.991204)
			(xy 314.913008 -299.954367) (xy 314.951129 -299.923242) (xy 314.99375 -299.898635) (xy 315.039766 -299.881183)
			(xy 315.087985 -299.871339) (xy 315.13716 -299.869358) (xy 315.186015 -299.87529) (xy 315.233286 -299.888982)
			(xy 315.277748 -299.91008) (xy 315.318251 -299.938036) (xy 315.353744 -299.972128) (xy 315.383309 -300.011472)
			(xy 315.40618 -300.055049) (xy 315.421764 -300.10173) (xy 315.429659 -300.150307) (xy 315.430154 -300.174914)
			(xy 315.429659 -300.199521) (xy 315.421764 -300.248098) (xy 315.40618 -300.294779) (xy 315.383309 -300.338356)
			(xy 315.353744 -300.3777) (xy 315.318251 -300.411792) (xy 315.277748 -300.439748) (xy 315.233286 -300.460846)
			(xy 315.186015 -300.474538) (xy 315.13716 -300.48047) (xy 315.087985 -300.478489) (xy 315.039766 -300.468645)
			(xy 314.99375 -300.451193) (xy 314.951129 -300.426586) (xy 314.913008 -300.395461) (xy 314.880373 -300.358624)
			(xy 314.85407 -300.317028) (xy 314.834779 -300.271752) (xy 314.823002 -300.223968) (xy 314.819042 -300.174914)
			(xy 314.480194 -300.174914) (xy 314.479699 -300.199521) (xy 314.471804 -300.248098) (xy 314.45622 -300.294779)
			(xy 314.433349 -300.338356) (xy 314.403784 -300.3777) (xy 314.368291 -300.411792) (xy 314.327788 -300.439748)
			(xy 314.283326 -300.460846) (xy 314.236055 -300.474538) (xy 314.1872 -300.48047) (xy 314.138025 -300.478489)
			(xy 314.089806 -300.468645) (xy 314.04379 -300.451193) (xy 314.001169 -300.426586) (xy 313.963048 -300.395461)
			(xy 313.930413 -300.358624) (xy 313.90411 -300.317028) (xy 313.884819 -300.271752) (xy 313.873042 -300.223968)
			(xy 313.869082 -300.174914) (xy 313.530234 -300.174914) (xy 313.529739 -300.199521) (xy 313.521844 -300.248098)
			(xy 313.50626 -300.294779) (xy 313.483389 -300.338356) (xy 313.453824 -300.3777) (xy 313.418331 -300.411792)
			(xy 313.377828 -300.439748) (xy 313.333366 -300.460846) (xy 313.286095 -300.474538) (xy 313.23724 -300.48047)
			(xy 313.188065 -300.478489) (xy 313.139846 -300.468645) (xy 313.09383 -300.451193) (xy 313.051209 -300.426586)
			(xy 313.013088 -300.395461) (xy 312.980453 -300.358624) (xy 312.95415 -300.317028) (xy 312.934859 -300.271752)
			(xy 312.923082 -300.223968) (xy 312.919122 -300.174914) (xy 312.58002 -300.174914) (xy 312.579525 -300.199521)
			(xy 312.57163 -300.248098) (xy 312.556046 -300.294779) (xy 312.533175 -300.338356) (xy 312.50361 -300.3777)
			(xy 312.468117 -300.411792) (xy 312.427614 -300.439748) (xy 312.383152 -300.460846) (xy 312.335881 -300.474538)
			(xy 312.287026 -300.48047) (xy 312.237851 -300.478489) (xy 312.189632 -300.468645) (xy 312.143616 -300.451193)
			(xy 312.100995 -300.426586) (xy 312.062874 -300.395461) (xy 312.030239 -300.358624) (xy 312.003936 -300.317028)
			(xy 311.984645 -300.271752) (xy 311.972868 -300.223968) (xy 311.968908 -300.174914) (xy 311.63006 -300.174914)
			(xy 311.629565 -300.199521) (xy 311.62167 -300.248098) (xy 311.606086 -300.294779) (xy 311.583215 -300.338356)
			(xy 311.55365 -300.3777) (xy 311.518157 -300.411792) (xy 311.477654 -300.439748) (xy 311.433192 -300.460846)
			(xy 311.385921 -300.474538) (xy 311.337066 -300.48047) (xy 311.287891 -300.478489) (xy 311.239672 -300.468645)
			(xy 311.193656 -300.451193) (xy 311.151035 -300.426586) (xy 311.112914 -300.395461) (xy 311.080279 -300.358624)
			(xy 311.053976 -300.317028) (xy 311.034685 -300.271752) (xy 311.022908 -300.223968) (xy 311.018948 -300.174914)
			(xy 310.6801 -300.174914) (xy 310.679605 -300.199521) (xy 310.67171 -300.248098) (xy 310.656126 -300.294779)
			(xy 310.633255 -300.338356) (xy 310.60369 -300.3777) (xy 310.568197 -300.411792) (xy 310.527694 -300.439748)
			(xy 310.483232 -300.460846) (xy 310.435961 -300.474538) (xy 310.387106 -300.48047) (xy 310.337931 -300.478489)
			(xy 310.289712 -300.468645) (xy 310.243696 -300.451193) (xy 310.201075 -300.426586) (xy 310.162954 -300.395461)
			(xy 310.130319 -300.358624) (xy 310.104016 -300.317028) (xy 310.084725 -300.271752) (xy 310.072948 -300.223968)
			(xy 310.068988 -300.174914) (xy 309.73014 -300.174914) (xy 309.729645 -300.199521) (xy 309.72175 -300.248098)
			(xy 309.706166 -300.294779) (xy 309.683295 -300.338356) (xy 309.65373 -300.3777) (xy 309.618237 -300.411792)
			(xy 309.577734 -300.439748) (xy 309.533272 -300.460846) (xy 309.486001 -300.474538) (xy 309.437146 -300.48047)
			(xy 309.387971 -300.478489) (xy 309.339752 -300.468645) (xy 309.293736 -300.451193) (xy 309.251115 -300.426586)
			(xy 309.212994 -300.395461) (xy 309.180359 -300.358624) (xy 309.154056 -300.317028) (xy 309.134765 -300.271752)
			(xy 309.122988 -300.223968) (xy 309.119028 -300.174914) (xy 308.78018 -300.174914) (xy 308.779685 -300.199521)
			(xy 308.77179 -300.248098) (xy 308.756206 -300.294779) (xy 308.733335 -300.338356) (xy 308.70377 -300.3777)
			(xy 308.668277 -300.411792) (xy 308.627774 -300.439748) (xy 308.583312 -300.460846) (xy 308.536041 -300.474538)
			(xy 308.487186 -300.48047) (xy 308.438011 -300.478489) (xy 308.389792 -300.468645) (xy 308.343776 -300.451193)
			(xy 308.301155 -300.426586) (xy 308.263034 -300.395461) (xy 308.230399 -300.358624) (xy 308.204096 -300.317028)
			(xy 308.184805 -300.271752) (xy 308.173028 -300.223968) (xy 308.169068 -300.174914) (xy 307.83022 -300.174914)
			(xy 307.829725 -300.199521) (xy 307.82183 -300.248098) (xy 307.806246 -300.294779) (xy 307.783375 -300.338356)
			(xy 307.75381 -300.3777) (xy 307.718317 -300.411792) (xy 307.677814 -300.439748) (xy 307.633352 -300.460846)
			(xy 307.586081 -300.474538) (xy 307.537226 -300.48047) (xy 307.488051 -300.478489) (xy 307.439832 -300.468645)
			(xy 307.393816 -300.451193) (xy 307.351195 -300.426586) (xy 307.313074 -300.395461) (xy 307.280439 -300.358624)
			(xy 307.254136 -300.317028) (xy 307.234845 -300.271752) (xy 307.223068 -300.223968) (xy 307.219108 -300.174914)
			(xy 306.880006 -300.174914) (xy 306.879511 -300.199521) (xy 306.871616 -300.248098) (xy 306.856032 -300.294779)
			(xy 306.833161 -300.338356) (xy 306.803596 -300.3777) (xy 306.768103 -300.411792) (xy 306.7276 -300.439748)
			(xy 306.683138 -300.460846) (xy 306.635867 -300.474538) (xy 306.587012 -300.48047) (xy 306.537837 -300.478489)
			(xy 306.489618 -300.468645) (xy 306.443602 -300.451193) (xy 306.400981 -300.426586) (xy 306.36286 -300.395461)
			(xy 306.330225 -300.358624) (xy 306.303922 -300.317028) (xy 306.284631 -300.271752) (xy 306.272854 -300.223968)
			(xy 306.268894 -300.174914) (xy 305.930046 -300.174914) (xy 305.929551 -300.199521) (xy 305.921656 -300.248098)
			(xy 305.906072 -300.294779) (xy 305.883201 -300.338356) (xy 305.853636 -300.3777) (xy 305.818143 -300.411792)
			(xy 305.77764 -300.439748) (xy 305.733178 -300.460846) (xy 305.685907 -300.474538) (xy 305.637052 -300.48047)
			(xy 305.587877 -300.478489) (xy 305.539658 -300.468645) (xy 305.493642 -300.451193) (xy 305.451021 -300.426586)
			(xy 305.4129 -300.395461) (xy 305.380265 -300.358624) (xy 305.353962 -300.317028) (xy 305.334671 -300.271752)
			(xy 305.322894 -300.223968) (xy 305.318934 -300.174914) (xy 304.980086 -300.174914) (xy 304.979591 -300.199521)
			(xy 304.971696 -300.248098) (xy 304.956112 -300.294779) (xy 304.933241 -300.338356) (xy 304.903676 -300.3777)
			(xy 304.868183 -300.411792) (xy 304.82768 -300.439748) (xy 304.783218 -300.460846) (xy 304.735947 -300.474538)
			(xy 304.687092 -300.48047) (xy 304.637917 -300.478489) (xy 304.589698 -300.468645) (xy 304.543682 -300.451193)
			(xy 304.501061 -300.426586) (xy 304.46294 -300.395461) (xy 304.430305 -300.358624) (xy 304.404002 -300.317028)
			(xy 304.384711 -300.271752) (xy 304.372934 -300.223968) (xy 304.368974 -300.174914) (xy 304.030126 -300.174914)
			(xy 304.029631 -300.199521) (xy 304.021736 -300.248098) (xy 304.006152 -300.294779) (xy 303.983281 -300.338356)
			(xy 303.953716 -300.3777) (xy 303.918223 -300.411792) (xy 303.87772 -300.439748) (xy 303.833258 -300.460846)
			(xy 303.785987 -300.474538) (xy 303.737132 -300.48047) (xy 303.687957 -300.478489) (xy 303.639738 -300.468645)
			(xy 303.593722 -300.451193) (xy 303.551101 -300.426586) (xy 303.51298 -300.395461) (xy 303.480345 -300.358624)
			(xy 303.454042 -300.317028) (xy 303.434751 -300.271752) (xy 303.422974 -300.223968) (xy 303.419014 -300.174914)
			(xy 303.080166 -300.174914) (xy 303.079671 -300.199521) (xy 303.071776 -300.248098) (xy 303.056192 -300.294779)
			(xy 303.033321 -300.338356) (xy 303.003756 -300.3777) (xy 302.968263 -300.411792) (xy 302.92776 -300.439748)
			(xy 302.883298 -300.460846) (xy 302.836027 -300.474538) (xy 302.787172 -300.48047) (xy 302.737997 -300.478489)
			(xy 302.689778 -300.468645) (xy 302.643762 -300.451193) (xy 302.601141 -300.426586) (xy 302.56302 -300.395461)
			(xy 302.530385 -300.358624) (xy 302.504082 -300.317028) (xy 302.484791 -300.271752) (xy 302.473014 -300.223968)
			(xy 302.469054 -300.174914) (xy 302.130206 -300.174914) (xy 302.129711 -300.199521) (xy 302.121816 -300.248098)
			(xy 302.106232 -300.294779) (xy 302.083361 -300.338356) (xy 302.053796 -300.3777) (xy 302.018303 -300.411792)
			(xy 301.9778 -300.439748) (xy 301.933338 -300.460846) (xy 301.886067 -300.474538) (xy 301.837212 -300.48047)
			(xy 301.788037 -300.478489) (xy 301.739818 -300.468645) (xy 301.693802 -300.451193) (xy 301.651181 -300.426586)
			(xy 301.61306 -300.395461) (xy 301.580425 -300.358624) (xy 301.554122 -300.317028) (xy 301.534831 -300.271752)
			(xy 301.523054 -300.223968) (xy 301.519094 -300.174914) (xy 301.179992 -300.174914) (xy 301.179497 -300.199521)
			(xy 301.171602 -300.248098) (xy 301.156018 -300.294779) (xy 301.133147 -300.338356) (xy 301.103582 -300.3777)
			(xy 301.068089 -300.411792) (xy 301.027586 -300.439748) (xy 300.983124 -300.460846) (xy 300.935853 -300.474538)
			(xy 300.886998 -300.48047) (xy 300.837823 -300.478489) (xy 300.789604 -300.468645) (xy 300.743588 -300.451193)
			(xy 300.700967 -300.426586) (xy 300.662846 -300.395461) (xy 300.630211 -300.358624) (xy 300.603908 -300.317028)
			(xy 300.584617 -300.271752) (xy 300.57284 -300.223968) (xy 300.56888 -300.174914) (xy 300.230032 -300.174914)
			(xy 300.229537 -300.199521) (xy 300.221642 -300.248098) (xy 300.206058 -300.294779) (xy 300.183187 -300.338356)
			(xy 300.153622 -300.3777) (xy 300.118129 -300.411792) (xy 300.077626 -300.439748) (xy 300.033164 -300.460846)
			(xy 299.985893 -300.474538) (xy 299.937038 -300.48047) (xy 299.887863 -300.478489) (xy 299.839644 -300.468645)
			(xy 299.793628 -300.451193) (xy 299.751007 -300.426586) (xy 299.712886 -300.395461) (xy 299.680251 -300.358624)
			(xy 299.653948 -300.317028) (xy 299.634657 -300.271752) (xy 299.62288 -300.223968) (xy 299.61892 -300.174914)
			(xy 299.280072 -300.174914) (xy 299.279577 -300.199521) (xy 299.271682 -300.248098) (xy 299.256098 -300.294779)
			(xy 299.233227 -300.338356) (xy 299.203662 -300.3777) (xy 299.168169 -300.411792) (xy 299.127666 -300.439748)
			(xy 299.083204 -300.460846) (xy 299.035933 -300.474538) (xy 298.987078 -300.48047) (xy 298.937903 -300.478489)
			(xy 298.889684 -300.468645) (xy 298.843668 -300.451193) (xy 298.801047 -300.426586) (xy 298.762926 -300.395461)
			(xy 298.730291 -300.358624) (xy 298.703988 -300.317028) (xy 298.684697 -300.271752) (xy 298.67292 -300.223968)
			(xy 298.66896 -300.174914) (xy 298.330112 -300.174914) (xy 298.329617 -300.199521) (xy 298.321722 -300.248098)
			(xy 298.306138 -300.294779) (xy 298.283267 -300.338356) (xy 298.253702 -300.3777) (xy 298.218209 -300.411792)
			(xy 298.177706 -300.439748) (xy 298.133244 -300.460846) (xy 298.085973 -300.474538) (xy 298.037118 -300.48047)
			(xy 297.987943 -300.478489) (xy 297.939724 -300.468645) (xy 297.893708 -300.451193) (xy 297.851087 -300.426586)
			(xy 297.812966 -300.395461) (xy 297.780331 -300.358624) (xy 297.754028 -300.317028) (xy 297.734737 -300.271752)
			(xy 297.72296 -300.223968) (xy 297.719 -300.174914) (xy 297.380152 -300.174914) (xy 297.379657 -300.199521)
			(xy 297.371762 -300.248098) (xy 297.356178 -300.294779) (xy 297.333307 -300.338356) (xy 297.303742 -300.3777)
			(xy 297.268249 -300.411792) (xy 297.227746 -300.439748) (xy 297.183284 -300.460846) (xy 297.136013 -300.474538)
			(xy 297.087158 -300.48047) (xy 297.037983 -300.478489) (xy 296.989764 -300.468645) (xy 296.943748 -300.451193)
			(xy 296.901127 -300.426586) (xy 296.863006 -300.395461) (xy 296.830371 -300.358624) (xy 296.804068 -300.317028)
			(xy 296.784777 -300.271752) (xy 296.773 -300.223968) (xy 296.76904 -300.174914) (xy 296.430192 -300.174914)
			(xy 296.429697 -300.199521) (xy 296.421802 -300.248098) (xy 296.406218 -300.294779) (xy 296.383347 -300.338356)
			(xy 296.353782 -300.3777) (xy 296.318289 -300.411792) (xy 296.277786 -300.439748) (xy 296.233324 -300.460846)
			(xy 296.186053 -300.474538) (xy 296.137198 -300.48047) (xy 296.088023 -300.478489) (xy 296.039804 -300.468645)
			(xy 295.993788 -300.451193) (xy 295.951167 -300.426586) (xy 295.913046 -300.395461) (xy 295.880411 -300.358624)
			(xy 295.854108 -300.317028) (xy 295.834817 -300.271752) (xy 295.82304 -300.223968) (xy 295.81908 -300.174914)
			(xy 295.480232 -300.174914) (xy 295.479737 -300.199521) (xy 295.471842 -300.248098) (xy 295.456258 -300.294779)
			(xy 295.433387 -300.338356) (xy 295.403822 -300.3777) (xy 295.368329 -300.411792) (xy 295.327826 -300.439748)
			(xy 295.283364 -300.460846) (xy 295.236093 -300.474538) (xy 295.187238 -300.48047) (xy 295.138063 -300.478489)
			(xy 295.089844 -300.468645) (xy 295.043828 -300.451193) (xy 295.001207 -300.426586) (xy 294.963086 -300.395461)
			(xy 294.930451 -300.358624) (xy 294.904148 -300.317028) (xy 294.884857 -300.271752) (xy 294.87308 -300.223968)
			(xy 294.86912 -300.174914) (xy 294.530018 -300.174914) (xy 294.529523 -300.199521) (xy 294.521628 -300.248098)
			(xy 294.506044 -300.294779) (xy 294.483173 -300.338356) (xy 294.453608 -300.3777) (xy 294.418115 -300.411792)
			(xy 294.377612 -300.439748) (xy 294.33315 -300.460846) (xy 294.285879 -300.474538) (xy 294.237024 -300.48047)
			(xy 294.187849 -300.478489) (xy 294.13963 -300.468645) (xy 294.093614 -300.451193) (xy 294.050993 -300.426586)
			(xy 294.012872 -300.395461) (xy 293.980237 -300.358624) (xy 293.953934 -300.317028) (xy 293.934643 -300.271752)
			(xy 293.922866 -300.223968) (xy 293.918906 -300.174914) (xy 293.580058 -300.174914) (xy 293.579563 -300.199521)
			(xy 293.571668 -300.248098) (xy 293.556084 -300.294779) (xy 293.533213 -300.338356) (xy 293.503648 -300.3777)
			(xy 293.468155 -300.411792) (xy 293.427652 -300.439748) (xy 293.38319 -300.460846) (xy 293.335919 -300.474538)
			(xy 293.287064 -300.48047) (xy 293.237889 -300.478489) (xy 293.18967 -300.468645) (xy 293.143654 -300.451193)
			(xy 293.101033 -300.426586) (xy 293.062912 -300.395461) (xy 293.030277 -300.358624) (xy 293.003974 -300.317028)
			(xy 292.984683 -300.271752) (xy 292.972906 -300.223968) (xy 292.968946 -300.174914) (xy 292.630098 -300.174914)
			(xy 292.629603 -300.199521) (xy 292.621708 -300.248098) (xy 292.606124 -300.294779) (xy 292.583253 -300.338356)
			(xy 292.553688 -300.3777) (xy 292.518195 -300.411792) (xy 292.477692 -300.439748) (xy 292.43323 -300.460846)
			(xy 292.385959 -300.474538) (xy 292.337104 -300.48047) (xy 292.287929 -300.478489) (xy 292.23971 -300.468645)
			(xy 292.193694 -300.451193) (xy 292.151073 -300.426586) (xy 292.112952 -300.395461) (xy 292.080317 -300.358624)
			(xy 292.054014 -300.317028) (xy 292.034723 -300.271752) (xy 292.022946 -300.223968) (xy 292.018986 -300.174914)
			(xy 290.730178 -300.174914) (xy 290.729683 -300.199521) (xy 290.721788 -300.248098) (xy 290.706204 -300.294779)
			(xy 290.683333 -300.338356) (xy 290.653768 -300.3777) (xy 290.618275 -300.411792) (xy 290.577772 -300.439748)
			(xy 290.53331 -300.460846) (xy 290.486039 -300.474538) (xy 290.437184 -300.48047) (xy 290.388009 -300.478489)
			(xy 290.33979 -300.468645) (xy 290.293774 -300.451193) (xy 290.251153 -300.426586) (xy 290.213032 -300.395461)
			(xy 290.180397 -300.358624) (xy 290.154094 -300.317028) (xy 290.134803 -300.271752) (xy 290.123026 -300.223968)
			(xy 290.119066 -300.174914) (xy 289.780218 -300.174914) (xy 289.779723 -300.199521) (xy 289.771828 -300.248098)
			(xy 289.756244 -300.294779) (xy 289.733373 -300.338356) (xy 289.703808 -300.3777) (xy 289.668315 -300.411792)
			(xy 289.627812 -300.439748) (xy 289.58335 -300.460846) (xy 289.536079 -300.474538) (xy 289.487224 -300.48047)
			(xy 289.438049 -300.478489) (xy 289.38983 -300.468645) (xy 289.343814 -300.451193) (xy 289.301193 -300.426586)
			(xy 289.263072 -300.395461) (xy 289.230437 -300.358624) (xy 289.204134 -300.317028) (xy 289.184843 -300.271752)
			(xy 289.173066 -300.223968) (xy 289.169106 -300.174914) (xy 288.830004 -300.174914) (xy 288.829509 -300.199521)
			(xy 288.821614 -300.248098) (xy 288.80603 -300.294779) (xy 288.783159 -300.338356) (xy 288.753594 -300.3777)
			(xy 288.718101 -300.411792) (xy 288.677598 -300.439748) (xy 288.633136 -300.460846) (xy 288.585865 -300.474538)
			(xy 288.53701 -300.48047) (xy 288.487835 -300.478489) (xy 288.439616 -300.468645) (xy 288.3936 -300.451193)
			(xy 288.350979 -300.426586) (xy 288.312858 -300.395461) (xy 288.280223 -300.358624) (xy 288.25392 -300.317028)
			(xy 288.234629 -300.271752) (xy 288.222852 -300.223968) (xy 288.218892 -300.174914) (xy 287.880044 -300.174914)
			(xy 287.879549 -300.199521) (xy 287.871654 -300.248098) (xy 287.85607 -300.294779) (xy 287.833199 -300.338356)
			(xy 287.803634 -300.3777) (xy 287.768141 -300.411792) (xy 287.727638 -300.439748) (xy 287.683176 -300.460846)
			(xy 287.635905 -300.474538) (xy 287.58705 -300.48047) (xy 287.537875 -300.478489) (xy 287.489656 -300.468645)
			(xy 287.44364 -300.451193) (xy 287.401019 -300.426586) (xy 287.362898 -300.395461) (xy 287.330263 -300.358624)
			(xy 287.30396 -300.317028) (xy 287.284669 -300.271752) (xy 287.272892 -300.223968) (xy 287.268932 -300.174914)
			(xy 286.930084 -300.174914) (xy 286.929589 -300.199521) (xy 286.921694 -300.248098) (xy 286.90611 -300.294779)
			(xy 286.883239 -300.338356) (xy 286.853674 -300.3777) (xy 286.818181 -300.411792) (xy 286.777678 -300.439748)
			(xy 286.733216 -300.460846) (xy 286.685945 -300.474538) (xy 286.63709 -300.48047) (xy 286.587915 -300.478489)
			(xy 286.539696 -300.468645) (xy 286.49368 -300.451193) (xy 286.451059 -300.426586) (xy 286.412938 -300.395461)
			(xy 286.380303 -300.358624) (xy 286.354 -300.317028) (xy 286.334709 -300.271752) (xy 286.322932 -300.223968)
			(xy 286.318972 -300.174914) (xy 285.980124 -300.174914) (xy 285.979629 -300.199521) (xy 285.971734 -300.248098)
			(xy 285.95615 -300.294779) (xy 285.933279 -300.338356) (xy 285.903714 -300.3777) (xy 285.868221 -300.411792)
			(xy 285.827718 -300.439748) (xy 285.783256 -300.460846) (xy 285.735985 -300.474538) (xy 285.68713 -300.48047)
			(xy 285.637955 -300.478489) (xy 285.589736 -300.468645) (xy 285.54372 -300.451193) (xy 285.501099 -300.426586)
			(xy 285.462978 -300.395461) (xy 285.430343 -300.358624) (xy 285.40404 -300.317028) (xy 285.384749 -300.271752)
			(xy 285.372972 -300.223968) (xy 285.369012 -300.174914) (xy 285.030164 -300.174914) (xy 285.029669 -300.199521)
			(xy 285.021774 -300.248098) (xy 285.00619 -300.294779) (xy 284.983319 -300.338356) (xy 284.953754 -300.3777)
			(xy 284.918261 -300.411792) (xy 284.877758 -300.439748) (xy 284.833296 -300.460846) (xy 284.786025 -300.474538)
			(xy 284.73717 -300.48047) (xy 284.687995 -300.478489) (xy 284.639776 -300.468645) (xy 284.59376 -300.451193)
			(xy 284.551139 -300.426586) (xy 284.513018 -300.395461) (xy 284.480383 -300.358624) (xy 284.45408 -300.317028)
			(xy 284.434789 -300.271752) (xy 284.423012 -300.223968) (xy 284.419052 -300.174914) (xy 284.080204 -300.174914)
			(xy 284.079709 -300.199521) (xy 284.071814 -300.248098) (xy 284.05623 -300.294779) (xy 284.033359 -300.338356)
			(xy 284.003794 -300.3777) (xy 283.968301 -300.411792) (xy 283.927798 -300.439748) (xy 283.883336 -300.460846)
			(xy 283.836065 -300.474538) (xy 283.78721 -300.48047) (xy 283.738035 -300.478489) (xy 283.689816 -300.468645)
			(xy 283.6438 -300.451193) (xy 283.601179 -300.426586) (xy 283.563058 -300.395461) (xy 283.530423 -300.358624)
			(xy 283.50412 -300.317028) (xy 283.484829 -300.271752) (xy 283.473052 -300.223968) (xy 283.469092 -300.174914)
			(xy 283.130244 -300.174914) (xy 283.129749 -300.199521) (xy 283.121854 -300.248098) (xy 283.10627 -300.294779)
			(xy 283.083399 -300.338356) (xy 283.053834 -300.3777) (xy 283.018341 -300.411792) (xy 282.977838 -300.439748)
			(xy 282.933376 -300.460846) (xy 282.886105 -300.474538) (xy 282.83725 -300.48047) (xy 282.788075 -300.478489)
			(xy 282.739856 -300.468645) (xy 282.69384 -300.451193) (xy 282.651219 -300.426586) (xy 282.613098 -300.395461)
			(xy 282.580463 -300.358624) (xy 282.55416 -300.317028) (xy 282.534869 -300.271752) (xy 282.523092 -300.223968)
			(xy 282.519132 -300.174914) (xy 282.18003 -300.174914) (xy 282.179535 -300.199521) (xy 282.17164 -300.248098)
			(xy 282.156056 -300.294779) (xy 282.133185 -300.338356) (xy 282.10362 -300.3777) (xy 282.068127 -300.411792)
			(xy 282.027624 -300.439748) (xy 281.983162 -300.460846) (xy 281.935891 -300.474538) (xy 281.887036 -300.48047)
			(xy 281.837861 -300.478489) (xy 281.789642 -300.468645) (xy 281.743626 -300.451193) (xy 281.701005 -300.426586)
			(xy 281.662884 -300.395461) (xy 281.630249 -300.358624) (xy 281.603946 -300.317028) (xy 281.584655 -300.271752)
			(xy 281.572878 -300.223968) (xy 281.568918 -300.174914) (xy 281.23007 -300.174914) (xy 281.229575 -300.199521)
			(xy 281.22168 -300.248098) (xy 281.206096 -300.294779) (xy 281.183225 -300.338356) (xy 281.15366 -300.3777)
			(xy 281.118167 -300.411792) (xy 281.077664 -300.439748) (xy 281.033202 -300.460846) (xy 280.985931 -300.474538)
			(xy 280.937076 -300.48047) (xy 280.887901 -300.478489) (xy 280.839682 -300.468645) (xy 280.793666 -300.451193)
			(xy 280.751045 -300.426586) (xy 280.712924 -300.395461) (xy 280.680289 -300.358624) (xy 280.653986 -300.317028)
			(xy 280.634695 -300.271752) (xy 280.622918 -300.223968) (xy 280.618958 -300.174914) (xy 280.28011 -300.174914)
			(xy 280.279615 -300.199521) (xy 280.27172 -300.248098) (xy 280.256136 -300.294779) (xy 280.233265 -300.338356)
			(xy 280.2037 -300.3777) (xy 280.168207 -300.411792) (xy 280.127704 -300.439748) (xy 280.083242 -300.460846)
			(xy 280.035971 -300.474538) (xy 279.987116 -300.48047) (xy 279.937941 -300.478489) (xy 279.889722 -300.468645)
			(xy 279.843706 -300.451193) (xy 279.801085 -300.426586) (xy 279.762964 -300.395461) (xy 279.730329 -300.358624)
			(xy 279.704026 -300.317028) (xy 279.684735 -300.271752) (xy 279.672958 -300.223968) (xy 279.668998 -300.174914)
			(xy 278.38019 -300.174914) (xy 278.379695 -300.199521) (xy 278.3718 -300.248098) (xy 278.356216 -300.294779)
			(xy 278.333345 -300.338356) (xy 278.30378 -300.3777) (xy 278.268287 -300.411792) (xy 278.227784 -300.439748)
			(xy 278.183322 -300.460846) (xy 278.136051 -300.474538) (xy 278.087196 -300.48047) (xy 278.038021 -300.478489)
			(xy 277.989802 -300.468645) (xy 277.943786 -300.451193) (xy 277.901165 -300.426586) (xy 277.863044 -300.395461)
			(xy 277.830409 -300.358624) (xy 277.804106 -300.317028) (xy 277.784815 -300.271752) (xy 277.773038 -300.223968)
			(xy 277.769078 -300.174914) (xy 277.43023 -300.174914) (xy 277.429735 -300.199521) (xy 277.42184 -300.248098)
			(xy 277.406256 -300.294779) (xy 277.383385 -300.338356) (xy 277.35382 -300.3777) (xy 277.318327 -300.411792)
			(xy 277.277824 -300.439748) (xy 277.233362 -300.460846) (xy 277.186091 -300.474538) (xy 277.137236 -300.48047)
			(xy 277.088061 -300.478489) (xy 277.039842 -300.468645) (xy 276.993826 -300.451193) (xy 276.951205 -300.426586)
			(xy 276.913084 -300.395461) (xy 276.880449 -300.358624) (xy 276.854146 -300.317028) (xy 276.834855 -300.271752)
			(xy 276.823078 -300.223968) (xy 276.819118 -300.174914) (xy 276.479985 -300.174914) (xy 276.480433 -300.183172)
			(xy 276.475067 -300.232525) (xy 276.461788 -300.280361) (xy 276.440944 -300.325417) (xy 276.413085 -300.366508)
			(xy 276.378946 -300.40255) (xy 276.339426 -300.432595) (xy 276.295565 -300.45585) (xy 276.24852 -300.471703)
			(xy 276.19953 -300.479735) (xy 276.174708 -300.480222) (xy 276.160525 -300.480044) (xy 276.132285 -300.477373)
			(xy 276.11832 -300.474888) (xy 276.105874 -300.472602) (xy 276.082252 -300.479968) (xy 276.004782 -300.557438)
			(xy 275.997416 -300.58106) (xy 275.999702 -300.593506) (xy 276.002175 -300.607472) (xy 276.004849 -300.635712)
			(xy 276.005036 -300.649894) (xy 276.004514 -300.675149) (xy 275.996201 -300.724971) (xy 275.9798 -300.772745)
			(xy 275.955759 -300.817168) (xy 275.924735 -300.857028) (xy 275.887573 -300.891238) (xy 275.845287 -300.918864)
			(xy 275.799031 -300.939154) (xy 275.750066 -300.951554) (xy 275.699728 -300.955725) (xy 275.64939 -300.951554)
			(xy 275.600425 -300.939154) (xy 275.554169 -300.918864) (xy 275.511883 -300.891238) (xy 275.474721 -300.857028)
			(xy 275.443697 -300.817168) (xy 275.419656 -300.772745) (xy 275.403255 -300.724971) (xy 275.394942 -300.675149)
			(xy 275.39442 -300.649894) (xy 275.394595 -300.635711) (xy 275.397268 -300.607471) (xy 275.399754 -300.593506)
			(xy 275.40204 -300.58106) (xy 275.394674 -300.557438) (xy 275.317204 -300.479968) (xy 275.293582 -300.472602)
			(xy 275.281136 -300.474888) (xy 275.267171 -300.477369) (xy 275.238931 -300.480038) (xy 275.224748 -300.480222)
			(xy 275.210565 -300.480038) (xy 275.182325 -300.477371) (xy 275.16836 -300.474888) (xy 275.155914 -300.472602)
			(xy 275.132292 -300.479968) (xy 275.054822 -300.557438) (xy 275.047456 -300.58106) (xy 275.049742 -300.593506)
			(xy 275.052215 -300.607472) (xy 275.054889 -300.635712) (xy 275.055076 -300.649894) (xy 275.054629 -300.674715)
			(xy 275.046599 -300.723703) (xy 275.030749 -300.770747) (xy 275.007498 -300.814606) (xy 274.977457 -300.854127)
			(xy 274.941418 -300.888267) (xy 274.900332 -300.916126) (xy 274.855279 -300.936972) (xy 274.807447 -300.950255)
			(xy 274.758096 -300.955624) (xy 274.708527 -300.952939) (xy 274.660046 -300.94227) (xy 274.613928 -300.923899)
			(xy 274.571391 -300.898308) (xy 274.533554 -300.866173) (xy 274.501414 -300.82834) (xy 274.475818 -300.785806)
			(xy 274.457441 -300.739691) (xy 274.446766 -300.69121) (xy 274.444075 -300.641642) (xy 274.449438 -300.59229)
			(xy 274.462715 -300.544457) (xy 274.483555 -300.499402) (xy 274.51141 -300.458311) (xy 274.545545 -300.422268)
			(xy 274.585062 -300.392223) (xy 274.628919 -300.368966) (xy 274.67596 -300.353111) (xy 274.724947 -300.345074)
			(xy 274.749768 -300.344586) (xy 274.763951 -300.344767) (xy 274.792191 -300.347436) (xy 274.806156 -300.34992)
			(xy 274.818602 -300.352206) (xy 274.842224 -300.34484) (xy 274.919694 -300.26737) (xy 274.92706 -300.243748)
			(xy 274.924774 -300.231302) (xy 274.922301 -300.217335) (xy 274.919627 -300.189096) (xy 274.91944 -300.174914)
			(xy 274.919618 -300.160731) (xy 274.922289 -300.132491) (xy 274.924774 -300.118526) (xy 274.92706 -300.10608)
			(xy 274.919694 -300.082458) (xy 274.842224 -300.004988) (xy 274.818602 -299.997622) (xy 274.806156 -299.999908)
			(xy 274.79219 -300.002387) (xy 274.763951 -300.005057) (xy 274.749768 -300.005242) (xy 274.725778 -300.004767)
			(xy 274.678388 -299.997257) (xy 274.632756 -299.982428) (xy 274.590006 -299.960643) (xy 274.551189 -299.93244)
			(xy 274.517262 -299.898512) (xy 274.489058 -299.859696) (xy 274.467273 -299.816945) (xy 274.452443 -299.771314)
			(xy 274.444933 -299.723924) (xy 274.44446 -299.699934) (xy 274.444619 -299.685687) (xy 274.447293 -299.657319)
			(xy 274.449794 -299.643292) (xy 274.45208 -299.6311) (xy 274.444714 -299.60697) (xy 274.367498 -299.529754)
			(xy 274.343622 -299.522388) (xy 274.331176 -299.524674) (xy 274.31721 -299.52715) (xy 274.28897 -299.529822)
			(xy 274.274788 -299.530008) (xy 274.249968 -299.529509) (xy 274.200983 -299.521477) (xy 274.153943 -299.505625)
			(xy 274.110087 -299.482372) (xy 274.07057 -299.45233) (xy 274.036434 -299.416291) (xy 274.008579 -299.375204)
			(xy 273.987737 -299.330152) (xy 273.974459 -299.282322) (xy 273.969093 -299.232973) (xy 273.629975 -299.232973)
			(xy 273.629641 -299.249561) (xy 273.621746 -299.298138) (xy 273.606162 -299.344819) (xy 273.583291 -299.388396)
			(xy 273.553726 -299.42774) (xy 273.518233 -299.461832) (xy 273.47773 -299.489788) (xy 273.433268 -299.510886)
			(xy 273.385997 -299.524578) (xy 273.337142 -299.53051) (xy 273.287967 -299.528529) (xy 273.239748 -299.518685)
			(xy 273.193732 -299.501233) (xy 273.151111 -299.476626) (xy 273.11299 -299.445501) (xy 273.080355 -299.408664)
			(xy 273.054052 -299.367068) (xy 273.034761 -299.321792) (xy 273.022984 -299.274008) (xy 273.019024 -299.224954)
			(xy 272.705333 -299.224954) (xy 272.705333 -299.251007) (xy 272.697195 -299.302381) (xy 272.681121 -299.35185)
			(xy 272.657506 -299.398194) (xy 272.626931 -299.440273) (xy 272.590149 -299.477051) (xy 272.548067 -299.507622)
			(xy 272.50172 -299.531233) (xy 272.45225 -299.547303) (xy 272.400875 -299.555435) (xy 272.374868 -299.555916)
			(xy 271.424908 -299.555916) (xy 271.398895 -299.555525) (xy 271.347509 -299.547387) (xy 271.298028 -299.531311)
			(xy 271.251672 -299.507693) (xy 271.209581 -299.477113) (xy 271.172792 -299.440325) (xy 271.142212 -299.398235)
			(xy 271.118592 -299.351879) (xy 271.102514 -299.302399) (xy 271.094376 -299.251013) (xy 270.779271 -299.251013)
			(xy 270.771612 -299.298138) (xy 270.756028 -299.344819) (xy 270.733157 -299.388396) (xy 270.703592 -299.42774)
			(xy 270.668099 -299.461832) (xy 270.627596 -299.489788) (xy 270.583134 -299.510886) (xy 270.535863 -299.524578)
			(xy 270.487008 -299.53051) (xy 270.437833 -299.528529) (xy 270.389614 -299.518685) (xy 270.343598 -299.501233)
			(xy 270.300977 -299.476626) (xy 270.262856 -299.445501) (xy 270.230221 -299.408664) (xy 270.203918 -299.367068)
			(xy 270.184627 -299.321792) (xy 270.17285 -299.274008) (xy 270.16889 -299.224954) (xy 269.854933 -299.224954)
			(xy 269.854933 -299.251007) (xy 269.846796 -299.302379) (xy 269.830722 -299.351847) (xy 269.807108 -299.39819)
			(xy 269.776534 -299.440269) (xy 269.739754 -299.477047) (xy 269.697673 -299.507618) (xy 269.651328 -299.53123)
			(xy 269.60186 -299.5473) (xy 269.550487 -299.555434) (xy 269.52448 -299.555916) (xy 268.57452 -299.555916)
			(xy 268.550136 -299.555482) (xy 268.501899 -299.548309) (xy 268.455238 -299.534129) (xy 268.411165 -299.513251)
			(xy 268.370636 -299.486128) (xy 268.334529 -299.453346) (xy 268.318742 -299.434758) (xy 268.31163 -299.426122)
			(xy 268.292072 -299.41647) (xy 268.192758 -299.41393) (xy 268.172692 -299.422312) (xy 268.165072 -299.430694)
			(xy 268.147587 -299.44907) (xy 268.107657 -299.480344) (xy 268.063104 -299.504585) (xy 268.015157 -299.521125)
			(xy 267.965134 -299.529508) (xy 267.939774 -299.530008) (xy 267.91452 -299.529484) (xy 267.864702 -299.521167)
			(xy 267.816932 -299.504764) (xy 267.772513 -299.480722) (xy 267.732656 -299.449698) (xy 267.69845 -299.412537)
			(xy 267.670826 -299.370252) (xy 267.650538 -299.323998) (xy 267.63814 -299.275035) (xy 267.633969 -299.2247)
			(xy 264.301649 -299.2247) (xy 264.285005 -299.276959) (xy 264.258791 -299.329554) (xy 264.224818 -299.377505)
			(xy 264.183891 -299.419676) (xy 264.160762 -299.437806) (xy 264.151364 -299.445172) (xy 264.14095 -299.465746)
			(xy 264.139426 -299.569632) (xy 264.149332 -299.590714) (xy 264.158476 -299.59808) (xy 264.180292 -299.616323)
			(xy 264.218835 -299.658133) (xy 264.250747 -299.705201) (xy 264.275319 -299.756484) (xy 264.292009 -299.810845)
			(xy 264.300447 -299.867081) (xy 264.30097 -299.895514) (xy 264.934444 -299.895514) (xy 264.938515 -299.839892)
			(xy 264.950641 -299.785455) (xy 264.970564 -299.733364) (xy 264.99786 -299.684729) (xy 265.031946 -299.640586)
			(xy 265.072095 -299.601877) (xy 265.117453 -299.569426) (xy 265.167053 -299.543925) (xy 265.219837 -299.525918)
			(xy 265.27468 -299.515788) (xy 265.330414 -299.513751) (xy 265.385851 -299.519851) (xy 265.439808 -299.533957)
			(xy 265.491137 -299.555769) (xy 265.538743 -299.584823) (xy 265.581611 -299.620498) (xy 265.618828 -299.662035)
			(xy 265.649601 -299.708548) (xy 265.673273 -299.759045) (xy 265.689341 -299.812452) (xy 265.697461 -299.867628)
			(xy 265.69797 -299.895514) (xy 265.820904 -299.895514) (xy 265.824975 -299.839892) (xy 265.837101 -299.785455)
			(xy 265.857024 -299.733364) (xy 265.88432 -299.684729) (xy 265.918406 -299.640586) (xy 265.958555 -299.601877)
			(xy 266.003913 -299.569426) (xy 266.053513 -299.543925) (xy 266.106297 -299.525918) (xy 266.16114 -299.515788)
			(xy 266.216874 -299.513751) (xy 266.272311 -299.519851) (xy 266.326268 -299.533957) (xy 266.377597 -299.555769)
			(xy 266.425203 -299.584823) (xy 266.468071 -299.620498) (xy 266.505288 -299.662035) (xy 266.536061 -299.708548)
			(xy 266.559733 -299.759045) (xy 266.575801 -299.812452) (xy 266.583921 -299.867628) (xy 266.58443 -299.895514)
			(xy 266.583921 -299.9234) (xy 266.575801 -299.978576) (xy 266.559733 -300.031983) (xy 266.536061 -300.08248)
			(xy 266.505288 -300.128993) (xy 266.468071 -300.17053) (xy 266.425203 -300.206205) (xy 266.377597 -300.235259)
			(xy 266.326268 -300.257071) (xy 266.272311 -300.271177) (xy 266.216874 -300.277277) (xy 266.16114 -300.27524)
			(xy 266.106297 -300.26511) (xy 266.053513 -300.247103) (xy 266.003913 -300.221602) (xy 265.958555 -300.189151)
			(xy 265.918406 -300.150442) (xy 265.88432 -300.106299) (xy 265.857024 -300.057664) (xy 265.837101 -300.005573)
			(xy 265.824975 -299.951136) (xy 265.820904 -299.895514) (xy 265.69797 -299.895514) (xy 265.697461 -299.9234)
			(xy 265.689341 -299.978576) (xy 265.673273 -300.031983) (xy 265.649601 -300.08248) (xy 265.618828 -300.128993)
			(xy 265.581611 -300.17053) (xy 265.538743 -300.206205) (xy 265.491137 -300.235259) (xy 265.439808 -300.257071)
			(xy 265.385851 -300.271177) (xy 265.330414 -300.277277) (xy 265.27468 -300.27524) (xy 265.219837 -300.26511)
			(xy 265.167053 -300.247103) (xy 265.117453 -300.221602) (xy 265.072095 -300.189151) (xy 265.031946 -300.150442)
			(xy 264.99786 -300.106299) (xy 264.970564 -300.057664) (xy 264.950641 -300.005573) (xy 264.938515 -299.951136)
			(xy 264.934444 -299.895514) (xy 264.30097 -299.895514) (xy 264.300484 -299.922765) (xy 264.292728 -299.976713)
			(xy 264.277373 -300.029008) (xy 264.254731 -300.078585) (xy 264.225265 -300.124435) (xy 264.189574 -300.165626)
			(xy 264.148383 -300.201317) (xy 264.102533 -300.230783) (xy 264.052956 -300.253425) (xy 264.000661 -300.26878)
			(xy 263.946713 -300.276536) (xy 263.892211 -300.276536) (xy 263.838263 -300.26878) (xy 263.785968 -300.253425)
			(xy 263.736391 -300.230783) (xy 263.690541 -300.201317) (xy 263.64935 -300.165626) (xy 263.613659 -300.124435)
			(xy 263.584193 -300.078585) (xy 263.561551 -300.029008) (xy 263.546196 -299.976713) (xy 263.53844 -299.922765)
			(xy 263.537954 -299.895514) (xy 254.594351 -299.895514) (xy 254.574214 -299.914004) (xy 254.447714 -300.019278)
			(xy 254.316239 -300.118268) (xy 254.1801 -300.210739) (xy 254.039621 -300.296473) (xy 253.895133 -300.375265)
			(xy 253.746981 -300.446929) (xy 253.595516 -300.511295) (xy 253.441096 -300.56821) (xy 253.284089 -300.617539)
			(xy 253.124866 -300.659165) (xy 252.963805 -300.69299) (xy 252.801288 -300.718933) (xy 252.637701 -300.736933)
			(xy 252.473432 -300.746947) (xy 252.308869 -300.74895) (xy 252.144405 -300.74294) (xy 251.980428 -300.728929)
			(xy 251.817328 -300.706951) (xy 251.655491 -300.677058) (xy 251.495301 -300.639322) (xy 251.337139 -300.59383)
			(xy 251.181379 -300.540693) (xy 251.028391 -300.480034) (xy 250.878538 -300.411999) (xy 250.732175 -300.336749)
			(xy 250.58965 -300.254461) (xy 250.451299 -300.165333) (xy 250.317453 -300.069574) (xy 250.188427 -299.967411)
			(xy 250.064529 -299.859088) (xy 249.946051 -299.744862) (xy 249.833275 -299.625002) (xy 249.726469 -299.499793)
			(xy 249.625885 -299.369533) (xy 249.531763 -299.234531) (xy 249.444325 -299.095105) (xy 249.36378 -298.951588)
			(xy 249.290317 -298.80432) (xy 249.224112 -298.653649) (xy 249.165321 -298.499934) (xy 249.114083 -298.343539)
			(xy 249.070521 -298.184835) (xy 249.034738 -298.024198) (xy 249.006818 -297.862009) (xy 248.986828 -297.698653)
			(xy 248.974815 -297.534518) (xy 248.970807 -297.369992) (xy 234.5309 -297.369992) (xy 234.5309 -301.031656)
			(xy 258.01142 -301.031656) (xy 258.015491 -300.976034) (xy 258.027617 -300.921597) (xy 258.04754 -300.869506)
			(xy 258.074836 -300.820871) (xy 258.108922 -300.776728) (xy 258.149071 -300.738019) (xy 258.194429 -300.705568)
			(xy 258.244029 -300.680067) (xy 258.296813 -300.66206) (xy 258.351656 -300.65193) (xy 258.40739 -300.649893)
			(xy 258.462827 -300.655993) (xy 258.516784 -300.670099) (xy 258.568113 -300.691911) (xy 258.615719 -300.720965)
			(xy 258.658587 -300.75664) (xy 258.695804 -300.798177) (xy 258.726577 -300.84469) (xy 258.750249 -300.895187)
			(xy 258.766317 -300.948594) (xy 258.767028 -300.953424) (xy 259.495288 -300.953424) (xy 259.499359 -300.897802)
			(xy 259.511485 -300.843365) (xy 259.531408 -300.791274) (xy 259.558704 -300.742639) (xy 259.59279 -300.698496)
			(xy 259.632939 -300.659787) (xy 259.678297 -300.627336) (xy 259.727897 -300.601835) (xy 259.780681 -300.583828)
			(xy 259.835524 -300.573698) (xy 259.891258 -300.571661) (xy 259.946695 -300.577761) (xy 260.000652 -300.591867)
			(xy 260.051981 -300.613679) (xy 260.097814 -300.641651) (xy 268.744074 -300.641651) (xy 268.749436 -300.5923)
			(xy 268.762711 -300.544467) (xy 268.783549 -300.499411) (xy 268.811402 -300.45832) (xy 268.845536 -300.422276)
			(xy 268.885051 -300.392229) (xy 268.928907 -300.368971) (xy 268.975947 -300.353114) (xy 269.024933 -300.345076)
			(xy 269.049754 -300.344586) (xy 269.063868 -300.34472) (xy 269.091979 -300.347267) (xy 269.105888 -300.349666)
			(xy 269.118588 -300.352206) (xy 269.14221 -300.34484) (xy 269.219426 -300.26737) (xy 269.226792 -300.243748)
			(xy 269.224506 -300.231302) (xy 269.222034 -300.217335) (xy 269.219359 -300.189096) (xy 269.219172 -300.174914)
			(xy 269.219694 -300.149659) (xy 269.228007 -300.099837) (xy 269.244408 -300.052063) (xy 269.268449 -300.00764)
			(xy 269.299473 -299.96778) (xy 269.336635 -299.93357) (xy 269.378921 -299.905944) (xy 269.425177 -299.885654)
			(xy 269.474142 -299.873254) (xy 269.52448 -299.869083) (xy 269.574818 -299.873254) (xy 269.623783 -299.885654)
			(xy 269.670039 -299.905944) (xy 269.712325 -299.93357) (xy 269.749487 -299.96778) (xy 269.780511 -300.00764)
			(xy 269.804552 -300.052063) (xy 269.820953 -300.099837) (xy 269.829266 -300.149659) (xy 269.829788 -300.174914)
			(xy 269.829614 -300.189097) (xy 269.82694 -300.217337) (xy 269.824454 -300.231302) (xy 269.822168 -300.243748)
			(xy 269.829534 -300.267624) (xy 269.90675 -300.34484) (xy 269.93088 -300.352206) (xy 269.943072 -300.34992)
			(xy 269.957102 -300.347441) (xy 269.985468 -300.344765) (xy 269.999714 -300.344586) (xy 270.013897 -300.344761)
			(xy 270.042137 -300.347434) (xy 270.056102 -300.34992) (xy 270.068548 -300.352206) (xy 270.09217 -300.34484)
			(xy 270.16964 -300.26737) (xy 270.177006 -300.243748) (xy 270.17472 -300.231302) (xy 270.172248 -300.217335)
			(xy 270.169573 -300.189096) (xy 270.169386 -300.174914) (xy 270.169908 -300.149659) (xy 270.178221 -300.099837)
			(xy 270.194622 -300.052063) (xy 270.218663 -300.00764) (xy 270.249687 -299.96778) (xy 270.286849 -299.93357)
			(xy 270.329135 -299.905944) (xy 270.375391 -299.885654) (xy 270.424356 -299.873254) (xy 270.474694 -299.869083)
			(xy 270.525032 -299.873254) (xy 270.573997 -299.885654) (xy 270.620253 -299.905944) (xy 270.662539 -299.93357)
			(xy 270.699701 -299.96778) (xy 270.730725 -300.00764) (xy 270.754766 -300.052063) (xy 270.771167 -300.099837)
			(xy 270.77948 -300.149659) (xy 270.780002 -300.174914) (xy 270.779827 -300.189097) (xy 270.777154 -300.217337)
			(xy 270.774668 -300.231302) (xy 270.772382 -300.243748) (xy 270.779748 -300.267624) (xy 270.856964 -300.34484)
			(xy 270.881094 -300.352206) (xy 270.893286 -300.34992) (xy 270.907315 -300.347439) (xy 270.935682 -300.344765)
			(xy 270.949928 -300.344586) (xy 270.964111 -300.344759) (xy 270.992351 -300.347433) (xy 271.006316 -300.34992)
			(xy 271.018762 -300.352206) (xy 271.042384 -300.34484) (xy 271.119854 -300.26737) (xy 271.12722 -300.243748)
			(xy 271.124934 -300.231302) (xy 271.122462 -300.217335) (xy 271.119787 -300.189096) (xy 271.1196 -300.174914)
			(xy 271.120122 -300.149659) (xy 271.128435 -300.099837) (xy 271.144836 -300.052063) (xy 271.168877 -300.00764)
			(xy 271.199901 -299.96778) (xy 271.237063 -299.93357) (xy 271.279349 -299.905944) (xy 271.325605 -299.885654)
			(xy 271.37457 -299.873254) (xy 271.424908 -299.869083) (xy 271.475246 -299.873254) (xy 271.524211 -299.885654)
			(xy 271.570467 -299.905944) (xy 271.612753 -299.93357) (xy 271.649915 -299.96778) (xy 271.680939 -300.00764)
			(xy 271.70498 -300.052063) (xy 271.721381 -300.099837) (xy 271.729694 -300.149659) (xy 271.730216 -300.174914)
			(xy 271.730041 -300.189097) (xy 271.727368 -300.217337) (xy 271.724882 -300.231302) (xy 271.722596 -300.243748)
			(xy 271.729962 -300.26737) (xy 271.807432 -300.34484) (xy 271.831054 -300.352206) (xy 271.8435 -300.34992)
			(xy 271.857467 -300.347448) (xy 271.885706 -300.344773) (xy 271.899888 -300.344586) (xy 271.914071 -300.344764)
			(xy 271.942311 -300.347435) (xy 271.956276 -300.34992) (xy 271.968722 -300.352206) (xy 271.992344 -300.34484)
			(xy 272.069814 -300.26737) (xy 272.07718 -300.243748) (xy 272.074894 -300.231302) (xy 272.072422 -300.217335)
			(xy 272.069747 -300.189096) (xy 272.06956 -300.174914) (xy 272.070082 -300.149659) (xy 272.078395 -300.099837)
			(xy 272.094796 -300.052063) (xy 272.118837 -300.00764) (xy 272.149861 -299.96778) (xy 272.187023 -299.93357)
			(xy 272.229309 -299.905944) (xy 272.275565 -299.885654) (xy 272.32453 -299.873254) (xy 272.374868 -299.869083)
			(xy 272.425206 -299.873254) (xy 272.474171 -299.885654) (xy 272.520427 -299.905944) (xy 272.562713 -299.93357)
			(xy 272.599875 -299.96778) (xy 272.630899 -300.00764) (xy 272.65494 -300.052063) (xy 272.671341 -300.099837)
			(xy 272.679654 -300.149659) (xy 272.680176 -300.174914) (xy 272.680002 -300.189097) (xy 272.677328 -300.217337)
			(xy 272.674842 -300.231302) (xy 272.672556 -300.243748) (xy 272.679922 -300.26737) (xy 272.757392 -300.34484)
			(xy 272.781014 -300.352206) (xy 272.79346 -300.34992) (xy 272.807425 -300.347439) (xy 272.835665 -300.34477)
			(xy 272.849848 -300.344586) (xy 272.864031 -300.34477) (xy 272.892271 -300.347437) (xy 272.906236 -300.34992)
			(xy 272.918682 -300.352206) (xy 272.942304 -300.34484) (xy 273.019774 -300.26737) (xy 273.02714 -300.243748)
			(xy 273.024854 -300.231302) (xy 273.022382 -300.217335) (xy 273.019707 -300.189096) (xy 273.01952 -300.174914)
			(xy 273.020042 -300.149659) (xy 273.028355 -300.099837) (xy 273.044756 -300.052063) (xy 273.068797 -300.00764)
			(xy 273.099821 -299.96778) (xy 273.136983 -299.93357) (xy 273.179269 -299.905944) (xy 273.225525 -299.885654)
			(xy 273.27449 -299.873254) (xy 273.324828 -299.869083) (xy 273.375166 -299.873254) (xy 273.424131 -299.885654)
			(xy 273.470387 -299.905944) (xy 273.512673 -299.93357) (xy 273.549835 -299.96778) (xy 273.580859 -300.00764)
			(xy 273.6049 -300.052063) (xy 273.621301 -300.099837) (xy 273.629614 -300.149659) (xy 273.630136 -300.174914)
			(xy 273.629961 -300.189097) (xy 273.627288 -300.217337) (xy 273.624802 -300.231302) (xy 273.622516 -300.243748)
			(xy 273.629882 -300.26737) (xy 273.707352 -300.34484) (xy 273.730974 -300.352206) (xy 273.74342 -300.34992)
			(xy 273.757386 -300.347445) (xy 273.785626 -300.344772) (xy 273.799808 -300.344586) (xy 273.824628 -300.345086)
			(xy 273.873614 -300.353119) (xy 273.920656 -300.36897) (xy 273.964513 -300.392223) (xy 274.004031 -300.422265)
			(xy 274.038167 -300.458305) (xy 274.066024 -300.499392) (xy 274.086866 -300.544445) (xy 274.100145 -300.592276)
			(xy 274.105511 -300.641626) (xy 274.102822 -300.691193) (xy 274.09215 -300.739673) (xy 274.073775 -300.785787)
			(xy 274.048182 -300.828321) (xy 274.016045 -300.866154) (xy 273.97821 -300.89829) (xy 273.935675 -300.923881)
			(xy 273.889559 -300.942254) (xy 273.841079 -300.952924) (xy 273.791512 -300.955611) (xy 273.742163 -300.950243)
			(xy 273.694332 -300.936961) (xy 273.64928 -300.916117) (xy 273.608194 -300.888259) (xy 273.572156 -300.85412)
			(xy 273.542116 -300.814601) (xy 273.518865 -300.770743) (xy 273.503015 -300.723701) (xy 273.494985 -300.674714)
			(xy 273.4945 -300.649894) (xy 273.494676 -300.635711) (xy 273.497348 -300.607471) (xy 273.499834 -300.593506)
			(xy 273.50212 -300.58106) (xy 273.494754 -300.557438) (xy 273.417284 -300.479968) (xy 273.393662 -300.472602)
			(xy 273.381216 -300.474888) (xy 273.367251 -300.477372) (xy 273.339011 -300.480039) (xy 273.324828 -300.480222)
			(xy 273.310645 -300.480041) (xy 273.282405 -300.477372) (xy 273.26844 -300.474888) (xy 273.255994 -300.472602)
			(xy 273.232372 -300.479968) (xy 273.154902 -300.557438) (xy 273.147536 -300.58106) (xy 273.149822 -300.593506)
			(xy 273.152296 -300.607472) (xy 273.154969 -300.635712) (xy 273.155156 -300.649894) (xy 273.154634 -300.675149)
			(xy 273.146321 -300.724971) (xy 273.12992 -300.772745) (xy 273.105879 -300.817168) (xy 273.074855 -300.857028)
			(xy 273.037693 -300.891238) (xy 272.995407 -300.918864) (xy 272.949151 -300.939154) (xy 272.900186 -300.951554)
			(xy 272.849848 -300.955725) (xy 272.79951 -300.951554) (xy 272.750545 -300.939154) (xy 272.704289 -300.918864)
			(xy 272.662003 -300.891238) (xy 272.624841 -300.857028) (xy 272.593817 -300.817168) (xy 272.569776 -300.772745)
			(xy 272.553375 -300.724971) (xy 272.545062 -300.675149) (xy 272.54454 -300.649894) (xy 272.544715 -300.635711)
			(xy 272.547388 -300.607471) (xy 272.549874 -300.593506) (xy 272.55216 -300.58106) (xy 272.544794 -300.557438)
			(xy 272.467324 -300.479968) (xy 272.443702 -300.472602) (xy 272.431256 -300.474888) (xy 272.41729 -300.477366)
			(xy 272.389051 -300.480037) (xy 272.374868 -300.480222) (xy 272.360685 -300.48005) (xy 272.332445 -300.477375)
			(xy 272.31848 -300.474888) (xy 272.306034 -300.472602) (xy 272.282412 -300.479968) (xy 272.204942 -300.557438)
			(xy 272.197576 -300.58106) (xy 272.199862 -300.593506) (xy 272.202335 -300.607472) (xy 272.205009 -300.635712)
			(xy 272.205196 -300.649894) (xy 272.204674 -300.675149) (xy 272.196361 -300.724971) (xy 272.17996 -300.772745)
			(xy 272.155919 -300.817168) (xy 272.124895 -300.857028) (xy 272.087733 -300.891238) (xy 272.045447 -300.918864)
			(xy 271.999191 -300.939154) (xy 271.950226 -300.951554) (xy 271.899888 -300.955725) (xy 271.84955 -300.951554)
			(xy 271.800585 -300.939154) (xy 271.754329 -300.918864) (xy 271.712043 -300.891238) (xy 271.674881 -300.857028)
			(xy 271.643857 -300.817168) (xy 271.619816 -300.772745) (xy 271.603415 -300.724971) (xy 271.595102 -300.675149)
			(xy 271.59458 -300.649894) (xy 271.594756 -300.635711) (xy 271.597429 -300.607471) (xy 271.599914 -300.593506)
			(xy 271.6022 -300.58106) (xy 271.594834 -300.557438) (xy 271.517364 -300.479968) (xy 271.493742 -300.472602)
			(xy 271.481296 -300.474888) (xy 271.46733 -300.477361) (xy 271.43909 -300.480035) (xy 271.424908 -300.480222)
			(xy 271.410725 -300.480044) (xy 271.382485 -300.477373) (xy 271.36852 -300.474888) (xy 271.356074 -300.472602)
			(xy 271.332452 -300.479968) (xy 271.254982 -300.557438) (xy 271.247616 -300.58106) (xy 271.249902 -300.593506)
			(xy 271.252375 -300.607472) (xy 271.255049 -300.635712) (xy 271.255236 -300.649894) (xy 271.254714 -300.675149)
			(xy 271.246401 -300.724971) (xy 271.23 -300.772745) (xy 271.205959 -300.817168) (xy 271.174935 -300.857028)
			(xy 271.137773 -300.891238) (xy 271.095487 -300.918864) (xy 271.049231 -300.939154) (xy 271.000266 -300.951554)
			(xy 270.949928 -300.955725) (xy 270.89959 -300.951554) (xy 270.850625 -300.939154) (xy 270.804369 -300.918864)
			(xy 270.762083 -300.891238) (xy 270.724921 -300.857028) (xy 270.693897 -300.817168) (xy 270.669856 -300.772745)
			(xy 270.653455 -300.724971) (xy 270.645142 -300.675149) (xy 270.64462 -300.649894) (xy 270.644795 -300.635711)
			(xy 270.647468 -300.607471) (xy 270.649954 -300.593506) (xy 270.65224 -300.58106) (xy 270.644874 -300.557184)
			(xy 270.567658 -300.479968) (xy 270.543528 -300.472602) (xy 270.531336 -300.474888) (xy 270.517308 -300.47738)
			(xy 270.48894 -300.480047) (xy 270.474694 -300.480222) (xy 270.460511 -300.480046) (xy 270.432271 -300.477373)
			(xy 270.418306 -300.474888) (xy 270.40586 -300.472602) (xy 270.382238 -300.479968) (xy 270.304768 -300.557438)
			(xy 270.297402 -300.58106) (xy 270.299688 -300.593506) (xy 270.302161 -300.607472) (xy 270.304835 -300.635712)
			(xy 270.305022 -300.649894) (xy 270.3045 -300.675149) (xy 270.296187 -300.724971) (xy 270.279786 -300.772745)
			(xy 270.255745 -300.817168) (xy 270.224721 -300.857028) (xy 270.187559 -300.891238) (xy 270.145273 -300.918864)
			(xy 270.099017 -300.939154) (xy 270.050052 -300.951554) (xy 269.999714 -300.955725) (xy 269.949376 -300.951554)
			(xy 269.900411 -300.939154) (xy 269.854155 -300.918864) (xy 269.811869 -300.891238) (xy 269.774707 -300.857028)
			(xy 269.743683 -300.817168) (xy 269.719642 -300.772745) (xy 269.703241 -300.724971) (xy 269.694928 -300.675149)
			(xy 269.694406 -300.649894) (xy 269.694582 -300.635711) (xy 269.697254 -300.607471) (xy 269.69974 -300.593506)
			(xy 269.702026 -300.58106) (xy 269.69466 -300.557184) (xy 269.617444 -300.479968) (xy 269.593314 -300.472602)
			(xy 269.581122 -300.474888) (xy 269.567092 -300.477368) (xy 269.538726 -300.480043) (xy 269.52448 -300.480222)
			(xy 269.510367 -300.480083) (xy 269.482255 -300.47754) (xy 269.468346 -300.475142) (xy 269.455646 -300.472602)
			(xy 269.432024 -300.479968) (xy 269.354808 -300.557438) (xy 269.347442 -300.58106) (xy 269.349728 -300.593506)
			(xy 269.352202 -300.607472) (xy 269.354875 -300.635712) (xy 269.355062 -300.649894) (xy 269.354629 -300.674715)
			(xy 269.346599 -300.723702) (xy 269.33075 -300.770745) (xy 269.307499 -300.814605) (xy 269.277458 -300.854125)
			(xy 269.241421 -300.888265) (xy 269.200334 -300.916125) (xy 269.155282 -300.936971) (xy 269.107451 -300.950254)
			(xy 269.058101 -300.955624) (xy 269.008532 -300.95294) (xy 268.960051 -300.942272) (xy 268.913934 -300.923901)
			(xy 268.871396 -300.898312) (xy 268.833559 -300.866178) (xy 268.801419 -300.828346) (xy 268.775822 -300.785813)
			(xy 268.757443 -300.739699) (xy 268.746767 -300.691219) (xy 268.744074 -300.641651) (xy 260.097814 -300.641651)
			(xy 260.099587 -300.642733) (xy 260.142455 -300.678408) (xy 260.179672 -300.719945) (xy 260.210445 -300.766458)
			(xy 260.234117 -300.816955) (xy 260.250185 -300.870362) (xy 260.258305 -300.925538) (xy 260.258814 -300.953424)
			(xy 260.258305 -300.98131) (xy 260.250185 -301.036486) (xy 260.234117 -301.089893) (xy 260.210445 -301.14039)
			(xy 260.179672 -301.186903) (xy 260.142455 -301.22844) (xy 260.099587 -301.264115) (xy 260.051981 -301.293169)
			(xy 260.000652 -301.314981) (xy 259.946695 -301.329087) (xy 259.891258 -301.335187) (xy 259.835524 -301.33315)
			(xy 259.780681 -301.32302) (xy 259.727897 -301.305013) (xy 259.678297 -301.279512) (xy 259.632939 -301.247061)
			(xy 259.59279 -301.208352) (xy 259.558704 -301.164209) (xy 259.531408 -301.115574) (xy 259.511485 -301.063483)
			(xy 259.499359 -301.009046) (xy 259.495288 -300.953424) (xy 258.767028 -300.953424) (xy 258.774437 -301.00377)
			(xy 258.774946 -301.031656) (xy 258.774437 -301.059542) (xy 258.766317 -301.114718) (xy 258.750249 -301.168125)
			(xy 258.726577 -301.218622) (xy 258.695804 -301.265135) (xy 258.658587 -301.306672) (xy 258.615719 -301.342347)
			(xy 258.568113 -301.371401) (xy 258.516784 -301.393213) (xy 258.462827 -301.407319) (xy 258.40739 -301.413419)
			(xy 258.351656 -301.411382) (xy 258.296813 -301.401252) (xy 258.244029 -301.383245) (xy 258.194429 -301.357744)
			(xy 258.149071 -301.325293) (xy 258.108922 -301.286584) (xy 258.074836 -301.242441) (xy 258.04754 -301.193806)
			(xy 258.027617 -301.141715) (xy 258.015491 -301.087278) (xy 258.01142 -301.031656) (xy 234.5309 -301.031656)
			(xy 234.5309 -301.599854) (xy 268.74395 -301.599854) (xy 268.74791 -301.5508) (xy 268.759687 -301.503016)
			(xy 268.778978 -301.45774) (xy 268.805281 -301.416144) (xy 268.837916 -301.379307) (xy 268.876037 -301.348182)
			(xy 268.918658 -301.323575) (xy 268.964674 -301.306123) (xy 269.012893 -301.296279) (xy 269.062068 -301.294298)
			(xy 269.110923 -301.30023) (xy 269.158194 -301.313922) (xy 269.202656 -301.33502) (xy 269.243159 -301.362976)
			(xy 269.278652 -301.397068) (xy 269.308217 -301.436412) (xy 269.331088 -301.479989) (xy 269.346672 -301.52667)
			(xy 269.354567 -301.575247) (xy 269.355062 -301.599854) (xy 269.69391 -301.599854) (xy 269.69787 -301.5508)
			(xy 269.709647 -301.503016) (xy 269.728938 -301.45774) (xy 269.755241 -301.416144) (xy 269.787876 -301.379307)
			(xy 269.825997 -301.348182) (xy 269.868618 -301.323575) (xy 269.914634 -301.306123) (xy 269.962853 -301.296279)
			(xy 270.012028 -301.294298) (xy 270.060883 -301.30023) (xy 270.108154 -301.313922) (xy 270.152616 -301.33502)
			(xy 270.193119 -301.362976) (xy 270.228612 -301.397068) (xy 270.258177 -301.436412) (xy 270.281048 -301.479989)
			(xy 270.296632 -301.52667) (xy 270.304527 -301.575247) (xy 270.305022 -301.599854) (xy 270.304527 -301.624461)
			(xy 270.304348 -301.625562) (xy 270.62328 -301.625562) (xy 270.62328 -301.574146) (xy 270.631323 -301.523364)
			(xy 270.647211 -301.474465) (xy 270.670554 -301.428653) (xy 270.700775 -301.387057) (xy 270.737131 -301.350701)
			(xy 270.778727 -301.32048) (xy 270.824539 -301.297137) (xy 270.873438 -301.281249) (xy 270.92422 -301.273206)
			(xy 270.975636 -301.273206) (xy 271.026418 -301.281249) (xy 271.075317 -301.297137) (xy 271.121129 -301.32048)
			(xy 271.162725 -301.350701) (xy 271.199081 -301.387057) (xy 271.229302 -301.428653) (xy 271.252645 -301.474465)
			(xy 271.268533 -301.523364) (xy 271.276576 -301.574146) (xy 271.27708 -301.599854) (xy 271.276576 -301.625562)
			(xy 271.57324 -301.625562) (xy 271.57324 -301.574146) (xy 271.581283 -301.523364) (xy 271.597171 -301.474465)
			(xy 271.620514 -301.428653) (xy 271.650735 -301.387057) (xy 271.687091 -301.350701) (xy 271.728687 -301.32048)
			(xy 271.774499 -301.297137) (xy 271.823398 -301.281249) (xy 271.87418 -301.273206) (xy 271.925596 -301.273206)
			(xy 271.976378 -301.281249) (xy 272.025277 -301.297137) (xy 272.071089 -301.32048) (xy 272.112685 -301.350701)
			(xy 272.149041 -301.387057) (xy 272.179262 -301.428653) (xy 272.202605 -301.474465) (xy 272.218493 -301.523364)
			(xy 272.226536 -301.574146) (xy 272.22704 -301.599854) (xy 272.544044 -301.599854) (xy 272.548004 -301.5508)
			(xy 272.559781 -301.503016) (xy 272.579072 -301.45774) (xy 272.605375 -301.416144) (xy 272.63801 -301.379307)
			(xy 272.676131 -301.348182) (xy 272.718752 -301.323575) (xy 272.764768 -301.306123) (xy 272.812987 -301.296279)
			(xy 272.862162 -301.294298) (xy 272.911017 -301.30023) (xy 272.958288 -301.313922) (xy 273.00275 -301.33502)
			(xy 273.043253 -301.362976) (xy 273.078746 -301.397068) (xy 273.108311 -301.436412) (xy 273.131182 -301.479989)
			(xy 273.146766 -301.52667) (xy 273.154661 -301.575247) (xy 273.155156 -301.599854) (xy 273.154661 -301.624461)
			(xy 273.154482 -301.625562) (xy 273.47316 -301.625562) (xy 273.47316 -301.574146) (xy 273.481203 -301.523364)
			(xy 273.497091 -301.474465) (xy 273.520434 -301.428653) (xy 273.550655 -301.387057) (xy 273.587011 -301.350701)
			(xy 273.628607 -301.32048) (xy 273.674419 -301.297137) (xy 273.723318 -301.281249) (xy 273.7741 -301.273206)
			(xy 273.825516 -301.273206) (xy 273.876298 -301.281249) (xy 273.925197 -301.297137) (xy 273.971009 -301.32048)
			(xy 274.012605 -301.350701) (xy 274.048961 -301.387057) (xy 274.079182 -301.428653) (xy 274.102525 -301.474465)
			(xy 274.118413 -301.523364) (xy 274.126456 -301.574146) (xy 274.12696 -301.599854) (xy 274.126456 -301.625562)
			(xy 274.42312 -301.625562) (xy 274.42312 -301.574146) (xy 274.431163 -301.523364) (xy 274.447051 -301.474465)
			(xy 274.470394 -301.428653) (xy 274.500615 -301.387057) (xy 274.536971 -301.350701) (xy 274.578567 -301.32048)
			(xy 274.624379 -301.297137) (xy 274.673278 -301.281249) (xy 274.72406 -301.273206) (xy 274.775476 -301.273206)
			(xy 274.826258 -301.281249) (xy 274.875157 -301.297137) (xy 274.920969 -301.32048) (xy 274.962565 -301.350701)
			(xy 274.998921 -301.387057) (xy 275.029142 -301.428653) (xy 275.052485 -301.474465) (xy 275.068373 -301.523364)
			(xy 275.076416 -301.574146) (xy 275.07692 -301.599854) (xy 275.393924 -301.599854) (xy 275.397884 -301.5508)
			(xy 275.409661 -301.503016) (xy 275.428952 -301.45774) (xy 275.455255 -301.416144) (xy 275.48789 -301.379307)
			(xy 275.526011 -301.348182) (xy 275.568632 -301.323575) (xy 275.614648 -301.306123) (xy 275.662867 -301.296279)
			(xy 275.712042 -301.294298) (xy 275.760897 -301.30023) (xy 275.808168 -301.313922) (xy 275.85263 -301.33502)
			(xy 275.893133 -301.362976) (xy 275.928626 -301.397068) (xy 275.958191 -301.436412) (xy 275.981062 -301.479989)
			(xy 275.996646 -301.52667) (xy 276.004541 -301.575247) (xy 276.004871 -301.59164) (xy 276.343934 -301.59164)
			(xy 276.349299 -301.54228) (xy 276.362578 -301.494439) (xy 276.383423 -301.449376) (xy 276.411283 -301.408279)
			(xy 276.445426 -301.372231) (xy 276.484951 -301.342182) (xy 276.528816 -301.318923) (xy 276.575867 -301.303067)
			(xy 276.624863 -301.295033) (xy 276.649688 -301.294546) (xy 276.663935 -301.294716) (xy 276.692303 -301.297383)
			(xy 276.70633 -301.29988) (xy 276.718522 -301.302166) (xy 276.742652 -301.2948) (xy 276.819868 -301.217584)
			(xy 276.827234 -301.193708) (xy 276.824948 -301.181262) (xy 276.822471 -301.167296) (xy 276.819799 -301.139057)
			(xy 276.819614 -301.124874) (xy 276.820136 -301.099619) (xy 276.828449 -301.049797) (xy 276.84485 -301.002023)
			(xy 276.868891 -300.9576) (xy 276.899915 -300.91774) (xy 276.937077 -300.88353) (xy 276.979363 -300.855904)
			(xy 277.025619 -300.835614) (xy 277.074584 -300.823214) (xy 277.124922 -300.819043) (xy 277.17526 -300.823214)
			(xy 277.224225 -300.835614) (xy 277.270481 -300.855904) (xy 277.312767 -300.88353) (xy 277.349929 -300.91774)
			(xy 277.380953 -300.9576) (xy 277.404994 -301.002023) (xy 277.421395 -301.049797) (xy 277.429708 -301.099619)
			(xy 277.43023 -301.124874) (xy 278.719038 -301.124874) (xy 278.722998 -301.07582) (xy 278.734775 -301.028036)
			(xy 278.754066 -300.98276) (xy 278.780369 -300.941164) (xy 278.813004 -300.904327) (xy 278.851125 -300.873202)
			(xy 278.893746 -300.848595) (xy 278.939762 -300.831143) (xy 278.987981 -300.821299) (xy 279.037156 -300.819318)
			(xy 279.086011 -300.82525) (xy 279.133282 -300.838942) (xy 279.177744 -300.86004) (xy 279.218247 -300.887996)
			(xy 279.25374 -300.922088) (xy 279.283305 -300.961432) (xy 279.306176 -301.005009) (xy 279.32176 -301.05169)
			(xy 279.329655 -301.100267) (xy 279.33015 -301.124874) (xy 279.668998 -301.124874) (xy 279.672958 -301.07582)
			(xy 279.684735 -301.028036) (xy 279.704026 -300.98276) (xy 279.730329 -300.941164) (xy 279.762964 -300.904327)
			(xy 279.801085 -300.873202) (xy 279.843706 -300.848595) (xy 279.889722 -300.831143) (xy 279.937941 -300.821299)
			(xy 279.987116 -300.819318) (xy 280.035971 -300.82525) (xy 280.083242 -300.838942) (xy 280.127704 -300.86004)
			(xy 280.168207 -300.887996) (xy 280.2037 -300.922088) (xy 280.233265 -300.961432) (xy 280.256136 -301.005009)
			(xy 280.27172 -301.05169) (xy 280.279615 -301.100267) (xy 280.28011 -301.124874) (xy 280.618958 -301.124874)
			(xy 280.622918 -301.07582) (xy 280.634695 -301.028036) (xy 280.653986 -300.98276) (xy 280.680289 -300.941164)
			(xy 280.712924 -300.904327) (xy 280.751045 -300.873202) (xy 280.793666 -300.848595) (xy 280.839682 -300.831143)
			(xy 280.887901 -300.821299) (xy 280.937076 -300.819318) (xy 280.985931 -300.82525) (xy 281.033202 -300.838942)
			(xy 281.077664 -300.86004) (xy 281.118167 -300.887996) (xy 281.15366 -300.922088) (xy 281.183225 -300.961432)
			(xy 281.206096 -301.005009) (xy 281.22168 -301.05169) (xy 281.229575 -301.100267) (xy 281.23007 -301.124874)
			(xy 281.568918 -301.124874) (xy 281.572878 -301.07582) (xy 281.584655 -301.028036) (xy 281.603946 -300.98276)
			(xy 281.630249 -300.941164) (xy 281.662884 -300.904327) (xy 281.701005 -300.873202) (xy 281.743626 -300.848595)
			(xy 281.789642 -300.831143) (xy 281.837861 -300.821299) (xy 281.887036 -300.819318) (xy 281.935891 -300.82525)
			(xy 281.983162 -300.838942) (xy 282.027624 -300.86004) (xy 282.068127 -300.887996) (xy 282.10362 -300.922088)
			(xy 282.133185 -300.961432) (xy 282.156056 -301.005009) (xy 282.17164 -301.05169) (xy 282.179535 -301.100267)
			(xy 282.18003 -301.124874) (xy 282.519132 -301.124874) (xy 282.523092 -301.07582) (xy 282.534869 -301.028036)
			(xy 282.55416 -300.98276) (xy 282.580463 -300.941164) (xy 282.613098 -300.904327) (xy 282.651219 -300.873202)
			(xy 282.69384 -300.848595) (xy 282.739856 -300.831143) (xy 282.788075 -300.821299) (xy 282.83725 -300.819318)
			(xy 282.886105 -300.82525) (xy 282.933376 -300.838942) (xy 282.977838 -300.86004) (xy 283.018341 -300.887996)
			(xy 283.053834 -300.922088) (xy 283.083399 -300.961432) (xy 283.10627 -301.005009) (xy 283.121854 -301.05169)
			(xy 283.129749 -301.100267) (xy 283.130244 -301.124874) (xy 283.469092 -301.124874) (xy 283.473052 -301.07582)
			(xy 283.484829 -301.028036) (xy 283.50412 -300.98276) (xy 283.530423 -300.941164) (xy 283.563058 -300.904327)
			(xy 283.601179 -300.873202) (xy 283.6438 -300.848595) (xy 283.689816 -300.831143) (xy 283.738035 -300.821299)
			(xy 283.78721 -300.819318) (xy 283.836065 -300.82525) (xy 283.883336 -300.838942) (xy 283.927798 -300.86004)
			(xy 283.968301 -300.887996) (xy 284.003794 -300.922088) (xy 284.033359 -300.961432) (xy 284.05623 -301.005009)
			(xy 284.071814 -301.05169) (xy 284.079709 -301.100267) (xy 284.080204 -301.124874) (xy 284.419052 -301.124874)
			(xy 284.423012 -301.07582) (xy 284.434789 -301.028036) (xy 284.45408 -300.98276) (xy 284.480383 -300.941164)
			(xy 284.513018 -300.904327) (xy 284.551139 -300.873202) (xy 284.59376 -300.848595) (xy 284.639776 -300.831143)
			(xy 284.687995 -300.821299) (xy 284.73717 -300.819318) (xy 284.786025 -300.82525) (xy 284.833296 -300.838942)
			(xy 284.877758 -300.86004) (xy 284.918261 -300.887996) (xy 284.953754 -300.922088) (xy 284.983319 -300.961432)
			(xy 285.00619 -301.005009) (xy 285.021774 -301.05169) (xy 285.029669 -301.100267) (xy 285.030164 -301.124874)
			(xy 285.369012 -301.124874) (xy 285.372972 -301.07582) (xy 285.384749 -301.028036) (xy 285.40404 -300.98276)
			(xy 285.430343 -300.941164) (xy 285.462978 -300.904327) (xy 285.501099 -300.873202) (xy 285.54372 -300.848595)
			(xy 285.589736 -300.831143) (xy 285.637955 -300.821299) (xy 285.68713 -300.819318) (xy 285.735985 -300.82525)
			(xy 285.783256 -300.838942) (xy 285.827718 -300.86004) (xy 285.868221 -300.887996) (xy 285.903714 -300.922088)
			(xy 285.933279 -300.961432) (xy 285.95615 -301.005009) (xy 285.971734 -301.05169) (xy 285.979629 -301.100267)
			(xy 285.980124 -301.124874) (xy 286.318972 -301.124874) (xy 286.322932 -301.07582) (xy 286.334709 -301.028036)
			(xy 286.354 -300.98276) (xy 286.380303 -300.941164) (xy 286.412938 -300.904327) (xy 286.451059 -300.873202)
			(xy 286.49368 -300.848595) (xy 286.539696 -300.831143) (xy 286.587915 -300.821299) (xy 286.63709 -300.819318)
			(xy 286.685945 -300.82525) (xy 286.733216 -300.838942) (xy 286.777678 -300.86004) (xy 286.818181 -300.887996)
			(xy 286.853674 -300.922088) (xy 286.883239 -300.961432) (xy 286.90611 -301.005009) (xy 286.921694 -301.05169)
			(xy 286.929589 -301.100267) (xy 286.930084 -301.124874) (xy 287.268932 -301.124874) (xy 287.272892 -301.07582)
			(xy 287.284669 -301.028036) (xy 287.30396 -300.98276) (xy 287.330263 -300.941164) (xy 287.362898 -300.904327)
			(xy 287.401019 -300.873202) (xy 287.44364 -300.848595) (xy 287.489656 -300.831143) (xy 287.537875 -300.821299)
			(xy 287.58705 -300.819318) (xy 287.635905 -300.82525) (xy 287.683176 -300.838942) (xy 287.727638 -300.86004)
			(xy 287.768141 -300.887996) (xy 287.803634 -300.922088) (xy 287.833199 -300.961432) (xy 287.85607 -301.005009)
			(xy 287.871654 -301.05169) (xy 287.879549 -301.100267) (xy 287.880044 -301.124874) (xy 288.218892 -301.124874)
			(xy 288.222852 -301.07582) (xy 288.234629 -301.028036) (xy 288.25392 -300.98276) (xy 288.280223 -300.941164)
			(xy 288.312858 -300.904327) (xy 288.350979 -300.873202) (xy 288.3936 -300.848595) (xy 288.439616 -300.831143)
			(xy 288.487835 -300.821299) (xy 288.53701 -300.819318) (xy 288.585865 -300.82525) (xy 288.633136 -300.838942)
			(xy 288.677598 -300.86004) (xy 288.718101 -300.887996) (xy 288.753594 -300.922088) (xy 288.783159 -300.961432)
			(xy 288.80603 -301.005009) (xy 288.821614 -301.05169) (xy 288.829509 -301.100267) (xy 288.830004 -301.124874)
			(xy 289.169106 -301.124874) (xy 289.173066 -301.07582) (xy 289.184843 -301.028036) (xy 289.204134 -300.98276)
			(xy 289.230437 -300.941164) (xy 289.263072 -300.904327) (xy 289.301193 -300.873202) (xy 289.343814 -300.848595)
			(xy 289.38983 -300.831143) (xy 289.438049 -300.821299) (xy 289.487224 -300.819318) (xy 289.536079 -300.82525)
			(xy 289.58335 -300.838942) (xy 289.627812 -300.86004) (xy 289.668315 -300.887996) (xy 289.703808 -300.922088)
			(xy 289.733373 -300.961432) (xy 289.756244 -301.005009) (xy 289.771828 -301.05169) (xy 289.779723 -301.100267)
			(xy 289.780218 -301.124874) (xy 290.119066 -301.124874) (xy 290.123026 -301.07582) (xy 290.134803 -301.028036)
			(xy 290.154094 -300.98276) (xy 290.180397 -300.941164) (xy 290.213032 -300.904327) (xy 290.251153 -300.873202)
			(xy 290.293774 -300.848595) (xy 290.33979 -300.831143) (xy 290.388009 -300.821299) (xy 290.437184 -300.819318)
			(xy 290.486039 -300.82525) (xy 290.53331 -300.838942) (xy 290.577772 -300.86004) (xy 290.618275 -300.887996)
			(xy 290.653768 -300.922088) (xy 290.683333 -300.961432) (xy 290.706204 -301.005009) (xy 290.721788 -301.05169)
			(xy 290.729683 -301.100267) (xy 290.730178 -301.124874) (xy 292.018986 -301.124874) (xy 292.022946 -301.07582)
			(xy 292.034723 -301.028036) (xy 292.054014 -300.98276) (xy 292.080317 -300.941164) (xy 292.112952 -300.904327)
			(xy 292.151073 -300.873202) (xy 292.193694 -300.848595) (xy 292.23971 -300.831143) (xy 292.287929 -300.821299)
			(xy 292.337104 -300.819318) (xy 292.385959 -300.82525) (xy 292.43323 -300.838942) (xy 292.477692 -300.86004)
			(xy 292.518195 -300.887996) (xy 292.553688 -300.922088) (xy 292.583253 -300.961432) (xy 292.606124 -301.005009)
			(xy 292.621708 -301.05169) (xy 292.629603 -301.100267) (xy 292.630098 -301.124874) (xy 292.968946 -301.124874)
			(xy 292.972906 -301.07582) (xy 292.984683 -301.028036) (xy 293.003974 -300.98276) (xy 293.030277 -300.941164)
			(xy 293.062912 -300.904327) (xy 293.101033 -300.873202) (xy 293.143654 -300.848595) (xy 293.18967 -300.831143)
			(xy 293.237889 -300.821299) (xy 293.287064 -300.819318) (xy 293.335919 -300.82525) (xy 293.38319 -300.838942)
			(xy 293.427652 -300.86004) (xy 293.468155 -300.887996) (xy 293.503648 -300.922088) (xy 293.533213 -300.961432)
			(xy 293.556084 -301.005009) (xy 293.571668 -301.05169) (xy 293.579563 -301.100267) (xy 293.580058 -301.124874)
			(xy 293.918906 -301.124874) (xy 293.922866 -301.07582) (xy 293.934643 -301.028036) (xy 293.953934 -300.98276)
			(xy 293.980237 -300.941164) (xy 294.012872 -300.904327) (xy 294.050993 -300.873202) (xy 294.093614 -300.848595)
			(xy 294.13963 -300.831143) (xy 294.187849 -300.821299) (xy 294.237024 -300.819318) (xy 294.285879 -300.82525)
			(xy 294.33315 -300.838942) (xy 294.377612 -300.86004) (xy 294.418115 -300.887996) (xy 294.453608 -300.922088)
			(xy 294.483173 -300.961432) (xy 294.506044 -301.005009) (xy 294.521628 -301.05169) (xy 294.529523 -301.100267)
			(xy 294.530018 -301.124874) (xy 294.86912 -301.124874) (xy 294.87308 -301.07582) (xy 294.884857 -301.028036)
			(xy 294.904148 -300.98276) (xy 294.930451 -300.941164) (xy 294.963086 -300.904327) (xy 295.001207 -300.873202)
			(xy 295.043828 -300.848595) (xy 295.089844 -300.831143) (xy 295.138063 -300.821299) (xy 295.187238 -300.819318)
			(xy 295.236093 -300.82525) (xy 295.283364 -300.838942) (xy 295.327826 -300.86004) (xy 295.368329 -300.887996)
			(xy 295.403822 -300.922088) (xy 295.433387 -300.961432) (xy 295.456258 -301.005009) (xy 295.471842 -301.05169)
			(xy 295.479737 -301.100267) (xy 295.480232 -301.124874) (xy 295.81908 -301.124874) (xy 295.82304 -301.07582)
			(xy 295.834817 -301.028036) (xy 295.854108 -300.98276) (xy 295.880411 -300.941164) (xy 295.913046 -300.904327)
			(xy 295.951167 -300.873202) (xy 295.993788 -300.848595) (xy 296.039804 -300.831143) (xy 296.088023 -300.821299)
			(xy 296.137198 -300.819318) (xy 296.186053 -300.82525) (xy 296.233324 -300.838942) (xy 296.277786 -300.86004)
			(xy 296.318289 -300.887996) (xy 296.353782 -300.922088) (xy 296.383347 -300.961432) (xy 296.406218 -301.005009)
			(xy 296.421802 -301.05169) (xy 296.429697 -301.100267) (xy 296.430192 -301.124874) (xy 296.76904 -301.124874)
			(xy 296.773 -301.07582) (xy 296.784777 -301.028036) (xy 296.804068 -300.98276) (xy 296.830371 -300.941164)
			(xy 296.863006 -300.904327) (xy 296.901127 -300.873202) (xy 296.943748 -300.848595) (xy 296.989764 -300.831143)
			(xy 297.037983 -300.821299) (xy 297.087158 -300.819318) (xy 297.136013 -300.82525) (xy 297.183284 -300.838942)
			(xy 297.227746 -300.86004) (xy 297.268249 -300.887996) (xy 297.303742 -300.922088) (xy 297.333307 -300.961432)
			(xy 297.356178 -301.005009) (xy 297.371762 -301.05169) (xy 297.379657 -301.100267) (xy 297.380152 -301.124874)
			(xy 297.719 -301.124874) (xy 297.72296 -301.07582) (xy 297.734737 -301.028036) (xy 297.754028 -300.98276)
			(xy 297.780331 -300.941164) (xy 297.812966 -300.904327) (xy 297.851087 -300.873202) (xy 297.893708 -300.848595)
			(xy 297.939724 -300.831143) (xy 297.987943 -300.821299) (xy 298.037118 -300.819318) (xy 298.085973 -300.82525)
			(xy 298.133244 -300.838942) (xy 298.177706 -300.86004) (xy 298.218209 -300.887996) (xy 298.253702 -300.922088)
			(xy 298.283267 -300.961432) (xy 298.306138 -301.005009) (xy 298.321722 -301.05169) (xy 298.329617 -301.100267)
			(xy 298.330112 -301.124874) (xy 298.66896 -301.124874) (xy 298.67292 -301.07582) (xy 298.684697 -301.028036)
			(xy 298.703988 -300.98276) (xy 298.730291 -300.941164) (xy 298.762926 -300.904327) (xy 298.801047 -300.873202)
			(xy 298.843668 -300.848595) (xy 298.889684 -300.831143) (xy 298.937903 -300.821299) (xy 298.987078 -300.819318)
			(xy 299.035933 -300.82525) (xy 299.083204 -300.838942) (xy 299.127666 -300.86004) (xy 299.168169 -300.887996)
			(xy 299.203662 -300.922088) (xy 299.233227 -300.961432) (xy 299.256098 -301.005009) (xy 299.271682 -301.05169)
			(xy 299.279577 -301.100267) (xy 299.280072 -301.124874) (xy 299.61892 -301.124874) (xy 299.62288 -301.07582)
			(xy 299.634657 -301.028036) (xy 299.653948 -300.98276) (xy 299.680251 -300.941164) (xy 299.712886 -300.904327)
			(xy 299.751007 -300.873202) (xy 299.793628 -300.848595) (xy 299.839644 -300.831143) (xy 299.887863 -300.821299)
			(xy 299.937038 -300.819318) (xy 299.985893 -300.82525) (xy 300.033164 -300.838942) (xy 300.077626 -300.86004)
			(xy 300.118129 -300.887996) (xy 300.153622 -300.922088) (xy 300.183187 -300.961432) (xy 300.206058 -301.005009)
			(xy 300.221642 -301.05169) (xy 300.229537 -301.100267) (xy 300.230032 -301.124874) (xy 300.56888 -301.124874)
			(xy 300.57284 -301.07582) (xy 300.584617 -301.028036) (xy 300.603908 -300.98276) (xy 300.630211 -300.941164)
			(xy 300.662846 -300.904327) (xy 300.700967 -300.873202) (xy 300.743588 -300.848595) (xy 300.789604 -300.831143)
			(xy 300.837823 -300.821299) (xy 300.886998 -300.819318) (xy 300.935853 -300.82525) (xy 300.983124 -300.838942)
			(xy 301.027586 -300.86004) (xy 301.068089 -300.887996) (xy 301.103582 -300.922088) (xy 301.133147 -300.961432)
			(xy 301.156018 -301.005009) (xy 301.171602 -301.05169) (xy 301.179497 -301.100267) (xy 301.179992 -301.124874)
			(xy 301.519094 -301.124874) (xy 301.523054 -301.07582) (xy 301.534831 -301.028036) (xy 301.554122 -300.98276)
			(xy 301.580425 -300.941164) (xy 301.61306 -300.904327) (xy 301.651181 -300.873202) (xy 301.693802 -300.848595)
			(xy 301.739818 -300.831143) (xy 301.788037 -300.821299) (xy 301.837212 -300.819318) (xy 301.886067 -300.82525)
			(xy 301.933338 -300.838942) (xy 301.9778 -300.86004) (xy 302.018303 -300.887996) (xy 302.053796 -300.922088)
			(xy 302.083361 -300.961432) (xy 302.106232 -301.005009) (xy 302.121816 -301.05169) (xy 302.129711 -301.100267)
			(xy 302.130206 -301.124874) (xy 302.469054 -301.124874) (xy 302.473014 -301.07582) (xy 302.484791 -301.028036)
			(xy 302.504082 -300.98276) (xy 302.530385 -300.941164) (xy 302.56302 -300.904327) (xy 302.601141 -300.873202)
			(xy 302.643762 -300.848595) (xy 302.689778 -300.831143) (xy 302.737997 -300.821299) (xy 302.787172 -300.819318)
			(xy 302.836027 -300.82525) (xy 302.883298 -300.838942) (xy 302.92776 -300.86004) (xy 302.968263 -300.887996)
			(xy 303.003756 -300.922088) (xy 303.033321 -300.961432) (xy 303.056192 -301.005009) (xy 303.071776 -301.05169)
			(xy 303.079671 -301.100267) (xy 303.080166 -301.124874) (xy 303.419014 -301.124874) (xy 303.422974 -301.07582)
			(xy 303.434751 -301.028036) (xy 303.454042 -300.98276) (xy 303.480345 -300.941164) (xy 303.51298 -300.904327)
			(xy 303.551101 -300.873202) (xy 303.593722 -300.848595) (xy 303.639738 -300.831143) (xy 303.687957 -300.821299)
			(xy 303.737132 -300.819318) (xy 303.785987 -300.82525) (xy 303.833258 -300.838942) (xy 303.87772 -300.86004)
			(xy 303.918223 -300.887996) (xy 303.953716 -300.922088) (xy 303.983281 -300.961432) (xy 304.006152 -301.005009)
			(xy 304.021736 -301.05169) (xy 304.029631 -301.100267) (xy 304.030126 -301.124874) (xy 304.368974 -301.124874)
			(xy 304.372934 -301.07582) (xy 304.384711 -301.028036) (xy 304.404002 -300.98276) (xy 304.430305 -300.941164)
			(xy 304.46294 -300.904327) (xy 304.501061 -300.873202) (xy 304.543682 -300.848595) (xy 304.589698 -300.831143)
			(xy 304.637917 -300.821299) (xy 304.687092 -300.819318) (xy 304.735947 -300.82525) (xy 304.783218 -300.838942)
			(xy 304.82768 -300.86004) (xy 304.868183 -300.887996) (xy 304.903676 -300.922088) (xy 304.933241 -300.961432)
			(xy 304.956112 -301.005009) (xy 304.971696 -301.05169) (xy 304.979591 -301.100267) (xy 304.980086 -301.124874)
			(xy 305.318934 -301.124874) (xy 305.322894 -301.07582) (xy 305.334671 -301.028036) (xy 305.353962 -300.98276)
			(xy 305.380265 -300.941164) (xy 305.4129 -300.904327) (xy 305.451021 -300.873202) (xy 305.493642 -300.848595)
			(xy 305.539658 -300.831143) (xy 305.587877 -300.821299) (xy 305.637052 -300.819318) (xy 305.685907 -300.82525)
			(xy 305.733178 -300.838942) (xy 305.77764 -300.86004) (xy 305.818143 -300.887996) (xy 305.853636 -300.922088)
			(xy 305.883201 -300.961432) (xy 305.906072 -301.005009) (xy 305.921656 -301.05169) (xy 305.929551 -301.100267)
			(xy 305.930046 -301.124874) (xy 308.169068 -301.124874) (xy 308.173028 -301.07582) (xy 308.184805 -301.028036)
			(xy 308.204096 -300.98276) (xy 308.230399 -300.941164) (xy 308.263034 -300.904327) (xy 308.301155 -300.873202)
			(xy 308.343776 -300.848595) (xy 308.389792 -300.831143) (xy 308.438011 -300.821299) (xy 308.487186 -300.819318)
			(xy 308.536041 -300.82525) (xy 308.583312 -300.838942) (xy 308.627774 -300.86004) (xy 308.668277 -300.887996)
			(xy 308.70377 -300.922088) (xy 308.733335 -300.961432) (xy 308.756206 -301.005009) (xy 308.77179 -301.05169)
			(xy 308.779685 -301.100267) (xy 308.78018 -301.124874) (xy 309.119028 -301.124874) (xy 309.122988 -301.07582)
			(xy 309.134765 -301.028036) (xy 309.154056 -300.98276) (xy 309.180359 -300.941164) (xy 309.212994 -300.904327)
			(xy 309.251115 -300.873202) (xy 309.293736 -300.848595) (xy 309.339752 -300.831143) (xy 309.387971 -300.821299)
			(xy 309.437146 -300.819318) (xy 309.486001 -300.82525) (xy 309.533272 -300.838942) (xy 309.577734 -300.86004)
			(xy 309.618237 -300.887996) (xy 309.65373 -300.922088) (xy 309.683295 -300.961432) (xy 309.706166 -301.005009)
			(xy 309.72175 -301.05169) (xy 309.729645 -301.100267) (xy 309.73014 -301.124874) (xy 310.068988 -301.124874)
			(xy 310.072948 -301.07582) (xy 310.084725 -301.028036) (xy 310.104016 -300.98276) (xy 310.130319 -300.941164)
			(xy 310.162954 -300.904327) (xy 310.201075 -300.873202) (xy 310.243696 -300.848595) (xy 310.289712 -300.831143)
			(xy 310.337931 -300.821299) (xy 310.387106 -300.819318) (xy 310.435961 -300.82525) (xy 310.483232 -300.838942)
			(xy 310.527694 -300.86004) (xy 310.568197 -300.887996) (xy 310.60369 -300.922088) (xy 310.633255 -300.961432)
			(xy 310.656126 -301.005009) (xy 310.67171 -301.05169) (xy 310.679605 -301.100267) (xy 310.6801 -301.124874)
			(xy 311.018948 -301.124874) (xy 311.022908 -301.07582) (xy 311.034685 -301.028036) (xy 311.053976 -300.98276)
			(xy 311.080279 -300.941164) (xy 311.112914 -300.904327) (xy 311.151035 -300.873202) (xy 311.193656 -300.848595)
			(xy 311.239672 -300.831143) (xy 311.287891 -300.821299) (xy 311.337066 -300.819318) (xy 311.385921 -300.82525)
			(xy 311.433192 -300.838942) (xy 311.477654 -300.86004) (xy 311.518157 -300.887996) (xy 311.55365 -300.922088)
			(xy 311.583215 -300.961432) (xy 311.606086 -301.005009) (xy 311.62167 -301.05169) (xy 311.629565 -301.100267)
			(xy 311.63006 -301.124874) (xy 311.968908 -301.124874) (xy 311.972868 -301.07582) (xy 311.984645 -301.028036)
			(xy 312.003936 -300.98276) (xy 312.030239 -300.941164) (xy 312.062874 -300.904327) (xy 312.100995 -300.873202)
			(xy 312.143616 -300.848595) (xy 312.189632 -300.831143) (xy 312.237851 -300.821299) (xy 312.287026 -300.819318)
			(xy 312.335881 -300.82525) (xy 312.383152 -300.838942) (xy 312.427614 -300.86004) (xy 312.468117 -300.887996)
			(xy 312.50361 -300.922088) (xy 312.533175 -300.961432) (xy 312.556046 -301.005009) (xy 312.57163 -301.05169)
			(xy 312.579525 -301.100267) (xy 312.58002 -301.124874) (xy 312.919122 -301.124874) (xy 312.923082 -301.07582)
			(xy 312.934859 -301.028036) (xy 312.95415 -300.98276) (xy 312.980453 -300.941164) (xy 313.013088 -300.904327)
			(xy 313.051209 -300.873202) (xy 313.09383 -300.848595) (xy 313.139846 -300.831143) (xy 313.188065 -300.821299)
			(xy 313.23724 -300.819318) (xy 313.286095 -300.82525) (xy 313.333366 -300.838942) (xy 313.377828 -300.86004)
			(xy 313.418331 -300.887996) (xy 313.453824 -300.922088) (xy 313.483389 -300.961432) (xy 313.50626 -301.005009)
			(xy 313.521844 -301.05169) (xy 313.529739 -301.100267) (xy 313.530234 -301.124874) (xy 313.869082 -301.124874)
			(xy 313.873042 -301.07582) (xy 313.884819 -301.028036) (xy 313.90411 -300.98276) (xy 313.930413 -300.941164)
			(xy 313.963048 -300.904327) (xy 314.001169 -300.873202) (xy 314.04379 -300.848595) (xy 314.089806 -300.831143)
			(xy 314.138025 -300.821299) (xy 314.1872 -300.819318) (xy 314.236055 -300.82525) (xy 314.283326 -300.838942)
			(xy 314.327788 -300.86004) (xy 314.368291 -300.887996) (xy 314.403784 -300.922088) (xy 314.433349 -300.961432)
			(xy 314.45622 -301.005009) (xy 314.471804 -301.05169) (xy 314.479699 -301.100267) (xy 314.480194 -301.124874)
			(xy 314.819042 -301.124874) (xy 314.823002 -301.07582) (xy 314.834779 -301.028036) (xy 314.85407 -300.98276)
			(xy 314.880373 -300.941164) (xy 314.913008 -300.904327) (xy 314.951129 -300.873202) (xy 314.99375 -300.848595)
			(xy 315.039766 -300.831143) (xy 315.087985 -300.821299) (xy 315.13716 -300.819318) (xy 315.186015 -300.82525)
			(xy 315.233286 -300.838942) (xy 315.277748 -300.86004) (xy 315.318251 -300.887996) (xy 315.353744 -300.922088)
			(xy 315.383309 -300.961432) (xy 315.40618 -301.005009) (xy 315.421764 -301.05169) (xy 315.429659 -301.100267)
			(xy 315.430154 -301.124874) (xy 315.429659 -301.149481) (xy 315.421764 -301.198058) (xy 315.40618 -301.244739)
			(xy 315.383309 -301.288316) (xy 315.353744 -301.32766) (xy 315.318251 -301.361752) (xy 315.277748 -301.389708)
			(xy 315.233286 -301.410806) (xy 315.186015 -301.424498) (xy 315.13716 -301.43043) (xy 315.087985 -301.428449)
			(xy 315.039766 -301.418605) (xy 314.99375 -301.401153) (xy 314.951129 -301.376546) (xy 314.913008 -301.345421)
			(xy 314.880373 -301.308584) (xy 314.85407 -301.266988) (xy 314.834779 -301.221712) (xy 314.823002 -301.173928)
			(xy 314.819042 -301.124874) (xy 314.480194 -301.124874) (xy 314.479699 -301.149481) (xy 314.471804 -301.198058)
			(xy 314.45622 -301.244739) (xy 314.433349 -301.288316) (xy 314.403784 -301.32766) (xy 314.368291 -301.361752)
			(xy 314.327788 -301.389708) (xy 314.283326 -301.410806) (xy 314.236055 -301.424498) (xy 314.1872 -301.43043)
			(xy 314.138025 -301.428449) (xy 314.089806 -301.418605) (xy 314.04379 -301.401153) (xy 314.001169 -301.376546)
			(xy 313.963048 -301.345421) (xy 313.930413 -301.308584) (xy 313.90411 -301.266988) (xy 313.884819 -301.221712)
			(xy 313.873042 -301.173928) (xy 313.869082 -301.124874) (xy 313.530234 -301.124874) (xy 313.529739 -301.149481)
			(xy 313.521844 -301.198058) (xy 313.50626 -301.244739) (xy 313.483389 -301.288316) (xy 313.453824 -301.32766)
			(xy 313.418331 -301.361752) (xy 313.377828 -301.389708) (xy 313.333366 -301.410806) (xy 313.286095 -301.424498)
			(xy 313.23724 -301.43043) (xy 313.188065 -301.428449) (xy 313.139846 -301.418605) (xy 313.09383 -301.401153)
			(xy 313.051209 -301.376546) (xy 313.013088 -301.345421) (xy 312.980453 -301.308584) (xy 312.95415 -301.266988)
			(xy 312.934859 -301.221712) (xy 312.923082 -301.173928) (xy 312.919122 -301.124874) (xy 312.58002 -301.124874)
			(xy 312.579525 -301.149481) (xy 312.57163 -301.198058) (xy 312.556046 -301.244739) (xy 312.533175 -301.288316)
			(xy 312.50361 -301.32766) (xy 312.468117 -301.361752) (xy 312.427614 -301.389708) (xy 312.383152 -301.410806)
			(xy 312.335881 -301.424498) (xy 312.287026 -301.43043) (xy 312.237851 -301.428449) (xy 312.189632 -301.418605)
			(xy 312.143616 -301.401153) (xy 312.100995 -301.376546) (xy 312.062874 -301.345421) (xy 312.030239 -301.308584)
			(xy 312.003936 -301.266988) (xy 311.984645 -301.221712) (xy 311.972868 -301.173928) (xy 311.968908 -301.124874)
			(xy 311.63006 -301.124874) (xy 311.629565 -301.149481) (xy 311.62167 -301.198058) (xy 311.606086 -301.244739)
			(xy 311.583215 -301.288316) (xy 311.55365 -301.32766) (xy 311.518157 -301.361752) (xy 311.477654 -301.389708)
			(xy 311.433192 -301.410806) (xy 311.385921 -301.424498) (xy 311.337066 -301.43043) (xy 311.287891 -301.428449)
			(xy 311.239672 -301.418605) (xy 311.193656 -301.401153) (xy 311.151035 -301.376546) (xy 311.112914 -301.345421)
			(xy 311.080279 -301.308584) (xy 311.053976 -301.266988) (xy 311.034685 -301.221712) (xy 311.022908 -301.173928)
			(xy 311.018948 -301.124874) (xy 310.6801 -301.124874) (xy 310.679605 -301.149481) (xy 310.67171 -301.198058)
			(xy 310.656126 -301.244739) (xy 310.633255 -301.288316) (xy 310.60369 -301.32766) (xy 310.568197 -301.361752)
			(xy 310.527694 -301.389708) (xy 310.483232 -301.410806) (xy 310.435961 -301.424498) (xy 310.387106 -301.43043)
			(xy 310.337931 -301.428449) (xy 310.289712 -301.418605) (xy 310.243696 -301.401153) (xy 310.201075 -301.376546)
			(xy 310.162954 -301.345421) (xy 310.130319 -301.308584) (xy 310.104016 -301.266988) (xy 310.084725 -301.221712)
			(xy 310.072948 -301.173928) (xy 310.068988 -301.124874) (xy 309.73014 -301.124874) (xy 309.729645 -301.149481)
			(xy 309.72175 -301.198058) (xy 309.706166 -301.244739) (xy 309.683295 -301.288316) (xy 309.65373 -301.32766)
			(xy 309.618237 -301.361752) (xy 309.577734 -301.389708) (xy 309.533272 -301.410806) (xy 309.486001 -301.424498)
			(xy 309.437146 -301.43043) (xy 309.387971 -301.428449) (xy 309.339752 -301.418605) (xy 309.293736 -301.401153)
			(xy 309.251115 -301.376546) (xy 309.212994 -301.345421) (xy 309.180359 -301.308584) (xy 309.154056 -301.266988)
			(xy 309.134765 -301.221712) (xy 309.122988 -301.173928) (xy 309.119028 -301.124874) (xy 308.78018 -301.124874)
			(xy 308.779685 -301.149481) (xy 308.77179 -301.198058) (xy 308.756206 -301.244739) (xy 308.733335 -301.288316)
			(xy 308.70377 -301.32766) (xy 308.668277 -301.361752) (xy 308.627774 -301.389708) (xy 308.583312 -301.410806)
			(xy 308.536041 -301.424498) (xy 308.487186 -301.43043) (xy 308.438011 -301.428449) (xy 308.389792 -301.418605)
			(xy 308.343776 -301.401153) (xy 308.301155 -301.376546) (xy 308.263034 -301.345421) (xy 308.230399 -301.308584)
			(xy 308.204096 -301.266988) (xy 308.184805 -301.221712) (xy 308.173028 -301.173928) (xy 308.169068 -301.124874)
			(xy 305.930046 -301.124874) (xy 305.929551 -301.149481) (xy 305.921656 -301.198058) (xy 305.906072 -301.244739)
			(xy 305.883201 -301.288316) (xy 305.853636 -301.32766) (xy 305.818143 -301.361752) (xy 305.77764 -301.389708)
			(xy 305.733178 -301.410806) (xy 305.685907 -301.424498) (xy 305.637052 -301.43043) (xy 305.587877 -301.428449)
			(xy 305.539658 -301.418605) (xy 305.493642 -301.401153) (xy 305.451021 -301.376546) (xy 305.4129 -301.345421)
			(xy 305.380265 -301.308584) (xy 305.353962 -301.266988) (xy 305.334671 -301.221712) (xy 305.322894 -301.173928)
			(xy 305.318934 -301.124874) (xy 304.980086 -301.124874) (xy 304.979591 -301.149481) (xy 304.971696 -301.198058)
			(xy 304.956112 -301.244739) (xy 304.933241 -301.288316) (xy 304.903676 -301.32766) (xy 304.868183 -301.361752)
			(xy 304.82768 -301.389708) (xy 304.783218 -301.410806) (xy 304.735947 -301.424498) (xy 304.687092 -301.43043)
			(xy 304.637917 -301.428449) (xy 304.589698 -301.418605) (xy 304.543682 -301.401153) (xy 304.501061 -301.376546)
			(xy 304.46294 -301.345421) (xy 304.430305 -301.308584) (xy 304.404002 -301.266988) (xy 304.384711 -301.221712)
			(xy 304.372934 -301.173928) (xy 304.368974 -301.124874) (xy 304.030126 -301.124874) (xy 304.029631 -301.149481)
			(xy 304.021736 -301.198058) (xy 304.006152 -301.244739) (xy 303.983281 -301.288316) (xy 303.953716 -301.32766)
			(xy 303.918223 -301.361752) (xy 303.87772 -301.389708) (xy 303.833258 -301.410806) (xy 303.785987 -301.424498)
			(xy 303.737132 -301.43043) (xy 303.687957 -301.428449) (xy 303.639738 -301.418605) (xy 303.593722 -301.401153)
			(xy 303.551101 -301.376546) (xy 303.51298 -301.345421) (xy 303.480345 -301.308584) (xy 303.454042 -301.266988)
			(xy 303.434751 -301.221712) (xy 303.422974 -301.173928) (xy 303.419014 -301.124874) (xy 303.080166 -301.124874)
			(xy 303.079671 -301.149481) (xy 303.071776 -301.198058) (xy 303.056192 -301.244739) (xy 303.033321 -301.288316)
			(xy 303.003756 -301.32766) (xy 302.968263 -301.361752) (xy 302.92776 -301.389708) (xy 302.883298 -301.410806)
			(xy 302.836027 -301.424498) (xy 302.787172 -301.43043) (xy 302.737997 -301.428449) (xy 302.689778 -301.418605)
			(xy 302.643762 -301.401153) (xy 302.601141 -301.376546) (xy 302.56302 -301.345421) (xy 302.530385 -301.308584)
			(xy 302.504082 -301.266988) (xy 302.484791 -301.221712) (xy 302.473014 -301.173928) (xy 302.469054 -301.124874)
			(xy 302.130206 -301.124874) (xy 302.129711 -301.149481) (xy 302.121816 -301.198058) (xy 302.106232 -301.244739)
			(xy 302.083361 -301.288316) (xy 302.053796 -301.32766) (xy 302.018303 -301.361752) (xy 301.9778 -301.389708)
			(xy 301.933338 -301.410806) (xy 301.886067 -301.424498) (xy 301.837212 -301.43043) (xy 301.788037 -301.428449)
			(xy 301.739818 -301.418605) (xy 301.693802 -301.401153) (xy 301.651181 -301.376546) (xy 301.61306 -301.345421)
			(xy 301.580425 -301.308584) (xy 301.554122 -301.266988) (xy 301.534831 -301.221712) (xy 301.523054 -301.173928)
			(xy 301.519094 -301.124874) (xy 301.179992 -301.124874) (xy 301.179497 -301.149481) (xy 301.171602 -301.198058)
			(xy 301.156018 -301.244739) (xy 301.133147 -301.288316) (xy 301.103582 -301.32766) (xy 301.068089 -301.361752)
			(xy 301.027586 -301.389708) (xy 300.983124 -301.410806) (xy 300.935853 -301.424498) (xy 300.886998 -301.43043)
			(xy 300.837823 -301.428449) (xy 300.789604 -301.418605) (xy 300.743588 -301.401153) (xy 300.700967 -301.376546)
			(xy 300.662846 -301.345421) (xy 300.630211 -301.308584) (xy 300.603908 -301.266988) (xy 300.584617 -301.221712)
			(xy 300.57284 -301.173928) (xy 300.56888 -301.124874) (xy 300.230032 -301.124874) (xy 300.229537 -301.149481)
			(xy 300.221642 -301.198058) (xy 300.206058 -301.244739) (xy 300.183187 -301.288316) (xy 300.153622 -301.32766)
			(xy 300.118129 -301.361752) (xy 300.077626 -301.389708) (xy 300.033164 -301.410806) (xy 299.985893 -301.424498)
			(xy 299.937038 -301.43043) (xy 299.887863 -301.428449) (xy 299.839644 -301.418605) (xy 299.793628 -301.401153)
			(xy 299.751007 -301.376546) (xy 299.712886 -301.345421) (xy 299.680251 -301.308584) (xy 299.653948 -301.266988)
			(xy 299.634657 -301.221712) (xy 299.62288 -301.173928) (xy 299.61892 -301.124874) (xy 299.280072 -301.124874)
			(xy 299.279577 -301.149481) (xy 299.271682 -301.198058) (xy 299.256098 -301.244739) (xy 299.233227 -301.288316)
			(xy 299.203662 -301.32766) (xy 299.168169 -301.361752) (xy 299.127666 -301.389708) (xy 299.083204 -301.410806)
			(xy 299.035933 -301.424498) (xy 298.987078 -301.43043) (xy 298.937903 -301.428449) (xy 298.889684 -301.418605)
			(xy 298.843668 -301.401153) (xy 298.801047 -301.376546) (xy 298.762926 -301.345421) (xy 298.730291 -301.308584)
			(xy 298.703988 -301.266988) (xy 298.684697 -301.221712) (xy 298.67292 -301.173928) (xy 298.66896 -301.124874)
			(xy 298.330112 -301.124874) (xy 298.329617 -301.149481) (xy 298.321722 -301.198058) (xy 298.306138 -301.244739)
			(xy 298.283267 -301.288316) (xy 298.253702 -301.32766) (xy 298.218209 -301.361752) (xy 298.177706 -301.389708)
			(xy 298.133244 -301.410806) (xy 298.085973 -301.424498) (xy 298.037118 -301.43043) (xy 297.987943 -301.428449)
			(xy 297.939724 -301.418605) (xy 297.893708 -301.401153) (xy 297.851087 -301.376546) (xy 297.812966 -301.345421)
			(xy 297.780331 -301.308584) (xy 297.754028 -301.266988) (xy 297.734737 -301.221712) (xy 297.72296 -301.173928)
			(xy 297.719 -301.124874) (xy 297.380152 -301.124874) (xy 297.379657 -301.149481) (xy 297.371762 -301.198058)
			(xy 297.356178 -301.244739) (xy 297.333307 -301.288316) (xy 297.303742 -301.32766) (xy 297.268249 -301.361752)
			(xy 297.227746 -301.389708) (xy 297.183284 -301.410806) (xy 297.136013 -301.424498) (xy 297.087158 -301.43043)
			(xy 297.037983 -301.428449) (xy 296.989764 -301.418605) (xy 296.943748 -301.401153) (xy 296.901127 -301.376546)
			(xy 296.863006 -301.345421) (xy 296.830371 -301.308584) (xy 296.804068 -301.266988) (xy 296.784777 -301.221712)
			(xy 296.773 -301.173928) (xy 296.76904 -301.124874) (xy 296.430192 -301.124874) (xy 296.429697 -301.149481)
			(xy 296.421802 -301.198058) (xy 296.406218 -301.244739) (xy 296.383347 -301.288316) (xy 296.353782 -301.32766)
			(xy 296.318289 -301.361752) (xy 296.277786 -301.389708) (xy 296.233324 -301.410806) (xy 296.186053 -301.424498)
			(xy 296.137198 -301.43043) (xy 296.088023 -301.428449) (xy 296.039804 -301.418605) (xy 295.993788 -301.401153)
			(xy 295.951167 -301.376546) (xy 295.913046 -301.345421) (xy 295.880411 -301.308584) (xy 295.854108 -301.266988)
			(xy 295.834817 -301.221712) (xy 295.82304 -301.173928) (xy 295.81908 -301.124874) (xy 295.480232 -301.124874)
			(xy 295.479737 -301.149481) (xy 295.471842 -301.198058) (xy 295.456258 -301.244739) (xy 295.433387 -301.288316)
			(xy 295.403822 -301.32766) (xy 295.368329 -301.361752) (xy 295.327826 -301.389708) (xy 295.283364 -301.410806)
			(xy 295.236093 -301.424498) (xy 295.187238 -301.43043) (xy 295.138063 -301.428449) (xy 295.089844 -301.418605)
			(xy 295.043828 -301.401153) (xy 295.001207 -301.376546) (xy 294.963086 -301.345421) (xy 294.930451 -301.308584)
			(xy 294.904148 -301.266988) (xy 294.884857 -301.221712) (xy 294.87308 -301.173928) (xy 294.86912 -301.124874)
			(xy 294.530018 -301.124874) (xy 294.529523 -301.149481) (xy 294.521628 -301.198058) (xy 294.506044 -301.244739)
			(xy 294.483173 -301.288316) (xy 294.453608 -301.32766) (xy 294.418115 -301.361752) (xy 294.377612 -301.389708)
			(xy 294.33315 -301.410806) (xy 294.285879 -301.424498) (xy 294.237024 -301.43043) (xy 294.187849 -301.428449)
			(xy 294.13963 -301.418605) (xy 294.093614 -301.401153) (xy 294.050993 -301.376546) (xy 294.012872 -301.345421)
			(xy 293.980237 -301.308584) (xy 293.953934 -301.266988) (xy 293.934643 -301.221712) (xy 293.922866 -301.173928)
			(xy 293.918906 -301.124874) (xy 293.580058 -301.124874) (xy 293.579563 -301.149481) (xy 293.571668 -301.198058)
			(xy 293.556084 -301.244739) (xy 293.533213 -301.288316) (xy 293.503648 -301.32766) (xy 293.468155 -301.361752)
			(xy 293.427652 -301.389708) (xy 293.38319 -301.410806) (xy 293.335919 -301.424498) (xy 293.287064 -301.43043)
			(xy 293.237889 -301.428449) (xy 293.18967 -301.418605) (xy 293.143654 -301.401153) (xy 293.101033 -301.376546)
			(xy 293.062912 -301.345421) (xy 293.030277 -301.308584) (xy 293.003974 -301.266988) (xy 292.984683 -301.221712)
			(xy 292.972906 -301.173928) (xy 292.968946 -301.124874) (xy 292.630098 -301.124874) (xy 292.629603 -301.149481)
			(xy 292.621708 -301.198058) (xy 292.606124 -301.244739) (xy 292.583253 -301.288316) (xy 292.553688 -301.32766)
			(xy 292.518195 -301.361752) (xy 292.477692 -301.389708) (xy 292.43323 -301.410806) (xy 292.385959 -301.424498)
			(xy 292.337104 -301.43043) (xy 292.287929 -301.428449) (xy 292.23971 -301.418605) (xy 292.193694 -301.401153)
			(xy 292.151073 -301.376546) (xy 292.112952 -301.345421) (xy 292.080317 -301.308584) (xy 292.054014 -301.266988)
			(xy 292.034723 -301.221712) (xy 292.022946 -301.173928) (xy 292.018986 -301.124874) (xy 290.730178 -301.124874)
			(xy 290.729683 -301.149481) (xy 290.721788 -301.198058) (xy 290.706204 -301.244739) (xy 290.683333 -301.288316)
			(xy 290.653768 -301.32766) (xy 290.618275 -301.361752) (xy 290.577772 -301.389708) (xy 290.53331 -301.410806)
			(xy 290.486039 -301.424498) (xy 290.437184 -301.43043) (xy 290.388009 -301.428449) (xy 290.33979 -301.418605)
			(xy 290.293774 -301.401153) (xy 290.251153 -301.376546) (xy 290.213032 -301.345421) (xy 290.180397 -301.308584)
			(xy 290.154094 -301.266988) (xy 290.134803 -301.221712) (xy 290.123026 -301.173928) (xy 290.119066 -301.124874)
			(xy 289.780218 -301.124874) (xy 289.779723 -301.149481) (xy 289.771828 -301.198058) (xy 289.756244 -301.244739)
			(xy 289.733373 -301.288316) (xy 289.703808 -301.32766) (xy 289.668315 -301.361752) (xy 289.627812 -301.389708)
			(xy 289.58335 -301.410806) (xy 289.536079 -301.424498) (xy 289.487224 -301.43043) (xy 289.438049 -301.428449)
			(xy 289.38983 -301.418605) (xy 289.343814 -301.401153) (xy 289.301193 -301.376546) (xy 289.263072 -301.345421)
			(xy 289.230437 -301.308584) (xy 289.204134 -301.266988) (xy 289.184843 -301.221712) (xy 289.173066 -301.173928)
			(xy 289.169106 -301.124874) (xy 288.830004 -301.124874) (xy 288.829509 -301.149481) (xy 288.821614 -301.198058)
			(xy 288.80603 -301.244739) (xy 288.783159 -301.288316) (xy 288.753594 -301.32766) (xy 288.718101 -301.361752)
			(xy 288.677598 -301.389708) (xy 288.633136 -301.410806) (xy 288.585865 -301.424498) (xy 288.53701 -301.43043)
			(xy 288.487835 -301.428449) (xy 288.439616 -301.418605) (xy 288.3936 -301.401153) (xy 288.350979 -301.376546)
			(xy 288.312858 -301.345421) (xy 288.280223 -301.308584) (xy 288.25392 -301.266988) (xy 288.234629 -301.221712)
			(xy 288.222852 -301.173928) (xy 288.218892 -301.124874) (xy 287.880044 -301.124874) (xy 287.879549 -301.149481)
			(xy 287.871654 -301.198058) (xy 287.85607 -301.244739) (xy 287.833199 -301.288316) (xy 287.803634 -301.32766)
			(xy 287.768141 -301.361752) (xy 287.727638 -301.389708) (xy 287.683176 -301.410806) (xy 287.635905 -301.424498)
			(xy 287.58705 -301.43043) (xy 287.537875 -301.428449) (xy 287.489656 -301.418605) (xy 287.44364 -301.401153)
			(xy 287.401019 -301.376546) (xy 287.362898 -301.345421) (xy 287.330263 -301.308584) (xy 287.30396 -301.266988)
			(xy 287.284669 -301.221712) (xy 287.272892 -301.173928) (xy 287.268932 -301.124874) (xy 286.930084 -301.124874)
			(xy 286.929589 -301.149481) (xy 286.921694 -301.198058) (xy 286.90611 -301.244739) (xy 286.883239 -301.288316)
			(xy 286.853674 -301.32766) (xy 286.818181 -301.361752) (xy 286.777678 -301.389708) (xy 286.733216 -301.410806)
			(xy 286.685945 -301.424498) (xy 286.63709 -301.43043) (xy 286.587915 -301.428449) (xy 286.539696 -301.418605)
			(xy 286.49368 -301.401153) (xy 286.451059 -301.376546) (xy 286.412938 -301.345421) (xy 286.380303 -301.308584)
			(xy 286.354 -301.266988) (xy 286.334709 -301.221712) (xy 286.322932 -301.173928) (xy 286.318972 -301.124874)
			(xy 285.980124 -301.124874) (xy 285.979629 -301.149481) (xy 285.971734 -301.198058) (xy 285.95615 -301.244739)
			(xy 285.933279 -301.288316) (xy 285.903714 -301.32766) (xy 285.868221 -301.361752) (xy 285.827718 -301.389708)
			(xy 285.783256 -301.410806) (xy 285.735985 -301.424498) (xy 285.68713 -301.43043) (xy 285.637955 -301.428449)
			(xy 285.589736 -301.418605) (xy 285.54372 -301.401153) (xy 285.501099 -301.376546) (xy 285.462978 -301.345421)
			(xy 285.430343 -301.308584) (xy 285.40404 -301.266988) (xy 285.384749 -301.221712) (xy 285.372972 -301.173928)
			(xy 285.369012 -301.124874) (xy 285.030164 -301.124874) (xy 285.029669 -301.149481) (xy 285.021774 -301.198058)
			(xy 285.00619 -301.244739) (xy 284.983319 -301.288316) (xy 284.953754 -301.32766) (xy 284.918261 -301.361752)
			(xy 284.877758 -301.389708) (xy 284.833296 -301.410806) (xy 284.786025 -301.424498) (xy 284.73717 -301.43043)
			(xy 284.687995 -301.428449) (xy 284.639776 -301.418605) (xy 284.59376 -301.401153) (xy 284.551139 -301.376546)
			(xy 284.513018 -301.345421) (xy 284.480383 -301.308584) (xy 284.45408 -301.266988) (xy 284.434789 -301.221712)
			(xy 284.423012 -301.173928) (xy 284.419052 -301.124874) (xy 284.080204 -301.124874) (xy 284.079709 -301.149481)
			(xy 284.071814 -301.198058) (xy 284.05623 -301.244739) (xy 284.033359 -301.288316) (xy 284.003794 -301.32766)
			(xy 283.968301 -301.361752) (xy 283.927798 -301.389708) (xy 283.883336 -301.410806) (xy 283.836065 -301.424498)
			(xy 283.78721 -301.43043) (xy 283.738035 -301.428449) (xy 283.689816 -301.418605) (xy 283.6438 -301.401153)
			(xy 283.601179 -301.376546) (xy 283.563058 -301.345421) (xy 283.530423 -301.308584) (xy 283.50412 -301.266988)
			(xy 283.484829 -301.221712) (xy 283.473052 -301.173928) (xy 283.469092 -301.124874) (xy 283.130244 -301.124874)
			(xy 283.129749 -301.149481) (xy 283.121854 -301.198058) (xy 283.10627 -301.244739) (xy 283.083399 -301.288316)
			(xy 283.053834 -301.32766) (xy 283.018341 -301.361752) (xy 282.977838 -301.389708) (xy 282.933376 -301.410806)
			(xy 282.886105 -301.424498) (xy 282.83725 -301.43043) (xy 282.788075 -301.428449) (xy 282.739856 -301.418605)
			(xy 282.69384 -301.401153) (xy 282.651219 -301.376546) (xy 282.613098 -301.345421) (xy 282.580463 -301.308584)
			(xy 282.55416 -301.266988) (xy 282.534869 -301.221712) (xy 282.523092 -301.173928) (xy 282.519132 -301.124874)
			(xy 282.18003 -301.124874) (xy 282.179535 -301.149481) (xy 282.17164 -301.198058) (xy 282.156056 -301.244739)
			(xy 282.133185 -301.288316) (xy 282.10362 -301.32766) (xy 282.068127 -301.361752) (xy 282.027624 -301.389708)
			(xy 281.983162 -301.410806) (xy 281.935891 -301.424498) (xy 281.887036 -301.43043) (xy 281.837861 -301.428449)
			(xy 281.789642 -301.418605) (xy 281.743626 -301.401153) (xy 281.701005 -301.376546) (xy 281.662884 -301.345421)
			(xy 281.630249 -301.308584) (xy 281.603946 -301.266988) (xy 281.584655 -301.221712) (xy 281.572878 -301.173928)
			(xy 281.568918 -301.124874) (xy 281.23007 -301.124874) (xy 281.229575 -301.149481) (xy 281.22168 -301.198058)
			(xy 281.206096 -301.244739) (xy 281.183225 -301.288316) (xy 281.15366 -301.32766) (xy 281.118167 -301.361752)
			(xy 281.077664 -301.389708) (xy 281.033202 -301.410806) (xy 280.985931 -301.424498) (xy 280.937076 -301.43043)
			(xy 280.887901 -301.428449) (xy 280.839682 -301.418605) (xy 280.793666 -301.401153) (xy 280.751045 -301.376546)
			(xy 280.712924 -301.345421) (xy 280.680289 -301.308584) (xy 280.653986 -301.266988) (xy 280.634695 -301.221712)
			(xy 280.622918 -301.173928) (xy 280.618958 -301.124874) (xy 280.28011 -301.124874) (xy 280.279615 -301.149481)
			(xy 280.27172 -301.198058) (xy 280.256136 -301.244739) (xy 280.233265 -301.288316) (xy 280.2037 -301.32766)
			(xy 280.168207 -301.361752) (xy 280.127704 -301.389708) (xy 280.083242 -301.410806) (xy 280.035971 -301.424498)
			(xy 279.987116 -301.43043) (xy 279.937941 -301.428449) (xy 279.889722 -301.418605) (xy 279.843706 -301.401153)
			(xy 279.801085 -301.376546) (xy 279.762964 -301.345421) (xy 279.730329 -301.308584) (xy 279.704026 -301.266988)
			(xy 279.684735 -301.221712) (xy 279.672958 -301.173928) (xy 279.668998 -301.124874) (xy 279.33015 -301.124874)
			(xy 279.329655 -301.149481) (xy 279.32176 -301.198058) (xy 279.306176 -301.244739) (xy 279.283305 -301.288316)
			(xy 279.25374 -301.32766) (xy 279.218247 -301.361752) (xy 279.177744 -301.389708) (xy 279.133282 -301.410806)
			(xy 279.086011 -301.424498) (xy 279.037156 -301.43043) (xy 278.987981 -301.428449) (xy 278.939762 -301.418605)
			(xy 278.893746 -301.401153) (xy 278.851125 -301.376546) (xy 278.813004 -301.345421) (xy 278.780369 -301.308584)
			(xy 278.754066 -301.266988) (xy 278.734775 -301.221712) (xy 278.722998 -301.173928) (xy 278.719038 -301.124874)
			(xy 277.43023 -301.124874) (xy 277.430049 -301.139057) (xy 277.42738 -301.167297) (xy 277.424896 -301.181262)
			(xy 277.42261 -301.193708) (xy 277.429976 -301.21733) (xy 277.507446 -301.2948) (xy 277.531068 -301.302166)
			(xy 277.543514 -301.29988) (xy 277.55748 -301.297405) (xy 277.58572 -301.294732) (xy 277.599902 -301.294546)
			(xy 277.624723 -301.29508) (xy 277.673712 -301.303112) (xy 277.720756 -301.318964) (xy 277.764616 -301.342218)
			(xy 277.804135 -301.372262) (xy 277.838274 -301.408303) (xy 277.866131 -301.449393) (xy 277.886974 -301.494449)
			(xy 277.900252 -301.542283) (xy 277.905617 -301.591635) (xy 277.902927 -301.641205) (xy 277.892252 -301.689686)
			(xy 277.873874 -301.735802) (xy 277.848278 -301.778337) (xy 277.816137 -301.816171) (xy 277.778298 -301.848306)
			(xy 277.735759 -301.873896) (xy 277.68964 -301.892266) (xy 277.641157 -301.902933) (xy 277.591587 -301.905616)
			(xy 277.542235 -301.900243) (xy 277.494403 -301.886957) (xy 277.449351 -301.866108) (xy 277.408266 -301.838244)
			(xy 277.372229 -301.8041) (xy 277.342192 -301.764575) (xy 277.318945 -301.720712) (xy 277.3031 -301.673666)
			(xy 277.295076 -301.624676) (xy 277.294594 -301.599854) (xy 277.294778 -301.585671) (xy 277.297445 -301.557431)
			(xy 277.299928 -301.543466) (xy 277.302214 -301.53102) (xy 277.294848 -301.507398) (xy 277.217378 -301.429928)
			(xy 277.193756 -301.422562) (xy 277.18131 -301.424848) (xy 277.167343 -301.427319) (xy 277.139104 -301.429994)
			(xy 277.124922 -301.430182) (xy 277.110675 -301.430019) (xy 277.082307 -301.427344) (xy 277.06828 -301.424848)
			(xy 277.056088 -301.422562) (xy 277.031958 -301.429928) (xy 276.954742 -301.507144) (xy 276.947376 -301.53102)
			(xy 276.949662 -301.543466) (xy 276.952143 -301.557431) (xy 276.954812 -301.585671) (xy 276.954996 -301.599854)
			(xy 276.954572 -301.624679) (xy 276.946547 -301.673677) (xy 276.9307 -301.72073) (xy 276.90745 -301.7646)
			(xy 276.877408 -301.804131) (xy 276.841366 -301.83828) (xy 276.800275 -301.866149) (xy 276.755216 -301.887002)
			(xy 276.707377 -301.90029) (xy 276.658018 -301.905664) (xy 276.60844 -301.902982) (xy 276.559949 -301.892314)
			(xy 276.513823 -301.873941) (xy 276.471277 -301.848348) (xy 276.433432 -301.816209) (xy 276.401286 -301.77837)
			(xy 276.375685 -301.735829) (xy 276.357303 -301.689706) (xy 276.346626 -301.641218) (xy 276.343934 -301.59164)
			(xy 276.004871 -301.59164) (xy 276.005036 -301.599854) (xy 276.004541 -301.624461) (xy 275.996646 -301.673038)
			(xy 275.981062 -301.719719) (xy 275.958191 -301.763296) (xy 275.928626 -301.80264) (xy 275.893133 -301.836732)
			(xy 275.85263 -301.864688) (xy 275.808168 -301.885786) (xy 275.760897 -301.899478) (xy 275.712042 -301.90541)
			(xy 275.662867 -301.903429) (xy 275.614648 -301.893585) (xy 275.568632 -301.876133) (xy 275.526011 -301.851526)
			(xy 275.48789 -301.820401) (xy 275.455255 -301.783564) (xy 275.428952 -301.741968) (xy 275.409661 -301.696692)
			(xy 275.397884 -301.648908) (xy 275.393924 -301.599854) (xy 275.07692 -301.599854) (xy 275.076416 -301.625562)
			(xy 275.068373 -301.676344) (xy 275.052485 -301.725243) (xy 275.029142 -301.771055) (xy 274.998921 -301.812651)
			(xy 274.962565 -301.849007) (xy 274.920969 -301.879228) (xy 274.875157 -301.902571) (xy 274.826258 -301.918459)
			(xy 274.775476 -301.926502) (xy 274.72406 -301.926502) (xy 274.673278 -301.918459) (xy 274.624379 -301.902571)
			(xy 274.578567 -301.879228) (xy 274.536971 -301.849007) (xy 274.500615 -301.812651) (xy 274.470394 -301.771055)
			(xy 274.447051 -301.725243) (xy 274.431163 -301.676344) (xy 274.42312 -301.625562) (xy 274.126456 -301.625562)
			(xy 274.118413 -301.676344) (xy 274.102525 -301.725243) (xy 274.079182 -301.771055) (xy 274.048961 -301.812651)
			(xy 274.012605 -301.849007) (xy 273.971009 -301.879228) (xy 273.925197 -301.902571) (xy 273.876298 -301.918459)
			(xy 273.825516 -301.926502) (xy 273.7741 -301.926502) (xy 273.723318 -301.918459) (xy 273.674419 -301.902571)
			(xy 273.628607 -301.879228) (xy 273.587011 -301.849007) (xy 273.550655 -301.812651) (xy 273.520434 -301.771055)
			(xy 273.497091 -301.725243) (xy 273.481203 -301.676344) (xy 273.47316 -301.625562) (xy 273.154482 -301.625562)
			(xy 273.146766 -301.673038) (xy 273.131182 -301.719719) (xy 273.108311 -301.763296) (xy 273.078746 -301.80264)
			(xy 273.043253 -301.836732) (xy 273.00275 -301.864688) (xy 272.958288 -301.885786) (xy 272.911017 -301.899478)
			(xy 272.862162 -301.90541) (xy 272.812987 -301.903429) (xy 272.764768 -301.893585) (xy 272.718752 -301.876133)
			(xy 272.676131 -301.851526) (xy 272.63801 -301.820401) (xy 272.605375 -301.783564) (xy 272.579072 -301.741968)
			(xy 272.559781 -301.696692) (xy 272.548004 -301.648908) (xy 272.544044 -301.599854) (xy 272.22704 -301.599854)
			(xy 272.226536 -301.625562) (xy 272.218493 -301.676344) (xy 272.202605 -301.725243) (xy 272.179262 -301.771055)
			(xy 272.149041 -301.812651) (xy 272.112685 -301.849007) (xy 272.071089 -301.879228) (xy 272.025277 -301.902571)
			(xy 271.976378 -301.918459) (xy 271.925596 -301.926502) (xy 271.87418 -301.926502) (xy 271.823398 -301.918459)
			(xy 271.774499 -301.902571) (xy 271.728687 -301.879228) (xy 271.687091 -301.849007) (xy 271.650735 -301.812651)
			(xy 271.620514 -301.771055) (xy 271.597171 -301.725243) (xy 271.581283 -301.676344) (xy 271.57324 -301.625562)
			(xy 271.276576 -301.625562) (xy 271.268533 -301.676344) (xy 271.252645 -301.725243) (xy 271.229302 -301.771055)
			(xy 271.199081 -301.812651) (xy 271.162725 -301.849007) (xy 271.121129 -301.879228) (xy 271.075317 -301.902571)
			(xy 271.026418 -301.918459) (xy 270.975636 -301.926502) (xy 270.92422 -301.926502) (xy 270.873438 -301.918459)
			(xy 270.824539 -301.902571) (xy 270.778727 -301.879228) (xy 270.737131 -301.849007) (xy 270.700775 -301.812651)
			(xy 270.670554 -301.771055) (xy 270.647211 -301.725243) (xy 270.631323 -301.676344) (xy 270.62328 -301.625562)
			(xy 270.304348 -301.625562) (xy 270.296632 -301.673038) (xy 270.281048 -301.719719) (xy 270.258177 -301.763296)
			(xy 270.228612 -301.80264) (xy 270.193119 -301.836732) (xy 270.152616 -301.864688) (xy 270.108154 -301.885786)
			(xy 270.060883 -301.899478) (xy 270.012028 -301.90541) (xy 269.962853 -301.903429) (xy 269.914634 -301.893585)
			(xy 269.868618 -301.876133) (xy 269.825997 -301.851526) (xy 269.787876 -301.820401) (xy 269.755241 -301.783564)
			(xy 269.728938 -301.741968) (xy 269.709647 -301.696692) (xy 269.69787 -301.648908) (xy 269.69391 -301.599854)
			(xy 269.355062 -301.599854) (xy 269.354567 -301.624461) (xy 269.346672 -301.673038) (xy 269.331088 -301.719719)
			(xy 269.308217 -301.763296) (xy 269.278652 -301.80264) (xy 269.243159 -301.836732) (xy 269.202656 -301.864688)
			(xy 269.158194 -301.885786) (xy 269.110923 -301.899478) (xy 269.062068 -301.90541) (xy 269.012893 -301.903429)
			(xy 268.964674 -301.893585) (xy 268.918658 -301.876133) (xy 268.876037 -301.851526) (xy 268.837916 -301.820401)
			(xy 268.805281 -301.783564) (xy 268.778978 -301.741968) (xy 268.759687 -301.696692) (xy 268.74791 -301.648908)
			(xy 268.74395 -301.599854) (xy 234.5309 -301.599854) (xy 234.5309 -302.074834) (xy 281.568918 -302.074834)
			(xy 281.572878 -302.02578) (xy 281.584655 -301.977996) (xy 281.603946 -301.93272) (xy 281.630249 -301.891124)
			(xy 281.662884 -301.854287) (xy 281.701005 -301.823162) (xy 281.743626 -301.798555) (xy 281.789642 -301.781103)
			(xy 281.837861 -301.771259) (xy 281.887036 -301.769278) (xy 281.935891 -301.77521) (xy 281.983162 -301.788902)
			(xy 282.027624 -301.81) (xy 282.068127 -301.837956) (xy 282.10362 -301.872048) (xy 282.133185 -301.911392)
			(xy 282.156056 -301.954969) (xy 282.17164 -302.00165) (xy 282.179535 -302.050227) (xy 282.18003 -302.074834)
			(xy 282.519132 -302.074834) (xy 282.523092 -302.02578) (xy 282.534869 -301.977996) (xy 282.55416 -301.93272)
			(xy 282.580463 -301.891124) (xy 282.613098 -301.854287) (xy 282.651219 -301.823162) (xy 282.69384 -301.798555)
			(xy 282.739856 -301.781103) (xy 282.788075 -301.771259) (xy 282.83725 -301.769278) (xy 282.886105 -301.77521)
			(xy 282.933376 -301.788902) (xy 282.977838 -301.81) (xy 283.018341 -301.837956) (xy 283.053834 -301.872048)
			(xy 283.083399 -301.911392) (xy 283.10627 -301.954969) (xy 283.121854 -302.00165) (xy 283.129749 -302.050227)
			(xy 283.130244 -302.074834) (xy 283.469092 -302.074834) (xy 283.473052 -302.02578) (xy 283.484829 -301.977996)
			(xy 283.50412 -301.93272) (xy 283.530423 -301.891124) (xy 283.563058 -301.854287) (xy 283.601179 -301.823162)
			(xy 283.6438 -301.798555) (xy 283.689816 -301.781103) (xy 283.738035 -301.771259) (xy 283.78721 -301.769278)
			(xy 283.836065 -301.77521) (xy 283.883336 -301.788902) (xy 283.927798 -301.81) (xy 283.968301 -301.837956)
			(xy 284.003794 -301.872048) (xy 284.033359 -301.911392) (xy 284.05623 -301.954969) (xy 284.071814 -302.00165)
			(xy 284.079709 -302.050227) (xy 284.080204 -302.074834) (xy 284.419052 -302.074834) (xy 284.423012 -302.02578)
			(xy 284.434789 -301.977996) (xy 284.45408 -301.93272) (xy 284.480383 -301.891124) (xy 284.513018 -301.854287)
			(xy 284.551139 -301.823162) (xy 284.59376 -301.798555) (xy 284.639776 -301.781103) (xy 284.687995 -301.771259)
			(xy 284.73717 -301.769278) (xy 284.786025 -301.77521) (xy 284.833296 -301.788902) (xy 284.877758 -301.81)
			(xy 284.918261 -301.837956) (xy 284.953754 -301.872048) (xy 284.983319 -301.911392) (xy 285.00619 -301.954969)
			(xy 285.021774 -302.00165) (xy 285.029669 -302.050227) (xy 285.030164 -302.074834) (xy 285.369012 -302.074834)
			(xy 285.372972 -302.02578) (xy 285.384749 -301.977996) (xy 285.40404 -301.93272) (xy 285.430343 -301.891124)
			(xy 285.462978 -301.854287) (xy 285.501099 -301.823162) (xy 285.54372 -301.798555) (xy 285.589736 -301.781103)
			(xy 285.637955 -301.771259) (xy 285.68713 -301.769278) (xy 285.735985 -301.77521) (xy 285.783256 -301.788902)
			(xy 285.827718 -301.81) (xy 285.868221 -301.837956) (xy 285.903714 -301.872048) (xy 285.933279 -301.911392)
			(xy 285.95615 -301.954969) (xy 285.971734 -302.00165) (xy 285.979629 -302.050227) (xy 285.980124 -302.074834)
			(xy 286.318972 -302.074834) (xy 286.322932 -302.02578) (xy 286.334709 -301.977996) (xy 286.354 -301.93272)
			(xy 286.380303 -301.891124) (xy 286.412938 -301.854287) (xy 286.451059 -301.823162) (xy 286.49368 -301.798555)
			(xy 286.539696 -301.781103) (xy 286.587915 -301.771259) (xy 286.63709 -301.769278) (xy 286.685945 -301.77521)
			(xy 286.733216 -301.788902) (xy 286.777678 -301.81) (xy 286.818181 -301.837956) (xy 286.853674 -301.872048)
			(xy 286.883239 -301.911392) (xy 286.90611 -301.954969) (xy 286.921694 -302.00165) (xy 286.929589 -302.050227)
			(xy 286.930084 -302.074834) (xy 287.268932 -302.074834) (xy 287.272892 -302.02578) (xy 287.284669 -301.977996)
			(xy 287.30396 -301.93272) (xy 287.330263 -301.891124) (xy 287.362898 -301.854287) (xy 287.401019 -301.823162)
			(xy 287.44364 -301.798555) (xy 287.489656 -301.781103) (xy 287.537875 -301.771259) (xy 287.58705 -301.769278)
			(xy 287.635905 -301.77521) (xy 287.683176 -301.788902) (xy 287.727638 -301.81) (xy 287.768141 -301.837956)
			(xy 287.803634 -301.872048) (xy 287.833199 -301.911392) (xy 287.85607 -301.954969) (xy 287.871654 -302.00165)
			(xy 287.879549 -302.050227) (xy 287.880044 -302.074834) (xy 288.218892 -302.074834) (xy 288.222852 -302.02578)
			(xy 288.234629 -301.977996) (xy 288.25392 -301.93272) (xy 288.280223 -301.891124) (xy 288.312858 -301.854287)
			(xy 288.350979 -301.823162) (xy 288.3936 -301.798555) (xy 288.439616 -301.781103) (xy 288.487835 -301.771259)
			(xy 288.53701 -301.769278) (xy 288.585865 -301.77521) (xy 288.633136 -301.788902) (xy 288.677598 -301.81)
			(xy 288.718101 -301.837956) (xy 288.753594 -301.872048) (xy 288.783159 -301.911392) (xy 288.80603 -301.954969)
			(xy 288.821614 -302.00165) (xy 288.829509 -302.050227) (xy 288.830004 -302.074834) (xy 289.169106 -302.074834)
			(xy 289.173066 -302.02578) (xy 289.184843 -301.977996) (xy 289.204134 -301.93272) (xy 289.230437 -301.891124)
			(xy 289.263072 -301.854287) (xy 289.301193 -301.823162) (xy 289.343814 -301.798555) (xy 289.38983 -301.781103)
			(xy 289.438049 -301.771259) (xy 289.487224 -301.769278) (xy 289.536079 -301.77521) (xy 289.58335 -301.788902)
			(xy 289.627812 -301.81) (xy 289.668315 -301.837956) (xy 289.703808 -301.872048) (xy 289.733373 -301.911392)
			(xy 289.756244 -301.954969) (xy 289.771828 -302.00165) (xy 289.779723 -302.050227) (xy 289.780218 -302.074834)
			(xy 290.119066 -302.074834) (xy 290.123026 -302.02578) (xy 290.134803 -301.977996) (xy 290.154094 -301.93272)
			(xy 290.180397 -301.891124) (xy 290.213032 -301.854287) (xy 290.251153 -301.823162) (xy 290.293774 -301.798555)
			(xy 290.33979 -301.781103) (xy 290.388009 -301.771259) (xy 290.437184 -301.769278) (xy 290.486039 -301.77521)
			(xy 290.53331 -301.788902) (xy 290.577772 -301.81) (xy 290.618275 -301.837956) (xy 290.653768 -301.872048)
			(xy 290.683333 -301.911392) (xy 290.706204 -301.954969) (xy 290.721788 -302.00165) (xy 290.729683 -302.050227)
			(xy 290.730178 -302.074834) (xy 292.018986 -302.074834) (xy 292.022946 -302.02578) (xy 292.034723 -301.977996)
			(xy 292.054014 -301.93272) (xy 292.080317 -301.891124) (xy 292.112952 -301.854287) (xy 292.151073 -301.823162)
			(xy 292.193694 -301.798555) (xy 292.23971 -301.781103) (xy 292.287929 -301.771259) (xy 292.337104 -301.769278)
			(xy 292.385959 -301.77521) (xy 292.43323 -301.788902) (xy 292.477692 -301.81) (xy 292.518195 -301.837956)
			(xy 292.553688 -301.872048) (xy 292.583253 -301.911392) (xy 292.606124 -301.954969) (xy 292.621708 -302.00165)
			(xy 292.629603 -302.050227) (xy 292.630098 -302.074834) (xy 292.968946 -302.074834) (xy 292.972906 -302.02578)
			(xy 292.984683 -301.977996) (xy 293.003974 -301.93272) (xy 293.030277 -301.891124) (xy 293.062912 -301.854287)
			(xy 293.101033 -301.823162) (xy 293.143654 -301.798555) (xy 293.18967 -301.781103) (xy 293.237889 -301.771259)
			(xy 293.287064 -301.769278) (xy 293.335919 -301.77521) (xy 293.38319 -301.788902) (xy 293.427652 -301.81)
			(xy 293.468155 -301.837956) (xy 293.503648 -301.872048) (xy 293.533213 -301.911392) (xy 293.556084 -301.954969)
			(xy 293.571668 -302.00165) (xy 293.579563 -302.050227) (xy 293.580058 -302.074834) (xy 293.918906 -302.074834)
			(xy 293.922866 -302.02578) (xy 293.934643 -301.977996) (xy 293.953934 -301.93272) (xy 293.980237 -301.891124)
			(xy 294.012872 -301.854287) (xy 294.050993 -301.823162) (xy 294.093614 -301.798555) (xy 294.13963 -301.781103)
			(xy 294.187849 -301.771259) (xy 294.237024 -301.769278) (xy 294.285879 -301.77521) (xy 294.33315 -301.788902)
			(xy 294.377612 -301.81) (xy 294.418115 -301.837956) (xy 294.453608 -301.872048) (xy 294.483173 -301.911392)
			(xy 294.506044 -301.954969) (xy 294.521628 -302.00165) (xy 294.529523 -302.050227) (xy 294.530018 -302.074834)
			(xy 294.86912 -302.074834) (xy 294.87308 -302.02578) (xy 294.884857 -301.977996) (xy 294.904148 -301.93272)
			(xy 294.930451 -301.891124) (xy 294.963086 -301.854287) (xy 295.001207 -301.823162) (xy 295.043828 -301.798555)
			(xy 295.089844 -301.781103) (xy 295.138063 -301.771259) (xy 295.187238 -301.769278) (xy 295.236093 -301.77521)
			(xy 295.283364 -301.788902) (xy 295.327826 -301.81) (xy 295.368329 -301.837956) (xy 295.403822 -301.872048)
			(xy 295.433387 -301.911392) (xy 295.456258 -301.954969) (xy 295.471842 -302.00165) (xy 295.479737 -302.050227)
			(xy 295.480232 -302.074834) (xy 295.81908 -302.074834) (xy 295.82304 -302.02578) (xy 295.834817 -301.977996)
			(xy 295.854108 -301.93272) (xy 295.880411 -301.891124) (xy 295.913046 -301.854287) (xy 295.951167 -301.823162)
			(xy 295.993788 -301.798555) (xy 296.039804 -301.781103) (xy 296.088023 -301.771259) (xy 296.137198 -301.769278)
			(xy 296.186053 -301.77521) (xy 296.233324 -301.788902) (xy 296.277786 -301.81) (xy 296.318289 -301.837956)
			(xy 296.353782 -301.872048) (xy 296.383347 -301.911392) (xy 296.406218 -301.954969) (xy 296.421802 -302.00165)
			(xy 296.429697 -302.050227) (xy 296.430192 -302.074834) (xy 296.76904 -302.074834) (xy 296.773 -302.02578)
			(xy 296.784777 -301.977996) (xy 296.804068 -301.93272) (xy 296.830371 -301.891124) (xy 296.863006 -301.854287)
			(xy 296.901127 -301.823162) (xy 296.943748 -301.798555) (xy 296.989764 -301.781103) (xy 297.037983 -301.771259)
			(xy 297.087158 -301.769278) (xy 297.136013 -301.77521) (xy 297.183284 -301.788902) (xy 297.227746 -301.81)
			(xy 297.268249 -301.837956) (xy 297.303742 -301.872048) (xy 297.333307 -301.911392) (xy 297.356178 -301.954969)
			(xy 297.371762 -302.00165) (xy 297.379657 -302.050227) (xy 297.380152 -302.074834) (xy 297.719 -302.074834)
			(xy 297.72296 -302.02578) (xy 297.734737 -301.977996) (xy 297.754028 -301.93272) (xy 297.780331 -301.891124)
			(xy 297.812966 -301.854287) (xy 297.851087 -301.823162) (xy 297.893708 -301.798555) (xy 297.939724 -301.781103)
			(xy 297.987943 -301.771259) (xy 298.037118 -301.769278) (xy 298.085973 -301.77521) (xy 298.133244 -301.788902)
			(xy 298.177706 -301.81) (xy 298.218209 -301.837956) (xy 298.253702 -301.872048) (xy 298.283267 -301.911392)
			(xy 298.306138 -301.954969) (xy 298.321722 -302.00165) (xy 298.329617 -302.050227) (xy 298.330112 -302.074834)
			(xy 298.66896 -302.074834) (xy 298.67292 -302.02578) (xy 298.684697 -301.977996) (xy 298.703988 -301.93272)
			(xy 298.730291 -301.891124) (xy 298.762926 -301.854287) (xy 298.801047 -301.823162) (xy 298.843668 -301.798555)
			(xy 298.889684 -301.781103) (xy 298.937903 -301.771259) (xy 298.987078 -301.769278) (xy 299.035933 -301.77521)
			(xy 299.083204 -301.788902) (xy 299.127666 -301.81) (xy 299.168169 -301.837956) (xy 299.203662 -301.872048)
			(xy 299.233227 -301.911392) (xy 299.256098 -301.954969) (xy 299.271682 -302.00165) (xy 299.279577 -302.050227)
			(xy 299.280072 -302.074834) (xy 299.61892 -302.074834) (xy 299.62288 -302.02578) (xy 299.634657 -301.977996)
			(xy 299.653948 -301.93272) (xy 299.680251 -301.891124) (xy 299.712886 -301.854287) (xy 299.751007 -301.823162)
			(xy 299.793628 -301.798555) (xy 299.839644 -301.781103) (xy 299.887863 -301.771259) (xy 299.937038 -301.769278)
			(xy 299.985893 -301.77521) (xy 300.033164 -301.788902) (xy 300.077626 -301.81) (xy 300.118129 -301.837956)
			(xy 300.153622 -301.872048) (xy 300.183187 -301.911392) (xy 300.206058 -301.954969) (xy 300.221642 -302.00165)
			(xy 300.229537 -302.050227) (xy 300.230032 -302.074834) (xy 300.56888 -302.074834) (xy 300.57284 -302.02578)
			(xy 300.584617 -301.977996) (xy 300.603908 -301.93272) (xy 300.630211 -301.891124) (xy 300.662846 -301.854287)
			(xy 300.700967 -301.823162) (xy 300.743588 -301.798555) (xy 300.789604 -301.781103) (xy 300.837823 -301.771259)
			(xy 300.886998 -301.769278) (xy 300.935853 -301.77521) (xy 300.983124 -301.788902) (xy 301.027586 -301.81)
			(xy 301.068089 -301.837956) (xy 301.103582 -301.872048) (xy 301.133147 -301.911392) (xy 301.156018 -301.954969)
			(xy 301.171602 -302.00165) (xy 301.179497 -302.050227) (xy 301.179992 -302.074834) (xy 301.519094 -302.074834)
			(xy 301.523054 -302.02578) (xy 301.534831 -301.977996) (xy 301.554122 -301.93272) (xy 301.580425 -301.891124)
			(xy 301.61306 -301.854287) (xy 301.651181 -301.823162) (xy 301.693802 -301.798555) (xy 301.739818 -301.781103)
			(xy 301.788037 -301.771259) (xy 301.837212 -301.769278) (xy 301.886067 -301.77521) (xy 301.933338 -301.788902)
			(xy 301.9778 -301.81) (xy 302.018303 -301.837956) (xy 302.053796 -301.872048) (xy 302.083361 -301.911392)
			(xy 302.106232 -301.954969) (xy 302.121816 -302.00165) (xy 302.129711 -302.050227) (xy 302.130206 -302.074834)
			(xy 302.469054 -302.074834) (xy 302.473014 -302.02578) (xy 302.484791 -301.977996) (xy 302.504082 -301.93272)
			(xy 302.530385 -301.891124) (xy 302.56302 -301.854287) (xy 302.601141 -301.823162) (xy 302.643762 -301.798555)
			(xy 302.689778 -301.781103) (xy 302.737997 -301.771259) (xy 302.787172 -301.769278) (xy 302.836027 -301.77521)
			(xy 302.883298 -301.788902) (xy 302.92776 -301.81) (xy 302.968263 -301.837956) (xy 303.003756 -301.872048)
			(xy 303.033321 -301.911392) (xy 303.056192 -301.954969) (xy 303.071776 -302.00165) (xy 303.079671 -302.050227)
			(xy 303.080166 -302.074834) (xy 303.419014 -302.074834) (xy 303.422974 -302.02578) (xy 303.434751 -301.977996)
			(xy 303.454042 -301.93272) (xy 303.480345 -301.891124) (xy 303.51298 -301.854287) (xy 303.551101 -301.823162)
			(xy 303.593722 -301.798555) (xy 303.639738 -301.781103) (xy 303.687957 -301.771259) (xy 303.737132 -301.769278)
			(xy 303.785987 -301.77521) (xy 303.833258 -301.788902) (xy 303.87772 -301.81) (xy 303.918223 -301.837956)
			(xy 303.953716 -301.872048) (xy 303.983281 -301.911392) (xy 304.006152 -301.954969) (xy 304.021736 -302.00165)
			(xy 304.029631 -302.050227) (xy 304.030126 -302.074834) (xy 304.368974 -302.074834) (xy 304.372934 -302.02578)
			(xy 304.384711 -301.977996) (xy 304.404002 -301.93272) (xy 304.430305 -301.891124) (xy 304.46294 -301.854287)
			(xy 304.501061 -301.823162) (xy 304.543682 -301.798555) (xy 304.589698 -301.781103) (xy 304.637917 -301.771259)
			(xy 304.687092 -301.769278) (xy 304.735947 -301.77521) (xy 304.783218 -301.788902) (xy 304.82768 -301.81)
			(xy 304.868183 -301.837956) (xy 304.903676 -301.872048) (xy 304.933241 -301.911392) (xy 304.956112 -301.954969)
			(xy 304.971696 -302.00165) (xy 304.979591 -302.050227) (xy 304.980086 -302.074834) (xy 305.318934 -302.074834)
			(xy 305.322894 -302.02578) (xy 305.334671 -301.977996) (xy 305.353962 -301.93272) (xy 305.380265 -301.891124)
			(xy 305.4129 -301.854287) (xy 305.451021 -301.823162) (xy 305.493642 -301.798555) (xy 305.539658 -301.781103)
			(xy 305.587877 -301.771259) (xy 305.637052 -301.769278) (xy 305.685907 -301.77521) (xy 305.733178 -301.788902)
			(xy 305.77764 -301.81) (xy 305.818143 -301.837956) (xy 305.853636 -301.872048) (xy 305.883201 -301.911392)
			(xy 305.906072 -301.954969) (xy 305.921656 -302.00165) (xy 305.929551 -302.050227) (xy 305.930046 -302.074834)
			(xy 306.268894 -302.074834) (xy 306.272854 -302.02578) (xy 306.284631 -301.977996) (xy 306.303922 -301.93272)
			(xy 306.330225 -301.891124) (xy 306.36286 -301.854287) (xy 306.400981 -301.823162) (xy 306.443602 -301.798555)
			(xy 306.489618 -301.781103) (xy 306.537837 -301.771259) (xy 306.587012 -301.769278) (xy 306.635867 -301.77521)
			(xy 306.683138 -301.788902) (xy 306.7276 -301.81) (xy 306.768103 -301.837956) (xy 306.803596 -301.872048)
			(xy 306.833161 -301.911392) (xy 306.856032 -301.954969) (xy 306.871616 -302.00165) (xy 306.879511 -302.050227)
			(xy 306.880006 -302.074834) (xy 307.219108 -302.074834) (xy 307.223068 -302.02578) (xy 307.234845 -301.977996)
			(xy 307.254136 -301.93272) (xy 307.280439 -301.891124) (xy 307.313074 -301.854287) (xy 307.351195 -301.823162)
			(xy 307.393816 -301.798555) (xy 307.439832 -301.781103) (xy 307.488051 -301.771259) (xy 307.537226 -301.769278)
			(xy 307.586081 -301.77521) (xy 307.633352 -301.788902) (xy 307.677814 -301.81) (xy 307.718317 -301.837956)
			(xy 307.75381 -301.872048) (xy 307.783375 -301.911392) (xy 307.806246 -301.954969) (xy 307.82183 -302.00165)
			(xy 307.829725 -302.050227) (xy 307.83022 -302.074834) (xy 308.169068 -302.074834) (xy 308.173028 -302.02578)
			(xy 308.184805 -301.977996) (xy 308.204096 -301.93272) (xy 308.230399 -301.891124) (xy 308.263034 -301.854287)
			(xy 308.301155 -301.823162) (xy 308.343776 -301.798555) (xy 308.389792 -301.781103) (xy 308.438011 -301.771259)
			(xy 308.487186 -301.769278) (xy 308.536041 -301.77521) (xy 308.583312 -301.788902) (xy 308.627774 -301.81)
			(xy 308.668277 -301.837956) (xy 308.70377 -301.872048) (xy 308.733335 -301.911392) (xy 308.756206 -301.954969)
			(xy 308.77179 -302.00165) (xy 308.779685 -302.050227) (xy 308.78018 -302.074834) (xy 309.119028 -302.074834)
			(xy 309.122988 -302.02578) (xy 309.134765 -301.977996) (xy 309.154056 -301.93272) (xy 309.180359 -301.891124)
			(xy 309.212994 -301.854287) (xy 309.251115 -301.823162) (xy 309.293736 -301.798555) (xy 309.339752 -301.781103)
			(xy 309.387971 -301.771259) (xy 309.437146 -301.769278) (xy 309.486001 -301.77521) (xy 309.533272 -301.788902)
			(xy 309.577734 -301.81) (xy 309.618237 -301.837956) (xy 309.65373 -301.872048) (xy 309.683295 -301.911392)
			(xy 309.706166 -301.954969) (xy 309.72175 -302.00165) (xy 309.729645 -302.050227) (xy 309.73014 -302.074834)
			(xy 310.068988 -302.074834) (xy 310.072948 -302.02578) (xy 310.084725 -301.977996) (xy 310.104016 -301.93272)
			(xy 310.130319 -301.891124) (xy 310.162954 -301.854287) (xy 310.201075 -301.823162) (xy 310.243696 -301.798555)
			(xy 310.289712 -301.781103) (xy 310.337931 -301.771259) (xy 310.387106 -301.769278) (xy 310.435961 -301.77521)
			(xy 310.483232 -301.788902) (xy 310.527694 -301.81) (xy 310.568197 -301.837956) (xy 310.60369 -301.872048)
			(xy 310.633255 -301.911392) (xy 310.656126 -301.954969) (xy 310.67171 -302.00165) (xy 310.679605 -302.050227)
			(xy 310.6801 -302.074834) (xy 311.018948 -302.074834) (xy 311.022908 -302.02578) (xy 311.034685 -301.977996)
			(xy 311.053976 -301.93272) (xy 311.080279 -301.891124) (xy 311.112914 -301.854287) (xy 311.151035 -301.823162)
			(xy 311.193656 -301.798555) (xy 311.239672 -301.781103) (xy 311.287891 -301.771259) (xy 311.337066 -301.769278)
			(xy 311.385921 -301.77521) (xy 311.433192 -301.788902) (xy 311.477654 -301.81) (xy 311.518157 -301.837956)
			(xy 311.55365 -301.872048) (xy 311.583215 -301.911392) (xy 311.606086 -301.954969) (xy 311.62167 -302.00165)
			(xy 311.629565 -302.050227) (xy 311.63006 -302.074834) (xy 311.968908 -302.074834) (xy 311.972868 -302.02578)
			(xy 311.984645 -301.977996) (xy 312.003936 -301.93272) (xy 312.030239 -301.891124) (xy 312.062874 -301.854287)
			(xy 312.100995 -301.823162) (xy 312.143616 -301.798555) (xy 312.189632 -301.781103) (xy 312.237851 -301.771259)
			(xy 312.287026 -301.769278) (xy 312.335881 -301.77521) (xy 312.383152 -301.788902) (xy 312.427614 -301.81)
			(xy 312.468117 -301.837956) (xy 312.50361 -301.872048) (xy 312.533175 -301.911392) (xy 312.556046 -301.954969)
			(xy 312.57163 -302.00165) (xy 312.579525 -302.050227) (xy 312.58002 -302.074834) (xy 312.919122 -302.074834)
			(xy 312.923082 -302.02578) (xy 312.934859 -301.977996) (xy 312.95415 -301.93272) (xy 312.980453 -301.891124)
			(xy 313.013088 -301.854287) (xy 313.051209 -301.823162) (xy 313.09383 -301.798555) (xy 313.139846 -301.781103)
			(xy 313.188065 -301.771259) (xy 313.23724 -301.769278) (xy 313.286095 -301.77521) (xy 313.333366 -301.788902)
			(xy 313.377828 -301.81) (xy 313.418331 -301.837956) (xy 313.453824 -301.872048) (xy 313.483389 -301.911392)
			(xy 313.50626 -301.954969) (xy 313.521844 -302.00165) (xy 313.529739 -302.050227) (xy 313.530234 -302.074834)
			(xy 313.869082 -302.074834) (xy 313.873042 -302.02578) (xy 313.884819 -301.977996) (xy 313.90411 -301.93272)
			(xy 313.930413 -301.891124) (xy 313.963048 -301.854287) (xy 314.001169 -301.823162) (xy 314.04379 -301.798555)
			(xy 314.089806 -301.781103) (xy 314.138025 -301.771259) (xy 314.1872 -301.769278) (xy 314.236055 -301.77521)
			(xy 314.283326 -301.788902) (xy 314.327788 -301.81) (xy 314.368291 -301.837956) (xy 314.403784 -301.872048)
			(xy 314.433349 -301.911392) (xy 314.45622 -301.954969) (xy 314.471804 -302.00165) (xy 314.479699 -302.050227)
			(xy 314.480194 -302.074834) (xy 314.819042 -302.074834) (xy 314.823002 -302.02578) (xy 314.834779 -301.977996)
			(xy 314.85407 -301.93272) (xy 314.880373 -301.891124) (xy 314.913008 -301.854287) (xy 314.951129 -301.823162)
			(xy 314.99375 -301.798555) (xy 315.039766 -301.781103) (xy 315.087985 -301.771259) (xy 315.13716 -301.769278)
			(xy 315.186015 -301.77521) (xy 315.233286 -301.788902) (xy 315.277748 -301.81) (xy 315.318251 -301.837956)
			(xy 315.353744 -301.872048) (xy 315.383309 -301.911392) (xy 315.40618 -301.954969) (xy 315.421764 -302.00165)
			(xy 315.429659 -302.050227) (xy 315.430154 -302.074834) (xy 315.429659 -302.099441) (xy 315.421764 -302.148018)
			(xy 315.40618 -302.194699) (xy 315.383309 -302.238276) (xy 315.353744 -302.27762) (xy 315.318251 -302.311712)
			(xy 315.277748 -302.339668) (xy 315.233286 -302.360766) (xy 315.186015 -302.374458) (xy 315.13716 -302.38039)
			(xy 315.087985 -302.378409) (xy 315.039766 -302.368565) (xy 314.99375 -302.351113) (xy 314.951129 -302.326506)
			(xy 314.913008 -302.295381) (xy 314.880373 -302.258544) (xy 314.85407 -302.216948) (xy 314.834779 -302.171672)
			(xy 314.823002 -302.123888) (xy 314.819042 -302.074834) (xy 314.480194 -302.074834) (xy 314.479699 -302.099441)
			(xy 314.471804 -302.148018) (xy 314.45622 -302.194699) (xy 314.433349 -302.238276) (xy 314.403784 -302.27762)
			(xy 314.368291 -302.311712) (xy 314.327788 -302.339668) (xy 314.283326 -302.360766) (xy 314.236055 -302.374458)
			(xy 314.1872 -302.38039) (xy 314.138025 -302.378409) (xy 314.089806 -302.368565) (xy 314.04379 -302.351113)
			(xy 314.001169 -302.326506) (xy 313.963048 -302.295381) (xy 313.930413 -302.258544) (xy 313.90411 -302.216948)
			(xy 313.884819 -302.171672) (xy 313.873042 -302.123888) (xy 313.869082 -302.074834) (xy 313.530234 -302.074834)
			(xy 313.529739 -302.099441) (xy 313.521844 -302.148018) (xy 313.50626 -302.194699) (xy 313.483389 -302.238276)
			(xy 313.453824 -302.27762) (xy 313.418331 -302.311712) (xy 313.377828 -302.339668) (xy 313.333366 -302.360766)
			(xy 313.286095 -302.374458) (xy 313.23724 -302.38039) (xy 313.188065 -302.378409) (xy 313.139846 -302.368565)
			(xy 313.09383 -302.351113) (xy 313.051209 -302.326506) (xy 313.013088 -302.295381) (xy 312.980453 -302.258544)
			(xy 312.95415 -302.216948) (xy 312.934859 -302.171672) (xy 312.923082 -302.123888) (xy 312.919122 -302.074834)
			(xy 312.58002 -302.074834) (xy 312.579525 -302.099441) (xy 312.57163 -302.148018) (xy 312.556046 -302.194699)
			(xy 312.533175 -302.238276) (xy 312.50361 -302.27762) (xy 312.468117 -302.311712) (xy 312.427614 -302.339668)
			(xy 312.383152 -302.360766) (xy 312.335881 -302.374458) (xy 312.287026 -302.38039) (xy 312.237851 -302.378409)
			(xy 312.189632 -302.368565) (xy 312.143616 -302.351113) (xy 312.100995 -302.326506) (xy 312.062874 -302.295381)
			(xy 312.030239 -302.258544) (xy 312.003936 -302.216948) (xy 311.984645 -302.171672) (xy 311.972868 -302.123888)
			(xy 311.968908 -302.074834) (xy 311.63006 -302.074834) (xy 311.629565 -302.099441) (xy 311.62167 -302.148018)
			(xy 311.606086 -302.194699) (xy 311.583215 -302.238276) (xy 311.55365 -302.27762) (xy 311.518157 -302.311712)
			(xy 311.477654 -302.339668) (xy 311.433192 -302.360766) (xy 311.385921 -302.374458) (xy 311.337066 -302.38039)
			(xy 311.287891 -302.378409) (xy 311.239672 -302.368565) (xy 311.193656 -302.351113) (xy 311.151035 -302.326506)
			(xy 311.112914 -302.295381) (xy 311.080279 -302.258544) (xy 311.053976 -302.216948) (xy 311.034685 -302.171672)
			(xy 311.022908 -302.123888) (xy 311.018948 -302.074834) (xy 310.6801 -302.074834) (xy 310.679605 -302.099441)
			(xy 310.67171 -302.148018) (xy 310.656126 -302.194699) (xy 310.633255 -302.238276) (xy 310.60369 -302.27762)
			(xy 310.568197 -302.311712) (xy 310.527694 -302.339668) (xy 310.483232 -302.360766) (xy 310.435961 -302.374458)
			(xy 310.387106 -302.38039) (xy 310.337931 -302.378409) (xy 310.289712 -302.368565) (xy 310.243696 -302.351113)
			(xy 310.201075 -302.326506) (xy 310.162954 -302.295381) (xy 310.130319 -302.258544) (xy 310.104016 -302.216948)
			(xy 310.084725 -302.171672) (xy 310.072948 -302.123888) (xy 310.068988 -302.074834) (xy 309.73014 -302.074834)
			(xy 309.729645 -302.099441) (xy 309.72175 -302.148018) (xy 309.706166 -302.194699) (xy 309.683295 -302.238276)
			(xy 309.65373 -302.27762) (xy 309.618237 -302.311712) (xy 309.577734 -302.339668) (xy 309.533272 -302.360766)
			(xy 309.486001 -302.374458) (xy 309.437146 -302.38039) (xy 309.387971 -302.378409) (xy 309.339752 -302.368565)
			(xy 309.293736 -302.351113) (xy 309.251115 -302.326506) (xy 309.212994 -302.295381) (xy 309.180359 -302.258544)
			(xy 309.154056 -302.216948) (xy 309.134765 -302.171672) (xy 309.122988 -302.123888) (xy 309.119028 -302.074834)
			(xy 308.78018 -302.074834) (xy 308.779685 -302.099441) (xy 308.77179 -302.148018) (xy 308.756206 -302.194699)
			(xy 308.733335 -302.238276) (xy 308.70377 -302.27762) (xy 308.668277 -302.311712) (xy 308.627774 -302.339668)
			(xy 308.583312 -302.360766) (xy 308.536041 -302.374458) (xy 308.487186 -302.38039) (xy 308.438011 -302.378409)
			(xy 308.389792 -302.368565) (xy 308.343776 -302.351113) (xy 308.301155 -302.326506) (xy 308.263034 -302.295381)
			(xy 308.230399 -302.258544) (xy 308.204096 -302.216948) (xy 308.184805 -302.171672) (xy 308.173028 -302.123888)
			(xy 308.169068 -302.074834) (xy 307.83022 -302.074834) (xy 307.829725 -302.099441) (xy 307.82183 -302.148018)
			(xy 307.806246 -302.194699) (xy 307.783375 -302.238276) (xy 307.75381 -302.27762) (xy 307.718317 -302.311712)
			(xy 307.677814 -302.339668) (xy 307.633352 -302.360766) (xy 307.586081 -302.374458) (xy 307.537226 -302.38039)
			(xy 307.488051 -302.378409) (xy 307.439832 -302.368565) (xy 307.393816 -302.351113) (xy 307.351195 -302.326506)
			(xy 307.313074 -302.295381) (xy 307.280439 -302.258544) (xy 307.254136 -302.216948) (xy 307.234845 -302.171672)
			(xy 307.223068 -302.123888) (xy 307.219108 -302.074834) (xy 306.880006 -302.074834) (xy 306.879511 -302.099441)
			(xy 306.871616 -302.148018) (xy 306.856032 -302.194699) (xy 306.833161 -302.238276) (xy 306.803596 -302.27762)
			(xy 306.768103 -302.311712) (xy 306.7276 -302.339668) (xy 306.683138 -302.360766) (xy 306.635867 -302.374458)
			(xy 306.587012 -302.38039) (xy 306.537837 -302.378409) (xy 306.489618 -302.368565) (xy 306.443602 -302.351113)
			(xy 306.400981 -302.326506) (xy 306.36286 -302.295381) (xy 306.330225 -302.258544) (xy 306.303922 -302.216948)
			(xy 306.284631 -302.171672) (xy 306.272854 -302.123888) (xy 306.268894 -302.074834) (xy 305.930046 -302.074834)
			(xy 305.929551 -302.099441) (xy 305.921656 -302.148018) (xy 305.906072 -302.194699) (xy 305.883201 -302.238276)
			(xy 305.853636 -302.27762) (xy 305.818143 -302.311712) (xy 305.77764 -302.339668) (xy 305.733178 -302.360766)
			(xy 305.685907 -302.374458) (xy 305.637052 -302.38039) (xy 305.587877 -302.378409) (xy 305.539658 -302.368565)
			(xy 305.493642 -302.351113) (xy 305.451021 -302.326506) (xy 305.4129 -302.295381) (xy 305.380265 -302.258544)
			(xy 305.353962 -302.216948) (xy 305.334671 -302.171672) (xy 305.322894 -302.123888) (xy 305.318934 -302.074834)
			(xy 304.980086 -302.074834) (xy 304.979591 -302.099441) (xy 304.971696 -302.148018) (xy 304.956112 -302.194699)
			(xy 304.933241 -302.238276) (xy 304.903676 -302.27762) (xy 304.868183 -302.311712) (xy 304.82768 -302.339668)
			(xy 304.783218 -302.360766) (xy 304.735947 -302.374458) (xy 304.687092 -302.38039) (xy 304.637917 -302.378409)
			(xy 304.589698 -302.368565) (xy 304.543682 -302.351113) (xy 304.501061 -302.326506) (xy 304.46294 -302.295381)
			(xy 304.430305 -302.258544) (xy 304.404002 -302.216948) (xy 304.384711 -302.171672) (xy 304.372934 -302.123888)
			(xy 304.368974 -302.074834) (xy 304.030126 -302.074834) (xy 304.029631 -302.099441) (xy 304.021736 -302.148018)
			(xy 304.006152 -302.194699) (xy 303.983281 -302.238276) (xy 303.953716 -302.27762) (xy 303.918223 -302.311712)
			(xy 303.87772 -302.339668) (xy 303.833258 -302.360766) (xy 303.785987 -302.374458) (xy 303.737132 -302.38039)
			(xy 303.687957 -302.378409) (xy 303.639738 -302.368565) (xy 303.593722 -302.351113) (xy 303.551101 -302.326506)
			(xy 303.51298 -302.295381) (xy 303.480345 -302.258544) (xy 303.454042 -302.216948) (xy 303.434751 -302.171672)
			(xy 303.422974 -302.123888) (xy 303.419014 -302.074834) (xy 303.080166 -302.074834) (xy 303.079671 -302.099441)
			(xy 303.071776 -302.148018) (xy 303.056192 -302.194699) (xy 303.033321 -302.238276) (xy 303.003756 -302.27762)
			(xy 302.968263 -302.311712) (xy 302.92776 -302.339668) (xy 302.883298 -302.360766) (xy 302.836027 -302.374458)
			(xy 302.787172 -302.38039) (xy 302.737997 -302.378409) (xy 302.689778 -302.368565) (xy 302.643762 -302.351113)
			(xy 302.601141 -302.326506) (xy 302.56302 -302.295381) (xy 302.530385 -302.258544) (xy 302.504082 -302.216948)
			(xy 302.484791 -302.171672) (xy 302.473014 -302.123888) (xy 302.469054 -302.074834) (xy 302.130206 -302.074834)
			(xy 302.129711 -302.099441) (xy 302.121816 -302.148018) (xy 302.106232 -302.194699) (xy 302.083361 -302.238276)
			(xy 302.053796 -302.27762) (xy 302.018303 -302.311712) (xy 301.9778 -302.339668) (xy 301.933338 -302.360766)
			(xy 301.886067 -302.374458) (xy 301.837212 -302.38039) (xy 301.788037 -302.378409) (xy 301.739818 -302.368565)
			(xy 301.693802 -302.351113) (xy 301.651181 -302.326506) (xy 301.61306 -302.295381) (xy 301.580425 -302.258544)
			(xy 301.554122 -302.216948) (xy 301.534831 -302.171672) (xy 301.523054 -302.123888) (xy 301.519094 -302.074834)
			(xy 301.179992 -302.074834) (xy 301.179497 -302.099441) (xy 301.171602 -302.148018) (xy 301.156018 -302.194699)
			(xy 301.133147 -302.238276) (xy 301.103582 -302.27762) (xy 301.068089 -302.311712) (xy 301.027586 -302.339668)
			(xy 300.983124 -302.360766) (xy 300.935853 -302.374458) (xy 300.886998 -302.38039) (xy 300.837823 -302.378409)
			(xy 300.789604 -302.368565) (xy 300.743588 -302.351113) (xy 300.700967 -302.326506) (xy 300.662846 -302.295381)
			(xy 300.630211 -302.258544) (xy 300.603908 -302.216948) (xy 300.584617 -302.171672) (xy 300.57284 -302.123888)
			(xy 300.56888 -302.074834) (xy 300.230032 -302.074834) (xy 300.229537 -302.099441) (xy 300.221642 -302.148018)
			(xy 300.206058 -302.194699) (xy 300.183187 -302.238276) (xy 300.153622 -302.27762) (xy 300.118129 -302.311712)
			(xy 300.077626 -302.339668) (xy 300.033164 -302.360766) (xy 299.985893 -302.374458) (xy 299.937038 -302.38039)
			(xy 299.887863 -302.378409) (xy 299.839644 -302.368565) (xy 299.793628 -302.351113) (xy 299.751007 -302.326506)
			(xy 299.712886 -302.295381) (xy 299.680251 -302.258544) (xy 299.653948 -302.216948) (xy 299.634657 -302.171672)
			(xy 299.62288 -302.123888) (xy 299.61892 -302.074834) (xy 299.280072 -302.074834) (xy 299.279577 -302.099441)
			(xy 299.271682 -302.148018) (xy 299.256098 -302.194699) (xy 299.233227 -302.238276) (xy 299.203662 -302.27762)
			(xy 299.168169 -302.311712) (xy 299.127666 -302.339668) (xy 299.083204 -302.360766) (xy 299.035933 -302.374458)
			(xy 298.987078 -302.38039) (xy 298.937903 -302.378409) (xy 298.889684 -302.368565) (xy 298.843668 -302.351113)
			(xy 298.801047 -302.326506) (xy 298.762926 -302.295381) (xy 298.730291 -302.258544) (xy 298.703988 -302.216948)
			(xy 298.684697 -302.171672) (xy 298.67292 -302.123888) (xy 298.66896 -302.074834) (xy 298.330112 -302.074834)
			(xy 298.329617 -302.099441) (xy 298.321722 -302.148018) (xy 298.306138 -302.194699) (xy 298.283267 -302.238276)
			(xy 298.253702 -302.27762) (xy 298.218209 -302.311712) (xy 298.177706 -302.339668) (xy 298.133244 -302.360766)
			(xy 298.085973 -302.374458) (xy 298.037118 -302.38039) (xy 297.987943 -302.378409) (xy 297.939724 -302.368565)
			(xy 297.893708 -302.351113) (xy 297.851087 -302.326506) (xy 297.812966 -302.295381) (xy 297.780331 -302.258544)
			(xy 297.754028 -302.216948) (xy 297.734737 -302.171672) (xy 297.72296 -302.123888) (xy 297.719 -302.074834)
			(xy 297.380152 -302.074834) (xy 297.379657 -302.099441) (xy 297.371762 -302.148018) (xy 297.356178 -302.194699)
			(xy 297.333307 -302.238276) (xy 297.303742 -302.27762) (xy 297.268249 -302.311712) (xy 297.227746 -302.339668)
			(xy 297.183284 -302.360766) (xy 297.136013 -302.374458) (xy 297.087158 -302.38039) (xy 297.037983 -302.378409)
			(xy 296.989764 -302.368565) (xy 296.943748 -302.351113) (xy 296.901127 -302.326506) (xy 296.863006 -302.295381)
			(xy 296.830371 -302.258544) (xy 296.804068 -302.216948) (xy 296.784777 -302.171672) (xy 296.773 -302.123888)
			(xy 296.76904 -302.074834) (xy 296.430192 -302.074834) (xy 296.429697 -302.099441) (xy 296.421802 -302.148018)
			(xy 296.406218 -302.194699) (xy 296.383347 -302.238276) (xy 296.353782 -302.27762) (xy 296.318289 -302.311712)
			(xy 296.277786 -302.339668) (xy 296.233324 -302.360766) (xy 296.186053 -302.374458) (xy 296.137198 -302.38039)
			(xy 296.088023 -302.378409) (xy 296.039804 -302.368565) (xy 295.993788 -302.351113) (xy 295.951167 -302.326506)
			(xy 295.913046 -302.295381) (xy 295.880411 -302.258544) (xy 295.854108 -302.216948) (xy 295.834817 -302.171672)
			(xy 295.82304 -302.123888) (xy 295.81908 -302.074834) (xy 295.480232 -302.074834) (xy 295.479737 -302.099441)
			(xy 295.471842 -302.148018) (xy 295.456258 -302.194699) (xy 295.433387 -302.238276) (xy 295.403822 -302.27762)
			(xy 295.368329 -302.311712) (xy 295.327826 -302.339668) (xy 295.283364 -302.360766) (xy 295.236093 -302.374458)
			(xy 295.187238 -302.38039) (xy 295.138063 -302.378409) (xy 295.089844 -302.368565) (xy 295.043828 -302.351113)
			(xy 295.001207 -302.326506) (xy 294.963086 -302.295381) (xy 294.930451 -302.258544) (xy 294.904148 -302.216948)
			(xy 294.884857 -302.171672) (xy 294.87308 -302.123888) (xy 294.86912 -302.074834) (xy 294.530018 -302.074834)
			(xy 294.529523 -302.099441) (xy 294.521628 -302.148018) (xy 294.506044 -302.194699) (xy 294.483173 -302.238276)
			(xy 294.453608 -302.27762) (xy 294.418115 -302.311712) (xy 294.377612 -302.339668) (xy 294.33315 -302.360766)
			(xy 294.285879 -302.374458) (xy 294.237024 -302.38039) (xy 294.187849 -302.378409) (xy 294.13963 -302.368565)
			(xy 294.093614 -302.351113) (xy 294.050993 -302.326506) (xy 294.012872 -302.295381) (xy 293.980237 -302.258544)
			(xy 293.953934 -302.216948) (xy 293.934643 -302.171672) (xy 293.922866 -302.123888) (xy 293.918906 -302.074834)
			(xy 293.580058 -302.074834) (xy 293.579563 -302.099441) (xy 293.571668 -302.148018) (xy 293.556084 -302.194699)
			(xy 293.533213 -302.238276) (xy 293.503648 -302.27762) (xy 293.468155 -302.311712) (xy 293.427652 -302.339668)
			(xy 293.38319 -302.360766) (xy 293.335919 -302.374458) (xy 293.287064 -302.38039) (xy 293.237889 -302.378409)
			(xy 293.18967 -302.368565) (xy 293.143654 -302.351113) (xy 293.101033 -302.326506) (xy 293.062912 -302.295381)
			(xy 293.030277 -302.258544) (xy 293.003974 -302.216948) (xy 292.984683 -302.171672) (xy 292.972906 -302.123888)
			(xy 292.968946 -302.074834) (xy 292.630098 -302.074834) (xy 292.629603 -302.099441) (xy 292.621708 -302.148018)
			(xy 292.606124 -302.194699) (xy 292.583253 -302.238276) (xy 292.553688 -302.27762) (xy 292.518195 -302.311712)
			(xy 292.477692 -302.339668) (xy 292.43323 -302.360766) (xy 292.385959 -302.374458) (xy 292.337104 -302.38039)
			(xy 292.287929 -302.378409) (xy 292.23971 -302.368565) (xy 292.193694 -302.351113) (xy 292.151073 -302.326506)
			(xy 292.112952 -302.295381) (xy 292.080317 -302.258544) (xy 292.054014 -302.216948) (xy 292.034723 -302.171672)
			(xy 292.022946 -302.123888) (xy 292.018986 -302.074834) (xy 290.730178 -302.074834) (xy 290.729683 -302.099441)
			(xy 290.721788 -302.148018) (xy 290.706204 -302.194699) (xy 290.683333 -302.238276) (xy 290.653768 -302.27762)
			(xy 290.618275 -302.311712) (xy 290.577772 -302.339668) (xy 290.53331 -302.360766) (xy 290.486039 -302.374458)
			(xy 290.437184 -302.38039) (xy 290.388009 -302.378409) (xy 290.33979 -302.368565) (xy 290.293774 -302.351113)
			(xy 290.251153 -302.326506) (xy 290.213032 -302.295381) (xy 290.180397 -302.258544) (xy 290.154094 -302.216948)
			(xy 290.134803 -302.171672) (xy 290.123026 -302.123888) (xy 290.119066 -302.074834) (xy 289.780218 -302.074834)
			(xy 289.779723 -302.099441) (xy 289.771828 -302.148018) (xy 289.756244 -302.194699) (xy 289.733373 -302.238276)
			(xy 289.703808 -302.27762) (xy 289.668315 -302.311712) (xy 289.627812 -302.339668) (xy 289.58335 -302.360766)
			(xy 289.536079 -302.374458) (xy 289.487224 -302.38039) (xy 289.438049 -302.378409) (xy 289.38983 -302.368565)
			(xy 289.343814 -302.351113) (xy 289.301193 -302.326506) (xy 289.263072 -302.295381) (xy 289.230437 -302.258544)
			(xy 289.204134 -302.216948) (xy 289.184843 -302.171672) (xy 289.173066 -302.123888) (xy 289.169106 -302.074834)
			(xy 288.830004 -302.074834) (xy 288.829509 -302.099441) (xy 288.821614 -302.148018) (xy 288.80603 -302.194699)
			(xy 288.783159 -302.238276) (xy 288.753594 -302.27762) (xy 288.718101 -302.311712) (xy 288.677598 -302.339668)
			(xy 288.633136 -302.360766) (xy 288.585865 -302.374458) (xy 288.53701 -302.38039) (xy 288.487835 -302.378409)
			(xy 288.439616 -302.368565) (xy 288.3936 -302.351113) (xy 288.350979 -302.326506) (xy 288.312858 -302.295381)
			(xy 288.280223 -302.258544) (xy 288.25392 -302.216948) (xy 288.234629 -302.171672) (xy 288.222852 -302.123888)
			(xy 288.218892 -302.074834) (xy 287.880044 -302.074834) (xy 287.879549 -302.099441) (xy 287.871654 -302.148018)
			(xy 287.85607 -302.194699) (xy 287.833199 -302.238276) (xy 287.803634 -302.27762) (xy 287.768141 -302.311712)
			(xy 287.727638 -302.339668) (xy 287.683176 -302.360766) (xy 287.635905 -302.374458) (xy 287.58705 -302.38039)
			(xy 287.537875 -302.378409) (xy 287.489656 -302.368565) (xy 287.44364 -302.351113) (xy 287.401019 -302.326506)
			(xy 287.362898 -302.295381) (xy 287.330263 -302.258544) (xy 287.30396 -302.216948) (xy 287.284669 -302.171672)
			(xy 287.272892 -302.123888) (xy 287.268932 -302.074834) (xy 286.930084 -302.074834) (xy 286.929589 -302.099441)
			(xy 286.921694 -302.148018) (xy 286.90611 -302.194699) (xy 286.883239 -302.238276) (xy 286.853674 -302.27762)
			(xy 286.818181 -302.311712) (xy 286.777678 -302.339668) (xy 286.733216 -302.360766) (xy 286.685945 -302.374458)
			(xy 286.63709 -302.38039) (xy 286.587915 -302.378409) (xy 286.539696 -302.368565) (xy 286.49368 -302.351113)
			(xy 286.451059 -302.326506) (xy 286.412938 -302.295381) (xy 286.380303 -302.258544) (xy 286.354 -302.216948)
			(xy 286.334709 -302.171672) (xy 286.322932 -302.123888) (xy 286.318972 -302.074834) (xy 285.980124 -302.074834)
			(xy 285.979629 -302.099441) (xy 285.971734 -302.148018) (xy 285.95615 -302.194699) (xy 285.933279 -302.238276)
			(xy 285.903714 -302.27762) (xy 285.868221 -302.311712) (xy 285.827718 -302.339668) (xy 285.783256 -302.360766)
			(xy 285.735985 -302.374458) (xy 285.68713 -302.38039) (xy 285.637955 -302.378409) (xy 285.589736 -302.368565)
			(xy 285.54372 -302.351113) (xy 285.501099 -302.326506) (xy 285.462978 -302.295381) (xy 285.430343 -302.258544)
			(xy 285.40404 -302.216948) (xy 285.384749 -302.171672) (xy 285.372972 -302.123888) (xy 285.369012 -302.074834)
			(xy 285.030164 -302.074834) (xy 285.029669 -302.099441) (xy 285.021774 -302.148018) (xy 285.00619 -302.194699)
			(xy 284.983319 -302.238276) (xy 284.953754 -302.27762) (xy 284.918261 -302.311712) (xy 284.877758 -302.339668)
			(xy 284.833296 -302.360766) (xy 284.786025 -302.374458) (xy 284.73717 -302.38039) (xy 284.687995 -302.378409)
			(xy 284.639776 -302.368565) (xy 284.59376 -302.351113) (xy 284.551139 -302.326506) (xy 284.513018 -302.295381)
			(xy 284.480383 -302.258544) (xy 284.45408 -302.216948) (xy 284.434789 -302.171672) (xy 284.423012 -302.123888)
			(xy 284.419052 -302.074834) (xy 284.080204 -302.074834) (xy 284.079709 -302.099441) (xy 284.071814 -302.148018)
			(xy 284.05623 -302.194699) (xy 284.033359 -302.238276) (xy 284.003794 -302.27762) (xy 283.968301 -302.311712)
			(xy 283.927798 -302.339668) (xy 283.883336 -302.360766) (xy 283.836065 -302.374458) (xy 283.78721 -302.38039)
			(xy 283.738035 -302.378409) (xy 283.689816 -302.368565) (xy 283.6438 -302.351113) (xy 283.601179 -302.326506)
			(xy 283.563058 -302.295381) (xy 283.530423 -302.258544) (xy 283.50412 -302.216948) (xy 283.484829 -302.171672)
			(xy 283.473052 -302.123888) (xy 283.469092 -302.074834) (xy 283.130244 -302.074834) (xy 283.129749 -302.099441)
			(xy 283.121854 -302.148018) (xy 283.10627 -302.194699) (xy 283.083399 -302.238276) (xy 283.053834 -302.27762)
			(xy 283.018341 -302.311712) (xy 282.977838 -302.339668) (xy 282.933376 -302.360766) (xy 282.886105 -302.374458)
			(xy 282.83725 -302.38039) (xy 282.788075 -302.378409) (xy 282.739856 -302.368565) (xy 282.69384 -302.351113)
			(xy 282.651219 -302.326506) (xy 282.613098 -302.295381) (xy 282.580463 -302.258544) (xy 282.55416 -302.216948)
			(xy 282.534869 -302.171672) (xy 282.523092 -302.123888) (xy 282.519132 -302.074834) (xy 282.18003 -302.074834)
			(xy 282.179535 -302.099441) (xy 282.17164 -302.148018) (xy 282.156056 -302.194699) (xy 282.133185 -302.238276)
			(xy 282.10362 -302.27762) (xy 282.068127 -302.311712) (xy 282.027624 -302.339668) (xy 281.983162 -302.360766)
			(xy 281.935891 -302.374458) (xy 281.887036 -302.38039) (xy 281.837861 -302.378409) (xy 281.789642 -302.368565)
			(xy 281.743626 -302.351113) (xy 281.701005 -302.326506) (xy 281.662884 -302.295381) (xy 281.630249 -302.258544)
			(xy 281.603946 -302.216948) (xy 281.584655 -302.171672) (xy 281.572878 -302.123888) (xy 281.568918 -302.074834)
			(xy 234.5309 -302.074834) (xy 234.5309 -302.550068) (xy 267.793736 -302.550068) (xy 267.797696 -302.501014)
			(xy 267.809473 -302.45323) (xy 267.828764 -302.407954) (xy 267.855067 -302.366358) (xy 267.887702 -302.329521)
			(xy 267.925823 -302.298396) (xy 267.968444 -302.273789) (xy 268.01446 -302.256337) (xy 268.062679 -302.246493)
			(xy 268.111854 -302.244512) (xy 268.160709 -302.250444) (xy 268.20798 -302.264136) (xy 268.252442 -302.285234)
			(xy 268.292945 -302.31319) (xy 268.328438 -302.347282) (xy 268.358003 -302.386626) (xy 268.380874 -302.430203)
			(xy 268.396458 -302.476884) (xy 268.404353 -302.525461) (xy 268.404848 -302.550068) (xy 268.404353 -302.574675)
			(xy 268.404215 -302.575522) (xy 268.723106 -302.575522) (xy 268.723106 -302.524106) (xy 268.731149 -302.473324)
			(xy 268.747037 -302.424425) (xy 268.77038 -302.378613) (xy 268.800601 -302.337017) (xy 268.836957 -302.300661)
			(xy 268.878553 -302.27044) (xy 268.924365 -302.247097) (xy 268.973264 -302.231209) (xy 269.024046 -302.223166)
			(xy 269.075462 -302.223166) (xy 269.126244 -302.231209) (xy 269.175143 -302.247097) (xy 269.220955 -302.27044)
			(xy 269.262551 -302.300661) (xy 269.298907 -302.337017) (xy 269.329128 -302.378613) (xy 269.352471 -302.424425)
			(xy 269.368359 -302.473324) (xy 269.376402 -302.524106) (xy 269.376906 -302.549814) (xy 269.376402 -302.575522)
			(xy 269.673066 -302.575522) (xy 269.673066 -302.524106) (xy 269.681109 -302.473324) (xy 269.696997 -302.424425)
			(xy 269.72034 -302.378613) (xy 269.750561 -302.337017) (xy 269.786917 -302.300661) (xy 269.828513 -302.27044)
			(xy 269.874325 -302.247097) (xy 269.923224 -302.231209) (xy 269.974006 -302.223166) (xy 270.025422 -302.223166)
			(xy 270.076204 -302.231209) (xy 270.125103 -302.247097) (xy 270.170915 -302.27044) (xy 270.212511 -302.300661)
			(xy 270.248867 -302.337017) (xy 270.279088 -302.378613) (xy 270.302431 -302.424425) (xy 270.318319 -302.473324)
			(xy 270.326362 -302.524106) (xy 270.326866 -302.549814) (xy 270.644124 -302.549814) (xy 270.648084 -302.50076)
			(xy 270.659861 -302.452976) (xy 270.679152 -302.4077) (xy 270.705455 -302.366104) (xy 270.73809 -302.329267)
			(xy 270.776211 -302.298142) (xy 270.818832 -302.273535) (xy 270.864848 -302.256083) (xy 270.913067 -302.246239)
			(xy 270.962242 -302.244258) (xy 271.011097 -302.25019) (xy 271.058368 -302.263882) (xy 271.10283 -302.28498)
			(xy 271.143333 -302.312936) (xy 271.178826 -302.347028) (xy 271.208391 -302.386372) (xy 271.231262 -302.429949)
			(xy 271.246846 -302.47663) (xy 271.254741 -302.525207) (xy 271.255236 -302.549814) (xy 271.594084 -302.549814)
			(xy 271.598044 -302.50076) (xy 271.609821 -302.452976) (xy 271.629112 -302.4077) (xy 271.655415 -302.366104)
			(xy 271.68805 -302.329267) (xy 271.726171 -302.298142) (xy 271.768792 -302.273535) (xy 271.814808 -302.256083)
			(xy 271.863027 -302.246239) (xy 271.912202 -302.244258) (xy 271.961057 -302.25019) (xy 272.008328 -302.263882)
			(xy 272.05279 -302.28498) (xy 272.093293 -302.312936) (xy 272.128786 -302.347028) (xy 272.158351 -302.386372)
			(xy 272.181222 -302.429949) (xy 272.196806 -302.47663) (xy 272.204701 -302.525207) (xy 272.205196 -302.549814)
			(xy 272.544044 -302.549814) (xy 272.548004 -302.50076) (xy 272.559781 -302.452976) (xy 272.579072 -302.4077)
			(xy 272.605375 -302.366104) (xy 272.63801 -302.329267) (xy 272.676131 -302.298142) (xy 272.718752 -302.273535)
			(xy 272.764768 -302.256083) (xy 272.812987 -302.246239) (xy 272.862162 -302.244258) (xy 272.911017 -302.25019)
			(xy 272.958288 -302.263882) (xy 273.00275 -302.28498) (xy 273.043253 -302.312936) (xy 273.078746 -302.347028)
			(xy 273.108311 -302.386372) (xy 273.131182 -302.429949) (xy 273.146766 -302.47663) (xy 273.154661 -302.525207)
			(xy 273.155156 -302.549814) (xy 273.494004 -302.549814) (xy 273.497964 -302.50076) (xy 273.509741 -302.452976)
			(xy 273.529032 -302.4077) (xy 273.555335 -302.366104) (xy 273.58797 -302.329267) (xy 273.626091 -302.298142)
			(xy 273.668712 -302.273535) (xy 273.714728 -302.256083) (xy 273.762947 -302.246239) (xy 273.812122 -302.244258)
			(xy 273.860977 -302.25019) (xy 273.908248 -302.263882) (xy 273.95271 -302.28498) (xy 273.993213 -302.312936)
			(xy 274.028706 -302.347028) (xy 274.058271 -302.386372) (xy 274.081142 -302.429949) (xy 274.096726 -302.47663)
			(xy 274.104621 -302.525207) (xy 274.105116 -302.549814) (xy 274.443964 -302.549814) (xy 274.447924 -302.50076)
			(xy 274.459701 -302.452976) (xy 274.478992 -302.4077) (xy 274.505295 -302.366104) (xy 274.53793 -302.329267)
			(xy 274.576051 -302.298142) (xy 274.618672 -302.273535) (xy 274.664688 -302.256083) (xy 274.712907 -302.246239)
			(xy 274.762082 -302.244258) (xy 274.810937 -302.25019) (xy 274.858208 -302.263882) (xy 274.90267 -302.28498)
			(xy 274.943173 -302.312936) (xy 274.978666 -302.347028) (xy 275.008231 -302.386372) (xy 275.031102 -302.429949)
			(xy 275.046686 -302.47663) (xy 275.054581 -302.525207) (xy 275.055076 -302.549814) (xy 275.054581 -302.574421)
			(xy 275.054402 -302.575522) (xy 275.37308 -302.575522) (xy 275.37308 -302.524106) (xy 275.381123 -302.473324)
			(xy 275.397011 -302.424425) (xy 275.420354 -302.378613) (xy 275.450575 -302.337017) (xy 275.486931 -302.300661)
			(xy 275.528527 -302.27044) (xy 275.574339 -302.247097) (xy 275.623238 -302.231209) (xy 275.67402 -302.223166)
			(xy 275.725436 -302.223166) (xy 275.776218 -302.231209) (xy 275.825117 -302.247097) (xy 275.870929 -302.27044)
			(xy 275.912525 -302.300661) (xy 275.948881 -302.337017) (xy 275.979102 -302.378613) (xy 276.002445 -302.424425)
			(xy 276.018333 -302.473324) (xy 276.026376 -302.524106) (xy 276.02688 -302.549814) (xy 276.026376 -302.575522)
			(xy 276.32304 -302.575522) (xy 276.32304 -302.524106) (xy 276.331083 -302.473324) (xy 276.346971 -302.424425)
			(xy 276.370314 -302.378613) (xy 276.400535 -302.337017) (xy 276.436891 -302.300661) (xy 276.478487 -302.27044)
			(xy 276.524299 -302.247097) (xy 276.573198 -302.231209) (xy 276.62398 -302.223166) (xy 276.675396 -302.223166)
			(xy 276.726178 -302.231209) (xy 276.775077 -302.247097) (xy 276.820889 -302.27044) (xy 276.862485 -302.300661)
			(xy 276.898841 -302.337017) (xy 276.929062 -302.378613) (xy 276.952405 -302.424425) (xy 276.968293 -302.473324)
			(xy 276.976336 -302.524106) (xy 276.97684 -302.549814) (xy 277.294098 -302.549814) (xy 277.298058 -302.50076)
			(xy 277.309835 -302.452976) (xy 277.329126 -302.4077) (xy 277.355429 -302.366104) (xy 277.388064 -302.329267)
			(xy 277.426185 -302.298142) (xy 277.468806 -302.273535) (xy 277.514822 -302.256083) (xy 277.563041 -302.246239)
			(xy 277.612216 -302.244258) (xy 277.661071 -302.25019) (xy 277.708342 -302.263882) (xy 277.752804 -302.28498)
			(xy 277.793307 -302.312936) (xy 277.8288 -302.347028) (xy 277.858365 -302.386372) (xy 277.881236 -302.429949)
			(xy 277.89682 -302.47663) (xy 277.904715 -302.525207) (xy 277.90521 -302.549814) (xy 277.904715 -302.574421)
			(xy 277.89682 -302.622998) (xy 277.881236 -302.669679) (xy 277.858365 -302.713256) (xy 277.8288 -302.7526)
			(xy 277.793307 -302.786692) (xy 277.752804 -302.814648) (xy 277.708342 -302.835746) (xy 277.661071 -302.849438)
			(xy 277.612216 -302.85537) (xy 277.563041 -302.853389) (xy 277.514822 -302.843545) (xy 277.468806 -302.826093)
			(xy 277.426185 -302.801486) (xy 277.388064 -302.770361) (xy 277.355429 -302.733524) (xy 277.329126 -302.691928)
			(xy 277.309835 -302.646652) (xy 277.298058 -302.598868) (xy 277.294098 -302.549814) (xy 276.97684 -302.549814)
			(xy 276.976336 -302.575522) (xy 276.968293 -302.626304) (xy 276.952405 -302.675203) (xy 276.929062 -302.721015)
			(xy 276.898841 -302.762611) (xy 276.862485 -302.798967) (xy 276.820889 -302.829188) (xy 276.775077 -302.852531)
			(xy 276.726178 -302.868419) (xy 276.675396 -302.876462) (xy 276.62398 -302.876462) (xy 276.573198 -302.868419)
			(xy 276.524299 -302.852531) (xy 276.478487 -302.829188) (xy 276.436891 -302.798967) (xy 276.400535 -302.762611)
			(xy 276.370314 -302.721015) (xy 276.346971 -302.675203) (xy 276.331083 -302.626304) (xy 276.32304 -302.575522)
			(xy 276.026376 -302.575522) (xy 276.018333 -302.626304) (xy 276.002445 -302.675203) (xy 275.979102 -302.721015)
			(xy 275.948881 -302.762611) (xy 275.912525 -302.798967) (xy 275.870929 -302.829188) (xy 275.825117 -302.852531)
			(xy 275.776218 -302.868419) (xy 275.725436 -302.876462) (xy 275.67402 -302.876462) (xy 275.623238 -302.868419)
			(xy 275.574339 -302.852531) (xy 275.528527 -302.829188) (xy 275.486931 -302.798967) (xy 275.450575 -302.762611)
			(xy 275.420354 -302.721015) (xy 275.397011 -302.675203) (xy 275.381123 -302.626304) (xy 275.37308 -302.575522)
			(xy 275.054402 -302.575522) (xy 275.046686 -302.622998) (xy 275.031102 -302.669679) (xy 275.008231 -302.713256)
			(xy 274.978666 -302.7526) (xy 274.943173 -302.786692) (xy 274.90267 -302.814648) (xy 274.858208 -302.835746)
			(xy 274.810937 -302.849438) (xy 274.762082 -302.85537) (xy 274.712907 -302.853389) (xy 274.664688 -302.843545)
			(xy 274.618672 -302.826093) (xy 274.576051 -302.801486) (xy 274.53793 -302.770361) (xy 274.505295 -302.733524)
			(xy 274.478992 -302.691928) (xy 274.459701 -302.646652) (xy 274.447924 -302.598868) (xy 274.443964 -302.549814)
			(xy 274.105116 -302.549814) (xy 274.104621 -302.574421) (xy 274.096726 -302.622998) (xy 274.081142 -302.669679)
			(xy 274.058271 -302.713256) (xy 274.028706 -302.7526) (xy 273.993213 -302.786692) (xy 273.95271 -302.814648)
			(xy 273.908248 -302.835746) (xy 273.860977 -302.849438) (xy 273.812122 -302.85537) (xy 273.762947 -302.853389)
			(xy 273.714728 -302.843545) (xy 273.668712 -302.826093) (xy 273.626091 -302.801486) (xy 273.58797 -302.770361)
			(xy 273.555335 -302.733524) (xy 273.529032 -302.691928) (xy 273.509741 -302.646652) (xy 273.497964 -302.598868)
			(xy 273.494004 -302.549814) (xy 273.155156 -302.549814) (xy 273.154661 -302.574421) (xy 273.146766 -302.622998)
			(xy 273.131182 -302.669679) (xy 273.108311 -302.713256) (xy 273.078746 -302.7526) (xy 273.043253 -302.786692)
			(xy 273.00275 -302.814648) (xy 272.958288 -302.835746) (xy 272.911017 -302.849438) (xy 272.862162 -302.85537)
			(xy 272.812987 -302.853389) (xy 272.764768 -302.843545) (xy 272.718752 -302.826093) (xy 272.676131 -302.801486)
			(xy 272.63801 -302.770361) (xy 272.605375 -302.733524) (xy 272.579072 -302.691928) (xy 272.559781 -302.646652)
			(xy 272.548004 -302.598868) (xy 272.544044 -302.549814) (xy 272.205196 -302.549814) (xy 272.204701 -302.574421)
			(xy 272.196806 -302.622998) (xy 272.181222 -302.669679) (xy 272.158351 -302.713256) (xy 272.128786 -302.7526)
			(xy 272.093293 -302.786692) (xy 272.05279 -302.814648) (xy 272.008328 -302.835746) (xy 271.961057 -302.849438)
			(xy 271.912202 -302.85537) (xy 271.863027 -302.853389) (xy 271.814808 -302.843545) (xy 271.768792 -302.826093)
			(xy 271.726171 -302.801486) (xy 271.68805 -302.770361) (xy 271.655415 -302.733524) (xy 271.629112 -302.691928)
			(xy 271.609821 -302.646652) (xy 271.598044 -302.598868) (xy 271.594084 -302.549814) (xy 271.255236 -302.549814)
			(xy 271.254741 -302.574421) (xy 271.246846 -302.622998) (xy 271.231262 -302.669679) (xy 271.208391 -302.713256)
			(xy 271.178826 -302.7526) (xy 271.143333 -302.786692) (xy 271.10283 -302.814648) (xy 271.058368 -302.835746)
			(xy 271.011097 -302.849438) (xy 270.962242 -302.85537) (xy 270.913067 -302.853389) (xy 270.864848 -302.843545)
			(xy 270.818832 -302.826093) (xy 270.776211 -302.801486) (xy 270.73809 -302.770361) (xy 270.705455 -302.733524)
			(xy 270.679152 -302.691928) (xy 270.659861 -302.646652) (xy 270.648084 -302.598868) (xy 270.644124 -302.549814)
			(xy 270.326866 -302.549814) (xy 270.326362 -302.575522) (xy 270.318319 -302.626304) (xy 270.302431 -302.675203)
			(xy 270.279088 -302.721015) (xy 270.248867 -302.762611) (xy 270.212511 -302.798967) (xy 270.170915 -302.829188)
			(xy 270.125103 -302.852531) (xy 270.076204 -302.868419) (xy 270.025422 -302.876462) (xy 269.974006 -302.876462)
			(xy 269.923224 -302.868419) (xy 269.874325 -302.852531) (xy 269.828513 -302.829188) (xy 269.786917 -302.798967)
			(xy 269.750561 -302.762611) (xy 269.72034 -302.721015) (xy 269.696997 -302.675203) (xy 269.681109 -302.626304)
			(xy 269.673066 -302.575522) (xy 269.376402 -302.575522) (xy 269.368359 -302.626304) (xy 269.352471 -302.675203)
			(xy 269.329128 -302.721015) (xy 269.298907 -302.762611) (xy 269.262551 -302.798967) (xy 269.220955 -302.829188)
			(xy 269.175143 -302.852531) (xy 269.126244 -302.868419) (xy 269.075462 -302.876462) (xy 269.024046 -302.876462)
			(xy 268.973264 -302.868419) (xy 268.924365 -302.852531) (xy 268.878553 -302.829188) (xy 268.836957 -302.798967)
			(xy 268.800601 -302.762611) (xy 268.77038 -302.721015) (xy 268.747037 -302.675203) (xy 268.731149 -302.626304)
			(xy 268.723106 -302.575522) (xy 268.404215 -302.575522) (xy 268.396458 -302.623252) (xy 268.380874 -302.669933)
			(xy 268.358003 -302.71351) (xy 268.328438 -302.752854) (xy 268.292945 -302.786946) (xy 268.252442 -302.814902)
			(xy 268.20798 -302.836) (xy 268.160709 -302.849692) (xy 268.111854 -302.855624) (xy 268.062679 -302.853643)
			(xy 268.01446 -302.843799) (xy 267.968444 -302.826347) (xy 267.925823 -302.80174) (xy 267.887702 -302.770615)
			(xy 267.855067 -302.733778) (xy 267.828764 -302.692182) (xy 267.809473 -302.646906) (xy 267.797696 -302.599122)
			(xy 267.793736 -302.550068) (xy 234.5309 -302.550068) (xy 234.5309 -303.024794) (xy 278.719038 -303.024794)
			(xy 278.722998 -302.97574) (xy 278.734775 -302.927956) (xy 278.754066 -302.88268) (xy 278.780369 -302.841084)
			(xy 278.813004 -302.804247) (xy 278.851125 -302.773122) (xy 278.893746 -302.748515) (xy 278.939762 -302.731063)
			(xy 278.987981 -302.721219) (xy 279.037156 -302.719238) (xy 279.086011 -302.72517) (xy 279.133282 -302.738862)
			(xy 279.177744 -302.75996) (xy 279.218247 -302.787916) (xy 279.25374 -302.822008) (xy 279.283305 -302.861352)
			(xy 279.306176 -302.904929) (xy 279.32176 -302.95161) (xy 279.329655 -303.000187) (xy 279.33015 -303.024794)
			(xy 279.668998 -303.024794) (xy 279.672958 -302.97574) (xy 279.684735 -302.927956) (xy 279.704026 -302.88268)
			(xy 279.730329 -302.841084) (xy 279.762964 -302.804247) (xy 279.801085 -302.773122) (xy 279.843706 -302.748515)
			(xy 279.889722 -302.731063) (xy 279.937941 -302.721219) (xy 279.987116 -302.719238) (xy 280.035971 -302.72517)
			(xy 280.083242 -302.738862) (xy 280.127704 -302.75996) (xy 280.168207 -302.787916) (xy 280.2037 -302.822008)
			(xy 280.233265 -302.861352) (xy 280.256136 -302.904929) (xy 280.27172 -302.95161) (xy 280.279615 -303.000187)
			(xy 280.28011 -303.024794) (xy 280.618958 -303.024794) (xy 280.622918 -302.97574) (xy 280.634695 -302.927956)
			(xy 280.653986 -302.88268) (xy 280.680289 -302.841084) (xy 280.712924 -302.804247) (xy 280.751045 -302.773122)
			(xy 280.793666 -302.748515) (xy 280.839682 -302.731063) (xy 280.887901 -302.721219) (xy 280.937076 -302.719238)
			(xy 280.985931 -302.72517) (xy 281.033202 -302.738862) (xy 281.077664 -302.75996) (xy 281.118167 -302.787916)
			(xy 281.15366 -302.822008) (xy 281.183225 -302.861352) (xy 281.206096 -302.904929) (xy 281.22168 -302.95161)
			(xy 281.229575 -303.000187) (xy 281.23007 -303.024794) (xy 281.568918 -303.024794) (xy 281.572878 -302.97574)
			(xy 281.584655 -302.927956) (xy 281.603946 -302.88268) (xy 281.630249 -302.841084) (xy 281.662884 -302.804247)
			(xy 281.701005 -302.773122) (xy 281.743626 -302.748515) (xy 281.789642 -302.731063) (xy 281.837861 -302.721219)
			(xy 281.887036 -302.719238) (xy 281.935891 -302.72517) (xy 281.983162 -302.738862) (xy 282.027624 -302.75996)
			(xy 282.068127 -302.787916) (xy 282.10362 -302.822008) (xy 282.133185 -302.861352) (xy 282.156056 -302.904929)
			(xy 282.17164 -302.95161) (xy 282.179535 -303.000187) (xy 282.18003 -303.024794) (xy 300.56888 -303.024794)
			(xy 300.57284 -302.97574) (xy 300.584617 -302.927956) (xy 300.603908 -302.88268) (xy 300.630211 -302.841084)
			(xy 300.662846 -302.804247) (xy 300.700967 -302.773122) (xy 300.743588 -302.748515) (xy 300.789604 -302.731063)
			(xy 300.837823 -302.721219) (xy 300.886998 -302.719238) (xy 300.935853 -302.72517) (xy 300.983124 -302.738862)
			(xy 301.027586 -302.75996) (xy 301.068089 -302.787916) (xy 301.103582 -302.822008) (xy 301.133147 -302.861352)
			(xy 301.156018 -302.904929) (xy 301.171602 -302.95161) (xy 301.179497 -303.000187) (xy 301.179992 -303.024794)
			(xy 301.519094 -303.024794) (xy 301.523054 -302.97574) (xy 301.534831 -302.927956) (xy 301.554122 -302.88268)
			(xy 301.580425 -302.841084) (xy 301.61306 -302.804247) (xy 301.651181 -302.773122) (xy 301.693802 -302.748515)
			(xy 301.739818 -302.731063) (xy 301.788037 -302.721219) (xy 301.837212 -302.719238) (xy 301.886067 -302.72517)
			(xy 301.933338 -302.738862) (xy 301.9778 -302.75996) (xy 302.018303 -302.787916) (xy 302.053796 -302.822008)
			(xy 302.083361 -302.861352) (xy 302.106232 -302.904929) (xy 302.121816 -302.95161) (xy 302.129711 -303.000187)
			(xy 302.130206 -303.024794) (xy 302.469054 -303.024794) (xy 302.473014 -302.97574) (xy 302.484791 -302.927956)
			(xy 302.504082 -302.88268) (xy 302.530385 -302.841084) (xy 302.56302 -302.804247) (xy 302.601141 -302.773122)
			(xy 302.643762 -302.748515) (xy 302.689778 -302.731063) (xy 302.737997 -302.721219) (xy 302.787172 -302.719238)
			(xy 302.836027 -302.72517) (xy 302.883298 -302.738862) (xy 302.92776 -302.75996) (xy 302.968263 -302.787916)
			(xy 303.003756 -302.822008) (xy 303.033321 -302.861352) (xy 303.056192 -302.904929) (xy 303.071776 -302.95161)
			(xy 303.079671 -303.000187) (xy 303.080166 -303.024794) (xy 303.419014 -303.024794) (xy 303.422974 -302.97574)
			(xy 303.434751 -302.927956) (xy 303.454042 -302.88268) (xy 303.480345 -302.841084) (xy 303.51298 -302.804247)
			(xy 303.551101 -302.773122) (xy 303.593722 -302.748515) (xy 303.639738 -302.731063) (xy 303.687957 -302.721219)
			(xy 303.737132 -302.719238) (xy 303.785987 -302.72517) (xy 303.833258 -302.738862) (xy 303.87772 -302.75996)
			(xy 303.918223 -302.787916) (xy 303.953716 -302.822008) (xy 303.983281 -302.861352) (xy 304.006152 -302.904929)
			(xy 304.021736 -302.95161) (xy 304.029631 -303.000187) (xy 304.030126 -303.024794) (xy 304.368974 -303.024794)
			(xy 304.372934 -302.97574) (xy 304.384711 -302.927956) (xy 304.404002 -302.88268) (xy 304.430305 -302.841084)
			(xy 304.46294 -302.804247) (xy 304.501061 -302.773122) (xy 304.543682 -302.748515) (xy 304.589698 -302.731063)
			(xy 304.637917 -302.721219) (xy 304.687092 -302.719238) (xy 304.735947 -302.72517) (xy 304.783218 -302.738862)
			(xy 304.82768 -302.75996) (xy 304.868183 -302.787916) (xy 304.903676 -302.822008) (xy 304.933241 -302.861352)
			(xy 304.956112 -302.904929) (xy 304.971696 -302.95161) (xy 304.979591 -303.000187) (xy 304.980086 -303.024794)
			(xy 305.318934 -303.024794) (xy 305.322894 -302.97574) (xy 305.334671 -302.927956) (xy 305.353962 -302.88268)
			(xy 305.380265 -302.841084) (xy 305.4129 -302.804247) (xy 305.451021 -302.773122) (xy 305.493642 -302.748515)
			(xy 305.539658 -302.731063) (xy 305.587877 -302.721219) (xy 305.637052 -302.719238) (xy 305.685907 -302.72517)
			(xy 305.733178 -302.738862) (xy 305.77764 -302.75996) (xy 305.818143 -302.787916) (xy 305.853636 -302.822008)
			(xy 305.883201 -302.861352) (xy 305.906072 -302.904929) (xy 305.921656 -302.95161) (xy 305.929551 -303.000187)
			(xy 305.930046 -303.024794) (xy 305.929551 -303.049401) (xy 305.921656 -303.097978) (xy 305.906072 -303.144659)
			(xy 305.883201 -303.188236) (xy 305.853636 -303.22758) (xy 305.818143 -303.261672) (xy 305.77764 -303.289628)
			(xy 305.733178 -303.310726) (xy 305.685907 -303.324418) (xy 305.637052 -303.33035) (xy 305.587877 -303.328369)
			(xy 305.539658 -303.318525) (xy 305.493642 -303.301073) (xy 305.451021 -303.276466) (xy 305.4129 -303.245341)
			(xy 305.380265 -303.208504) (xy 305.353962 -303.166908) (xy 305.334671 -303.121632) (xy 305.322894 -303.073848)
			(xy 305.318934 -303.024794) (xy 304.980086 -303.024794) (xy 304.979591 -303.049401) (xy 304.971696 -303.097978)
			(xy 304.956112 -303.144659) (xy 304.933241 -303.188236) (xy 304.903676 -303.22758) (xy 304.868183 -303.261672)
			(xy 304.82768 -303.289628) (xy 304.783218 -303.310726) (xy 304.735947 -303.324418) (xy 304.687092 -303.33035)
			(xy 304.637917 -303.328369) (xy 304.589698 -303.318525) (xy 304.543682 -303.301073) (xy 304.501061 -303.276466)
			(xy 304.46294 -303.245341) (xy 304.430305 -303.208504) (xy 304.404002 -303.166908) (xy 304.384711 -303.121632)
			(xy 304.372934 -303.073848) (xy 304.368974 -303.024794) (xy 304.030126 -303.024794) (xy 304.029631 -303.049401)
			(xy 304.021736 -303.097978) (xy 304.006152 -303.144659) (xy 303.983281 -303.188236) (xy 303.953716 -303.22758)
			(xy 303.918223 -303.261672) (xy 303.87772 -303.289628) (xy 303.833258 -303.310726) (xy 303.785987 -303.324418)
			(xy 303.737132 -303.33035) (xy 303.687957 -303.328369) (xy 303.639738 -303.318525) (xy 303.593722 -303.301073)
			(xy 303.551101 -303.276466) (xy 303.51298 -303.245341) (xy 303.480345 -303.208504) (xy 303.454042 -303.166908)
			(xy 303.434751 -303.121632) (xy 303.422974 -303.073848) (xy 303.419014 -303.024794) (xy 303.080166 -303.024794)
			(xy 303.079671 -303.049401) (xy 303.071776 -303.097978) (xy 303.056192 -303.144659) (xy 303.033321 -303.188236)
			(xy 303.003756 -303.22758) (xy 302.968263 -303.261672) (xy 302.92776 -303.289628) (xy 302.883298 -303.310726)
			(xy 302.836027 -303.324418) (xy 302.787172 -303.33035) (xy 302.737997 -303.328369) (xy 302.689778 -303.318525)
			(xy 302.643762 -303.301073) (xy 302.601141 -303.276466) (xy 302.56302 -303.245341) (xy 302.530385 -303.208504)
			(xy 302.504082 -303.166908) (xy 302.484791 -303.121632) (xy 302.473014 -303.073848) (xy 302.469054 -303.024794)
			(xy 302.130206 -303.024794) (xy 302.129711 -303.049401) (xy 302.121816 -303.097978) (xy 302.106232 -303.144659)
			(xy 302.083361 -303.188236) (xy 302.053796 -303.22758) (xy 302.018303 -303.261672) (xy 301.9778 -303.289628)
			(xy 301.933338 -303.310726) (xy 301.886067 -303.324418) (xy 301.837212 -303.33035) (xy 301.788037 -303.328369)
			(xy 301.739818 -303.318525) (xy 301.693802 -303.301073) (xy 301.651181 -303.276466) (xy 301.61306 -303.245341)
			(xy 301.580425 -303.208504) (xy 301.554122 -303.166908) (xy 301.534831 -303.121632) (xy 301.523054 -303.073848)
			(xy 301.519094 -303.024794) (xy 301.179992 -303.024794) (xy 301.179497 -303.049401) (xy 301.171602 -303.097978)
			(xy 301.156018 -303.144659) (xy 301.133147 -303.188236) (xy 301.103582 -303.22758) (xy 301.068089 -303.261672)
			(xy 301.027586 -303.289628) (xy 300.983124 -303.310726) (xy 300.935853 -303.324418) (xy 300.886998 -303.33035)
			(xy 300.837823 -303.328369) (xy 300.789604 -303.318525) (xy 300.743588 -303.301073) (xy 300.700967 -303.276466)
			(xy 300.662846 -303.245341) (xy 300.630211 -303.208504) (xy 300.603908 -303.166908) (xy 300.584617 -303.121632)
			(xy 300.57284 -303.073848) (xy 300.56888 -303.024794) (xy 282.18003 -303.024794) (xy 282.179535 -303.049401)
			(xy 282.17164 -303.097978) (xy 282.156056 -303.144659) (xy 282.133185 -303.188236) (xy 282.10362 -303.22758)
			(xy 282.068127 -303.261672) (xy 282.027624 -303.289628) (xy 281.983162 -303.310726) (xy 281.935891 -303.324418)
			(xy 281.887036 -303.33035) (xy 281.837861 -303.328369) (xy 281.789642 -303.318525) (xy 281.743626 -303.301073)
			(xy 281.701005 -303.276466) (xy 281.662884 -303.245341) (xy 281.630249 -303.208504) (xy 281.603946 -303.166908)
			(xy 281.584655 -303.121632) (xy 281.572878 -303.073848) (xy 281.568918 -303.024794) (xy 281.23007 -303.024794)
			(xy 281.229575 -303.049401) (xy 281.22168 -303.097978) (xy 281.206096 -303.144659) (xy 281.183225 -303.188236)
			(xy 281.15366 -303.22758) (xy 281.118167 -303.261672) (xy 281.077664 -303.289628) (xy 281.033202 -303.310726)
			(xy 280.985931 -303.324418) (xy 280.937076 -303.33035) (xy 280.887901 -303.328369) (xy 280.839682 -303.318525)
			(xy 280.793666 -303.301073) (xy 280.751045 -303.276466) (xy 280.712924 -303.245341) (xy 280.680289 -303.208504)
			(xy 280.653986 -303.166908) (xy 280.634695 -303.121632) (xy 280.622918 -303.073848) (xy 280.618958 -303.024794)
			(xy 280.28011 -303.024794) (xy 280.279615 -303.049401) (xy 280.27172 -303.097978) (xy 280.256136 -303.144659)
			(xy 280.233265 -303.188236) (xy 280.2037 -303.22758) (xy 280.168207 -303.261672) (xy 280.127704 -303.289628)
			(xy 280.083242 -303.310726) (xy 280.035971 -303.324418) (xy 279.987116 -303.33035) (xy 279.937941 -303.328369)
			(xy 279.889722 -303.318525) (xy 279.843706 -303.301073) (xy 279.801085 -303.276466) (xy 279.762964 -303.245341)
			(xy 279.730329 -303.208504) (xy 279.704026 -303.166908) (xy 279.684735 -303.121632) (xy 279.672958 -303.073848)
			(xy 279.668998 -303.024794) (xy 279.33015 -303.024794) (xy 279.329655 -303.049401) (xy 279.32176 -303.097978)
			(xy 279.306176 -303.144659) (xy 279.283305 -303.188236) (xy 279.25374 -303.22758) (xy 279.218247 -303.261672)
			(xy 279.177744 -303.289628) (xy 279.133282 -303.310726) (xy 279.086011 -303.324418) (xy 279.037156 -303.33035)
			(xy 278.987981 -303.328369) (xy 278.939762 -303.318525) (xy 278.893746 -303.301073) (xy 278.851125 -303.276466)
			(xy 278.813004 -303.245341) (xy 278.780369 -303.208504) (xy 278.754066 -303.166908) (xy 278.734775 -303.121632)
			(xy 278.722998 -303.073848) (xy 278.719038 -303.024794) (xy 234.5309 -303.024794) (xy 234.5309 -303.217326)
			(xy 234.531361 -303.227202) (xy 234.538807 -303.245499) (xy 234.545378 -303.252886) (xy 234.545632 -303.25314)
			(xy 234.792266 -303.499774) (xy 268.74395 -303.499774) (xy 268.74791 -303.45072) (xy 268.759687 -303.402936)
			(xy 268.778978 -303.35766) (xy 268.805281 -303.316064) (xy 268.837916 -303.279227) (xy 268.876037 -303.248102)
			(xy 268.918658 -303.223495) (xy 268.964674 -303.206043) (xy 269.012893 -303.196199) (xy 269.062068 -303.194218)
			(xy 269.110923 -303.20015) (xy 269.158194 -303.213842) (xy 269.202656 -303.23494) (xy 269.243159 -303.262896)
			(xy 269.278652 -303.296988) (xy 269.308217 -303.336332) (xy 269.331088 -303.379909) (xy 269.346672 -303.42659)
			(xy 269.354567 -303.475167) (xy 269.355062 -303.499774) (xy 269.69391 -303.499774) (xy 269.69787 -303.45072)
			(xy 269.709647 -303.402936) (xy 269.728938 -303.35766) (xy 269.755241 -303.316064) (xy 269.787876 -303.279227)
			(xy 269.825997 -303.248102) (xy 269.868618 -303.223495) (xy 269.914634 -303.206043) (xy 269.962853 -303.196199)
			(xy 270.012028 -303.194218) (xy 270.060883 -303.20015) (xy 270.108154 -303.213842) (xy 270.152616 -303.23494)
			(xy 270.193119 -303.262896) (xy 270.228612 -303.296988) (xy 270.258177 -303.336332) (xy 270.281048 -303.379909)
			(xy 270.296632 -303.42659) (xy 270.304527 -303.475167) (xy 270.305022 -303.499774) (xy 270.304527 -303.524381)
			(xy 270.304348 -303.525482) (xy 270.62328 -303.525482) (xy 270.62328 -303.474066) (xy 270.631323 -303.423284)
			(xy 270.647211 -303.374385) (xy 270.670554 -303.328573) (xy 270.700775 -303.286977) (xy 270.737131 -303.250621)
			(xy 270.778727 -303.2204) (xy 270.824539 -303.197057) (xy 270.873438 -303.181169) (xy 270.92422 -303.173126)
			(xy 270.975636 -303.173126) (xy 271.026418 -303.181169) (xy 271.075317 -303.197057) (xy 271.121129 -303.2204)
			(xy 271.162725 -303.250621) (xy 271.199081 -303.286977) (xy 271.229302 -303.328573) (xy 271.252645 -303.374385)
			(xy 271.268533 -303.423284) (xy 271.276576 -303.474066) (xy 271.27708 -303.499774) (xy 271.276576 -303.525482)
			(xy 271.57324 -303.525482) (xy 271.57324 -303.474066) (xy 271.581283 -303.423284) (xy 271.597171 -303.374385)
			(xy 271.620514 -303.328573) (xy 271.650735 -303.286977) (xy 271.687091 -303.250621) (xy 271.728687 -303.2204)
			(xy 271.774499 -303.197057) (xy 271.823398 -303.181169) (xy 271.87418 -303.173126) (xy 271.925596 -303.173126)
			(xy 271.976378 -303.181169) (xy 272.025277 -303.197057) (xy 272.071089 -303.2204) (xy 272.112685 -303.250621)
			(xy 272.149041 -303.286977) (xy 272.179262 -303.328573) (xy 272.202605 -303.374385) (xy 272.218493 -303.423284)
			(xy 272.226536 -303.474066) (xy 272.22704 -303.499774) (xy 272.544044 -303.499774) (xy 272.548004 -303.45072)
			(xy 272.559781 -303.402936) (xy 272.579072 -303.35766) (xy 272.605375 -303.316064) (xy 272.63801 -303.279227)
			(xy 272.676131 -303.248102) (xy 272.718752 -303.223495) (xy 272.764768 -303.206043) (xy 272.812987 -303.196199)
			(xy 272.862162 -303.194218) (xy 272.911017 -303.20015) (xy 272.958288 -303.213842) (xy 273.00275 -303.23494)
			(xy 273.043253 -303.262896) (xy 273.078746 -303.296988) (xy 273.108311 -303.336332) (xy 273.131182 -303.379909)
			(xy 273.146766 -303.42659) (xy 273.154661 -303.475167) (xy 273.155156 -303.499774) (xy 273.154661 -303.524381)
			(xy 273.154482 -303.525482) (xy 273.47316 -303.525482) (xy 273.47316 -303.474066) (xy 273.481203 -303.423284)
			(xy 273.497091 -303.374385) (xy 273.520434 -303.328573) (xy 273.550655 -303.286977) (xy 273.587011 -303.250621)
			(xy 273.628607 -303.2204) (xy 273.674419 -303.197057) (xy 273.723318 -303.181169) (xy 273.7741 -303.173126)
			(xy 273.825516 -303.173126) (xy 273.876298 -303.181169) (xy 273.925197 -303.197057) (xy 273.971009 -303.2204)
			(xy 274.012605 -303.250621) (xy 274.048961 -303.286977) (xy 274.079182 -303.328573) (xy 274.102525 -303.374385)
			(xy 274.118413 -303.423284) (xy 274.126456 -303.474066) (xy 274.12696 -303.499774) (xy 274.126456 -303.525482)
			(xy 274.42312 -303.525482) (xy 274.42312 -303.474066) (xy 274.431163 -303.423284) (xy 274.447051 -303.374385)
			(xy 274.470394 -303.328573) (xy 274.500615 -303.286977) (xy 274.536971 -303.250621) (xy 274.578567 -303.2204)
			(xy 274.624379 -303.197057) (xy 274.673278 -303.181169) (xy 274.72406 -303.173126) (xy 274.775476 -303.173126)
			(xy 274.826258 -303.181169) (xy 274.875157 -303.197057) (xy 274.920969 -303.2204) (xy 274.962565 -303.250621)
			(xy 274.998921 -303.286977) (xy 275.029142 -303.328573) (xy 275.052485 -303.374385) (xy 275.068373 -303.423284)
			(xy 275.076416 -303.474066) (xy 275.07692 -303.499774) (xy 275.393924 -303.499774) (xy 275.397884 -303.45072)
			(xy 275.409661 -303.402936) (xy 275.428952 -303.35766) (xy 275.455255 -303.316064) (xy 275.48789 -303.279227)
			(xy 275.526011 -303.248102) (xy 275.568632 -303.223495) (xy 275.614648 -303.206043) (xy 275.662867 -303.196199)
			(xy 275.712042 -303.194218) (xy 275.760897 -303.20015) (xy 275.808168 -303.213842) (xy 275.85263 -303.23494)
			(xy 275.893133 -303.262896) (xy 275.928626 -303.296988) (xy 275.958191 -303.336332) (xy 275.981062 -303.379909)
			(xy 275.996646 -303.42659) (xy 276.004541 -303.475167) (xy 276.005036 -303.499774) (xy 276.343884 -303.499774)
			(xy 276.347844 -303.45072) (xy 276.359621 -303.402936) (xy 276.378912 -303.35766) (xy 276.405215 -303.316064)
			(xy 276.43785 -303.279227) (xy 276.475971 -303.248102) (xy 276.518592 -303.223495) (xy 276.564608 -303.206043)
			(xy 276.612827 -303.196199) (xy 276.662002 -303.194218) (xy 276.710857 -303.20015) (xy 276.758128 -303.213842)
			(xy 276.80259 -303.23494) (xy 276.843093 -303.262896) (xy 276.878586 -303.296988) (xy 276.908151 -303.336332)
			(xy 276.931022 -303.379909) (xy 276.946606 -303.42659) (xy 276.954501 -303.475167) (xy 276.954996 -303.499774)
			(xy 277.294098 -303.499774) (xy 277.298058 -303.45072) (xy 277.309835 -303.402936) (xy 277.329126 -303.35766)
			(xy 277.355429 -303.316064) (xy 277.388064 -303.279227) (xy 277.426185 -303.248102) (xy 277.468806 -303.223495)
			(xy 277.514822 -303.206043) (xy 277.563041 -303.196199) (xy 277.612216 -303.194218) (xy 277.661071 -303.20015)
			(xy 277.708342 -303.213842) (xy 277.752804 -303.23494) (xy 277.793307 -303.262896) (xy 277.8288 -303.296988)
			(xy 277.858365 -303.336332) (xy 277.881236 -303.379909) (xy 277.89682 -303.42659) (xy 277.904715 -303.475167)
			(xy 277.90521 -303.499774) (xy 277.904715 -303.524381) (xy 277.89682 -303.572958) (xy 277.881236 -303.619639)
			(xy 277.858365 -303.663216) (xy 277.8288 -303.70256) (xy 277.793307 -303.736652) (xy 277.752804 -303.764608)
			(xy 277.708342 -303.785706) (xy 277.661071 -303.799398) (xy 277.612216 -303.80533) (xy 277.563041 -303.803349)
			(xy 277.514822 -303.793505) (xy 277.468806 -303.776053) (xy 277.426185 -303.751446) (xy 277.388064 -303.720321)
			(xy 277.355429 -303.683484) (xy 277.329126 -303.641888) (xy 277.309835 -303.596612) (xy 277.298058 -303.548828)
			(xy 277.294098 -303.499774) (xy 276.954996 -303.499774) (xy 276.954501 -303.524381) (xy 276.946606 -303.572958)
			(xy 276.931022 -303.619639) (xy 276.908151 -303.663216) (xy 276.878586 -303.70256) (xy 276.843093 -303.736652)
			(xy 276.80259 -303.764608) (xy 276.758128 -303.785706) (xy 276.710857 -303.799398) (xy 276.662002 -303.80533)
			(xy 276.612827 -303.803349) (xy 276.564608 -303.793505) (xy 276.518592 -303.776053) (xy 276.475971 -303.751446)
			(xy 276.43785 -303.720321) (xy 276.405215 -303.683484) (xy 276.378912 -303.641888) (xy 276.359621 -303.596612)
			(xy 276.347844 -303.548828) (xy 276.343884 -303.499774) (xy 276.005036 -303.499774) (xy 276.004541 -303.524381)
			(xy 275.996646 -303.572958) (xy 275.981062 -303.619639) (xy 275.958191 -303.663216) (xy 275.928626 -303.70256)
			(xy 275.893133 -303.736652) (xy 275.85263 -303.764608) (xy 275.808168 -303.785706) (xy 275.760897 -303.799398)
			(xy 275.712042 -303.80533) (xy 275.662867 -303.803349) (xy 275.614648 -303.793505) (xy 275.568632 -303.776053)
			(xy 275.526011 -303.751446) (xy 275.48789 -303.720321) (xy 275.455255 -303.683484) (xy 275.428952 -303.641888)
			(xy 275.409661 -303.596612) (xy 275.397884 -303.548828) (xy 275.393924 -303.499774) (xy 275.07692 -303.499774)
			(xy 275.076416 -303.525482) (xy 275.068373 -303.576264) (xy 275.052485 -303.625163) (xy 275.029142 -303.670975)
			(xy 274.998921 -303.712571) (xy 274.962565 -303.748927) (xy 274.920969 -303.779148) (xy 274.875157 -303.802491)
			(xy 274.826258 -303.818379) (xy 274.775476 -303.826422) (xy 274.72406 -303.826422) (xy 274.673278 -303.818379)
			(xy 274.624379 -303.802491) (xy 274.578567 -303.779148) (xy 274.536971 -303.748927) (xy 274.500615 -303.712571)
			(xy 274.470394 -303.670975) (xy 274.447051 -303.625163) (xy 274.431163 -303.576264) (xy 274.42312 -303.525482)
			(xy 274.126456 -303.525482) (xy 274.118413 -303.576264) (xy 274.102525 -303.625163) (xy 274.079182 -303.670975)
			(xy 274.048961 -303.712571) (xy 274.012605 -303.748927) (xy 273.971009 -303.779148) (xy 273.925197 -303.802491)
			(xy 273.876298 -303.818379) (xy 273.825516 -303.826422) (xy 273.7741 -303.826422) (xy 273.723318 -303.818379)
			(xy 273.674419 -303.802491) (xy 273.628607 -303.779148) (xy 273.587011 -303.748927) (xy 273.550655 -303.712571)
			(xy 273.520434 -303.670975) (xy 273.497091 -303.625163) (xy 273.481203 -303.576264) (xy 273.47316 -303.525482)
			(xy 273.154482 -303.525482) (xy 273.146766 -303.572958) (xy 273.131182 -303.619639) (xy 273.108311 -303.663216)
			(xy 273.078746 -303.70256) (xy 273.043253 -303.736652) (xy 273.00275 -303.764608) (xy 272.958288 -303.785706)
			(xy 272.911017 -303.799398) (xy 272.862162 -303.80533) (xy 272.812987 -303.803349) (xy 272.764768 -303.793505)
			(xy 272.718752 -303.776053) (xy 272.676131 -303.751446) (xy 272.63801 -303.720321) (xy 272.605375 -303.683484)
			(xy 272.579072 -303.641888) (xy 272.559781 -303.596612) (xy 272.548004 -303.548828) (xy 272.544044 -303.499774)
			(xy 272.22704 -303.499774) (xy 272.226536 -303.525482) (xy 272.218493 -303.576264) (xy 272.202605 -303.625163)
			(xy 272.179262 -303.670975) (xy 272.149041 -303.712571) (xy 272.112685 -303.748927) (xy 272.071089 -303.779148)
			(xy 272.025277 -303.802491) (xy 271.976378 -303.818379) (xy 271.925596 -303.826422) (xy 271.87418 -303.826422)
			(xy 271.823398 -303.818379) (xy 271.774499 -303.802491) (xy 271.728687 -303.779148) (xy 271.687091 -303.748927)
			(xy 271.650735 -303.712571) (xy 271.620514 -303.670975) (xy 271.597171 -303.625163) (xy 271.581283 -303.576264)
			(xy 271.57324 -303.525482) (xy 271.276576 -303.525482) (xy 271.268533 -303.576264) (xy 271.252645 -303.625163)
			(xy 271.229302 -303.670975) (xy 271.199081 -303.712571) (xy 271.162725 -303.748927) (xy 271.121129 -303.779148)
			(xy 271.075317 -303.802491) (xy 271.026418 -303.818379) (xy 270.975636 -303.826422) (xy 270.92422 -303.826422)
			(xy 270.873438 -303.818379) (xy 270.824539 -303.802491) (xy 270.778727 -303.779148) (xy 270.737131 -303.748927)
			(xy 270.700775 -303.712571) (xy 270.670554 -303.670975) (xy 270.647211 -303.625163) (xy 270.631323 -303.576264)
			(xy 270.62328 -303.525482) (xy 270.304348 -303.525482) (xy 270.296632 -303.572958) (xy 270.281048 -303.619639)
			(xy 270.258177 -303.663216) (xy 270.228612 -303.70256) (xy 270.193119 -303.736652) (xy 270.152616 -303.764608)
			(xy 270.108154 -303.785706) (xy 270.060883 -303.799398) (xy 270.012028 -303.80533) (xy 269.962853 -303.803349)
			(xy 269.914634 -303.793505) (xy 269.868618 -303.776053) (xy 269.825997 -303.751446) (xy 269.787876 -303.720321)
			(xy 269.755241 -303.683484) (xy 269.728938 -303.641888) (xy 269.709647 -303.596612) (xy 269.69787 -303.548828)
			(xy 269.69391 -303.499774) (xy 269.355062 -303.499774) (xy 269.354567 -303.524381) (xy 269.346672 -303.572958)
			(xy 269.331088 -303.619639) (xy 269.308217 -303.663216) (xy 269.278652 -303.70256) (xy 269.243159 -303.736652)
			(xy 269.202656 -303.764608) (xy 269.158194 -303.785706) (xy 269.110923 -303.799398) (xy 269.062068 -303.80533)
			(xy 269.012893 -303.803349) (xy 268.964674 -303.793505) (xy 268.918658 -303.776053) (xy 268.876037 -303.751446)
			(xy 268.837916 -303.720321) (xy 268.805281 -303.683484) (xy 268.778978 -303.641888) (xy 268.759687 -303.596612)
			(xy 268.74791 -303.548828) (xy 268.74395 -303.499774) (xy 234.792266 -303.499774) (xy 235.029502 -303.73701)
			(xy 235.03001 -303.737518) (xy 235.037387 -303.744111) (xy 235.055687 -303.751582) (xy 235.06557 -303.751996)
			(xy 245.67261 -303.751996) (xy 245.682679 -303.752421) (xy 245.701282 -303.760137) (xy 245.708678 -303.766982)
			(xy 245.91645 -303.974754) (xy 278.719038 -303.974754) (xy 278.722998 -303.9257) (xy 278.734775 -303.877916)
			(xy 278.754066 -303.83264) (xy 278.780369 -303.791044) (xy 278.813004 -303.754207) (xy 278.851125 -303.723082)
			(xy 278.893746 -303.698475) (xy 278.939762 -303.681023) (xy 278.987981 -303.671179) (xy 279.037156 -303.669198)
			(xy 279.086011 -303.67513) (xy 279.133282 -303.688822) (xy 279.177744 -303.70992) (xy 279.218247 -303.737876)
			(xy 279.25374 -303.771968) (xy 279.283305 -303.811312) (xy 279.306176 -303.854889) (xy 279.32176 -303.90157)
			(xy 279.329655 -303.950147) (xy 279.33015 -303.974754) (xy 279.668998 -303.974754) (xy 279.672958 -303.9257)
			(xy 279.684735 -303.877916) (xy 279.704026 -303.83264) (xy 279.730329 -303.791044) (xy 279.762964 -303.754207)
			(xy 279.801085 -303.723082) (xy 279.843706 -303.698475) (xy 279.889722 -303.681023) (xy 279.937941 -303.671179)
			(xy 279.987116 -303.669198) (xy 280.035971 -303.67513) (xy 280.083242 -303.688822) (xy 280.127704 -303.70992)
			(xy 280.168207 -303.737876) (xy 280.2037 -303.771968) (xy 280.233265 -303.811312) (xy 280.256136 -303.854889)
			(xy 280.27172 -303.90157) (xy 280.279615 -303.950147) (xy 280.28011 -303.974754) (xy 280.618958 -303.974754)
			(xy 280.622918 -303.9257) (xy 280.634695 -303.877916) (xy 280.653986 -303.83264) (xy 280.680289 -303.791044)
			(xy 280.712924 -303.754207) (xy 280.751045 -303.723082) (xy 280.793666 -303.698475) (xy 280.839682 -303.681023)
			(xy 280.887901 -303.671179) (xy 280.937076 -303.669198) (xy 280.985931 -303.67513) (xy 281.033202 -303.688822)
			(xy 281.077664 -303.70992) (xy 281.118167 -303.737876) (xy 281.15366 -303.771968) (xy 281.183225 -303.811312)
			(xy 281.206096 -303.854889) (xy 281.22168 -303.90157) (xy 281.229575 -303.950147) (xy 281.23007 -303.974754)
			(xy 281.568918 -303.974754) (xy 281.572878 -303.9257) (xy 281.584655 -303.877916) (xy 281.603946 -303.83264)
			(xy 281.630249 -303.791044) (xy 281.662884 -303.754207) (xy 281.701005 -303.723082) (xy 281.743626 -303.698475)
			(xy 281.789642 -303.681023) (xy 281.837861 -303.671179) (xy 281.887036 -303.669198) (xy 281.935891 -303.67513)
			(xy 281.983162 -303.688822) (xy 282.027624 -303.70992) (xy 282.068127 -303.737876) (xy 282.10362 -303.771968)
			(xy 282.133185 -303.811312) (xy 282.156056 -303.854889) (xy 282.17164 -303.90157) (xy 282.179535 -303.950147)
			(xy 282.18003 -303.974754) (xy 282.519132 -303.974754) (xy 282.523092 -303.9257) (xy 282.534869 -303.877916)
			(xy 282.55416 -303.83264) (xy 282.580463 -303.791044) (xy 282.613098 -303.754207) (xy 282.651219 -303.723082)
			(xy 282.69384 -303.698475) (xy 282.739856 -303.681023) (xy 282.788075 -303.671179) (xy 282.83725 -303.669198)
			(xy 282.886105 -303.67513) (xy 282.933376 -303.688822) (xy 282.977838 -303.70992) (xy 283.018341 -303.737876)
			(xy 283.053834 -303.771968) (xy 283.083399 -303.811312) (xy 283.10627 -303.854889) (xy 283.121854 -303.90157)
			(xy 283.129749 -303.950147) (xy 283.130244 -303.974754) (xy 283.469092 -303.974754) (xy 283.473052 -303.9257)
			(xy 283.484829 -303.877916) (xy 283.50412 -303.83264) (xy 283.530423 -303.791044) (xy 283.563058 -303.754207)
			(xy 283.601179 -303.723082) (xy 283.6438 -303.698475) (xy 283.689816 -303.681023) (xy 283.738035 -303.671179)
			(xy 283.78721 -303.669198) (xy 283.836065 -303.67513) (xy 283.883336 -303.688822) (xy 283.927798 -303.70992)
			(xy 283.968301 -303.737876) (xy 284.003794 -303.771968) (xy 284.033359 -303.811312) (xy 284.05623 -303.854889)
			(xy 284.071814 -303.90157) (xy 284.079709 -303.950147) (xy 284.080204 -303.974754) (xy 284.419052 -303.974754)
			(xy 284.423012 -303.9257) (xy 284.434789 -303.877916) (xy 284.45408 -303.83264) (xy 284.480383 -303.791044)
			(xy 284.513018 -303.754207) (xy 284.551139 -303.723082) (xy 284.59376 -303.698475) (xy 284.639776 -303.681023)
			(xy 284.687995 -303.671179) (xy 284.73717 -303.669198) (xy 284.786025 -303.67513) (xy 284.833296 -303.688822)
			(xy 284.877758 -303.70992) (xy 284.918261 -303.737876) (xy 284.953754 -303.771968) (xy 284.983319 -303.811312)
			(xy 285.00619 -303.854889) (xy 285.021774 -303.90157) (xy 285.029669 -303.950147) (xy 285.030164 -303.974754)
			(xy 285.369012 -303.974754) (xy 285.372972 -303.9257) (xy 285.384749 -303.877916) (xy 285.40404 -303.83264)
			(xy 285.430343 -303.791044) (xy 285.462978 -303.754207) (xy 285.501099 -303.723082) (xy 285.54372 -303.698475)
			(xy 285.589736 -303.681023) (xy 285.637955 -303.671179) (xy 285.68713 -303.669198) (xy 285.735985 -303.67513)
			(xy 285.783256 -303.688822) (xy 285.827718 -303.70992) (xy 285.868221 -303.737876) (xy 285.903714 -303.771968)
			(xy 285.933279 -303.811312) (xy 285.95615 -303.854889) (xy 285.971734 -303.90157) (xy 285.979629 -303.950147)
			(xy 285.980124 -303.974754) (xy 286.318972 -303.974754) (xy 286.322932 -303.9257) (xy 286.334709 -303.877916)
			(xy 286.354 -303.83264) (xy 286.380303 -303.791044) (xy 286.412938 -303.754207) (xy 286.451059 -303.723082)
			(xy 286.49368 -303.698475) (xy 286.539696 -303.681023) (xy 286.587915 -303.671179) (xy 286.63709 -303.669198)
			(xy 286.685945 -303.67513) (xy 286.733216 -303.688822) (xy 286.777678 -303.70992) (xy 286.818181 -303.737876)
			(xy 286.853674 -303.771968) (xy 286.883239 -303.811312) (xy 286.90611 -303.854889) (xy 286.921694 -303.90157)
			(xy 286.929589 -303.950147) (xy 286.930084 -303.974754) (xy 287.268932 -303.974754) (xy 287.272892 -303.9257)
			(xy 287.284669 -303.877916) (xy 287.30396 -303.83264) (xy 287.330263 -303.791044) (xy 287.362898 -303.754207)
			(xy 287.401019 -303.723082) (xy 287.44364 -303.698475) (xy 287.489656 -303.681023) (xy 287.537875 -303.671179)
			(xy 287.58705 -303.669198) (xy 287.635905 -303.67513) (xy 287.683176 -303.688822) (xy 287.727638 -303.70992)
			(xy 287.768141 -303.737876) (xy 287.803634 -303.771968) (xy 287.833199 -303.811312) (xy 287.85607 -303.854889)
			(xy 287.871654 -303.90157) (xy 287.879549 -303.950147) (xy 287.880044 -303.974754) (xy 288.218892 -303.974754)
			(xy 288.222852 -303.9257) (xy 288.234629 -303.877916) (xy 288.25392 -303.83264) (xy 288.280223 -303.791044)
			(xy 288.312858 -303.754207) (xy 288.350979 -303.723082) (xy 288.3936 -303.698475) (xy 288.439616 -303.681023)
			(xy 288.487835 -303.671179) (xy 288.53701 -303.669198) (xy 288.585865 -303.67513) (xy 288.633136 -303.688822)
			(xy 288.677598 -303.70992) (xy 288.718101 -303.737876) (xy 288.753594 -303.771968) (xy 288.783159 -303.811312)
			(xy 288.80603 -303.854889) (xy 288.821614 -303.90157) (xy 288.829509 -303.950147) (xy 288.830004 -303.974754)
			(xy 289.169106 -303.974754) (xy 289.173066 -303.9257) (xy 289.184843 -303.877916) (xy 289.204134 -303.83264)
			(xy 289.230437 -303.791044) (xy 289.263072 -303.754207) (xy 289.301193 -303.723082) (xy 289.343814 -303.698475)
			(xy 289.38983 -303.681023) (xy 289.438049 -303.671179) (xy 289.487224 -303.669198) (xy 289.536079 -303.67513)
			(xy 289.58335 -303.688822) (xy 289.627812 -303.70992) (xy 289.668315 -303.737876) (xy 289.703808 -303.771968)
			(xy 289.733373 -303.811312) (xy 289.756244 -303.854889) (xy 289.771828 -303.90157) (xy 289.779723 -303.950147)
			(xy 289.780218 -303.974754) (xy 290.119066 -303.974754) (xy 290.123026 -303.9257) (xy 290.134803 -303.877916)
			(xy 290.154094 -303.83264) (xy 290.180397 -303.791044) (xy 290.213032 -303.754207) (xy 290.251153 -303.723082)
			(xy 290.293774 -303.698475) (xy 290.33979 -303.681023) (xy 290.388009 -303.671179) (xy 290.437184 -303.669198)
			(xy 290.486039 -303.67513) (xy 290.53331 -303.688822) (xy 290.577772 -303.70992) (xy 290.618275 -303.737876)
			(xy 290.653768 -303.771968) (xy 290.683333 -303.811312) (xy 290.706204 -303.854889) (xy 290.721788 -303.90157)
			(xy 290.729683 -303.950147) (xy 290.730178 -303.974754) (xy 292.018986 -303.974754) (xy 292.022946 -303.9257)
			(xy 292.034723 -303.877916) (xy 292.054014 -303.83264) (xy 292.080317 -303.791044) (xy 292.112952 -303.754207)
			(xy 292.151073 -303.723082) (xy 292.193694 -303.698475) (xy 292.23971 -303.681023) (xy 292.287929 -303.671179)
			(xy 292.337104 -303.669198) (xy 292.385959 -303.67513) (xy 292.43323 -303.688822) (xy 292.477692 -303.70992)
			(xy 292.518195 -303.737876) (xy 292.553688 -303.771968) (xy 292.583253 -303.811312) (xy 292.606124 -303.854889)
			(xy 292.621708 -303.90157) (xy 292.629603 -303.950147) (xy 292.630098 -303.974754) (xy 292.968946 -303.974754)
			(xy 292.972906 -303.9257) (xy 292.984683 -303.877916) (xy 293.003974 -303.83264) (xy 293.030277 -303.791044)
			(xy 293.062912 -303.754207) (xy 293.101033 -303.723082) (xy 293.143654 -303.698475) (xy 293.18967 -303.681023)
			(xy 293.237889 -303.671179) (xy 293.287064 -303.669198) (xy 293.335919 -303.67513) (xy 293.38319 -303.688822)
			(xy 293.427652 -303.70992) (xy 293.468155 -303.737876) (xy 293.503648 -303.771968) (xy 293.533213 -303.811312)
			(xy 293.556084 -303.854889) (xy 293.571668 -303.90157) (xy 293.579563 -303.950147) (xy 293.580058 -303.974754)
			(xy 293.918906 -303.974754) (xy 293.922866 -303.9257) (xy 293.934643 -303.877916) (xy 293.953934 -303.83264)
			(xy 293.980237 -303.791044) (xy 294.012872 -303.754207) (xy 294.050993 -303.723082) (xy 294.093614 -303.698475)
			(xy 294.13963 -303.681023) (xy 294.187849 -303.671179) (xy 294.237024 -303.669198) (xy 294.285879 -303.67513)
			(xy 294.33315 -303.688822) (xy 294.377612 -303.70992) (xy 294.418115 -303.737876) (xy 294.453608 -303.771968)
			(xy 294.483173 -303.811312) (xy 294.506044 -303.854889) (xy 294.521628 -303.90157) (xy 294.529523 -303.950147)
			(xy 294.530018 -303.974754) (xy 294.86912 -303.974754) (xy 294.87308 -303.9257) (xy 294.884857 -303.877916)
			(xy 294.904148 -303.83264) (xy 294.930451 -303.791044) (xy 294.963086 -303.754207) (xy 295.001207 -303.723082)
			(xy 295.043828 -303.698475) (xy 295.089844 -303.681023) (xy 295.138063 -303.671179) (xy 295.187238 -303.669198)
			(xy 295.236093 -303.67513) (xy 295.283364 -303.688822) (xy 295.327826 -303.70992) (xy 295.368329 -303.737876)
			(xy 295.403822 -303.771968) (xy 295.433387 -303.811312) (xy 295.456258 -303.854889) (xy 295.471842 -303.90157)
			(xy 295.479737 -303.950147) (xy 295.480232 -303.974754) (xy 295.81908 -303.974754) (xy 295.82304 -303.9257)
			(xy 295.834817 -303.877916) (xy 295.854108 -303.83264) (xy 295.880411 -303.791044) (xy 295.913046 -303.754207)
			(xy 295.951167 -303.723082) (xy 295.993788 -303.698475) (xy 296.039804 -303.681023) (xy 296.088023 -303.671179)
			(xy 296.137198 -303.669198) (xy 296.186053 -303.67513) (xy 296.233324 -303.688822) (xy 296.277786 -303.70992)
			(xy 296.318289 -303.737876) (xy 296.353782 -303.771968) (xy 296.383347 -303.811312) (xy 296.406218 -303.854889)
			(xy 296.421802 -303.90157) (xy 296.429697 -303.950147) (xy 296.430192 -303.974754) (xy 296.76904 -303.974754)
			(xy 296.773 -303.9257) (xy 296.784777 -303.877916) (xy 296.804068 -303.83264) (xy 296.830371 -303.791044)
			(xy 296.863006 -303.754207) (xy 296.901127 -303.723082) (xy 296.943748 -303.698475) (xy 296.989764 -303.681023)
			(xy 297.037983 -303.671179) (xy 297.087158 -303.669198) (xy 297.136013 -303.67513) (xy 297.183284 -303.688822)
			(xy 297.227746 -303.70992) (xy 297.268249 -303.737876) (xy 297.303742 -303.771968) (xy 297.333307 -303.811312)
			(xy 297.356178 -303.854889) (xy 297.371762 -303.90157) (xy 297.379657 -303.950147) (xy 297.380152 -303.974754)
			(xy 297.719 -303.974754) (xy 297.72296 -303.9257) (xy 297.734737 -303.877916) (xy 297.754028 -303.83264)
			(xy 297.780331 -303.791044) (xy 297.812966 -303.754207) (xy 297.851087 -303.723082) (xy 297.893708 -303.698475)
			(xy 297.939724 -303.681023) (xy 297.987943 -303.671179) (xy 298.037118 -303.669198) (xy 298.085973 -303.67513)
			(xy 298.133244 -303.688822) (xy 298.177706 -303.70992) (xy 298.218209 -303.737876) (xy 298.253702 -303.771968)
			(xy 298.283267 -303.811312) (xy 298.306138 -303.854889) (xy 298.321722 -303.90157) (xy 298.329617 -303.950147)
			(xy 298.330112 -303.974754) (xy 298.66896 -303.974754) (xy 298.67292 -303.9257) (xy 298.684697 -303.877916)
			(xy 298.703988 -303.83264) (xy 298.730291 -303.791044) (xy 298.762926 -303.754207) (xy 298.801047 -303.723082)
			(xy 298.843668 -303.698475) (xy 298.889684 -303.681023) (xy 298.937903 -303.671179) (xy 298.987078 -303.669198)
			(xy 299.035933 -303.67513) (xy 299.083204 -303.688822) (xy 299.127666 -303.70992) (xy 299.168169 -303.737876)
			(xy 299.203662 -303.771968) (xy 299.233227 -303.811312) (xy 299.256098 -303.854889) (xy 299.271682 -303.90157)
			(xy 299.279577 -303.950147) (xy 299.280072 -303.974754) (xy 299.61892 -303.974754) (xy 299.62288 -303.9257)
			(xy 299.634657 -303.877916) (xy 299.653948 -303.83264) (xy 299.680251 -303.791044) (xy 299.712886 -303.754207)
			(xy 299.751007 -303.723082) (xy 299.793628 -303.698475) (xy 299.839644 -303.681023) (xy 299.887863 -303.671179)
			(xy 299.937038 -303.669198) (xy 299.985893 -303.67513) (xy 300.033164 -303.688822) (xy 300.077626 -303.70992)
			(xy 300.118129 -303.737876) (xy 300.153622 -303.771968) (xy 300.183187 -303.811312) (xy 300.206058 -303.854889)
			(xy 300.221642 -303.90157) (xy 300.229537 -303.950147) (xy 300.229935 -303.969928) (xy 300.57396 -303.969928)
			(xy 300.57792 -303.920874) (xy 300.589697 -303.87309) (xy 300.608988 -303.827814) (xy 300.635291 -303.786218)
			(xy 300.667926 -303.749381) (xy 300.706047 -303.718256) (xy 300.748668 -303.693649) (xy 300.794684 -303.676197)
			(xy 300.842903 -303.666353) (xy 300.892078 -303.664372) (xy 300.940933 -303.670304) (xy 300.988204 -303.683996)
			(xy 301.032666 -303.705094) (xy 301.073169 -303.73305) (xy 301.108662 -303.767142) (xy 301.138227 -303.806486)
			(xy 301.161098 -303.850063) (xy 301.176682 -303.896744) (xy 301.184577 -303.945321) (xy 301.185072 -303.969928)
			(xy 301.184975 -303.974754) (xy 301.519094 -303.974754) (xy 301.523054 -303.9257) (xy 301.534831 -303.877916)
			(xy 301.554122 -303.83264) (xy 301.580425 -303.791044) (xy 301.61306 -303.754207) (xy 301.651181 -303.723082)
			(xy 301.693802 -303.698475) (xy 301.739818 -303.681023) (xy 301.788037 -303.671179) (xy 301.837212 -303.669198)
			(xy 301.886067 -303.67513) (xy 301.933338 -303.688822) (xy 301.9778 -303.70992) (xy 302.018303 -303.737876)
			(xy 302.053796 -303.771968) (xy 302.083361 -303.811312) (xy 302.106232 -303.854889) (xy 302.121816 -303.90157)
			(xy 302.129711 -303.950147) (xy 302.130206 -303.974754) (xy 302.469054 -303.974754) (xy 302.473014 -303.9257)
			(xy 302.484791 -303.877916) (xy 302.504082 -303.83264) (xy 302.530385 -303.791044) (xy 302.56302 -303.754207)
			(xy 302.601141 -303.723082) (xy 302.643762 -303.698475) (xy 302.689778 -303.681023) (xy 302.737997 -303.671179)
			(xy 302.787172 -303.669198) (xy 302.836027 -303.67513) (xy 302.883298 -303.688822) (xy 302.92776 -303.70992)
			(xy 302.968263 -303.737876) (xy 303.003756 -303.771968) (xy 303.033321 -303.811312) (xy 303.056192 -303.854889)
			(xy 303.071776 -303.90157) (xy 303.079671 -303.950147) (xy 303.080166 -303.974754) (xy 303.419014 -303.974754)
			(xy 303.422974 -303.9257) (xy 303.434751 -303.877916) (xy 303.454042 -303.83264) (xy 303.480345 -303.791044)
			(xy 303.51298 -303.754207) (xy 303.551101 -303.723082) (xy 303.593722 -303.698475) (xy 303.639738 -303.681023)
			(xy 303.687957 -303.671179) (xy 303.737132 -303.669198) (xy 303.785987 -303.67513) (xy 303.833258 -303.688822)
			(xy 303.87772 -303.70992) (xy 303.918223 -303.737876) (xy 303.953716 -303.771968) (xy 303.983281 -303.811312)
			(xy 304.006152 -303.854889) (xy 304.021736 -303.90157) (xy 304.029631 -303.950147) (xy 304.030126 -303.974754)
			(xy 304.368974 -303.974754) (xy 304.372934 -303.9257) (xy 304.384711 -303.877916) (xy 304.404002 -303.83264)
			(xy 304.430305 -303.791044) (xy 304.46294 -303.754207) (xy 304.501061 -303.723082) (xy 304.543682 -303.698475)
			(xy 304.589698 -303.681023) (xy 304.637917 -303.671179) (xy 304.687092 -303.669198) (xy 304.735947 -303.67513)
			(xy 304.783218 -303.688822) (xy 304.82768 -303.70992) (xy 304.868183 -303.737876) (xy 304.903676 -303.771968)
			(xy 304.933241 -303.811312) (xy 304.956112 -303.854889) (xy 304.971696 -303.90157) (xy 304.979591 -303.950147)
			(xy 304.980086 -303.974754) (xy 304.979591 -303.999361) (xy 304.971696 -304.047938) (xy 304.956112 -304.094619)
			(xy 304.933241 -304.138196) (xy 304.903676 -304.17754) (xy 304.868183 -304.211632) (xy 304.82768 -304.239588)
			(xy 304.783218 -304.260686) (xy 304.735947 -304.274378) (xy 304.687092 -304.28031) (xy 304.637917 -304.278329)
			(xy 304.589698 -304.268485) (xy 304.543682 -304.251033) (xy 304.501061 -304.226426) (xy 304.46294 -304.195301)
			(xy 304.430305 -304.158464) (xy 304.404002 -304.116868) (xy 304.384711 -304.071592) (xy 304.372934 -304.023808)
			(xy 304.368974 -303.974754) (xy 304.030126 -303.974754) (xy 304.029631 -303.999361) (xy 304.021736 -304.047938)
			(xy 304.006152 -304.094619) (xy 303.983281 -304.138196) (xy 303.953716 -304.17754) (xy 303.918223 -304.211632)
			(xy 303.87772 -304.239588) (xy 303.833258 -304.260686) (xy 303.785987 -304.274378) (xy 303.737132 -304.28031)
			(xy 303.687957 -304.278329) (xy 303.639738 -304.268485) (xy 303.593722 -304.251033) (xy 303.551101 -304.226426)
			(xy 303.51298 -304.195301) (xy 303.480345 -304.158464) (xy 303.454042 -304.116868) (xy 303.434751 -304.071592)
			(xy 303.422974 -304.023808) (xy 303.419014 -303.974754) (xy 303.080166 -303.974754) (xy 303.079671 -303.999361)
			(xy 303.071776 -304.047938) (xy 303.056192 -304.094619) (xy 303.033321 -304.138196) (xy 303.003756 -304.17754)
			(xy 302.968263 -304.211632) (xy 302.92776 -304.239588) (xy 302.883298 -304.260686) (xy 302.836027 -304.274378)
			(xy 302.787172 -304.28031) (xy 302.737997 -304.278329) (xy 302.689778 -304.268485) (xy 302.643762 -304.251033)
			(xy 302.601141 -304.226426) (xy 302.56302 -304.195301) (xy 302.530385 -304.158464) (xy 302.504082 -304.116868)
			(xy 302.484791 -304.071592) (xy 302.473014 -304.023808) (xy 302.469054 -303.974754) (xy 302.130206 -303.974754)
			(xy 302.129711 -303.999361) (xy 302.121816 -304.047938) (xy 302.106232 -304.094619) (xy 302.083361 -304.138196)
			(xy 302.053796 -304.17754) (xy 302.018303 -304.211632) (xy 301.9778 -304.239588) (xy 301.933338 -304.260686)
			(xy 301.886067 -304.274378) (xy 301.837212 -304.28031) (xy 301.788037 -304.278329) (xy 301.739818 -304.268485)
			(xy 301.693802 -304.251033) (xy 301.651181 -304.226426) (xy 301.61306 -304.195301) (xy 301.580425 -304.158464)
			(xy 301.554122 -304.116868) (xy 301.534831 -304.071592) (xy 301.523054 -304.023808) (xy 301.519094 -303.974754)
			(xy 301.184975 -303.974754) (xy 301.184577 -303.994535) (xy 301.176682 -304.043112) (xy 301.161098 -304.089793)
			(xy 301.138227 -304.13337) (xy 301.108662 -304.172714) (xy 301.073169 -304.206806) (xy 301.032666 -304.234762)
			(xy 300.988204 -304.25586) (xy 300.940933 -304.269552) (xy 300.892078 -304.275484) (xy 300.842903 -304.273503)
			(xy 300.794684 -304.263659) (xy 300.748668 -304.246207) (xy 300.706047 -304.2216) (xy 300.667926 -304.190475)
			(xy 300.635291 -304.153638) (xy 300.608988 -304.112042) (xy 300.589697 -304.066766) (xy 300.57792 -304.018982)
			(xy 300.57396 -303.969928) (xy 300.229935 -303.969928) (xy 300.230032 -303.974754) (xy 300.229537 -303.999361)
			(xy 300.221642 -304.047938) (xy 300.206058 -304.094619) (xy 300.183187 -304.138196) (xy 300.153622 -304.17754)
			(xy 300.118129 -304.211632) (xy 300.077626 -304.239588) (xy 300.033164 -304.260686) (xy 299.985893 -304.274378)
			(xy 299.937038 -304.28031) (xy 299.887863 -304.278329) (xy 299.839644 -304.268485) (xy 299.793628 -304.251033)
			(xy 299.751007 -304.226426) (xy 299.712886 -304.195301) (xy 299.680251 -304.158464) (xy 299.653948 -304.116868)
			(xy 299.634657 -304.071592) (xy 299.62288 -304.023808) (xy 299.61892 -303.974754) (xy 299.280072 -303.974754)
			(xy 299.279577 -303.999361) (xy 299.271682 -304.047938) (xy 299.256098 -304.094619) (xy 299.233227 -304.138196)
			(xy 299.203662 -304.17754) (xy 299.168169 -304.211632) (xy 299.127666 -304.239588) (xy 299.083204 -304.260686)
			(xy 299.035933 -304.274378) (xy 298.987078 -304.28031) (xy 298.937903 -304.278329) (xy 298.889684 -304.268485)
			(xy 298.843668 -304.251033) (xy 298.801047 -304.226426) (xy 298.762926 -304.195301) (xy 298.730291 -304.158464)
			(xy 298.703988 -304.116868) (xy 298.684697 -304.071592) (xy 298.67292 -304.023808) (xy 298.66896 -303.974754)
			(xy 298.330112 -303.974754) (xy 298.329617 -303.999361) (xy 298.321722 -304.047938) (xy 298.306138 -304.094619)
			(xy 298.283267 -304.138196) (xy 298.253702 -304.17754) (xy 298.218209 -304.211632) (xy 298.177706 -304.239588)
			(xy 298.133244 -304.260686) (xy 298.085973 -304.274378) (xy 298.037118 -304.28031) (xy 297.987943 -304.278329)
			(xy 297.939724 -304.268485) (xy 297.893708 -304.251033) (xy 297.851087 -304.226426) (xy 297.812966 -304.195301)
			(xy 297.780331 -304.158464) (xy 297.754028 -304.116868) (xy 297.734737 -304.071592) (xy 297.72296 -304.023808)
			(xy 297.719 -303.974754) (xy 297.380152 -303.974754) (xy 297.379657 -303.999361) (xy 297.371762 -304.047938)
			(xy 297.356178 -304.094619) (xy 297.333307 -304.138196) (xy 297.303742 -304.17754) (xy 297.268249 -304.211632)
			(xy 297.227746 -304.239588) (xy 297.183284 -304.260686) (xy 297.136013 -304.274378) (xy 297.087158 -304.28031)
			(xy 297.037983 -304.278329) (xy 296.989764 -304.268485) (xy 296.943748 -304.251033) (xy 296.901127 -304.226426)
			(xy 296.863006 -304.195301) (xy 296.830371 -304.158464) (xy 296.804068 -304.116868) (xy 296.784777 -304.071592)
			(xy 296.773 -304.023808) (xy 296.76904 -303.974754) (xy 296.430192 -303.974754) (xy 296.429697 -303.999361)
			(xy 296.421802 -304.047938) (xy 296.406218 -304.094619) (xy 296.383347 -304.138196) (xy 296.353782 -304.17754)
			(xy 296.318289 -304.211632) (xy 296.277786 -304.239588) (xy 296.233324 -304.260686) (xy 296.186053 -304.274378)
			(xy 296.137198 -304.28031) (xy 296.088023 -304.278329) (xy 296.039804 -304.268485) (xy 295.993788 -304.251033)
			(xy 295.951167 -304.226426) (xy 295.913046 -304.195301) (xy 295.880411 -304.158464) (xy 295.854108 -304.116868)
			(xy 295.834817 -304.071592) (xy 295.82304 -304.023808) (xy 295.81908 -303.974754) (xy 295.480232 -303.974754)
			(xy 295.479737 -303.999361) (xy 295.471842 -304.047938) (xy 295.456258 -304.094619) (xy 295.433387 -304.138196)
			(xy 295.403822 -304.17754) (xy 295.368329 -304.211632) (xy 295.327826 -304.239588) (xy 295.283364 -304.260686)
			(xy 295.236093 -304.274378) (xy 295.187238 -304.28031) (xy 295.138063 -304.278329) (xy 295.089844 -304.268485)
			(xy 295.043828 -304.251033) (xy 295.001207 -304.226426) (xy 294.963086 -304.195301) (xy 294.930451 -304.158464)
			(xy 294.904148 -304.116868) (xy 294.884857 -304.071592) (xy 294.87308 -304.023808) (xy 294.86912 -303.974754)
			(xy 294.530018 -303.974754) (xy 294.529523 -303.999361) (xy 294.521628 -304.047938) (xy 294.506044 -304.094619)
			(xy 294.483173 -304.138196) (xy 294.453608 -304.17754) (xy 294.418115 -304.211632) (xy 294.377612 -304.239588)
			(xy 294.33315 -304.260686) (xy 294.285879 -304.274378) (xy 294.237024 -304.28031) (xy 294.187849 -304.278329)
			(xy 294.13963 -304.268485) (xy 294.093614 -304.251033) (xy 294.050993 -304.226426) (xy 294.012872 -304.195301)
			(xy 293.980237 -304.158464) (xy 293.953934 -304.116868) (xy 293.934643 -304.071592) (xy 293.922866 -304.023808)
			(xy 293.918906 -303.974754) (xy 293.580058 -303.974754) (xy 293.579563 -303.999361) (xy 293.571668 -304.047938)
			(xy 293.556084 -304.094619) (xy 293.533213 -304.138196) (xy 293.503648 -304.17754) (xy 293.468155 -304.211632)
			(xy 293.427652 -304.239588) (xy 293.38319 -304.260686) (xy 293.335919 -304.274378) (xy 293.287064 -304.28031)
			(xy 293.237889 -304.278329) (xy 293.18967 -304.268485) (xy 293.143654 -304.251033) (xy 293.101033 -304.226426)
			(xy 293.062912 -304.195301) (xy 293.030277 -304.158464) (xy 293.003974 -304.116868) (xy 292.984683 -304.071592)
			(xy 292.972906 -304.023808) (xy 292.968946 -303.974754) (xy 292.630098 -303.974754) (xy 292.629603 -303.999361)
			(xy 292.621708 -304.047938) (xy 292.606124 -304.094619) (xy 292.583253 -304.138196) (xy 292.553688 -304.17754)
			(xy 292.518195 -304.211632) (xy 292.477692 -304.239588) (xy 292.43323 -304.260686) (xy 292.385959 -304.274378)
			(xy 292.337104 -304.28031) (xy 292.287929 -304.278329) (xy 292.23971 -304.268485) (xy 292.193694 -304.251033)
			(xy 292.151073 -304.226426) (xy 292.112952 -304.195301) (xy 292.080317 -304.158464) (xy 292.054014 -304.116868)
			(xy 292.034723 -304.071592) (xy 292.022946 -304.023808) (xy 292.018986 -303.974754) (xy 290.730178 -303.974754)
			(xy 290.729683 -303.999361) (xy 290.721788 -304.047938) (xy 290.706204 -304.094619) (xy 290.683333 -304.138196)
			(xy 290.653768 -304.17754) (xy 290.618275 -304.211632) (xy 290.577772 -304.239588) (xy 290.53331 -304.260686)
			(xy 290.486039 -304.274378) (xy 290.437184 -304.28031) (xy 290.388009 -304.278329) (xy 290.33979 -304.268485)
			(xy 290.293774 -304.251033) (xy 290.251153 -304.226426) (xy 290.213032 -304.195301) (xy 290.180397 -304.158464)
			(xy 290.154094 -304.116868) (xy 290.134803 -304.071592) (xy 290.123026 -304.023808) (xy 290.119066 -303.974754)
			(xy 289.780218 -303.974754) (xy 289.779723 -303.999361) (xy 289.771828 -304.047938) (xy 289.756244 -304.094619)
			(xy 289.733373 -304.138196) (xy 289.703808 -304.17754) (xy 289.668315 -304.211632) (xy 289.627812 -304.239588)
			(xy 289.58335 -304.260686) (xy 289.536079 -304.274378) (xy 289.487224 -304.28031) (xy 289.438049 -304.278329)
			(xy 289.38983 -304.268485) (xy 289.343814 -304.251033) (xy 289.301193 -304.226426) (xy 289.263072 -304.195301)
			(xy 289.230437 -304.158464) (xy 289.204134 -304.116868) (xy 289.184843 -304.071592) (xy 289.173066 -304.023808)
			(xy 289.169106 -303.974754) (xy 288.830004 -303.974754) (xy 288.829509 -303.999361) (xy 288.821614 -304.047938)
			(xy 288.80603 -304.094619) (xy 288.783159 -304.138196) (xy 288.753594 -304.17754) (xy 288.718101 -304.211632)
			(xy 288.677598 -304.239588) (xy 288.633136 -304.260686) (xy 288.585865 -304.274378) (xy 288.53701 -304.28031)
			(xy 288.487835 -304.278329) (xy 288.439616 -304.268485) (xy 288.3936 -304.251033) (xy 288.350979 -304.226426)
			(xy 288.312858 -304.195301) (xy 288.280223 -304.158464) (xy 288.25392 -304.116868) (xy 288.234629 -304.071592)
			(xy 288.222852 -304.023808) (xy 288.218892 -303.974754) (xy 287.880044 -303.974754) (xy 287.879549 -303.999361)
			(xy 287.871654 -304.047938) (xy 287.85607 -304.094619) (xy 287.833199 -304.138196) (xy 287.803634 -304.17754)
			(xy 287.768141 -304.211632) (xy 287.727638 -304.239588) (xy 287.683176 -304.260686) (xy 287.635905 -304.274378)
			(xy 287.58705 -304.28031) (xy 287.537875 -304.278329) (xy 287.489656 -304.268485) (xy 287.44364 -304.251033)
			(xy 287.401019 -304.226426) (xy 287.362898 -304.195301) (xy 287.330263 -304.158464) (xy 287.30396 -304.116868)
			(xy 287.284669 -304.071592) (xy 287.272892 -304.023808) (xy 287.268932 -303.974754) (xy 286.930084 -303.974754)
			(xy 286.929589 -303.999361) (xy 286.921694 -304.047938) (xy 286.90611 -304.094619) (xy 286.883239 -304.138196)
			(xy 286.853674 -304.17754) (xy 286.818181 -304.211632) (xy 286.777678 -304.239588) (xy 286.733216 -304.260686)
			(xy 286.685945 -304.274378) (xy 286.63709 -304.28031) (xy 286.587915 -304.278329) (xy 286.539696 -304.268485)
			(xy 286.49368 -304.251033) (xy 286.451059 -304.226426) (xy 286.412938 -304.195301) (xy 286.380303 -304.158464)
			(xy 286.354 -304.116868) (xy 286.334709 -304.071592) (xy 286.322932 -304.023808) (xy 286.318972 -303.974754)
			(xy 285.980124 -303.974754) (xy 285.979629 -303.999361) (xy 285.971734 -304.047938) (xy 285.95615 -304.094619)
			(xy 285.933279 -304.138196) (xy 285.903714 -304.17754) (xy 285.868221 -304.211632) (xy 285.827718 -304.239588)
			(xy 285.783256 -304.260686) (xy 285.735985 -304.274378) (xy 285.68713 -304.28031) (xy 285.637955 -304.278329)
			(xy 285.589736 -304.268485) (xy 285.54372 -304.251033) (xy 285.501099 -304.226426) (xy 285.462978 -304.195301)
			(xy 285.430343 -304.158464) (xy 285.40404 -304.116868) (xy 285.384749 -304.071592) (xy 285.372972 -304.023808)
			(xy 285.369012 -303.974754) (xy 285.030164 -303.974754) (xy 285.029669 -303.999361) (xy 285.021774 -304.047938)
			(xy 285.00619 -304.094619) (xy 284.983319 -304.138196) (xy 284.953754 -304.17754) (xy 284.918261 -304.211632)
			(xy 284.877758 -304.239588) (xy 284.833296 -304.260686) (xy 284.786025 -304.274378) (xy 284.73717 -304.28031)
			(xy 284.687995 -304.278329) (xy 284.639776 -304.268485) (xy 284.59376 -304.251033) (xy 284.551139 -304.226426)
			(xy 284.513018 -304.195301) (xy 284.480383 -304.158464) (xy 284.45408 -304.116868) (xy 284.434789 -304.071592)
			(xy 284.423012 -304.023808) (xy 284.419052 -303.974754) (xy 284.080204 -303.974754) (xy 284.079709 -303.999361)
			(xy 284.071814 -304.047938) (xy 284.05623 -304.094619) (xy 284.033359 -304.138196) (xy 284.003794 -304.17754)
			(xy 283.968301 -304.211632) (xy 283.927798 -304.239588) (xy 283.883336 -304.260686) (xy 283.836065 -304.274378)
			(xy 283.78721 -304.28031) (xy 283.738035 -304.278329) (xy 283.689816 -304.268485) (xy 283.6438 -304.251033)
			(xy 283.601179 -304.226426) (xy 283.563058 -304.195301) (xy 283.530423 -304.158464) (xy 283.50412 -304.116868)
			(xy 283.484829 -304.071592) (xy 283.473052 -304.023808) (xy 283.469092 -303.974754) (xy 283.130244 -303.974754)
			(xy 283.129749 -303.999361) (xy 283.121854 -304.047938) (xy 283.10627 -304.094619) (xy 283.083399 -304.138196)
			(xy 283.053834 -304.17754) (xy 283.018341 -304.211632) (xy 282.977838 -304.239588) (xy 282.933376 -304.260686)
			(xy 282.886105 -304.274378) (xy 282.83725 -304.28031) (xy 282.788075 -304.278329) (xy 282.739856 -304.268485)
			(xy 282.69384 -304.251033) (xy 282.651219 -304.226426) (xy 282.613098 -304.195301) (xy 282.580463 -304.158464)
			(xy 282.55416 -304.116868) (xy 282.534869 -304.071592) (xy 282.523092 -304.023808) (xy 282.519132 -303.974754)
			(xy 282.18003 -303.974754) (xy 282.179535 -303.999361) (xy 282.17164 -304.047938) (xy 282.156056 -304.094619)
			(xy 282.133185 -304.138196) (xy 282.10362 -304.17754) (xy 282.068127 -304.211632) (xy 282.027624 -304.239588)
			(xy 281.983162 -304.260686) (xy 281.935891 -304.274378) (xy 281.887036 -304.28031) (xy 281.837861 -304.278329)
			(xy 281.789642 -304.268485) (xy 281.743626 -304.251033) (xy 281.701005 -304.226426) (xy 281.662884 -304.195301)
			(xy 281.630249 -304.158464) (xy 281.603946 -304.116868) (xy 281.584655 -304.071592) (xy 281.572878 -304.023808)
			(xy 281.568918 -303.974754) (xy 281.23007 -303.974754) (xy 281.229575 -303.999361) (xy 281.22168 -304.047938)
			(xy 281.206096 -304.094619) (xy 281.183225 -304.138196) (xy 281.15366 -304.17754) (xy 281.118167 -304.211632)
			(xy 281.077664 -304.239588) (xy 281.033202 -304.260686) (xy 280.985931 -304.274378) (xy 280.937076 -304.28031)
			(xy 280.887901 -304.278329) (xy 280.839682 -304.268485) (xy 280.793666 -304.251033) (xy 280.751045 -304.226426)
			(xy 280.712924 -304.195301) (xy 280.680289 -304.158464) (xy 280.653986 -304.116868) (xy 280.634695 -304.071592)
			(xy 280.622918 -304.023808) (xy 280.618958 -303.974754) (xy 280.28011 -303.974754) (xy 280.279615 -303.999361)
			(xy 280.27172 -304.047938) (xy 280.256136 -304.094619) (xy 280.233265 -304.138196) (xy 280.2037 -304.17754)
			(xy 280.168207 -304.211632) (xy 280.127704 -304.239588) (xy 280.083242 -304.260686) (xy 280.035971 -304.274378)
			(xy 279.987116 -304.28031) (xy 279.937941 -304.278329) (xy 279.889722 -304.268485) (xy 279.843706 -304.251033)
			(xy 279.801085 -304.226426) (xy 279.762964 -304.195301) (xy 279.730329 -304.158464) (xy 279.704026 -304.116868)
			(xy 279.684735 -304.071592) (xy 279.672958 -304.023808) (xy 279.668998 -303.974754) (xy 279.33015 -303.974754)
			(xy 279.329655 -303.999361) (xy 279.32176 -304.047938) (xy 279.306176 -304.094619) (xy 279.283305 -304.138196)
			(xy 279.25374 -304.17754) (xy 279.218247 -304.211632) (xy 279.177744 -304.239588) (xy 279.133282 -304.260686)
			(xy 279.086011 -304.274378) (xy 279.037156 -304.28031) (xy 278.987981 -304.278329) (xy 278.939762 -304.268485)
			(xy 278.893746 -304.251033) (xy 278.851125 -304.226426) (xy 278.813004 -304.195301) (xy 278.780369 -304.158464)
			(xy 278.754066 -304.116868) (xy 278.734775 -304.071592) (xy 278.722998 -304.023808) (xy 278.719038 -303.974754)
			(xy 245.91645 -303.974754) (xy 246.391684 -304.449988) (xy 267.793736 -304.449988) (xy 267.797696 -304.400934)
			(xy 267.809473 -304.35315) (xy 267.828764 -304.307874) (xy 267.855067 -304.266278) (xy 267.887702 -304.229441)
			(xy 267.925823 -304.198316) (xy 267.968444 -304.173709) (xy 268.01446 -304.156257) (xy 268.062679 -304.146413)
			(xy 268.111854 -304.144432) (xy 268.160709 -304.150364) (xy 268.20798 -304.164056) (xy 268.252442 -304.185154)
			(xy 268.292945 -304.21311) (xy 268.328438 -304.247202) (xy 268.358003 -304.286546) (xy 268.380874 -304.330123)
			(xy 268.396458 -304.376804) (xy 268.404353 -304.425381) (xy 268.404848 -304.449988) (xy 268.404353 -304.474595)
			(xy 268.404215 -304.475442) (xy 268.723106 -304.475442) (xy 268.723106 -304.424026) (xy 268.731149 -304.373244)
			(xy 268.747037 -304.324345) (xy 268.77038 -304.278533) (xy 268.800601 -304.236937) (xy 268.836957 -304.200581)
			(xy 268.878553 -304.17036) (xy 268.924365 -304.147017) (xy 268.973264 -304.131129) (xy 269.024046 -304.123086)
			(xy 269.075462 -304.123086) (xy 269.126244 -304.131129) (xy 269.175143 -304.147017) (xy 269.220955 -304.17036)
			(xy 269.262551 -304.200581) (xy 269.298907 -304.236937) (xy 269.329128 -304.278533) (xy 269.352471 -304.324345)
			(xy 269.368359 -304.373244) (xy 269.376402 -304.424026) (xy 269.376906 -304.449734) (xy 269.376402 -304.475442)
			(xy 269.673066 -304.475442) (xy 269.673066 -304.424026) (xy 269.681109 -304.373244) (xy 269.696997 -304.324345)
			(xy 269.72034 -304.278533) (xy 269.750561 -304.236937) (xy 269.786917 -304.200581) (xy 269.828513 -304.17036)
			(xy 269.874325 -304.147017) (xy 269.923224 -304.131129) (xy 269.974006 -304.123086) (xy 270.025422 -304.123086)
			(xy 270.076204 -304.131129) (xy 270.125103 -304.147017) (xy 270.170915 -304.17036) (xy 270.212511 -304.200581)
			(xy 270.248867 -304.236937) (xy 270.279088 -304.278533) (xy 270.302431 -304.324345) (xy 270.318319 -304.373244)
			(xy 270.326362 -304.424026) (xy 270.326866 -304.449734) (xy 270.644124 -304.449734) (xy 270.648084 -304.40068)
			(xy 270.659861 -304.352896) (xy 270.679152 -304.30762) (xy 270.705455 -304.266024) (xy 270.73809 -304.229187)
			(xy 270.776211 -304.198062) (xy 270.818832 -304.173455) (xy 270.864848 -304.156003) (xy 270.913067 -304.146159)
			(xy 270.962242 -304.144178) (xy 271.011097 -304.15011) (xy 271.058368 -304.163802) (xy 271.10283 -304.1849)
			(xy 271.143333 -304.212856) (xy 271.178826 -304.246948) (xy 271.208391 -304.286292) (xy 271.231262 -304.329869)
			(xy 271.246846 -304.37655) (xy 271.254741 -304.425127) (xy 271.255236 -304.449734) (xy 271.594084 -304.449734)
			(xy 271.598044 -304.40068) (xy 271.609821 -304.352896) (xy 271.629112 -304.30762) (xy 271.655415 -304.266024)
			(xy 271.68805 -304.229187) (xy 271.726171 -304.198062) (xy 271.768792 -304.173455) (xy 271.814808 -304.156003)
			(xy 271.863027 -304.146159) (xy 271.912202 -304.144178) (xy 271.961057 -304.15011) (xy 272.008328 -304.163802)
			(xy 272.05279 -304.1849) (xy 272.093293 -304.212856) (xy 272.128786 -304.246948) (xy 272.158351 -304.286292)
			(xy 272.181222 -304.329869) (xy 272.196806 -304.37655) (xy 272.204701 -304.425127) (xy 272.205196 -304.449734)
			(xy 272.544044 -304.449734) (xy 272.548004 -304.40068) (xy 272.559781 -304.352896) (xy 272.579072 -304.30762)
			(xy 272.605375 -304.266024) (xy 272.63801 -304.229187) (xy 272.676131 -304.198062) (xy 272.718752 -304.173455)
			(xy 272.764768 -304.156003) (xy 272.812987 -304.146159) (xy 272.862162 -304.144178) (xy 272.911017 -304.15011)
			(xy 272.958288 -304.163802) (xy 273.00275 -304.1849) (xy 273.043253 -304.212856) (xy 273.078746 -304.246948)
			(xy 273.108311 -304.286292) (xy 273.131182 -304.329869) (xy 273.146766 -304.37655) (xy 273.154661 -304.425127)
			(xy 273.155156 -304.449734) (xy 273.494004 -304.449734) (xy 273.497964 -304.40068) (xy 273.509741 -304.352896)
			(xy 273.529032 -304.30762) (xy 273.555335 -304.266024) (xy 273.58797 -304.229187) (xy 273.626091 -304.198062)
			(xy 273.668712 -304.173455) (xy 273.714728 -304.156003) (xy 273.762947 -304.146159) (xy 273.812122 -304.144178)
			(xy 273.860977 -304.15011) (xy 273.908248 -304.163802) (xy 273.95271 -304.1849) (xy 273.993213 -304.212856)
			(xy 274.028706 -304.246948) (xy 274.058271 -304.286292) (xy 274.081142 -304.329869) (xy 274.096726 -304.37655)
			(xy 274.104621 -304.425127) (xy 274.105116 -304.449734) (xy 274.443964 -304.449734) (xy 274.447924 -304.40068)
			(xy 274.459701 -304.352896) (xy 274.478992 -304.30762) (xy 274.505295 -304.266024) (xy 274.53793 -304.229187)
			(xy 274.576051 -304.198062) (xy 274.618672 -304.173455) (xy 274.664688 -304.156003) (xy 274.712907 -304.146159)
			(xy 274.762082 -304.144178) (xy 274.810937 -304.15011) (xy 274.858208 -304.163802) (xy 274.90267 -304.1849)
			(xy 274.943173 -304.212856) (xy 274.978666 -304.246948) (xy 275.008231 -304.286292) (xy 275.031102 -304.329869)
			(xy 275.046686 -304.37655) (xy 275.054581 -304.425127) (xy 275.055076 -304.449734) (xy 275.054581 -304.474341)
			(xy 275.054402 -304.475442) (xy 275.37308 -304.475442) (xy 275.37308 -304.424026) (xy 275.381123 -304.373244)
			(xy 275.397011 -304.324345) (xy 275.420354 -304.278533) (xy 275.450575 -304.236937) (xy 275.486931 -304.200581)
			(xy 275.528527 -304.17036) (xy 275.574339 -304.147017) (xy 275.623238 -304.131129) (xy 275.67402 -304.123086)
			(xy 275.725436 -304.123086) (xy 275.776218 -304.131129) (xy 275.825117 -304.147017) (xy 275.870929 -304.17036)
			(xy 275.912525 -304.200581) (xy 275.948881 -304.236937) (xy 275.979102 -304.278533) (xy 276.002445 -304.324345)
			(xy 276.018333 -304.373244) (xy 276.026376 -304.424026) (xy 276.02688 -304.449734) (xy 276.026376 -304.475442)
			(xy 276.32304 -304.475442) (xy 276.32304 -304.424026) (xy 276.331083 -304.373244) (xy 276.346971 -304.324345)
			(xy 276.370314 -304.278533) (xy 276.400535 -304.236937) (xy 276.436891 -304.200581) (xy 276.478487 -304.17036)
			(xy 276.524299 -304.147017) (xy 276.573198 -304.131129) (xy 276.62398 -304.123086) (xy 276.675396 -304.123086)
			(xy 276.726178 -304.131129) (xy 276.775077 -304.147017) (xy 276.820889 -304.17036) (xy 276.862485 -304.200581)
			(xy 276.898841 -304.236937) (xy 276.929062 -304.278533) (xy 276.952405 -304.324345) (xy 276.968293 -304.373244)
			(xy 276.976336 -304.424026) (xy 276.97684 -304.449734) (xy 277.294098 -304.449734) (xy 277.298058 -304.40068)
			(xy 277.309835 -304.352896) (xy 277.329126 -304.30762) (xy 277.355429 -304.266024) (xy 277.388064 -304.229187)
			(xy 277.426185 -304.198062) (xy 277.468806 -304.173455) (xy 277.514822 -304.156003) (xy 277.563041 -304.146159)
			(xy 277.612216 -304.144178) (xy 277.661071 -304.15011) (xy 277.708342 -304.163802) (xy 277.752804 -304.1849)
			(xy 277.793307 -304.212856) (xy 277.8288 -304.246948) (xy 277.858365 -304.286292) (xy 277.881236 -304.329869)
			(xy 277.89682 -304.37655) (xy 277.904715 -304.425127) (xy 277.90521 -304.449734) (xy 277.904715 -304.474341)
			(xy 277.89682 -304.522918) (xy 277.881236 -304.569599) (xy 277.858365 -304.613176) (xy 277.8288 -304.65252)
			(xy 277.793307 -304.686612) (xy 277.752804 -304.714568) (xy 277.708342 -304.735666) (xy 277.661071 -304.749358)
			(xy 277.612216 -304.75529) (xy 277.563041 -304.753309) (xy 277.514822 -304.743465) (xy 277.468806 -304.726013)
			(xy 277.426185 -304.701406) (xy 277.388064 -304.670281) (xy 277.355429 -304.633444) (xy 277.329126 -304.591848)
			(xy 277.309835 -304.546572) (xy 277.298058 -304.498788) (xy 277.294098 -304.449734) (xy 276.97684 -304.449734)
			(xy 276.976336 -304.475442) (xy 276.968293 -304.526224) (xy 276.952405 -304.575123) (xy 276.929062 -304.620935)
			(xy 276.898841 -304.662531) (xy 276.862485 -304.698887) (xy 276.820889 -304.729108) (xy 276.775077 -304.752451)
			(xy 276.726178 -304.768339) (xy 276.675396 -304.776382) (xy 276.62398 -304.776382) (xy 276.573198 -304.768339)
			(xy 276.524299 -304.752451) (xy 276.478487 -304.729108) (xy 276.436891 -304.698887) (xy 276.400535 -304.662531)
			(xy 276.370314 -304.620935) (xy 276.346971 -304.575123) (xy 276.331083 -304.526224) (xy 276.32304 -304.475442)
			(xy 276.026376 -304.475442) (xy 276.018333 -304.526224) (xy 276.002445 -304.575123) (xy 275.979102 -304.620935)
			(xy 275.948881 -304.662531) (xy 275.912525 -304.698887) (xy 275.870929 -304.729108) (xy 275.825117 -304.752451)
			(xy 275.776218 -304.768339) (xy 275.725436 -304.776382) (xy 275.67402 -304.776382) (xy 275.623238 -304.768339)
			(xy 275.574339 -304.752451) (xy 275.528527 -304.729108) (xy 275.486931 -304.698887) (xy 275.450575 -304.662531)
			(xy 275.420354 -304.620935) (xy 275.397011 -304.575123) (xy 275.381123 -304.526224) (xy 275.37308 -304.475442)
			(xy 275.054402 -304.475442) (xy 275.046686 -304.522918) (xy 275.031102 -304.569599) (xy 275.008231 -304.613176)
			(xy 274.978666 -304.65252) (xy 274.943173 -304.686612) (xy 274.90267 -304.714568) (xy 274.858208 -304.735666)
			(xy 274.810937 -304.749358) (xy 274.762082 -304.75529) (xy 274.712907 -304.753309) (xy 274.664688 -304.743465)
			(xy 274.618672 -304.726013) (xy 274.576051 -304.701406) (xy 274.53793 -304.670281) (xy 274.505295 -304.633444)
			(xy 274.478992 -304.591848) (xy 274.459701 -304.546572) (xy 274.447924 -304.498788) (xy 274.443964 -304.449734)
			(xy 274.105116 -304.449734) (xy 274.104621 -304.474341) (xy 274.096726 -304.522918) (xy 274.081142 -304.569599)
			(xy 274.058271 -304.613176) (xy 274.028706 -304.65252) (xy 273.993213 -304.686612) (xy 273.95271 -304.714568)
			(xy 273.908248 -304.735666) (xy 273.860977 -304.749358) (xy 273.812122 -304.75529) (xy 273.762947 -304.753309)
			(xy 273.714728 -304.743465) (xy 273.668712 -304.726013) (xy 273.626091 -304.701406) (xy 273.58797 -304.670281)
			(xy 273.555335 -304.633444) (xy 273.529032 -304.591848) (xy 273.509741 -304.546572) (xy 273.497964 -304.498788)
			(xy 273.494004 -304.449734) (xy 273.155156 -304.449734) (xy 273.154661 -304.474341) (xy 273.146766 -304.522918)
			(xy 273.131182 -304.569599) (xy 273.108311 -304.613176) (xy 273.078746 -304.65252) (xy 273.043253 -304.686612)
			(xy 273.00275 -304.714568) (xy 272.958288 -304.735666) (xy 272.911017 -304.749358) (xy 272.862162 -304.75529)
			(xy 272.812987 -304.753309) (xy 272.764768 -304.743465) (xy 272.718752 -304.726013) (xy 272.676131 -304.701406)
			(xy 272.63801 -304.670281) (xy 272.605375 -304.633444) (xy 272.579072 -304.591848) (xy 272.559781 -304.546572)
			(xy 272.548004 -304.498788) (xy 272.544044 -304.449734) (xy 272.205196 -304.449734) (xy 272.204701 -304.474341)
			(xy 272.196806 -304.522918) (xy 272.181222 -304.569599) (xy 272.158351 -304.613176) (xy 272.128786 -304.65252)
			(xy 272.093293 -304.686612) (xy 272.05279 -304.714568) (xy 272.008328 -304.735666) (xy 271.961057 -304.749358)
			(xy 271.912202 -304.75529) (xy 271.863027 -304.753309) (xy 271.814808 -304.743465) (xy 271.768792 -304.726013)
			(xy 271.726171 -304.701406) (xy 271.68805 -304.670281) (xy 271.655415 -304.633444) (xy 271.629112 -304.591848)
			(xy 271.609821 -304.546572) (xy 271.598044 -304.498788) (xy 271.594084 -304.449734) (xy 271.255236 -304.449734)
			(xy 271.254741 -304.474341) (xy 271.246846 -304.522918) (xy 271.231262 -304.569599) (xy 271.208391 -304.613176)
			(xy 271.178826 -304.65252) (xy 271.143333 -304.686612) (xy 271.10283 -304.714568) (xy 271.058368 -304.735666)
			(xy 271.011097 -304.749358) (xy 270.962242 -304.75529) (xy 270.913067 -304.753309) (xy 270.864848 -304.743465)
			(xy 270.818832 -304.726013) (xy 270.776211 -304.701406) (xy 270.73809 -304.670281) (xy 270.705455 -304.633444)
			(xy 270.679152 -304.591848) (xy 270.659861 -304.546572) (xy 270.648084 -304.498788) (xy 270.644124 -304.449734)
			(xy 270.326866 -304.449734) (xy 270.326362 -304.475442) (xy 270.318319 -304.526224) (xy 270.302431 -304.575123)
			(xy 270.279088 -304.620935) (xy 270.248867 -304.662531) (xy 270.212511 -304.698887) (xy 270.170915 -304.729108)
			(xy 270.125103 -304.752451) (xy 270.076204 -304.768339) (xy 270.025422 -304.776382) (xy 269.974006 -304.776382)
			(xy 269.923224 -304.768339) (xy 269.874325 -304.752451) (xy 269.828513 -304.729108) (xy 269.786917 -304.698887)
			(xy 269.750561 -304.662531) (xy 269.72034 -304.620935) (xy 269.696997 -304.575123) (xy 269.681109 -304.526224)
			(xy 269.673066 -304.475442) (xy 269.376402 -304.475442) (xy 269.368359 -304.526224) (xy 269.352471 -304.575123)
			(xy 269.329128 -304.620935) (xy 269.298907 -304.662531) (xy 269.262551 -304.698887) (xy 269.220955 -304.729108)
			(xy 269.175143 -304.752451) (xy 269.126244 -304.768339) (xy 269.075462 -304.776382) (xy 269.024046 -304.776382)
			(xy 268.973264 -304.768339) (xy 268.924365 -304.752451) (xy 268.878553 -304.729108) (xy 268.836957 -304.698887)
			(xy 268.800601 -304.662531) (xy 268.77038 -304.620935) (xy 268.747037 -304.575123) (xy 268.731149 -304.526224)
			(xy 268.723106 -304.475442) (xy 268.404215 -304.475442) (xy 268.396458 -304.523172) (xy 268.380874 -304.569853)
			(xy 268.358003 -304.61343) (xy 268.328438 -304.652774) (xy 268.292945 -304.686866) (xy 268.252442 -304.714822)
			(xy 268.20798 -304.73592) (xy 268.160709 -304.749612) (xy 268.111854 -304.755544) (xy 268.062679 -304.753563)
			(xy 268.01446 -304.743719) (xy 267.968444 -304.726267) (xy 267.925823 -304.70166) (xy 267.887702 -304.670535)
			(xy 267.855067 -304.633698) (xy 267.828764 -304.592102) (xy 267.809473 -304.546826) (xy 267.797696 -304.499042)
			(xy 267.793736 -304.449988) (xy 246.391684 -304.449988) (xy 246.86641 -304.924714) (xy 278.719038 -304.924714)
			(xy 278.722998 -304.87566) (xy 278.734775 -304.827876) (xy 278.754066 -304.7826) (xy 278.780369 -304.741004)
			(xy 278.813004 -304.704167) (xy 278.851125 -304.673042) (xy 278.893746 -304.648435) (xy 278.939762 -304.630983)
			(xy 278.987981 -304.621139) (xy 279.037156 -304.619158) (xy 279.086011 -304.62509) (xy 279.133282 -304.638782)
			(xy 279.177744 -304.65988) (xy 279.218247 -304.687836) (xy 279.25374 -304.721928) (xy 279.283305 -304.761272)
			(xy 279.306176 -304.804849) (xy 279.32176 -304.85153) (xy 279.329655 -304.900107) (xy 279.33015 -304.924714)
			(xy 279.668998 -304.924714) (xy 279.672958 -304.87566) (xy 279.684735 -304.827876) (xy 279.704026 -304.7826)
			(xy 279.730329 -304.741004) (xy 279.762964 -304.704167) (xy 279.801085 -304.673042) (xy 279.843706 -304.648435)
			(xy 279.889722 -304.630983) (xy 279.937941 -304.621139) (xy 279.987116 -304.619158) (xy 280.035971 -304.62509)
			(xy 280.083242 -304.638782) (xy 280.127704 -304.65988) (xy 280.168207 -304.687836) (xy 280.2037 -304.721928)
			(xy 280.233265 -304.761272) (xy 280.256136 -304.804849) (xy 280.27172 -304.85153) (xy 280.279615 -304.900107)
			(xy 280.28011 -304.924714) (xy 280.618958 -304.924714) (xy 280.622918 -304.87566) (xy 280.634695 -304.827876)
			(xy 280.653986 -304.7826) (xy 280.680289 -304.741004) (xy 280.712924 -304.704167) (xy 280.751045 -304.673042)
			(xy 280.793666 -304.648435) (xy 280.839682 -304.630983) (xy 280.887901 -304.621139) (xy 280.937076 -304.619158)
			(xy 280.985931 -304.62509) (xy 281.033202 -304.638782) (xy 281.077664 -304.65988) (xy 281.118167 -304.687836)
			(xy 281.15366 -304.721928) (xy 281.183225 -304.761272) (xy 281.206096 -304.804849) (xy 281.22168 -304.85153)
			(xy 281.229575 -304.900107) (xy 281.23007 -304.924714) (xy 281.568918 -304.924714) (xy 281.572878 -304.87566)
			(xy 281.584655 -304.827876) (xy 281.603946 -304.7826) (xy 281.630249 -304.741004) (xy 281.662884 -304.704167)
			(xy 281.701005 -304.673042) (xy 281.743626 -304.648435) (xy 281.789642 -304.630983) (xy 281.837861 -304.621139)
			(xy 281.887036 -304.619158) (xy 281.935891 -304.62509) (xy 281.983162 -304.638782) (xy 282.027624 -304.65988)
			(xy 282.068127 -304.687836) (xy 282.10362 -304.721928) (xy 282.133185 -304.761272) (xy 282.156056 -304.804849)
			(xy 282.17164 -304.85153) (xy 282.179535 -304.900107) (xy 282.18003 -304.924714) (xy 282.519132 -304.924714)
			(xy 282.523092 -304.87566) (xy 282.534869 -304.827876) (xy 282.55416 -304.7826) (xy 282.580463 -304.741004)
			(xy 282.613098 -304.704167) (xy 282.651219 -304.673042) (xy 282.69384 -304.648435) (xy 282.739856 -304.630983)
			(xy 282.788075 -304.621139) (xy 282.83725 -304.619158) (xy 282.886105 -304.62509) (xy 282.933376 -304.638782)
			(xy 282.977838 -304.65988) (xy 283.018341 -304.687836) (xy 283.053834 -304.721928) (xy 283.083399 -304.761272)
			(xy 283.10627 -304.804849) (xy 283.121854 -304.85153) (xy 283.129749 -304.900107) (xy 283.130244 -304.924714)
			(xy 283.469092 -304.924714) (xy 283.473052 -304.87566) (xy 283.484829 -304.827876) (xy 283.50412 -304.7826)
			(xy 283.530423 -304.741004) (xy 283.563058 -304.704167) (xy 283.601179 -304.673042) (xy 283.6438 -304.648435)
			(xy 283.689816 -304.630983) (xy 283.738035 -304.621139) (xy 283.78721 -304.619158) (xy 283.836065 -304.62509)
			(xy 283.883336 -304.638782) (xy 283.927798 -304.65988) (xy 283.968301 -304.687836) (xy 284.003794 -304.721928)
			(xy 284.033359 -304.761272) (xy 284.05623 -304.804849) (xy 284.071814 -304.85153) (xy 284.079709 -304.900107)
			(xy 284.080204 -304.924714) (xy 284.419052 -304.924714) (xy 284.423012 -304.87566) (xy 284.434789 -304.827876)
			(xy 284.45408 -304.7826) (xy 284.480383 -304.741004) (xy 284.513018 -304.704167) (xy 284.551139 -304.673042)
			(xy 284.59376 -304.648435) (xy 284.639776 -304.630983) (xy 284.687995 -304.621139) (xy 284.73717 -304.619158)
			(xy 284.786025 -304.62509) (xy 284.833296 -304.638782) (xy 284.877758 -304.65988) (xy 284.918261 -304.687836)
			(xy 284.953754 -304.721928) (xy 284.983319 -304.761272) (xy 285.00619 -304.804849) (xy 285.021774 -304.85153)
			(xy 285.029669 -304.900107) (xy 285.030164 -304.924714) (xy 285.369012 -304.924714) (xy 285.372972 -304.87566)
			(xy 285.384749 -304.827876) (xy 285.40404 -304.7826) (xy 285.430343 -304.741004) (xy 285.462978 -304.704167)
			(xy 285.501099 -304.673042) (xy 285.54372 -304.648435) (xy 285.589736 -304.630983) (xy 285.637955 -304.621139)
			(xy 285.68713 -304.619158) (xy 285.735985 -304.62509) (xy 285.783256 -304.638782) (xy 285.827718 -304.65988)
			(xy 285.868221 -304.687836) (xy 285.903714 -304.721928) (xy 285.933279 -304.761272) (xy 285.95615 -304.804849)
			(xy 285.971734 -304.85153) (xy 285.979629 -304.900107) (xy 285.980124 -304.924714) (xy 286.318972 -304.924714)
			(xy 286.322932 -304.87566) (xy 286.334709 -304.827876) (xy 286.354 -304.7826) (xy 286.380303 -304.741004)
			(xy 286.412938 -304.704167) (xy 286.451059 -304.673042) (xy 286.49368 -304.648435) (xy 286.539696 -304.630983)
			(xy 286.587915 -304.621139) (xy 286.63709 -304.619158) (xy 286.685945 -304.62509) (xy 286.733216 -304.638782)
			(xy 286.777678 -304.65988) (xy 286.818181 -304.687836) (xy 286.853674 -304.721928) (xy 286.883239 -304.761272)
			(xy 286.90611 -304.804849) (xy 286.921694 -304.85153) (xy 286.929589 -304.900107) (xy 286.930084 -304.924714)
			(xy 287.268932 -304.924714) (xy 287.272892 -304.87566) (xy 287.284669 -304.827876) (xy 287.30396 -304.7826)
			(xy 287.330263 -304.741004) (xy 287.362898 -304.704167) (xy 287.401019 -304.673042) (xy 287.44364 -304.648435)
			(xy 287.489656 -304.630983) (xy 287.537875 -304.621139) (xy 287.58705 -304.619158) (xy 287.635905 -304.62509)
			(xy 287.683176 -304.638782) (xy 287.727638 -304.65988) (xy 287.768141 -304.687836) (xy 287.803634 -304.721928)
			(xy 287.833199 -304.761272) (xy 287.85607 -304.804849) (xy 287.871654 -304.85153) (xy 287.879549 -304.900107)
			(xy 287.880044 -304.924714) (xy 288.218892 -304.924714) (xy 288.222852 -304.87566) (xy 288.234629 -304.827876)
			(xy 288.25392 -304.7826) (xy 288.280223 -304.741004) (xy 288.312858 -304.704167) (xy 288.350979 -304.673042)
			(xy 288.3936 -304.648435) (xy 288.439616 -304.630983) (xy 288.487835 -304.621139) (xy 288.53701 -304.619158)
			(xy 288.585865 -304.62509) (xy 288.633136 -304.638782) (xy 288.677598 -304.65988) (xy 288.718101 -304.687836)
			(xy 288.753594 -304.721928) (xy 288.783159 -304.761272) (xy 288.80603 -304.804849) (xy 288.821614 -304.85153)
			(xy 288.829509 -304.900107) (xy 288.830004 -304.924714) (xy 289.169106 -304.924714) (xy 289.173066 -304.87566)
			(xy 289.184843 -304.827876) (xy 289.204134 -304.7826) (xy 289.230437 -304.741004) (xy 289.263072 -304.704167)
			(xy 289.301193 -304.673042) (xy 289.343814 -304.648435) (xy 289.38983 -304.630983) (xy 289.438049 -304.621139)
			(xy 289.487224 -304.619158) (xy 289.536079 -304.62509) (xy 289.58335 -304.638782) (xy 289.627812 -304.65988)
			(xy 289.668315 -304.687836) (xy 289.703808 -304.721928) (xy 289.733373 -304.761272) (xy 289.756244 -304.804849)
			(xy 289.771828 -304.85153) (xy 289.779723 -304.900107) (xy 289.780218 -304.924714) (xy 290.119066 -304.924714)
			(xy 290.123026 -304.87566) (xy 290.134803 -304.827876) (xy 290.154094 -304.7826) (xy 290.180397 -304.741004)
			(xy 290.213032 -304.704167) (xy 290.251153 -304.673042) (xy 290.293774 -304.648435) (xy 290.33979 -304.630983)
			(xy 290.388009 -304.621139) (xy 290.437184 -304.619158) (xy 290.486039 -304.62509) (xy 290.53331 -304.638782)
			(xy 290.577772 -304.65988) (xy 290.618275 -304.687836) (xy 290.653768 -304.721928) (xy 290.683333 -304.761272)
			(xy 290.706204 -304.804849) (xy 290.721788 -304.85153) (xy 290.729683 -304.900107) (xy 290.730178 -304.924714)
			(xy 292.018986 -304.924714) (xy 292.022946 -304.87566) (xy 292.034723 -304.827876) (xy 292.054014 -304.7826)
			(xy 292.080317 -304.741004) (xy 292.112952 -304.704167) (xy 292.151073 -304.673042) (xy 292.193694 -304.648435)
			(xy 292.23971 -304.630983) (xy 292.287929 -304.621139) (xy 292.337104 -304.619158) (xy 292.385959 -304.62509)
			(xy 292.43323 -304.638782) (xy 292.477692 -304.65988) (xy 292.518195 -304.687836) (xy 292.553688 -304.721928)
			(xy 292.583253 -304.761272) (xy 292.606124 -304.804849) (xy 292.621708 -304.85153) (xy 292.629603 -304.900107)
			(xy 292.630098 -304.924714) (xy 292.968946 -304.924714) (xy 292.972906 -304.87566) (xy 292.984683 -304.827876)
			(xy 293.003974 -304.7826) (xy 293.030277 -304.741004) (xy 293.062912 -304.704167) (xy 293.101033 -304.673042)
			(xy 293.143654 -304.648435) (xy 293.18967 -304.630983) (xy 293.237889 -304.621139) (xy 293.287064 -304.619158)
			(xy 293.335919 -304.62509) (xy 293.38319 -304.638782) (xy 293.427652 -304.65988) (xy 293.468155 -304.687836)
			(xy 293.503648 -304.721928) (xy 293.533213 -304.761272) (xy 293.556084 -304.804849) (xy 293.571668 -304.85153)
			(xy 293.579563 -304.900107) (xy 293.580058 -304.924714) (xy 293.918906 -304.924714) (xy 293.922866 -304.87566)
			(xy 293.934643 -304.827876) (xy 293.953934 -304.7826) (xy 293.980237 -304.741004) (xy 294.012872 -304.704167)
			(xy 294.050993 -304.673042) (xy 294.093614 -304.648435) (xy 294.13963 -304.630983) (xy 294.187849 -304.621139)
			(xy 294.237024 -304.619158) (xy 294.285879 -304.62509) (xy 294.33315 -304.638782) (xy 294.377612 -304.65988)
			(xy 294.418115 -304.687836) (xy 294.453608 -304.721928) (xy 294.483173 -304.761272) (xy 294.506044 -304.804849)
			(xy 294.521628 -304.85153) (xy 294.529523 -304.900107) (xy 294.530018 -304.924714) (xy 294.86912 -304.924714)
			(xy 294.87308 -304.87566) (xy 294.884857 -304.827876) (xy 294.904148 -304.7826) (xy 294.930451 -304.741004)
			(xy 294.963086 -304.704167) (xy 295.001207 -304.673042) (xy 295.043828 -304.648435) (xy 295.089844 -304.630983)
			(xy 295.138063 -304.621139) (xy 295.187238 -304.619158) (xy 295.236093 -304.62509) (xy 295.283364 -304.638782)
			(xy 295.327826 -304.65988) (xy 295.368329 -304.687836) (xy 295.403822 -304.721928) (xy 295.433387 -304.761272)
			(xy 295.456258 -304.804849) (xy 295.471842 -304.85153) (xy 295.479737 -304.900107) (xy 295.480232 -304.924714)
			(xy 295.81908 -304.924714) (xy 295.82304 -304.87566) (xy 295.834817 -304.827876) (xy 295.854108 -304.7826)
			(xy 295.880411 -304.741004) (xy 295.913046 -304.704167) (xy 295.951167 -304.673042) (xy 295.993788 -304.648435)
			(xy 296.039804 -304.630983) (xy 296.088023 -304.621139) (xy 296.137198 -304.619158) (xy 296.186053 -304.62509)
			(xy 296.233324 -304.638782) (xy 296.277786 -304.65988) (xy 296.318289 -304.687836) (xy 296.353782 -304.721928)
			(xy 296.383347 -304.761272) (xy 296.406218 -304.804849) (xy 296.421802 -304.85153) (xy 296.429697 -304.900107)
			(xy 296.430192 -304.924714) (xy 296.76904 -304.924714) (xy 296.773 -304.87566) (xy 296.784777 -304.827876)
			(xy 296.804068 -304.7826) (xy 296.830371 -304.741004) (xy 296.863006 -304.704167) (xy 296.901127 -304.673042)
			(xy 296.943748 -304.648435) (xy 296.989764 -304.630983) (xy 297.037983 -304.621139) (xy 297.087158 -304.619158)
			(xy 297.136013 -304.62509) (xy 297.183284 -304.638782) (xy 297.227746 -304.65988) (xy 297.268249 -304.687836)
			(xy 297.303742 -304.721928) (xy 297.333307 -304.761272) (xy 297.356178 -304.804849) (xy 297.371762 -304.85153)
			(xy 297.379657 -304.900107) (xy 297.380152 -304.924714) (xy 297.719 -304.924714) (xy 297.72296 -304.87566)
			(xy 297.734737 -304.827876) (xy 297.754028 -304.7826) (xy 297.780331 -304.741004) (xy 297.812966 -304.704167)
			(xy 297.851087 -304.673042) (xy 297.893708 -304.648435) (xy 297.939724 -304.630983) (xy 297.987943 -304.621139)
			(xy 298.037118 -304.619158) (xy 298.085973 -304.62509) (xy 298.133244 -304.638782) (xy 298.177706 -304.65988)
			(xy 298.218209 -304.687836) (xy 298.253702 -304.721928) (xy 298.283267 -304.761272) (xy 298.306138 -304.804849)
			(xy 298.321722 -304.85153) (xy 298.329617 -304.900107) (xy 298.330112 -304.924714) (xy 298.66896 -304.924714)
			(xy 298.67292 -304.87566) (xy 298.684697 -304.827876) (xy 298.703988 -304.7826) (xy 298.730291 -304.741004)
			(xy 298.762926 -304.704167) (xy 298.801047 -304.673042) (xy 298.843668 -304.648435) (xy 298.889684 -304.630983)
			(xy 298.937903 -304.621139) (xy 298.987078 -304.619158) (xy 299.035933 -304.62509) (xy 299.083204 -304.638782)
			(xy 299.127666 -304.65988) (xy 299.168169 -304.687836) (xy 299.203662 -304.721928) (xy 299.233227 -304.761272)
			(xy 299.256098 -304.804849) (xy 299.271682 -304.85153) (xy 299.279577 -304.900107) (xy 299.280072 -304.924714)
			(xy 299.61892 -304.924714) (xy 299.62288 -304.87566) (xy 299.634657 -304.827876) (xy 299.653948 -304.7826)
			(xy 299.680251 -304.741004) (xy 299.712886 -304.704167) (xy 299.751007 -304.673042) (xy 299.793628 -304.648435)
			(xy 299.839644 -304.630983) (xy 299.887863 -304.621139) (xy 299.937038 -304.619158) (xy 299.985893 -304.62509)
			(xy 300.033164 -304.638782) (xy 300.077626 -304.65988) (xy 300.118129 -304.687836) (xy 300.153622 -304.721928)
			(xy 300.183187 -304.761272) (xy 300.206058 -304.804849) (xy 300.221642 -304.85153) (xy 300.229537 -304.900107)
			(xy 300.230032 -304.924714) (xy 300.56888 -304.924714) (xy 300.57284 -304.87566) (xy 300.584617 -304.827876)
			(xy 300.603908 -304.7826) (xy 300.630211 -304.741004) (xy 300.662846 -304.704167) (xy 300.700967 -304.673042)
			(xy 300.743588 -304.648435) (xy 300.789604 -304.630983) (xy 300.837823 -304.621139) (xy 300.886998 -304.619158)
			(xy 300.935853 -304.62509) (xy 300.983124 -304.638782) (xy 301.027586 -304.65988) (xy 301.068089 -304.687836)
			(xy 301.103582 -304.721928) (xy 301.133147 -304.761272) (xy 301.156018 -304.804849) (xy 301.171602 -304.85153)
			(xy 301.179497 -304.900107) (xy 301.179992 -304.924714) (xy 301.519094 -304.924714) (xy 301.523054 -304.87566)
			(xy 301.534831 -304.827876) (xy 301.554122 -304.7826) (xy 301.580425 -304.741004) (xy 301.61306 -304.704167)
			(xy 301.651181 -304.673042) (xy 301.693802 -304.648435) (xy 301.739818 -304.630983) (xy 301.788037 -304.621139)
			(xy 301.837212 -304.619158) (xy 301.886067 -304.62509) (xy 301.933338 -304.638782) (xy 301.9778 -304.65988)
			(xy 302.018303 -304.687836) (xy 302.053796 -304.721928) (xy 302.083361 -304.761272) (xy 302.106232 -304.804849)
			(xy 302.121816 -304.85153) (xy 302.129711 -304.900107) (xy 302.130206 -304.924714) (xy 302.469054 -304.924714)
			(xy 302.473014 -304.87566) (xy 302.484791 -304.827876) (xy 302.504082 -304.7826) (xy 302.530385 -304.741004)
			(xy 302.56302 -304.704167) (xy 302.601141 -304.673042) (xy 302.643762 -304.648435) (xy 302.689778 -304.630983)
			(xy 302.737997 -304.621139) (xy 302.787172 -304.619158) (xy 302.836027 -304.62509) (xy 302.883298 -304.638782)
			(xy 302.92776 -304.65988) (xy 302.968263 -304.687836) (xy 303.003756 -304.721928) (xy 303.033321 -304.761272)
			(xy 303.056192 -304.804849) (xy 303.071776 -304.85153) (xy 303.079671 -304.900107) (xy 303.080166 -304.924714)
			(xy 303.419014 -304.924714) (xy 303.422974 -304.87566) (xy 303.434751 -304.827876) (xy 303.454042 -304.7826)
			(xy 303.480345 -304.741004) (xy 303.51298 -304.704167) (xy 303.551101 -304.673042) (xy 303.593722 -304.648435)
			(xy 303.639738 -304.630983) (xy 303.687957 -304.621139) (xy 303.737132 -304.619158) (xy 303.785987 -304.62509)
			(xy 303.833258 -304.638782) (xy 303.87772 -304.65988) (xy 303.918223 -304.687836) (xy 303.953716 -304.721928)
			(xy 303.983281 -304.761272) (xy 304.006152 -304.804849) (xy 304.021736 -304.85153) (xy 304.029631 -304.900107)
			(xy 304.030126 -304.924714) (xy 304.368974 -304.924714) (xy 304.372934 -304.87566) (xy 304.384711 -304.827876)
			(xy 304.404002 -304.7826) (xy 304.430305 -304.741004) (xy 304.46294 -304.704167) (xy 304.501061 -304.673042)
			(xy 304.543682 -304.648435) (xy 304.589698 -304.630983) (xy 304.637917 -304.621139) (xy 304.687092 -304.619158)
			(xy 304.735947 -304.62509) (xy 304.783218 -304.638782) (xy 304.82768 -304.65988) (xy 304.868183 -304.687836)
			(xy 304.903676 -304.721928) (xy 304.933241 -304.761272) (xy 304.956112 -304.804849) (xy 304.971696 -304.85153)
			(xy 304.979591 -304.900107) (xy 304.980086 -304.924714) (xy 304.979591 -304.949321) (xy 304.971696 -304.997898)
			(xy 304.956112 -305.044579) (xy 304.933241 -305.088156) (xy 304.903676 -305.1275) (xy 304.868183 -305.161592)
			(xy 304.82768 -305.189548) (xy 304.783218 -305.210646) (xy 304.735947 -305.224338) (xy 304.687092 -305.23027)
			(xy 304.637917 -305.228289) (xy 304.589698 -305.218445) (xy 304.543682 -305.200993) (xy 304.501061 -305.176386)
			(xy 304.46294 -305.145261) (xy 304.430305 -305.108424) (xy 304.404002 -305.066828) (xy 304.384711 -305.021552)
			(xy 304.372934 -304.973768) (xy 304.368974 -304.924714) (xy 304.030126 -304.924714) (xy 304.029631 -304.949321)
			(xy 304.021736 -304.997898) (xy 304.006152 -305.044579) (xy 303.983281 -305.088156) (xy 303.953716 -305.1275)
			(xy 303.918223 -305.161592) (xy 303.87772 -305.189548) (xy 303.833258 -305.210646) (xy 303.785987 -305.224338)
			(xy 303.737132 -305.23027) (xy 303.687957 -305.228289) (xy 303.639738 -305.218445) (xy 303.593722 -305.200993)
			(xy 303.551101 -305.176386) (xy 303.51298 -305.145261) (xy 303.480345 -305.108424) (xy 303.454042 -305.066828)
			(xy 303.434751 -305.021552) (xy 303.422974 -304.973768) (xy 303.419014 -304.924714) (xy 303.080166 -304.924714)
			(xy 303.079671 -304.949321) (xy 303.071776 -304.997898) (xy 303.056192 -305.044579) (xy 303.033321 -305.088156)
			(xy 303.003756 -305.1275) (xy 302.968263 -305.161592) (xy 302.92776 -305.189548) (xy 302.883298 -305.210646)
			(xy 302.836027 -305.224338) (xy 302.787172 -305.23027) (xy 302.737997 -305.228289) (xy 302.689778 -305.218445)
			(xy 302.643762 -305.200993) (xy 302.601141 -305.176386) (xy 302.56302 -305.145261) (xy 302.530385 -305.108424)
			(xy 302.504082 -305.066828) (xy 302.484791 -305.021552) (xy 302.473014 -304.973768) (xy 302.469054 -304.924714)
			(xy 302.130206 -304.924714) (xy 302.129711 -304.949321) (xy 302.121816 -304.997898) (xy 302.106232 -305.044579)
			(xy 302.083361 -305.088156) (xy 302.053796 -305.1275) (xy 302.018303 -305.161592) (xy 301.9778 -305.189548)
			(xy 301.933338 -305.210646) (xy 301.886067 -305.224338) (xy 301.837212 -305.23027) (xy 301.788037 -305.228289)
			(xy 301.739818 -305.218445) (xy 301.693802 -305.200993) (xy 301.651181 -305.176386) (xy 301.61306 -305.145261)
			(xy 301.580425 -305.108424) (xy 301.554122 -305.066828) (xy 301.534831 -305.021552) (xy 301.523054 -304.973768)
			(xy 301.519094 -304.924714) (xy 301.179992 -304.924714) (xy 301.179497 -304.949321) (xy 301.171602 -304.997898)
			(xy 301.156018 -305.044579) (xy 301.133147 -305.088156) (xy 301.103582 -305.1275) (xy 301.068089 -305.161592)
			(xy 301.027586 -305.189548) (xy 300.983124 -305.210646) (xy 300.935853 -305.224338) (xy 300.886998 -305.23027)
			(xy 300.837823 -305.228289) (xy 300.789604 -305.218445) (xy 300.743588 -305.200993) (xy 300.700967 -305.176386)
			(xy 300.662846 -305.145261) (xy 300.630211 -305.108424) (xy 300.603908 -305.066828) (xy 300.584617 -305.021552)
			(xy 300.57284 -304.973768) (xy 300.56888 -304.924714) (xy 300.230032 -304.924714) (xy 300.229537 -304.949321)
			(xy 300.221642 -304.997898) (xy 300.206058 -305.044579) (xy 300.183187 -305.088156) (xy 300.153622 -305.1275)
			(xy 300.118129 -305.161592) (xy 300.077626 -305.189548) (xy 300.033164 -305.210646) (xy 299.985893 -305.224338)
			(xy 299.937038 -305.23027) (xy 299.887863 -305.228289) (xy 299.839644 -305.218445) (xy 299.793628 -305.200993)
			(xy 299.751007 -305.176386) (xy 299.712886 -305.145261) (xy 299.680251 -305.108424) (xy 299.653948 -305.066828)
			(xy 299.634657 -305.021552) (xy 299.62288 -304.973768) (xy 299.61892 -304.924714) (xy 299.280072 -304.924714)
			(xy 299.279577 -304.949321) (xy 299.271682 -304.997898) (xy 299.256098 -305.044579) (xy 299.233227 -305.088156)
			(xy 299.203662 -305.1275) (xy 299.168169 -305.161592) (xy 299.127666 -305.189548) (xy 299.083204 -305.210646)
			(xy 299.035933 -305.224338) (xy 298.987078 -305.23027) (xy 298.937903 -305.228289) (xy 298.889684 -305.218445)
			(xy 298.843668 -305.200993) (xy 298.801047 -305.176386) (xy 298.762926 -305.145261) (xy 298.730291 -305.108424)
			(xy 298.703988 -305.066828) (xy 298.684697 -305.021552) (xy 298.67292 -304.973768) (xy 298.66896 -304.924714)
			(xy 298.330112 -304.924714) (xy 298.329617 -304.949321) (xy 298.321722 -304.997898) (xy 298.306138 -305.044579)
			(xy 298.283267 -305.088156) (xy 298.253702 -305.1275) (xy 298.218209 -305.161592) (xy 298.177706 -305.189548)
			(xy 298.133244 -305.210646) (xy 298.085973 -305.224338) (xy 298.037118 -305.23027) (xy 297.987943 -305.228289)
			(xy 297.939724 -305.218445) (xy 297.893708 -305.200993) (xy 297.851087 -305.176386) (xy 297.812966 -305.145261)
			(xy 297.780331 -305.108424) (xy 297.754028 -305.066828) (xy 297.734737 -305.021552) (xy 297.72296 -304.973768)
			(xy 297.719 -304.924714) (xy 297.380152 -304.924714) (xy 297.379657 -304.949321) (xy 297.371762 -304.997898)
			(xy 297.356178 -305.044579) (xy 297.333307 -305.088156) (xy 297.303742 -305.1275) (xy 297.268249 -305.161592)
			(xy 297.227746 -305.189548) (xy 297.183284 -305.210646) (xy 297.136013 -305.224338) (xy 297.087158 -305.23027)
			(xy 297.037983 -305.228289) (xy 296.989764 -305.218445) (xy 296.943748 -305.200993) (xy 296.901127 -305.176386)
			(xy 296.863006 -305.145261) (xy 296.830371 -305.108424) (xy 296.804068 -305.066828) (xy 296.784777 -305.021552)
			(xy 296.773 -304.973768) (xy 296.76904 -304.924714) (xy 296.430192 -304.924714) (xy 296.429697 -304.949321)
			(xy 296.421802 -304.997898) (xy 296.406218 -305.044579) (xy 296.383347 -305.088156) (xy 296.353782 -305.1275)
			(xy 296.318289 -305.161592) (xy 296.277786 -305.189548) (xy 296.233324 -305.210646) (xy 296.186053 -305.224338)
			(xy 296.137198 -305.23027) (xy 296.088023 -305.228289) (xy 296.039804 -305.218445) (xy 295.993788 -305.200993)
			(xy 295.951167 -305.176386) (xy 295.913046 -305.145261) (xy 295.880411 -305.108424) (xy 295.854108 -305.066828)
			(xy 295.834817 -305.021552) (xy 295.82304 -304.973768) (xy 295.81908 -304.924714) (xy 295.480232 -304.924714)
			(xy 295.479737 -304.949321) (xy 295.471842 -304.997898) (xy 295.456258 -305.044579) (xy 295.433387 -305.088156)
			(xy 295.403822 -305.1275) (xy 295.368329 -305.161592) (xy 295.327826 -305.189548) (xy 295.283364 -305.210646)
			(xy 295.236093 -305.224338) (xy 295.187238 -305.23027) (xy 295.138063 -305.228289) (xy 295.089844 -305.218445)
			(xy 295.043828 -305.200993) (xy 295.001207 -305.176386) (xy 294.963086 -305.145261) (xy 294.930451 -305.108424)
			(xy 294.904148 -305.066828) (xy 294.884857 -305.021552) (xy 294.87308 -304.973768) (xy 294.86912 -304.924714)
			(xy 294.530018 -304.924714) (xy 294.529523 -304.949321) (xy 294.521628 -304.997898) (xy 294.506044 -305.044579)
			(xy 294.483173 -305.088156) (xy 294.453608 -305.1275) (xy 294.418115 -305.161592) (xy 294.377612 -305.189548)
			(xy 294.33315 -305.210646) (xy 294.285879 -305.224338) (xy 294.237024 -305.23027) (xy 294.187849 -305.228289)
			(xy 294.13963 -305.218445) (xy 294.093614 -305.200993) (xy 294.050993 -305.176386) (xy 294.012872 -305.145261)
			(xy 293.980237 -305.108424) (xy 293.953934 -305.066828) (xy 293.934643 -305.021552) (xy 293.922866 -304.973768)
			(xy 293.918906 -304.924714) (xy 293.580058 -304.924714) (xy 293.579563 -304.949321) (xy 293.571668 -304.997898)
			(xy 293.556084 -305.044579) (xy 293.533213 -305.088156) (xy 293.503648 -305.1275) (xy 293.468155 -305.161592)
			(xy 293.427652 -305.189548) (xy 293.38319 -305.210646) (xy 293.335919 -305.224338) (xy 293.287064 -305.23027)
			(xy 293.237889 -305.228289) (xy 293.18967 -305.218445) (xy 293.143654 -305.200993) (xy 293.101033 -305.176386)
			(xy 293.062912 -305.145261) (xy 293.030277 -305.108424) (xy 293.003974 -305.066828) (xy 292.984683 -305.021552)
			(xy 292.972906 -304.973768) (xy 292.968946 -304.924714) (xy 292.630098 -304.924714) (xy 292.629603 -304.949321)
			(xy 292.621708 -304.997898) (xy 292.606124 -305.044579) (xy 292.583253 -305.088156) (xy 292.553688 -305.1275)
			(xy 292.518195 -305.161592) (xy 292.477692 -305.189548) (xy 292.43323 -305.210646) (xy 292.385959 -305.224338)
			(xy 292.337104 -305.23027) (xy 292.287929 -305.228289) (xy 292.23971 -305.218445) (xy 292.193694 -305.200993)
			(xy 292.151073 -305.176386) (xy 292.112952 -305.145261) (xy 292.080317 -305.108424) (xy 292.054014 -305.066828)
			(xy 292.034723 -305.021552) (xy 292.022946 -304.973768) (xy 292.018986 -304.924714) (xy 290.730178 -304.924714)
			(xy 290.729683 -304.949321) (xy 290.721788 -304.997898) (xy 290.706204 -305.044579) (xy 290.683333 -305.088156)
			(xy 290.653768 -305.1275) (xy 290.618275 -305.161592) (xy 290.577772 -305.189548) (xy 290.53331 -305.210646)
			(xy 290.486039 -305.224338) (xy 290.437184 -305.23027) (xy 290.388009 -305.228289) (xy 290.33979 -305.218445)
			(xy 290.293774 -305.200993) (xy 290.251153 -305.176386) (xy 290.213032 -305.145261) (xy 290.180397 -305.108424)
			(xy 290.154094 -305.066828) (xy 290.134803 -305.021552) (xy 290.123026 -304.973768) (xy 290.119066 -304.924714)
			(xy 289.780218 -304.924714) (xy 289.779723 -304.949321) (xy 289.771828 -304.997898) (xy 289.756244 -305.044579)
			(xy 289.733373 -305.088156) (xy 289.703808 -305.1275) (xy 289.668315 -305.161592) (xy 289.627812 -305.189548)
			(xy 289.58335 -305.210646) (xy 289.536079 -305.224338) (xy 289.487224 -305.23027) (xy 289.438049 -305.228289)
			(xy 289.38983 -305.218445) (xy 289.343814 -305.200993) (xy 289.301193 -305.176386) (xy 289.263072 -305.145261)
			(xy 289.230437 -305.108424) (xy 289.204134 -305.066828) (xy 289.184843 -305.021552) (xy 289.173066 -304.973768)
			(xy 289.169106 -304.924714) (xy 288.830004 -304.924714) (xy 288.829509 -304.949321) (xy 288.821614 -304.997898)
			(xy 288.80603 -305.044579) (xy 288.783159 -305.088156) (xy 288.753594 -305.1275) (xy 288.718101 -305.161592)
			(xy 288.677598 -305.189548) (xy 288.633136 -305.210646) (xy 288.585865 -305.224338) (xy 288.53701 -305.23027)
			(xy 288.487835 -305.228289) (xy 288.439616 -305.218445) (xy 288.3936 -305.200993) (xy 288.350979 -305.176386)
			(xy 288.312858 -305.145261) (xy 288.280223 -305.108424) (xy 288.25392 -305.066828) (xy 288.234629 -305.021552)
			(xy 288.222852 -304.973768) (xy 288.218892 -304.924714) (xy 287.880044 -304.924714) (xy 287.879549 -304.949321)
			(xy 287.871654 -304.997898) (xy 287.85607 -305.044579) (xy 287.833199 -305.088156) (xy 287.803634 -305.1275)
			(xy 287.768141 -305.161592) (xy 287.727638 -305.189548) (xy 287.683176 -305.210646) (xy 287.635905 -305.224338)
			(xy 287.58705 -305.23027) (xy 287.537875 -305.228289) (xy 287.489656 -305.218445) (xy 287.44364 -305.200993)
			(xy 287.401019 -305.176386) (xy 287.362898 -305.145261) (xy 287.330263 -305.108424) (xy 287.30396 -305.066828)
			(xy 287.284669 -305.021552) (xy 287.272892 -304.973768) (xy 287.268932 -304.924714) (xy 286.930084 -304.924714)
			(xy 286.929589 -304.949321) (xy 286.921694 -304.997898) (xy 286.90611 -305.044579) (xy 286.883239 -305.088156)
			(xy 286.853674 -305.1275) (xy 286.818181 -305.161592) (xy 286.777678 -305.189548) (xy 286.733216 -305.210646)
			(xy 286.685945 -305.224338) (xy 286.63709 -305.23027) (xy 286.587915 -305.228289) (xy 286.539696 -305.218445)
			(xy 286.49368 -305.200993) (xy 286.451059 -305.176386) (xy 286.412938 -305.145261) (xy 286.380303 -305.108424)
			(xy 286.354 -305.066828) (xy 286.334709 -305.021552) (xy 286.322932 -304.973768) (xy 286.318972 -304.924714)
			(xy 285.980124 -304.924714) (xy 285.979629 -304.949321) (xy 285.971734 -304.997898) (xy 285.95615 -305.044579)
			(xy 285.933279 -305.088156) (xy 285.903714 -305.1275) (xy 285.868221 -305.161592) (xy 285.827718 -305.189548)
			(xy 285.783256 -305.210646) (xy 285.735985 -305.224338) (xy 285.68713 -305.23027) (xy 285.637955 -305.228289)
			(xy 285.589736 -305.218445) (xy 285.54372 -305.200993) (xy 285.501099 -305.176386) (xy 285.462978 -305.145261)
			(xy 285.430343 -305.108424) (xy 285.40404 -305.066828) (xy 285.384749 -305.021552) (xy 285.372972 -304.973768)
			(xy 285.369012 -304.924714) (xy 285.030164 -304.924714) (xy 285.029669 -304.949321) (xy 285.021774 -304.997898)
			(xy 285.00619 -305.044579) (xy 284.983319 -305.088156) (xy 284.953754 -305.1275) (xy 284.918261 -305.161592)
			(xy 284.877758 -305.189548) (xy 284.833296 -305.210646) (xy 284.786025 -305.224338) (xy 284.73717 -305.23027)
			(xy 284.687995 -305.228289) (xy 284.639776 -305.218445) (xy 284.59376 -305.200993) (xy 284.551139 -305.176386)
			(xy 284.513018 -305.145261) (xy 284.480383 -305.108424) (xy 284.45408 -305.066828) (xy 284.434789 -305.021552)
			(xy 284.423012 -304.973768) (xy 284.419052 -304.924714) (xy 284.080204 -304.924714) (xy 284.079709 -304.949321)
			(xy 284.071814 -304.997898) (xy 284.05623 -305.044579) (xy 284.033359 -305.088156) (xy 284.003794 -305.1275)
			(xy 283.968301 -305.161592) (xy 283.927798 -305.189548) (xy 283.883336 -305.210646) (xy 283.836065 -305.224338)
			(xy 283.78721 -305.23027) (xy 283.738035 -305.228289) (xy 283.689816 -305.218445) (xy 283.6438 -305.200993)
			(xy 283.601179 -305.176386) (xy 283.563058 -305.145261) (xy 283.530423 -305.108424) (xy 283.50412 -305.066828)
			(xy 283.484829 -305.021552) (xy 283.473052 -304.973768) (xy 283.469092 -304.924714) (xy 283.130244 -304.924714)
			(xy 283.129749 -304.949321) (xy 283.121854 -304.997898) (xy 283.10627 -305.044579) (xy 283.083399 -305.088156)
			(xy 283.053834 -305.1275) (xy 283.018341 -305.161592) (xy 282.977838 -305.189548) (xy 282.933376 -305.210646)
			(xy 282.886105 -305.224338) (xy 282.83725 -305.23027) (xy 282.788075 -305.228289) (xy 282.739856 -305.218445)
			(xy 282.69384 -305.200993) (xy 282.651219 -305.176386) (xy 282.613098 -305.145261) (xy 282.580463 -305.108424)
			(xy 282.55416 -305.066828) (xy 282.534869 -305.021552) (xy 282.523092 -304.973768) (xy 282.519132 -304.924714)
			(xy 282.18003 -304.924714) (xy 282.179535 -304.949321) (xy 282.17164 -304.997898) (xy 282.156056 -305.044579)
			(xy 282.133185 -305.088156) (xy 282.10362 -305.1275) (xy 282.068127 -305.161592) (xy 282.027624 -305.189548)
			(xy 281.983162 -305.210646) (xy 281.935891 -305.224338) (xy 281.887036 -305.23027) (xy 281.837861 -305.228289)
			(xy 281.789642 -305.218445) (xy 281.743626 -305.200993) (xy 281.701005 -305.176386) (xy 281.662884 -305.145261)
			(xy 281.630249 -305.108424) (xy 281.603946 -305.066828) (xy 281.584655 -305.021552) (xy 281.572878 -304.973768)
			(xy 281.568918 -304.924714) (xy 281.23007 -304.924714) (xy 281.229575 -304.949321) (xy 281.22168 -304.997898)
			(xy 281.206096 -305.044579) (xy 281.183225 -305.088156) (xy 281.15366 -305.1275) (xy 281.118167 -305.161592)
			(xy 281.077664 -305.189548) (xy 281.033202 -305.210646) (xy 280.985931 -305.224338) (xy 280.937076 -305.23027)
			(xy 280.887901 -305.228289) (xy 280.839682 -305.218445) (xy 280.793666 -305.200993) (xy 280.751045 -305.176386)
			(xy 280.712924 -305.145261) (xy 280.680289 -305.108424) (xy 280.653986 -305.066828) (xy 280.634695 -305.021552)
			(xy 280.622918 -304.973768) (xy 280.618958 -304.924714) (xy 280.28011 -304.924714) (xy 280.279615 -304.949321)
			(xy 280.27172 -304.997898) (xy 280.256136 -305.044579) (xy 280.233265 -305.088156) (xy 280.2037 -305.1275)
			(xy 280.168207 -305.161592) (xy 280.127704 -305.189548) (xy 280.083242 -305.210646) (xy 280.035971 -305.224338)
			(xy 279.987116 -305.23027) (xy 279.937941 -305.228289) (xy 279.889722 -305.218445) (xy 279.843706 -305.200993)
			(xy 279.801085 -305.176386) (xy 279.762964 -305.145261) (xy 279.730329 -305.108424) (xy 279.704026 -305.066828)
			(xy 279.684735 -305.021552) (xy 279.672958 -304.973768) (xy 279.668998 -304.924714) (xy 279.33015 -304.924714)
			(xy 279.329655 -304.949321) (xy 279.32176 -304.997898) (xy 279.306176 -305.044579) (xy 279.283305 -305.088156)
			(xy 279.25374 -305.1275) (xy 279.218247 -305.161592) (xy 279.177744 -305.189548) (xy 279.133282 -305.210646)
			(xy 279.086011 -305.224338) (xy 279.037156 -305.23027) (xy 278.987981 -305.228289) (xy 278.939762 -305.218445)
			(xy 278.893746 -305.200993) (xy 278.851125 -305.176386) (xy 278.813004 -305.145261) (xy 278.780369 -305.108424)
			(xy 278.754066 -305.066828) (xy 278.734775 -305.021552) (xy 278.722998 -304.973768) (xy 278.719038 -304.924714)
			(xy 246.86641 -304.924714) (xy 248.18604 -306.244344) (xy 258.80912 -306.244344) (xy 258.809122 -306.189831)
			(xy 258.816882 -306.135873) (xy 258.832242 -306.083569) (xy 258.85489 -306.033984) (xy 258.884365 -305.988127)
			(xy 258.920065 -305.946931) (xy 258.961266 -305.911235) (xy 259.007127 -305.881767) (xy 259.056715 -305.859125)
			(xy 259.109021 -305.843772) (xy 259.16298 -305.836018) (xy 259.190236 -305.835558) (xy 259.219446 -305.836574)
			(xy 259.233236 -305.837162) (xy 259.260291 -305.831747) (xy 259.28491 -305.81929) (xy 259.305298 -305.800699)
			(xy 259.319966 -305.77733) (xy 259.327847 -305.750888) (xy 259.328363 -305.723302) (xy 259.325364 -305.709828)
			(xy 259.31965 -305.686238) (xy 259.313536 -305.638086) (xy 259.313172 -305.613816) (xy 259.313638 -305.586561)
			(xy 259.321393 -305.532607) (xy 259.336748 -305.480305) (xy 259.35939 -305.430721) (xy 259.388859 -305.384864)
			(xy 259.424554 -305.343668) (xy 259.465748 -305.307971) (xy 259.511603 -305.2785) (xy 259.561186 -305.255855)
			(xy 259.613487 -305.240497) (xy 259.667441 -305.232739) (xy 259.721951 -305.232739) (xy 259.775905 -305.240496)
			(xy 259.828206 -305.255852) (xy 259.877789 -305.278496) (xy 259.923645 -305.307966) (xy 259.964841 -305.343662)
			(xy 260.000536 -305.384858) (xy 260.010234 -305.399948) (xy 268.74395 -305.399948) (xy 268.74791 -305.350894)
			(xy 268.759687 -305.30311) (xy 268.778978 -305.257834) (xy 268.805281 -305.216238) (xy 268.837916 -305.179401)
			(xy 268.876037 -305.148276) (xy 268.918658 -305.123669) (xy 268.964674 -305.106217) (xy 269.012893 -305.096373)
			(xy 269.062068 -305.094392) (xy 269.110923 -305.100324) (xy 269.158194 -305.114016) (xy 269.202656 -305.135114)
			(xy 269.243159 -305.16307) (xy 269.278652 -305.197162) (xy 269.308217 -305.236506) (xy 269.331088 -305.280083)
			(xy 269.346672 -305.326764) (xy 269.354567 -305.375341) (xy 269.355062 -305.399948) (xy 269.69391 -305.399948)
			(xy 269.69787 -305.350894) (xy 269.709647 -305.30311) (xy 269.728938 -305.257834) (xy 269.755241 -305.216238)
			(xy 269.787876 -305.179401) (xy 269.825997 -305.148276) (xy 269.868618 -305.123669) (xy 269.914634 -305.106217)
			(xy 269.962853 -305.096373) (xy 270.012028 -305.094392) (xy 270.060883 -305.100324) (xy 270.108154 -305.114016)
			(xy 270.152616 -305.135114) (xy 270.193119 -305.16307) (xy 270.228612 -305.197162) (xy 270.258177 -305.236506)
			(xy 270.281048 -305.280083) (xy 270.296632 -305.326764) (xy 270.304527 -305.375341) (xy 270.305022 -305.399948)
			(xy 270.304527 -305.424555) (xy 270.304348 -305.425656) (xy 270.62328 -305.425656) (xy 270.62328 -305.37424)
			(xy 270.631323 -305.323458) (xy 270.647211 -305.274559) (xy 270.670554 -305.228747) (xy 270.700775 -305.187151)
			(xy 270.737131 -305.150795) (xy 270.778727 -305.120574) (xy 270.824539 -305.097231) (xy 270.873438 -305.081343)
			(xy 270.92422 -305.0733) (xy 270.975636 -305.0733) (xy 271.026418 -305.081343) (xy 271.075317 -305.097231)
			(xy 271.121129 -305.120574) (xy 271.162725 -305.150795) (xy 271.199081 -305.187151) (xy 271.229302 -305.228747)
			(xy 271.252645 -305.274559) (xy 271.268533 -305.323458) (xy 271.276576 -305.37424) (xy 271.27708 -305.399948)
			(xy 271.276576 -305.425656) (xy 271.57324 -305.425656) (xy 271.57324 -305.37424) (xy 271.581283 -305.323458)
			(xy 271.597171 -305.274559) (xy 271.620514 -305.228747) (xy 271.650735 -305.187151) (xy 271.687091 -305.150795)
			(xy 271.728687 -305.120574) (xy 271.774499 -305.097231) (xy 271.823398 -305.081343) (xy 271.87418 -305.0733)
			(xy 271.925596 -305.0733) (xy 271.976378 -305.081343) (xy 272.025277 -305.097231) (xy 272.071089 -305.120574)
			(xy 272.112685 -305.150795) (xy 272.149041 -305.187151) (xy 272.179262 -305.228747) (xy 272.202605 -305.274559)
			(xy 272.218493 -305.323458) (xy 272.226536 -305.37424) (xy 272.22704 -305.399948) (xy 272.544044 -305.399948)
			(xy 272.548004 -305.350894) (xy 272.559781 -305.30311) (xy 272.579072 -305.257834) (xy 272.605375 -305.216238)
			(xy 272.63801 -305.179401) (xy 272.676131 -305.148276) (xy 272.718752 -305.123669) (xy 272.764768 -305.106217)
			(xy 272.812987 -305.096373) (xy 272.862162 -305.094392) (xy 272.911017 -305.100324) (xy 272.958288 -305.114016)
			(xy 273.00275 -305.135114) (xy 273.043253 -305.16307) (xy 273.078746 -305.197162) (xy 273.108311 -305.236506)
			(xy 273.131182 -305.280083) (xy 273.146766 -305.326764) (xy 273.154661 -305.375341) (xy 273.155156 -305.399948)
			(xy 273.154661 -305.424555) (xy 273.154482 -305.425656) (xy 273.47316 -305.425656) (xy 273.47316 -305.37424)
			(xy 273.481203 -305.323458) (xy 273.497091 -305.274559) (xy 273.520434 -305.228747) (xy 273.550655 -305.187151)
			(xy 273.587011 -305.150795) (xy 273.628607 -305.120574) (xy 273.674419 -305.097231) (xy 273.723318 -305.081343)
			(xy 273.7741 -305.0733) (xy 273.825516 -305.0733) (xy 273.876298 -305.081343) (xy 273.925197 -305.097231)
			(xy 273.971009 -305.120574) (xy 274.012605 -305.150795) (xy 274.048961 -305.187151) (xy 274.079182 -305.228747)
			(xy 274.102525 -305.274559) (xy 274.118413 -305.323458) (xy 274.126456 -305.37424) (xy 274.12696 -305.399948)
			(xy 274.126456 -305.425656) (xy 274.42312 -305.425656) (xy 274.42312 -305.37424) (xy 274.431163 -305.323458)
			(xy 274.447051 -305.274559) (xy 274.470394 -305.228747) (xy 274.500615 -305.187151) (xy 274.536971 -305.150795)
			(xy 274.578567 -305.120574) (xy 274.624379 -305.097231) (xy 274.673278 -305.081343) (xy 274.72406 -305.0733)
			(xy 274.775476 -305.0733) (xy 274.826258 -305.081343) (xy 274.875157 -305.097231) (xy 274.920969 -305.120574)
			(xy 274.962565 -305.150795) (xy 274.998921 -305.187151) (xy 275.029142 -305.228747) (xy 275.052485 -305.274559)
			(xy 275.068373 -305.323458) (xy 275.076416 -305.37424) (xy 275.07692 -305.399948) (xy 275.393924 -305.399948)
			(xy 275.397884 -305.350894) (xy 275.409661 -305.30311) (xy 275.428952 -305.257834) (xy 275.455255 -305.216238)
			(xy 275.48789 -305.179401) (xy 275.526011 -305.148276) (xy 275.568632 -305.123669) (xy 275.614648 -305.106217)
			(xy 275.662867 -305.096373) (xy 275.712042 -305.094392) (xy 275.760897 -305.100324) (xy 275.808168 -305.114016)
			(xy 275.85263 -305.135114) (xy 275.893133 -305.16307) (xy 275.928626 -305.197162) (xy 275.958191 -305.236506)
			(xy 275.981062 -305.280083) (xy 275.996646 -305.326764) (xy 276.004541 -305.375341) (xy 276.005036 -305.399948)
			(xy 276.343884 -305.399948) (xy 276.347844 -305.350894) (xy 276.359621 -305.30311) (xy 276.378912 -305.257834)
			(xy 276.405215 -305.216238) (xy 276.43785 -305.179401) (xy 276.475971 -305.148276) (xy 276.518592 -305.123669)
			(xy 276.564608 -305.106217) (xy 276.612827 -305.096373) (xy 276.662002 -305.094392) (xy 276.710857 -305.100324)
			(xy 276.758128 -305.114016) (xy 276.80259 -305.135114) (xy 276.843093 -305.16307) (xy 276.878586 -305.197162)
			(xy 276.908151 -305.236506) (xy 276.931022 -305.280083) (xy 276.946606 -305.326764) (xy 276.954501 -305.375341)
			(xy 276.954996 -305.399948) (xy 277.294098 -305.399948) (xy 277.298058 -305.350894) (xy 277.309835 -305.30311)
			(xy 277.329126 -305.257834) (xy 277.355429 -305.216238) (xy 277.388064 -305.179401) (xy 277.426185 -305.148276)
			(xy 277.468806 -305.123669) (xy 277.514822 -305.106217) (xy 277.563041 -305.096373) (xy 277.612216 -305.094392)
			(xy 277.661071 -305.100324) (xy 277.708342 -305.114016) (xy 277.752804 -305.135114) (xy 277.793307 -305.16307)
			(xy 277.8288 -305.197162) (xy 277.858365 -305.236506) (xy 277.881236 -305.280083) (xy 277.89682 -305.326764)
			(xy 277.904715 -305.375341) (xy 277.90521 -305.399948) (xy 277.904715 -305.424555) (xy 277.89682 -305.473132)
			(xy 277.881236 -305.519813) (xy 277.858365 -305.56339) (xy 277.8288 -305.602734) (xy 277.793307 -305.636826)
			(xy 277.752804 -305.664782) (xy 277.708342 -305.68588) (xy 277.661071 -305.699572) (xy 277.612216 -305.705504)
			(xy 277.563041 -305.703523) (xy 277.514822 -305.693679) (xy 277.468806 -305.676227) (xy 277.426185 -305.65162)
			(xy 277.388064 -305.620495) (xy 277.355429 -305.583658) (xy 277.329126 -305.542062) (xy 277.309835 -305.496786)
			(xy 277.298058 -305.449002) (xy 277.294098 -305.399948) (xy 276.954996 -305.399948) (xy 276.954501 -305.424555)
			(xy 276.946606 -305.473132) (xy 276.931022 -305.519813) (xy 276.908151 -305.56339) (xy 276.878586 -305.602734)
			(xy 276.843093 -305.636826) (xy 276.80259 -305.664782) (xy 276.758128 -305.68588) (xy 276.710857 -305.699572)
			(xy 276.662002 -305.705504) (xy 276.612827 -305.703523) (xy 276.564608 -305.693679) (xy 276.518592 -305.676227)
			(xy 276.475971 -305.65162) (xy 276.43785 -305.620495) (xy 276.405215 -305.583658) (xy 276.378912 -305.542062)
			(xy 276.359621 -305.496786) (xy 276.347844 -305.449002) (xy 276.343884 -305.399948) (xy 276.005036 -305.399948)
			(xy 276.004541 -305.424555) (xy 275.996646 -305.473132) (xy 275.981062 -305.519813) (xy 275.958191 -305.56339)
			(xy 275.928626 -305.602734) (xy 275.893133 -305.636826) (xy 275.85263 -305.664782) (xy 275.808168 -305.68588)
			(xy 275.760897 -305.699572) (xy 275.712042 -305.705504) (xy 275.662867 -305.703523) (xy 275.614648 -305.693679)
			(xy 275.568632 -305.676227) (xy 275.526011 -305.65162) (xy 275.48789 -305.620495) (xy 275.455255 -305.583658)
			(xy 275.428952 -305.542062) (xy 275.409661 -305.496786) (xy 275.397884 -305.449002) (xy 275.393924 -305.399948)
			(xy 275.07692 -305.399948) (xy 275.076416 -305.425656) (xy 275.068373 -305.476438) (xy 275.052485 -305.525337)
			(xy 275.029142 -305.571149) (xy 274.998921 -305.612745) (xy 274.962565 -305.649101) (xy 274.920969 -305.679322)
			(xy 274.875157 -305.702665) (xy 274.826258 -305.718553) (xy 274.775476 -305.726596) (xy 274.72406 -305.726596)
			(xy 274.673278 -305.718553) (xy 274.624379 -305.702665) (xy 274.578567 -305.679322) (xy 274.536971 -305.649101)
			(xy 274.500615 -305.612745) (xy 274.470394 -305.571149) (xy 274.447051 -305.525337) (xy 274.431163 -305.476438)
			(xy 274.42312 -305.425656) (xy 274.126456 -305.425656) (xy 274.118413 -305.476438) (xy 274.102525 -305.525337)
			(xy 274.079182 -305.571149) (xy 274.048961 -305.612745) (xy 274.012605 -305.649101) (xy 273.971009 -305.679322)
			(xy 273.925197 -305.702665) (xy 273.876298 -305.718553) (xy 273.825516 -305.726596) (xy 273.7741 -305.726596)
			(xy 273.723318 -305.718553) (xy 273.674419 -305.702665) (xy 273.628607 -305.679322) (xy 273.587011 -305.649101)
			(xy 273.550655 -305.612745) (xy 273.520434 -305.571149) (xy 273.497091 -305.525337) (xy 273.481203 -305.476438)
			(xy 273.47316 -305.425656) (xy 273.154482 -305.425656) (xy 273.146766 -305.473132) (xy 273.131182 -305.519813)
			(xy 273.108311 -305.56339) (xy 273.078746 -305.602734) (xy 273.043253 -305.636826) (xy 273.00275 -305.664782)
			(xy 272.958288 -305.68588) (xy 272.911017 -305.699572) (xy 272.862162 -305.705504) (xy 272.812987 -305.703523)
			(xy 272.764768 -305.693679) (xy 272.718752 -305.676227) (xy 272.676131 -305.65162) (xy 272.63801 -305.620495)
			(xy 272.605375 -305.583658) (xy 272.579072 -305.542062) (xy 272.559781 -305.496786) (xy 272.548004 -305.449002)
			(xy 272.544044 -305.399948) (xy 272.22704 -305.399948) (xy 272.226536 -305.425656) (xy 272.218493 -305.476438)
			(xy 272.202605 -305.525337) (xy 272.179262 -305.571149) (xy 272.149041 -305.612745) (xy 272.112685 -305.649101)
			(xy 272.071089 -305.679322) (xy 272.025277 -305.702665) (xy 271.976378 -305.718553) (xy 271.925596 -305.726596)
			(xy 271.87418 -305.726596) (xy 271.823398 -305.718553) (xy 271.774499 -305.702665) (xy 271.728687 -305.679322)
			(xy 271.687091 -305.649101) (xy 271.650735 -305.612745) (xy 271.620514 -305.571149) (xy 271.597171 -305.525337)
			(xy 271.581283 -305.476438) (xy 271.57324 -305.425656) (xy 271.276576 -305.425656) (xy 271.268533 -305.476438)
			(xy 271.252645 -305.525337) (xy 271.229302 -305.571149) (xy 271.199081 -305.612745) (xy 271.162725 -305.649101)
			(xy 271.121129 -305.679322) (xy 271.075317 -305.702665) (xy 271.026418 -305.718553) (xy 270.975636 -305.726596)
			(xy 270.92422 -305.726596) (xy 270.873438 -305.718553) (xy 270.824539 -305.702665) (xy 270.778727 -305.679322)
			(xy 270.737131 -305.649101) (xy 270.700775 -305.612745) (xy 270.670554 -305.571149) (xy 270.647211 -305.525337)
			(xy 270.631323 -305.476438) (xy 270.62328 -305.425656) (xy 270.304348 -305.425656) (xy 270.296632 -305.473132)
			(xy 270.281048 -305.519813) (xy 270.258177 -305.56339) (xy 270.228612 -305.602734) (xy 270.193119 -305.636826)
			(xy 270.152616 -305.664782) (xy 270.108154 -305.68588) (xy 270.060883 -305.699572) (xy 270.012028 -305.705504)
			(xy 269.962853 -305.703523) (xy 269.914634 -305.693679) (xy 269.868618 -305.676227) (xy 269.825997 -305.65162)
			(xy 269.787876 -305.620495) (xy 269.755241 -305.583658) (xy 269.728938 -305.542062) (xy 269.709647 -305.496786)
			(xy 269.69787 -305.449002) (xy 269.69391 -305.399948) (xy 269.355062 -305.399948) (xy 269.354567 -305.424555)
			(xy 269.346672 -305.473132) (xy 269.331088 -305.519813) (xy 269.308217 -305.56339) (xy 269.278652 -305.602734)
			(xy 269.243159 -305.636826) (xy 269.202656 -305.664782) (xy 269.158194 -305.68588) (xy 269.110923 -305.699572)
			(xy 269.062068 -305.705504) (xy 269.012893 -305.703523) (xy 268.964674 -305.693679) (xy 268.918658 -305.676227)
			(xy 268.876037 -305.65162) (xy 268.837916 -305.620495) (xy 268.805281 -305.583658) (xy 268.778978 -305.542062)
			(xy 268.759687 -305.496786) (xy 268.74791 -305.449002) (xy 268.74395 -305.399948) (xy 260.010234 -305.399948)
			(xy 260.030006 -305.430714) (xy 260.052649 -305.480298) (xy 260.068005 -305.532599) (xy 260.075762 -305.586553)
			(xy 260.075761 -305.641063) (xy 260.068002 -305.695017) (xy 260.052643 -305.747317) (xy 260.029998 -305.7969)
			(xy 260.000527 -305.842755) (xy 259.972646 -305.874928) (xy 278.719038 -305.874928) (xy 278.722998 -305.825874)
			(xy 278.734775 -305.77809) (xy 278.754066 -305.732814) (xy 278.780369 -305.691218) (xy 278.813004 -305.654381)
			(xy 278.851125 -305.623256) (xy 278.893746 -305.598649) (xy 278.939762 -305.581197) (xy 278.987981 -305.571353)
			(xy 279.037156 -305.569372) (xy 279.086011 -305.575304) (xy 279.133282 -305.588996) (xy 279.177744 -305.610094)
			(xy 279.218247 -305.63805) (xy 279.25374 -305.672142) (xy 279.283305 -305.711486) (xy 279.306176 -305.755063)
			(xy 279.32176 -305.801744) (xy 279.329655 -305.850321) (xy 279.33015 -305.874928) (xy 279.668998 -305.874928)
			(xy 279.672958 -305.825874) (xy 279.684735 -305.77809) (xy 279.704026 -305.732814) (xy 279.730329 -305.691218)
			(xy 279.762964 -305.654381) (xy 279.801085 -305.623256) (xy 279.843706 -305.598649) (xy 279.889722 -305.581197)
			(xy 279.937941 -305.571353) (xy 279.987116 -305.569372) (xy 280.035971 -305.575304) (xy 280.083242 -305.588996)
			(xy 280.127704 -305.610094) (xy 280.168207 -305.63805) (xy 280.2037 -305.672142) (xy 280.233265 -305.711486)
			(xy 280.256136 -305.755063) (xy 280.27172 -305.801744) (xy 280.279615 -305.850321) (xy 280.28011 -305.874928)
			(xy 280.618958 -305.874928) (xy 280.622918 -305.825874) (xy 280.634695 -305.77809) (xy 280.653986 -305.732814)
			(xy 280.680289 -305.691218) (xy 280.712924 -305.654381) (xy 280.751045 -305.623256) (xy 280.793666 -305.598649)
			(xy 280.839682 -305.581197) (xy 280.887901 -305.571353) (xy 280.937076 -305.569372) (xy 280.985931 -305.575304)
			(xy 281.033202 -305.588996) (xy 281.077664 -305.610094) (xy 281.118167 -305.63805) (xy 281.15366 -305.672142)
			(xy 281.183225 -305.711486) (xy 281.206096 -305.755063) (xy 281.22168 -305.801744) (xy 281.229575 -305.850321)
			(xy 281.23007 -305.874928) (xy 281.568918 -305.874928) (xy 281.572878 -305.825874) (xy 281.584655 -305.77809)
			(xy 281.603946 -305.732814) (xy 281.630249 -305.691218) (xy 281.662884 -305.654381) (xy 281.701005 -305.623256)
			(xy 281.743626 -305.598649) (xy 281.789642 -305.581197) (xy 281.837861 -305.571353) (xy 281.887036 -305.569372)
			(xy 281.935891 -305.575304) (xy 281.983162 -305.588996) (xy 282.027624 -305.610094) (xy 282.068127 -305.63805)
			(xy 282.10362 -305.672142) (xy 282.133185 -305.711486) (xy 282.156056 -305.755063) (xy 282.17164 -305.801744)
			(xy 282.179535 -305.850321) (xy 282.18003 -305.874928) (xy 282.519132 -305.874928) (xy 282.523092 -305.825874)
			(xy 282.534869 -305.77809) (xy 282.55416 -305.732814) (xy 282.580463 -305.691218) (xy 282.613098 -305.654381)
			(xy 282.651219 -305.623256) (xy 282.69384 -305.598649) (xy 282.739856 -305.581197) (xy 282.788075 -305.571353)
			(xy 282.83725 -305.569372) (xy 282.886105 -305.575304) (xy 282.933376 -305.588996) (xy 282.977838 -305.610094)
			(xy 283.018341 -305.63805) (xy 283.053834 -305.672142) (xy 283.083399 -305.711486) (xy 283.10627 -305.755063)
			(xy 283.121854 -305.801744) (xy 283.129749 -305.850321) (xy 283.130244 -305.874928) (xy 283.469092 -305.874928)
			(xy 283.473052 -305.825874) (xy 283.484829 -305.77809) (xy 283.50412 -305.732814) (xy 283.530423 -305.691218)
			(xy 283.563058 -305.654381) (xy 283.601179 -305.623256) (xy 283.6438 -305.598649) (xy 283.689816 -305.581197)
			(xy 283.738035 -305.571353) (xy 283.78721 -305.569372) (xy 283.836065 -305.575304) (xy 283.883336 -305.588996)
			(xy 283.927798 -305.610094) (xy 283.968301 -305.63805) (xy 284.003794 -305.672142) (xy 284.033359 -305.711486)
			(xy 284.05623 -305.755063) (xy 284.071814 -305.801744) (xy 284.079709 -305.850321) (xy 284.080204 -305.874928)
			(xy 284.419052 -305.874928) (xy 284.423012 -305.825874) (xy 284.434789 -305.77809) (xy 284.45408 -305.732814)
			(xy 284.480383 -305.691218) (xy 284.513018 -305.654381) (xy 284.551139 -305.623256) (xy 284.59376 -305.598649)
			(xy 284.639776 -305.581197) (xy 284.687995 -305.571353) (xy 284.73717 -305.569372) (xy 284.786025 -305.575304)
			(xy 284.833296 -305.588996) (xy 284.877758 -305.610094) (xy 284.918261 -305.63805) (xy 284.953754 -305.672142)
			(xy 284.983319 -305.711486) (xy 285.00619 -305.755063) (xy 285.021774 -305.801744) (xy 285.029669 -305.850321)
			(xy 285.030164 -305.874928) (xy 285.369012 -305.874928) (xy 285.372972 -305.825874) (xy 285.384749 -305.77809)
			(xy 285.40404 -305.732814) (xy 285.430343 -305.691218) (xy 285.462978 -305.654381) (xy 285.501099 -305.623256)
			(xy 285.54372 -305.598649) (xy 285.589736 -305.581197) (xy 285.637955 -305.571353) (xy 285.68713 -305.569372)
			(xy 285.735985 -305.575304) (xy 285.783256 -305.588996) (xy 285.827718 -305.610094) (xy 285.868221 -305.63805)
			(xy 285.903714 -305.672142) (xy 285.933279 -305.711486) (xy 285.95615 -305.755063) (xy 285.971734 -305.801744)
			(xy 285.979629 -305.850321) (xy 285.980124 -305.874928) (xy 286.318972 -305.874928) (xy 286.322932 -305.825874)
			(xy 286.334709 -305.77809) (xy 286.354 -305.732814) (xy 286.380303 -305.691218) (xy 286.412938 -305.654381)
			(xy 286.451059 -305.623256) (xy 286.49368 -305.598649) (xy 286.539696 -305.581197) (xy 286.587915 -305.571353)
			(xy 286.63709 -305.569372) (xy 286.685945 -305.575304) (xy 286.733216 -305.588996) (xy 286.777678 -305.610094)
			(xy 286.818181 -305.63805) (xy 286.853674 -305.672142) (xy 286.883239 -305.711486) (xy 286.90611 -305.755063)
			(xy 286.921694 -305.801744) (xy 286.929589 -305.850321) (xy 286.930084 -305.874928) (xy 287.268932 -305.874928)
			(xy 287.272892 -305.825874) (xy 287.284669 -305.77809) (xy 287.30396 -305.732814) (xy 287.330263 -305.691218)
			(xy 287.362898 -305.654381) (xy 287.401019 -305.623256) (xy 287.44364 -305.598649) (xy 287.489656 -305.581197)
			(xy 287.537875 -305.571353) (xy 287.58705 -305.569372) (xy 287.635905 -305.575304) (xy 287.683176 -305.588996)
			(xy 287.727638 -305.610094) (xy 287.768141 -305.63805) (xy 287.803634 -305.672142) (xy 287.833199 -305.711486)
			(xy 287.85607 -305.755063) (xy 287.871654 -305.801744) (xy 287.879549 -305.850321) (xy 287.880044 -305.874928)
			(xy 288.218892 -305.874928) (xy 288.222852 -305.825874) (xy 288.234629 -305.77809) (xy 288.25392 -305.732814)
			(xy 288.280223 -305.691218) (xy 288.312858 -305.654381) (xy 288.350979 -305.623256) (xy 288.3936 -305.598649)
			(xy 288.439616 -305.581197) (xy 288.487835 -305.571353) (xy 288.53701 -305.569372) (xy 288.585865 -305.575304)
			(xy 288.633136 -305.588996) (xy 288.677598 -305.610094) (xy 288.718101 -305.63805) (xy 288.753594 -305.672142)
			(xy 288.783159 -305.711486) (xy 288.80603 -305.755063) (xy 288.821614 -305.801744) (xy 288.829509 -305.850321)
			(xy 288.830004 -305.874928) (xy 289.169106 -305.874928) (xy 289.173066 -305.825874) (xy 289.184843 -305.77809)
			(xy 289.204134 -305.732814) (xy 289.230437 -305.691218) (xy 289.263072 -305.654381) (xy 289.301193 -305.623256)
			(xy 289.343814 -305.598649) (xy 289.38983 -305.581197) (xy 289.438049 -305.571353) (xy 289.487224 -305.569372)
			(xy 289.536079 -305.575304) (xy 289.58335 -305.588996) (xy 289.627812 -305.610094) (xy 289.668315 -305.63805)
			(xy 289.703808 -305.672142) (xy 289.733373 -305.711486) (xy 289.756244 -305.755063) (xy 289.771828 -305.801744)
			(xy 289.779723 -305.850321) (xy 289.780218 -305.874928) (xy 290.119066 -305.874928) (xy 290.123026 -305.825874)
			(xy 290.134803 -305.77809) (xy 290.154094 -305.732814) (xy 290.180397 -305.691218) (xy 290.213032 -305.654381)
			(xy 290.251153 -305.623256) (xy 290.293774 -305.598649) (xy 290.33979 -305.581197) (xy 290.388009 -305.571353)
			(xy 290.437184 -305.569372) (xy 290.486039 -305.575304) (xy 290.53331 -305.588996) (xy 290.577772 -305.610094)
			(xy 290.618275 -305.63805) (xy 290.653768 -305.672142) (xy 290.683333 -305.711486) (xy 290.706204 -305.755063)
			(xy 290.721788 -305.801744) (xy 290.729683 -305.850321) (xy 290.730178 -305.874928) (xy 292.018986 -305.874928)
			(xy 292.022946 -305.825874) (xy 292.034723 -305.77809) (xy 292.054014 -305.732814) (xy 292.080317 -305.691218)
			(xy 292.112952 -305.654381) (xy 292.151073 -305.623256) (xy 292.193694 -305.598649) (xy 292.23971 -305.581197)
			(xy 292.287929 -305.571353) (xy 292.337104 -305.569372) (xy 292.385959 -305.575304) (xy 292.43323 -305.588996)
			(xy 292.477692 -305.610094) (xy 292.518195 -305.63805) (xy 292.553688 -305.672142) (xy 292.583253 -305.711486)
			(xy 292.606124 -305.755063) (xy 292.621708 -305.801744) (xy 292.629603 -305.850321) (xy 292.630098 -305.874928)
			(xy 292.968946 -305.874928) (xy 292.972906 -305.825874) (xy 292.984683 -305.77809) (xy 293.003974 -305.732814)
			(xy 293.030277 -305.691218) (xy 293.062912 -305.654381) (xy 293.101033 -305.623256) (xy 293.143654 -305.598649)
			(xy 293.18967 -305.581197) (xy 293.237889 -305.571353) (xy 293.287064 -305.569372) (xy 293.335919 -305.575304)
			(xy 293.38319 -305.588996) (xy 293.427652 -305.610094) (xy 293.468155 -305.63805) (xy 293.503648 -305.672142)
			(xy 293.533213 -305.711486) (xy 293.556084 -305.755063) (xy 293.571668 -305.801744) (xy 293.579563 -305.850321)
			(xy 293.580058 -305.874928) (xy 293.918906 -305.874928) (xy 293.922866 -305.825874) (xy 293.934643 -305.77809)
			(xy 293.953934 -305.732814) (xy 293.980237 -305.691218) (xy 294.012872 -305.654381) (xy 294.050993 -305.623256)
			(xy 294.093614 -305.598649) (xy 294.13963 -305.581197) (xy 294.187849 -305.571353) (xy 294.237024 -305.569372)
			(xy 294.285879 -305.575304) (xy 294.33315 -305.588996) (xy 294.377612 -305.610094) (xy 294.418115 -305.63805)
			(xy 294.453608 -305.672142) (xy 294.483173 -305.711486) (xy 294.506044 -305.755063) (xy 294.521628 -305.801744)
			(xy 294.529523 -305.850321) (xy 294.530018 -305.874928) (xy 294.86912 -305.874928) (xy 294.87308 -305.825874)
			(xy 294.884857 -305.77809) (xy 294.904148 -305.732814) (xy 294.930451 -305.691218) (xy 294.963086 -305.654381)
			(xy 295.001207 -305.623256) (xy 295.043828 -305.598649) (xy 295.089844 -305.581197) (xy 295.138063 -305.571353)
			(xy 295.187238 -305.569372) (xy 295.236093 -305.575304) (xy 295.283364 -305.588996) (xy 295.327826 -305.610094)
			(xy 295.368329 -305.63805) (xy 295.403822 -305.672142) (xy 295.433387 -305.711486) (xy 295.456258 -305.755063)
			(xy 295.471842 -305.801744) (xy 295.479737 -305.850321) (xy 295.480232 -305.874928) (xy 295.81908 -305.874928)
			(xy 295.82304 -305.825874) (xy 295.834817 -305.77809) (xy 295.854108 -305.732814) (xy 295.880411 -305.691218)
			(xy 295.913046 -305.654381) (xy 295.951167 -305.623256) (xy 295.993788 -305.598649) (xy 296.039804 -305.581197)
			(xy 296.088023 -305.571353) (xy 296.137198 -305.569372) (xy 296.186053 -305.575304) (xy 296.233324 -305.588996)
			(xy 296.277786 -305.610094) (xy 296.318289 -305.63805) (xy 296.353782 -305.672142) (xy 296.383347 -305.711486)
			(xy 296.406218 -305.755063) (xy 296.421802 -305.801744) (xy 296.429697 -305.850321) (xy 296.430192 -305.874928)
			(xy 296.76904 -305.874928) (xy 296.773 -305.825874) (xy 296.784777 -305.77809) (xy 296.804068 -305.732814)
			(xy 296.830371 -305.691218) (xy 296.863006 -305.654381) (xy 296.901127 -305.623256) (xy 296.943748 -305.598649)
			(xy 296.989764 -305.581197) (xy 297.037983 -305.571353) (xy 297.087158 -305.569372) (xy 297.136013 -305.575304)
			(xy 297.183284 -305.588996) (xy 297.227746 -305.610094) (xy 297.268249 -305.63805) (xy 297.303742 -305.672142)
			(xy 297.333307 -305.711486) (xy 297.356178 -305.755063) (xy 297.371762 -305.801744) (xy 297.379657 -305.850321)
			(xy 297.380152 -305.874928) (xy 297.719 -305.874928) (xy 297.72296 -305.825874) (xy 297.734737 -305.77809)
			(xy 297.754028 -305.732814) (xy 297.780331 -305.691218) (xy 297.812966 -305.654381) (xy 297.851087 -305.623256)
			(xy 297.893708 -305.598649) (xy 297.939724 -305.581197) (xy 297.987943 -305.571353) (xy 298.037118 -305.569372)
			(xy 298.085973 -305.575304) (xy 298.133244 -305.588996) (xy 298.177706 -305.610094) (xy 298.218209 -305.63805)
			(xy 298.253702 -305.672142) (xy 298.283267 -305.711486) (xy 298.306138 -305.755063) (xy 298.321722 -305.801744)
			(xy 298.329617 -305.850321) (xy 298.330112 -305.874928) (xy 298.66896 -305.874928) (xy 298.67292 -305.825874)
			(xy 298.684697 -305.77809) (xy 298.703988 -305.732814) (xy 298.730291 -305.691218) (xy 298.762926 -305.654381)
			(xy 298.801047 -305.623256) (xy 298.843668 -305.598649) (xy 298.889684 -305.581197) (xy 298.937903 -305.571353)
			(xy 298.987078 -305.569372) (xy 299.035933 -305.575304) (xy 299.083204 -305.588996) (xy 299.127666 -305.610094)
			(xy 299.168169 -305.63805) (xy 299.203662 -305.672142) (xy 299.233227 -305.711486) (xy 299.256098 -305.755063)
			(xy 299.271682 -305.801744) (xy 299.279577 -305.850321) (xy 299.280072 -305.874928) (xy 299.61892 -305.874928)
			(xy 299.62288 -305.825874) (xy 299.634657 -305.77809) (xy 299.653948 -305.732814) (xy 299.680251 -305.691218)
			(xy 299.712886 -305.654381) (xy 299.751007 -305.623256) (xy 299.793628 -305.598649) (xy 299.839644 -305.581197)
			(xy 299.887863 -305.571353) (xy 299.937038 -305.569372) (xy 299.985893 -305.575304) (xy 300.033164 -305.588996)
			(xy 300.077626 -305.610094) (xy 300.118129 -305.63805) (xy 300.153622 -305.672142) (xy 300.183187 -305.711486)
			(xy 300.206058 -305.755063) (xy 300.221642 -305.801744) (xy 300.229537 -305.850321) (xy 300.230032 -305.874928)
			(xy 300.56888 -305.874928) (xy 300.57284 -305.825874) (xy 300.584617 -305.77809) (xy 300.603908 -305.732814)
			(xy 300.630211 -305.691218) (xy 300.662846 -305.654381) (xy 300.700967 -305.623256) (xy 300.743588 -305.598649)
			(xy 300.789604 -305.581197) (xy 300.837823 -305.571353) (xy 300.886998 -305.569372) (xy 300.935853 -305.575304)
			(xy 300.983124 -305.588996) (xy 301.027586 -305.610094) (xy 301.068089 -305.63805) (xy 301.103582 -305.672142)
			(xy 301.133147 -305.711486) (xy 301.156018 -305.755063) (xy 301.171602 -305.801744) (xy 301.179497 -305.850321)
			(xy 301.179992 -305.874928) (xy 301.519094 -305.874928) (xy 301.523054 -305.825874) (xy 301.534831 -305.77809)
			(xy 301.554122 -305.732814) (xy 301.580425 -305.691218) (xy 301.61306 -305.654381) (xy 301.651181 -305.623256)
			(xy 301.693802 -305.598649) (xy 301.739818 -305.581197) (xy 301.788037 -305.571353) (xy 301.837212 -305.569372)
			(xy 301.886067 -305.575304) (xy 301.933338 -305.588996) (xy 301.9778 -305.610094) (xy 302.018303 -305.63805)
			(xy 302.053796 -305.672142) (xy 302.083361 -305.711486) (xy 302.106232 -305.755063) (xy 302.121816 -305.801744)
			(xy 302.129711 -305.850321) (xy 302.130206 -305.874928) (xy 302.469054 -305.874928) (xy 302.473014 -305.825874)
			(xy 302.484791 -305.77809) (xy 302.504082 -305.732814) (xy 302.530385 -305.691218) (xy 302.56302 -305.654381)
			(xy 302.601141 -305.623256) (xy 302.643762 -305.598649) (xy 302.689778 -305.581197) (xy 302.737997 -305.571353)
			(xy 302.787172 -305.569372) (xy 302.836027 -305.575304) (xy 302.883298 -305.588996) (xy 302.92776 -305.610094)
			(xy 302.968263 -305.63805) (xy 303.003756 -305.672142) (xy 303.033321 -305.711486) (xy 303.056192 -305.755063)
			(xy 303.071776 -305.801744) (xy 303.079671 -305.850321) (xy 303.080166 -305.874928) (xy 303.419014 -305.874928)
			(xy 303.422974 -305.825874) (xy 303.434751 -305.77809) (xy 303.454042 -305.732814) (xy 303.480345 -305.691218)
			(xy 303.51298 -305.654381) (xy 303.551101 -305.623256) (xy 303.593722 -305.598649) (xy 303.639738 -305.581197)
			(xy 303.687957 -305.571353) (xy 303.737132 -305.569372) (xy 303.785987 -305.575304) (xy 303.833258 -305.588996)
			(xy 303.87772 -305.610094) (xy 303.918223 -305.63805) (xy 303.953716 -305.672142) (xy 303.983281 -305.711486)
			(xy 304.006152 -305.755063) (xy 304.021736 -305.801744) (xy 304.029631 -305.850321) (xy 304.030126 -305.874928)
			(xy 304.029631 -305.899535) (xy 304.021736 -305.948112) (xy 304.006152 -305.994793) (xy 303.983281 -306.03837)
			(xy 303.953716 -306.077714) (xy 303.918223 -306.111806) (xy 303.87772 -306.139762) (xy 303.833258 -306.16086)
			(xy 303.785987 -306.174552) (xy 303.737132 -306.180484) (xy 303.687957 -306.178503) (xy 303.639738 -306.168659)
			(xy 303.593722 -306.151207) (xy 303.551101 -306.1266) (xy 303.51298 -306.095475) (xy 303.480345 -306.058638)
			(xy 303.454042 -306.017042) (xy 303.434751 -305.971766) (xy 303.422974 -305.923982) (xy 303.419014 -305.874928)
			(xy 303.080166 -305.874928) (xy 303.079671 -305.899535) (xy 303.071776 -305.948112) (xy 303.056192 -305.994793)
			(xy 303.033321 -306.03837) (xy 303.003756 -306.077714) (xy 302.968263 -306.111806) (xy 302.92776 -306.139762)
			(xy 302.883298 -306.16086) (xy 302.836027 -306.174552) (xy 302.787172 -306.180484) (xy 302.737997 -306.178503)
			(xy 302.689778 -306.168659) (xy 302.643762 -306.151207) (xy 302.601141 -306.1266) (xy 302.56302 -306.095475)
			(xy 302.530385 -306.058638) (xy 302.504082 -306.017042) (xy 302.484791 -305.971766) (xy 302.473014 -305.923982)
			(xy 302.469054 -305.874928) (xy 302.130206 -305.874928) (xy 302.129711 -305.899535) (xy 302.121816 -305.948112)
			(xy 302.106232 -305.994793) (xy 302.083361 -306.03837) (xy 302.053796 -306.077714) (xy 302.018303 -306.111806)
			(xy 301.9778 -306.139762) (xy 301.933338 -306.16086) (xy 301.886067 -306.174552) (xy 301.837212 -306.180484)
			(xy 301.788037 -306.178503) (xy 301.739818 -306.168659) (xy 301.693802 -306.151207) (xy 301.651181 -306.1266)
			(xy 301.61306 -306.095475) (xy 301.580425 -306.058638) (xy 301.554122 -306.017042) (xy 301.534831 -305.971766)
			(xy 301.523054 -305.923982) (xy 301.519094 -305.874928) (xy 301.179992 -305.874928) (xy 301.179497 -305.899535)
			(xy 301.171602 -305.948112) (xy 301.156018 -305.994793) (xy 301.133147 -306.03837) (xy 301.103582 -306.077714)
			(xy 301.068089 -306.111806) (xy 301.027586 -306.139762) (xy 300.983124 -306.16086) (xy 300.935853 -306.174552)
			(xy 300.886998 -306.180484) (xy 300.837823 -306.178503) (xy 300.789604 -306.168659) (xy 300.743588 -306.151207)
			(xy 300.700967 -306.1266) (xy 300.662846 -306.095475) (xy 300.630211 -306.058638) (xy 300.603908 -306.017042)
			(xy 300.584617 -305.971766) (xy 300.57284 -305.923982) (xy 300.56888 -305.874928) (xy 300.230032 -305.874928)
			(xy 300.229537 -305.899535) (xy 300.221642 -305.948112) (xy 300.206058 -305.994793) (xy 300.183187 -306.03837)
			(xy 300.153622 -306.077714) (xy 300.118129 -306.111806) (xy 300.077626 -306.139762) (xy 300.033164 -306.16086)
			(xy 299.985893 -306.174552) (xy 299.937038 -306.180484) (xy 299.887863 -306.178503) (xy 299.839644 -306.168659)
			(xy 299.793628 -306.151207) (xy 299.751007 -306.1266) (xy 299.712886 -306.095475) (xy 299.680251 -306.058638)
			(xy 299.653948 -306.017042) (xy 299.634657 -305.971766) (xy 299.62288 -305.923982) (xy 299.61892 -305.874928)
			(xy 299.280072 -305.874928) (xy 299.279577 -305.899535) (xy 299.271682 -305.948112) (xy 299.256098 -305.994793)
			(xy 299.233227 -306.03837) (xy 299.203662 -306.077714) (xy 299.168169 -306.111806) (xy 299.127666 -306.139762)
			(xy 299.083204 -306.16086) (xy 299.035933 -306.174552) (xy 298.987078 -306.180484) (xy 298.937903 -306.178503)
			(xy 298.889684 -306.168659) (xy 298.843668 -306.151207) (xy 298.801047 -306.1266) (xy 298.762926 -306.095475)
			(xy 298.730291 -306.058638) (xy 298.703988 -306.017042) (xy 298.684697 -305.971766) (xy 298.67292 -305.923982)
			(xy 298.66896 -305.874928) (xy 298.330112 -305.874928) (xy 298.329617 -305.899535) (xy 298.321722 -305.948112)
			(xy 298.306138 -305.994793) (xy 298.283267 -306.03837) (xy 298.253702 -306.077714) (xy 298.218209 -306.111806)
			(xy 298.177706 -306.139762) (xy 298.133244 -306.16086) (xy 298.085973 -306.174552) (xy 298.037118 -306.180484)
			(xy 297.987943 -306.178503) (xy 297.939724 -306.168659) (xy 297.893708 -306.151207) (xy 297.851087 -306.1266)
			(xy 297.812966 -306.095475) (xy 297.780331 -306.058638) (xy 297.754028 -306.017042) (xy 297.734737 -305.971766)
			(xy 297.72296 -305.923982) (xy 297.719 -305.874928) (xy 297.380152 -305.874928) (xy 297.379657 -305.899535)
			(xy 297.371762 -305.948112) (xy 297.356178 -305.994793) (xy 297.333307 -306.03837) (xy 297.303742 -306.077714)
			(xy 297.268249 -306.111806) (xy 297.227746 -306.139762) (xy 297.183284 -306.16086) (xy 297.136013 -306.174552)
			(xy 297.087158 -306.180484) (xy 297.037983 -306.178503) (xy 296.989764 -306.168659) (xy 296.943748 -306.151207)
			(xy 296.901127 -306.1266) (xy 296.863006 -306.095475) (xy 296.830371 -306.058638) (xy 296.804068 -306.017042)
			(xy 296.784777 -305.971766) (xy 296.773 -305.923982) (xy 296.76904 -305.874928) (xy 296.430192 -305.874928)
			(xy 296.429697 -305.899535) (xy 296.421802 -305.948112) (xy 296.406218 -305.994793) (xy 296.383347 -306.03837)
			(xy 296.353782 -306.077714) (xy 296.318289 -306.111806) (xy 296.277786 -306.139762) (xy 296.233324 -306.16086)
			(xy 296.186053 -306.174552) (xy 296.137198 -306.180484) (xy 296.088023 -306.178503) (xy 296.039804 -306.168659)
			(xy 295.993788 -306.151207) (xy 295.951167 -306.1266) (xy 295.913046 -306.095475) (xy 295.880411 -306.058638)
			(xy 295.854108 -306.017042) (xy 295.834817 -305.971766) (xy 295.82304 -305.923982) (xy 295.81908 -305.874928)
			(xy 295.480232 -305.874928) (xy 295.479737 -305.899535) (xy 295.471842 -305.948112) (xy 295.456258 -305.994793)
			(xy 295.433387 -306.03837) (xy 295.403822 -306.077714) (xy 295.368329 -306.111806) (xy 295.327826 -306.139762)
			(xy 295.283364 -306.16086) (xy 295.236093 -306.174552) (xy 295.187238 -306.180484) (xy 295.138063 -306.178503)
			(xy 295.089844 -306.168659) (xy 295.043828 -306.151207) (xy 295.001207 -306.1266) (xy 294.963086 -306.095475)
			(xy 294.930451 -306.058638) (xy 294.904148 -306.017042) (xy 294.884857 -305.971766) (xy 294.87308 -305.923982)
			(xy 294.86912 -305.874928) (xy 294.530018 -305.874928) (xy 294.529523 -305.899535) (xy 294.521628 -305.948112)
			(xy 294.506044 -305.994793) (xy 294.483173 -306.03837) (xy 294.453608 -306.077714) (xy 294.418115 -306.111806)
			(xy 294.377612 -306.139762) (xy 294.33315 -306.16086) (xy 294.285879 -306.174552) (xy 294.237024 -306.180484)
			(xy 294.187849 -306.178503) (xy 294.13963 -306.168659) (xy 294.093614 -306.151207) (xy 294.050993 -306.1266)
			(xy 294.012872 -306.095475) (xy 293.980237 -306.058638) (xy 293.953934 -306.017042) (xy 293.934643 -305.971766)
			(xy 293.922866 -305.923982) (xy 293.918906 -305.874928) (xy 293.580058 -305.874928) (xy 293.579563 -305.899535)
			(xy 293.571668 -305.948112) (xy 293.556084 -305.994793) (xy 293.533213 -306.03837) (xy 293.503648 -306.077714)
			(xy 293.468155 -306.111806) (xy 293.427652 -306.139762) (xy 293.38319 -306.16086) (xy 293.335919 -306.174552)
			(xy 293.287064 -306.180484) (xy 293.237889 -306.178503) (xy 293.18967 -306.168659) (xy 293.143654 -306.151207)
			(xy 293.101033 -306.1266) (xy 293.062912 -306.095475) (xy 293.030277 -306.058638) (xy 293.003974 -306.017042)
			(xy 292.984683 -305.971766) (xy 292.972906 -305.923982) (xy 292.968946 -305.874928) (xy 292.630098 -305.874928)
			(xy 292.629603 -305.899535) (xy 292.621708 -305.948112) (xy 292.606124 -305.994793) (xy 292.583253 -306.03837)
			(xy 292.553688 -306.077714) (xy 292.518195 -306.111806) (xy 292.477692 -306.139762) (xy 292.43323 -306.16086)
			(xy 292.385959 -306.174552) (xy 292.337104 -306.180484) (xy 292.287929 -306.178503) (xy 292.23971 -306.168659)
			(xy 292.193694 -306.151207) (xy 292.151073 -306.1266) (xy 292.112952 -306.095475) (xy 292.080317 -306.058638)
			(xy 292.054014 -306.017042) (xy 292.034723 -305.971766) (xy 292.022946 -305.923982) (xy 292.018986 -305.874928)
			(xy 290.730178 -305.874928) (xy 290.729683 -305.899535) (xy 290.721788 -305.948112) (xy 290.706204 -305.994793)
			(xy 290.683333 -306.03837) (xy 290.653768 -306.077714) (xy 290.618275 -306.111806) (xy 290.577772 -306.139762)
			(xy 290.53331 -306.16086) (xy 290.486039 -306.174552) (xy 290.437184 -306.180484) (xy 290.388009 -306.178503)
			(xy 290.33979 -306.168659) (xy 290.293774 -306.151207) (xy 290.251153 -306.1266) (xy 290.213032 -306.095475)
			(xy 290.180397 -306.058638) (xy 290.154094 -306.017042) (xy 290.134803 -305.971766) (xy 290.123026 -305.923982)
			(xy 290.119066 -305.874928) (xy 289.780218 -305.874928) (xy 289.779723 -305.899535) (xy 289.771828 -305.948112)
			(xy 289.756244 -305.994793) (xy 289.733373 -306.03837) (xy 289.703808 -306.077714) (xy 289.668315 -306.111806)
			(xy 289.627812 -306.139762) (xy 289.58335 -306.16086) (xy 289.536079 -306.174552) (xy 289.487224 -306.180484)
			(xy 289.438049 -306.178503) (xy 289.38983 -306.168659) (xy 289.343814 -306.151207) (xy 289.301193 -306.1266)
			(xy 289.263072 -306.095475) (xy 289.230437 -306.058638) (xy 289.204134 -306.017042) (xy 289.184843 -305.971766)
			(xy 289.173066 -305.923982) (xy 289.169106 -305.874928) (xy 288.830004 -305.874928) (xy 288.829509 -305.899535)
			(xy 288.821614 -305.948112) (xy 288.80603 -305.994793) (xy 288.783159 -306.03837) (xy 288.753594 -306.077714)
			(xy 288.718101 -306.111806) (xy 288.677598 -306.139762) (xy 288.633136 -306.16086) (xy 288.585865 -306.174552)
			(xy 288.53701 -306.180484) (xy 288.487835 -306.178503) (xy 288.439616 -306.168659) (xy 288.3936 -306.151207)
			(xy 288.350979 -306.1266) (xy 288.312858 -306.095475) (xy 288.280223 -306.058638) (xy 288.25392 -306.017042)
			(xy 288.234629 -305.971766) (xy 288.222852 -305.923982) (xy 288.218892 -305.874928) (xy 287.880044 -305.874928)
			(xy 287.879549 -305.899535) (xy 287.871654 -305.948112) (xy 287.85607 -305.994793) (xy 287.833199 -306.03837)
			(xy 287.803634 -306.077714) (xy 287.768141 -306.111806) (xy 287.727638 -306.139762) (xy 287.683176 -306.16086)
			(xy 287.635905 -306.174552) (xy 287.58705 -306.180484) (xy 287.537875 -306.178503) (xy 287.489656 -306.168659)
			(xy 287.44364 -306.151207) (xy 287.401019 -306.1266) (xy 287.362898 -306.095475) (xy 287.330263 -306.058638)
			(xy 287.30396 -306.017042) (xy 287.284669 -305.971766) (xy 287.272892 -305.923982) (xy 287.268932 -305.874928)
			(xy 286.930084 -305.874928) (xy 286.929589 -305.899535) (xy 286.921694 -305.948112) (xy 286.90611 -305.994793)
			(xy 286.883239 -306.03837) (xy 286.853674 -306.077714) (xy 286.818181 -306.111806) (xy 286.777678 -306.139762)
			(xy 286.733216 -306.16086) (xy 286.685945 -306.174552) (xy 286.63709 -306.180484) (xy 286.587915 -306.178503)
			(xy 286.539696 -306.168659) (xy 286.49368 -306.151207) (xy 286.451059 -306.1266) (xy 286.412938 -306.095475)
			(xy 286.380303 -306.058638) (xy 286.354 -306.017042) (xy 286.334709 -305.971766) (xy 286.322932 -305.923982)
			(xy 286.318972 -305.874928) (xy 285.980124 -305.874928) (xy 285.979629 -305.899535) (xy 285.971734 -305.948112)
			(xy 285.95615 -305.994793) (xy 285.933279 -306.03837) (xy 285.903714 -306.077714) (xy 285.868221 -306.111806)
			(xy 285.827718 -306.139762) (xy 285.783256 -306.16086) (xy 285.735985 -306.174552) (xy 285.68713 -306.180484)
			(xy 285.637955 -306.178503) (xy 285.589736 -306.168659) (xy 285.54372 -306.151207) (xy 285.501099 -306.1266)
			(xy 285.462978 -306.095475) (xy 285.430343 -306.058638) (xy 285.40404 -306.017042) (xy 285.384749 -305.971766)
			(xy 285.372972 -305.923982) (xy 285.369012 -305.874928) (xy 285.030164 -305.874928) (xy 285.029669 -305.899535)
			(xy 285.021774 -305.948112) (xy 285.00619 -305.994793) (xy 284.983319 -306.03837) (xy 284.953754 -306.077714)
			(xy 284.918261 -306.111806) (xy 284.877758 -306.139762) (xy 284.833296 -306.16086) (xy 284.786025 -306.174552)
			(xy 284.73717 -306.180484) (xy 284.687995 -306.178503) (xy 284.639776 -306.168659) (xy 284.59376 -306.151207)
			(xy 284.551139 -306.1266) (xy 284.513018 -306.095475) (xy 284.480383 -306.058638) (xy 284.45408 -306.017042)
			(xy 284.434789 -305.971766) (xy 284.423012 -305.923982) (xy 284.419052 -305.874928) (xy 284.080204 -305.874928)
			(xy 284.079709 -305.899535) (xy 284.071814 -305.948112) (xy 284.05623 -305.994793) (xy 284.033359 -306.03837)
			(xy 284.003794 -306.077714) (xy 283.968301 -306.111806) (xy 283.927798 -306.139762) (xy 283.883336 -306.16086)
			(xy 283.836065 -306.174552) (xy 283.78721 -306.180484) (xy 283.738035 -306.178503) (xy 283.689816 -306.168659)
			(xy 283.6438 -306.151207) (xy 283.601179 -306.1266) (xy 283.563058 -306.095475) (xy 283.530423 -306.058638)
			(xy 283.50412 -306.017042) (xy 283.484829 -305.971766) (xy 283.473052 -305.923982) (xy 283.469092 -305.874928)
			(xy 283.130244 -305.874928) (xy 283.129749 -305.899535) (xy 283.121854 -305.948112) (xy 283.10627 -305.994793)
			(xy 283.083399 -306.03837) (xy 283.053834 -306.077714) (xy 283.018341 -306.111806) (xy 282.977838 -306.139762)
			(xy 282.933376 -306.16086) (xy 282.886105 -306.174552) (xy 282.83725 -306.180484) (xy 282.788075 -306.178503)
			(xy 282.739856 -306.168659) (xy 282.69384 -306.151207) (xy 282.651219 -306.1266) (xy 282.613098 -306.095475)
			(xy 282.580463 -306.058638) (xy 282.55416 -306.017042) (xy 282.534869 -305.971766) (xy 282.523092 -305.923982)
			(xy 282.519132 -305.874928) (xy 282.18003 -305.874928) (xy 282.179535 -305.899535) (xy 282.17164 -305.948112)
			(xy 282.156056 -305.994793) (xy 282.133185 -306.03837) (xy 282.10362 -306.077714) (xy 282.068127 -306.111806)
			(xy 282.027624 -306.139762) (xy 281.983162 -306.16086) (xy 281.935891 -306.174552) (xy 281.887036 -306.180484)
			(xy 281.837861 -306.178503) (xy 281.789642 -306.168659) (xy 281.743626 -306.151207) (xy 281.701005 -306.1266)
			(xy 281.662884 -306.095475) (xy 281.630249 -306.058638) (xy 281.603946 -306.017042) (xy 281.584655 -305.971766)
			(xy 281.572878 -305.923982) (xy 281.568918 -305.874928) (xy 281.23007 -305.874928) (xy 281.229575 -305.899535)
			(xy 281.22168 -305.948112) (xy 281.206096 -305.994793) (xy 281.183225 -306.03837) (xy 281.15366 -306.077714)
			(xy 281.118167 -306.111806) (xy 281.077664 -306.139762) (xy 281.033202 -306.16086) (xy 280.985931 -306.174552)
			(xy 280.937076 -306.180484) (xy 280.887901 -306.178503) (xy 280.839682 -306.168659) (xy 280.793666 -306.151207)
			(xy 280.751045 -306.1266) (xy 280.712924 -306.095475) (xy 280.680289 -306.058638) (xy 280.653986 -306.017042)
			(xy 280.634695 -305.971766) (xy 280.622918 -305.923982) (xy 280.618958 -305.874928) (xy 280.28011 -305.874928)
			(xy 280.279615 -305.899535) (xy 280.27172 -305.948112) (xy 280.256136 -305.994793) (xy 280.233265 -306.03837)
			(xy 280.2037 -306.077714) (xy 280.168207 -306.111806) (xy 280.127704 -306.139762) (xy 280.083242 -306.16086)
			(xy 280.035971 -306.174552) (xy 279.987116 -306.180484) (xy 279.937941 -306.178503) (xy 279.889722 -306.168659)
			(xy 279.843706 -306.151207) (xy 279.801085 -306.1266) (xy 279.762964 -306.095475) (xy 279.730329 -306.058638)
			(xy 279.704026 -306.017042) (xy 279.684735 -305.971766) (xy 279.672958 -305.923982) (xy 279.668998 -305.874928)
			(xy 279.33015 -305.874928) (xy 279.329655 -305.899535) (xy 279.32176 -305.948112) (xy 279.306176 -305.994793)
			(xy 279.283305 -306.03837) (xy 279.25374 -306.077714) (xy 279.218247 -306.111806) (xy 279.177744 -306.139762)
			(xy 279.133282 -306.16086) (xy 279.086011 -306.174552) (xy 279.037156 -306.180484) (xy 278.987981 -306.178503)
			(xy 278.939762 -306.168659) (xy 278.893746 -306.151207) (xy 278.851125 -306.1266) (xy 278.813004 -306.095475)
			(xy 278.780369 -306.058638) (xy 278.754066 -306.017042) (xy 278.734775 -305.971766) (xy 278.722998 -305.923982)
			(xy 278.719038 -305.874928) (xy 259.972646 -305.874928) (xy 259.964829 -305.883949) (xy 259.923633 -305.919643)
			(xy 259.877775 -305.949111) (xy 259.828191 -305.971753) (xy 259.775889 -305.987108) (xy 259.721935 -305.994863)
			(xy 259.69468 -305.995324) (xy 259.66547 -305.994308) (xy 259.65168 -305.993757) (xy 259.62463 -305.999167)
			(xy 259.600013 -306.011618) (xy 259.579627 -306.030203) (xy 259.564957 -306.053565) (xy 259.557075 -306.080001)
			(xy 259.556555 -306.107583) (xy 259.559552 -306.121054) (xy 259.565263 -306.144645) (xy 259.571379 -306.192797)
			(xy 259.571744 -306.217066) (xy 259.571281 -306.244322) (xy 259.563528 -306.298281) (xy 259.548299 -306.350162)
			(xy 267.793736 -306.350162) (xy 267.797696 -306.301108) (xy 267.809473 -306.253324) (xy 267.828764 -306.208048)
			(xy 267.855067 -306.166452) (xy 267.887702 -306.129615) (xy 267.925823 -306.09849) (xy 267.968444 -306.073883)
			(xy 268.01446 -306.056431) (xy 268.062679 -306.046587) (xy 268.111854 -306.044606) (xy 268.160709 -306.050538)
			(xy 268.20798 -306.06423) (xy 268.252442 -306.085328) (xy 268.292945 -306.113284) (xy 268.328438 -306.147376)
			(xy 268.358003 -306.18672) (xy 268.380874 -306.230297) (xy 268.396458 -306.276978) (xy 268.404353 -306.325555)
			(xy 268.404848 -306.350162) (xy 268.404353 -306.374769) (xy 268.404215 -306.375616) (xy 268.723106 -306.375616)
			(xy 268.723106 -306.3242) (xy 268.731149 -306.273418) (xy 268.747037 -306.224519) (xy 268.77038 -306.178707)
			(xy 268.800601 -306.137111) (xy 268.836957 -306.100755) (xy 268.878553 -306.070534) (xy 268.924365 -306.047191)
			(xy 268.973264 -306.031303) (xy 269.024046 -306.02326) (xy 269.075462 -306.02326) (xy 269.126244 -306.031303)
			(xy 269.175143 -306.047191) (xy 269.220955 -306.070534) (xy 269.262551 -306.100755) (xy 269.298907 -306.137111)
			(xy 269.329128 -306.178707) (xy 269.352471 -306.224519) (xy 269.368359 -306.273418) (xy 269.376402 -306.3242)
			(xy 269.376906 -306.349908) (xy 269.376402 -306.375616) (xy 269.673066 -306.375616) (xy 269.673066 -306.3242)
			(xy 269.681109 -306.273418) (xy 269.696997 -306.224519) (xy 269.72034 -306.178707) (xy 269.750561 -306.137111)
			(xy 269.786917 -306.100755) (xy 269.828513 -306.070534) (xy 269.874325 -306.047191) (xy 269.923224 -306.031303)
			(xy 269.974006 -306.02326) (xy 270.025422 -306.02326) (xy 270.076204 -306.031303) (xy 270.125103 -306.047191)
			(xy 270.170915 -306.070534) (xy 270.212511 -306.100755) (xy 270.248867 -306.137111) (xy 270.279088 -306.178707)
			(xy 270.302431 -306.224519) (xy 270.318319 -306.273418) (xy 270.326362 -306.3242) (xy 270.326866 -306.349908)
			(xy 270.644124 -306.349908) (xy 270.648084 -306.300854) (xy 270.659861 -306.25307) (xy 270.679152 -306.207794)
			(xy 270.705455 -306.166198) (xy 270.73809 -306.129361) (xy 270.776211 -306.098236) (xy 270.818832 -306.073629)
			(xy 270.864848 -306.056177) (xy 270.913067 -306.046333) (xy 270.962242 -306.044352) (xy 271.011097 -306.050284)
			(xy 271.058368 -306.063976) (xy 271.10283 -306.085074) (xy 271.143333 -306.11303) (xy 271.178826 -306.147122)
			(xy 271.208391 -306.186466) (xy 271.231262 -306.230043) (xy 271.246846 -306.276724) (xy 271.254741 -306.325301)
			(xy 271.255236 -306.349908) (xy 271.594084 -306.349908) (xy 271.598044 -306.300854) (xy 271.609821 -306.25307)
			(xy 271.629112 -306.207794) (xy 271.655415 -306.166198) (xy 271.68805 -306.129361) (xy 271.726171 -306.098236)
			(xy 271.768792 -306.073629) (xy 271.814808 -306.056177) (xy 271.863027 -306.046333) (xy 271.912202 -306.044352)
			(xy 271.961057 -306.050284) (xy 272.008328 -306.063976) (xy 272.05279 -306.085074) (xy 272.093293 -306.11303)
			(xy 272.128786 -306.147122) (xy 272.158351 -306.186466) (xy 272.181222 -306.230043) (xy 272.196806 -306.276724)
			(xy 272.204701 -306.325301) (xy 272.205196 -306.349908) (xy 272.544044 -306.349908) (xy 272.548004 -306.300854)
			(xy 272.559781 -306.25307) (xy 272.579072 -306.207794) (xy 272.605375 -306.166198) (xy 272.63801 -306.129361)
			(xy 272.676131 -306.098236) (xy 272.718752 -306.073629) (xy 272.764768 -306.056177) (xy 272.812987 -306.046333)
			(xy 272.862162 -306.044352) (xy 272.911017 -306.050284) (xy 272.958288 -306.063976) (xy 273.00275 -306.085074)
			(xy 273.043253 -306.11303) (xy 273.078746 -306.147122) (xy 273.108311 -306.186466) (xy 273.131182 -306.230043)
			(xy 273.146766 -306.276724) (xy 273.154661 -306.325301) (xy 273.155156 -306.349908) (xy 273.494004 -306.349908)
			(xy 273.497964 -306.300854) (xy 273.509741 -306.25307) (xy 273.529032 -306.207794) (xy 273.555335 -306.166198)
			(xy 273.58797 -306.129361) (xy 273.626091 -306.098236) (xy 273.668712 -306.073629) (xy 273.714728 -306.056177)
			(xy 273.762947 -306.046333) (xy 273.812122 -306.044352) (xy 273.860977 -306.050284) (xy 273.908248 -306.063976)
			(xy 273.95271 -306.085074) (xy 273.993213 -306.11303) (xy 274.028706 -306.147122) (xy 274.058271 -306.186466)
			(xy 274.081142 -306.230043) (xy 274.096726 -306.276724) (xy 274.104621 -306.325301) (xy 274.105116 -306.349908)
			(xy 274.443964 -306.349908) (xy 274.447924 -306.300854) (xy 274.459701 -306.25307) (xy 274.478992 -306.207794)
			(xy 274.505295 -306.166198) (xy 274.53793 -306.129361) (xy 274.576051 -306.098236) (xy 274.618672 -306.073629)
			(xy 274.664688 -306.056177) (xy 274.712907 -306.046333) (xy 274.762082 -306.044352) (xy 274.810937 -306.050284)
			(xy 274.858208 -306.063976) (xy 274.90267 -306.085074) (xy 274.943173 -306.11303) (xy 274.978666 -306.147122)
			(xy 275.008231 -306.186466) (xy 275.031102 -306.230043) (xy 275.046686 -306.276724) (xy 275.054581 -306.325301)
			(xy 275.055076 -306.349908) (xy 275.054581 -306.374515) (xy 275.054402 -306.375616) (xy 275.37308 -306.375616)
			(xy 275.37308 -306.3242) (xy 275.381123 -306.273418) (xy 275.397011 -306.224519) (xy 275.420354 -306.178707)
			(xy 275.450575 -306.137111) (xy 275.486931 -306.100755) (xy 275.528527 -306.070534) (xy 275.574339 -306.047191)
			(xy 275.623238 -306.031303) (xy 275.67402 -306.02326) (xy 275.725436 -306.02326) (xy 275.776218 -306.031303)
			(xy 275.825117 -306.047191) (xy 275.870929 -306.070534) (xy 275.912525 -306.100755) (xy 275.948881 -306.137111)
			(xy 275.979102 -306.178707) (xy 276.002445 -306.224519) (xy 276.018333 -306.273418) (xy 276.026376 -306.3242)
			(xy 276.02688 -306.349908) (xy 276.026376 -306.375616) (xy 276.32304 -306.375616) (xy 276.32304 -306.3242)
			(xy 276.331083 -306.273418) (xy 276.346971 -306.224519) (xy 276.370314 -306.178707) (xy 276.400535 -306.137111)
			(xy 276.436891 -306.100755) (xy 276.478487 -306.070534) (xy 276.524299 -306.047191) (xy 276.573198 -306.031303)
			(xy 276.62398 -306.02326) (xy 276.675396 -306.02326) (xy 276.726178 -306.031303) (xy 276.775077 -306.047191)
			(xy 276.820889 -306.070534) (xy 276.862485 -306.100755) (xy 276.898841 -306.137111) (xy 276.929062 -306.178707)
			(xy 276.952405 -306.224519) (xy 276.968293 -306.273418) (xy 276.976336 -306.3242) (xy 276.97684 -306.349908)
			(xy 277.294098 -306.349908) (xy 277.298058 -306.300854) (xy 277.309835 -306.25307) (xy 277.329126 -306.207794)
			(xy 277.355429 -306.166198) (xy 277.388064 -306.129361) (xy 277.426185 -306.098236) (xy 277.468806 -306.073629)
			(xy 277.514822 -306.056177) (xy 277.563041 -306.046333) (xy 277.612216 -306.044352) (xy 277.661071 -306.050284)
			(xy 277.708342 -306.063976) (xy 277.752804 -306.085074) (xy 277.793307 -306.11303) (xy 277.8288 -306.147122)
			(xy 277.858365 -306.186466) (xy 277.881236 -306.230043) (xy 277.89682 -306.276724) (xy 277.904715 -306.325301)
			(xy 277.90521 -306.349908) (xy 277.904715 -306.374515) (xy 277.89682 -306.423092) (xy 277.881236 -306.469773)
			(xy 277.858365 -306.51335) (xy 277.8288 -306.552694) (xy 277.793307 -306.586786) (xy 277.752804 -306.614742)
			(xy 277.708342 -306.63584) (xy 277.661071 -306.649532) (xy 277.612216 -306.655464) (xy 277.563041 -306.653483)
			(xy 277.514822 -306.643639) (xy 277.468806 -306.626187) (xy 277.426185 -306.60158) (xy 277.388064 -306.570455)
			(xy 277.355429 -306.533618) (xy 277.329126 -306.492022) (xy 277.309835 -306.446746) (xy 277.298058 -306.398962)
			(xy 277.294098 -306.349908) (xy 276.97684 -306.349908) (xy 276.976336 -306.375616) (xy 276.968293 -306.426398)
			(xy 276.952405 -306.475297) (xy 276.929062 -306.521109) (xy 276.898841 -306.562705) (xy 276.862485 -306.599061)
			(xy 276.820889 -306.629282) (xy 276.775077 -306.652625) (xy 276.726178 -306.668513) (xy 276.675396 -306.676556)
			(xy 276.62398 -306.676556) (xy 276.573198 -306.668513) (xy 276.524299 -306.652625) (xy 276.478487 -306.629282)
			(xy 276.436891 -306.599061) (xy 276.400535 -306.562705) (xy 276.370314 -306.521109) (xy 276.346971 -306.475297)
			(xy 276.331083 -306.426398) (xy 276.32304 -306.375616) (xy 276.026376 -306.375616) (xy 276.018333 -306.426398)
			(xy 276.002445 -306.475297) (xy 275.979102 -306.521109) (xy 275.948881 -306.562705) (xy 275.912525 -306.599061)
			(xy 275.870929 -306.629282) (xy 275.825117 -306.652625) (xy 275.776218 -306.668513) (xy 275.725436 -306.676556)
			(xy 275.67402 -306.676556) (xy 275.623238 -306.668513) (xy 275.574339 -306.652625) (xy 275.528527 -306.629282)
			(xy 275.486931 -306.599061) (xy 275.450575 -306.562705) (xy 275.420354 -306.521109) (xy 275.397011 -306.475297)
			(xy 275.381123 -306.426398) (xy 275.37308 -306.375616) (xy 275.054402 -306.375616) (xy 275.046686 -306.423092)
			(xy 275.031102 -306.469773) (xy 275.008231 -306.51335) (xy 274.978666 -306.552694) (xy 274.943173 -306.586786)
			(xy 274.90267 -306.614742) (xy 274.858208 -306.63584) (xy 274.810937 -306.649532) (xy 274.762082 -306.655464)
			(xy 274.712907 -306.653483) (xy 274.664688 -306.643639) (xy 274.618672 -306.626187) (xy 274.576051 -306.60158)
			(xy 274.53793 -306.570455) (xy 274.505295 -306.533618) (xy 274.478992 -306.492022) (xy 274.459701 -306.446746)
			(xy 274.447924 -306.398962) (xy 274.443964 -306.349908) (xy 274.105116 -306.349908) (xy 274.104621 -306.374515)
			(xy 274.096726 -306.423092) (xy 274.081142 -306.469773) (xy 274.058271 -306.51335) (xy 274.028706 -306.552694)
			(xy 273.993213 -306.586786) (xy 273.95271 -306.614742) (xy 273.908248 -306.63584) (xy 273.860977 -306.649532)
			(xy 273.812122 -306.655464) (xy 273.762947 -306.653483) (xy 273.714728 -306.643639) (xy 273.668712 -306.626187)
			(xy 273.626091 -306.60158) (xy 273.58797 -306.570455) (xy 273.555335 -306.533618) (xy 273.529032 -306.492022)
			(xy 273.509741 -306.446746) (xy 273.497964 -306.398962) (xy 273.494004 -306.349908) (xy 273.155156 -306.349908)
			(xy 273.154661 -306.374515) (xy 273.146766 -306.423092) (xy 273.131182 -306.469773) (xy 273.108311 -306.51335)
			(xy 273.078746 -306.552694) (xy 273.043253 -306.586786) (xy 273.00275 -306.614742) (xy 272.958288 -306.63584)
			(xy 272.911017 -306.649532) (xy 272.862162 -306.655464) (xy 272.812987 -306.653483) (xy 272.764768 -306.643639)
			(xy 272.718752 -306.626187) (xy 272.676131 -306.60158) (xy 272.63801 -306.570455) (xy 272.605375 -306.533618)
			(xy 272.579072 -306.492022) (xy 272.559781 -306.446746) (xy 272.548004 -306.398962) (xy 272.544044 -306.349908)
			(xy 272.205196 -306.349908) (xy 272.204701 -306.374515) (xy 272.196806 -306.423092) (xy 272.181222 -306.469773)
			(xy 272.158351 -306.51335) (xy 272.128786 -306.552694) (xy 272.093293 -306.586786) (xy 272.05279 -306.614742)
			(xy 272.008328 -306.63584) (xy 271.961057 -306.649532) (xy 271.912202 -306.655464) (xy 271.863027 -306.653483)
			(xy 271.814808 -306.643639) (xy 271.768792 -306.626187) (xy 271.726171 -306.60158) (xy 271.68805 -306.570455)
			(xy 271.655415 -306.533618) (xy 271.629112 -306.492022) (xy 271.609821 -306.446746) (xy 271.598044 -306.398962)
			(xy 271.594084 -306.349908) (xy 271.255236 -306.349908) (xy 271.254741 -306.374515) (xy 271.246846 -306.423092)
			(xy 271.231262 -306.469773) (xy 271.208391 -306.51335) (xy 271.178826 -306.552694) (xy 271.143333 -306.586786)
			(xy 271.10283 -306.614742) (xy 271.058368 -306.63584) (xy 271.011097 -306.649532) (xy 270.962242 -306.655464)
			(xy 270.913067 -306.653483) (xy 270.864848 -306.643639) (xy 270.818832 -306.626187) (xy 270.776211 -306.60158)
			(xy 270.73809 -306.570455) (xy 270.705455 -306.533618) (xy 270.679152 -306.492022) (xy 270.659861 -306.446746)
			(xy 270.648084 -306.398962) (xy 270.644124 -306.349908) (xy 270.326866 -306.349908) (xy 270.326362 -306.375616)
			(xy 270.318319 -306.426398) (xy 270.302431 -306.475297) (xy 270.279088 -306.521109) (xy 270.248867 -306.562705)
			(xy 270.212511 -306.599061) (xy 270.170915 -306.629282) (xy 270.125103 -306.652625) (xy 270.076204 -306.668513)
			(xy 270.025422 -306.676556) (xy 269.974006 -306.676556) (xy 269.923224 -306.668513) (xy 269.874325 -306.652625)
			(xy 269.828513 -306.629282) (xy 269.786917 -306.599061) (xy 269.750561 -306.562705) (xy 269.72034 -306.521109)
			(xy 269.696997 -306.475297) (xy 269.681109 -306.426398) (xy 269.673066 -306.375616) (xy 269.376402 -306.375616)
			(xy 269.368359 -306.426398) (xy 269.352471 -306.475297) (xy 269.329128 -306.521109) (xy 269.298907 -306.562705)
			(xy 269.262551 -306.599061) (xy 269.220955 -306.629282) (xy 269.175143 -306.652625) (xy 269.126244 -306.668513)
			(xy 269.075462 -306.676556) (xy 269.024046 -306.676556) (xy 268.973264 -306.668513) (xy 268.924365 -306.652625)
			(xy 268.878553 -306.629282) (xy 268.836957 -306.599061) (xy 268.800601 -306.562705) (xy 268.77038 -306.521109)
			(xy 268.747037 -306.475297) (xy 268.731149 -306.426398) (xy 268.723106 -306.375616) (xy 268.404215 -306.375616)
			(xy 268.396458 -306.423346) (xy 268.380874 -306.470027) (xy 268.358003 -306.513604) (xy 268.328438 -306.552948)
			(xy 268.292945 -306.58704) (xy 268.252442 -306.614996) (xy 268.20798 -306.636094) (xy 268.160709 -306.649786)
			(xy 268.111854 -306.655718) (xy 268.062679 -306.653737) (xy 268.01446 -306.643893) (xy 267.968444 -306.626441)
			(xy 267.925823 -306.601834) (xy 267.887702 -306.570709) (xy 267.855067 -306.533872) (xy 267.828764 -306.492276)
			(xy 267.809473 -306.447) (xy 267.797696 -306.399216) (xy 267.793736 -306.350162) (xy 259.548299 -306.350162)
			(xy 259.548174 -306.350587) (xy 259.525532 -306.400175) (xy 259.496063 -306.446036) (xy 259.460368 -306.487236)
			(xy 259.419172 -306.522937) (xy 259.373314 -306.552411) (xy 259.323729 -306.575058) (xy 259.271425 -306.590418)
			(xy 259.217467 -306.598178) (xy 259.162954 -306.59818) (xy 259.108996 -306.590423) (xy 259.056691 -306.575066)
			(xy 259.007105 -306.552421) (xy 258.961245 -306.522949) (xy 258.920047 -306.487251) (xy 258.884349 -306.446053)
			(xy 258.854878 -306.400194) (xy 258.832233 -306.350607) (xy 258.816877 -306.298302) (xy 258.80912 -306.244344)
			(xy 248.18604 -306.244344) (xy 248.760996 -306.8193) (xy 261.957056 -306.8193) (xy 261.961127 -306.763678)
			(xy 261.973253 -306.709241) (xy 261.993176 -306.65715) (xy 262.020472 -306.608515) (xy 262.054558 -306.564372)
			(xy 262.094707 -306.525663) (xy 262.140065 -306.493212) (xy 262.189665 -306.467711) (xy 262.242449 -306.449704)
			(xy 262.297292 -306.439574) (xy 262.353026 -306.437537) (xy 262.408463 -306.443637) (xy 262.46242 -306.457743)
			(xy 262.513749 -306.479555) (xy 262.561355 -306.508609) (xy 262.604223 -306.544284) (xy 262.64144 -306.585821)
			(xy 262.672213 -306.632334) (xy 262.695885 -306.682831) (xy 262.711953 -306.736238) (xy 262.720073 -306.791414)
			(xy 262.720582 -306.8193) (xy 262.72048 -306.824888) (xy 278.719038 -306.824888) (xy 278.722998 -306.775834)
			(xy 278.734775 -306.72805) (xy 278.754066 -306.682774) (xy 278.780369 -306.641178) (xy 278.813004 -306.604341)
			(xy 278.851125 -306.573216) (xy 278.893746 -306.548609) (xy 278.939762 -306.531157) (xy 278.987981 -306.521313)
			(xy 279.037156 -306.519332) (xy 279.086011 -306.525264) (xy 279.133282 -306.538956) (xy 279.177744 -306.560054)
			(xy 279.218247 -306.58801) (xy 279.25374 -306.622102) (xy 279.283305 -306.661446) (xy 279.306176 -306.705023)
			(xy 279.32176 -306.751704) (xy 279.329655 -306.800281) (xy 279.33015 -306.824888) (xy 279.668998 -306.824888)
			(xy 279.672958 -306.775834) (xy 279.684735 -306.72805) (xy 279.704026 -306.682774) (xy 279.730329 -306.641178)
			(xy 279.762964 -306.604341) (xy 279.801085 -306.573216) (xy 279.843706 -306.548609) (xy 279.889722 -306.531157)
			(xy 279.937941 -306.521313) (xy 279.987116 -306.519332) (xy 280.035971 -306.525264) (xy 280.083242 -306.538956)
			(xy 280.127704 -306.560054) (xy 280.168207 -306.58801) (xy 280.2037 -306.622102) (xy 280.233265 -306.661446)
			(xy 280.256136 -306.705023) (xy 280.27172 -306.751704) (xy 280.279615 -306.800281) (xy 280.28011 -306.824888)
			(xy 280.618958 -306.824888) (xy 280.622918 -306.775834) (xy 280.634695 -306.72805) (xy 280.653986 -306.682774)
			(xy 280.680289 -306.641178) (xy 280.712924 -306.604341) (xy 280.751045 -306.573216) (xy 280.793666 -306.548609)
			(xy 280.839682 -306.531157) (xy 280.887901 -306.521313) (xy 280.937076 -306.519332) (xy 280.985931 -306.525264)
			(xy 281.033202 -306.538956) (xy 281.077664 -306.560054) (xy 281.118167 -306.58801) (xy 281.15366 -306.622102)
			(xy 281.183225 -306.661446) (xy 281.206096 -306.705023) (xy 281.22168 -306.751704) (xy 281.229575 -306.800281)
			(xy 281.23007 -306.824888) (xy 281.568918 -306.824888) (xy 281.572878 -306.775834) (xy 281.584655 -306.72805)
			(xy 281.603946 -306.682774) (xy 281.630249 -306.641178) (xy 281.662884 -306.604341) (xy 281.701005 -306.573216)
			(xy 281.743626 -306.548609) (xy 281.789642 -306.531157) (xy 281.837861 -306.521313) (xy 281.887036 -306.519332)
			(xy 281.935891 -306.525264) (xy 281.983162 -306.538956) (xy 282.027624 -306.560054) (xy 282.068127 -306.58801)
			(xy 282.10362 -306.622102) (xy 282.133185 -306.661446) (xy 282.156056 -306.705023) (xy 282.17164 -306.751704)
			(xy 282.179535 -306.800281) (xy 282.18003 -306.824888) (xy 282.519132 -306.824888) (xy 282.523092 -306.775834)
			(xy 282.534869 -306.72805) (xy 282.55416 -306.682774) (xy 282.580463 -306.641178) (xy 282.613098 -306.604341)
			(xy 282.651219 -306.573216) (xy 282.69384 -306.548609) (xy 282.739856 -306.531157) (xy 282.788075 -306.521313)
			(xy 282.83725 -306.519332) (xy 282.886105 -306.525264) (xy 282.933376 -306.538956) (xy 282.977838 -306.560054)
			(xy 283.018341 -306.58801) (xy 283.053834 -306.622102) (xy 283.083399 -306.661446) (xy 283.10627 -306.705023)
			(xy 283.121854 -306.751704) (xy 283.129749 -306.800281) (xy 283.130244 -306.824888) (xy 283.469092 -306.824888)
			(xy 283.473052 -306.775834) (xy 283.484829 -306.72805) (xy 283.50412 -306.682774) (xy 283.530423 -306.641178)
			(xy 283.563058 -306.604341) (xy 283.601179 -306.573216) (xy 283.6438 -306.548609) (xy 283.689816 -306.531157)
			(xy 283.738035 -306.521313) (xy 283.78721 -306.519332) (xy 283.836065 -306.525264) (xy 283.883336 -306.538956)
			(xy 283.927798 -306.560054) (xy 283.968301 -306.58801) (xy 284.003794 -306.622102) (xy 284.033359 -306.661446)
			(xy 284.05623 -306.705023) (xy 284.071814 -306.751704) (xy 284.079709 -306.800281) (xy 284.080204 -306.824888)
			(xy 284.419052 -306.824888) (xy 284.423012 -306.775834) (xy 284.434789 -306.72805) (xy 284.45408 -306.682774)
			(xy 284.480383 -306.641178) (xy 284.513018 -306.604341) (xy 284.551139 -306.573216) (xy 284.59376 -306.548609)
			(xy 284.639776 -306.531157) (xy 284.687995 -306.521313) (xy 284.73717 -306.519332) (xy 284.786025 -306.525264)
			(xy 284.833296 -306.538956) (xy 284.877758 -306.560054) (xy 284.918261 -306.58801) (xy 284.953754 -306.622102)
			(xy 284.983319 -306.661446) (xy 285.00619 -306.705023) (xy 285.021774 -306.751704) (xy 285.029669 -306.800281)
			(xy 285.030164 -306.824888) (xy 285.369012 -306.824888) (xy 285.372972 -306.775834) (xy 285.384749 -306.72805)
			(xy 285.40404 -306.682774) (xy 285.430343 -306.641178) (xy 285.462978 -306.604341) (xy 285.501099 -306.573216)
			(xy 285.54372 -306.548609) (xy 285.589736 -306.531157) (xy 285.637955 -306.521313) (xy 285.68713 -306.519332)
			(xy 285.735985 -306.525264) (xy 285.783256 -306.538956) (xy 285.827718 -306.560054) (xy 285.868221 -306.58801)
			(xy 285.903714 -306.622102) (xy 285.933279 -306.661446) (xy 285.95615 -306.705023) (xy 285.971734 -306.751704)
			(xy 285.979629 -306.800281) (xy 285.980124 -306.824888) (xy 286.318972 -306.824888) (xy 286.322932 -306.775834)
			(xy 286.334709 -306.72805) (xy 286.354 -306.682774) (xy 286.380303 -306.641178) (xy 286.412938 -306.604341)
			(xy 286.451059 -306.573216) (xy 286.49368 -306.548609) (xy 286.539696 -306.531157) (xy 286.587915 -306.521313)
			(xy 286.63709 -306.519332) (xy 286.685945 -306.525264) (xy 286.733216 -306.538956) (xy 286.777678 -306.560054)
			(xy 286.818181 -306.58801) (xy 286.853674 -306.622102) (xy 286.883239 -306.661446) (xy 286.90611 -306.705023)
			(xy 286.921694 -306.751704) (xy 286.929589 -306.800281) (xy 286.930084 -306.824888) (xy 287.268932 -306.824888)
			(xy 287.272892 -306.775834) (xy 287.284669 -306.72805) (xy 287.30396 -306.682774) (xy 287.330263 -306.641178)
			(xy 287.362898 -306.604341) (xy 287.401019 -306.573216) (xy 287.44364 -306.548609) (xy 287.489656 -306.531157)
			(xy 287.537875 -306.521313) (xy 287.58705 -306.519332) (xy 287.635905 -306.525264) (xy 287.683176 -306.538956)
			(xy 287.727638 -306.560054) (xy 287.768141 -306.58801) (xy 287.803634 -306.622102) (xy 287.833199 -306.661446)
			(xy 287.85607 -306.705023) (xy 287.871654 -306.751704) (xy 287.879549 -306.800281) (xy 287.880044 -306.824888)
			(xy 288.218892 -306.824888) (xy 288.222852 -306.775834) (xy 288.234629 -306.72805) (xy 288.25392 -306.682774)
			(xy 288.280223 -306.641178) (xy 288.312858 -306.604341) (xy 288.350979 -306.573216) (xy 288.3936 -306.548609)
			(xy 288.439616 -306.531157) (xy 288.487835 -306.521313) (xy 288.53701 -306.519332) (xy 288.585865 -306.525264)
			(xy 288.633136 -306.538956) (xy 288.677598 -306.560054) (xy 288.718101 -306.58801) (xy 288.753594 -306.622102)
			(xy 288.783159 -306.661446) (xy 288.80603 -306.705023) (xy 288.821614 -306.751704) (xy 288.829509 -306.800281)
			(xy 288.830004 -306.824888) (xy 289.169106 -306.824888) (xy 289.173066 -306.775834) (xy 289.184843 -306.72805)
			(xy 289.204134 -306.682774) (xy 289.230437 -306.641178) (xy 289.263072 -306.604341) (xy 289.301193 -306.573216)
			(xy 289.343814 -306.548609) (xy 289.38983 -306.531157) (xy 289.438049 -306.521313) (xy 289.487224 -306.519332)
			(xy 289.536079 -306.525264) (xy 289.58335 -306.538956) (xy 289.627812 -306.560054) (xy 289.668315 -306.58801)
			(xy 289.703808 -306.622102) (xy 289.733373 -306.661446) (xy 289.756244 -306.705023) (xy 289.771828 -306.751704)
			(xy 289.779723 -306.800281) (xy 289.780218 -306.824888) (xy 290.119066 -306.824888) (xy 290.123026 -306.775834)
			(xy 290.134803 -306.72805) (xy 290.154094 -306.682774) (xy 290.180397 -306.641178) (xy 290.213032 -306.604341)
			(xy 290.251153 -306.573216) (xy 290.293774 -306.548609) (xy 290.33979 -306.531157) (xy 290.388009 -306.521313)
			(xy 290.437184 -306.519332) (xy 290.486039 -306.525264) (xy 290.53331 -306.538956) (xy 290.577772 -306.560054)
			(xy 290.618275 -306.58801) (xy 290.653768 -306.622102) (xy 290.683333 -306.661446) (xy 290.706204 -306.705023)
			(xy 290.721788 -306.751704) (xy 290.729683 -306.800281) (xy 290.730178 -306.824888) (xy 292.018986 -306.824888)
			(xy 292.022946 -306.775834) (xy 292.034723 -306.72805) (xy 292.054014 -306.682774) (xy 292.080317 -306.641178)
			(xy 292.112952 -306.604341) (xy 292.151073 -306.573216) (xy 292.193694 -306.548609) (xy 292.23971 -306.531157)
			(xy 292.287929 -306.521313) (xy 292.337104 -306.519332) (xy 292.385959 -306.525264) (xy 292.43323 -306.538956)
			(xy 292.477692 -306.560054) (xy 292.518195 -306.58801) (xy 292.553688 -306.622102) (xy 292.583253 -306.661446)
			(xy 292.606124 -306.705023) (xy 292.621708 -306.751704) (xy 292.629603 -306.800281) (xy 292.630098 -306.824888)
			(xy 292.968946 -306.824888) (xy 292.972906 -306.775834) (xy 292.984683 -306.72805) (xy 293.003974 -306.682774)
			(xy 293.030277 -306.641178) (xy 293.062912 -306.604341) (xy 293.101033 -306.573216) (xy 293.143654 -306.548609)
			(xy 293.18967 -306.531157) (xy 293.237889 -306.521313) (xy 293.287064 -306.519332) (xy 293.335919 -306.525264)
			(xy 293.38319 -306.538956) (xy 293.427652 -306.560054) (xy 293.468155 -306.58801) (xy 293.503648 -306.622102)
			(xy 293.533213 -306.661446) (xy 293.556084 -306.705023) (xy 293.571668 -306.751704) (xy 293.579563 -306.800281)
			(xy 293.580058 -306.824888) (xy 293.918906 -306.824888) (xy 293.922866 -306.775834) (xy 293.934643 -306.72805)
			(xy 293.953934 -306.682774) (xy 293.980237 -306.641178) (xy 294.012872 -306.604341) (xy 294.050993 -306.573216)
			(xy 294.093614 -306.548609) (xy 294.13963 -306.531157) (xy 294.187849 -306.521313) (xy 294.237024 -306.519332)
			(xy 294.285879 -306.525264) (xy 294.33315 -306.538956) (xy 294.377612 -306.560054) (xy 294.418115 -306.58801)
			(xy 294.453608 -306.622102) (xy 294.483173 -306.661446) (xy 294.506044 -306.705023) (xy 294.521628 -306.751704)
			(xy 294.529523 -306.800281) (xy 294.530018 -306.824888) (xy 294.86912 -306.824888) (xy 294.87308 -306.775834)
			(xy 294.884857 -306.72805) (xy 294.904148 -306.682774) (xy 294.930451 -306.641178) (xy 294.963086 -306.604341)
			(xy 295.001207 -306.573216) (xy 295.043828 -306.548609) (xy 295.089844 -306.531157) (xy 295.138063 -306.521313)
			(xy 295.187238 -306.519332) (xy 295.236093 -306.525264) (xy 295.283364 -306.538956) (xy 295.327826 -306.560054)
			(xy 295.368329 -306.58801) (xy 295.403822 -306.622102) (xy 295.433387 -306.661446) (xy 295.456258 -306.705023)
			(xy 295.471842 -306.751704) (xy 295.479737 -306.800281) (xy 295.480232 -306.824888) (xy 295.81908 -306.824888)
			(xy 295.82304 -306.775834) (xy 295.834817 -306.72805) (xy 295.854108 -306.682774) (xy 295.880411 -306.641178)
			(xy 295.913046 -306.604341) (xy 295.951167 -306.573216) (xy 295.993788 -306.548609) (xy 296.039804 -306.531157)
			(xy 296.088023 -306.521313) (xy 296.137198 -306.519332) (xy 296.186053 -306.525264) (xy 296.233324 -306.538956)
			(xy 296.277786 -306.560054) (xy 296.318289 -306.58801) (xy 296.353782 -306.622102) (xy 296.383347 -306.661446)
			(xy 296.406218 -306.705023) (xy 296.421802 -306.751704) (xy 296.429697 -306.800281) (xy 296.430192 -306.824888)
			(xy 296.76904 -306.824888) (xy 296.773 -306.775834) (xy 296.784777 -306.72805) (xy 296.804068 -306.682774)
			(xy 296.830371 -306.641178) (xy 296.863006 -306.604341) (xy 296.901127 -306.573216) (xy 296.943748 -306.548609)
			(xy 296.989764 -306.531157) (xy 297.037983 -306.521313) (xy 297.087158 -306.519332) (xy 297.136013 -306.525264)
			(xy 297.183284 -306.538956) (xy 297.227746 -306.560054) (xy 297.268249 -306.58801) (xy 297.303742 -306.622102)
			(xy 297.333307 -306.661446) (xy 297.356178 -306.705023) (xy 297.371762 -306.751704) (xy 297.379657 -306.800281)
			(xy 297.380152 -306.824888) (xy 297.719 -306.824888) (xy 297.72296 -306.775834) (xy 297.734737 -306.72805)
			(xy 297.754028 -306.682774) (xy 297.780331 -306.641178) (xy 297.812966 -306.604341) (xy 297.851087 -306.573216)
			(xy 297.893708 -306.548609) (xy 297.939724 -306.531157) (xy 297.987943 -306.521313) (xy 298.037118 -306.519332)
			(xy 298.085973 -306.525264) (xy 298.133244 -306.538956) (xy 298.177706 -306.560054) (xy 298.218209 -306.58801)
			(xy 298.253702 -306.622102) (xy 298.283267 -306.661446) (xy 298.306138 -306.705023) (xy 298.321722 -306.751704)
			(xy 298.329617 -306.800281) (xy 298.330112 -306.824888) (xy 298.66896 -306.824888) (xy 298.67292 -306.775834)
			(xy 298.684697 -306.72805) (xy 298.703988 -306.682774) (xy 298.730291 -306.641178) (xy 298.762926 -306.604341)
			(xy 298.801047 -306.573216) (xy 298.843668 -306.548609) (xy 298.889684 -306.531157) (xy 298.937903 -306.521313)
			(xy 298.987078 -306.519332) (xy 299.035933 -306.525264) (xy 299.083204 -306.538956) (xy 299.127666 -306.560054)
			(xy 299.168169 -306.58801) (xy 299.203662 -306.622102) (xy 299.233227 -306.661446) (xy 299.256098 -306.705023)
			(xy 299.271682 -306.751704) (xy 299.279577 -306.800281) (xy 299.280072 -306.824888) (xy 299.61892 -306.824888)
			(xy 299.62288 -306.775834) (xy 299.634657 -306.72805) (xy 299.653948 -306.682774) (xy 299.680251 -306.641178)
			(xy 299.712886 -306.604341) (xy 299.751007 -306.573216) (xy 299.793628 -306.548609) (xy 299.839644 -306.531157)
			(xy 299.887863 -306.521313) (xy 299.937038 -306.519332) (xy 299.985893 -306.525264) (xy 300.033164 -306.538956)
			(xy 300.077626 -306.560054) (xy 300.118129 -306.58801) (xy 300.153622 -306.622102) (xy 300.183187 -306.661446)
			(xy 300.206058 -306.705023) (xy 300.221642 -306.751704) (xy 300.229537 -306.800281) (xy 300.230032 -306.824888)
			(xy 300.56888 -306.824888) (xy 300.57284 -306.775834) (xy 300.584617 -306.72805) (xy 300.603908 -306.682774)
			(xy 300.630211 -306.641178) (xy 300.662846 -306.604341) (xy 300.700967 -306.573216) (xy 300.743588 -306.548609)
			(xy 300.789604 -306.531157) (xy 300.837823 -306.521313) (xy 300.886998 -306.519332) (xy 300.935853 -306.525264)
			(xy 300.983124 -306.538956) (xy 301.027586 -306.560054) (xy 301.068089 -306.58801) (xy 301.103582 -306.622102)
			(xy 301.133147 -306.661446) (xy 301.156018 -306.705023) (xy 301.171602 -306.751704) (xy 301.179497 -306.800281)
			(xy 301.179992 -306.824888) (xy 301.519094 -306.824888) (xy 301.523054 -306.775834) (xy 301.534831 -306.72805)
			(xy 301.554122 -306.682774) (xy 301.580425 -306.641178) (xy 301.61306 -306.604341) (xy 301.651181 -306.573216)
			(xy 301.693802 -306.548609) (xy 301.739818 -306.531157) (xy 301.788037 -306.521313) (xy 301.837212 -306.519332)
			(xy 301.886067 -306.525264) (xy 301.933338 -306.538956) (xy 301.9778 -306.560054) (xy 302.018303 -306.58801)
			(xy 302.053796 -306.622102) (xy 302.083361 -306.661446) (xy 302.106232 -306.705023) (xy 302.121816 -306.751704)
			(xy 302.129711 -306.800281) (xy 302.130206 -306.824888) (xy 302.469054 -306.824888) (xy 302.473014 -306.775834)
			(xy 302.484791 -306.72805) (xy 302.504082 -306.682774) (xy 302.530385 -306.641178) (xy 302.56302 -306.604341)
			(xy 302.601141 -306.573216) (xy 302.643762 -306.548609) (xy 302.689778 -306.531157) (xy 302.737997 -306.521313)
			(xy 302.787172 -306.519332) (xy 302.836027 -306.525264) (xy 302.883298 -306.538956) (xy 302.92776 -306.560054)
			(xy 302.968263 -306.58801) (xy 303.003756 -306.622102) (xy 303.033321 -306.661446) (xy 303.056192 -306.705023)
			(xy 303.071776 -306.751704) (xy 303.079671 -306.800281) (xy 303.080166 -306.824888) (xy 303.419014 -306.824888)
			(xy 303.422974 -306.775834) (xy 303.434751 -306.72805) (xy 303.454042 -306.682774) (xy 303.480345 -306.641178)
			(xy 303.51298 -306.604341) (xy 303.551101 -306.573216) (xy 303.593722 -306.548609) (xy 303.639738 -306.531157)
			(xy 303.687957 -306.521313) (xy 303.737132 -306.519332) (xy 303.785987 -306.525264) (xy 303.833258 -306.538956)
			(xy 303.87772 -306.560054) (xy 303.918223 -306.58801) (xy 303.953716 -306.622102) (xy 303.983281 -306.661446)
			(xy 304.006152 -306.705023) (xy 304.021736 -306.751704) (xy 304.029631 -306.800281) (xy 304.030126 -306.824888)
			(xy 304.029631 -306.849495) (xy 304.021736 -306.898072) (xy 304.006152 -306.944753) (xy 303.983281 -306.98833)
			(xy 303.953716 -307.027674) (xy 303.918223 -307.061766) (xy 303.87772 -307.089722) (xy 303.833258 -307.11082)
			(xy 303.785987 -307.124512) (xy 303.737132 -307.130444) (xy 303.687957 -307.128463) (xy 303.639738 -307.118619)
			(xy 303.593722 -307.101167) (xy 303.551101 -307.07656) (xy 303.51298 -307.045435) (xy 303.480345 -307.008598)
			(xy 303.454042 -306.967002) (xy 303.434751 -306.921726) (xy 303.422974 -306.873942) (xy 303.419014 -306.824888)
			(xy 303.080166 -306.824888) (xy 303.079671 -306.849495) (xy 303.071776 -306.898072) (xy 303.056192 -306.944753)
			(xy 303.033321 -306.98833) (xy 303.003756 -307.027674) (xy 302.968263 -307.061766) (xy 302.92776 -307.089722)
			(xy 302.883298 -307.11082) (xy 302.836027 -307.124512) (xy 302.787172 -307.130444) (xy 302.737997 -307.128463)
			(xy 302.689778 -307.118619) (xy 302.643762 -307.101167) (xy 302.601141 -307.07656) (xy 302.56302 -307.045435)
			(xy 302.530385 -307.008598) (xy 302.504082 -306.967002) (xy 302.484791 -306.921726) (xy 302.473014 -306.873942)
			(xy 302.469054 -306.824888) (xy 302.130206 -306.824888) (xy 302.129711 -306.849495) (xy 302.121816 -306.898072)
			(xy 302.106232 -306.944753) (xy 302.083361 -306.98833) (xy 302.053796 -307.027674) (xy 302.018303 -307.061766)
			(xy 301.9778 -307.089722) (xy 301.933338 -307.11082) (xy 301.886067 -307.124512) (xy 301.837212 -307.130444)
			(xy 301.788037 -307.128463) (xy 301.739818 -307.118619) (xy 301.693802 -307.101167) (xy 301.651181 -307.07656)
			(xy 301.61306 -307.045435) (xy 301.580425 -307.008598) (xy 301.554122 -306.967002) (xy 301.534831 -306.921726)
			(xy 301.523054 -306.873942) (xy 301.519094 -306.824888) (xy 301.179992 -306.824888) (xy 301.179497 -306.849495)
			(xy 301.171602 -306.898072) (xy 301.156018 -306.944753) (xy 301.133147 -306.98833) (xy 301.103582 -307.027674)
			(xy 301.068089 -307.061766) (xy 301.027586 -307.089722) (xy 300.983124 -307.11082) (xy 300.935853 -307.124512)
			(xy 300.886998 -307.130444) (xy 300.837823 -307.128463) (xy 300.789604 -307.118619) (xy 300.743588 -307.101167)
			(xy 300.700967 -307.07656) (xy 300.662846 -307.045435) (xy 300.630211 -307.008598) (xy 300.603908 -306.967002)
			(xy 300.584617 -306.921726) (xy 300.57284 -306.873942) (xy 300.56888 -306.824888) (xy 300.230032 -306.824888)
			(xy 300.229537 -306.849495) (xy 300.221642 -306.898072) (xy 300.206058 -306.944753) (xy 300.183187 -306.98833)
			(xy 300.153622 -307.027674) (xy 300.118129 -307.061766) (xy 300.077626 -307.089722) (xy 300.033164 -307.11082)
			(xy 299.985893 -307.124512) (xy 299.937038 -307.130444) (xy 299.887863 -307.128463) (xy 299.839644 -307.118619)
			(xy 299.793628 -307.101167) (xy 299.751007 -307.07656) (xy 299.712886 -307.045435) (xy 299.680251 -307.008598)
			(xy 299.653948 -306.967002) (xy 299.634657 -306.921726) (xy 299.62288 -306.873942) (xy 299.61892 -306.824888)
			(xy 299.280072 -306.824888) (xy 299.279577 -306.849495) (xy 299.271682 -306.898072) (xy 299.256098 -306.944753)
			(xy 299.233227 -306.98833) (xy 299.203662 -307.027674) (xy 299.168169 -307.061766) (xy 299.127666 -307.089722)
			(xy 299.083204 -307.11082) (xy 299.035933 -307.124512) (xy 298.987078 -307.130444) (xy 298.937903 -307.128463)
			(xy 298.889684 -307.118619) (xy 298.843668 -307.101167) (xy 298.801047 -307.07656) (xy 298.762926 -307.045435)
			(xy 298.730291 -307.008598) (xy 298.703988 -306.967002) (xy 298.684697 -306.921726) (xy 298.67292 -306.873942)
			(xy 298.66896 -306.824888) (xy 298.330112 -306.824888) (xy 298.329617 -306.849495) (xy 298.321722 -306.898072)
			(xy 298.306138 -306.944753) (xy 298.283267 -306.98833) (xy 298.253702 -307.027674) (xy 298.218209 -307.061766)
			(xy 298.177706 -307.089722) (xy 298.133244 -307.11082) (xy 298.085973 -307.124512) (xy 298.037118 -307.130444)
			(xy 297.987943 -307.128463) (xy 297.939724 -307.118619) (xy 297.893708 -307.101167) (xy 297.851087 -307.07656)
			(xy 297.812966 -307.045435) (xy 297.780331 -307.008598) (xy 297.754028 -306.967002) (xy 297.734737 -306.921726)
			(xy 297.72296 -306.873942) (xy 297.719 -306.824888) (xy 297.380152 -306.824888) (xy 297.379657 -306.849495)
			(xy 297.371762 -306.898072) (xy 297.356178 -306.944753) (xy 297.333307 -306.98833) (xy 297.303742 -307.027674)
			(xy 297.268249 -307.061766) (xy 297.227746 -307.089722) (xy 297.183284 -307.11082) (xy 297.136013 -307.124512)
			(xy 297.087158 -307.130444) (xy 297.037983 -307.128463) (xy 296.989764 -307.118619) (xy 296.943748 -307.101167)
			(xy 296.901127 -307.07656) (xy 296.863006 -307.045435) (xy 296.830371 -307.008598) (xy 296.804068 -306.967002)
			(xy 296.784777 -306.921726) (xy 296.773 -306.873942) (xy 296.76904 -306.824888) (xy 296.430192 -306.824888)
			(xy 296.429697 -306.849495) (xy 296.421802 -306.898072) (xy 296.406218 -306.944753) (xy 296.383347 -306.98833)
			(xy 296.353782 -307.027674) (xy 296.318289 -307.061766) (xy 296.277786 -307.089722) (xy 296.233324 -307.11082)
			(xy 296.186053 -307.124512) (xy 296.137198 -307.130444) (xy 296.088023 -307.128463) (xy 296.039804 -307.118619)
			(xy 295.993788 -307.101167) (xy 295.951167 -307.07656) (xy 295.913046 -307.045435) (xy 295.880411 -307.008598)
			(xy 295.854108 -306.967002) (xy 295.834817 -306.921726) (xy 295.82304 -306.873942) (xy 295.81908 -306.824888)
			(xy 295.480232 -306.824888) (xy 295.479737 -306.849495) (xy 295.471842 -306.898072) (xy 295.456258 -306.944753)
			(xy 295.433387 -306.98833) (xy 295.403822 -307.027674) (xy 295.368329 -307.061766) (xy 295.327826 -307.089722)
			(xy 295.283364 -307.11082) (xy 295.236093 -307.124512) (xy 295.187238 -307.130444) (xy 295.138063 -307.128463)
			(xy 295.089844 -307.118619) (xy 295.043828 -307.101167) (xy 295.001207 -307.07656) (xy 294.963086 -307.045435)
			(xy 294.930451 -307.008598) (xy 294.904148 -306.967002) (xy 294.884857 -306.921726) (xy 294.87308 -306.873942)
			(xy 294.86912 -306.824888) (xy 294.530018 -306.824888) (xy 294.529523 -306.849495) (xy 294.521628 -306.898072)
			(xy 294.506044 -306.944753) (xy 294.483173 -306.98833) (xy 294.453608 -307.027674) (xy 294.418115 -307.061766)
			(xy 294.377612 -307.089722) (xy 294.33315 -307.11082) (xy 294.285879 -307.124512) (xy 294.237024 -307.130444)
			(xy 294.187849 -307.128463) (xy 294.13963 -307.118619) (xy 294.093614 -307.101167) (xy 294.050993 -307.07656)
			(xy 294.012872 -307.045435) (xy 293.980237 -307.008598) (xy 293.953934 -306.967002) (xy 293.934643 -306.921726)
			(xy 293.922866 -306.873942) (xy 293.918906 -306.824888) (xy 293.580058 -306.824888) (xy 293.579563 -306.849495)
			(xy 293.571668 -306.898072) (xy 293.556084 -306.944753) (xy 293.533213 -306.98833) (xy 293.503648 -307.027674)
			(xy 293.468155 -307.061766) (xy 293.427652 -307.089722) (xy 293.38319 -307.11082) (xy 293.335919 -307.124512)
			(xy 293.287064 -307.130444) (xy 293.237889 -307.128463) (xy 293.18967 -307.118619) (xy 293.143654 -307.101167)
			(xy 293.101033 -307.07656) (xy 293.062912 -307.045435) (xy 293.030277 -307.008598) (xy 293.003974 -306.967002)
			(xy 292.984683 -306.921726) (xy 292.972906 -306.873942) (xy 292.968946 -306.824888) (xy 292.630098 -306.824888)
			(xy 292.629603 -306.849495) (xy 292.621708 -306.898072) (xy 292.606124 -306.944753) (xy 292.583253 -306.98833)
			(xy 292.553688 -307.027674) (xy 292.518195 -307.061766) (xy 292.477692 -307.089722) (xy 292.43323 -307.11082)
			(xy 292.385959 -307.124512) (xy 292.337104 -307.130444) (xy 292.287929 -307.128463) (xy 292.23971 -307.118619)
			(xy 292.193694 -307.101167) (xy 292.151073 -307.07656) (xy 292.112952 -307.045435) (xy 292.080317 -307.008598)
			(xy 292.054014 -306.967002) (xy 292.034723 -306.921726) (xy 292.022946 -306.873942) (xy 292.018986 -306.824888)
			(xy 290.730178 -306.824888) (xy 290.729683 -306.849495) (xy 290.721788 -306.898072) (xy 290.706204 -306.944753)
			(xy 290.683333 -306.98833) (xy 290.653768 -307.027674) (xy 290.618275 -307.061766) (xy 290.577772 -307.089722)
			(xy 290.53331 -307.11082) (xy 290.486039 -307.124512) (xy 290.437184 -307.130444) (xy 290.388009 -307.128463)
			(xy 290.33979 -307.118619) (xy 290.293774 -307.101167) (xy 290.251153 -307.07656) (xy 290.213032 -307.045435)
			(xy 290.180397 -307.008598) (xy 290.154094 -306.967002) (xy 290.134803 -306.921726) (xy 290.123026 -306.873942)
			(xy 290.119066 -306.824888) (xy 289.780218 -306.824888) (xy 289.779723 -306.849495) (xy 289.771828 -306.898072)
			(xy 289.756244 -306.944753) (xy 289.733373 -306.98833) (xy 289.703808 -307.027674) (xy 289.668315 -307.061766)
			(xy 289.627812 -307.089722) (xy 289.58335 -307.11082) (xy 289.536079 -307.124512) (xy 289.487224 -307.130444)
			(xy 289.438049 -307.128463) (xy 289.38983 -307.118619) (xy 289.343814 -307.101167) (xy 289.301193 -307.07656)
			(xy 289.263072 -307.045435) (xy 289.230437 -307.008598) (xy 289.204134 -306.967002) (xy 289.184843 -306.921726)
			(xy 289.173066 -306.873942) (xy 289.169106 -306.824888) (xy 288.830004 -306.824888) (xy 288.829509 -306.849495)
			(xy 288.821614 -306.898072) (xy 288.80603 -306.944753) (xy 288.783159 -306.98833) (xy 288.753594 -307.027674)
			(xy 288.718101 -307.061766) (xy 288.677598 -307.089722) (xy 288.633136 -307.11082) (xy 288.585865 -307.124512)
			(xy 288.53701 -307.130444) (xy 288.487835 -307.128463) (xy 288.439616 -307.118619) (xy 288.3936 -307.101167)
			(xy 288.350979 -307.07656) (xy 288.312858 -307.045435) (xy 288.280223 -307.008598) (xy 288.25392 -306.967002)
			(xy 288.234629 -306.921726) (xy 288.222852 -306.873942) (xy 288.218892 -306.824888) (xy 287.880044 -306.824888)
			(xy 287.879549 -306.849495) (xy 287.871654 -306.898072) (xy 287.85607 -306.944753) (xy 287.833199 -306.98833)
			(xy 287.803634 -307.027674) (xy 287.768141 -307.061766) (xy 287.727638 -307.089722) (xy 287.683176 -307.11082)
			(xy 287.635905 -307.124512) (xy 287.58705 -307.130444) (xy 287.537875 -307.128463) (xy 287.489656 -307.118619)
			(xy 287.44364 -307.101167) (xy 287.401019 -307.07656) (xy 287.362898 -307.045435) (xy 287.330263 -307.008598)
			(xy 287.30396 -306.967002) (xy 287.284669 -306.921726) (xy 287.272892 -306.873942) (xy 287.268932 -306.824888)
			(xy 286.930084 -306.824888) (xy 286.929589 -306.849495) (xy 286.921694 -306.898072) (xy 286.90611 -306.944753)
			(xy 286.883239 -306.98833) (xy 286.853674 -307.027674) (xy 286.818181 -307.061766) (xy 286.777678 -307.089722)
			(xy 286.733216 -307.11082) (xy 286.685945 -307.124512) (xy 286.63709 -307.130444) (xy 286.587915 -307.128463)
			(xy 286.539696 -307.118619) (xy 286.49368 -307.101167) (xy 286.451059 -307.07656) (xy 286.412938 -307.045435)
			(xy 286.380303 -307.008598) (xy 286.354 -306.967002) (xy 286.334709 -306.921726) (xy 286.322932 -306.873942)
			(xy 286.318972 -306.824888) (xy 285.980124 -306.824888) (xy 285.979629 -306.849495) (xy 285.971734 -306.898072)
			(xy 285.95615 -306.944753) (xy 285.933279 -306.98833) (xy 285.903714 -307.027674) (xy 285.868221 -307.061766)
			(xy 285.827718 -307.089722) (xy 285.783256 -307.11082) (xy 285.735985 -307.124512) (xy 285.68713 -307.130444)
			(xy 285.637955 -307.128463) (xy 285.589736 -307.118619) (xy 285.54372 -307.101167) (xy 285.501099 -307.07656)
			(xy 285.462978 -307.045435) (xy 285.430343 -307.008598) (xy 285.40404 -306.967002) (xy 285.384749 -306.921726)
			(xy 285.372972 -306.873942) (xy 285.369012 -306.824888) (xy 285.030164 -306.824888) (xy 285.029669 -306.849495)
			(xy 285.021774 -306.898072) (xy 285.00619 -306.944753) (xy 284.983319 -306.98833) (xy 284.953754 -307.027674)
			(xy 284.918261 -307.061766) (xy 284.877758 -307.089722) (xy 284.833296 -307.11082) (xy 284.786025 -307.124512)
			(xy 284.73717 -307.130444) (xy 284.687995 -307.128463) (xy 284.639776 -307.118619) (xy 284.59376 -307.101167)
			(xy 284.551139 -307.07656) (xy 284.513018 -307.045435) (xy 284.480383 -307.008598) (xy 284.45408 -306.967002)
			(xy 284.434789 -306.921726) (xy 284.423012 -306.873942) (xy 284.419052 -306.824888) (xy 284.080204 -306.824888)
			(xy 284.079709 -306.849495) (xy 284.071814 -306.898072) (xy 284.05623 -306.944753) (xy 284.033359 -306.98833)
			(xy 284.003794 -307.027674) (xy 283.968301 -307.061766) (xy 283.927798 -307.089722) (xy 283.883336 -307.11082)
			(xy 283.836065 -307.124512) (xy 283.78721 -307.130444) (xy 283.738035 -307.128463) (xy 283.689816 -307.118619)
			(xy 283.6438 -307.101167) (xy 283.601179 -307.07656) (xy 283.563058 -307.045435) (xy 283.530423 -307.008598)
			(xy 283.50412 -306.967002) (xy 283.484829 -306.921726) (xy 283.473052 -306.873942) (xy 283.469092 -306.824888)
			(xy 283.130244 -306.824888) (xy 283.129749 -306.849495) (xy 283.121854 -306.898072) (xy 283.10627 -306.944753)
			(xy 283.083399 -306.98833) (xy 283.053834 -307.027674) (xy 283.018341 -307.061766) (xy 282.977838 -307.089722)
			(xy 282.933376 -307.11082) (xy 282.886105 -307.124512) (xy 282.83725 -307.130444) (xy 282.788075 -307.128463)
			(xy 282.739856 -307.118619) (xy 282.69384 -307.101167) (xy 282.651219 -307.07656) (xy 282.613098 -307.045435)
			(xy 282.580463 -307.008598) (xy 282.55416 -306.967002) (xy 282.534869 -306.921726) (xy 282.523092 -306.873942)
			(xy 282.519132 -306.824888) (xy 282.18003 -306.824888) (xy 282.179535 -306.849495) (xy 282.17164 -306.898072)
			(xy 282.156056 -306.944753) (xy 282.133185 -306.98833) (xy 282.10362 -307.027674) (xy 282.068127 -307.061766)
			(xy 282.027624 -307.089722) (xy 281.983162 -307.11082) (xy 281.935891 -307.124512) (xy 281.887036 -307.130444)
			(xy 281.837861 -307.128463) (xy 281.789642 -307.118619) (xy 281.743626 -307.101167) (xy 281.701005 -307.07656)
			(xy 281.662884 -307.045435) (xy 281.630249 -307.008598) (xy 281.603946 -306.967002) (xy 281.584655 -306.921726)
			(xy 281.572878 -306.873942) (xy 281.568918 -306.824888) (xy 281.23007 -306.824888) (xy 281.229575 -306.849495)
			(xy 281.22168 -306.898072) (xy 281.206096 -306.944753) (xy 281.183225 -306.98833) (xy 281.15366 -307.027674)
			(xy 281.118167 -307.061766) (xy 281.077664 -307.089722) (xy 281.033202 -307.11082) (xy 280.985931 -307.124512)
			(xy 280.937076 -307.130444) (xy 280.887901 -307.128463) (xy 280.839682 -307.118619) (xy 280.793666 -307.101167)
			(xy 280.751045 -307.07656) (xy 280.712924 -307.045435) (xy 280.680289 -307.008598) (xy 280.653986 -306.967002)
			(xy 280.634695 -306.921726) (xy 280.622918 -306.873942) (xy 280.618958 -306.824888) (xy 280.28011 -306.824888)
			(xy 280.279615 -306.849495) (xy 280.27172 -306.898072) (xy 280.256136 -306.944753) (xy 280.233265 -306.98833)
			(xy 280.2037 -307.027674) (xy 280.168207 -307.061766) (xy 280.127704 -307.089722) (xy 280.083242 -307.11082)
			(xy 280.035971 -307.124512) (xy 279.987116 -307.130444) (xy 279.937941 -307.128463) (xy 279.889722 -307.118619)
			(xy 279.843706 -307.101167) (xy 279.801085 -307.07656) (xy 279.762964 -307.045435) (xy 279.730329 -307.008598)
			(xy 279.704026 -306.967002) (xy 279.684735 -306.921726) (xy 279.672958 -306.873942) (xy 279.668998 -306.824888)
			(xy 279.33015 -306.824888) (xy 279.329655 -306.849495) (xy 279.32176 -306.898072) (xy 279.306176 -306.944753)
			(xy 279.283305 -306.98833) (xy 279.25374 -307.027674) (xy 279.218247 -307.061766) (xy 279.177744 -307.089722)
			(xy 279.133282 -307.11082) (xy 279.086011 -307.124512) (xy 279.037156 -307.130444) (xy 278.987981 -307.128463)
			(xy 278.939762 -307.118619) (xy 278.893746 -307.101167) (xy 278.851125 -307.07656) (xy 278.813004 -307.045435)
			(xy 278.780369 -307.008598) (xy 278.754066 -306.967002) (xy 278.734775 -306.921726) (xy 278.722998 -306.873942)
			(xy 278.719038 -306.824888) (xy 262.72048 -306.824888) (xy 262.720073 -306.847186) (xy 262.711953 -306.902362)
			(xy 262.695885 -306.955769) (xy 262.672213 -307.006266) (xy 262.64144 -307.052779) (xy 262.604223 -307.094316)
			(xy 262.561355 -307.129991) (xy 262.513749 -307.159045) (xy 262.46242 -307.180857) (xy 262.408463 -307.194963)
			(xy 262.353026 -307.201063) (xy 262.297292 -307.199026) (xy 262.242449 -307.188896) (xy 262.189665 -307.170889)
			(xy 262.140065 -307.145388) (xy 262.094707 -307.112937) (xy 262.054558 -307.074228) (xy 262.020472 -307.030085)
			(xy 261.993176 -306.98145) (xy 261.973253 -306.929359) (xy 261.961127 -306.874922) (xy 261.957056 -306.8193)
			(xy 248.760996 -306.8193) (xy 248.799858 -306.858162) (xy 248.806699 -306.865562) (xy 248.814418 -306.884161)
			(xy 248.814844 -306.89423) (xy 248.814844 -307.170328) (xy 248.815325 -307.180664) (xy 248.823446 -307.199676)
			(xy 248.830592 -307.207158) (xy 248.8514 -307.227668) (xy 248.88716 -307.273869) (xy 248.915467 -307.324977)
			(xy 248.926096 -307.352192) (xy 248.937056 -307.384103) (xy 248.948814 -307.450537) (xy 248.949464 -307.484272)
			(xy 248.949301 -307.4924) (xy 263.930382 -307.4924) (xy 263.934453 -307.436778) (xy 263.946579 -307.382341)
			(xy 263.966502 -307.33025) (xy 263.993798 -307.281615) (xy 264.027884 -307.237472) (xy 264.068033 -307.198763)
			(xy 264.113391 -307.166312) (xy 264.162991 -307.140811) (xy 264.215775 -307.122804) (xy 264.270618 -307.112674)
			(xy 264.326352 -307.110637) (xy 264.381789 -307.116737) (xy 264.435746 -307.130843) (xy 264.487075 -307.152655)
			(xy 264.534681 -307.181709) (xy 264.577549 -307.217384) (xy 264.614766 -307.258921) (xy 264.641857 -307.299868)
			(xy 268.74395 -307.299868) (xy 268.74791 -307.250814) (xy 268.759687 -307.20303) (xy 268.778978 -307.157754)
			(xy 268.805281 -307.116158) (xy 268.837916 -307.079321) (xy 268.876037 -307.048196) (xy 268.918658 -307.023589)
			(xy 268.964674 -307.006137) (xy 269.012893 -306.996293) (xy 269.062068 -306.994312) (xy 269.110923 -307.000244)
			(xy 269.158194 -307.013936) (xy 269.202656 -307.035034) (xy 269.243159 -307.06299) (xy 269.278652 -307.097082)
			(xy 269.308217 -307.136426) (xy 269.331088 -307.180003) (xy 269.346672 -307.226684) (xy 269.354567 -307.275261)
			(xy 269.355062 -307.299868) (xy 269.69391 -307.299868) (xy 269.69787 -307.250814) (xy 269.709647 -307.20303)
			(xy 269.728938 -307.157754) (xy 269.755241 -307.116158) (xy 269.787876 -307.079321) (xy 269.825997 -307.048196)
			(xy 269.868618 -307.023589) (xy 269.914634 -307.006137) (xy 269.962853 -306.996293) (xy 270.012028 -306.994312)
			(xy 270.060883 -307.000244) (xy 270.108154 -307.013936) (xy 270.152616 -307.035034) (xy 270.193119 -307.06299)
			(xy 270.228612 -307.097082) (xy 270.258177 -307.136426) (xy 270.281048 -307.180003) (xy 270.296632 -307.226684)
			(xy 270.304527 -307.275261) (xy 270.305022 -307.299868) (xy 270.304527 -307.324475) (xy 270.304348 -307.325576)
			(xy 270.62328 -307.325576) (xy 270.62328 -307.27416) (xy 270.631323 -307.223378) (xy 270.647211 -307.174479)
			(xy 270.670554 -307.128667) (xy 270.700775 -307.087071) (xy 270.737131 -307.050715) (xy 270.778727 -307.020494)
			(xy 270.824539 -306.997151) (xy 270.873438 -306.981263) (xy 270.92422 -306.97322) (xy 270.975636 -306.97322)
			(xy 271.026418 -306.981263) (xy 271.075317 -306.997151) (xy 271.121129 -307.020494) (xy 271.162725 -307.050715)
			(xy 271.199081 -307.087071) (xy 271.229302 -307.128667) (xy 271.252645 -307.174479) (xy 271.268533 -307.223378)
			(xy 271.276576 -307.27416) (xy 271.27708 -307.299868) (xy 271.276576 -307.325576) (xy 271.57324 -307.325576)
			(xy 271.57324 -307.27416) (xy 271.581283 -307.223378) (xy 271.597171 -307.174479) (xy 271.620514 -307.128667)
			(xy 271.650735 -307.087071) (xy 271.687091 -307.050715) (xy 271.728687 -307.020494) (xy 271.774499 -306.997151)
			(xy 271.823398 -306.981263) (xy 271.87418 -306.97322) (xy 271.925596 -306.97322) (xy 271.976378 -306.981263)
			(xy 272.025277 -306.997151) (xy 272.071089 -307.020494) (xy 272.112685 -307.050715) (xy 272.149041 -307.087071)
			(xy 272.179262 -307.128667) (xy 272.202605 -307.174479) (xy 272.218493 -307.223378) (xy 272.226536 -307.27416)
			(xy 272.22704 -307.299868) (xy 272.544044 -307.299868) (xy 272.548004 -307.250814) (xy 272.559781 -307.20303)
			(xy 272.579072 -307.157754) (xy 272.605375 -307.116158) (xy 272.63801 -307.079321) (xy 272.676131 -307.048196)
			(xy 272.718752 -307.023589) (xy 272.764768 -307.006137) (xy 272.812987 -306.996293) (xy 272.862162 -306.994312)
			(xy 272.911017 -307.000244) (xy 272.958288 -307.013936) (xy 273.00275 -307.035034) (xy 273.043253 -307.06299)
			(xy 273.078746 -307.097082) (xy 273.108311 -307.136426) (xy 273.131182 -307.180003) (xy 273.146766 -307.226684)
			(xy 273.154661 -307.275261) (xy 273.155156 -307.299868) (xy 273.154661 -307.324475) (xy 273.154482 -307.325576)
			(xy 273.47316 -307.325576) (xy 273.47316 -307.27416) (xy 273.481203 -307.223378) (xy 273.497091 -307.174479)
			(xy 273.520434 -307.128667) (xy 273.550655 -307.087071) (xy 273.587011 -307.050715) (xy 273.628607 -307.020494)
			(xy 273.674419 -306.997151) (xy 273.723318 -306.981263) (xy 273.7741 -306.97322) (xy 273.825516 -306.97322)
			(xy 273.876298 -306.981263) (xy 273.925197 -306.997151) (xy 273.971009 -307.020494) (xy 274.012605 -307.050715)
			(xy 274.048961 -307.087071) (xy 274.079182 -307.128667) (xy 274.102525 -307.174479) (xy 274.118413 -307.223378)
			(xy 274.126456 -307.27416) (xy 274.12696 -307.299868) (xy 274.126456 -307.325576) (xy 274.42312 -307.325576)
			(xy 274.42312 -307.27416) (xy 274.431163 -307.223378) (xy 274.447051 -307.174479) (xy 274.470394 -307.128667)
			(xy 274.500615 -307.087071) (xy 274.536971 -307.050715) (xy 274.578567 -307.020494) (xy 274.624379 -306.997151)
			(xy 274.673278 -306.981263) (xy 274.72406 -306.97322) (xy 274.775476 -306.97322) (xy 274.826258 -306.981263)
			(xy 274.875157 -306.997151) (xy 274.920969 -307.020494) (xy 274.962565 -307.050715) (xy 274.998921 -307.087071)
			(xy 275.029142 -307.128667) (xy 275.052485 -307.174479) (xy 275.068373 -307.223378) (xy 275.076416 -307.27416)
			(xy 275.07692 -307.299868) (xy 275.393924 -307.299868) (xy 275.397884 -307.250814) (xy 275.409661 -307.20303)
			(xy 275.428952 -307.157754) (xy 275.455255 -307.116158) (xy 275.48789 -307.079321) (xy 275.526011 -307.048196)
			(xy 275.568632 -307.023589) (xy 275.614648 -307.006137) (xy 275.662867 -306.996293) (xy 275.712042 -306.994312)
			(xy 275.760897 -307.000244) (xy 275.808168 -307.013936) (xy 275.85263 -307.035034) (xy 275.893133 -307.06299)
			(xy 275.928626 -307.097082) (xy 275.958191 -307.136426) (xy 275.981062 -307.180003) (xy 275.996646 -307.226684)
			(xy 276.004541 -307.275261) (xy 276.005036 -307.299868) (xy 276.343884 -307.299868) (xy 276.347844 -307.250814)
			(xy 276.359621 -307.20303) (xy 276.378912 -307.157754) (xy 276.405215 -307.116158) (xy 276.43785 -307.079321)
			(xy 276.475971 -307.048196) (xy 276.518592 -307.023589) (xy 276.564608 -307.006137) (xy 276.612827 -306.996293)
			(xy 276.662002 -306.994312) (xy 276.710857 -307.000244) (xy 276.758128 -307.013936) (xy 276.80259 -307.035034)
			(xy 276.843093 -307.06299) (xy 276.878586 -307.097082) (xy 276.908151 -307.136426) (xy 276.931022 -307.180003)
			(xy 276.946606 -307.226684) (xy 276.954501 -307.275261) (xy 276.954996 -307.299868) (xy 277.294098 -307.299868)
			(xy 277.298058 -307.250814) (xy 277.309835 -307.20303) (xy 277.329126 -307.157754) (xy 277.355429 -307.116158)
			(xy 277.388064 -307.079321) (xy 277.426185 -307.048196) (xy 277.468806 -307.023589) (xy 277.514822 -307.006137)
			(xy 277.563041 -306.996293) (xy 277.612216 -306.994312) (xy 277.661071 -307.000244) (xy 277.708342 -307.013936)
			(xy 277.752804 -307.035034) (xy 277.793307 -307.06299) (xy 277.8288 -307.097082) (xy 277.858365 -307.136426)
			(xy 277.881236 -307.180003) (xy 277.89682 -307.226684) (xy 277.904715 -307.275261) (xy 277.90521 -307.299868)
			(xy 277.904715 -307.324475) (xy 277.89682 -307.373052) (xy 277.881236 -307.419733) (xy 277.858365 -307.46331)
			(xy 277.8288 -307.502654) (xy 277.793307 -307.536746) (xy 277.752804 -307.564702) (xy 277.708342 -307.5858)
			(xy 277.661071 -307.599492) (xy 277.612216 -307.605424) (xy 277.563041 -307.603443) (xy 277.514822 -307.593599)
			(xy 277.468806 -307.576147) (xy 277.426185 -307.55154) (xy 277.388064 -307.520415) (xy 277.355429 -307.483578)
			(xy 277.329126 -307.441982) (xy 277.309835 -307.396706) (xy 277.298058 -307.348922) (xy 277.294098 -307.299868)
			(xy 276.954996 -307.299868) (xy 276.954501 -307.324475) (xy 276.946606 -307.373052) (xy 276.931022 -307.419733)
			(xy 276.908151 -307.46331) (xy 276.878586 -307.502654) (xy 276.843093 -307.536746) (xy 276.80259 -307.564702)
			(xy 276.758128 -307.5858) (xy 276.710857 -307.599492) (xy 276.662002 -307.605424) (xy 276.612827 -307.603443)
			(xy 276.564608 -307.593599) (xy 276.518592 -307.576147) (xy 276.475971 -307.55154) (xy 276.43785 -307.520415)
			(xy 276.405215 -307.483578) (xy 276.378912 -307.441982) (xy 276.359621 -307.396706) (xy 276.347844 -307.348922)
			(xy 276.343884 -307.299868) (xy 276.005036 -307.299868) (xy 276.004541 -307.324475) (xy 275.996646 -307.373052)
			(xy 275.981062 -307.419733) (xy 275.958191 -307.46331) (xy 275.928626 -307.502654) (xy 275.893133 -307.536746)
			(xy 275.85263 -307.564702) (xy 275.808168 -307.5858) (xy 275.760897 -307.599492) (xy 275.712042 -307.605424)
			(xy 275.662867 -307.603443) (xy 275.614648 -307.593599) (xy 275.568632 -307.576147) (xy 275.526011 -307.55154)
			(xy 275.48789 -307.520415) (xy 275.455255 -307.483578) (xy 275.428952 -307.441982) (xy 275.409661 -307.396706)
			(xy 275.397884 -307.348922) (xy 275.393924 -307.299868) (xy 275.07692 -307.299868) (xy 275.076416 -307.325576)
			(xy 275.068373 -307.376358) (xy 275.052485 -307.425257) (xy 275.029142 -307.471069) (xy 274.998921 -307.512665)
			(xy 274.962565 -307.549021) (xy 274.920969 -307.579242) (xy 274.875157 -307.602585) (xy 274.826258 -307.618473)
			(xy 274.775476 -307.626516) (xy 274.72406 -307.626516) (xy 274.673278 -307.618473) (xy 274.624379 -307.602585)
			(xy 274.578567 -307.579242) (xy 274.536971 -307.549021) (xy 274.500615 -307.512665) (xy 274.470394 -307.471069)
			(xy 274.447051 -307.425257) (xy 274.431163 -307.376358) (xy 274.42312 -307.325576) (xy 274.126456 -307.325576)
			(xy 274.118413 -307.376358) (xy 274.102525 -307.425257) (xy 274.079182 -307.471069) (xy 274.048961 -307.512665)
			(xy 274.012605 -307.549021) (xy 273.971009 -307.579242) (xy 273.925197 -307.602585) (xy 273.876298 -307.618473)
			(xy 273.825516 -307.626516) (xy 273.7741 -307.626516) (xy 273.723318 -307.618473) (xy 273.674419 -307.602585)
			(xy 273.628607 -307.579242) (xy 273.587011 -307.549021) (xy 273.550655 -307.512665) (xy 273.520434 -307.471069)
			(xy 273.497091 -307.425257) (xy 273.481203 -307.376358) (xy 273.47316 -307.325576) (xy 273.154482 -307.325576)
			(xy 273.146766 -307.373052) (xy 273.131182 -307.419733) (xy 273.108311 -307.46331) (xy 273.078746 -307.502654)
			(xy 273.043253 -307.536746) (xy 273.00275 -307.564702) (xy 272.958288 -307.5858) (xy 272.911017 -307.599492)
			(xy 272.862162 -307.605424) (xy 272.812987 -307.603443) (xy 272.764768 -307.593599) (xy 272.718752 -307.576147)
			(xy 272.676131 -307.55154) (xy 272.63801 -307.520415) (xy 272.605375 -307.483578) (xy 272.579072 -307.441982)
			(xy 272.559781 -307.396706) (xy 272.548004 -307.348922) (xy 272.544044 -307.299868) (xy 272.22704 -307.299868)
			(xy 272.226536 -307.325576) (xy 272.218493 -307.376358) (xy 272.202605 -307.425257) (xy 272.179262 -307.471069)
			(xy 272.149041 -307.512665) (xy 272.112685 -307.549021) (xy 272.071089 -307.579242) (xy 272.025277 -307.602585)
			(xy 271.976378 -307.618473) (xy 271.925596 -307.626516) (xy 271.87418 -307.626516) (xy 271.823398 -307.618473)
			(xy 271.774499 -307.602585) (xy 271.728687 -307.579242) (xy 271.687091 -307.549021) (xy 271.650735 -307.512665)
			(xy 271.620514 -307.471069) (xy 271.597171 -307.425257) (xy 271.581283 -307.376358) (xy 271.57324 -307.325576)
			(xy 271.276576 -307.325576) (xy 271.268533 -307.376358) (xy 271.252645 -307.425257) (xy 271.229302 -307.471069)
			(xy 271.199081 -307.512665) (xy 271.162725 -307.549021) (xy 271.121129 -307.579242) (xy 271.075317 -307.602585)
			(xy 271.026418 -307.618473) (xy 270.975636 -307.626516) (xy 270.92422 -307.626516) (xy 270.873438 -307.618473)
			(xy 270.824539 -307.602585) (xy 270.778727 -307.579242) (xy 270.737131 -307.549021) (xy 270.700775 -307.512665)
			(xy 270.670554 -307.471069) (xy 270.647211 -307.425257) (xy 270.631323 -307.376358) (xy 270.62328 -307.325576)
			(xy 270.304348 -307.325576) (xy 270.296632 -307.373052) (xy 270.281048 -307.419733) (xy 270.258177 -307.46331)
			(xy 270.228612 -307.502654) (xy 270.193119 -307.536746) (xy 270.152616 -307.564702) (xy 270.108154 -307.5858)
			(xy 270.060883 -307.599492) (xy 270.012028 -307.605424) (xy 269.962853 -307.603443) (xy 269.914634 -307.593599)
			(xy 269.868618 -307.576147) (xy 269.825997 -307.55154) (xy 269.787876 -307.520415) (xy 269.755241 -307.483578)
			(xy 269.728938 -307.441982) (xy 269.709647 -307.396706) (xy 269.69787 -307.348922) (xy 269.69391 -307.299868)
			(xy 269.355062 -307.299868) (xy 269.354567 -307.324475) (xy 269.346672 -307.373052) (xy 269.331088 -307.419733)
			(xy 269.308217 -307.46331) (xy 269.278652 -307.502654) (xy 269.243159 -307.536746) (xy 269.202656 -307.564702)
			(xy 269.158194 -307.5858) (xy 269.110923 -307.599492) (xy 269.062068 -307.605424) (xy 269.012893 -307.603443)
			(xy 268.964674 -307.593599) (xy 268.918658 -307.576147) (xy 268.876037 -307.55154) (xy 268.837916 -307.520415)
			(xy 268.805281 -307.483578) (xy 268.778978 -307.441982) (xy 268.759687 -307.396706) (xy 268.74791 -307.348922)
			(xy 268.74395 -307.299868) (xy 264.641857 -307.299868) (xy 264.645539 -307.305434) (xy 264.669211 -307.355931)
			(xy 264.685279 -307.409338) (xy 264.693399 -307.464514) (xy 264.693908 -307.4924) (xy 264.693399 -307.520286)
			(xy 264.685279 -307.575462) (xy 264.669211 -307.628869) (xy 264.645539 -307.679366) (xy 264.614766 -307.725879)
			(xy 264.577549 -307.767416) (xy 264.568619 -307.774848) (xy 278.719038 -307.774848) (xy 278.722998 -307.725794)
			(xy 278.734775 -307.67801) (xy 278.754066 -307.632734) (xy 278.780369 -307.591138) (xy 278.813004 -307.554301)
			(xy 278.851125 -307.523176) (xy 278.893746 -307.498569) (xy 278.939762 -307.481117) (xy 278.987981 -307.471273)
			(xy 279.037156 -307.469292) (xy 279.086011 -307.475224) (xy 279.133282 -307.488916) (xy 279.177744 -307.510014)
			(xy 279.218247 -307.53797) (xy 279.25374 -307.572062) (xy 279.283305 -307.611406) (xy 279.306176 -307.654983)
			(xy 279.32176 -307.701664) (xy 279.329655 -307.750241) (xy 279.33015 -307.774848) (xy 279.668998 -307.774848)
			(xy 279.672958 -307.725794) (xy 279.684735 -307.67801) (xy 279.704026 -307.632734) (xy 279.730329 -307.591138)
			(xy 279.762964 -307.554301) (xy 279.801085 -307.523176) (xy 279.843706 -307.498569) (xy 279.889722 -307.481117)
			(xy 279.937941 -307.471273) (xy 279.987116 -307.469292) (xy 280.035971 -307.475224) (xy 280.083242 -307.488916)
			(xy 280.127704 -307.510014) (xy 280.168207 -307.53797) (xy 280.2037 -307.572062) (xy 280.233265 -307.611406)
			(xy 280.256136 -307.654983) (xy 280.27172 -307.701664) (xy 280.279615 -307.750241) (xy 280.28011 -307.774848)
			(xy 280.618958 -307.774848) (xy 280.622918 -307.725794) (xy 280.634695 -307.67801) (xy 280.653986 -307.632734)
			(xy 280.680289 -307.591138) (xy 280.712924 -307.554301) (xy 280.751045 -307.523176) (xy 280.793666 -307.498569)
			(xy 280.839682 -307.481117) (xy 280.887901 -307.471273) (xy 280.937076 -307.469292) (xy 280.985931 -307.475224)
			(xy 281.033202 -307.488916) (xy 281.077664 -307.510014) (xy 281.118167 -307.53797) (xy 281.15366 -307.572062)
			(xy 281.183225 -307.611406) (xy 281.206096 -307.654983) (xy 281.22168 -307.701664) (xy 281.229575 -307.750241)
			(xy 281.23007 -307.774848) (xy 281.568918 -307.774848) (xy 281.572878 -307.725794) (xy 281.584655 -307.67801)
			(xy 281.603946 -307.632734) (xy 281.630249 -307.591138) (xy 281.662884 -307.554301) (xy 281.701005 -307.523176)
			(xy 281.743626 -307.498569) (xy 281.789642 -307.481117) (xy 281.837861 -307.471273) (xy 281.887036 -307.469292)
			(xy 281.935891 -307.475224) (xy 281.983162 -307.488916) (xy 282.027624 -307.510014) (xy 282.068127 -307.53797)
			(xy 282.10362 -307.572062) (xy 282.133185 -307.611406) (xy 282.156056 -307.654983) (xy 282.17164 -307.701664)
			(xy 282.179535 -307.750241) (xy 282.18003 -307.774848) (xy 282.519132 -307.774848) (xy 282.523092 -307.725794)
			(xy 282.534869 -307.67801) (xy 282.55416 -307.632734) (xy 282.580463 -307.591138) (xy 282.613098 -307.554301)
			(xy 282.651219 -307.523176) (xy 282.69384 -307.498569) (xy 282.739856 -307.481117) (xy 282.788075 -307.471273)
			(xy 282.83725 -307.469292) (xy 282.886105 -307.475224) (xy 282.933376 -307.488916) (xy 282.977838 -307.510014)
			(xy 283.018341 -307.53797) (xy 283.053834 -307.572062) (xy 283.083399 -307.611406) (xy 283.10627 -307.654983)
			(xy 283.121854 -307.701664) (xy 283.129749 -307.750241) (xy 283.130244 -307.774848) (xy 283.469092 -307.774848)
			(xy 283.473052 -307.725794) (xy 283.484829 -307.67801) (xy 283.50412 -307.632734) (xy 283.530423 -307.591138)
			(xy 283.563058 -307.554301) (xy 283.601179 -307.523176) (xy 283.6438 -307.498569) (xy 283.689816 -307.481117)
			(xy 283.738035 -307.471273) (xy 283.78721 -307.469292) (xy 283.836065 -307.475224) (xy 283.883336 -307.488916)
			(xy 283.927798 -307.510014) (xy 283.968301 -307.53797) (xy 284.003794 -307.572062) (xy 284.033359 -307.611406)
			(xy 284.05623 -307.654983) (xy 284.071814 -307.701664) (xy 284.079709 -307.750241) (xy 284.080204 -307.774848)
			(xy 284.419052 -307.774848) (xy 284.423012 -307.725794) (xy 284.434789 -307.67801) (xy 284.45408 -307.632734)
			(xy 284.480383 -307.591138) (xy 284.513018 -307.554301) (xy 284.551139 -307.523176) (xy 284.59376 -307.498569)
			(xy 284.639776 -307.481117) (xy 284.687995 -307.471273) (xy 284.73717 -307.469292) (xy 284.786025 -307.475224)
			(xy 284.833296 -307.488916) (xy 284.877758 -307.510014) (xy 284.918261 -307.53797) (xy 284.953754 -307.572062)
			(xy 284.983319 -307.611406) (xy 285.00619 -307.654983) (xy 285.021774 -307.701664) (xy 285.029669 -307.750241)
			(xy 285.030164 -307.774848) (xy 285.369012 -307.774848) (xy 285.372972 -307.725794) (xy 285.384749 -307.67801)
			(xy 285.40404 -307.632734) (xy 285.430343 -307.591138) (xy 285.462978 -307.554301) (xy 285.501099 -307.523176)
			(xy 285.54372 -307.498569) (xy 285.589736 -307.481117) (xy 285.637955 -307.471273) (xy 285.68713 -307.469292)
			(xy 285.735985 -307.475224) (xy 285.783256 -307.488916) (xy 285.827718 -307.510014) (xy 285.868221 -307.53797)
			(xy 285.903714 -307.572062) (xy 285.933279 -307.611406) (xy 285.95615 -307.654983) (xy 285.971734 -307.701664)
			(xy 285.979629 -307.750241) (xy 285.980124 -307.774848) (xy 286.318972 -307.774848) (xy 286.322932 -307.725794)
			(xy 286.334709 -307.67801) (xy 286.354 -307.632734) (xy 286.380303 -307.591138) (xy 286.412938 -307.554301)
			(xy 286.451059 -307.523176) (xy 286.49368 -307.498569) (xy 286.539696 -307.481117) (xy 286.587915 -307.471273)
			(xy 286.63709 -307.469292) (xy 286.685945 -307.475224) (xy 286.733216 -307.488916) (xy 286.777678 -307.510014)
			(xy 286.818181 -307.53797) (xy 286.853674 -307.572062) (xy 286.883239 -307.611406) (xy 286.90611 -307.654983)
			(xy 286.921694 -307.701664) (xy 286.929589 -307.750241) (xy 286.930084 -307.774848) (xy 287.268932 -307.774848)
			(xy 287.272892 -307.725794) (xy 287.284669 -307.67801) (xy 287.30396 -307.632734) (xy 287.330263 -307.591138)
			(xy 287.362898 -307.554301) (xy 287.401019 -307.523176) (xy 287.44364 -307.498569) (xy 287.489656 -307.481117)
			(xy 287.537875 -307.471273) (xy 287.58705 -307.469292) (xy 287.635905 -307.475224) (xy 287.683176 -307.488916)
			(xy 287.727638 -307.510014) (xy 287.768141 -307.53797) (xy 287.803634 -307.572062) (xy 287.833199 -307.611406)
			(xy 287.85607 -307.654983) (xy 287.871654 -307.701664) (xy 287.879549 -307.750241) (xy 287.880044 -307.774848)
			(xy 288.219146 -307.774848) (xy 288.223106 -307.725794) (xy 288.234883 -307.67801) (xy 288.254174 -307.632734)
			(xy 288.280477 -307.591138) (xy 288.313112 -307.554301) (xy 288.351233 -307.523176) (xy 288.393854 -307.498569)
			(xy 288.43987 -307.481117) (xy 288.488089 -307.471273) (xy 288.537264 -307.469292) (xy 288.586119 -307.475224)
			(xy 288.63339 -307.488916) (xy 288.677852 -307.510014) (xy 288.718355 -307.53797) (xy 288.753848 -307.572062)
			(xy 288.783413 -307.611406) (xy 288.806284 -307.654983) (xy 288.821868 -307.701664) (xy 288.829763 -307.750241)
			(xy 288.830258 -307.774848) (xy 289.169106 -307.774848) (xy 289.173066 -307.725794) (xy 289.184843 -307.67801)
			(xy 289.204134 -307.632734) (xy 289.230437 -307.591138) (xy 289.263072 -307.554301) (xy 289.301193 -307.523176)
			(xy 289.343814 -307.498569) (xy 289.38983 -307.481117) (xy 289.438049 -307.471273) (xy 289.487224 -307.469292)
			(xy 289.536079 -307.475224) (xy 289.58335 -307.488916) (xy 289.627812 -307.510014) (xy 289.668315 -307.53797)
			(xy 289.703808 -307.572062) (xy 289.733373 -307.611406) (xy 289.756244 -307.654983) (xy 289.771828 -307.701664)
			(xy 289.779723 -307.750241) (xy 289.780218 -307.774848) (xy 290.119066 -307.774848) (xy 290.123026 -307.725794)
			(xy 290.134803 -307.67801) (xy 290.154094 -307.632734) (xy 290.180397 -307.591138) (xy 290.213032 -307.554301)
			(xy 290.251153 -307.523176) (xy 290.293774 -307.498569) (xy 290.33979 -307.481117) (xy 290.388009 -307.471273)
			(xy 290.437184 -307.469292) (xy 290.486039 -307.475224) (xy 290.53331 -307.488916) (xy 290.577772 -307.510014)
			(xy 290.618275 -307.53797) (xy 290.653768 -307.572062) (xy 290.683333 -307.611406) (xy 290.706204 -307.654983)
			(xy 290.721788 -307.701664) (xy 290.729683 -307.750241) (xy 290.730178 -307.774848) (xy 292.018986 -307.774848)
			(xy 292.022946 -307.725794) (xy 292.034723 -307.67801) (xy 292.054014 -307.632734) (xy 292.080317 -307.591138)
			(xy 292.112952 -307.554301) (xy 292.151073 -307.523176) (xy 292.193694 -307.498569) (xy 292.23971 -307.481117)
			(xy 292.287929 -307.471273) (xy 292.337104 -307.469292) (xy 292.385959 -307.475224) (xy 292.43323 -307.488916)
			(xy 292.477692 -307.510014) (xy 292.518195 -307.53797) (xy 292.553688 -307.572062) (xy 292.583253 -307.611406)
			(xy 292.606124 -307.654983) (xy 292.621708 -307.701664) (xy 292.629603 -307.750241) (xy 292.630098 -307.774848)
			(xy 292.968946 -307.774848) (xy 292.972906 -307.725794) (xy 292.984683 -307.67801) (xy 293.003974 -307.632734)
			(xy 293.030277 -307.591138) (xy 293.062912 -307.554301) (xy 293.101033 -307.523176) (xy 293.143654 -307.498569)
			(xy 293.18967 -307.481117) (xy 293.237889 -307.471273) (xy 293.287064 -307.469292) (xy 293.335919 -307.475224)
			(xy 293.38319 -307.488916) (xy 293.427652 -307.510014) (xy 293.468155 -307.53797) (xy 293.503648 -307.572062)
			(xy 293.533213 -307.611406) (xy 293.556084 -307.654983) (xy 293.571668 -307.701664) (xy 293.579563 -307.750241)
			(xy 293.580058 -307.774848) (xy 293.918906 -307.774848) (xy 293.922866 -307.725794) (xy 293.934643 -307.67801)
			(xy 293.953934 -307.632734) (xy 293.980237 -307.591138) (xy 294.012872 -307.554301) (xy 294.050993 -307.523176)
			(xy 294.093614 -307.498569) (xy 294.13963 -307.481117) (xy 294.187849 -307.471273) (xy 294.237024 -307.469292)
			(xy 294.285879 -307.475224) (xy 294.33315 -307.488916) (xy 294.377612 -307.510014) (xy 294.418115 -307.53797)
			(xy 294.453608 -307.572062) (xy 294.483173 -307.611406) (xy 294.506044 -307.654983) (xy 294.521628 -307.701664)
			(xy 294.529523 -307.750241) (xy 294.530013 -307.774594) (xy 294.868866 -307.774594) (xy 294.872826 -307.72554)
			(xy 294.884603 -307.677756) (xy 294.903894 -307.63248) (xy 294.930197 -307.590884) (xy 294.962832 -307.554047)
			(xy 295.000953 -307.522922) (xy 295.043574 -307.498315) (xy 295.08959 -307.480863) (xy 295.137809 -307.471019)
			(xy 295.186984 -307.469038) (xy 295.235839 -307.47497) (xy 295.28311 -307.488662) (xy 295.327572 -307.50976)
			(xy 295.368075 -307.537716) (xy 295.403568 -307.571808) (xy 295.433133 -307.611152) (xy 295.456004 -307.654729)
			(xy 295.471588 -307.70141) (xy 295.479483 -307.749987) (xy 295.479978 -307.774594) (xy 295.81908 -307.774594)
			(xy 295.82304 -307.72554) (xy 295.834817 -307.677756) (xy 295.854108 -307.63248) (xy 295.880411 -307.590884)
			(xy 295.913046 -307.554047) (xy 295.951167 -307.522922) (xy 295.993788 -307.498315) (xy 296.039804 -307.480863)
			(xy 296.088023 -307.471019) (xy 296.137198 -307.469038) (xy 296.186053 -307.47497) (xy 296.233324 -307.488662)
			(xy 296.277786 -307.50976) (xy 296.318289 -307.537716) (xy 296.353782 -307.571808) (xy 296.383347 -307.611152)
			(xy 296.406218 -307.654729) (xy 296.421802 -307.70141) (xy 296.429697 -307.749987) (xy 296.430192 -307.774594)
			(xy 296.430187 -307.774848) (xy 296.76904 -307.774848) (xy 296.773 -307.725794) (xy 296.784777 -307.67801)
			(xy 296.804068 -307.632734) (xy 296.830371 -307.591138) (xy 296.863006 -307.554301) (xy 296.901127 -307.523176)
			(xy 296.943748 -307.498569) (xy 296.989764 -307.481117) (xy 297.037983 -307.471273) (xy 297.087158 -307.469292)
			(xy 297.136013 -307.475224) (xy 297.183284 -307.488916) (xy 297.227746 -307.510014) (xy 297.268249 -307.53797)
			(xy 297.303742 -307.572062) (xy 297.333307 -307.611406) (xy 297.356178 -307.654983) (xy 297.371762 -307.701664)
			(xy 297.379657 -307.750241) (xy 297.380152 -307.774848) (xy 297.719 -307.774848) (xy 297.72296 -307.725794)
			(xy 297.734737 -307.67801) (xy 297.754028 -307.632734) (xy 297.780331 -307.591138) (xy 297.812966 -307.554301)
			(xy 297.851087 -307.523176) (xy 297.893708 -307.498569) (xy 297.939724 -307.481117) (xy 297.987943 -307.471273)
			(xy 298.037118 -307.469292) (xy 298.085973 -307.475224) (xy 298.133244 -307.488916) (xy 298.177706 -307.510014)
			(xy 298.218209 -307.53797) (xy 298.253702 -307.572062) (xy 298.283267 -307.611406) (xy 298.306138 -307.654983)
			(xy 298.321722 -307.701664) (xy 298.329617 -307.750241) (xy 298.330112 -307.774848) (xy 298.66896 -307.774848)
			(xy 298.67292 -307.725794) (xy 298.684697 -307.67801) (xy 298.703988 -307.632734) (xy 298.730291 -307.591138)
			(xy 298.762926 -307.554301) (xy 298.801047 -307.523176) (xy 298.843668 -307.498569) (xy 298.889684 -307.481117)
			(xy 298.937903 -307.471273) (xy 298.987078 -307.469292) (xy 299.035933 -307.475224) (xy 299.083204 -307.488916)
			(xy 299.127666 -307.510014) (xy 299.168169 -307.53797) (xy 299.203662 -307.572062) (xy 299.233227 -307.611406)
			(xy 299.256098 -307.654983) (xy 299.271682 -307.701664) (xy 299.279577 -307.750241) (xy 299.280072 -307.774848)
			(xy 299.61892 -307.774848) (xy 299.62288 -307.725794) (xy 299.634657 -307.67801) (xy 299.653948 -307.632734)
			(xy 299.680251 -307.591138) (xy 299.712886 -307.554301) (xy 299.751007 -307.523176) (xy 299.793628 -307.498569)
			(xy 299.839644 -307.481117) (xy 299.887863 -307.471273) (xy 299.937038 -307.469292) (xy 299.985893 -307.475224)
			(xy 300.033164 -307.488916) (xy 300.077626 -307.510014) (xy 300.118129 -307.53797) (xy 300.153622 -307.572062)
			(xy 300.183187 -307.611406) (xy 300.206058 -307.654983) (xy 300.221642 -307.701664) (xy 300.229537 -307.750241)
			(xy 300.230032 -307.774848) (xy 300.56888 -307.774848) (xy 300.57284 -307.725794) (xy 300.584617 -307.67801)
			(xy 300.603908 -307.632734) (xy 300.630211 -307.591138) (xy 300.662846 -307.554301) (xy 300.700967 -307.523176)
			(xy 300.743588 -307.498569) (xy 300.789604 -307.481117) (xy 300.837823 -307.471273) (xy 300.886998 -307.469292)
			(xy 300.935853 -307.475224) (xy 300.983124 -307.488916) (xy 301.027586 -307.510014) (xy 301.068089 -307.53797)
			(xy 301.103582 -307.572062) (xy 301.133147 -307.611406) (xy 301.156018 -307.654983) (xy 301.171602 -307.701664)
			(xy 301.179497 -307.750241) (xy 301.179992 -307.774848) (xy 301.519094 -307.774848) (xy 301.523054 -307.725794)
			(xy 301.534831 -307.67801) (xy 301.554122 -307.632734) (xy 301.580425 -307.591138) (xy 301.61306 -307.554301)
			(xy 301.651181 -307.523176) (xy 301.693802 -307.498569) (xy 301.739818 -307.481117) (xy 301.788037 -307.471273)
			(xy 301.837212 -307.469292) (xy 301.886067 -307.475224) (xy 301.933338 -307.488916) (xy 301.9778 -307.510014)
			(xy 302.018303 -307.53797) (xy 302.053796 -307.572062) (xy 302.083361 -307.611406) (xy 302.106232 -307.654983)
			(xy 302.121816 -307.701664) (xy 302.129711 -307.750241) (xy 302.130206 -307.774848) (xy 302.469054 -307.774848)
			(xy 302.473014 -307.725794) (xy 302.484791 -307.67801) (xy 302.504082 -307.632734) (xy 302.530385 -307.591138)
			(xy 302.56302 -307.554301) (xy 302.601141 -307.523176) (xy 302.643762 -307.498569) (xy 302.689778 -307.481117)
			(xy 302.737997 -307.471273) (xy 302.787172 -307.469292) (xy 302.836027 -307.475224) (xy 302.883298 -307.488916)
			(xy 302.92776 -307.510014) (xy 302.968263 -307.53797) (xy 303.003756 -307.572062) (xy 303.033321 -307.611406)
			(xy 303.056192 -307.654983) (xy 303.071776 -307.701664) (xy 303.079671 -307.750241) (xy 303.080166 -307.774848)
			(xy 303.419014 -307.774848) (xy 303.422974 -307.725794) (xy 303.434751 -307.67801) (xy 303.454042 -307.632734)
			(xy 303.480345 -307.591138) (xy 303.51298 -307.554301) (xy 303.551101 -307.523176) (xy 303.593722 -307.498569)
			(xy 303.639738 -307.481117) (xy 303.687957 -307.471273) (xy 303.737132 -307.469292) (xy 303.785987 -307.475224)
			(xy 303.833258 -307.488916) (xy 303.87772 -307.510014) (xy 303.918223 -307.53797) (xy 303.953716 -307.572062)
			(xy 303.983281 -307.611406) (xy 304.006152 -307.654983) (xy 304.021736 -307.701664) (xy 304.029631 -307.750241)
			(xy 304.030126 -307.774848) (xy 304.029631 -307.799455) (xy 304.021736 -307.848032) (xy 304.006152 -307.894713)
			(xy 303.983281 -307.93829) (xy 303.953716 -307.977634) (xy 303.918223 -308.011726) (xy 303.87772 -308.039682)
			(xy 303.833258 -308.06078) (xy 303.785987 -308.074472) (xy 303.737132 -308.080404) (xy 303.687957 -308.078423)
			(xy 303.639738 -308.068579) (xy 303.593722 -308.051127) (xy 303.551101 -308.02652) (xy 303.51298 -307.995395)
			(xy 303.480345 -307.958558) (xy 303.454042 -307.916962) (xy 303.434751 -307.871686) (xy 303.422974 -307.823902)
			(xy 303.419014 -307.774848) (xy 303.080166 -307.774848) (xy 303.079671 -307.799455) (xy 303.071776 -307.848032)
			(xy 303.056192 -307.894713) (xy 303.033321 -307.93829) (xy 303.003756 -307.977634) (xy 302.968263 -308.011726)
			(xy 302.92776 -308.039682) (xy 302.883298 -308.06078) (xy 302.836027 -308.074472) (xy 302.787172 -308.080404)
			(xy 302.737997 -308.078423) (xy 302.689778 -308.068579) (xy 302.643762 -308.051127) (xy 302.601141 -308.02652)
			(xy 302.56302 -307.995395) (xy 302.530385 -307.958558) (xy 302.504082 -307.916962) (xy 302.484791 -307.871686)
			(xy 302.473014 -307.823902) (xy 302.469054 -307.774848) (xy 302.130206 -307.774848) (xy 302.129711 -307.799455)
			(xy 302.121816 -307.848032) (xy 302.106232 -307.894713) (xy 302.083361 -307.93829) (xy 302.053796 -307.977634)
			(xy 302.018303 -308.011726) (xy 301.9778 -308.039682) (xy 301.933338 -308.06078) (xy 301.886067 -308.074472)
			(xy 301.837212 -308.080404) (xy 301.788037 -308.078423) (xy 301.739818 -308.068579) (xy 301.693802 -308.051127)
			(xy 301.651181 -308.02652) (xy 301.61306 -307.995395) (xy 301.580425 -307.958558) (xy 301.554122 -307.916962)
			(xy 301.534831 -307.871686) (xy 301.523054 -307.823902) (xy 301.519094 -307.774848) (xy 301.179992 -307.774848)
			(xy 301.179497 -307.799455) (xy 301.171602 -307.848032) (xy 301.156018 -307.894713) (xy 301.133147 -307.93829)
			(xy 301.103582 -307.977634) (xy 301.068089 -308.011726) (xy 301.027586 -308.039682) (xy 300.983124 -308.06078)
			(xy 300.935853 -308.074472) (xy 300.886998 -308.080404) (xy 300.837823 -308.078423) (xy 300.789604 -308.068579)
			(xy 300.743588 -308.051127) (xy 300.700967 -308.02652) (xy 300.662846 -307.995395) (xy 300.630211 -307.958558)
			(xy 300.603908 -307.916962) (xy 300.584617 -307.871686) (xy 300.57284 -307.823902) (xy 300.56888 -307.774848)
			(xy 300.230032 -307.774848) (xy 300.229537 -307.799455) (xy 300.221642 -307.848032) (xy 300.206058 -307.894713)
			(xy 300.183187 -307.93829) (xy 300.153622 -307.977634) (xy 300.118129 -308.011726) (xy 300.077626 -308.039682)
			(xy 300.033164 -308.06078) (xy 299.985893 -308.074472) (xy 299.937038 -308.080404) (xy 299.887863 -308.078423)
			(xy 299.839644 -308.068579) (xy 299.793628 -308.051127) (xy 299.751007 -308.02652) (xy 299.712886 -307.995395)
			(xy 299.680251 -307.958558) (xy 299.653948 -307.916962) (xy 299.634657 -307.871686) (xy 299.62288 -307.823902)
			(xy 299.61892 -307.774848) (xy 299.280072 -307.774848) (xy 299.279577 -307.799455) (xy 299.271682 -307.848032)
			(xy 299.256098 -307.894713) (xy 299.233227 -307.93829) (xy 299.203662 -307.977634) (xy 299.168169 -308.011726)
			(xy 299.127666 -308.039682) (xy 299.083204 -308.06078) (xy 299.035933 -308.074472) (xy 298.987078 -308.080404)
			(xy 298.937903 -308.078423) (xy 298.889684 -308.068579) (xy 298.843668 -308.051127) (xy 298.801047 -308.02652)
			(xy 298.762926 -307.995395) (xy 298.730291 -307.958558) (xy 298.703988 -307.916962) (xy 298.684697 -307.871686)
			(xy 298.67292 -307.823902) (xy 298.66896 -307.774848) (xy 298.330112 -307.774848) (xy 298.329617 -307.799455)
			(xy 298.321722 -307.848032) (xy 298.306138 -307.894713) (xy 298.283267 -307.93829) (xy 298.253702 -307.977634)
			(xy 298.218209 -308.011726) (xy 298.177706 -308.039682) (xy 298.133244 -308.06078) (xy 298.085973 -308.074472)
			(xy 298.037118 -308.080404) (xy 297.987943 -308.078423) (xy 297.939724 -308.068579) (xy 297.893708 -308.051127)
			(xy 297.851087 -308.02652) (xy 297.812966 -307.995395) (xy 297.780331 -307.958558) (xy 297.754028 -307.916962)
			(xy 297.734737 -307.871686) (xy 297.72296 -307.823902) (xy 297.719 -307.774848) (xy 297.380152 -307.774848)
			(xy 297.379657 -307.799455) (xy 297.371762 -307.848032) (xy 297.356178 -307.894713) (xy 297.333307 -307.93829)
			(xy 297.303742 -307.977634) (xy 297.268249 -308.011726) (xy 297.227746 -308.039682) (xy 297.183284 -308.06078)
			(xy 297.136013 -308.074472) (xy 297.087158 -308.080404) (xy 297.037983 -308.078423) (xy 296.989764 -308.068579)
			(xy 296.943748 -308.051127) (xy 296.901127 -308.02652) (xy 296.863006 -307.995395) (xy 296.830371 -307.958558)
			(xy 296.804068 -307.916962) (xy 296.784777 -307.871686) (xy 296.773 -307.823902) (xy 296.76904 -307.774848)
			(xy 296.430187 -307.774848) (xy 296.429697 -307.799201) (xy 296.421802 -307.847778) (xy 296.406218 -307.894459)
			(xy 296.383347 -307.938036) (xy 296.353782 -307.97738) (xy 296.318289 -308.011472) (xy 296.277786 -308.039428)
			(xy 296.233324 -308.060526) (xy 296.186053 -308.074218) (xy 296.137198 -308.08015) (xy 296.088023 -308.078169)
			(xy 296.039804 -308.068325) (xy 295.993788 -308.050873) (xy 295.951167 -308.026266) (xy 295.913046 -307.995141)
			(xy 295.880411 -307.958304) (xy 295.854108 -307.916708) (xy 295.834817 -307.871432) (xy 295.82304 -307.823648)
			(xy 295.81908 -307.774594) (xy 295.479978 -307.774594) (xy 295.479483 -307.799201) (xy 295.471588 -307.847778)
			(xy 295.456004 -307.894459) (xy 295.433133 -307.938036) (xy 295.403568 -307.97738) (xy 295.368075 -308.011472)
			(xy 295.327572 -308.039428) (xy 295.28311 -308.060526) (xy 295.235839 -308.074218) (xy 295.186984 -308.08015)
			(xy 295.137809 -308.078169) (xy 295.08959 -308.068325) (xy 295.043574 -308.050873) (xy 295.000953 -308.026266)
			(xy 294.962832 -307.995141) (xy 294.930197 -307.958304) (xy 294.903894 -307.916708) (xy 294.884603 -307.871432)
			(xy 294.872826 -307.823648) (xy 294.868866 -307.774594) (xy 294.530013 -307.774594) (xy 294.530018 -307.774848)
			(xy 294.529523 -307.799455) (xy 294.521628 -307.848032) (xy 294.506044 -307.894713) (xy 294.483173 -307.93829)
			(xy 294.453608 -307.977634) (xy 294.418115 -308.011726) (xy 294.377612 -308.039682) (xy 294.33315 -308.06078)
			(xy 294.285879 -308.074472) (xy 294.237024 -308.080404) (xy 294.187849 -308.078423) (xy 294.13963 -308.068579)
			(xy 294.093614 -308.051127) (xy 294.050993 -308.02652) (xy 294.012872 -307.995395) (xy 293.980237 -307.958558)
			(xy 293.953934 -307.916962) (xy 293.934643 -307.871686) (xy 293.922866 -307.823902) (xy 293.918906 -307.774848)
			(xy 293.580058 -307.774848) (xy 293.579563 -307.799455) (xy 293.571668 -307.848032) (xy 293.556084 -307.894713)
			(xy 293.533213 -307.93829) (xy 293.503648 -307.977634) (xy 293.468155 -308.011726) (xy 293.427652 -308.039682)
			(xy 293.38319 -308.06078) (xy 293.335919 -308.074472) (xy 293.287064 -308.080404) (xy 293.237889 -308.078423)
			(xy 293.18967 -308.068579) (xy 293.143654 -308.051127) (xy 293.101033 -308.02652) (xy 293.062912 -307.995395)
			(xy 293.030277 -307.958558) (xy 293.003974 -307.916962) (xy 292.984683 -307.871686) (xy 292.972906 -307.823902)
			(xy 292.968946 -307.774848) (xy 292.630098 -307.774848) (xy 292.629603 -307.799455) (xy 292.621708 -307.848032)
			(xy 292.606124 -307.894713) (xy 292.583253 -307.93829) (xy 292.553688 -307.977634) (xy 292.518195 -308.011726)
			(xy 292.477692 -308.039682) (xy 292.43323 -308.06078) (xy 292.385959 -308.074472) (xy 292.337104 -308.080404)
			(xy 292.287929 -308.078423) (xy 292.23971 -308.068579) (xy 292.193694 -308.051127) (xy 292.151073 -308.02652)
			(xy 292.112952 -307.995395) (xy 292.080317 -307.958558) (xy 292.054014 -307.916962) (xy 292.034723 -307.871686)
			(xy 292.022946 -307.823902) (xy 292.018986 -307.774848) (xy 290.730178 -307.774848) (xy 290.729683 -307.799455)
			(xy 290.721788 -307.848032) (xy 290.706204 -307.894713) (xy 290.683333 -307.93829) (xy 290.653768 -307.977634)
			(xy 290.618275 -308.011726) (xy 290.577772 -308.039682) (xy 290.53331 -308.06078) (xy 290.486039 -308.074472)
			(xy 290.437184 -308.080404) (xy 290.388009 -308.078423) (xy 290.33979 -308.068579) (xy 290.293774 -308.051127)
			(xy 290.251153 -308.02652) (xy 290.213032 -307.995395) (xy 290.180397 -307.958558) (xy 290.154094 -307.916962)
			(xy 290.134803 -307.871686) (xy 290.123026 -307.823902) (xy 290.119066 -307.774848) (xy 289.780218 -307.774848)
			(xy 289.779723 -307.799455) (xy 289.771828 -307.848032) (xy 289.756244 -307.894713) (xy 289.733373 -307.93829)
			(xy 289.703808 -307.977634) (xy 289.668315 -308.011726) (xy 289.627812 -308.039682) (xy 289.58335 -308.06078)
			(xy 289.536079 -308.074472) (xy 289.487224 -308.080404) (xy 289.438049 -308.078423) (xy 289.38983 -308.068579)
			(xy 289.343814 -308.051127) (xy 289.301193 -308.02652) (xy 289.263072 -307.995395) (xy 289.230437 -307.958558)
			(xy 289.204134 -307.916962) (xy 289.184843 -307.871686) (xy 289.173066 -307.823902) (xy 289.169106 -307.774848)
			(xy 288.830258 -307.774848) (xy 288.829763 -307.799455) (xy 288.821868 -307.848032) (xy 288.806284 -307.894713)
			(xy 288.783413 -307.93829) (xy 288.753848 -307.977634) (xy 288.718355 -308.011726) (xy 288.677852 -308.039682)
			(xy 288.63339 -308.06078) (xy 288.586119 -308.074472) (xy 288.537264 -308.080404) (xy 288.488089 -308.078423)
			(xy 288.43987 -308.068579) (xy 288.393854 -308.051127) (xy 288.351233 -308.02652) (xy 288.313112 -307.995395)
			(xy 288.280477 -307.958558) (xy 288.254174 -307.916962) (xy 288.234883 -307.871686) (xy 288.223106 -307.823902)
			(xy 288.219146 -307.774848) (xy 287.880044 -307.774848) (xy 287.879549 -307.799455) (xy 287.871654 -307.848032)
			(xy 287.85607 -307.894713) (xy 287.833199 -307.93829) (xy 287.803634 -307.977634) (xy 287.768141 -308.011726)
			(xy 287.727638 -308.039682) (xy 287.683176 -308.06078) (xy 287.635905 -308.074472) (xy 287.58705 -308.080404)
			(xy 287.537875 -308.078423) (xy 287.489656 -308.068579) (xy 287.44364 -308.051127) (xy 287.401019 -308.02652)
			(xy 287.362898 -307.995395) (xy 287.330263 -307.958558) (xy 287.30396 -307.916962) (xy 287.284669 -307.871686)
			(xy 287.272892 -307.823902) (xy 287.268932 -307.774848) (xy 286.930084 -307.774848) (xy 286.929589 -307.799455)
			(xy 286.921694 -307.848032) (xy 286.90611 -307.894713) (xy 286.883239 -307.93829) (xy 286.853674 -307.977634)
			(xy 286.818181 -308.011726) (xy 286.777678 -308.039682) (xy 286.733216 -308.06078) (xy 286.685945 -308.074472)
			(xy 286.63709 -308.080404) (xy 286.587915 -308.078423) (xy 286.539696 -308.068579) (xy 286.49368 -308.051127)
			(xy 286.451059 -308.02652) (xy 286.412938 -307.995395) (xy 286.380303 -307.958558) (xy 286.354 -307.916962)
			(xy 286.334709 -307.871686) (xy 286.322932 -307.823902) (xy 286.318972 -307.774848) (xy 285.980124 -307.774848)
			(xy 285.979629 -307.799455) (xy 285.971734 -307.848032) (xy 285.95615 -307.894713) (xy 285.933279 -307.93829)
			(xy 285.903714 -307.977634) (xy 285.868221 -308.011726) (xy 285.827718 -308.039682) (xy 285.783256 -308.06078)
			(xy 285.735985 -308.074472) (xy 285.68713 -308.080404) (xy 285.637955 -308.078423) (xy 285.589736 -308.068579)
			(xy 285.54372 -308.051127) (xy 285.501099 -308.02652) (xy 285.462978 -307.995395) (xy 285.430343 -307.958558)
			(xy 285.40404 -307.916962) (xy 285.384749 -307.871686) (xy 285.372972 -307.823902) (xy 285.369012 -307.774848)
			(xy 285.030164 -307.774848) (xy 285.029669 -307.799455) (xy 285.021774 -307.848032) (xy 285.00619 -307.894713)
			(xy 284.983319 -307.93829) (xy 284.953754 -307.977634) (xy 284.918261 -308.011726) (xy 284.877758 -308.039682)
			(xy 284.833296 -308.06078) (xy 284.786025 -308.074472) (xy 284.73717 -308.080404) (xy 284.687995 -308.078423)
			(xy 284.639776 -308.068579) (xy 284.59376 -308.051127) (xy 284.551139 -308.02652) (xy 284.513018 -307.995395)
			(xy 284.480383 -307.958558) (xy 284.45408 -307.916962) (xy 284.434789 -307.871686) (xy 284.423012 -307.823902)
			(xy 284.419052 -307.774848) (xy 284.080204 -307.774848) (xy 284.079709 -307.799455) (xy 284.071814 -307.848032)
			(xy 284.05623 -307.894713) (xy 284.033359 -307.93829) (xy 284.003794 -307.977634) (xy 283.968301 -308.011726)
			(xy 283.927798 -308.039682) (xy 283.883336 -308.06078) (xy 283.836065 -308.074472) (xy 283.78721 -308.080404)
			(xy 283.738035 -308.078423) (xy 283.689816 -308.068579) (xy 283.6438 -308.051127) (xy 283.601179 -308.02652)
			(xy 283.563058 -307.995395) (xy 283.530423 -307.958558) (xy 283.50412 -307.916962) (xy 283.484829 -307.871686)
			(xy 283.473052 -307.823902) (xy 283.469092 -307.774848) (xy 283.130244 -307.774848) (xy 283.129749 -307.799455)
			(xy 283.121854 -307.848032) (xy 283.10627 -307.894713) (xy 283.083399 -307.93829) (xy 283.053834 -307.977634)
			(xy 283.018341 -308.011726) (xy 282.977838 -308.039682) (xy 282.933376 -308.06078) (xy 282.886105 -308.074472)
			(xy 282.83725 -308.080404) (xy 282.788075 -308.078423) (xy 282.739856 -308.068579) (xy 282.69384 -308.051127)
			(xy 282.651219 -308.02652) (xy 282.613098 -307.995395) (xy 282.580463 -307.958558) (xy 282.55416 -307.916962)
			(xy 282.534869 -307.871686) (xy 282.523092 -307.823902) (xy 282.519132 -307.774848) (xy 282.18003 -307.774848)
			(xy 282.179535 -307.799455) (xy 282.17164 -307.848032) (xy 282.156056 -307.894713) (xy 282.133185 -307.93829)
			(xy 282.10362 -307.977634) (xy 282.068127 -308.011726) (xy 282.027624 -308.039682) (xy 281.983162 -308.06078)
			(xy 281.935891 -308.074472) (xy 281.887036 -308.080404) (xy 281.837861 -308.078423) (xy 281.789642 -308.068579)
			(xy 281.743626 -308.051127) (xy 281.701005 -308.02652) (xy 281.662884 -307.995395) (xy 281.630249 -307.958558)
			(xy 281.603946 -307.916962) (xy 281.584655 -307.871686) (xy 281.572878 -307.823902) (xy 281.568918 -307.774848)
			(xy 281.23007 -307.774848) (xy 281.229575 -307.799455) (xy 281.22168 -307.848032) (xy 281.206096 -307.894713)
			(xy 281.183225 -307.93829) (xy 281.15366 -307.977634) (xy 281.118167 -308.011726) (xy 281.077664 -308.039682)
			(xy 281.033202 -308.06078) (xy 280.985931 -308.074472) (xy 280.937076 -308.080404) (xy 280.887901 -308.078423)
			(xy 280.839682 -308.068579) (xy 280.793666 -308.051127) (xy 280.751045 -308.02652) (xy 280.712924 -307.995395)
			(xy 280.680289 -307.958558) (xy 280.653986 -307.916962) (xy 280.634695 -307.871686) (xy 280.622918 -307.823902)
			(xy 280.618958 -307.774848) (xy 280.28011 -307.774848) (xy 280.279615 -307.799455) (xy 280.27172 -307.848032)
			(xy 280.256136 -307.894713) (xy 280.233265 -307.93829) (xy 280.2037 -307.977634) (xy 280.168207 -308.011726)
			(xy 280.127704 -308.039682) (xy 280.083242 -308.06078) (xy 280.035971 -308.074472) (xy 279.987116 -308.080404)
			(xy 279.937941 -308.078423) (xy 279.889722 -308.068579) (xy 279.843706 -308.051127) (xy 279.801085 -308.02652)
			(xy 279.762964 -307.995395) (xy 279.730329 -307.958558) (xy 279.704026 -307.916962) (xy 279.684735 -307.871686)
			(xy 279.672958 -307.823902) (xy 279.668998 -307.774848) (xy 279.33015 -307.774848) (xy 279.329655 -307.799455)
			(xy 279.32176 -307.848032) (xy 279.306176 -307.894713) (xy 279.283305 -307.93829) (xy 279.25374 -307.977634)
			(xy 279.218247 -308.011726) (xy 279.177744 -308.039682) (xy 279.133282 -308.06078) (xy 279.086011 -308.074472)
			(xy 279.037156 -308.080404) (xy 278.987981 -308.078423) (xy 278.939762 -308.068579) (xy 278.893746 -308.051127)
			(xy 278.851125 -308.02652) (xy 278.813004 -307.995395) (xy 278.780369 -307.958558) (xy 278.754066 -307.916962)
			(xy 278.734775 -307.871686) (xy 278.722998 -307.823902) (xy 278.719038 -307.774848) (xy 264.568619 -307.774848)
			(xy 264.534681 -307.803091) (xy 264.487075 -307.832145) (xy 264.435746 -307.853957) (xy 264.381789 -307.868063)
			(xy 264.326352 -307.874163) (xy 264.270618 -307.872126) (xy 264.215775 -307.861996) (xy 264.162991 -307.843989)
			(xy 264.113391 -307.818488) (xy 264.068033 -307.786037) (xy 264.027884 -307.747328) (xy 263.993798 -307.703185)
			(xy 263.966502 -307.65455) (xy 263.946579 -307.602459) (xy 263.934453 -307.548022) (xy 263.930382 -307.4924)
			(xy 248.949301 -307.4924) (xy 248.948789 -307.518004) (xy 248.937039 -307.584437) (xy 248.926096 -307.616352)
			(xy 248.915484 -307.643575) (xy 248.887179 -307.694687) (xy 248.851407 -307.740881) (xy 248.830592 -307.761386)
			(xy 248.823424 -307.768859) (xy 248.815276 -307.787872) (xy 248.814844 -307.798216) (xy 248.814844 -308.254908)
			(xy 248.815321 -308.265246) (xy 248.823437 -308.284263) (xy 248.830592 -308.291738) (xy 248.851401 -308.312248)
			(xy 248.887163 -308.358447) (xy 248.915473 -308.409554) (xy 248.926096 -308.436772) (xy 248.930808 -308.450488)
			(xy 260.278116 -308.450488) (xy 260.282187 -308.394866) (xy 260.294313 -308.340429) (xy 260.314236 -308.288338)
			(xy 260.341532 -308.239703) (xy 260.375618 -308.19556) (xy 260.415767 -308.156851) (xy 260.461125 -308.1244)
			(xy 260.510725 -308.098899) (xy 260.563509 -308.080892) (xy 260.618352 -308.070762) (xy 260.674086 -308.068725)
			(xy 260.729523 -308.074825) (xy 260.78348 -308.088931) (xy 260.834809 -308.110743) (xy 260.882415 -308.139797)
			(xy 260.925283 -308.175472) (xy 260.9625 -308.217009) (xy 260.984381 -308.250082) (xy 267.793736 -308.250082)
			(xy 267.797696 -308.201028) (xy 267.809473 -308.153244) (xy 267.828764 -308.107968) (xy 267.855067 -308.066372)
			(xy 267.887702 -308.029535) (xy 267.925823 -307.99841) (xy 267.968444 -307.973803) (xy 268.01446 -307.956351)
			(xy 268.062679 -307.946507) (xy 268.111854 -307.944526) (xy 268.160709 -307.950458) (xy 268.20798 -307.96415)
			(xy 268.252442 -307.985248) (xy 268.292945 -308.013204) (xy 268.328438 -308.047296) (xy 268.358003 -308.08664)
			(xy 268.380874 -308.130217) (xy 268.396458 -308.176898) (xy 268.404353 -308.225475) (xy 268.404848 -308.250082)
			(xy 268.404353 -308.274689) (xy 268.404215 -308.275536) (xy 268.723106 -308.275536) (xy 268.723106 -308.22412)
			(xy 268.731149 -308.173338) (xy 268.747037 -308.124439) (xy 268.77038 -308.078627) (xy 268.800601 -308.037031)
			(xy 268.836957 -308.000675) (xy 268.878553 -307.970454) (xy 268.924365 -307.947111) (xy 268.973264 -307.931223)
			(xy 269.024046 -307.92318) (xy 269.075462 -307.92318) (xy 269.126244 -307.931223) (xy 269.175143 -307.947111)
			(xy 269.220955 -307.970454) (xy 269.262551 -308.000675) (xy 269.298907 -308.037031) (xy 269.329128 -308.078627)
			(xy 269.352471 -308.124439) (xy 269.368359 -308.173338) (xy 269.376402 -308.22412) (xy 269.376906 -308.249828)
			(xy 269.376402 -308.275536) (xy 269.673066 -308.275536) (xy 269.673066 -308.22412) (xy 269.681109 -308.173338)
			(xy 269.696997 -308.124439) (xy 269.72034 -308.078627) (xy 269.750561 -308.037031) (xy 269.786917 -308.000675)
			(xy 269.828513 -307.970454) (xy 269.874325 -307.947111) (xy 269.923224 -307.931223) (xy 269.974006 -307.92318)
			(xy 270.025422 -307.92318) (xy 270.076204 -307.931223) (xy 270.125103 -307.947111) (xy 270.170915 -307.970454)
			(xy 270.212511 -308.000675) (xy 270.248867 -308.037031) (xy 270.279088 -308.078627) (xy 270.302431 -308.124439)
			(xy 270.318319 -308.173338) (xy 270.326362 -308.22412) (xy 270.326866 -308.249828) (xy 270.644124 -308.249828)
			(xy 270.648084 -308.200774) (xy 270.659861 -308.15299) (xy 270.679152 -308.107714) (xy 270.705455 -308.066118)
			(xy 270.73809 -308.029281) (xy 270.776211 -307.998156) (xy 270.818832 -307.973549) (xy 270.864848 -307.956097)
			(xy 270.913067 -307.946253) (xy 270.962242 -307.944272) (xy 271.011097 -307.950204) (xy 271.058368 -307.963896)
			(xy 271.10283 -307.984994) (xy 271.143333 -308.01295) (xy 271.178826 -308.047042) (xy 271.208391 -308.086386)
			(xy 271.231262 -308.129963) (xy 271.246846 -308.176644) (xy 271.254741 -308.225221) (xy 271.255236 -308.249828)
			(xy 271.594084 -308.249828) (xy 271.598044 -308.200774) (xy 271.609821 -308.15299) (xy 271.629112 -308.107714)
			(xy 271.655415 -308.066118) (xy 271.68805 -308.029281) (xy 271.726171 -307.998156) (xy 271.768792 -307.973549)
			(xy 271.814808 -307.956097) (xy 271.863027 -307.946253) (xy 271.912202 -307.944272) (xy 271.961057 -307.950204)
			(xy 272.008328 -307.963896) (xy 272.05279 -307.984994) (xy 272.093293 -308.01295) (xy 272.128786 -308.047042)
			(xy 272.158351 -308.086386) (xy 272.181222 -308.129963) (xy 272.196806 -308.176644) (xy 272.204701 -308.225221)
			(xy 272.205196 -308.249828) (xy 272.544044 -308.249828) (xy 272.548004 -308.200774) (xy 272.559781 -308.15299)
			(xy 272.579072 -308.107714) (xy 272.605375 -308.066118) (xy 272.63801 -308.029281) (xy 272.676131 -307.998156)
			(xy 272.718752 -307.973549) (xy 272.764768 -307.956097) (xy 272.812987 -307.946253) (xy 272.862162 -307.944272)
			(xy 272.911017 -307.950204) (xy 272.958288 -307.963896) (xy 273.00275 -307.984994) (xy 273.043253 -308.01295)
			(xy 273.078746 -308.047042) (xy 273.108311 -308.086386) (xy 273.131182 -308.129963) (xy 273.146766 -308.176644)
			(xy 273.154661 -308.225221) (xy 273.155156 -308.249828) (xy 273.494004 -308.249828) (xy 273.497964 -308.200774)
			(xy 273.509741 -308.15299) (xy 273.529032 -308.107714) (xy 273.555335 -308.066118) (xy 273.58797 -308.029281)
			(xy 273.626091 -307.998156) (xy 273.668712 -307.973549) (xy 273.714728 -307.956097) (xy 273.762947 -307.946253)
			(xy 273.812122 -307.944272) (xy 273.860977 -307.950204) (xy 273.908248 -307.963896) (xy 273.95271 -307.984994)
			(xy 273.993213 -308.01295) (xy 274.028706 -308.047042) (xy 274.058271 -308.086386) (xy 274.081142 -308.129963)
			(xy 274.096726 -308.176644) (xy 274.104621 -308.225221) (xy 274.105116 -308.249828) (xy 274.443964 -308.249828)
			(xy 274.447924 -308.200774) (xy 274.459701 -308.15299) (xy 274.478992 -308.107714) (xy 274.505295 -308.066118)
			(xy 274.53793 -308.029281) (xy 274.576051 -307.998156) (xy 274.618672 -307.973549) (xy 274.664688 -307.956097)
			(xy 274.712907 -307.946253) (xy 274.762082 -307.944272) (xy 274.810937 -307.950204) (xy 274.858208 -307.963896)
			(xy 274.90267 -307.984994) (xy 274.943173 -308.01295) (xy 274.978666 -308.047042) (xy 275.008231 -308.086386)
			(xy 275.031102 -308.129963) (xy 275.046686 -308.176644) (xy 275.054581 -308.225221) (xy 275.055076 -308.249828)
			(xy 275.054581 -308.274435) (xy 275.054402 -308.275536) (xy 275.37308 -308.275536) (xy 275.37308 -308.22412)
			(xy 275.381123 -308.173338) (xy 275.397011 -308.124439) (xy 275.420354 -308.078627) (xy 275.450575 -308.037031)
			(xy 275.486931 -308.000675) (xy 275.528527 -307.970454) (xy 275.574339 -307.947111) (xy 275.623238 -307.931223)
			(xy 275.67402 -307.92318) (xy 275.725436 -307.92318) (xy 275.776218 -307.931223) (xy 275.825117 -307.947111)
			(xy 275.870929 -307.970454) (xy 275.912525 -308.000675) (xy 275.948881 -308.037031) (xy 275.979102 -308.078627)
			(xy 276.002445 -308.124439) (xy 276.018333 -308.173338) (xy 276.026376 -308.22412) (xy 276.02688 -308.249828)
			(xy 276.026376 -308.275536) (xy 276.32304 -308.275536) (xy 276.32304 -308.22412) (xy 276.331083 -308.173338)
			(xy 276.346971 -308.124439) (xy 276.370314 -308.078627) (xy 276.400535 -308.037031) (xy 276.436891 -308.000675)
			(xy 276.478487 -307.970454) (xy 276.524299 -307.947111) (xy 276.573198 -307.931223) (xy 276.62398 -307.92318)
			(xy 276.675396 -307.92318) (xy 276.726178 -307.931223) (xy 276.775077 -307.947111) (xy 276.820889 -307.970454)
			(xy 276.862485 -308.000675) (xy 276.898841 -308.037031) (xy 276.929062 -308.078627) (xy 276.952405 -308.124439)
			(xy 276.968293 -308.173338) (xy 276.976336 -308.22412) (xy 276.97684 -308.249828) (xy 277.294098 -308.249828)
			(xy 277.298058 -308.200774) (xy 277.309835 -308.15299) (xy 277.329126 -308.107714) (xy 277.355429 -308.066118)
			(xy 277.388064 -308.029281) (xy 277.426185 -307.998156) (xy 277.468806 -307.973549) (xy 277.514822 -307.956097)
			(xy 277.563041 -307.946253) (xy 277.612216 -307.944272) (xy 277.661071 -307.950204) (xy 277.708342 -307.963896)
			(xy 277.752804 -307.984994) (xy 277.793307 -308.01295) (xy 277.8288 -308.047042) (xy 277.858365 -308.086386)
			(xy 277.881236 -308.129963) (xy 277.89682 -308.176644) (xy 277.904715 -308.225221) (xy 277.90521 -308.249828)
			(xy 277.904715 -308.274435) (xy 277.89682 -308.323012) (xy 277.881236 -308.369693) (xy 277.858365 -308.41327)
			(xy 277.8288 -308.452614) (xy 277.793307 -308.486706) (xy 277.752804 -308.514662) (xy 277.708342 -308.53576)
			(xy 277.661071 -308.549452) (xy 277.612216 -308.555384) (xy 277.563041 -308.553403) (xy 277.514822 -308.543559)
			(xy 277.468806 -308.526107) (xy 277.426185 -308.5015) (xy 277.388064 -308.470375) (xy 277.355429 -308.433538)
			(xy 277.329126 -308.391942) (xy 277.309835 -308.346666) (xy 277.298058 -308.298882) (xy 277.294098 -308.249828)
			(xy 276.97684 -308.249828) (xy 276.976336 -308.275536) (xy 276.968293 -308.326318) (xy 276.952405 -308.375217)
			(xy 276.929062 -308.421029) (xy 276.898841 -308.462625) (xy 276.862485 -308.498981) (xy 276.820889 -308.529202)
			(xy 276.775077 -308.552545) (xy 276.726178 -308.568433) (xy 276.675396 -308.576476) (xy 276.62398 -308.576476)
			(xy 276.573198 -308.568433) (xy 276.524299 -308.552545) (xy 276.478487 -308.529202) (xy 276.436891 -308.498981)
			(xy 276.400535 -308.462625) (xy 276.370314 -308.421029) (xy 276.346971 -308.375217) (xy 276.331083 -308.326318)
			(xy 276.32304 -308.275536) (xy 276.026376 -308.275536) (xy 276.018333 -308.326318) (xy 276.002445 -308.375217)
			(xy 275.979102 -308.421029) (xy 275.948881 -308.462625) (xy 275.912525 -308.498981) (xy 275.870929 -308.529202)
			(xy 275.825117 -308.552545) (xy 275.776218 -308.568433) (xy 275.725436 -308.576476) (xy 275.67402 -308.576476)
			(xy 275.623238 -308.568433) (xy 275.574339 -308.552545) (xy 275.528527 -308.529202) (xy 275.486931 -308.498981)
			(xy 275.450575 -308.462625) (xy 275.420354 -308.421029) (xy 275.397011 -308.375217) (xy 275.381123 -308.326318)
			(xy 275.37308 -308.275536) (xy 275.054402 -308.275536) (xy 275.046686 -308.323012) (xy 275.031102 -308.369693)
			(xy 275.008231 -308.41327) (xy 274.978666 -308.452614) (xy 274.943173 -308.486706) (xy 274.90267 -308.514662)
			(xy 274.858208 -308.53576) (xy 274.810937 -308.549452) (xy 274.762082 -308.555384) (xy 274.712907 -308.553403)
			(xy 274.664688 -308.543559) (xy 274.618672 -308.526107) (xy 274.576051 -308.5015) (xy 274.53793 -308.470375)
			(xy 274.505295 -308.433538) (xy 274.478992 -308.391942) (xy 274.459701 -308.346666) (xy 274.447924 -308.298882)
			(xy 274.443964 -308.249828) (xy 274.105116 -308.249828) (xy 274.104621 -308.274435) (xy 274.096726 -308.323012)
			(xy 274.081142 -308.369693) (xy 274.058271 -308.41327) (xy 274.028706 -308.452614) (xy 273.993213 -308.486706)
			(xy 273.95271 -308.514662) (xy 273.908248 -308.53576) (xy 273.860977 -308.549452) (xy 273.812122 -308.555384)
			(xy 273.762947 -308.553403) (xy 273.714728 -308.543559) (xy 273.668712 -308.526107) (xy 273.626091 -308.5015)
			(xy 273.58797 -308.470375) (xy 273.555335 -308.433538) (xy 273.529032 -308.391942) (xy 273.509741 -308.346666)
			(xy 273.497964 -308.298882) (xy 273.494004 -308.249828) (xy 273.155156 -308.249828) (xy 273.154661 -308.274435)
			(xy 273.146766 -308.323012) (xy 273.131182 -308.369693) (xy 273.108311 -308.41327) (xy 273.078746 -308.452614)
			(xy 273.043253 -308.486706) (xy 273.00275 -308.514662) (xy 272.958288 -308.53576) (xy 272.911017 -308.549452)
			(xy 272.862162 -308.555384) (xy 272.812987 -308.553403) (xy 272.764768 -308.543559) (xy 272.718752 -308.526107)
			(xy 272.676131 -308.5015) (xy 272.63801 -308.470375) (xy 272.605375 -308.433538) (xy 272.579072 -308.391942)
			(xy 272.559781 -308.346666) (xy 272.548004 -308.298882) (xy 272.544044 -308.249828) (xy 272.205196 -308.249828)
			(xy 272.204701 -308.274435) (xy 272.196806 -308.323012) (xy 272.181222 -308.369693) (xy 272.158351 -308.41327)
			(xy 272.128786 -308.452614) (xy 272.093293 -308.486706) (xy 272.05279 -308.514662) (xy 272.008328 -308.53576)
			(xy 271.961057 -308.549452) (xy 271.912202 -308.555384) (xy 271.863027 -308.553403) (xy 271.814808 -308.543559)
			(xy 271.768792 -308.526107) (xy 271.726171 -308.5015) (xy 271.68805 -308.470375) (xy 271.655415 -308.433538)
			(xy 271.629112 -308.391942) (xy 271.609821 -308.346666) (xy 271.598044 -308.298882) (xy 271.594084 -308.249828)
			(xy 271.255236 -308.249828) (xy 271.254741 -308.274435) (xy 271.246846 -308.323012) (xy 271.231262 -308.369693)
			(xy 271.208391 -308.41327) (xy 271.178826 -308.452614) (xy 271.143333 -308.486706) (xy 271.10283 -308.514662)
			(xy 271.058368 -308.53576) (xy 271.011097 -308.549452) (xy 270.962242 -308.555384) (xy 270.913067 -308.553403)
			(xy 270.864848 -308.543559) (xy 270.818832 -308.526107) (xy 270.776211 -308.5015) (xy 270.73809 -308.470375)
			(xy 270.705455 -308.433538) (xy 270.679152 -308.391942) (xy 270.659861 -308.346666) (xy 270.648084 -308.298882)
			(xy 270.644124 -308.249828) (xy 270.326866 -308.249828) (xy 270.326362 -308.275536) (xy 270.318319 -308.326318)
			(xy 270.302431 -308.375217) (xy 270.279088 -308.421029) (xy 270.248867 -308.462625) (xy 270.212511 -308.498981)
			(xy 270.170915 -308.529202) (xy 270.125103 -308.552545) (xy 270.076204 -308.568433) (xy 270.025422 -308.576476)
			(xy 269.974006 -308.576476) (xy 269.923224 -308.568433) (xy 269.874325 -308.552545) (xy 269.828513 -308.529202)
			(xy 269.786917 -308.498981) (xy 269.750561 -308.462625) (xy 269.72034 -308.421029) (xy 269.696997 -308.375217)
			(xy 269.681109 -308.326318) (xy 269.673066 -308.275536) (xy 269.376402 -308.275536) (xy 269.368359 -308.326318)
			(xy 269.352471 -308.375217) (xy 269.329128 -308.421029) (xy 269.298907 -308.462625) (xy 269.262551 -308.498981)
			(xy 269.220955 -308.529202) (xy 269.175143 -308.552545) (xy 269.126244 -308.568433) (xy 269.075462 -308.576476)
			(xy 269.024046 -308.576476) (xy 268.973264 -308.568433) (xy 268.924365 -308.552545) (xy 268.878553 -308.529202)
			(xy 268.836957 -308.498981) (xy 268.800601 -308.462625) (xy 268.77038 -308.421029) (xy 268.747037 -308.375217)
			(xy 268.731149 -308.326318) (xy 268.723106 -308.275536) (xy 268.404215 -308.275536) (xy 268.396458 -308.323266)
			(xy 268.380874 -308.369947) (xy 268.358003 -308.413524) (xy 268.328438 -308.452868) (xy 268.292945 -308.48696)
			(xy 268.252442 -308.514916) (xy 268.20798 -308.536014) (xy 268.160709 -308.549706) (xy 268.111854 -308.555638)
			(xy 268.062679 -308.553657) (xy 268.01446 -308.543813) (xy 267.968444 -308.526361) (xy 267.925823 -308.501754)
			(xy 267.887702 -308.470629) (xy 267.855067 -308.433792) (xy 267.828764 -308.392196) (xy 267.809473 -308.34692)
			(xy 267.797696 -308.299136) (xy 267.793736 -308.250082) (xy 260.984381 -308.250082) (xy 260.993273 -308.263522)
			(xy 261.016945 -308.314019) (xy 261.033013 -308.367426) (xy 261.041133 -308.422602) (xy 261.041642 -308.450488)
			(xy 261.041133 -308.478374) (xy 261.033013 -308.53355) (xy 261.016945 -308.586957) (xy 260.993273 -308.637454)
			(xy 260.978668 -308.65953) (xy 262.605518 -308.65953) (xy 262.609589 -308.603908) (xy 262.621715 -308.549471)
			(xy 262.641638 -308.49738) (xy 262.668934 -308.448745) (xy 262.70302 -308.404602) (xy 262.743169 -308.365893)
			(xy 262.788527 -308.333442) (xy 262.838127 -308.307941) (xy 262.890911 -308.289934) (xy 262.945754 -308.279804)
			(xy 263.001488 -308.277767) (xy 263.056925 -308.283867) (xy 263.110882 -308.297973) (xy 263.162211 -308.319785)
			(xy 263.209817 -308.348839) (xy 263.252685 -308.384514) (xy 263.289902 -308.426051) (xy 263.320675 -308.472564)
			(xy 263.344347 -308.523061) (xy 263.360415 -308.576468) (xy 263.368535 -308.631644) (xy 263.369044 -308.65953)
			(xy 263.368535 -308.687416) (xy 263.363032 -308.724808) (xy 278.719038 -308.724808) (xy 278.722998 -308.675754)
			(xy 278.734775 -308.62797) (xy 278.754066 -308.582694) (xy 278.780369 -308.541098) (xy 278.813004 -308.504261)
			(xy 278.851125 -308.473136) (xy 278.893746 -308.448529) (xy 278.939762 -308.431077) (xy 278.987981 -308.421233)
			(xy 279.037156 -308.419252) (xy 279.086011 -308.425184) (xy 279.133282 -308.438876) (xy 279.177744 -308.459974)
			(xy 279.218247 -308.48793) (xy 279.25374 -308.522022) (xy 279.283305 -308.561366) (xy 279.306176 -308.604943)
			(xy 279.32176 -308.651624) (xy 279.329655 -308.700201) (xy 279.33015 -308.724808) (xy 279.668998 -308.724808)
			(xy 279.672958 -308.675754) (xy 279.684735 -308.62797) (xy 279.704026 -308.582694) (xy 279.730329 -308.541098)
			(xy 279.762964 -308.504261) (xy 279.801085 -308.473136) (xy 279.843706 -308.448529) (xy 279.889722 -308.431077)
			(xy 279.937941 -308.421233) (xy 279.987116 -308.419252) (xy 280.035971 -308.425184) (xy 280.083242 -308.438876)
			(xy 280.127704 -308.459974) (xy 280.168207 -308.48793) (xy 280.2037 -308.522022) (xy 280.233265 -308.561366)
			(xy 280.256136 -308.604943) (xy 280.27172 -308.651624) (xy 280.279615 -308.700201) (xy 280.28011 -308.724808)
			(xy 280.618958 -308.724808) (xy 280.622918 -308.675754) (xy 280.634695 -308.62797) (xy 280.653986 -308.582694)
			(xy 280.680289 -308.541098) (xy 280.712924 -308.504261) (xy 280.751045 -308.473136) (xy 280.793666 -308.448529)
			(xy 280.839682 -308.431077) (xy 280.887901 -308.421233) (xy 280.937076 -308.419252) (xy 280.985931 -308.425184)
			(xy 281.033202 -308.438876) (xy 281.077664 -308.459974) (xy 281.118167 -308.48793) (xy 281.15366 -308.522022)
			(xy 281.183225 -308.561366) (xy 281.206096 -308.604943) (xy 281.22168 -308.651624) (xy 281.229575 -308.700201)
			(xy 281.23007 -308.724808) (xy 281.229903 -308.733095) (xy 281.568959 -308.733095) (xy 281.571645 -308.683521)
			(xy 281.582316 -308.635035) (xy 281.600691 -308.588914) (xy 281.626285 -308.546374) (xy 281.658424 -308.508534)
			(xy 281.696262 -308.476393) (xy 281.738802 -308.450797) (xy 281.784922 -308.43242) (xy 281.833407 -308.421747)
			(xy 281.88298 -308.419059) (xy 281.932336 -308.424427) (xy 281.980173 -308.437708) (xy 282.02523 -308.458554)
			(xy 282.066322 -308.486416) (xy 282.102364 -308.520558) (xy 282.132409 -308.560081) (xy 282.155663 -308.603945)
			(xy 282.171514 -308.650992) (xy 282.179545 -308.699985) (xy 282.18003 -308.724808) (xy 282.179854 -308.738991)
			(xy 282.177181 -308.767231) (xy 282.174696 -308.781196) (xy 282.172521 -308.795161) (xy 282.1751 -308.823295)
			(xy 282.18529 -308.849645) (xy 282.202312 -308.872194) (xy 282.224862 -308.889214) (xy 282.251213 -308.899402)
			(xy 282.279347 -308.901979) (xy 282.293314 -308.899814) (xy 282.30728 -308.89734) (xy 282.33552 -308.894666)
			(xy 282.349702 -308.89448) (xy 282.374523 -308.89498) (xy 282.423511 -308.903012) (xy 282.470554 -308.918863)
			(xy 282.514412 -308.942116) (xy 282.553932 -308.972158) (xy 282.58807 -309.008198) (xy 282.615927 -309.049286)
			(xy 282.636771 -309.09434) (xy 282.650051 -309.142173) (xy 282.655416 -309.191511) (xy 282.994169 -309.191511)
			(xy 282.999538 -309.142158) (xy 283.012821 -309.094323) (xy 283.033667 -309.049267) (xy 283.061529 -309.008178)
			(xy 283.09567 -308.972137) (xy 283.135193 -308.942095) (xy 283.179056 -308.918843) (xy 283.226103 -308.902994)
			(xy 283.275094 -308.894965) (xy 283.299916 -308.89448) (xy 283.314099 -308.894655) (xy 283.342339 -308.897328)
			(xy 283.356304 -308.899814) (xy 283.370269 -308.901986) (xy 283.398402 -308.899406) (xy 283.42475 -308.889215)
			(xy 283.447298 -308.872193) (xy 283.464318 -308.849645) (xy 283.474507 -308.823295) (xy 283.477085 -308.795162)
			(xy 283.474922 -308.781196) (xy 283.472449 -308.76723) (xy 283.469775 -308.73899) (xy 283.469588 -308.724808)
			(xy 283.470069 -308.699986) (xy 283.478099 -308.650997) (xy 283.49395 -308.603952) (xy 283.517202 -308.56009)
			(xy 283.547244 -308.520569) (xy 283.583284 -308.486429) (xy 283.624373 -308.458569) (xy 283.669428 -308.437723)
			(xy 283.717262 -308.424441) (xy 283.766614 -308.419073) (xy 283.816185 -308.42176) (xy 283.864668 -308.432432)
			(xy 283.910785 -308.450806) (xy 283.953323 -308.4764) (xy 283.991159 -308.508538) (xy 284.023298 -308.546374)
			(xy 284.048892 -308.588911) (xy 284.067267 -308.635029) (xy 284.077939 -308.683511) (xy 284.080178 -308.724808)
			(xy 284.419052 -308.724808) (xy 284.423012 -308.675754) (xy 284.434789 -308.62797) (xy 284.45408 -308.582694)
			(xy 284.480383 -308.541098) (xy 284.513018 -308.504261) (xy 284.551139 -308.473136) (xy 284.59376 -308.448529)
			(xy 284.639776 -308.431077) (xy 284.687995 -308.421233) (xy 284.73717 -308.419252) (xy 284.786025 -308.425184)
			(xy 284.833296 -308.438876) (xy 284.877758 -308.459974) (xy 284.918261 -308.48793) (xy 284.953754 -308.522022)
			(xy 284.983319 -308.561366) (xy 285.00619 -308.604943) (xy 285.021774 -308.651624) (xy 285.029669 -308.700201)
			(xy 285.030164 -308.724808) (xy 285.369012 -308.724808) (xy 285.372972 -308.675754) (xy 285.384749 -308.62797)
			(xy 285.40404 -308.582694) (xy 285.430343 -308.541098) (xy 285.462978 -308.504261) (xy 285.501099 -308.473136)
			(xy 285.54372 -308.448529) (xy 285.589736 -308.431077) (xy 285.637955 -308.421233) (xy 285.68713 -308.419252)
			(xy 285.735985 -308.425184) (xy 285.783256 -308.438876) (xy 285.827718 -308.459974) (xy 285.868221 -308.48793)
			(xy 285.903714 -308.522022) (xy 285.933279 -308.561366) (xy 285.95615 -308.604943) (xy 285.971734 -308.651624)
			(xy 285.979629 -308.700201) (xy 285.980124 -308.724808) (xy 286.318972 -308.724808) (xy 286.322932 -308.675754)
			(xy 286.334709 -308.62797) (xy 286.354 -308.582694) (xy 286.380303 -308.541098) (xy 286.412938 -308.504261)
			(xy 286.451059 -308.473136) (xy 286.49368 -308.448529) (xy 286.539696 -308.431077) (xy 286.587915 -308.421233)
			(xy 286.63709 -308.419252) (xy 286.685945 -308.425184) (xy 286.733216 -308.438876) (xy 286.777678 -308.459974)
			(xy 286.818181 -308.48793) (xy 286.853674 -308.522022) (xy 286.883239 -308.561366) (xy 286.90611 -308.604943)
			(xy 286.921694 -308.651624) (xy 286.929589 -308.700201) (xy 286.930084 -308.724808) (xy 286.929917 -308.733104)
			(xy 287.268946 -308.733104) (xy 287.27163 -308.683528) (xy 287.2823 -308.635039) (xy 287.300675 -308.588915)
			(xy 287.326269 -308.546371) (xy 287.358409 -308.508529) (xy 287.396249 -308.476386) (xy 287.43879 -308.450787)
			(xy 287.484912 -308.432409) (xy 287.5334 -308.421734) (xy 287.582976 -308.419045) (xy 287.632334 -308.424412)
			(xy 287.680174 -308.437694) (xy 287.725234 -308.458541) (xy 287.766328 -308.486403) (xy 287.802373 -308.520547)
			(xy 287.83242 -308.560072) (xy 287.855675 -308.603938) (xy 287.871527 -308.650988) (xy 287.879559 -308.699983)
			(xy 287.880044 -308.724808) (xy 287.879868 -308.738991) (xy 287.877195 -308.767231) (xy 287.87471 -308.781196)
			(xy 287.872424 -308.793642) (xy 287.87979 -308.817264) (xy 287.95726 -308.894734) (xy 287.980882 -308.9021)
			(xy 287.993328 -308.899814) (xy 288.007294 -308.897338) (xy 288.035533 -308.894666) (xy 288.049716 -308.89448)
			(xy 288.063963 -308.894645) (xy 288.092331 -308.897316) (xy 288.106358 -308.899814) (xy 288.11855 -308.9021)
			(xy 288.14268 -308.894734) (xy 288.219896 -308.817518) (xy 288.227262 -308.793642) (xy 288.224976 -308.781196)
			(xy 288.222503 -308.76723) (xy 288.219829 -308.73899) (xy 288.219642 -308.724808) (xy 288.220069 -308.699987)
			(xy 288.228099 -308.650999) (xy 288.243948 -308.603956) (xy 288.267198 -308.560096) (xy 288.297238 -308.520575)
			(xy 288.333276 -308.486435) (xy 288.374363 -308.458575) (xy 288.419415 -308.437728) (xy 288.467246 -308.424444)
			(xy 288.516596 -308.419074) (xy 288.566165 -308.421758) (xy 288.614647 -308.432425) (xy 288.660764 -308.450796)
			(xy 288.703302 -308.476385) (xy 288.74114 -308.508519) (xy 288.773281 -308.54635) (xy 288.798878 -308.588884)
			(xy 288.817258 -308.634997) (xy 288.827935 -308.683477) (xy 288.83018 -308.724808) (xy 290.119066 -308.724808)
			(xy 290.123026 -308.675754) (xy 290.134803 -308.62797) (xy 290.154094 -308.582694) (xy 290.180397 -308.541098)
			(xy 290.213032 -308.504261) (xy 290.251153 -308.473136) (xy 290.293774 -308.448529) (xy 290.33979 -308.431077)
			(xy 290.388009 -308.421233) (xy 290.437184 -308.419252) (xy 290.486039 -308.425184) (xy 290.53331 -308.438876)
			(xy 290.577772 -308.459974) (xy 290.618275 -308.48793) (xy 290.653768 -308.522022) (xy 290.683333 -308.561366)
			(xy 290.706204 -308.604943) (xy 290.721788 -308.651624) (xy 290.729683 -308.700201) (xy 290.730178 -308.724808)
			(xy 290.730012 -308.733072) (xy 292.019091 -308.733072) (xy 292.02178 -308.683505) (xy 292.032452 -308.635026)
			(xy 292.050828 -308.588912) (xy 292.076421 -308.546378) (xy 292.108558 -308.508546) (xy 292.146393 -308.47641)
			(xy 292.188928 -308.45082) (xy 292.235043 -308.432447) (xy 292.283523 -308.421777) (xy 292.33309 -308.419091)
			(xy 292.382439 -308.42446) (xy 292.430269 -308.437741) (xy 292.475321 -308.458586) (xy 292.516406 -308.486444)
			(xy 292.552444 -308.520583) (xy 292.582484 -308.560102) (xy 292.605734 -308.60396) (xy 292.621583 -308.651002)
			(xy 292.629613 -308.699988) (xy 292.630098 -308.724808) (xy 292.629923 -308.738991) (xy 292.62725 -308.767231)
			(xy 292.624764 -308.781196) (xy 292.622478 -308.793642) (xy 292.629844 -308.817264) (xy 292.707314 -308.894734)
			(xy 292.730936 -308.9021) (xy 292.743382 -308.899814) (xy 292.757347 -308.89733) (xy 292.785587 -308.894663)
			(xy 292.79977 -308.89448) (xy 292.813953 -308.894661) (xy 292.842193 -308.89733) (xy 292.856158 -308.899814)
			(xy 292.868604 -308.9021) (xy 292.892226 -308.894734) (xy 292.969696 -308.817264) (xy 292.977062 -308.793642)
			(xy 292.974776 -308.781196) (xy 292.972303 -308.76723) (xy 292.969629 -308.73899) (xy 292.969442 -308.724808)
			(xy 292.969964 -308.699553) (xy 292.978277 -308.649731) (xy 292.994678 -308.601957) (xy 293.018719 -308.557534)
			(xy 293.049743 -308.517674) (xy 293.086905 -308.483464) (xy 293.129191 -308.455838) (xy 293.175447 -308.435548)
			(xy 293.224412 -308.423148) (xy 293.27475 -308.418977) (xy 293.325088 -308.423148) (xy 293.374053 -308.435548)
			(xy 293.420309 -308.455838) (xy 293.462595 -308.483464) (xy 293.499757 -308.517674) (xy 293.530781 -308.557534)
			(xy 293.554822 -308.601957) (xy 293.571223 -308.649731) (xy 293.579536 -308.699553) (xy 293.580058 -308.724808)
			(xy 293.579883 -308.738991) (xy 293.57721 -308.767231) (xy 293.574724 -308.781196) (xy 293.572438 -308.793642)
			(xy 293.579804 -308.817264) (xy 293.657274 -308.894734) (xy 293.680896 -308.9021) (xy 293.693342 -308.899814)
			(xy 293.707308 -308.897336) (xy 293.735547 -308.894665) (xy 293.74973 -308.89448) (xy 293.763913 -308.894653)
			(xy 293.792153 -308.897327) (xy 293.806118 -308.899814) (xy 293.818564 -308.9021) (xy 293.842186 -308.894734)
			(xy 293.919656 -308.817264) (xy 293.927022 -308.793642) (xy 293.924736 -308.781196) (xy 293.922263 -308.76723)
			(xy 293.919589 -308.73899) (xy 293.919402 -308.724808) (xy 293.919869 -308.699987) (xy 293.927899 -308.650997)
			(xy 293.943749 -308.603953) (xy 293.967001 -308.560092) (xy 293.997043 -308.520571) (xy 294.033082 -308.48643)
			(xy 294.07417 -308.45857) (xy 294.119225 -308.437724) (xy 294.167058 -308.424442) (xy 294.216409 -308.419073)
			(xy 294.26598 -308.42176) (xy 294.314462 -308.43243) (xy 294.36058 -308.450803) (xy 294.403118 -308.476396)
			(xy 294.440954 -308.508533) (xy 294.473094 -308.546368) (xy 294.498689 -308.588904) (xy 294.517065 -308.635021)
			(xy 294.527738 -308.683503) (xy 294.529965 -308.724554) (xy 294.868866 -308.724554) (xy 294.872826 -308.6755)
			(xy 294.884603 -308.627716) (xy 294.903894 -308.58244) (xy 294.930197 -308.540844) (xy 294.962832 -308.504007)
			(xy 295.000953 -308.472882) (xy 295.043574 -308.448275) (xy 295.08959 -308.430823) (xy 295.137809 -308.420979)
			(xy 295.186984 -308.418998) (xy 295.235839 -308.42493) (xy 295.28311 -308.438622) (xy 295.327572 -308.45972)
			(xy 295.368075 -308.487676) (xy 295.403568 -308.521768) (xy 295.433133 -308.561112) (xy 295.456004 -308.604689)
			(xy 295.471588 -308.65137) (xy 295.479483 -308.699947) (xy 295.479978 -308.724554) (xy 295.479973 -308.724808)
			(xy 295.81908 -308.724808) (xy 295.82304 -308.675754) (xy 295.834817 -308.62797) (xy 295.854108 -308.582694)
			(xy 295.880411 -308.541098) (xy 295.913046 -308.504261) (xy 295.951167 -308.473136) (xy 295.993788 -308.448529)
			(xy 296.039804 -308.431077) (xy 296.088023 -308.421233) (xy 296.137198 -308.419252) (xy 296.186053 -308.425184)
			(xy 296.233324 -308.438876) (xy 296.277786 -308.459974) (xy 296.318289 -308.48793) (xy 296.353782 -308.522022)
			(xy 296.383347 -308.561366) (xy 296.406218 -308.604943) (xy 296.421802 -308.651624) (xy 296.429697 -308.700201)
			(xy 296.430192 -308.724808) (xy 296.76904 -308.724808) (xy 296.773 -308.675754) (xy 296.784777 -308.62797)
			(xy 296.804068 -308.582694) (xy 296.830371 -308.541098) (xy 296.863006 -308.504261) (xy 296.901127 -308.473136)
			(xy 296.943748 -308.448529) (xy 296.989764 -308.431077) (xy 297.037983 -308.421233) (xy 297.087158 -308.419252)
			(xy 297.136013 -308.425184) (xy 297.183284 -308.438876) (xy 297.227746 -308.459974) (xy 297.268249 -308.48793)
			(xy 297.303742 -308.522022) (xy 297.333307 -308.561366) (xy 297.356178 -308.604943) (xy 297.371762 -308.651624)
			(xy 297.379657 -308.700201) (xy 297.380152 -308.724808) (xy 297.719 -308.724808) (xy 297.72296 -308.675754)
			(xy 297.734737 -308.62797) (xy 297.754028 -308.582694) (xy 297.780331 -308.541098) (xy 297.812966 -308.504261)
			(xy 297.851087 -308.473136) (xy 297.893708 -308.448529) (xy 297.939724 -308.431077) (xy 297.987943 -308.421233)
			(xy 298.037118 -308.419252) (xy 298.085973 -308.425184) (xy 298.133244 -308.438876) (xy 298.177706 -308.459974)
			(xy 298.218209 -308.48793) (xy 298.253702 -308.522022) (xy 298.283267 -308.561366) (xy 298.306138 -308.604943)
			(xy 298.321722 -308.651624) (xy 298.329617 -308.700201) (xy 298.330112 -308.724808) (xy 298.66896 -308.724808)
			(xy 298.67292 -308.675754) (xy 298.684697 -308.62797) (xy 298.703988 -308.582694) (xy 298.730291 -308.541098)
			(xy 298.762926 -308.504261) (xy 298.801047 -308.473136) (xy 298.843668 -308.448529) (xy 298.889684 -308.431077)
			(xy 298.937903 -308.421233) (xy 298.987078 -308.419252) (xy 299.035933 -308.425184) (xy 299.083204 -308.438876)
			(xy 299.127666 -308.459974) (xy 299.168169 -308.48793) (xy 299.203662 -308.522022) (xy 299.233227 -308.561366)
			(xy 299.256098 -308.604943) (xy 299.271682 -308.651624) (xy 299.279577 -308.700201) (xy 299.280072 -308.724808)
			(xy 299.61892 -308.724808) (xy 299.62288 -308.675754) (xy 299.634657 -308.62797) (xy 299.653948 -308.582694)
			(xy 299.680251 -308.541098) (xy 299.712886 -308.504261) (xy 299.751007 -308.473136) (xy 299.793628 -308.448529)
			(xy 299.839644 -308.431077) (xy 299.887863 -308.421233) (xy 299.937038 -308.419252) (xy 299.985893 -308.425184)
			(xy 300.033164 -308.438876) (xy 300.077626 -308.459974) (xy 300.118129 -308.48793) (xy 300.153622 -308.522022)
			(xy 300.183187 -308.561366) (xy 300.206058 -308.604943) (xy 300.221642 -308.651624) (xy 300.229537 -308.700201)
			(xy 300.230032 -308.724808) (xy 300.569134 -308.724808) (xy 300.573094 -308.675754) (xy 300.584871 -308.62797)
			(xy 300.604162 -308.582694) (xy 300.630465 -308.541098) (xy 300.6631 -308.504261) (xy 300.701221 -308.473136)
			(xy 300.743842 -308.448529) (xy 300.789858 -308.431077) (xy 300.838077 -308.421233) (xy 300.887252 -308.419252)
			(xy 300.936107 -308.425184) (xy 300.983378 -308.438876) (xy 301.02784 -308.459974) (xy 301.068343 -308.48793)
			(xy 301.103836 -308.522022) (xy 301.133401 -308.561366) (xy 301.156272 -308.604943) (xy 301.171856 -308.651624)
			(xy 301.179751 -308.700201) (xy 301.180246 -308.724808) (xy 301.519094 -308.724808) (xy 301.523054 -308.675754)
			(xy 301.534831 -308.62797) (xy 301.554122 -308.582694) (xy 301.580425 -308.541098) (xy 301.61306 -308.504261)
			(xy 301.651181 -308.473136) (xy 301.693802 -308.448529) (xy 301.739818 -308.431077) (xy 301.788037 -308.421233)
			(xy 301.837212 -308.419252) (xy 301.886067 -308.425184) (xy 301.933338 -308.438876) (xy 301.9778 -308.459974)
			(xy 302.018303 -308.48793) (xy 302.053796 -308.522022) (xy 302.083361 -308.561366) (xy 302.106232 -308.604943)
			(xy 302.121816 -308.651624) (xy 302.129711 -308.700201) (xy 302.130206 -308.724808) (xy 302.469054 -308.724808)
			(xy 302.473014 -308.675754) (xy 302.484791 -308.62797) (xy 302.504082 -308.582694) (xy 302.530385 -308.541098)
			(xy 302.56302 -308.504261) (xy 302.601141 -308.473136) (xy 302.643762 -308.448529) (xy 302.689778 -308.431077)
			(xy 302.737997 -308.421233) (xy 302.787172 -308.419252) (xy 302.836027 -308.425184) (xy 302.883298 -308.438876)
			(xy 302.92776 -308.459974) (xy 302.968263 -308.48793) (xy 303.003756 -308.522022) (xy 303.033321 -308.561366)
			(xy 303.056192 -308.604943) (xy 303.071776 -308.651624) (xy 303.079671 -308.700201) (xy 303.080166 -308.724808)
			(xy 303.419014 -308.724808) (xy 303.422974 -308.675754) (xy 303.434751 -308.62797) (xy 303.454042 -308.582694)
			(xy 303.480345 -308.541098) (xy 303.51298 -308.504261) (xy 303.551101 -308.473136) (xy 303.593722 -308.448529)
			(xy 303.639738 -308.431077) (xy 303.687957 -308.421233) (xy 303.737132 -308.419252) (xy 303.785987 -308.425184)
			(xy 303.833258 -308.438876) (xy 303.87772 -308.459974) (xy 303.918223 -308.48793) (xy 303.953716 -308.522022)
			(xy 303.983281 -308.561366) (xy 304.006152 -308.604943) (xy 304.021736 -308.651624) (xy 304.029631 -308.700201)
			(xy 304.030126 -308.724808) (xy 304.029631 -308.749415) (xy 304.021736 -308.797992) (xy 304.006152 -308.844673)
			(xy 303.983281 -308.88825) (xy 303.953716 -308.927594) (xy 303.918223 -308.961686) (xy 303.87772 -308.989642)
			(xy 303.833258 -309.01074) (xy 303.785987 -309.024432) (xy 303.737132 -309.030364) (xy 303.687957 -309.028383)
			(xy 303.639738 -309.018539) (xy 303.593722 -309.001087) (xy 303.551101 -308.97648) (xy 303.51298 -308.945355)
			(xy 303.480345 -308.908518) (xy 303.454042 -308.866922) (xy 303.434751 -308.821646) (xy 303.422974 -308.773862)
			(xy 303.419014 -308.724808) (xy 303.080166 -308.724808) (xy 303.079671 -308.749415) (xy 303.071776 -308.797992)
			(xy 303.056192 -308.844673) (xy 303.033321 -308.88825) (xy 303.003756 -308.927594) (xy 302.968263 -308.961686)
			(xy 302.92776 -308.989642) (xy 302.883298 -309.01074) (xy 302.836027 -309.024432) (xy 302.787172 -309.030364)
			(xy 302.737997 -309.028383) (xy 302.689778 -309.018539) (xy 302.643762 -309.001087) (xy 302.601141 -308.97648)
			(xy 302.56302 -308.945355) (xy 302.530385 -308.908518) (xy 302.504082 -308.866922) (xy 302.484791 -308.821646)
			(xy 302.473014 -308.773862) (xy 302.469054 -308.724808) (xy 302.130206 -308.724808) (xy 302.129711 -308.749415)
			(xy 302.121816 -308.797992) (xy 302.106232 -308.844673) (xy 302.083361 -308.88825) (xy 302.053796 -308.927594)
			(xy 302.018303 -308.961686) (xy 301.9778 -308.989642) (xy 301.933338 -309.01074) (xy 301.886067 -309.024432)
			(xy 301.837212 -309.030364) (xy 301.788037 -309.028383) (xy 301.739818 -309.018539) (xy 301.693802 -309.001087)
			(xy 301.651181 -308.97648) (xy 301.61306 -308.945355) (xy 301.580425 -308.908518) (xy 301.554122 -308.866922)
			(xy 301.534831 -308.821646) (xy 301.523054 -308.773862) (xy 301.519094 -308.724808) (xy 301.180246 -308.724808)
			(xy 301.179751 -308.749415) (xy 301.171856 -308.797992) (xy 301.156272 -308.844673) (xy 301.133401 -308.88825)
			(xy 301.103836 -308.927594) (xy 301.068343 -308.961686) (xy 301.02784 -308.989642) (xy 300.983378 -309.01074)
			(xy 300.936107 -309.024432) (xy 300.887252 -309.030364) (xy 300.838077 -309.028383) (xy 300.789858 -309.018539)
			(xy 300.743842 -309.001087) (xy 300.701221 -308.97648) (xy 300.6631 -308.945355) (xy 300.630465 -308.908518)
			(xy 300.604162 -308.866922) (xy 300.584871 -308.821646) (xy 300.573094 -308.773862) (xy 300.569134 -308.724808)
			(xy 300.230032 -308.724808) (xy 300.229537 -308.749415) (xy 300.221642 -308.797992) (xy 300.206058 -308.844673)
			(xy 300.183187 -308.88825) (xy 300.153622 -308.927594) (xy 300.118129 -308.961686) (xy 300.077626 -308.989642)
			(xy 300.033164 -309.01074) (xy 299.985893 -309.024432) (xy 299.937038 -309.030364) (xy 299.887863 -309.028383)
			(xy 299.839644 -309.018539) (xy 299.793628 -309.001087) (xy 299.751007 -308.97648) (xy 299.712886 -308.945355)
			(xy 299.680251 -308.908518) (xy 299.653948 -308.866922) (xy 299.634657 -308.821646) (xy 299.62288 -308.773862)
			(xy 299.61892 -308.724808) (xy 299.280072 -308.724808) (xy 299.279577 -308.749415) (xy 299.271682 -308.797992)
			(xy 299.256098 -308.844673) (xy 299.233227 -308.88825) (xy 299.203662 -308.927594) (xy 299.168169 -308.961686)
			(xy 299.127666 -308.989642) (xy 299.083204 -309.01074) (xy 299.035933 -309.024432) (xy 298.987078 -309.030364)
			(xy 298.937903 -309.028383) (xy 298.889684 -309.018539) (xy 298.843668 -309.001087) (xy 298.801047 -308.97648)
			(xy 298.762926 -308.945355) (xy 298.730291 -308.908518) (xy 298.703988 -308.866922) (xy 298.684697 -308.821646)
			(xy 298.67292 -308.773862) (xy 298.66896 -308.724808) (xy 298.330112 -308.724808) (xy 298.329617 -308.749415)
			(xy 298.321722 -308.797992) (xy 298.306138 -308.844673) (xy 298.283267 -308.88825) (xy 298.253702 -308.927594)
			(xy 298.218209 -308.961686) (xy 298.177706 -308.989642) (xy 298.133244 -309.01074) (xy 298.085973 -309.024432)
			(xy 298.037118 -309.030364) (xy 297.987943 -309.028383) (xy 297.939724 -309.018539) (xy 297.893708 -309.001087)
			(xy 297.851087 -308.97648) (xy 297.812966 -308.945355) (xy 297.780331 -308.908518) (xy 297.754028 -308.866922)
			(xy 297.734737 -308.821646) (xy 297.72296 -308.773862) (xy 297.719 -308.724808) (xy 297.380152 -308.724808)
			(xy 297.379657 -308.749415) (xy 297.371762 -308.797992) (xy 297.356178 -308.844673) (xy 297.333307 -308.88825)
			(xy 297.303742 -308.927594) (xy 297.268249 -308.961686) (xy 297.227746 -308.989642) (xy 297.183284 -309.01074)
			(xy 297.136013 -309.024432) (xy 297.087158 -309.030364) (xy 297.037983 -309.028383) (xy 296.989764 -309.018539)
			(xy 296.943748 -309.001087) (xy 296.901127 -308.97648) (xy 296.863006 -308.945355) (xy 296.830371 -308.908518)
			(xy 296.804068 -308.866922) (xy 296.784777 -308.821646) (xy 296.773 -308.773862) (xy 296.76904 -308.724808)
			(xy 296.430192 -308.724808) (xy 296.429697 -308.749415) (xy 296.421802 -308.797992) (xy 296.406218 -308.844673)
			(xy 296.383347 -308.88825) (xy 296.353782 -308.927594) (xy 296.318289 -308.961686) (xy 296.277786 -308.989642)
			(xy 296.233324 -309.01074) (xy 296.186053 -309.024432) (xy 296.137198 -309.030364) (xy 296.088023 -309.028383)
			(xy 296.039804 -309.018539) (xy 295.993788 -309.001087) (xy 295.951167 -308.97648) (xy 295.913046 -308.945355)
			(xy 295.880411 -308.908518) (xy 295.854108 -308.866922) (xy 295.834817 -308.821646) (xy 295.82304 -308.773862)
			(xy 295.81908 -308.724808) (xy 295.479973 -308.724808) (xy 295.479483 -308.749161) (xy 295.471588 -308.797738)
			(xy 295.456004 -308.844419) (xy 295.433133 -308.887996) (xy 295.403568 -308.92734) (xy 295.368075 -308.961432)
			(xy 295.327572 -308.989388) (xy 295.28311 -309.010486) (xy 295.235839 -309.024178) (xy 295.186984 -309.03011)
			(xy 295.137809 -309.028129) (xy 295.08959 -309.018285) (xy 295.043574 -309.000833) (xy 295.000953 -308.976226)
			(xy 294.962832 -308.945101) (xy 294.930197 -308.908264) (xy 294.903894 -308.866668) (xy 294.884603 -308.821392)
			(xy 294.872826 -308.773608) (xy 294.868866 -308.724554) (xy 294.529965 -308.724554) (xy 294.530427 -308.733073)
			(xy 294.525061 -308.782425) (xy 294.511782 -308.830259) (xy 294.490939 -308.875314) (xy 294.463081 -308.916404)
			(xy 294.428943 -308.952445) (xy 294.389423 -308.982489) (xy 294.345564 -309.005744) (xy 294.29852 -309.021596)
			(xy 294.249531 -309.029629) (xy 294.22471 -309.030116) (xy 294.210527 -309.029938) (xy 294.182287 -309.027267)
			(xy 294.168322 -309.024782) (xy 294.155876 -309.022496) (xy 294.132254 -309.029862) (xy 294.054784 -309.107332)
			(xy 294.047418 -309.130954) (xy 294.049704 -309.1434) (xy 294.052177 -309.157367) (xy 294.054851 -309.185606)
			(xy 294.055038 -309.199788) (xy 294.054516 -309.225043) (xy 294.046203 -309.274865) (xy 294.029802 -309.322639)
			(xy 294.005761 -309.367062) (xy 293.974737 -309.406922) (xy 293.937575 -309.441132) (xy 293.895289 -309.468758)
			(xy 293.849033 -309.489048) (xy 293.800068 -309.501448) (xy 293.74973 -309.505619) (xy 293.699392 -309.501448)
			(xy 293.650427 -309.489048) (xy 293.604171 -309.468758) (xy 293.561885 -309.441132) (xy 293.524723 -309.406922)
			(xy 293.493699 -309.367062) (xy 293.469658 -309.322639) (xy 293.453257 -309.274865) (xy 293.444944 -309.225043)
			(xy 293.444422 -309.199788) (xy 293.444596 -309.185605) (xy 293.44727 -309.157365) (xy 293.449756 -309.1434)
			(xy 293.452042 -309.130954) (xy 293.444676 -309.107332) (xy 293.367206 -309.029862) (xy 293.343584 -309.022496)
			(xy 293.331138 -309.024782) (xy 293.317173 -309.027263) (xy 293.288933 -309.029932) (xy 293.27475 -309.030116)
			(xy 293.260567 -309.029932) (xy 293.232327 -309.027265) (xy 293.218362 -309.024782) (xy 293.205916 -309.022496)
			(xy 293.182294 -309.029862) (xy 293.104824 -309.107332) (xy 293.097458 -309.130954) (xy 293.099744 -309.1434)
			(xy 293.102216 -309.157367) (xy 293.104891 -309.185606) (xy 293.105078 -309.199788) (xy 293.104556 -309.225043)
			(xy 293.096243 -309.274865) (xy 293.079842 -309.322639) (xy 293.055801 -309.367062) (xy 293.024777 -309.406922)
			(xy 292.987615 -309.441132) (xy 292.945329 -309.468758) (xy 292.899073 -309.489048) (xy 292.850108 -309.501448)
			(xy 292.79977 -309.505619) (xy 292.749432 -309.501448) (xy 292.700467 -309.489048) (xy 292.654211 -309.468758)
			(xy 292.611925 -309.441132) (xy 292.574763 -309.406922) (xy 292.543739 -309.367062) (xy 292.519698 -309.322639)
			(xy 292.503297 -309.274865) (xy 292.494984 -309.225043) (xy 292.494462 -309.199788) (xy 292.494637 -309.185605)
			(xy 292.49731 -309.157365) (xy 292.499796 -309.1434) (xy 292.502082 -309.130954) (xy 292.494716 -309.107332)
			(xy 292.417246 -309.029862) (xy 292.393624 -309.022496) (xy 292.381178 -309.024782) (xy 292.367212 -309.027257)
			(xy 292.338972 -309.02993) (xy 292.32479 -309.030116) (xy 292.29997 -309.029611) (xy 292.250984 -309.021579)
			(xy 292.203943 -309.005727) (xy 292.160086 -308.982474) (xy 292.120569 -308.952432) (xy 292.086433 -308.916392)
			(xy 292.058577 -308.875305) (xy 292.037735 -308.830252) (xy 292.024456 -308.782421) (xy 292.019091 -308.733072)
			(xy 290.730012 -308.733072) (xy 290.729683 -308.749415) (xy 290.721788 -308.797992) (xy 290.706204 -308.844673)
			(xy 290.683333 -308.88825) (xy 290.653768 -308.927594) (xy 290.618275 -308.961686) (xy 290.577772 -308.989642)
			(xy 290.53331 -309.01074) (xy 290.486039 -309.024432) (xy 290.437184 -309.030364) (xy 290.388009 -309.028383)
			(xy 290.33979 -309.018539) (xy 290.293774 -309.001087) (xy 290.251153 -308.97648) (xy 290.213032 -308.945355)
			(xy 290.180397 -308.908518) (xy 290.154094 -308.866922) (xy 290.134803 -308.821646) (xy 290.123026 -308.773862)
			(xy 290.119066 -308.724808) (xy 288.83018 -308.724808) (xy 288.830628 -308.733046) (xy 288.825267 -308.782397)
			(xy 288.811992 -308.830231) (xy 288.791154 -308.875287) (xy 288.763301 -308.916378) (xy 288.729168 -308.952423)
			(xy 288.689653 -308.98247) (xy 288.645798 -309.005729) (xy 288.598757 -309.021587) (xy 288.549771 -309.029626)
			(xy 288.52495 -309.030116) (xy 288.510703 -309.029949) (xy 288.482336 -309.027276) (xy 288.468308 -309.024782)
			(xy 288.456116 -309.022496) (xy 288.431986 -309.029862) (xy 288.35477 -309.107078) (xy 288.347404 -309.130954)
			(xy 288.34969 -309.1434) (xy 288.352162 -309.157367) (xy 288.354837 -309.185606) (xy 288.355024 -309.199788)
			(xy 288.354502 -309.225043) (xy 288.346189 -309.274865) (xy 288.329788 -309.322639) (xy 288.305747 -309.367062)
			(xy 288.274723 -309.406922) (xy 288.237561 -309.441132) (xy 288.195275 -309.468758) (xy 288.149019 -309.489048)
			(xy 288.100054 -309.501448) (xy 288.049716 -309.505619) (xy 287.999378 -309.501448) (xy 287.950413 -309.489048)
			(xy 287.904157 -309.468758) (xy 287.861871 -309.441132) (xy 287.824709 -309.406922) (xy 287.793685 -309.367062)
			(xy 287.769644 -309.322639) (xy 287.753243 -309.274865) (xy 287.74493 -309.225043) (xy 287.744408 -309.199788)
			(xy 287.744583 -309.185605) (xy 287.747256 -309.157365) (xy 287.749742 -309.1434) (xy 287.752028 -309.130954)
			(xy 287.744662 -309.107332) (xy 287.667192 -309.029862) (xy 287.64357 -309.022496) (xy 287.631124 -309.024782)
			(xy 287.617159 -309.027265) (xy 287.588919 -309.029932) (xy 287.574736 -309.030116) (xy 287.549911 -309.029661)
			(xy 287.500915 -309.021634) (xy 287.453864 -309.005786) (xy 287.409996 -308.982535) (xy 287.370468 -308.952492)
			(xy 287.336321 -308.91645) (xy 287.308454 -308.875359) (xy 287.287604 -308.8303) (xy 287.274317 -308.782462)
			(xy 287.268946 -308.733104) (xy 286.929917 -308.733104) (xy 286.929589 -308.749415) (xy 286.921694 -308.797992)
			(xy 286.90611 -308.844673) (xy 286.883239 -308.88825) (xy 286.853674 -308.927594) (xy 286.818181 -308.961686)
			(xy 286.777678 -308.989642) (xy 286.733216 -309.01074) (xy 286.685945 -309.024432) (xy 286.63709 -309.030364)
			(xy 286.587915 -309.028383) (xy 286.539696 -309.018539) (xy 286.49368 -309.001087) (xy 286.451059 -308.97648)
			(xy 286.412938 -308.945355) (xy 286.380303 -308.908518) (xy 286.354 -308.866922) (xy 286.334709 -308.821646)
			(xy 286.322932 -308.773862) (xy 286.318972 -308.724808) (xy 285.980124 -308.724808) (xy 285.979629 -308.749415)
			(xy 285.971734 -308.797992) (xy 285.95615 -308.844673) (xy 285.933279 -308.88825) (xy 285.903714 -308.927594)
			(xy 285.868221 -308.961686) (xy 285.827718 -308.989642) (xy 285.783256 -309.01074) (xy 285.735985 -309.024432)
			(xy 285.68713 -309.030364) (xy 285.637955 -309.028383) (xy 285.589736 -309.018539) (xy 285.54372 -309.001087)
			(xy 285.501099 -308.97648) (xy 285.462978 -308.945355) (xy 285.430343 -308.908518) (xy 285.40404 -308.866922)
			(xy 285.384749 -308.821646) (xy 285.372972 -308.773862) (xy 285.369012 -308.724808) (xy 285.030164 -308.724808)
			(xy 285.029669 -308.749415) (xy 285.021774 -308.797992) (xy 285.00619 -308.844673) (xy 284.983319 -308.88825)
			(xy 284.953754 -308.927594) (xy 284.918261 -308.961686) (xy 284.877758 -308.989642) (xy 284.833296 -309.01074)
			(xy 284.786025 -309.024432) (xy 284.73717 -309.030364) (xy 284.687995 -309.028383) (xy 284.639776 -309.018539)
			(xy 284.59376 -309.001087) (xy 284.551139 -308.97648) (xy 284.513018 -308.945355) (xy 284.480383 -308.908518)
			(xy 284.45408 -308.866922) (xy 284.434789 -308.821646) (xy 284.423012 -308.773862) (xy 284.419052 -308.724808)
			(xy 284.080178 -308.724808) (xy 284.080627 -308.733082) (xy 284.075259 -308.782434) (xy 284.061978 -308.830268)
			(xy 284.041133 -308.875323) (xy 284.013274 -308.916413) (xy 283.979134 -308.952453) (xy 283.939613 -308.982496)
			(xy 283.895752 -309.005749) (xy 283.848707 -309.0216) (xy 283.799718 -309.02963) (xy 283.774896 -309.030116)
			(xy 283.760713 -309.02994) (xy 283.732473 -309.027267) (xy 283.718508 -309.024782) (xy 283.704541 -309.022628)
			(xy 283.67641 -309.025205) (xy 283.650063 -309.035393) (xy 283.627516 -309.052411) (xy 283.610496 -309.074957)
			(xy 283.600306 -309.101304) (xy 283.597727 -309.129435) (xy 283.59989 -309.1434) (xy 283.602362 -309.157367)
			(xy 283.605037 -309.185606) (xy 283.605224 -309.199788) (xy 283.604735 -309.22461) (xy 283.596705 -309.273601)
			(xy 283.580855 -309.320648) (xy 283.557602 -309.36451) (xy 283.52756 -309.404033) (xy 283.491519 -309.438174)
			(xy 283.450429 -309.466035) (xy 283.405373 -309.486881) (xy 283.357538 -309.500163) (xy 283.308185 -309.505531)
			(xy 283.258613 -309.502843) (xy 283.210129 -309.492172) (xy 283.16401 -309.473796) (xy 283.121472 -309.448202)
			(xy 283.083635 -309.416062) (xy 283.051496 -309.378225) (xy 283.025902 -309.335686) (xy 283.007527 -309.289567)
			(xy 282.996856 -309.241083) (xy 282.994169 -309.191511) (xy 282.655416 -309.191511) (xy 282.655417 -309.191524)
			(xy 282.652729 -309.241092) (xy 282.642056 -309.289573) (xy 282.623681 -309.335689) (xy 282.598087 -309.378224)
			(xy 282.565949 -309.416059) (xy 282.528113 -309.448195) (xy 282.485577 -309.473787) (xy 282.43946 -309.49216)
			(xy 282.390979 -309.50283) (xy 282.34141 -309.505517) (xy 282.292059 -309.500148) (xy 282.244227 -309.486866)
			(xy 282.199174 -309.466021) (xy 282.158087 -309.438161) (xy 282.122049 -309.404021) (xy 282.092008 -309.364501)
			(xy 282.068757 -309.320641) (xy 282.052908 -309.273597) (xy 282.044879 -309.224609) (xy 282.044394 -309.199788)
			(xy 282.044569 -309.185605) (xy 282.047242 -309.157365) (xy 282.049728 -309.1434) (xy 282.051879 -309.129433)
			(xy 282.0493 -309.101304) (xy 282.039111 -309.074958) (xy 282.022094 -309.052412) (xy 281.999549 -309.035393)
			(xy 281.973204 -309.025202) (xy 281.945075 -309.022621) (xy 281.93111 -309.024782) (xy 281.917143 -309.027253)
			(xy 281.888904 -309.029928) (xy 281.874722 -309.030116) (xy 281.849899 -309.029646) (xy 281.800906 -309.021617)
			(xy 281.753857 -309.005768) (xy 281.709993 -308.982516) (xy 281.670468 -308.952474) (xy 281.636324 -308.916433)
			(xy 281.608461 -308.875342) (xy 281.587613 -308.830286) (xy 281.574329 -308.78245) (xy 281.568959 -308.733095)
			(xy 281.229903 -308.733095) (xy 281.229575 -308.749415) (xy 281.22168 -308.797992) (xy 281.206096 -308.844673)
			(xy 281.183225 -308.88825) (xy 281.15366 -308.927594) (xy 281.118167 -308.961686) (xy 281.077664 -308.989642)
			(xy 281.033202 -309.01074) (xy 280.985931 -309.024432) (xy 280.937076 -309.030364) (xy 280.887901 -309.028383)
			(xy 280.839682 -309.018539) (xy 280.793666 -309.001087) (xy 280.751045 -308.97648) (xy 280.712924 -308.945355)
			(xy 280.680289 -308.908518) (xy 280.653986 -308.866922) (xy 280.634695 -308.821646) (xy 280.622918 -308.773862)
			(xy 280.618958 -308.724808) (xy 280.28011 -308.724808) (xy 280.279615 -308.749415) (xy 280.27172 -308.797992)
			(xy 280.256136 -308.844673) (xy 280.233265 -308.88825) (xy 280.2037 -308.927594) (xy 280.168207 -308.961686)
			(xy 280.127704 -308.989642) (xy 280.083242 -309.01074) (xy 280.035971 -309.024432) (xy 279.987116 -309.030364)
			(xy 279.937941 -309.028383) (xy 279.889722 -309.018539) (xy 279.843706 -309.001087) (xy 279.801085 -308.97648)
			(xy 279.762964 -308.945355) (xy 279.730329 -308.908518) (xy 279.704026 -308.866922) (xy 279.684735 -308.821646)
			(xy 279.672958 -308.773862) (xy 279.668998 -308.724808) (xy 279.33015 -308.724808) (xy 279.329655 -308.749415)
			(xy 279.32176 -308.797992) (xy 279.306176 -308.844673) (xy 279.283305 -308.88825) (xy 279.25374 -308.927594)
			(xy 279.218247 -308.961686) (xy 279.177744 -308.989642) (xy 279.133282 -309.01074) (xy 279.086011 -309.024432)
			(xy 279.037156 -309.030364) (xy 278.987981 -309.028383) (xy 278.939762 -309.018539) (xy 278.893746 -309.001087)
			(xy 278.851125 -308.97648) (xy 278.813004 -308.945355) (xy 278.780369 -308.908518) (xy 278.754066 -308.866922)
			(xy 278.734775 -308.821646) (xy 278.722998 -308.773862) (xy 278.719038 -308.724808) (xy 263.363032 -308.724808)
			(xy 263.360415 -308.742592) (xy 263.344347 -308.795999) (xy 263.320675 -308.846496) (xy 263.289902 -308.893009)
			(xy 263.252685 -308.934546) (xy 263.209817 -308.970221) (xy 263.162211 -308.999275) (xy 263.110882 -309.021087)
			(xy 263.056925 -309.035193) (xy 263.001488 -309.041293) (xy 262.945754 -309.039256) (xy 262.890911 -309.029126)
			(xy 262.838127 -309.011119) (xy 262.788527 -308.985618) (xy 262.743169 -308.953167) (xy 262.70302 -308.914458)
			(xy 262.668934 -308.870315) (xy 262.641638 -308.82168) (xy 262.621715 -308.769589) (xy 262.609589 -308.715152)
			(xy 262.605518 -308.65953) (xy 260.978668 -308.65953) (xy 260.9625 -308.683967) (xy 260.925283 -308.725504)
			(xy 260.882415 -308.761179) (xy 260.834809 -308.790233) (xy 260.78348 -308.812045) (xy 260.729523 -308.826151)
			(xy 260.674086 -308.832251) (xy 260.618352 -308.830214) (xy 260.563509 -308.820084) (xy 260.510725 -308.802077)
			(xy 260.461125 -308.776576) (xy 260.415767 -308.744125) (xy 260.375618 -308.705416) (xy 260.341532 -308.661273)
			(xy 260.314236 -308.612638) (xy 260.294313 -308.560547) (xy 260.282187 -308.50611) (xy 260.278116 -308.450488)
			(xy 248.930808 -308.450488) (xy 248.937058 -308.468683) (xy 248.948819 -308.535117) (xy 248.949464 -308.568852)
			(xy 248.94879 -308.602585) (xy 248.937044 -308.669018) (xy 248.926096 -308.700932) (xy 248.915486 -308.728156)
			(xy 248.887182 -308.779269) (xy 248.851412 -308.825466) (xy 248.830592 -308.845966) (xy 248.823437 -308.853443)
			(xy 248.815319 -308.872457) (xy 248.814844 -308.882796) (xy 248.814844 -309.414926) (xy 259.199886 -309.414926)
			(xy 259.203957 -309.359304) (xy 259.216083 -309.304867) (xy 259.236006 -309.252776) (xy 259.263302 -309.204141)
			(xy 259.297388 -309.159998) (xy 259.337537 -309.121289) (xy 259.382895 -309.088838) (xy 259.432495 -309.063337)
			(xy 259.485279 -309.04533) (xy 259.540122 -309.0352) (xy 259.595856 -309.033163) (xy 259.651293 -309.039263)
			(xy 259.70525 -309.053369) (xy 259.756579 -309.075181) (xy 259.804185 -309.104235) (xy 259.847053 -309.13991)
			(xy 259.88427 -309.181447) (xy 259.896404 -309.199788) (xy 268.74395 -309.199788) (xy 268.74791 -309.150734)
			(xy 268.759687 -309.10295) (xy 268.778978 -309.057674) (xy 268.805281 -309.016078) (xy 268.837916 -308.979241)
			(xy 268.876037 -308.948116) (xy 268.918658 -308.923509) (xy 268.964674 -308.906057) (xy 269.012893 -308.896213)
			(xy 269.062068 -308.894232) (xy 269.110923 -308.900164) (xy 269.158194 -308.913856) (xy 269.202656 -308.934954)
			(xy 269.243159 -308.96291) (xy 269.278652 -308.997002) (xy 269.308217 -309.036346) (xy 269.331088 -309.079923)
			(xy 269.346672 -309.126604) (xy 269.354567 -309.175181) (xy 269.355062 -309.199788) (xy 269.69391 -309.199788)
			(xy 269.69787 -309.150734) (xy 269.709647 -309.10295) (xy 269.728938 -309.057674) (xy 269.755241 -309.016078)
			(xy 269.787876 -308.979241) (xy 269.825997 -308.948116) (xy 269.868618 -308.923509) (xy 269.914634 -308.906057)
			(xy 269.962853 -308.896213) (xy 270.012028 -308.894232) (xy 270.060883 -308.900164) (xy 270.108154 -308.913856)
			(xy 270.152616 -308.934954) (xy 270.193119 -308.96291) (xy 270.228612 -308.997002) (xy 270.258177 -309.036346)
			(xy 270.281048 -309.079923) (xy 270.296632 -309.126604) (xy 270.304527 -309.175181) (xy 270.305022 -309.199788)
			(xy 270.304527 -309.224395) (xy 270.304348 -309.225496) (xy 270.62328 -309.225496) (xy 270.62328 -309.17408)
			(xy 270.631323 -309.123298) (xy 270.647211 -309.074399) (xy 270.670554 -309.028587) (xy 270.700775 -308.986991)
			(xy 270.737131 -308.950635) (xy 270.778727 -308.920414) (xy 270.824539 -308.897071) (xy 270.873438 -308.881183)
			(xy 270.92422 -308.87314) (xy 270.975636 -308.87314) (xy 271.026418 -308.881183) (xy 271.075317 -308.897071)
			(xy 271.121129 -308.920414) (xy 271.162725 -308.950635) (xy 271.199081 -308.986991) (xy 271.229302 -309.028587)
			(xy 271.252645 -309.074399) (xy 271.268533 -309.123298) (xy 271.276576 -309.17408) (xy 271.27708 -309.199788)
			(xy 271.276576 -309.225496) (xy 271.57324 -309.225496) (xy 271.57324 -309.17408) (xy 271.581283 -309.123298)
			(xy 271.597171 -309.074399) (xy 271.620514 -309.028587) (xy 271.650735 -308.986991) (xy 271.687091 -308.950635)
			(xy 271.728687 -308.920414) (xy 271.774499 -308.897071) (xy 271.823398 -308.881183) (xy 271.87418 -308.87314)
			(xy 271.925596 -308.87314) (xy 271.976378 -308.881183) (xy 272.025277 -308.897071) (xy 272.071089 -308.920414)
			(xy 272.112685 -308.950635) (xy 272.149041 -308.986991) (xy 272.179262 -309.028587) (xy 272.202605 -309.074399)
			(xy 272.218493 -309.123298) (xy 272.226536 -309.17408) (xy 272.22704 -309.199788) (xy 272.544044 -309.199788)
			(xy 272.548004 -309.150734) (xy 272.559781 -309.10295) (xy 272.579072 -309.057674) (xy 272.605375 -309.016078)
			(xy 272.63801 -308.979241) (xy 272.676131 -308.948116) (xy 272.718752 -308.923509) (xy 272.764768 -308.906057)
			(xy 272.812987 -308.896213) (xy 272.862162 -308.894232) (xy 272.911017 -308.900164) (xy 272.958288 -308.913856)
			(xy 273.00275 -308.934954) (xy 273.043253 -308.96291) (xy 273.078746 -308.997002) (xy 273.108311 -309.036346)
			(xy 273.131182 -309.079923) (xy 273.146766 -309.126604) (xy 273.154661 -309.175181) (xy 273.155156 -309.199788)
			(xy 273.154661 -309.224395) (xy 273.154482 -309.225496) (xy 273.47316 -309.225496) (xy 273.47316 -309.17408)
			(xy 273.481203 -309.123298) (xy 273.497091 -309.074399) (xy 273.520434 -309.028587) (xy 273.550655 -308.986991)
			(xy 273.587011 -308.950635) (xy 273.628607 -308.920414) (xy 273.674419 -308.897071) (xy 273.723318 -308.881183)
			(xy 273.7741 -308.87314) (xy 273.825516 -308.87314) (xy 273.876298 -308.881183) (xy 273.925197 -308.897071)
			(xy 273.971009 -308.920414) (xy 274.012605 -308.950635) (xy 274.048961 -308.986991) (xy 274.079182 -309.028587)
			(xy 274.102525 -309.074399) (xy 274.118413 -309.123298) (xy 274.126456 -309.17408) (xy 274.12696 -309.199788)
			(xy 274.126456 -309.225496) (xy 274.42312 -309.225496) (xy 274.42312 -309.17408) (xy 274.431163 -309.123298)
			(xy 274.447051 -309.074399) (xy 274.470394 -309.028587) (xy 274.500615 -308.986991) (xy 274.536971 -308.950635)
			(xy 274.578567 -308.920414) (xy 274.624379 -308.897071) (xy 274.673278 -308.881183) (xy 274.72406 -308.87314)
			(xy 274.775476 -308.87314) (xy 274.826258 -308.881183) (xy 274.875157 -308.897071) (xy 274.920969 -308.920414)
			(xy 274.962565 -308.950635) (xy 274.998921 -308.986991) (xy 275.029142 -309.028587) (xy 275.052485 -309.074399)
			(xy 275.068373 -309.123298) (xy 275.076416 -309.17408) (xy 275.07692 -309.199788) (xy 275.393924 -309.199788)
			(xy 275.397884 -309.150734) (xy 275.409661 -309.10295) (xy 275.428952 -309.057674) (xy 275.455255 -309.016078)
			(xy 275.48789 -308.979241) (xy 275.526011 -308.948116) (xy 275.568632 -308.923509) (xy 275.614648 -308.906057)
			(xy 275.662867 -308.896213) (xy 275.712042 -308.894232) (xy 275.760897 -308.900164) (xy 275.808168 -308.913856)
			(xy 275.85263 -308.934954) (xy 275.893133 -308.96291) (xy 275.928626 -308.997002) (xy 275.958191 -309.036346)
			(xy 275.981062 -309.079923) (xy 275.996646 -309.126604) (xy 276.004541 -309.175181) (xy 276.005036 -309.199788)
			(xy 276.343884 -309.199788) (xy 276.347844 -309.150734) (xy 276.359621 -309.10295) (xy 276.378912 -309.057674)
			(xy 276.405215 -309.016078) (xy 276.43785 -308.979241) (xy 276.475971 -308.948116) (xy 276.518592 -308.923509)
			(xy 276.564608 -308.906057) (xy 276.612827 -308.896213) (xy 276.662002 -308.894232) (xy 276.710857 -308.900164)
			(xy 276.758128 -308.913856) (xy 276.80259 -308.934954) (xy 276.843093 -308.96291) (xy 276.878586 -308.997002)
			(xy 276.908151 -309.036346) (xy 276.931022 -309.079923) (xy 276.946606 -309.126604) (xy 276.954501 -309.175181)
			(xy 276.954996 -309.199788) (xy 277.294098 -309.199788) (xy 277.298058 -309.150734) (xy 277.309835 -309.10295)
			(xy 277.329126 -309.057674) (xy 277.355429 -309.016078) (xy 277.388064 -308.979241) (xy 277.426185 -308.948116)
			(xy 277.468806 -308.923509) (xy 277.514822 -308.906057) (xy 277.563041 -308.896213) (xy 277.612216 -308.894232)
			(xy 277.661071 -308.900164) (xy 277.708342 -308.913856) (xy 277.752804 -308.934954) (xy 277.793307 -308.96291)
			(xy 277.8288 -308.997002) (xy 277.858365 -309.036346) (xy 277.881236 -309.079923) (xy 277.89682 -309.126604)
			(xy 277.904715 -309.175181) (xy 277.90521 -309.199788) (xy 277.904715 -309.224395) (xy 277.89682 -309.272972)
			(xy 277.881236 -309.319653) (xy 277.858365 -309.36323) (xy 277.8288 -309.402574) (xy 277.793307 -309.436666)
			(xy 277.752804 -309.464622) (xy 277.708342 -309.48572) (xy 277.661071 -309.499412) (xy 277.612216 -309.505344)
			(xy 277.563041 -309.503363) (xy 277.514822 -309.493519) (xy 277.468806 -309.476067) (xy 277.426185 -309.45146)
			(xy 277.388064 -309.420335) (xy 277.355429 -309.383498) (xy 277.329126 -309.341902) (xy 277.309835 -309.296626)
			(xy 277.298058 -309.248842) (xy 277.294098 -309.199788) (xy 276.954996 -309.199788) (xy 276.954501 -309.224395)
			(xy 276.946606 -309.272972) (xy 276.931022 -309.319653) (xy 276.908151 -309.36323) (xy 276.878586 -309.402574)
			(xy 276.843093 -309.436666) (xy 276.80259 -309.464622) (xy 276.758128 -309.48572) (xy 276.710857 -309.499412)
			(xy 276.662002 -309.505344) (xy 276.612827 -309.503363) (xy 276.564608 -309.493519) (xy 276.518592 -309.476067)
			(xy 276.475971 -309.45146) (xy 276.43785 -309.420335) (xy 276.405215 -309.383498) (xy 276.378912 -309.341902)
			(xy 276.359621 -309.296626) (xy 276.347844 -309.248842) (xy 276.343884 -309.199788) (xy 276.005036 -309.199788)
			(xy 276.004541 -309.224395) (xy 275.996646 -309.272972) (xy 275.981062 -309.319653) (xy 275.958191 -309.36323)
			(xy 275.928626 -309.402574) (xy 275.893133 -309.436666) (xy 275.85263 -309.464622) (xy 275.808168 -309.48572)
			(xy 275.760897 -309.499412) (xy 275.712042 -309.505344) (xy 275.662867 -309.503363) (xy 275.614648 -309.493519)
			(xy 275.568632 -309.476067) (xy 275.526011 -309.45146) (xy 275.48789 -309.420335) (xy 275.455255 -309.383498)
			(xy 275.428952 -309.341902) (xy 275.409661 -309.296626) (xy 275.397884 -309.248842) (xy 275.393924 -309.199788)
			(xy 275.07692 -309.199788) (xy 275.076416 -309.225496) (xy 275.068373 -309.276278) (xy 275.052485 -309.325177)
			(xy 275.029142 -309.370989) (xy 274.998921 -309.412585) (xy 274.962565 -309.448941) (xy 274.920969 -309.479162)
			(xy 274.875157 -309.502505) (xy 274.826258 -309.518393) (xy 274.775476 -309.526436) (xy 274.72406 -309.526436)
			(xy 274.673278 -309.518393) (xy 274.624379 -309.502505) (xy 274.578567 -309.479162) (xy 274.536971 -309.448941)
			(xy 274.500615 -309.412585) (xy 274.470394 -309.370989) (xy 274.447051 -309.325177) (xy 274.431163 -309.276278)
			(xy 274.42312 -309.225496) (xy 274.126456 -309.225496) (xy 274.118413 -309.276278) (xy 274.102525 -309.325177)
			(xy 274.079182 -309.370989) (xy 274.048961 -309.412585) (xy 274.012605 -309.448941) (xy 273.971009 -309.479162)
			(xy 273.925197 -309.502505) (xy 273.876298 -309.518393) (xy 273.825516 -309.526436) (xy 273.7741 -309.526436)
			(xy 273.723318 -309.518393) (xy 273.674419 -309.502505) (xy 273.628607 -309.479162) (xy 273.587011 -309.448941)
			(xy 273.550655 -309.412585) (xy 273.520434 -309.370989) (xy 273.497091 -309.325177) (xy 273.481203 -309.276278)
			(xy 273.47316 -309.225496) (xy 273.154482 -309.225496) (xy 273.146766 -309.272972) (xy 273.131182 -309.319653)
			(xy 273.108311 -309.36323) (xy 273.078746 -309.402574) (xy 273.043253 -309.436666) (xy 273.00275 -309.464622)
			(xy 272.958288 -309.48572) (xy 272.911017 -309.499412) (xy 272.862162 -309.505344) (xy 272.812987 -309.503363)
			(xy 272.764768 -309.493519) (xy 272.718752 -309.476067) (xy 272.676131 -309.45146) (xy 272.63801 -309.420335)
			(xy 272.605375 -309.383498) (xy 272.579072 -309.341902) (xy 272.559781 -309.296626) (xy 272.548004 -309.248842)
			(xy 272.544044 -309.199788) (xy 272.22704 -309.199788) (xy 272.226536 -309.225496) (xy 272.218493 -309.276278)
			(xy 272.202605 -309.325177) (xy 272.179262 -309.370989) (xy 272.149041 -309.412585) (xy 272.112685 -309.448941)
			(xy 272.071089 -309.479162) (xy 272.025277 -309.502505) (xy 271.976378 -309.518393) (xy 271.925596 -309.526436)
			(xy 271.87418 -309.526436) (xy 271.823398 -309.518393) (xy 271.774499 -309.502505) (xy 271.728687 -309.479162)
			(xy 271.687091 -309.448941) (xy 271.650735 -309.412585) (xy 271.620514 -309.370989) (xy 271.597171 -309.325177)
			(xy 271.581283 -309.276278) (xy 271.57324 -309.225496) (xy 271.276576 -309.225496) (xy 271.268533 -309.276278)
			(xy 271.252645 -309.325177) (xy 271.229302 -309.370989) (xy 271.199081 -309.412585) (xy 271.162725 -309.448941)
			(xy 271.121129 -309.479162) (xy 271.075317 -309.502505) (xy 271.026418 -309.518393) (xy 270.975636 -309.526436)
			(xy 270.92422 -309.526436) (xy 270.873438 -309.518393) (xy 270.824539 -309.502505) (xy 270.778727 -309.479162)
			(xy 270.737131 -309.448941) (xy 270.700775 -309.412585) (xy 270.670554 -309.370989) (xy 270.647211 -309.325177)
			(xy 270.631323 -309.276278) (xy 270.62328 -309.225496) (xy 270.304348 -309.225496) (xy 270.296632 -309.272972)
			(xy 270.281048 -309.319653) (xy 270.258177 -309.36323) (xy 270.228612 -309.402574) (xy 270.193119 -309.436666)
			(xy 270.152616 -309.464622) (xy 270.108154 -309.48572) (xy 270.060883 -309.499412) (xy 270.012028 -309.505344)
			(xy 269.962853 -309.503363) (xy 269.914634 -309.493519) (xy 269.868618 -309.476067) (xy 269.825997 -309.45146)
			(xy 269.787876 -309.420335) (xy 269.755241 -309.383498) (xy 269.728938 -309.341902) (xy 269.709647 -309.296626)
			(xy 269.69787 -309.248842) (xy 269.69391 -309.199788) (xy 269.355062 -309.199788) (xy 269.354567 -309.224395)
			(xy 269.346672 -309.272972) (xy 269.331088 -309.319653) (xy 269.308217 -309.36323) (xy 269.278652 -309.402574)
			(xy 269.243159 -309.436666) (xy 269.202656 -309.464622) (xy 269.158194 -309.48572) (xy 269.110923 -309.499412)
			(xy 269.062068 -309.505344) (xy 269.012893 -309.503363) (xy 268.964674 -309.493519) (xy 268.918658 -309.476067)
			(xy 268.876037 -309.45146) (xy 268.837916 -309.420335) (xy 268.805281 -309.383498) (xy 268.778978 -309.341902)
			(xy 268.759687 -309.296626) (xy 268.74791 -309.248842) (xy 268.74395 -309.199788) (xy 259.896404 -309.199788)
			(xy 259.915043 -309.22796) (xy 259.938715 -309.278457) (xy 259.954783 -309.331864) (xy 259.962903 -309.38704)
			(xy 259.963412 -309.414926) (xy 259.962903 -309.442812) (xy 259.954783 -309.497988) (xy 259.938715 -309.551395)
			(xy 259.915043 -309.601892) (xy 259.88427 -309.648405) (xy 259.847053 -309.689942) (xy 259.804185 -309.725617)
			(xy 259.756579 -309.754671) (xy 259.70525 -309.776483) (xy 259.651293 -309.790589) (xy 259.595856 -309.796689)
			(xy 259.540122 -309.794652) (xy 259.485279 -309.784522) (xy 259.432495 -309.766515) (xy 259.382895 -309.741014)
			(xy 259.337537 -309.708563) (xy 259.297388 -309.669854) (xy 259.263302 -309.625711) (xy 259.236006 -309.577076)
			(xy 259.216083 -309.524985) (xy 259.203957 -309.470548) (xy 259.199886 -309.414926) (xy 248.814844 -309.414926)
			(xy 248.814844 -310.075326) (xy 248.817384 -310.082946) (xy 248.826036 -310.110999) (xy 248.826521 -310.113934)
			(xy 261.18642 -310.113934) (xy 261.190491 -310.058312) (xy 261.202617 -310.003875) (xy 261.22254 -309.951784)
			(xy 261.249836 -309.903149) (xy 261.283922 -309.859006) (xy 261.324071 -309.820297) (xy 261.369429 -309.787846)
			(xy 261.419029 -309.762345) (xy 261.471813 -309.744338) (xy 261.526656 -309.734208) (xy 261.58239 -309.732171)
			(xy 261.637827 -309.738271) (xy 261.691784 -309.752377) (xy 261.743113 -309.774189) (xy 261.790719 -309.803243)
			(xy 261.833587 -309.838918) (xy 261.870804 -309.880455) (xy 261.901577 -309.926968) (xy 261.925249 -309.977465)
			(xy 261.941317 -310.030872) (xy 261.949437 -310.086048) (xy 261.949946 -310.113934) (xy 261.949437 -310.14182)
			(xy 261.941317 -310.196996) (xy 261.929168 -310.237378) (xy 266.300712 -310.237378) (xy 266.301198 -310.210127)
			(xy 266.308954 -310.156179) (xy 266.324309 -310.103884) (xy 266.346951 -310.054307) (xy 266.376417 -310.008457)
			(xy 266.412108 -309.967266) (xy 266.453299 -309.931575) (xy 266.499149 -309.902109) (xy 266.548726 -309.879467)
			(xy 266.601021 -309.864112) (xy 266.654969 -309.856356) (xy 266.709471 -309.856356) (xy 266.763419 -309.864112)
			(xy 266.815714 -309.879467) (xy 266.865291 -309.902109) (xy 266.911141 -309.931575) (xy 266.952332 -309.967266)
			(xy 266.988023 -310.008457) (xy 267.017489 -310.054307) (xy 267.040131 -310.103884) (xy 267.053672 -310.150002)
			(xy 267.793736 -310.150002) (xy 267.797696 -310.100948) (xy 267.809473 -310.053164) (xy 267.828764 -310.007888)
			(xy 267.855067 -309.966292) (xy 267.887702 -309.929455) (xy 267.925823 -309.89833) (xy 267.968444 -309.873723)
			(xy 268.01446 -309.856271) (xy 268.062679 -309.846427) (xy 268.111854 -309.844446) (xy 268.160709 -309.850378)
			(xy 268.20798 -309.86407) (xy 268.252442 -309.885168) (xy 268.292945 -309.913124) (xy 268.328438 -309.947216)
			(xy 268.358003 -309.98656) (xy 268.380874 -310.030137) (xy 268.396458 -310.076818) (xy 268.404353 -310.125395)
			(xy 268.404848 -310.150002) (xy 268.404353 -310.174609) (xy 268.404215 -310.175456) (xy 268.723106 -310.175456)
			(xy 268.723106 -310.12404) (xy 268.731149 -310.073258) (xy 268.747037 -310.024359) (xy 268.77038 -309.978547)
			(xy 268.800601 -309.936951) (xy 268.836957 -309.900595) (xy 268.878553 -309.870374) (xy 268.924365 -309.847031)
			(xy 268.973264 -309.831143) (xy 269.024046 -309.8231) (xy 269.075462 -309.8231) (xy 269.126244 -309.831143)
			(xy 269.175143 -309.847031) (xy 269.220955 -309.870374) (xy 269.262551 -309.900595) (xy 269.298907 -309.936951)
			(xy 269.329128 -309.978547) (xy 269.352471 -310.024359) (xy 269.368359 -310.073258) (xy 269.376402 -310.12404)
			(xy 269.376906 -310.149748) (xy 269.376402 -310.175456) (xy 269.673066 -310.175456) (xy 269.673066 -310.12404)
			(xy 269.681109 -310.073258) (xy 269.696997 -310.024359) (xy 269.72034 -309.978547) (xy 269.750561 -309.936951)
			(xy 269.786917 -309.900595) (xy 269.828513 -309.870374) (xy 269.874325 -309.847031) (xy 269.923224 -309.831143)
			(xy 269.974006 -309.8231) (xy 270.025422 -309.8231) (xy 270.076204 -309.831143) (xy 270.125103 -309.847031)
			(xy 270.170915 -309.870374) (xy 270.212511 -309.900595) (xy 270.248867 -309.936951) (xy 270.279088 -309.978547)
			(xy 270.302431 -310.024359) (xy 270.318319 -310.073258) (xy 270.326362 -310.12404) (xy 270.326866 -310.149748)
			(xy 270.644124 -310.149748) (xy 270.648084 -310.100694) (xy 270.659861 -310.05291) (xy 270.679152 -310.007634)
			(xy 270.705455 -309.966038) (xy 270.73809 -309.929201) (xy 270.776211 -309.898076) (xy 270.818832 -309.873469)
			(xy 270.864848 -309.856017) (xy 270.913067 -309.846173) (xy 270.962242 -309.844192) (xy 271.011097 -309.850124)
			(xy 271.058368 -309.863816) (xy 271.10283 -309.884914) (xy 271.143333 -309.91287) (xy 271.178826 -309.946962)
			(xy 271.208391 -309.986306) (xy 271.231262 -310.029883) (xy 271.246846 -310.076564) (xy 271.254741 -310.125141)
			(xy 271.255236 -310.149748) (xy 271.594084 -310.149748) (xy 271.598044 -310.100694) (xy 271.609821 -310.05291)
			(xy 271.629112 -310.007634) (xy 271.655415 -309.966038) (xy 271.68805 -309.929201) (xy 271.726171 -309.898076)
			(xy 271.768792 -309.873469) (xy 271.814808 -309.856017) (xy 271.863027 -309.846173) (xy 271.912202 -309.844192)
			(xy 271.961057 -309.850124) (xy 272.008328 -309.863816) (xy 272.05279 -309.884914) (xy 272.093293 -309.91287)
			(xy 272.128786 -309.946962) (xy 272.158351 -309.986306) (xy 272.181222 -310.029883) (xy 272.196806 -310.076564)
			(xy 272.204701 -310.125141) (xy 272.205196 -310.149748) (xy 272.544044 -310.149748) (xy 272.548004 -310.100694)
			(xy 272.559781 -310.05291) (xy 272.579072 -310.007634) (xy 272.605375 -309.966038) (xy 272.63801 -309.929201)
			(xy 272.676131 -309.898076) (xy 272.718752 -309.873469) (xy 272.764768 -309.856017) (xy 272.812987 -309.846173)
			(xy 272.862162 -309.844192) (xy 272.911017 -309.850124) (xy 272.958288 -309.863816) (xy 273.00275 -309.884914)
			(xy 273.043253 -309.91287) (xy 273.078746 -309.946962) (xy 273.108311 -309.986306) (xy 273.131182 -310.029883)
			(xy 273.146766 -310.076564) (xy 273.154661 -310.125141) (xy 273.155156 -310.149748) (xy 273.494004 -310.149748)
			(xy 273.497964 -310.100694) (xy 273.509741 -310.05291) (xy 273.529032 -310.007634) (xy 273.555335 -309.966038)
			(xy 273.58797 -309.929201) (xy 273.626091 -309.898076) (xy 273.668712 -309.873469) (xy 273.714728 -309.856017)
			(xy 273.762947 -309.846173) (xy 273.812122 -309.844192) (xy 273.860977 -309.850124) (xy 273.908248 -309.863816)
			(xy 273.95271 -309.884914) (xy 273.993213 -309.91287) (xy 274.028706 -309.946962) (xy 274.058271 -309.986306)
			(xy 274.081142 -310.029883) (xy 274.096726 -310.076564) (xy 274.104621 -310.125141) (xy 274.105116 -310.149748)
			(xy 274.443964 -310.149748) (xy 274.447924 -310.100694) (xy 274.459701 -310.05291) (xy 274.478992 -310.007634)
			(xy 274.505295 -309.966038) (xy 274.53793 -309.929201) (xy 274.576051 -309.898076) (xy 274.618672 -309.873469)
			(xy 274.664688 -309.856017) (xy 274.712907 -309.846173) (xy 274.762082 -309.844192) (xy 274.810937 -309.850124)
			(xy 274.858208 -309.863816) (xy 274.90267 -309.884914) (xy 274.943173 -309.91287) (xy 274.978666 -309.946962)
			(xy 275.008231 -309.986306) (xy 275.031102 -310.029883) (xy 275.046686 -310.076564) (xy 275.054581 -310.125141)
			(xy 275.055076 -310.149748) (xy 275.393924 -310.149748) (xy 275.397884 -310.100694) (xy 275.409661 -310.05291)
			(xy 275.428952 -310.007634) (xy 275.455255 -309.966038) (xy 275.48789 -309.929201) (xy 275.526011 -309.898076)
			(xy 275.568632 -309.873469) (xy 275.614648 -309.856017) (xy 275.662867 -309.846173) (xy 275.712042 -309.844192)
			(xy 275.760897 -309.850124) (xy 275.808168 -309.863816) (xy 275.85263 -309.884914) (xy 275.893133 -309.91287)
			(xy 275.928626 -309.946962) (xy 275.958191 -309.986306) (xy 275.981062 -310.029883) (xy 275.996646 -310.076564)
			(xy 276.004541 -310.125141) (xy 276.005036 -310.149748) (xy 276.343884 -310.149748) (xy 276.347844 -310.100694)
			(xy 276.359621 -310.05291) (xy 276.378912 -310.007634) (xy 276.405215 -309.966038) (xy 276.43785 -309.929201)
			(xy 276.475971 -309.898076) (xy 276.518592 -309.873469) (xy 276.564608 -309.856017) (xy 276.612827 -309.846173)
			(xy 276.662002 -309.844192) (xy 276.710857 -309.850124) (xy 276.758128 -309.863816) (xy 276.80259 -309.884914)
			(xy 276.843093 -309.91287) (xy 276.878586 -309.946962) (xy 276.908151 -309.986306) (xy 276.931022 -310.029883)
			(xy 276.946606 -310.076564) (xy 276.954501 -310.125141) (xy 276.954996 -310.149748) (xy 277.294098 -310.149748)
			(xy 277.298058 -310.100694) (xy 277.309835 -310.05291) (xy 277.329126 -310.007634) (xy 277.355429 -309.966038)
			(xy 277.388064 -309.929201) (xy 277.426185 -309.898076) (xy 277.468806 -309.873469) (xy 277.514822 -309.856017)
			(xy 277.563041 -309.846173) (xy 277.612216 -309.844192) (xy 277.661071 -309.850124) (xy 277.708342 -309.863816)
			(xy 277.752804 -309.884914) (xy 277.793307 -309.91287) (xy 277.8288 -309.946962) (xy 277.858365 -309.986306)
			(xy 277.881236 -310.029883) (xy 277.89682 -310.076564) (xy 277.904715 -310.125141) (xy 277.905043 -310.141429)
			(xy 278.244229 -310.141429) (xy 278.249593 -310.092089) (xy 278.262869 -310.044267) (xy 278.283705 -309.999222)
			(xy 278.311555 -309.958141) (xy 278.345683 -309.922106) (xy 278.385192 -309.892068) (xy 278.429039 -309.868816)
			(xy 278.47607 -309.852964) (xy 278.525047 -309.844929) (xy 278.549862 -309.84444) (xy 278.564045 -309.844621)
			(xy 278.592285 -309.84729) (xy 278.60625 -309.849774) (xy 278.618696 -309.85206) (xy 278.642318 -309.844694)
			(xy 278.719788 -309.767224) (xy 278.727154 -309.743602) (xy 278.724868 -309.731156) (xy 278.722389 -309.717191)
			(xy 278.719719 -309.688951) (xy 278.719534 -309.674768) (xy 278.720056 -309.649513) (xy 278.728369 -309.599691)
			(xy 278.74477 -309.551917) (xy 278.768811 -309.507494) (xy 278.799835 -309.467634) (xy 278.836997 -309.433424)
			(xy 278.879283 -309.405798) (xy 278.925539 -309.385508) (xy 278.974504 -309.373108) (xy 279.024842 -309.368937)
			(xy 279.07518 -309.373108) (xy 279.124145 -309.385508) (xy 279.170401 -309.405798) (xy 279.212687 -309.433424)
			(xy 279.249849 -309.467634) (xy 279.280873 -309.507494) (xy 279.304914 -309.551917) (xy 279.321315 -309.599691)
			(xy 279.329628 -309.649513) (xy 279.33015 -309.674768) (xy 279.329968 -309.688951) (xy 279.327299 -309.717191)
			(xy 279.324816 -309.731156) (xy 279.32253 -309.743602) (xy 279.329896 -309.767224) (xy 279.407366 -309.844694)
			(xy 279.430988 -309.85206) (xy 279.443434 -309.849774) (xy 279.4574 -309.847297) (xy 279.485639 -309.844625)
			(xy 279.499822 -309.84444) (xy 279.52464 -309.844901) (xy 279.573621 -309.852935) (xy 279.620658 -309.868786)
			(xy 279.66451 -309.892038) (xy 279.704024 -309.922078) (xy 279.738157 -309.958114) (xy 279.766011 -309.999198)
			(xy 279.786852 -310.044247) (xy 279.80013 -310.092073) (xy 279.805497 -310.141416) (xy 280.144129 -310.141416)
			(xy 280.149496 -310.092075) (xy 280.162774 -310.044253) (xy 280.183613 -309.999208) (xy 280.211465 -309.958128)
			(xy 280.245596 -309.922095) (xy 280.285107 -309.892058) (xy 280.328956 -309.868809) (xy 280.375989 -309.852959)
			(xy 280.424966 -309.844927) (xy 280.449782 -309.84444) (xy 280.463965 -309.844618) (xy 280.492205 -309.847289)
			(xy 280.50617 -309.849774) (xy 280.518616 -309.85206) (xy 280.542238 -309.844694) (xy 280.619708 -309.767224)
			(xy 280.627074 -309.743602) (xy 280.624788 -309.731156) (xy 280.622309 -309.71719) (xy 280.619639 -309.688951)
			(xy 280.619454 -309.674768) (xy 280.619976 -309.649513) (xy 280.628289 -309.599691) (xy 280.64469 -309.551917)
			(xy 280.668731 -309.507494) (xy 280.699755 -309.467634) (xy 280.736917 -309.433424) (xy 280.779203 -309.405798)
			(xy 280.825459 -309.385508) (xy 280.874424 -309.373108) (xy 280.924762 -309.368937) (xy 280.9751 -309.373108)
			(xy 281.024065 -309.385508) (xy 281.070321 -309.405798) (xy 281.112607 -309.433424) (xy 281.149769 -309.467634)
			(xy 281.180793 -309.507494) (xy 281.204834 -309.551917) (xy 281.221235 -309.599691) (xy 281.229548 -309.649513)
			(xy 281.23007 -309.674768) (xy 281.22989 -309.688951) (xy 281.22722 -309.717191) (xy 281.224736 -309.731156)
			(xy 281.22245 -309.743602) (xy 281.229816 -309.767224) (xy 281.307286 -309.844694) (xy 281.330908 -309.85206)
			(xy 281.343354 -309.849774) (xy 281.357319 -309.847294) (xy 281.385559 -309.844625) (xy 281.399742 -309.84444)
			(xy 281.424558 -309.844923) (xy 281.473535 -309.852959) (xy 281.520567 -309.868812) (xy 281.564414 -309.892064)
			(xy 281.603923 -309.922104) (xy 281.638052 -309.95814) (xy 281.665901 -309.999221) (xy 281.686738 -310.044267)
			(xy 281.700013 -310.092091) (xy 281.705377 -310.141432) (xy 281.704926 -310.149748) (xy 282.043898 -310.149748)
			(xy 282.047858 -310.100694) (xy 282.059635 -310.05291) (xy 282.078926 -310.007634) (xy 282.105229 -309.966038)
			(xy 282.137864 -309.929201) (xy 282.175985 -309.898076) (xy 282.218606 -309.873469) (xy 282.264622 -309.856017)
			(xy 282.312841 -309.846173) (xy 282.362016 -309.844192) (xy 282.410871 -309.850124) (xy 282.458142 -309.863816)
			(xy 282.502604 -309.884914) (xy 282.543107 -309.91287) (xy 282.5786 -309.946962) (xy 282.608165 -309.986306)
			(xy 282.631036 -310.029883) (xy 282.64662 -310.076564) (xy 282.654515 -310.125141) (xy 282.65501 -310.149748)
			(xy 282.994112 -310.149748) (xy 282.998072 -310.100694) (xy 283.009849 -310.05291) (xy 283.02914 -310.007634)
			(xy 283.055443 -309.966038) (xy 283.088078 -309.929201) (xy 283.126199 -309.898076) (xy 283.16882 -309.873469)
			(xy 283.214836 -309.856017) (xy 283.263055 -309.846173) (xy 283.31223 -309.844192) (xy 283.361085 -309.850124)
			(xy 283.408356 -309.863816) (xy 283.452818 -309.884914) (xy 283.493321 -309.91287) (xy 283.528814 -309.946962)
			(xy 283.558379 -309.986306) (xy 283.58125 -310.029883) (xy 283.596834 -310.076564) (xy 283.604729 -310.125141)
			(xy 283.605224 -310.149748) (xy 283.944072 -310.149748) (xy 283.948032 -310.100694) (xy 283.959809 -310.05291)
			(xy 283.9791 -310.007634) (xy 284.005403 -309.966038) (xy 284.038038 -309.929201) (xy 284.076159 -309.898076)
			(xy 284.11878 -309.873469) (xy 284.164796 -309.856017) (xy 284.213015 -309.846173) (xy 284.26219 -309.844192)
			(xy 284.311045 -309.850124) (xy 284.358316 -309.863816) (xy 284.402778 -309.884914) (xy 284.443281 -309.91287)
			(xy 284.478774 -309.946962) (xy 284.508339 -309.986306) (xy 284.53121 -310.029883) (xy 284.546794 -310.076564)
			(xy 284.554689 -310.125141) (xy 284.555184 -310.149748) (xy 284.894032 -310.149748) (xy 284.897992 -310.100694)
			(xy 284.909769 -310.05291) (xy 284.92906 -310.007634) (xy 284.955363 -309.966038) (xy 284.987998 -309.929201)
			(xy 285.026119 -309.898076) (xy 285.06874 -309.873469) (xy 285.114756 -309.856017) (xy 285.162975 -309.846173)
			(xy 285.21215 -309.844192) (xy 285.261005 -309.850124) (xy 285.308276 -309.863816) (xy 285.352738 -309.884914)
			(xy 285.393241 -309.91287) (xy 285.428734 -309.946962) (xy 285.458299 -309.986306) (xy 285.48117 -310.029883)
			(xy 285.496754 -310.076564) (xy 285.504649 -310.125141) (xy 285.505144 -310.149748) (xy 285.843992 -310.149748)
			(xy 285.847952 -310.100694) (xy 285.859729 -310.05291) (xy 285.87902 -310.007634) (xy 285.905323 -309.966038)
			(xy 285.937958 -309.929201) (xy 285.976079 -309.898076) (xy 286.0187 -309.873469) (xy 286.064716 -309.856017)
			(xy 286.112935 -309.846173) (xy 286.16211 -309.844192) (xy 286.210965 -309.850124) (xy 286.258236 -309.863816)
			(xy 286.302698 -309.884914) (xy 286.343201 -309.91287) (xy 286.378694 -309.946962) (xy 286.408259 -309.986306)
			(xy 286.43113 -310.029883) (xy 286.446714 -310.076564) (xy 286.454609 -310.125141) (xy 286.455104 -310.149748)
			(xy 286.793952 -310.149748) (xy 286.797912 -310.100694) (xy 286.809689 -310.05291) (xy 286.82898 -310.007634)
			(xy 286.855283 -309.966038) (xy 286.887918 -309.929201) (xy 286.926039 -309.898076) (xy 286.96866 -309.873469)
			(xy 287.014676 -309.856017) (xy 287.062895 -309.846173) (xy 287.11207 -309.844192) (xy 287.160925 -309.850124)
			(xy 287.208196 -309.863816) (xy 287.252658 -309.884914) (xy 287.293161 -309.91287) (xy 287.328654 -309.946962)
			(xy 287.358219 -309.986306) (xy 287.38109 -310.029883) (xy 287.396674 -310.076564) (xy 287.404569 -310.125141)
			(xy 287.405064 -310.149748) (xy 287.743912 -310.149748) (xy 287.747872 -310.100694) (xy 287.759649 -310.05291)
			(xy 287.77894 -310.007634) (xy 287.805243 -309.966038) (xy 287.837878 -309.929201) (xy 287.875999 -309.898076)
			(xy 287.91862 -309.873469) (xy 287.964636 -309.856017) (xy 288.012855 -309.846173) (xy 288.06203 -309.844192)
			(xy 288.110885 -309.850124) (xy 288.158156 -309.863816) (xy 288.202618 -309.884914) (xy 288.243121 -309.91287)
			(xy 288.278614 -309.946962) (xy 288.308179 -309.986306) (xy 288.33105 -310.029883) (xy 288.346634 -310.076564)
			(xy 288.354529 -310.125141) (xy 288.355024 -310.149748) (xy 288.694126 -310.149748) (xy 288.698086 -310.100694)
			(xy 288.709863 -310.05291) (xy 288.729154 -310.007634) (xy 288.755457 -309.966038) (xy 288.788092 -309.929201)
			(xy 288.826213 -309.898076) (xy 288.868834 -309.873469) (xy 288.91485 -309.856017) (xy 288.963069 -309.846173)
			(xy 289.012244 -309.844192) (xy 289.061099 -309.850124) (xy 289.10837 -309.863816) (xy 289.152832 -309.884914)
			(xy 289.193335 -309.91287) (xy 289.228828 -309.946962) (xy 289.258393 -309.986306) (xy 289.281264 -310.029883)
			(xy 289.296848 -310.076564) (xy 289.304743 -310.125141) (xy 289.305238 -310.149748) (xy 289.644086 -310.149748)
			(xy 289.648046 -310.100694) (xy 289.659823 -310.05291) (xy 289.679114 -310.007634) (xy 289.705417 -309.966038)
			(xy 289.738052 -309.929201) (xy 289.776173 -309.898076) (xy 289.818794 -309.873469) (xy 289.86481 -309.856017)
			(xy 289.913029 -309.846173) (xy 289.962204 -309.844192) (xy 290.011059 -309.850124) (xy 290.05833 -309.863816)
			(xy 290.102792 -309.884914) (xy 290.143295 -309.91287) (xy 290.178788 -309.946962) (xy 290.208353 -309.986306)
			(xy 290.231224 -310.029883) (xy 290.246808 -310.076564) (xy 290.254703 -310.125141) (xy 290.255198 -310.149748)
			(xy 290.594046 -310.149748) (xy 290.598006 -310.100694) (xy 290.609783 -310.05291) (xy 290.629074 -310.007634)
			(xy 290.655377 -309.966038) (xy 290.688012 -309.929201) (xy 290.726133 -309.898076) (xy 290.768754 -309.873469)
			(xy 290.81477 -309.856017) (xy 290.862989 -309.846173) (xy 290.912164 -309.844192) (xy 290.961019 -309.850124)
			(xy 291.00829 -309.863816) (xy 291.052752 -309.884914) (xy 291.093255 -309.91287) (xy 291.128748 -309.946962)
			(xy 291.158313 -309.986306) (xy 291.181184 -310.029883) (xy 291.196768 -310.076564) (xy 291.204663 -310.125141)
			(xy 291.205158 -310.149748) (xy 291.544006 -310.149748) (xy 291.547966 -310.100694) (xy 291.559743 -310.05291)
			(xy 291.579034 -310.007634) (xy 291.605337 -309.966038) (xy 291.637972 -309.929201) (xy 291.676093 -309.898076)
			(xy 291.718714 -309.873469) (xy 291.76473 -309.856017) (xy 291.812949 -309.846173) (xy 291.862124 -309.844192)
			(xy 291.910979 -309.850124) (xy 291.95825 -309.863816) (xy 292.002712 -309.884914) (xy 292.043215 -309.91287)
			(xy 292.078708 -309.946962) (xy 292.108273 -309.986306) (xy 292.131144 -310.029883) (xy 292.146728 -310.076564)
			(xy 292.154623 -310.125141) (xy 292.155118 -310.149748) (xy 292.493966 -310.149748) (xy 292.497926 -310.100694)
			(xy 292.509703 -310.05291) (xy 292.528994 -310.007634) (xy 292.555297 -309.966038) (xy 292.587932 -309.929201)
			(xy 292.626053 -309.898076) (xy 292.668674 -309.873469) (xy 292.71469 -309.856017) (xy 292.762909 -309.846173)
			(xy 292.812084 -309.844192) (xy 292.860939 -309.850124) (xy 292.90821 -309.863816) (xy 292.952672 -309.884914)
			(xy 292.993175 -309.91287) (xy 293.028668 -309.946962) (xy 293.058233 -309.986306) (xy 293.081104 -310.029883)
			(xy 293.096688 -310.076564) (xy 293.104583 -310.125141) (xy 293.105078 -310.149748) (xy 293.443926 -310.149748)
			(xy 293.447886 -310.100694) (xy 293.459663 -310.05291) (xy 293.478954 -310.007634) (xy 293.505257 -309.966038)
			(xy 293.537892 -309.929201) (xy 293.576013 -309.898076) (xy 293.618634 -309.873469) (xy 293.66465 -309.856017)
			(xy 293.712869 -309.846173) (xy 293.762044 -309.844192) (xy 293.810899 -309.850124) (xy 293.85817 -309.863816)
			(xy 293.902632 -309.884914) (xy 293.943135 -309.91287) (xy 293.978628 -309.946962) (xy 294.008193 -309.986306)
			(xy 294.031064 -310.029883) (xy 294.046648 -310.076564) (xy 294.054543 -310.125141) (xy 294.055038 -310.149748)
			(xy 294.393886 -310.149748) (xy 294.397846 -310.100694) (xy 294.409623 -310.05291) (xy 294.428914 -310.007634)
			(xy 294.455217 -309.966038) (xy 294.487852 -309.929201) (xy 294.525973 -309.898076) (xy 294.568594 -309.873469)
			(xy 294.61461 -309.856017) (xy 294.662829 -309.846173) (xy 294.712004 -309.844192) (xy 294.760859 -309.850124)
			(xy 294.80813 -309.863816) (xy 294.852592 -309.884914) (xy 294.893095 -309.91287) (xy 294.928588 -309.946962)
			(xy 294.958153 -309.986306) (xy 294.981024 -310.029883) (xy 294.996608 -310.076564) (xy 295.004503 -310.125141)
			(xy 295.004998 -310.149748) (xy 295.3441 -310.149748) (xy 295.34806 -310.100694) (xy 295.359837 -310.05291)
			(xy 295.379128 -310.007634) (xy 295.405431 -309.966038) (xy 295.438066 -309.929201) (xy 295.476187 -309.898076)
			(xy 295.518808 -309.873469) (xy 295.564824 -309.856017) (xy 295.613043 -309.846173) (xy 295.662218 -309.844192)
			(xy 295.711073 -309.850124) (xy 295.758344 -309.863816) (xy 295.802806 -309.884914) (xy 295.843309 -309.91287)
			(xy 295.878802 -309.946962) (xy 295.908367 -309.986306) (xy 295.931238 -310.029883) (xy 295.946822 -310.076564)
			(xy 295.954717 -310.125141) (xy 295.955212 -310.149748) (xy 296.29406 -310.149748) (xy 296.29802 -310.100694)
			(xy 296.309797 -310.05291) (xy 296.329088 -310.007634) (xy 296.355391 -309.966038) (xy 296.388026 -309.929201)
			(xy 296.426147 -309.898076) (xy 296.468768 -309.873469) (xy 296.514784 -309.856017) (xy 296.563003 -309.846173)
			(xy 296.612178 -309.844192) (xy 296.661033 -309.850124) (xy 296.708304 -309.863816) (xy 296.752766 -309.884914)
			(xy 296.793269 -309.91287) (xy 296.828762 -309.946962) (xy 296.858327 -309.986306) (xy 296.881198 -310.029883)
			(xy 296.896782 -310.076564) (xy 296.904677 -310.125141) (xy 296.905172 -310.149748) (xy 297.24402 -310.149748)
			(xy 297.24798 -310.100694) (xy 297.259757 -310.05291) (xy 297.279048 -310.007634) (xy 297.305351 -309.966038)
			(xy 297.337986 -309.929201) (xy 297.376107 -309.898076) (xy 297.418728 -309.873469) (xy 297.464744 -309.856017)
			(xy 297.512963 -309.846173) (xy 297.562138 -309.844192) (xy 297.610993 -309.850124) (xy 297.658264 -309.863816)
			(xy 297.702726 -309.884914) (xy 297.743229 -309.91287) (xy 297.778722 -309.946962) (xy 297.808287 -309.986306)
			(xy 297.831158 -310.029883) (xy 297.846742 -310.076564) (xy 297.854637 -310.125141) (xy 297.855132 -310.149748)
			(xy 298.19398 -310.149748) (xy 298.19794 -310.100694) (xy 298.209717 -310.05291) (xy 298.229008 -310.007634)
			(xy 298.255311 -309.966038) (xy 298.287946 -309.929201) (xy 298.326067 -309.898076) (xy 298.368688 -309.873469)
			(xy 298.414704 -309.856017) (xy 298.462923 -309.846173) (xy 298.512098 -309.844192) (xy 298.560953 -309.850124)
			(xy 298.608224 -309.863816) (xy 298.652686 -309.884914) (xy 298.693189 -309.91287) (xy 298.728682 -309.946962)
			(xy 298.758247 -309.986306) (xy 298.781118 -310.029883) (xy 298.796702 -310.076564) (xy 298.804597 -310.125141)
			(xy 298.805092 -310.149748) (xy 299.14394 -310.149748) (xy 299.1479 -310.100694) (xy 299.159677 -310.05291)
			(xy 299.178968 -310.007634) (xy 299.205271 -309.966038) (xy 299.237906 -309.929201) (xy 299.276027 -309.898076)
			(xy 299.318648 -309.873469) (xy 299.364664 -309.856017) (xy 299.412883 -309.846173) (xy 299.462058 -309.844192)
			(xy 299.510913 -309.850124) (xy 299.558184 -309.863816) (xy 299.602646 -309.884914) (xy 299.643149 -309.91287)
			(xy 299.678642 -309.946962) (xy 299.708207 -309.986306) (xy 299.731078 -310.029883) (xy 299.746662 -310.076564)
			(xy 299.754557 -310.125141) (xy 299.755052 -310.149748) (xy 300.0939 -310.149748) (xy 300.09786 -310.100694)
			(xy 300.109637 -310.05291) (xy 300.128928 -310.007634) (xy 300.155231 -309.966038) (xy 300.187866 -309.929201)
			(xy 300.225987 -309.898076) (xy 300.268608 -309.873469) (xy 300.314624 -309.856017) (xy 300.362843 -309.846173)
			(xy 300.412018 -309.844192) (xy 300.460873 -309.850124) (xy 300.508144 -309.863816) (xy 300.552606 -309.884914)
			(xy 300.593109 -309.91287) (xy 300.628602 -309.946962) (xy 300.658167 -309.986306) (xy 300.681038 -310.029883)
			(xy 300.696622 -310.076564) (xy 300.704517 -310.125141) (xy 300.705012 -310.149748) (xy 301.044114 -310.149748)
			(xy 301.048074 -310.100694) (xy 301.059851 -310.05291) (xy 301.079142 -310.007634) (xy 301.105445 -309.966038)
			(xy 301.13808 -309.929201) (xy 301.176201 -309.898076) (xy 301.218822 -309.873469) (xy 301.264838 -309.856017)
			(xy 301.313057 -309.846173) (xy 301.362232 -309.844192) (xy 301.411087 -309.850124) (xy 301.458358 -309.863816)
			(xy 301.50282 -309.884914) (xy 301.543323 -309.91287) (xy 301.578816 -309.946962) (xy 301.608381 -309.986306)
			(xy 301.631252 -310.029883) (xy 301.646836 -310.076564) (xy 301.654731 -310.125141) (xy 301.655226 -310.149748)
			(xy 301.994074 -310.149748) (xy 301.998034 -310.100694) (xy 302.009811 -310.05291) (xy 302.029102 -310.007634)
			(xy 302.055405 -309.966038) (xy 302.08804 -309.929201) (xy 302.126161 -309.898076) (xy 302.168782 -309.873469)
			(xy 302.214798 -309.856017) (xy 302.263017 -309.846173) (xy 302.312192 -309.844192) (xy 302.361047 -309.850124)
			(xy 302.408318 -309.863816) (xy 302.45278 -309.884914) (xy 302.493283 -309.91287) (xy 302.528776 -309.946962)
			(xy 302.558341 -309.986306) (xy 302.581212 -310.029883) (xy 302.596796 -310.076564) (xy 302.604691 -310.125141)
			(xy 302.605186 -310.149748) (xy 302.944034 -310.149748) (xy 302.947994 -310.100694) (xy 302.959771 -310.05291)
			(xy 302.979062 -310.007634) (xy 303.005365 -309.966038) (xy 303.038 -309.929201) (xy 303.076121 -309.898076)
			(xy 303.118742 -309.873469) (xy 303.164758 -309.856017) (xy 303.212977 -309.846173) (xy 303.262152 -309.844192)
			(xy 303.311007 -309.850124) (xy 303.358278 -309.863816) (xy 303.40274 -309.884914) (xy 303.443243 -309.91287)
			(xy 303.478736 -309.946962) (xy 303.508301 -309.986306) (xy 303.531172 -310.029883) (xy 303.546756 -310.076564)
			(xy 303.554651 -310.125141) (xy 303.555146 -310.149748) (xy 303.554651 -310.174355) (xy 303.546756 -310.222932)
			(xy 303.531172 -310.269613) (xy 303.508301 -310.31319) (xy 303.478736 -310.352534) (xy 303.443243 -310.386626)
			(xy 303.40274 -310.414582) (xy 303.358278 -310.43568) (xy 303.311007 -310.449372) (xy 303.262152 -310.455304)
			(xy 303.212977 -310.453323) (xy 303.164758 -310.443479) (xy 303.118742 -310.426027) (xy 303.076121 -310.40142)
			(xy 303.038 -310.370295) (xy 303.005365 -310.333458) (xy 302.979062 -310.291862) (xy 302.959771 -310.246586)
			(xy 302.947994 -310.198802) (xy 302.944034 -310.149748) (xy 302.605186 -310.149748) (xy 302.604691 -310.174355)
			(xy 302.596796 -310.222932) (xy 302.581212 -310.269613) (xy 302.558341 -310.31319) (xy 302.528776 -310.352534)
			(xy 302.493283 -310.386626) (xy 302.45278 -310.414582) (xy 302.408318 -310.43568) (xy 302.361047 -310.449372)
			(xy 302.312192 -310.455304) (xy 302.263017 -310.453323) (xy 302.214798 -310.443479) (xy 302.168782 -310.426027)
			(xy 302.126161 -310.40142) (xy 302.08804 -310.370295) (xy 302.055405 -310.333458) (xy 302.029102 -310.291862)
			(xy 302.009811 -310.246586) (xy 301.998034 -310.198802) (xy 301.994074 -310.149748) (xy 301.655226 -310.149748)
			(xy 301.654731 -310.174355) (xy 301.646836 -310.222932) (xy 301.631252 -310.269613) (xy 301.608381 -310.31319)
			(xy 301.578816 -310.352534) (xy 301.543323 -310.386626) (xy 301.50282 -310.414582) (xy 301.458358 -310.43568)
			(xy 301.411087 -310.449372) (xy 301.362232 -310.455304) (xy 301.313057 -310.453323) (xy 301.264838 -310.443479)
			(xy 301.218822 -310.426027) (xy 301.176201 -310.40142) (xy 301.13808 -310.370295) (xy 301.105445 -310.333458)
			(xy 301.079142 -310.291862) (xy 301.059851 -310.246586) (xy 301.048074 -310.198802) (xy 301.044114 -310.149748)
			(xy 300.705012 -310.149748) (xy 300.704517 -310.174355) (xy 300.696622 -310.222932) (xy 300.681038 -310.269613)
			(xy 300.658167 -310.31319) (xy 300.628602 -310.352534) (xy 300.593109 -310.386626) (xy 300.552606 -310.414582)
			(xy 300.508144 -310.43568) (xy 300.460873 -310.449372) (xy 300.412018 -310.455304) (xy 300.362843 -310.453323)
			(xy 300.314624 -310.443479) (xy 300.268608 -310.426027) (xy 300.225987 -310.40142) (xy 300.187866 -310.370295)
			(xy 300.155231 -310.333458) (xy 300.128928 -310.291862) (xy 300.109637 -310.246586) (xy 300.09786 -310.198802)
			(xy 300.0939 -310.149748) (xy 299.755052 -310.149748) (xy 299.754557 -310.174355) (xy 299.746662 -310.222932)
			(xy 299.731078 -310.269613) (xy 299.708207 -310.31319) (xy 299.678642 -310.352534) (xy 299.643149 -310.386626)
			(xy 299.602646 -310.414582) (xy 299.558184 -310.43568) (xy 299.510913 -310.449372) (xy 299.462058 -310.455304)
			(xy 299.412883 -310.453323) (xy 299.364664 -310.443479) (xy 299.318648 -310.426027) (xy 299.276027 -310.40142)
			(xy 299.237906 -310.370295) (xy 299.205271 -310.333458) (xy 299.178968 -310.291862) (xy 299.159677 -310.246586)
			(xy 299.1479 -310.198802) (xy 299.14394 -310.149748) (xy 298.805092 -310.149748) (xy 298.804597 -310.174355)
			(xy 298.796702 -310.222932) (xy 298.781118 -310.269613) (xy 298.758247 -310.31319) (xy 298.728682 -310.352534)
			(xy 298.693189 -310.386626) (xy 298.652686 -310.414582) (xy 298.608224 -310.43568) (xy 298.560953 -310.449372)
			(xy 298.512098 -310.455304) (xy 298.462923 -310.453323) (xy 298.414704 -310.443479) (xy 298.368688 -310.426027)
			(xy 298.326067 -310.40142) (xy 298.287946 -310.370295) (xy 298.255311 -310.333458) (xy 298.229008 -310.291862)
			(xy 298.209717 -310.246586) (xy 298.19794 -310.198802) (xy 298.19398 -310.149748) (xy 297.855132 -310.149748)
			(xy 297.854637 -310.174355) (xy 297.846742 -310.222932) (xy 297.831158 -310.269613) (xy 297.808287 -310.31319)
			(xy 297.778722 -310.352534) (xy 297.743229 -310.386626) (xy 297.702726 -310.414582) (xy 297.658264 -310.43568)
			(xy 297.610993 -310.449372) (xy 297.562138 -310.455304) (xy 297.512963 -310.453323) (xy 297.464744 -310.443479)
			(xy 297.418728 -310.426027) (xy 297.376107 -310.40142) (xy 297.337986 -310.370295) (xy 297.305351 -310.333458)
			(xy 297.279048 -310.291862) (xy 297.259757 -310.246586) (xy 297.24798 -310.198802) (xy 297.24402 -310.149748)
			(xy 296.905172 -310.149748) (xy 296.904677 -310.174355) (xy 296.896782 -310.222932) (xy 296.881198 -310.269613)
			(xy 296.858327 -310.31319) (xy 296.828762 -310.352534) (xy 296.793269 -310.386626) (xy 296.752766 -310.414582)
			(xy 296.708304 -310.43568) (xy 296.661033 -310.449372) (xy 296.612178 -310.455304) (xy 296.563003 -310.453323)
			(xy 296.514784 -310.443479) (xy 296.468768 -310.426027) (xy 296.426147 -310.40142) (xy 296.388026 -310.370295)
			(xy 296.355391 -310.333458) (xy 296.329088 -310.291862) (xy 296.309797 -310.246586) (xy 296.29802 -310.198802)
			(xy 296.29406 -310.149748) (xy 295.955212 -310.149748) (xy 295.954717 -310.174355) (xy 295.946822 -310.222932)
			(xy 295.931238 -310.269613) (xy 295.908367 -310.31319) (xy 295.878802 -310.352534) (xy 295.843309 -310.386626)
			(xy 295.802806 -310.414582) (xy 295.758344 -310.43568) (xy 295.711073 -310.449372) (xy 295.662218 -310.455304)
			(xy 295.613043 -310.453323) (xy 295.564824 -310.443479) (xy 295.518808 -310.426027) (xy 295.476187 -310.40142)
			(xy 295.438066 -310.370295) (xy 295.405431 -310.333458) (xy 295.379128 -310.291862) (xy 295.359837 -310.246586)
			(xy 295.34806 -310.198802) (xy 295.3441 -310.149748) (xy 295.004998 -310.149748) (xy 295.004503 -310.174355)
			(xy 294.996608 -310.222932) (xy 294.981024 -310.269613) (xy 294.958153 -310.31319) (xy 294.928588 -310.352534)
			(xy 294.893095 -310.386626) (xy 294.852592 -310.414582) (xy 294.80813 -310.43568) (xy 294.760859 -310.449372)
			(xy 294.712004 -310.455304) (xy 294.662829 -310.453323) (xy 294.61461 -310.443479) (xy 294.568594 -310.426027)
			(xy 294.525973 -310.40142) (xy 294.487852 -310.370295) (xy 294.455217 -310.333458) (xy 294.428914 -310.291862)
			(xy 294.409623 -310.246586) (xy 294.397846 -310.198802) (xy 294.393886 -310.149748) (xy 294.055038 -310.149748)
			(xy 294.054543 -310.174355) (xy 294.046648 -310.222932) (xy 294.031064 -310.269613) (xy 294.008193 -310.31319)
			(xy 293.978628 -310.352534) (xy 293.943135 -310.386626) (xy 293.902632 -310.414582) (xy 293.85817 -310.43568)
			(xy 293.810899 -310.449372) (xy 293.762044 -310.455304) (xy 293.712869 -310.453323) (xy 293.66465 -310.443479)
			(xy 293.618634 -310.426027) (xy 293.576013 -310.40142) (xy 293.537892 -310.370295) (xy 293.505257 -310.333458)
			(xy 293.478954 -310.291862) (xy 293.459663 -310.246586) (xy 293.447886 -310.198802) (xy 293.443926 -310.149748)
			(xy 293.105078 -310.149748) (xy 293.104583 -310.174355) (xy 293.096688 -310.222932) (xy 293.081104 -310.269613)
			(xy 293.058233 -310.31319) (xy 293.028668 -310.352534) (xy 292.993175 -310.386626) (xy 292.952672 -310.414582)
			(xy 292.90821 -310.43568) (xy 292.860939 -310.449372) (xy 292.812084 -310.455304) (xy 292.762909 -310.453323)
			(xy 292.71469 -310.443479) (xy 292.668674 -310.426027) (xy 292.626053 -310.40142) (xy 292.587932 -310.370295)
			(xy 292.555297 -310.333458) (xy 292.528994 -310.291862) (xy 292.509703 -310.246586) (xy 292.497926 -310.198802)
			(xy 292.493966 -310.149748) (xy 292.155118 -310.149748) (xy 292.154623 -310.174355) (xy 292.146728 -310.222932)
			(xy 292.131144 -310.269613) (xy 292.108273 -310.31319) (xy 292.078708 -310.352534) (xy 292.043215 -310.386626)
			(xy 292.002712 -310.414582) (xy 291.95825 -310.43568) (xy 291.910979 -310.449372) (xy 291.862124 -310.455304)
			(xy 291.812949 -310.453323) (xy 291.76473 -310.443479) (xy 291.718714 -310.426027) (xy 291.676093 -310.40142)
			(xy 291.637972 -310.370295) (xy 291.605337 -310.333458) (xy 291.579034 -310.291862) (xy 291.559743 -310.246586)
			(xy 291.547966 -310.198802) (xy 291.544006 -310.149748) (xy 291.205158 -310.149748) (xy 291.204663 -310.174355)
			(xy 291.196768 -310.222932) (xy 291.181184 -310.269613) (xy 291.158313 -310.31319) (xy 291.128748 -310.352534)
			(xy 291.093255 -310.386626) (xy 291.052752 -310.414582) (xy 291.00829 -310.43568) (xy 290.961019 -310.449372)
			(xy 290.912164 -310.455304) (xy 290.862989 -310.453323) (xy 290.81477 -310.443479) (xy 290.768754 -310.426027)
			(xy 290.726133 -310.40142) (xy 290.688012 -310.370295) (xy 290.655377 -310.333458) (xy 290.629074 -310.291862)
			(xy 290.609783 -310.246586) (xy 290.598006 -310.198802) (xy 290.594046 -310.149748) (xy 290.255198 -310.149748)
			(xy 290.254703 -310.174355) (xy 290.246808 -310.222932) (xy 290.231224 -310.269613) (xy 290.208353 -310.31319)
			(xy 290.178788 -310.352534) (xy 290.143295 -310.386626) (xy 290.102792 -310.414582) (xy 290.05833 -310.43568)
			(xy 290.011059 -310.449372) (xy 289.962204 -310.455304) (xy 289.913029 -310.453323) (xy 289.86481 -310.443479)
			(xy 289.818794 -310.426027) (xy 289.776173 -310.40142) (xy 289.738052 -310.370295) (xy 289.705417 -310.333458)
			(xy 289.679114 -310.291862) (xy 289.659823 -310.246586) (xy 289.648046 -310.198802) (xy 289.644086 -310.149748)
			(xy 289.305238 -310.149748) (xy 289.304743 -310.174355) (xy 289.296848 -310.222932) (xy 289.281264 -310.269613)
			(xy 289.258393 -310.31319) (xy 289.228828 -310.352534) (xy 289.193335 -310.386626) (xy 289.152832 -310.414582)
			(xy 289.10837 -310.43568) (xy 289.061099 -310.449372) (xy 289.012244 -310.455304) (xy 288.963069 -310.453323)
			(xy 288.91485 -310.443479) (xy 288.868834 -310.426027) (xy 288.826213 -310.40142) (xy 288.788092 -310.370295)
			(xy 288.755457 -310.333458) (xy 288.729154 -310.291862) (xy 288.709863 -310.246586) (xy 288.698086 -310.198802)
			(xy 288.694126 -310.149748) (xy 288.355024 -310.149748) (xy 288.354529 -310.174355) (xy 288.346634 -310.222932)
			(xy 288.33105 -310.269613) (xy 288.308179 -310.31319) (xy 288.278614 -310.352534) (xy 288.243121 -310.386626)
			(xy 288.202618 -310.414582) (xy 288.158156 -310.43568) (xy 288.110885 -310.449372) (xy 288.06203 -310.455304)
			(xy 288.012855 -310.453323) (xy 287.964636 -310.443479) (xy 287.91862 -310.426027) (xy 287.875999 -310.40142)
			(xy 287.837878 -310.370295) (xy 287.805243 -310.333458) (xy 287.77894 -310.291862) (xy 287.759649 -310.246586)
			(xy 287.747872 -310.198802) (xy 287.743912 -310.149748) (xy 287.405064 -310.149748) (xy 287.404569 -310.174355)
			(xy 287.396674 -310.222932) (xy 287.38109 -310.269613) (xy 287.358219 -310.31319) (xy 287.328654 -310.352534)
			(xy 287.293161 -310.386626) (xy 287.252658 -310.414582) (xy 287.208196 -310.43568) (xy 287.160925 -310.449372)
			(xy 287.11207 -310.455304) (xy 287.062895 -310.453323) (xy 287.014676 -310.443479) (xy 286.96866 -310.426027)
			(xy 286.926039 -310.40142) (xy 286.887918 -310.370295) (xy 286.855283 -310.333458) (xy 286.82898 -310.291862)
			(xy 286.809689 -310.246586) (xy 286.797912 -310.198802) (xy 286.793952 -310.149748) (xy 286.455104 -310.149748)
			(xy 286.454609 -310.174355) (xy 286.446714 -310.222932) (xy 286.43113 -310.269613) (xy 286.408259 -310.31319)
			(xy 286.378694 -310.352534) (xy 286.343201 -310.386626) (xy 286.302698 -310.414582) (xy 286.258236 -310.43568)
			(xy 286.210965 -310.449372) (xy 286.16211 -310.455304) (xy 286.112935 -310.453323) (xy 286.064716 -310.443479)
			(xy 286.0187 -310.426027) (xy 285.976079 -310.40142) (xy 285.937958 -310.370295) (xy 285.905323 -310.333458)
			(xy 285.87902 -310.291862) (xy 285.859729 -310.246586) (xy 285.847952 -310.198802) (xy 285.843992 -310.149748)
			(xy 285.505144 -310.149748) (xy 285.504649 -310.174355) (xy 285.496754 -310.222932) (xy 285.48117 -310.269613)
			(xy 285.458299 -310.31319) (xy 285.428734 -310.352534) (xy 285.393241 -310.386626) (xy 285.352738 -310.414582)
			(xy 285.308276 -310.43568) (xy 285.261005 -310.449372) (xy 285.21215 -310.455304) (xy 285.162975 -310.453323)
			(xy 285.114756 -310.443479) (xy 285.06874 -310.426027) (xy 285.026119 -310.40142) (xy 284.987998 -310.370295)
			(xy 284.955363 -310.333458) (xy 284.92906 -310.291862) (xy 284.909769 -310.246586) (xy 284.897992 -310.198802)
			(xy 284.894032 -310.149748) (xy 284.555184 -310.149748) (xy 284.554689 -310.174355) (xy 284.546794 -310.222932)
			(xy 284.53121 -310.269613) (xy 284.508339 -310.31319) (xy 284.478774 -310.352534) (xy 284.443281 -310.386626)
			(xy 284.402778 -310.414582) (xy 284.358316 -310.43568) (xy 284.311045 -310.449372) (xy 284.26219 -310.455304)
			(xy 284.213015 -310.453323) (xy 284.164796 -310.443479) (xy 284.11878 -310.426027) (xy 284.076159 -310.40142)
			(xy 284.038038 -310.370295) (xy 284.005403 -310.333458) (xy 283.9791 -310.291862) (xy 283.959809 -310.246586)
			(xy 283.948032 -310.198802) (xy 283.944072 -310.149748) (xy 283.605224 -310.149748) (xy 283.604729 -310.174355)
			(xy 283.596834 -310.222932) (xy 283.58125 -310.269613) (xy 283.558379 -310.31319) (xy 283.528814 -310.352534)
			(xy 283.493321 -310.386626) (xy 283.452818 -310.414582) (xy 283.408356 -310.43568) (xy 283.361085 -310.449372)
			(xy 283.31223 -310.455304) (xy 283.263055 -310.453323) (xy 283.214836 -310.443479) (xy 283.16882 -310.426027)
			(xy 283.126199 -310.40142) (xy 283.088078 -310.370295) (xy 283.055443 -310.333458) (xy 283.02914 -310.291862)
			(xy 283.009849 -310.246586) (xy 282.998072 -310.198802) (xy 282.994112 -310.149748) (xy 282.65501 -310.149748)
			(xy 282.654515 -310.174355) (xy 282.64662 -310.222932) (xy 282.631036 -310.269613) (xy 282.608165 -310.31319)
			(xy 282.5786 -310.352534) (xy 282.543107 -310.386626) (xy 282.502604 -310.414582) (xy 282.458142 -310.43568)
			(xy 282.410871 -310.449372) (xy 282.362016 -310.455304) (xy 282.312841 -310.453323) (xy 282.264622 -310.443479)
			(xy 282.218606 -310.426027) (xy 282.175985 -310.40142) (xy 282.137864 -310.370295) (xy 282.105229 -310.333458)
			(xy 282.078926 -310.291862) (xy 282.059635 -310.246586) (xy 282.047858 -310.198802) (xy 282.043898 -310.149748)
			(xy 281.704926 -310.149748) (xy 281.702688 -310.190991) (xy 281.692018 -310.239462) (xy 281.673646 -310.285569)
			(xy 281.648058 -310.328096) (xy 281.615928 -310.365923) (xy 281.578101 -310.398055) (xy 281.535574 -310.423644)
			(xy 281.489468 -310.442016) (xy 281.440997 -310.452688) (xy 281.391438 -310.455377) (xy 281.342097 -310.450014)
			(xy 281.294273 -310.43674) (xy 281.249227 -310.415904) (xy 281.208144 -310.388055) (xy 281.172108 -310.353928)
			(xy 281.142068 -310.31442) (xy 281.118814 -310.270572) (xy 281.10296 -310.223541) (xy 281.094924 -310.174564)
			(xy 281.094434 -310.149748) (xy 281.094617 -310.135565) (xy 281.097285 -310.107325) (xy 281.099768 -310.09336)
			(xy 281.102054 -310.080914) (xy 281.094688 -310.057292) (xy 281.017218 -309.979822) (xy 280.993596 -309.972456)
			(xy 280.98115 -309.974742) (xy 280.967184 -309.977221) (xy 280.938945 -309.979891) (xy 280.924762 -309.980076)
			(xy 280.910579 -309.979905) (xy 280.882339 -309.977229) (xy 280.868374 -309.974742) (xy 280.855928 -309.972456)
			(xy 280.832306 -309.979822) (xy 280.754836 -310.057292) (xy 280.74747 -310.080914) (xy 280.749756 -310.09336)
			(xy 280.752236 -310.107325) (xy 280.754906 -310.135565) (xy 280.75509 -310.149748) (xy 280.75457 -310.174564)
			(xy 280.746534 -310.22354) (xy 280.730679 -310.270572) (xy 280.707426 -310.314419) (xy 280.677385 -310.353926)
			(xy 280.641348 -310.388054) (xy 280.600266 -310.415902) (xy 280.555219 -310.436737) (xy 280.507395 -310.45001)
			(xy 280.458054 -310.455372) (xy 280.408495 -310.45268) (xy 280.360025 -310.442007) (xy 280.313919 -310.423634)
			(xy 280.271394 -310.398043) (xy 280.233568 -310.365911) (xy 280.201439 -310.328082) (xy 280.175853 -310.285554)
			(xy 280.157484 -310.239446) (xy 280.146815 -310.190975) (xy 280.144129 -310.141416) (xy 279.805497 -310.141416)
			(xy 279.805497 -310.141418) (xy 279.80281 -310.190981) (xy 279.79214 -310.239456) (xy 279.773769 -310.285567)
			(xy 279.748181 -310.328099) (xy 279.716049 -310.36593) (xy 279.67822 -310.398066) (xy 279.635691 -310.423658)
			(xy 279.589581 -310.442033) (xy 279.541107 -310.452706) (xy 279.491544 -310.455398) (xy 279.442199 -310.450035)
			(xy 279.394371 -310.436761) (xy 279.349321 -310.415924) (xy 279.308235 -310.388073) (xy 279.272195 -310.353943)
			(xy 279.242152 -310.314432) (xy 279.218897 -310.270582) (xy 279.203041 -310.223546) (xy 279.195004 -310.174566)
			(xy 279.194514 -310.149748) (xy 279.194697 -310.135565) (xy 279.197365 -310.107325) (xy 279.199848 -310.09336)
			(xy 279.202134 -310.080914) (xy 279.194768 -310.057292) (xy 279.117298 -309.979822) (xy 279.093676 -309.972456)
			(xy 279.08123 -309.974742) (xy 279.067265 -309.977224) (xy 279.039025 -309.979892) (xy 279.024842 -309.980076)
			(xy 279.010659 -309.979894) (xy 278.982419 -309.977226) (xy 278.968454 -309.974742) (xy 278.956008 -309.972456)
			(xy 278.932386 -309.979822) (xy 278.854916 -310.057292) (xy 278.84755 -310.080914) (xy 278.849836 -310.09336)
			(xy 278.852316 -310.107325) (xy 278.854986 -310.135565) (xy 278.85517 -310.149748) (xy 278.85467 -310.174563)
			(xy 278.846634 -310.223539) (xy 278.83078 -310.27057) (xy 278.807527 -310.314417) (xy 278.777487 -310.353924)
			(xy 278.741451 -310.388051) (xy 278.70037 -310.415899) (xy 278.655324 -310.436735) (xy 278.607501 -310.450009)
			(xy 278.558161 -310.455371) (xy 278.508603 -310.452681) (xy 278.460132 -310.44201) (xy 278.414027 -310.423638)
			(xy 278.371501 -310.398049) (xy 278.333675 -310.365918) (xy 278.301545 -310.32809) (xy 278.275958 -310.285564)
			(xy 278.257587 -310.239458) (xy 278.246917 -310.190988) (xy 278.244229 -310.141429) (xy 277.905043 -310.141429)
			(xy 277.90521 -310.149748) (xy 277.904715 -310.174355) (xy 277.89682 -310.222932) (xy 277.881236 -310.269613)
			(xy 277.858365 -310.31319) (xy 277.8288 -310.352534) (xy 277.793307 -310.386626) (xy 277.752804 -310.414582)
			(xy 277.708342 -310.43568) (xy 277.661071 -310.449372) (xy 277.612216 -310.455304) (xy 277.563041 -310.453323)
			(xy 277.514822 -310.443479) (xy 277.468806 -310.426027) (xy 277.426185 -310.40142) (xy 277.388064 -310.370295)
			(xy 277.355429 -310.333458) (xy 277.329126 -310.291862) (xy 277.309835 -310.246586) (xy 277.298058 -310.198802)
			(xy 277.294098 -310.149748) (xy 276.954996 -310.149748) (xy 276.954501 -310.174355) (xy 276.946606 -310.222932)
			(xy 276.931022 -310.269613) (xy 276.908151 -310.31319) (xy 276.878586 -310.352534) (xy 276.843093 -310.386626)
			(xy 276.80259 -310.414582) (xy 276.758128 -310.43568) (xy 276.710857 -310.449372) (xy 276.662002 -310.455304)
			(xy 276.612827 -310.453323) (xy 276.564608 -310.443479) (xy 276.518592 -310.426027) (xy 276.475971 -310.40142)
			(xy 276.43785 -310.370295) (xy 276.405215 -310.333458) (xy 276.378912 -310.291862) (xy 276.359621 -310.246586)
			(xy 276.347844 -310.198802) (xy 276.343884 -310.149748) (xy 276.005036 -310.149748) (xy 276.004541 -310.174355)
			(xy 275.996646 -310.222932) (xy 275.981062 -310.269613) (xy 275.958191 -310.31319) (xy 275.928626 -310.352534)
			(xy 275.893133 -310.386626) (xy 275.85263 -310.414582) (xy 275.808168 -310.43568) (xy 275.760897 -310.449372)
			(xy 275.712042 -310.455304) (xy 275.662867 -310.453323) (xy 275.614648 -310.443479) (xy 275.568632 -310.426027)
			(xy 275.526011 -310.40142) (xy 275.48789 -310.370295) (xy 275.455255 -310.333458) (xy 275.428952 -310.291862)
			(xy 275.409661 -310.246586) (xy 275.397884 -310.198802) (xy 275.393924 -310.149748) (xy 275.055076 -310.149748)
			(xy 275.054581 -310.174355) (xy 275.046686 -310.222932) (xy 275.031102 -310.269613) (xy 275.008231 -310.31319)
			(xy 274.978666 -310.352534) (xy 274.943173 -310.386626) (xy 274.90267 -310.414582) (xy 274.858208 -310.43568)
			(xy 274.810937 -310.449372) (xy 274.762082 -310.455304) (xy 274.712907 -310.453323) (xy 274.664688 -310.443479)
			(xy 274.618672 -310.426027) (xy 274.576051 -310.40142) (xy 274.53793 -310.370295) (xy 274.505295 -310.333458)
			(xy 274.478992 -310.291862) (xy 274.459701 -310.246586) (xy 274.447924 -310.198802) (xy 274.443964 -310.149748)
			(xy 274.105116 -310.149748) (xy 274.104621 -310.174355) (xy 274.096726 -310.222932) (xy 274.081142 -310.269613)
			(xy 274.058271 -310.31319) (xy 274.028706 -310.352534) (xy 273.993213 -310.386626) (xy 273.95271 -310.414582)
			(xy 273.908248 -310.43568) (xy 273.860977 -310.449372) (xy 273.812122 -310.455304) (xy 273.762947 -310.453323)
			(xy 273.714728 -310.443479) (xy 273.668712 -310.426027) (xy 273.626091 -310.40142) (xy 273.58797 -310.370295)
			(xy 273.555335 -310.333458) (xy 273.529032 -310.291862) (xy 273.509741 -310.246586) (xy 273.497964 -310.198802)
			(xy 273.494004 -310.149748) (xy 273.155156 -310.149748) (xy 273.154661 -310.174355) (xy 273.146766 -310.222932)
			(xy 273.131182 -310.269613) (xy 273.108311 -310.31319) (xy 273.078746 -310.352534) (xy 273.043253 -310.386626)
			(xy 273.00275 -310.414582) (xy 272.958288 -310.43568) (xy 272.911017 -310.449372) (xy 272.862162 -310.455304)
			(xy 272.812987 -310.453323) (xy 272.764768 -310.443479) (xy 272.718752 -310.426027) (xy 272.676131 -310.40142)
			(xy 272.63801 -310.370295) (xy 272.605375 -310.333458) (xy 272.579072 -310.291862) (xy 272.559781 -310.246586)
			(xy 272.548004 -310.198802) (xy 272.544044 -310.149748) (xy 272.205196 -310.149748) (xy 272.204701 -310.174355)
			(xy 272.196806 -310.222932) (xy 272.181222 -310.269613) (xy 272.158351 -310.31319) (xy 272.128786 -310.352534)
			(xy 272.093293 -310.386626) (xy 272.05279 -310.414582) (xy 272.008328 -310.43568) (xy 271.961057 -310.449372)
			(xy 271.912202 -310.455304) (xy 271.863027 -310.453323) (xy 271.814808 -310.443479) (xy 271.768792 -310.426027)
			(xy 271.726171 -310.40142) (xy 271.68805 -310.370295) (xy 271.655415 -310.333458) (xy 271.629112 -310.291862)
			(xy 271.609821 -310.246586) (xy 271.598044 -310.198802) (xy 271.594084 -310.149748) (xy 271.255236 -310.149748)
			(xy 271.254741 -310.174355) (xy 271.246846 -310.222932) (xy 271.231262 -310.269613) (xy 271.208391 -310.31319)
			(xy 271.178826 -310.352534) (xy 271.143333 -310.386626) (xy 271.10283 -310.414582) (xy 271.058368 -310.43568)
			(xy 271.011097 -310.449372) (xy 270.962242 -310.455304) (xy 270.913067 -310.453323) (xy 270.864848 -310.443479)
			(xy 270.818832 -310.426027) (xy 270.776211 -310.40142) (xy 270.73809 -310.370295) (xy 270.705455 -310.333458)
			(xy 270.679152 -310.291862) (xy 270.659861 -310.246586) (xy 270.648084 -310.198802) (xy 270.644124 -310.149748)
			(xy 270.326866 -310.149748) (xy 270.326362 -310.175456) (xy 270.318319 -310.226238) (xy 270.302431 -310.275137)
			(xy 270.279088 -310.320949) (xy 270.248867 -310.362545) (xy 270.212511 -310.398901) (xy 270.170915 -310.429122)
			(xy 270.125103 -310.452465) (xy 270.076204 -310.468353) (xy 270.025422 -310.476396) (xy 269.974006 -310.476396)
			(xy 269.923224 -310.468353) (xy 269.874325 -310.452465) (xy 269.828513 -310.429122) (xy 269.786917 -310.398901)
			(xy 269.750561 -310.362545) (xy 269.72034 -310.320949) (xy 269.696997 -310.275137) (xy 269.681109 -310.226238)
			(xy 269.673066 -310.175456) (xy 269.376402 -310.175456) (xy 269.368359 -310.226238) (xy 269.352471 -310.275137)
			(xy 269.329128 -310.320949) (xy 269.298907 -310.362545) (xy 269.262551 -310.398901) (xy 269.220955 -310.429122)
			(xy 269.175143 -310.452465) (xy 269.126244 -310.468353) (xy 269.075462 -310.476396) (xy 269.024046 -310.476396)
			(xy 268.973264 -310.468353) (xy 268.924365 -310.452465) (xy 268.878553 -310.429122) (xy 268.836957 -310.398901)
			(xy 268.800601 -310.362545) (xy 268.77038 -310.320949) (xy 268.747037 -310.275137) (xy 268.731149 -310.226238)
			(xy 268.723106 -310.175456) (xy 268.404215 -310.175456) (xy 268.396458 -310.223186) (xy 268.380874 -310.269867)
			(xy 268.358003 -310.313444) (xy 268.328438 -310.352788) (xy 268.292945 -310.38688) (xy 268.252442 -310.414836)
			(xy 268.20798 -310.435934) (xy 268.160709 -310.449626) (xy 268.111854 -310.455558) (xy 268.062679 -310.453577)
			(xy 268.01446 -310.443733) (xy 267.968444 -310.426281) (xy 267.925823 -310.401674) (xy 267.887702 -310.370549)
			(xy 267.855067 -310.333712) (xy 267.828764 -310.292116) (xy 267.809473 -310.24684) (xy 267.797696 -310.199056)
			(xy 267.793736 -310.150002) (xy 267.053672 -310.150002) (xy 267.055486 -310.156179) (xy 267.063242 -310.210127)
			(xy 267.063728 -310.237378) (xy 267.063203 -310.266152) (xy 267.054551 -310.323046) (xy 267.037455 -310.377996)
			(xy 267.012301 -310.429756) (xy 266.979662 -310.477153) (xy 266.96035 -310.49849) (xy 266.951009 -310.509061)
			(xy 266.93809 -310.534129) (xy 266.932524 -310.561776) (xy 266.934738 -310.58989) (xy 266.944561 -310.616326)
			(xy 266.961243 -310.639064) (xy 266.983512 -310.656368) (xy 266.996418 -310.662066) (xy 267.022494 -310.673139)
			(xy 267.071314 -310.701876) (xy 267.115349 -310.737516) (xy 267.153631 -310.779275) (xy 267.185318 -310.826234)
			(xy 267.209715 -310.877362) (xy 267.226283 -310.931535) (xy 267.234661 -310.987563) (xy 267.235178 -311.015888)
			(xy 267.234692 -311.043139) (xy 267.226936 -311.097087) (xy 267.226092 -311.099962) (xy 268.74395 -311.099962)
			(xy 268.74791 -311.050908) (xy 268.759687 -311.003124) (xy 268.778978 -310.957848) (xy 268.805281 -310.916252)
			(xy 268.837916 -310.879415) (xy 268.876037 -310.84829) (xy 268.918658 -310.823683) (xy 268.964674 -310.806231)
			(xy 269.012893 -310.796387) (xy 269.062068 -310.794406) (xy 269.110923 -310.800338) (xy 269.158194 -310.81403)
			(xy 269.202656 -310.835128) (xy 269.243159 -310.863084) (xy 269.278652 -310.897176) (xy 269.308217 -310.93652)
			(xy 269.331088 -310.980097) (xy 269.346672 -311.026778) (xy 269.354567 -311.075355) (xy 269.355062 -311.099962)
			(xy 269.69391 -311.099962) (xy 269.69787 -311.050908) (xy 269.709647 -311.003124) (xy 269.728938 -310.957848)
			(xy 269.755241 -310.916252) (xy 269.787876 -310.879415) (xy 269.825997 -310.84829) (xy 269.868618 -310.823683)
			(xy 269.914634 -310.806231) (xy 269.962853 -310.796387) (xy 270.012028 -310.794406) (xy 270.060883 -310.800338)
			(xy 270.108154 -310.81403) (xy 270.152616 -310.835128) (xy 270.193119 -310.863084) (xy 270.228612 -310.897176)
			(xy 270.258177 -310.93652) (xy 270.281048 -310.980097) (xy 270.296632 -311.026778) (xy 270.304527 -311.075355)
			(xy 270.305022 -311.099962) (xy 270.644124 -311.099962) (xy 270.648084 -311.050908) (xy 270.659861 -311.003124)
			(xy 270.679152 -310.957848) (xy 270.705455 -310.916252) (xy 270.73809 -310.879415) (xy 270.776211 -310.84829)
			(xy 270.818832 -310.823683) (xy 270.864848 -310.806231) (xy 270.913067 -310.796387) (xy 270.962242 -310.794406)
			(xy 271.011097 -310.800338) (xy 271.058368 -310.81403) (xy 271.10283 -310.835128) (xy 271.143333 -310.863084)
			(xy 271.178826 -310.897176) (xy 271.208391 -310.93652) (xy 271.231262 -310.980097) (xy 271.246846 -311.026778)
			(xy 271.254741 -311.075355) (xy 271.255236 -311.099962) (xy 271.254741 -311.124569) (xy 271.254562 -311.12567)
			(xy 271.57324 -311.12567) (xy 271.57324 -311.074254) (xy 271.581283 -311.023472) (xy 271.597171 -310.974573)
			(xy 271.620514 -310.928761) (xy 271.650735 -310.887165) (xy 271.687091 -310.850809) (xy 271.728687 -310.820588)
			(xy 271.774499 -310.797245) (xy 271.823398 -310.781357) (xy 271.87418 -310.773314) (xy 271.925596 -310.773314)
			(xy 271.976378 -310.781357) (xy 272.025277 -310.797245) (xy 272.071089 -310.820588) (xy 272.112685 -310.850809)
			(xy 272.149041 -310.887165) (xy 272.179262 -310.928761) (xy 272.202605 -310.974573) (xy 272.218493 -311.023472)
			(xy 272.226536 -311.074254) (xy 272.22704 -311.099962) (xy 272.544044 -311.099962) (xy 272.548004 -311.050908)
			(xy 272.559781 -311.003124) (xy 272.579072 -310.957848) (xy 272.605375 -310.916252) (xy 272.63801 -310.879415)
			(xy 272.676131 -310.84829) (xy 272.718752 -310.823683) (xy 272.764768 -310.806231) (xy 272.812987 -310.796387)
			(xy 272.862162 -310.794406) (xy 272.911017 -310.800338) (xy 272.958288 -310.81403) (xy 273.00275 -310.835128)
			(xy 273.043253 -310.863084) (xy 273.078746 -310.897176) (xy 273.108311 -310.93652) (xy 273.131182 -310.980097)
			(xy 273.146766 -311.026778) (xy 273.154661 -311.075355) (xy 273.155156 -311.099962) (xy 273.154661 -311.124569)
			(xy 273.154482 -311.12567) (xy 273.47316 -311.12567) (xy 273.47316 -311.074254) (xy 273.481203 -311.023472)
			(xy 273.497091 -310.974573) (xy 273.520434 -310.928761) (xy 273.550655 -310.887165) (xy 273.587011 -310.850809)
			(xy 273.628607 -310.820588) (xy 273.674419 -310.797245) (xy 273.723318 -310.781357) (xy 273.7741 -310.773314)
			(xy 273.825516 -310.773314) (xy 273.876298 -310.781357) (xy 273.925197 -310.797245) (xy 273.971009 -310.820588)
			(xy 274.012605 -310.850809) (xy 274.048961 -310.887165) (xy 274.079182 -310.928761) (xy 274.102525 -310.974573)
			(xy 274.118413 -311.023472) (xy 274.126456 -311.074254) (xy 274.12696 -311.099962) (xy 274.443964 -311.099962)
			(xy 274.447924 -311.050908) (xy 274.459701 -311.003124) (xy 274.478992 -310.957848) (xy 274.505295 -310.916252)
			(xy 274.53793 -310.879415) (xy 274.576051 -310.84829) (xy 274.618672 -310.823683) (xy 274.664688 -310.806231)
			(xy 274.712907 -310.796387) (xy 274.762082 -310.794406) (xy 274.810937 -310.800338) (xy 274.858208 -310.81403)
			(xy 274.90267 -310.835128) (xy 274.943173 -310.863084) (xy 274.978666 -310.897176) (xy 275.008231 -310.93652)
			(xy 275.031102 -310.980097) (xy 275.046686 -311.026778) (xy 275.054581 -311.075355) (xy 275.055076 -311.099962)
			(xy 275.393924 -311.099962) (xy 275.397884 -311.050908) (xy 275.409661 -311.003124) (xy 275.428952 -310.957848)
			(xy 275.455255 -310.916252) (xy 275.48789 -310.879415) (xy 275.526011 -310.84829) (xy 275.568632 -310.823683)
			(xy 275.614648 -310.806231) (xy 275.662867 -310.796387) (xy 275.712042 -310.794406) (xy 275.760897 -310.800338)
			(xy 275.808168 -310.81403) (xy 275.85263 -310.835128) (xy 275.893133 -310.863084) (xy 275.928626 -310.897176)
			(xy 275.958191 -310.93652) (xy 275.981062 -310.980097) (xy 275.996646 -311.026778) (xy 276.004541 -311.075355)
			(xy 276.005036 -311.099962) (xy 276.343884 -311.099962) (xy 276.347844 -311.050908) (xy 276.359621 -311.003124)
			(xy 276.378912 -310.957848) (xy 276.405215 -310.916252) (xy 276.43785 -310.879415) (xy 276.475971 -310.84829)
			(xy 276.518592 -310.823683) (xy 276.564608 -310.806231) (xy 276.612827 -310.796387) (xy 276.662002 -310.794406)
			(xy 276.710857 -310.800338) (xy 276.758128 -310.81403) (xy 276.80259 -310.835128) (xy 276.843093 -310.863084)
			(xy 276.878586 -310.897176) (xy 276.908151 -310.93652) (xy 276.931022 -310.980097) (xy 276.946606 -311.026778)
			(xy 276.954501 -311.075355) (xy 276.954996 -311.099962) (xy 277.294098 -311.099962) (xy 277.298058 -311.050908)
			(xy 277.309835 -311.003124) (xy 277.329126 -310.957848) (xy 277.355429 -310.916252) (xy 277.388064 -310.879415)
			(xy 277.426185 -310.84829) (xy 277.468806 -310.823683) (xy 277.514822 -310.806231) (xy 277.563041 -310.796387)
			(xy 277.612216 -310.794406) (xy 277.661071 -310.800338) (xy 277.708342 -310.81403) (xy 277.752804 -310.835128)
			(xy 277.793307 -310.863084) (xy 277.8288 -310.897176) (xy 277.858365 -310.93652) (xy 277.881236 -310.980097)
			(xy 277.89682 -311.026778) (xy 277.904715 -311.075355) (xy 277.90521 -311.099962) (xy 278.244058 -311.099962)
			(xy 278.248018 -311.050908) (xy 278.259795 -311.003124) (xy 278.279086 -310.957848) (xy 278.305389 -310.916252)
			(xy 278.338024 -310.879415) (xy 278.376145 -310.84829) (xy 278.418766 -310.823683) (xy 278.464782 -310.806231)
			(xy 278.513001 -310.796387) (xy 278.562176 -310.794406) (xy 278.611031 -310.800338) (xy 278.658302 -310.81403)
			(xy 278.702764 -310.835128) (xy 278.743267 -310.863084) (xy 278.77876 -310.897176) (xy 278.808325 -310.93652)
			(xy 278.831196 -310.980097) (xy 278.84678 -311.026778) (xy 278.854675 -311.075355) (xy 278.85517 -311.099962)
			(xy 279.194018 -311.099962) (xy 279.197978 -311.050908) (xy 279.209755 -311.003124) (xy 279.229046 -310.957848)
			(xy 279.255349 -310.916252) (xy 279.287984 -310.879415) (xy 279.326105 -310.84829) (xy 279.368726 -310.823683)
			(xy 279.414742 -310.806231) (xy 279.462961 -310.796387) (xy 279.512136 -310.794406) (xy 279.560991 -310.800338)
			(xy 279.608262 -310.81403) (xy 279.652724 -310.835128) (xy 279.693227 -310.863084) (xy 279.72872 -310.897176)
			(xy 279.758285 -310.93652) (xy 279.781156 -310.980097) (xy 279.79674 -311.026778) (xy 279.804635 -311.075355)
			(xy 279.80513 -311.099962) (xy 280.143978 -311.099962) (xy 280.147938 -311.050908) (xy 280.159715 -311.003124)
			(xy 280.179006 -310.957848) (xy 280.205309 -310.916252) (xy 280.237944 -310.879415) (xy 280.276065 -310.84829)
			(xy 280.318686 -310.823683) (xy 280.364702 -310.806231) (xy 280.412921 -310.796387) (xy 280.462096 -310.794406)
			(xy 280.510951 -310.800338) (xy 280.558222 -310.81403) (xy 280.602684 -310.835128) (xy 280.643187 -310.863084)
			(xy 280.67868 -310.897176) (xy 280.708245 -310.93652) (xy 280.731116 -310.980097) (xy 280.7467 -311.026778)
			(xy 280.754595 -311.075355) (xy 280.75509 -311.099962) (xy 281.093938 -311.099962) (xy 281.097898 -311.050908)
			(xy 281.109675 -311.003124) (xy 281.128966 -310.957848) (xy 281.155269 -310.916252) (xy 281.187904 -310.879415)
			(xy 281.226025 -310.84829) (xy 281.268646 -310.823683) (xy 281.314662 -310.806231) (xy 281.362881 -310.796387)
			(xy 281.412056 -310.794406) (xy 281.460911 -310.800338) (xy 281.508182 -310.81403) (xy 281.552644 -310.835128)
			(xy 281.593147 -310.863084) (xy 281.62864 -310.897176) (xy 281.658205 -310.93652) (xy 281.681076 -310.980097)
			(xy 281.69666 -311.026778) (xy 281.704555 -311.075355) (xy 281.70505 -311.099962) (xy 282.043898 -311.099962)
			(xy 282.047858 -311.050908) (xy 282.059635 -311.003124) (xy 282.078926 -310.957848) (xy 282.105229 -310.916252)
			(xy 282.137864 -310.879415) (xy 282.175985 -310.84829) (xy 282.218606 -310.823683) (xy 282.264622 -310.806231)
			(xy 282.312841 -310.796387) (xy 282.362016 -310.794406) (xy 282.410871 -310.800338) (xy 282.458142 -310.81403)
			(xy 282.502604 -310.835128) (xy 282.543107 -310.863084) (xy 282.5786 -310.897176) (xy 282.608165 -310.93652)
			(xy 282.631036 -310.980097) (xy 282.64662 -311.026778) (xy 282.654515 -311.075355) (xy 282.65501 -311.099962)
			(xy 282.994112 -311.099962) (xy 282.998072 -311.050908) (xy 283.009849 -311.003124) (xy 283.02914 -310.957848)
			(xy 283.055443 -310.916252) (xy 283.088078 -310.879415) (xy 283.126199 -310.84829) (xy 283.16882 -310.823683)
			(xy 283.214836 -310.806231) (xy 283.263055 -310.796387) (xy 283.31223 -310.794406) (xy 283.361085 -310.800338)
			(xy 283.408356 -310.81403) (xy 283.452818 -310.835128) (xy 283.493321 -310.863084) (xy 283.528814 -310.897176)
			(xy 283.558379 -310.93652) (xy 283.58125 -310.980097) (xy 283.596834 -311.026778) (xy 283.604729 -311.075355)
			(xy 283.605224 -311.099962) (xy 283.944072 -311.099962) (xy 283.948032 -311.050908) (xy 283.959809 -311.003124)
			(xy 283.9791 -310.957848) (xy 284.005403 -310.916252) (xy 284.038038 -310.879415) (xy 284.076159 -310.84829)
			(xy 284.11878 -310.823683) (xy 284.164796 -310.806231) (xy 284.213015 -310.796387) (xy 284.26219 -310.794406)
			(xy 284.311045 -310.800338) (xy 284.358316 -310.81403) (xy 284.402778 -310.835128) (xy 284.443281 -310.863084)
			(xy 284.478774 -310.897176) (xy 284.508339 -310.93652) (xy 284.53121 -310.980097) (xy 284.546794 -311.026778)
			(xy 284.554689 -311.075355) (xy 284.555184 -311.099962) (xy 284.894032 -311.099962) (xy 284.897992 -311.050908)
			(xy 284.909769 -311.003124) (xy 284.92906 -310.957848) (xy 284.955363 -310.916252) (xy 284.987998 -310.879415)
			(xy 285.026119 -310.84829) (xy 285.06874 -310.823683) (xy 285.114756 -310.806231) (xy 285.162975 -310.796387)
			(xy 285.21215 -310.794406) (xy 285.261005 -310.800338) (xy 285.308276 -310.81403) (xy 285.352738 -310.835128)
			(xy 285.393241 -310.863084) (xy 285.428734 -310.897176) (xy 285.458299 -310.93652) (xy 285.48117 -310.980097)
			(xy 285.496754 -311.026778) (xy 285.504649 -311.075355) (xy 285.505144 -311.099962) (xy 285.843992 -311.099962)
			(xy 285.847952 -311.050908) (xy 285.859729 -311.003124) (xy 285.87902 -310.957848) (xy 285.905323 -310.916252)
			(xy 285.937958 -310.879415) (xy 285.976079 -310.84829) (xy 286.0187 -310.823683) (xy 286.064716 -310.806231)
			(xy 286.112935 -310.796387) (xy 286.16211 -310.794406) (xy 286.210965 -310.800338) (xy 286.258236 -310.81403)
			(xy 286.302698 -310.835128) (xy 286.343201 -310.863084) (xy 286.378694 -310.897176) (xy 286.408259 -310.93652)
			(xy 286.43113 -310.980097) (xy 286.446714 -311.026778) (xy 286.454609 -311.075355) (xy 286.455104 -311.099962)
			(xy 286.793952 -311.099962) (xy 286.797912 -311.050908) (xy 286.809689 -311.003124) (xy 286.82898 -310.957848)
			(xy 286.855283 -310.916252) (xy 286.887918 -310.879415) (xy 286.926039 -310.84829) (xy 286.96866 -310.823683)
			(xy 287.014676 -310.806231) (xy 287.062895 -310.796387) (xy 287.11207 -310.794406) (xy 287.160925 -310.800338)
			(xy 287.208196 -310.81403) (xy 287.252658 -310.835128) (xy 287.293161 -310.863084) (xy 287.328654 -310.897176)
			(xy 287.358219 -310.93652) (xy 287.38109 -310.980097) (xy 287.396674 -311.026778) (xy 287.404569 -311.075355)
			(xy 287.405064 -311.099962) (xy 287.743912 -311.099962) (xy 287.747872 -311.050908) (xy 287.759649 -311.003124)
			(xy 287.77894 -310.957848) (xy 287.805243 -310.916252) (xy 287.837878 -310.879415) (xy 287.875999 -310.84829)
			(xy 287.91862 -310.823683) (xy 287.964636 -310.806231) (xy 288.012855 -310.796387) (xy 288.06203 -310.794406)
			(xy 288.110885 -310.800338) (xy 288.158156 -310.81403) (xy 288.202618 -310.835128) (xy 288.243121 -310.863084)
			(xy 288.278614 -310.897176) (xy 288.308179 -310.93652) (xy 288.33105 -310.980097) (xy 288.346634 -311.026778)
			(xy 288.354529 -311.075355) (xy 288.355024 -311.099962) (xy 288.694126 -311.099962) (xy 288.698086 -311.050908)
			(xy 288.709863 -311.003124) (xy 288.729154 -310.957848) (xy 288.755457 -310.916252) (xy 288.788092 -310.879415)
			(xy 288.826213 -310.84829) (xy 288.868834 -310.823683) (xy 288.91485 -310.806231) (xy 288.963069 -310.796387)
			(xy 289.012244 -310.794406) (xy 289.061099 -310.800338) (xy 289.10837 -310.81403) (xy 289.152832 -310.835128)
			(xy 289.193335 -310.863084) (xy 289.228828 -310.897176) (xy 289.258393 -310.93652) (xy 289.281264 -310.980097)
			(xy 289.296848 -311.026778) (xy 289.304743 -311.075355) (xy 289.305238 -311.099962) (xy 289.644086 -311.099962)
			(xy 289.648046 -311.050908) (xy 289.659823 -311.003124) (xy 289.679114 -310.957848) (xy 289.705417 -310.916252)
			(xy 289.738052 -310.879415) (xy 289.776173 -310.84829) (xy 289.818794 -310.823683) (xy 289.86481 -310.806231)
			(xy 289.913029 -310.796387) (xy 289.962204 -310.794406) (xy 290.011059 -310.800338) (xy 290.05833 -310.81403)
			(xy 290.102792 -310.835128) (xy 290.143295 -310.863084) (xy 290.178788 -310.897176) (xy 290.208353 -310.93652)
			(xy 290.231224 -310.980097) (xy 290.246808 -311.026778) (xy 290.254703 -311.075355) (xy 290.255198 -311.099962)
			(xy 290.254703 -311.124569) (xy 290.254524 -311.12567) (xy 290.573202 -311.12567) (xy 290.573202 -311.074254)
			(xy 290.581245 -311.023472) (xy 290.597133 -310.974573) (xy 290.620476 -310.928761) (xy 290.650697 -310.887165)
			(xy 290.687053 -310.850809) (xy 290.728649 -310.820588) (xy 290.774461 -310.797245) (xy 290.82336 -310.781357)
			(xy 290.874142 -310.773314) (xy 290.925558 -310.773314) (xy 290.97634 -310.781357) (xy 291.025239 -310.797245)
			(xy 291.071051 -310.820588) (xy 291.112647 -310.850809) (xy 291.149003 -310.887165) (xy 291.179224 -310.928761)
			(xy 291.202567 -310.974573) (xy 291.218455 -311.023472) (xy 291.226498 -311.074254) (xy 291.227002 -311.099962)
			(xy 291.544006 -311.099962) (xy 291.547966 -311.050908) (xy 291.559743 -311.003124) (xy 291.579034 -310.957848)
			(xy 291.605337 -310.916252) (xy 291.637972 -310.879415) (xy 291.676093 -310.84829) (xy 291.718714 -310.823683)
			(xy 291.76473 -310.806231) (xy 291.812949 -310.796387) (xy 291.862124 -310.794406) (xy 291.910979 -310.800338)
			(xy 291.95825 -310.81403) (xy 292.002712 -310.835128) (xy 292.043215 -310.863084) (xy 292.078708 -310.897176)
			(xy 292.108273 -310.93652) (xy 292.131144 -310.980097) (xy 292.146728 -311.026778) (xy 292.154623 -311.075355)
			(xy 292.155118 -311.099962) (xy 292.154623 -311.124569) (xy 292.154444 -311.12567) (xy 292.473122 -311.12567)
			(xy 292.473122 -311.074254) (xy 292.481165 -311.023472) (xy 292.497053 -310.974573) (xy 292.520396 -310.928761)
			(xy 292.550617 -310.887165) (xy 292.586973 -310.850809) (xy 292.628569 -310.820588) (xy 292.674381 -310.797245)
			(xy 292.72328 -310.781357) (xy 292.774062 -310.773314) (xy 292.825478 -310.773314) (xy 292.87626 -310.781357)
			(xy 292.925159 -310.797245) (xy 292.970971 -310.820588) (xy 293.012567 -310.850809) (xy 293.048923 -310.887165)
			(xy 293.079144 -310.928761) (xy 293.102487 -310.974573) (xy 293.118375 -311.023472) (xy 293.126418 -311.074254)
			(xy 293.126922 -311.099962) (xy 293.443926 -311.099962) (xy 293.447886 -311.050908) (xy 293.459663 -311.003124)
			(xy 293.478954 -310.957848) (xy 293.505257 -310.916252) (xy 293.537892 -310.879415) (xy 293.576013 -310.84829)
			(xy 293.618634 -310.823683) (xy 293.66465 -310.806231) (xy 293.712869 -310.796387) (xy 293.762044 -310.794406)
			(xy 293.810899 -310.800338) (xy 293.85817 -310.81403) (xy 293.902632 -310.835128) (xy 293.943135 -310.863084)
			(xy 293.978628 -310.897176) (xy 294.008193 -310.93652) (xy 294.031064 -310.980097) (xy 294.046648 -311.026778)
			(xy 294.054543 -311.075355) (xy 294.055038 -311.099962) (xy 294.054543 -311.124569) (xy 294.054364 -311.12567)
			(xy 294.373042 -311.12567) (xy 294.373042 -311.074254) (xy 294.381085 -311.023472) (xy 294.396973 -310.974573)
			(xy 294.420316 -310.928761) (xy 294.450537 -310.887165) (xy 294.486893 -310.850809) (xy 294.528489 -310.820588)
			(xy 294.574301 -310.797245) (xy 294.6232 -310.781357) (xy 294.673982 -310.773314) (xy 294.725398 -310.773314)
			(xy 294.77618 -310.781357) (xy 294.825079 -310.797245) (xy 294.870891 -310.820588) (xy 294.912487 -310.850809)
			(xy 294.948843 -310.887165) (xy 294.979064 -310.928761) (xy 295.002407 -310.974573) (xy 295.018295 -311.023472)
			(xy 295.026338 -311.074254) (xy 295.026842 -311.099962) (xy 295.3441 -311.099962) (xy 295.34806 -311.050908)
			(xy 295.359837 -311.003124) (xy 295.379128 -310.957848) (xy 295.405431 -310.916252) (xy 295.438066 -310.879415)
			(xy 295.476187 -310.84829) (xy 295.518808 -310.823683) (xy 295.564824 -310.806231) (xy 295.613043 -310.796387)
			(xy 295.662218 -310.794406) (xy 295.711073 -310.800338) (xy 295.758344 -310.81403) (xy 295.802806 -310.835128)
			(xy 295.843309 -310.863084) (xy 295.878802 -310.897176) (xy 295.908367 -310.93652) (xy 295.931238 -310.980097)
			(xy 295.946822 -311.026778) (xy 295.954717 -311.075355) (xy 295.955212 -311.099962) (xy 295.954717 -311.124569)
			(xy 295.954538 -311.12567) (xy 296.273216 -311.12567) (xy 296.273216 -311.074254) (xy 296.281259 -311.023472)
			(xy 296.297147 -310.974573) (xy 296.32049 -310.928761) (xy 296.350711 -310.887165) (xy 296.387067 -310.850809)
			(xy 296.428663 -310.820588) (xy 296.474475 -310.797245) (xy 296.523374 -310.781357) (xy 296.574156 -310.773314)
			(xy 296.625572 -310.773314) (xy 296.676354 -310.781357) (xy 296.725253 -310.797245) (xy 296.771065 -310.820588)
			(xy 296.812661 -310.850809) (xy 296.849017 -310.887165) (xy 296.879238 -310.928761) (xy 296.902581 -310.974573)
			(xy 296.918469 -311.023472) (xy 296.926512 -311.074254) (xy 296.927016 -311.099962) (xy 297.24402 -311.099962)
			(xy 297.24798 -311.050908) (xy 297.259757 -311.003124) (xy 297.279048 -310.957848) (xy 297.305351 -310.916252)
			(xy 297.337986 -310.879415) (xy 297.376107 -310.84829) (xy 297.418728 -310.823683) (xy 297.464744 -310.806231)
			(xy 297.512963 -310.796387) (xy 297.562138 -310.794406) (xy 297.610993 -310.800338) (xy 297.658264 -310.81403)
			(xy 297.702726 -310.835128) (xy 297.743229 -310.863084) (xy 297.778722 -310.897176) (xy 297.808287 -310.93652)
			(xy 297.831158 -310.980097) (xy 297.846742 -311.026778) (xy 297.854637 -311.075355) (xy 297.855132 -311.099962)
			(xy 297.854637 -311.124569) (xy 297.854458 -311.12567) (xy 298.173136 -311.12567) (xy 298.173136 -311.074254)
			(xy 298.181179 -311.023472) (xy 298.197067 -310.974573) (xy 298.22041 -310.928761) (xy 298.250631 -310.887165)
			(xy 298.286987 -310.850809) (xy 298.328583 -310.820588) (xy 298.374395 -310.797245) (xy 298.423294 -310.781357)
			(xy 298.474076 -310.773314) (xy 298.525492 -310.773314) (xy 298.576274 -310.781357) (xy 298.625173 -310.797245)
			(xy 298.670985 -310.820588) (xy 298.712581 -310.850809) (xy 298.748937 -310.887165) (xy 298.779158 -310.928761)
			(xy 298.802501 -310.974573) (xy 298.818389 -311.023472) (xy 298.826432 -311.074254) (xy 298.826936 -311.099962)
			(xy 299.14394 -311.099962) (xy 299.1479 -311.050908) (xy 299.159677 -311.003124) (xy 299.178968 -310.957848)
			(xy 299.205271 -310.916252) (xy 299.237906 -310.879415) (xy 299.276027 -310.84829) (xy 299.318648 -310.823683)
			(xy 299.364664 -310.806231) (xy 299.412883 -310.796387) (xy 299.462058 -310.794406) (xy 299.510913 -310.800338)
			(xy 299.558184 -310.81403) (xy 299.602646 -310.835128) (xy 299.643149 -310.863084) (xy 299.678642 -310.897176)
			(xy 299.708207 -310.93652) (xy 299.731078 -310.980097) (xy 299.746662 -311.026778) (xy 299.754557 -311.075355)
			(xy 299.755052 -311.099962) (xy 299.754557 -311.124569) (xy 299.754378 -311.12567) (xy 300.073056 -311.12567)
			(xy 300.073056 -311.074254) (xy 300.081099 -311.023472) (xy 300.096987 -310.974573) (xy 300.12033 -310.928761)
			(xy 300.150551 -310.887165) (xy 300.186907 -310.850809) (xy 300.228503 -310.820588) (xy 300.274315 -310.797245)
			(xy 300.323214 -310.781357) (xy 300.373996 -310.773314) (xy 300.425412 -310.773314) (xy 300.476194 -310.781357)
			(xy 300.525093 -310.797245) (xy 300.570905 -310.820588) (xy 300.612501 -310.850809) (xy 300.648857 -310.887165)
			(xy 300.679078 -310.928761) (xy 300.702421 -310.974573) (xy 300.718309 -311.023472) (xy 300.726352 -311.074254)
			(xy 300.726856 -311.099962) (xy 301.044114 -311.099962) (xy 301.048074 -311.050908) (xy 301.059851 -311.003124)
			(xy 301.079142 -310.957848) (xy 301.105445 -310.916252) (xy 301.13808 -310.879415) (xy 301.176201 -310.84829)
			(xy 301.218822 -310.823683) (xy 301.264838 -310.806231) (xy 301.313057 -310.796387) (xy 301.362232 -310.794406)
			(xy 301.411087 -310.800338) (xy 301.458358 -310.81403) (xy 301.50282 -310.835128) (xy 301.543323 -310.863084)
			(xy 301.578816 -310.897176) (xy 301.608381 -310.93652) (xy 301.631252 -310.980097) (xy 301.646836 -311.026778)
			(xy 301.654731 -311.075355) (xy 301.655226 -311.099962) (xy 301.654731 -311.124569) (xy 301.654552 -311.12567)
			(xy 301.97323 -311.12567) (xy 301.97323 -311.074254) (xy 301.981273 -311.023472) (xy 301.997161 -310.974573)
			(xy 302.020504 -310.928761) (xy 302.050725 -310.887165) (xy 302.087081 -310.850809) (xy 302.128677 -310.820588)
			(xy 302.174489 -310.797245) (xy 302.223388 -310.781357) (xy 302.27417 -310.773314) (xy 302.325586 -310.773314)
			(xy 302.376368 -310.781357) (xy 302.425267 -310.797245) (xy 302.471079 -310.820588) (xy 302.512675 -310.850809)
			(xy 302.549031 -310.887165) (xy 302.579252 -310.928761) (xy 302.602595 -310.974573) (xy 302.618483 -311.023472)
			(xy 302.626526 -311.074254) (xy 302.62703 -311.099962) (xy 302.944034 -311.099962) (xy 302.947994 -311.050908)
			(xy 302.959771 -311.003124) (xy 302.979062 -310.957848) (xy 303.005365 -310.916252) (xy 303.038 -310.879415)
			(xy 303.076121 -310.84829) (xy 303.118742 -310.823683) (xy 303.164758 -310.806231) (xy 303.212977 -310.796387)
			(xy 303.262152 -310.794406) (xy 303.311007 -310.800338) (xy 303.358278 -310.81403) (xy 303.40274 -310.835128)
			(xy 303.443243 -310.863084) (xy 303.478736 -310.897176) (xy 303.508301 -310.93652) (xy 303.531172 -310.980097)
			(xy 303.546756 -311.026778) (xy 303.554651 -311.075355) (xy 303.555146 -311.099962) (xy 303.554651 -311.124569)
			(xy 303.546756 -311.173146) (xy 303.531172 -311.219827) (xy 303.508301 -311.263404) (xy 303.478736 -311.302748)
			(xy 303.443243 -311.33684) (xy 303.40274 -311.364796) (xy 303.358278 -311.385894) (xy 303.311007 -311.399586)
			(xy 303.262152 -311.405518) (xy 303.212977 -311.403537) (xy 303.164758 -311.393693) (xy 303.118742 -311.376241)
			(xy 303.076121 -311.351634) (xy 303.038 -311.320509) (xy 303.005365 -311.283672) (xy 302.979062 -311.242076)
			(xy 302.959771 -311.1968) (xy 302.947994 -311.149016) (xy 302.944034 -311.099962) (xy 302.62703 -311.099962)
			(xy 302.626526 -311.12567) (xy 302.618483 -311.176452) (xy 302.602595 -311.225351) (xy 302.579252 -311.271163)
			(xy 302.549031 -311.312759) (xy 302.512675 -311.349115) (xy 302.471079 -311.379336) (xy 302.425267 -311.402679)
			(xy 302.376368 -311.418567) (xy 302.325586 -311.42661) (xy 302.27417 -311.42661) (xy 302.223388 -311.418567)
			(xy 302.174489 -311.402679) (xy 302.128677 -311.379336) (xy 302.087081 -311.349115) (xy 302.050725 -311.312759)
			(xy 302.020504 -311.271163) (xy 301.997161 -311.225351) (xy 301.981273 -311.176452) (xy 301.97323 -311.12567)
			(xy 301.654552 -311.12567) (xy 301.646836 -311.173146) (xy 301.631252 -311.219827) (xy 301.608381 -311.263404)
			(xy 301.578816 -311.302748) (xy 301.543323 -311.33684) (xy 301.50282 -311.364796) (xy 301.458358 -311.385894)
			(xy 301.411087 -311.399586) (xy 301.362232 -311.405518) (xy 301.313057 -311.403537) (xy 301.264838 -311.393693)
			(xy 301.218822 -311.376241) (xy 301.176201 -311.351634) (xy 301.13808 -311.320509) (xy 301.105445 -311.283672)
			(xy 301.079142 -311.242076) (xy 301.059851 -311.1968) (xy 301.048074 -311.149016) (xy 301.044114 -311.099962)
			(xy 300.726856 -311.099962) (xy 300.726352 -311.12567) (xy 300.718309 -311.176452) (xy 300.702421 -311.225351)
			(xy 300.679078 -311.271163) (xy 300.648857 -311.312759) (xy 300.612501 -311.349115) (xy 300.570905 -311.379336)
			(xy 300.525093 -311.402679) (xy 300.476194 -311.418567) (xy 300.425412 -311.42661) (xy 300.373996 -311.42661)
			(xy 300.323214 -311.418567) (xy 300.274315 -311.402679) (xy 300.228503 -311.379336) (xy 300.186907 -311.349115)
			(xy 300.150551 -311.312759) (xy 300.12033 -311.271163) (xy 300.096987 -311.225351) (xy 300.081099 -311.176452)
			(xy 300.073056 -311.12567) (xy 299.754378 -311.12567) (xy 299.746662 -311.173146) (xy 299.731078 -311.219827)
			(xy 299.708207 -311.263404) (xy 299.678642 -311.302748) (xy 299.643149 -311.33684) (xy 299.602646 -311.364796)
			(xy 299.558184 -311.385894) (xy 299.510913 -311.399586) (xy 299.462058 -311.405518) (xy 299.412883 -311.403537)
			(xy 299.364664 -311.393693) (xy 299.318648 -311.376241) (xy 299.276027 -311.351634) (xy 299.237906 -311.320509)
			(xy 299.205271 -311.283672) (xy 299.178968 -311.242076) (xy 299.159677 -311.1968) (xy 299.1479 -311.149016)
			(xy 299.14394 -311.099962) (xy 298.826936 -311.099962) (xy 298.826432 -311.12567) (xy 298.818389 -311.176452)
			(xy 298.802501 -311.225351) (xy 298.779158 -311.271163) (xy 298.748937 -311.312759) (xy 298.712581 -311.349115)
			(xy 298.670985 -311.379336) (xy 298.625173 -311.402679) (xy 298.576274 -311.418567) (xy 298.525492 -311.42661)
			(xy 298.474076 -311.42661) (xy 298.423294 -311.418567) (xy 298.374395 -311.402679) (xy 298.328583 -311.379336)
			(xy 298.286987 -311.349115) (xy 298.250631 -311.312759) (xy 298.22041 -311.271163) (xy 298.197067 -311.225351)
			(xy 298.181179 -311.176452) (xy 298.173136 -311.12567) (xy 297.854458 -311.12567) (xy 297.846742 -311.173146)
			(xy 297.831158 -311.219827) (xy 297.808287 -311.263404) (xy 297.778722 -311.302748) (xy 297.743229 -311.33684)
			(xy 297.702726 -311.364796) (xy 297.658264 -311.385894) (xy 297.610993 -311.399586) (xy 297.562138 -311.405518)
			(xy 297.512963 -311.403537) (xy 297.464744 -311.393693) (xy 297.418728 -311.376241) (xy 297.376107 -311.351634)
			(xy 297.337986 -311.320509) (xy 297.305351 -311.283672) (xy 297.279048 -311.242076) (xy 297.259757 -311.1968)
			(xy 297.24798 -311.149016) (xy 297.24402 -311.099962) (xy 296.927016 -311.099962) (xy 296.926512 -311.12567)
			(xy 296.918469 -311.176452) (xy 296.902581 -311.225351) (xy 296.879238 -311.271163) (xy 296.849017 -311.312759)
			(xy 296.812661 -311.349115) (xy 296.771065 -311.379336) (xy 296.725253 -311.402679) (xy 296.676354 -311.418567)
			(xy 296.625572 -311.42661) (xy 296.574156 -311.42661) (xy 296.523374 -311.418567) (xy 296.474475 -311.402679)
			(xy 296.428663 -311.379336) (xy 296.387067 -311.349115) (xy 296.350711 -311.312759) (xy 296.32049 -311.271163)
			(xy 296.297147 -311.225351) (xy 296.281259 -311.176452) (xy 296.273216 -311.12567) (xy 295.954538 -311.12567)
			(xy 295.946822 -311.173146) (xy 295.931238 -311.219827) (xy 295.908367 -311.263404) (xy 295.878802 -311.302748)
			(xy 295.843309 -311.33684) (xy 295.802806 -311.364796) (xy 295.758344 -311.385894) (xy 295.711073 -311.399586)
			(xy 295.662218 -311.405518) (xy 295.613043 -311.403537) (xy 295.564824 -311.393693) (xy 295.518808 -311.376241)
			(xy 295.476187 -311.351634) (xy 295.438066 -311.320509) (xy 295.405431 -311.283672) (xy 295.379128 -311.242076)
			(xy 295.359837 -311.1968) (xy 295.34806 -311.149016) (xy 295.3441 -311.099962) (xy 295.026842 -311.099962)
			(xy 295.026338 -311.12567) (xy 295.018295 -311.176452) (xy 295.002407 -311.225351) (xy 294.979064 -311.271163)
			(xy 294.948843 -311.312759) (xy 294.912487 -311.349115) (xy 294.870891 -311.379336) (xy 294.825079 -311.402679)
			(xy 294.77618 -311.418567) (xy 294.725398 -311.42661) (xy 294.673982 -311.42661) (xy 294.6232 -311.418567)
			(xy 294.574301 -311.402679) (xy 294.528489 -311.379336) (xy 294.486893 -311.349115) (xy 294.450537 -311.312759)
			(xy 294.420316 -311.271163) (xy 294.396973 -311.225351) (xy 294.381085 -311.176452) (xy 294.373042 -311.12567)
			(xy 294.054364 -311.12567) (xy 294.046648 -311.173146) (xy 294.031064 -311.219827) (xy 294.008193 -311.263404)
			(xy 293.978628 -311.302748) (xy 293.943135 -311.33684) (xy 293.902632 -311.364796) (xy 293.85817 -311.385894)
			(xy 293.810899 -311.399586) (xy 293.762044 -311.405518) (xy 293.712869 -311.403537) (xy 293.66465 -311.393693)
			(xy 293.618634 -311.376241) (xy 293.576013 -311.351634) (xy 293.537892 -311.320509) (xy 293.505257 -311.283672)
			(xy 293.478954 -311.242076) (xy 293.459663 -311.1968) (xy 293.447886 -311.149016) (xy 293.443926 -311.099962)
			(xy 293.126922 -311.099962) (xy 293.126418 -311.12567) (xy 293.118375 -311.176452) (xy 293.102487 -311.225351)
			(xy 293.079144 -311.271163) (xy 293.048923 -311.312759) (xy 293.012567 -311.349115) (xy 292.970971 -311.379336)
			(xy 292.925159 -311.402679) (xy 292.87626 -311.418567) (xy 292.825478 -311.42661) (xy 292.774062 -311.42661)
			(xy 292.72328 -311.418567) (xy 292.674381 -311.402679) (xy 292.628569 -311.379336) (xy 292.586973 -311.349115)
			(xy 292.550617 -311.312759) (xy 292.520396 -311.271163) (xy 292.497053 -311.225351) (xy 292.481165 -311.176452)
			(xy 292.473122 -311.12567) (xy 292.154444 -311.12567) (xy 292.146728 -311.173146) (xy 292.131144 -311.219827)
			(xy 292.108273 -311.263404) (xy 292.078708 -311.302748) (xy 292.043215 -311.33684) (xy 292.002712 -311.364796)
			(xy 291.95825 -311.385894) (xy 291.910979 -311.399586) (xy 291.862124 -311.405518) (xy 291.812949 -311.403537)
			(xy 291.76473 -311.393693) (xy 291.718714 -311.376241) (xy 291.676093 -311.351634) (xy 291.637972 -311.320509)
			(xy 291.605337 -311.283672) (xy 291.579034 -311.242076) (xy 291.559743 -311.1968) (xy 291.547966 -311.149016)
			(xy 291.544006 -311.099962) (xy 291.227002 -311.099962) (xy 291.226498 -311.12567) (xy 291.218455 -311.176452)
			(xy 291.202567 -311.225351) (xy 291.179224 -311.271163) (xy 291.149003 -311.312759) (xy 291.112647 -311.349115)
			(xy 291.071051 -311.379336) (xy 291.025239 -311.402679) (xy 290.97634 -311.418567) (xy 290.925558 -311.42661)
			(xy 290.874142 -311.42661) (xy 290.82336 -311.418567) (xy 290.774461 -311.402679) (xy 290.728649 -311.379336)
			(xy 290.687053 -311.349115) (xy 290.650697 -311.312759) (xy 290.620476 -311.271163) (xy 290.597133 -311.225351)
			(xy 290.581245 -311.176452) (xy 290.573202 -311.12567) (xy 290.254524 -311.12567) (xy 290.246808 -311.173146)
			(xy 290.231224 -311.219827) (xy 290.208353 -311.263404) (xy 290.178788 -311.302748) (xy 290.143295 -311.33684)
			(xy 290.102792 -311.364796) (xy 290.05833 -311.385894) (xy 290.011059 -311.399586) (xy 289.962204 -311.405518)
			(xy 289.913029 -311.403537) (xy 289.86481 -311.393693) (xy 289.818794 -311.376241) (xy 289.776173 -311.351634)
			(xy 289.738052 -311.320509) (xy 289.705417 -311.283672) (xy 289.679114 -311.242076) (xy 289.659823 -311.1968)
			(xy 289.648046 -311.149016) (xy 289.644086 -311.099962) (xy 289.305238 -311.099962) (xy 289.304743 -311.124569)
			(xy 289.296848 -311.173146) (xy 289.281264 -311.219827) (xy 289.258393 -311.263404) (xy 289.228828 -311.302748)
			(xy 289.193335 -311.33684) (xy 289.152832 -311.364796) (xy 289.10837 -311.385894) (xy 289.061099 -311.399586)
			(xy 289.012244 -311.405518) (xy 288.963069 -311.403537) (xy 288.91485 -311.393693) (xy 288.868834 -311.376241)
			(xy 288.826213 -311.351634) (xy 288.788092 -311.320509) (xy 288.755457 -311.283672) (xy 288.729154 -311.242076)
			(xy 288.709863 -311.1968) (xy 288.698086 -311.149016) (xy 288.694126 -311.099962) (xy 288.355024 -311.099962)
			(xy 288.354529 -311.124569) (xy 288.346634 -311.173146) (xy 288.33105 -311.219827) (xy 288.308179 -311.263404)
			(xy 288.278614 -311.302748) (xy 288.243121 -311.33684) (xy 288.202618 -311.364796) (xy 288.158156 -311.385894)
			(xy 288.110885 -311.399586) (xy 288.06203 -311.405518) (xy 288.012855 -311.403537) (xy 287.964636 -311.393693)
			(xy 287.91862 -311.376241) (xy 287.875999 -311.351634) (xy 287.837878 -311.320509) (xy 287.805243 -311.283672)
			(xy 287.77894 -311.242076) (xy 287.759649 -311.1968) (xy 287.747872 -311.149016) (xy 287.743912 -311.099962)
			(xy 287.405064 -311.099962) (xy 287.404569 -311.124569) (xy 287.396674 -311.173146) (xy 287.38109 -311.219827)
			(xy 287.358219 -311.263404) (xy 287.328654 -311.302748) (xy 287.293161 -311.33684) (xy 287.252658 -311.364796)
			(xy 287.208196 -311.385894) (xy 287.160925 -311.399586) (xy 287.11207 -311.405518) (xy 287.062895 -311.403537)
			(xy 287.014676 -311.393693) (xy 286.96866 -311.376241) (xy 286.926039 -311.351634) (xy 286.887918 -311.320509)
			(xy 286.855283 -311.283672) (xy 286.82898 -311.242076) (xy 286.809689 -311.1968) (xy 286.797912 -311.149016)
			(xy 286.793952 -311.099962) (xy 286.455104 -311.099962) (xy 286.454609 -311.124569) (xy 286.446714 -311.173146)
			(xy 286.43113 -311.219827) (xy 286.408259 -311.263404) (xy 286.378694 -311.302748) (xy 286.343201 -311.33684)
			(xy 286.302698 -311.364796) (xy 286.258236 -311.385894) (xy 286.210965 -311.399586) (xy 286.16211 -311.405518)
			(xy 286.112935 -311.403537) (xy 286.064716 -311.393693) (xy 286.0187 -311.376241) (xy 285.976079 -311.351634)
			(xy 285.937958 -311.320509) (xy 285.905323 -311.283672) (xy 285.87902 -311.242076) (xy 285.859729 -311.1968)
			(xy 285.847952 -311.149016) (xy 285.843992 -311.099962) (xy 285.505144 -311.099962) (xy 285.504649 -311.124569)
			(xy 285.496754 -311.173146) (xy 285.48117 -311.219827) (xy 285.458299 -311.263404) (xy 285.428734 -311.302748)
			(xy 285.393241 -311.33684) (xy 285.352738 -311.364796) (xy 285.308276 -311.385894) (xy 285.261005 -311.399586)
			(xy 285.21215 -311.405518) (xy 285.162975 -311.403537) (xy 285.114756 -311.393693) (xy 285.06874 -311.376241)
			(xy 285.026119 -311.351634) (xy 284.987998 -311.320509) (xy 284.955363 -311.283672) (xy 284.92906 -311.242076)
			(xy 284.909769 -311.1968) (xy 284.897992 -311.149016) (xy 284.894032 -311.099962) (xy 284.555184 -311.099962)
			(xy 284.554689 -311.124569) (xy 284.546794 -311.173146) (xy 284.53121 -311.219827) (xy 284.508339 -311.263404)
			(xy 284.478774 -311.302748) (xy 284.443281 -311.33684) (xy 284.402778 -311.364796) (xy 284.358316 -311.385894)
			(xy 284.311045 -311.399586) (xy 284.26219 -311.405518) (xy 284.213015 -311.403537) (xy 284.164796 -311.393693)
			(xy 284.11878 -311.376241) (xy 284.076159 -311.351634) (xy 284.038038 -311.320509) (xy 284.005403 -311.283672)
			(xy 283.9791 -311.242076) (xy 283.959809 -311.1968) (xy 283.948032 -311.149016) (xy 283.944072 -311.099962)
			(xy 283.605224 -311.099962) (xy 283.604729 -311.124569) (xy 283.596834 -311.173146) (xy 283.58125 -311.219827)
			(xy 283.558379 -311.263404) (xy 283.528814 -311.302748) (xy 283.493321 -311.33684) (xy 283.452818 -311.364796)
			(xy 283.408356 -311.385894) (xy 283.361085 -311.399586) (xy 283.31223 -311.405518) (xy 283.263055 -311.403537)
			(xy 283.214836 -311.393693) (xy 283.16882 -311.376241) (xy 283.126199 -311.351634) (xy 283.088078 -311.320509)
			(xy 283.055443 -311.283672) (xy 283.02914 -311.242076) (xy 283.009849 -311.1968) (xy 282.998072 -311.149016)
			(xy 282.994112 -311.099962) (xy 282.65501 -311.099962) (xy 282.654515 -311.124569) (xy 282.64662 -311.173146)
			(xy 282.631036 -311.219827) (xy 282.608165 -311.263404) (xy 282.5786 -311.302748) (xy 282.543107 -311.33684)
			(xy 282.502604 -311.364796) (xy 282.458142 -311.385894) (xy 282.410871 -311.399586) (xy 282.362016 -311.405518)
			(xy 282.312841 -311.403537) (xy 282.264622 -311.393693) (xy 282.218606 -311.376241) (xy 282.175985 -311.351634)
			(xy 282.137864 -311.320509) (xy 282.105229 -311.283672) (xy 282.078926 -311.242076) (xy 282.059635 -311.1968)
			(xy 282.047858 -311.149016) (xy 282.043898 -311.099962) (xy 281.70505 -311.099962) (xy 281.704555 -311.124569)
			(xy 281.69666 -311.173146) (xy 281.681076 -311.219827) (xy 281.658205 -311.263404) (xy 281.62864 -311.302748)
			(xy 281.593147 -311.33684) (xy 281.552644 -311.364796) (xy 281.508182 -311.385894) (xy 281.460911 -311.399586)
			(xy 281.412056 -311.405518) (xy 281.362881 -311.403537) (xy 281.314662 -311.393693) (xy 281.268646 -311.376241)
			(xy 281.226025 -311.351634) (xy 281.187904 -311.320509) (xy 281.155269 -311.283672) (xy 281.128966 -311.242076)
			(xy 281.109675 -311.1968) (xy 281.097898 -311.149016) (xy 281.093938 -311.099962) (xy 280.75509 -311.099962)
			(xy 280.754595 -311.124569) (xy 280.7467 -311.173146) (xy 280.731116 -311.219827) (xy 280.708245 -311.263404)
			(xy 280.67868 -311.302748) (xy 280.643187 -311.33684) (xy 280.602684 -311.364796) (xy 280.558222 -311.385894)
			(xy 280.510951 -311.399586) (xy 280.462096 -311.405518) (xy 280.412921 -311.403537) (xy 280.364702 -311.393693)
			(xy 280.318686 -311.376241) (xy 280.276065 -311.351634) (xy 280.237944 -311.320509) (xy 280.205309 -311.283672)
			(xy 280.179006 -311.242076) (xy 280.159715 -311.1968) (xy 280.147938 -311.149016) (xy 280.143978 -311.099962)
			(xy 279.80513 -311.099962) (xy 279.804635 -311.124569) (xy 279.79674 -311.173146) (xy 279.781156 -311.219827)
			(xy 279.758285 -311.263404) (xy 279.72872 -311.302748) (xy 279.693227 -311.33684) (xy 279.652724 -311.364796)
			(xy 279.608262 -311.385894) (xy 279.560991 -311.399586) (xy 279.512136 -311.405518) (xy 279.462961 -311.403537)
			(xy 279.414742 -311.393693) (xy 279.368726 -311.376241) (xy 279.326105 -311.351634) (xy 279.287984 -311.320509)
			(xy 279.255349 -311.283672) (xy 279.229046 -311.242076) (xy 279.209755 -311.1968) (xy 279.197978 -311.149016)
			(xy 279.194018 -311.099962) (xy 278.85517 -311.099962) (xy 278.854675 -311.124569) (xy 278.84678 -311.173146)
			(xy 278.831196 -311.219827) (xy 278.808325 -311.263404) (xy 278.77876 -311.302748) (xy 278.743267 -311.33684)
			(xy 278.702764 -311.364796) (xy 278.658302 -311.385894) (xy 278.611031 -311.399586) (xy 278.562176 -311.405518)
			(xy 278.513001 -311.403537) (xy 278.464782 -311.393693) (xy 278.418766 -311.376241) (xy 278.376145 -311.351634)
			(xy 278.338024 -311.320509) (xy 278.305389 -311.283672) (xy 278.279086 -311.242076) (xy 278.259795 -311.1968)
			(xy 278.248018 -311.149016) (xy 278.244058 -311.099962) (xy 277.90521 -311.099962) (xy 277.904715 -311.124569)
			(xy 277.89682 -311.173146) (xy 277.881236 -311.219827) (xy 277.858365 -311.263404) (xy 277.8288 -311.302748)
			(xy 277.793307 -311.33684) (xy 277.752804 -311.364796) (xy 277.708342 -311.385894) (xy 277.661071 -311.399586)
			(xy 277.612216 -311.405518) (xy 277.563041 -311.403537) (xy 277.514822 -311.393693) (xy 277.468806 -311.376241)
			(xy 277.426185 -311.351634) (xy 277.388064 -311.320509) (xy 277.355429 -311.283672) (xy 277.329126 -311.242076)
			(xy 277.309835 -311.1968) (xy 277.298058 -311.149016) (xy 277.294098 -311.099962) (xy 276.954996 -311.099962)
			(xy 276.954501 -311.124569) (xy 276.946606 -311.173146) (xy 276.931022 -311.219827) (xy 276.908151 -311.263404)
			(xy 276.878586 -311.302748) (xy 276.843093 -311.33684) (xy 276.80259 -311.364796) (xy 276.758128 -311.385894)
			(xy 276.710857 -311.399586) (xy 276.662002 -311.405518) (xy 276.612827 -311.403537) (xy 276.564608 -311.393693)
			(xy 276.518592 -311.376241) (xy 276.475971 -311.351634) (xy 276.43785 -311.320509) (xy 276.405215 -311.283672)
			(xy 276.378912 -311.242076) (xy 276.359621 -311.1968) (xy 276.347844 -311.149016) (xy 276.343884 -311.099962)
			(xy 276.005036 -311.099962) (xy 276.004541 -311.124569) (xy 275.996646 -311.173146) (xy 275.981062 -311.219827)
			(xy 275.958191 -311.263404) (xy 275.928626 -311.302748) (xy 275.893133 -311.33684) (xy 275.85263 -311.364796)
			(xy 275.808168 -311.385894) (xy 275.760897 -311.399586) (xy 275.712042 -311.405518) (xy 275.662867 -311.403537)
			(xy 275.614648 -311.393693) (xy 275.568632 -311.376241) (xy 275.526011 -311.351634) (xy 275.48789 -311.320509)
			(xy 275.455255 -311.283672) (xy 275.428952 -311.242076) (xy 275.409661 -311.1968) (xy 275.397884 -311.149016)
			(xy 275.393924 -311.099962) (xy 275.055076 -311.099962) (xy 275.054581 -311.124569) (xy 275.046686 -311.173146)
			(xy 275.031102 -311.219827) (xy 275.008231 -311.263404) (xy 274.978666 -311.302748) (xy 274.943173 -311.33684)
			(xy 274.90267 -311.364796) (xy 274.858208 -311.385894) (xy 274.810937 -311.399586) (xy 274.762082 -311.405518)
			(xy 274.712907 -311.403537) (xy 274.664688 -311.393693) (xy 274.618672 -311.376241) (xy 274.576051 -311.351634)
			(xy 274.53793 -311.320509) (xy 274.505295 -311.283672) (xy 274.478992 -311.242076) (xy 274.459701 -311.1968)
			(xy 274.447924 -311.149016) (xy 274.443964 -311.099962) (xy 274.12696 -311.099962) (xy 274.126456 -311.12567)
			(xy 274.118413 -311.176452) (xy 274.102525 -311.225351) (xy 274.079182 -311.271163) (xy 274.048961 -311.312759)
			(xy 274.012605 -311.349115) (xy 273.971009 -311.379336) (xy 273.925197 -311.402679) (xy 273.876298 -311.418567)
			(xy 273.825516 -311.42661) (xy 273.7741 -311.42661) (xy 273.723318 -311.418567) (xy 273.674419 -311.402679)
			(xy 273.628607 -311.379336) (xy 273.587011 -311.349115) (xy 273.550655 -311.312759) (xy 273.520434 -311.271163)
			(xy 273.497091 -311.225351) (xy 273.481203 -311.176452) (xy 273.47316 -311.12567) (xy 273.154482 -311.12567)
			(xy 273.146766 -311.173146) (xy 273.131182 -311.219827) (xy 273.108311 -311.263404) (xy 273.078746 -311.302748)
			(xy 273.043253 -311.33684) (xy 273.00275 -311.364796) (xy 272.958288 -311.385894) (xy 272.911017 -311.399586)
			(xy 272.862162 -311.405518) (xy 272.812987 -311.403537) (xy 272.764768 -311.393693) (xy 272.718752 -311.376241)
			(xy 272.676131 -311.351634) (xy 272.63801 -311.320509) (xy 272.605375 -311.283672) (xy 272.579072 -311.242076)
			(xy 272.559781 -311.1968) (xy 272.548004 -311.149016) (xy 272.544044 -311.099962) (xy 272.22704 -311.099962)
			(xy 272.226536 -311.12567) (xy 272.218493 -311.176452) (xy 272.202605 -311.225351) (xy 272.179262 -311.271163)
			(xy 272.149041 -311.312759) (xy 272.112685 -311.349115) (xy 272.071089 -311.379336) (xy 272.025277 -311.402679)
			(xy 271.976378 -311.418567) (xy 271.925596 -311.42661) (xy 271.87418 -311.42661) (xy 271.823398 -311.418567)
			(xy 271.774499 -311.402679) (xy 271.728687 -311.379336) (xy 271.687091 -311.349115) (xy 271.650735 -311.312759)
			(xy 271.620514 -311.271163) (xy 271.597171 -311.225351) (xy 271.581283 -311.176452) (xy 271.57324 -311.12567)
			(xy 271.254562 -311.12567) (xy 271.246846 -311.173146) (xy 271.231262 -311.219827) (xy 271.208391 -311.263404)
			(xy 271.178826 -311.302748) (xy 271.143333 -311.33684) (xy 271.10283 -311.364796) (xy 271.058368 -311.385894)
			(xy 271.011097 -311.399586) (xy 270.962242 -311.405518) (xy 270.913067 -311.403537) (xy 270.864848 -311.393693)
			(xy 270.818832 -311.376241) (xy 270.776211 -311.351634) (xy 270.73809 -311.320509) (xy 270.705455 -311.283672)
			(xy 270.679152 -311.242076) (xy 270.659861 -311.1968) (xy 270.648084 -311.149016) (xy 270.644124 -311.099962)
			(xy 270.305022 -311.099962) (xy 270.304527 -311.124569) (xy 270.296632 -311.173146) (xy 270.281048 -311.219827)
			(xy 270.258177 -311.263404) (xy 270.228612 -311.302748) (xy 270.193119 -311.33684) (xy 270.152616 -311.364796)
			(xy 270.108154 -311.385894) (xy 270.060883 -311.399586) (xy 270.012028 -311.405518) (xy 269.962853 -311.403537)
			(xy 269.914634 -311.393693) (xy 269.868618 -311.376241) (xy 269.825997 -311.351634) (xy 269.787876 -311.320509)
			(xy 269.755241 -311.283672) (xy 269.728938 -311.242076) (xy 269.709647 -311.1968) (xy 269.69787 -311.149016)
			(xy 269.69391 -311.099962) (xy 269.355062 -311.099962) (xy 269.354567 -311.124569) (xy 269.346672 -311.173146)
			(xy 269.331088 -311.219827) (xy 269.308217 -311.263404) (xy 269.278652 -311.302748) (xy 269.243159 -311.33684)
			(xy 269.202656 -311.364796) (xy 269.158194 -311.385894) (xy 269.110923 -311.399586) (xy 269.062068 -311.405518)
			(xy 269.012893 -311.403537) (xy 268.964674 -311.393693) (xy 268.918658 -311.376241) (xy 268.876037 -311.351634)
			(xy 268.837916 -311.320509) (xy 268.805281 -311.283672) (xy 268.778978 -311.242076) (xy 268.759687 -311.1968)
			(xy 268.74791 -311.149016) (xy 268.74395 -311.099962) (xy 267.226092 -311.099962) (xy 267.211581 -311.149382)
			(xy 267.188939 -311.198959) (xy 267.159473 -311.244809) (xy 267.123782 -311.286) (xy 267.082591 -311.321691)
			(xy 267.036741 -311.351157) (xy 266.987164 -311.373799) (xy 266.934869 -311.389154) (xy 266.880921 -311.39691)
			(xy 266.826419 -311.39691) (xy 266.772471 -311.389154) (xy 266.720176 -311.373799) (xy 266.670599 -311.351157)
			(xy 266.624749 -311.321691) (xy 266.583558 -311.286) (xy 266.547867 -311.244809) (xy 266.518401 -311.198959)
			(xy 266.495759 -311.149382) (xy 266.480404 -311.097087) (xy 266.472648 -311.043139) (xy 266.472162 -311.015888)
			(xy 266.472669 -310.987113) (xy 266.481326 -310.930219) (xy 266.498427 -310.875269) (xy 266.523584 -310.823509)
			(xy 266.556227 -310.776113) (xy 266.57554 -310.754776) (xy 266.584808 -310.744144) (xy 266.597733 -310.719093)
			(xy 266.603308 -310.691461) (xy 266.601106 -310.663358) (xy 266.591296 -310.636931) (xy 266.574626 -310.614199)
			(xy 266.552371 -310.596898) (xy 266.539472 -310.5912) (xy 266.513381 -310.58016) (xy 266.46456 -310.551418)
			(xy 266.420525 -310.515774) (xy 266.382244 -310.47401) (xy 266.350559 -310.427046) (xy 266.326165 -310.375913)
			(xy 266.3096 -310.321736) (xy 266.301227 -310.265705) (xy 266.300712 -310.237378) (xy 261.929168 -310.237378)
			(xy 261.925249 -310.250403) (xy 261.901577 -310.3009) (xy 261.870804 -310.347413) (xy 261.833587 -310.38895)
			(xy 261.790719 -310.424625) (xy 261.743113 -310.453679) (xy 261.691784 -310.475491) (xy 261.637827 -310.489597)
			(xy 261.58239 -310.495697) (xy 261.526656 -310.49366) (xy 261.471813 -310.48353) (xy 261.419029 -310.465523)
			(xy 261.369429 -310.440022) (xy 261.324071 -310.407571) (xy 261.283922 -310.368862) (xy 261.249836 -310.324719)
			(xy 261.22254 -310.276084) (xy 261.202617 -310.223993) (xy 261.190491 -310.169556) (xy 261.18642 -310.113934)
			(xy 248.826521 -310.113934) (xy 248.835603 -310.168917) (xy 248.836434 -310.198262) (xy 248.836434 -310.20131)
			(xy 248.835895 -310.231805) (xy 248.826325 -310.292038) (xy 248.817384 -310.321198) (xy 248.814844 -310.328818)
			(xy 248.814844 -310.832246) (xy 260.467854 -310.832246) (xy 260.471925 -310.776624) (xy 260.484051 -310.722187)
			(xy 260.503974 -310.670096) (xy 260.53127 -310.621461) (xy 260.565356 -310.577318) (xy 260.605505 -310.538609)
			(xy 260.650863 -310.506158) (xy 260.700463 -310.480657) (xy 260.753247 -310.46265) (xy 260.80809 -310.45252)
			(xy 260.863824 -310.450483) (xy 260.919261 -310.456583) (xy 260.973218 -310.470689) (xy 261.024547 -310.492501)
			(xy 261.072153 -310.521555) (xy 261.115021 -310.55723) (xy 261.152238 -310.598767) (xy 261.183011 -310.64528)
			(xy 261.206683 -310.695777) (xy 261.222751 -310.749184) (xy 261.230871 -310.80436) (xy 261.23138 -310.832246)
			(xy 261.230871 -310.860132) (xy 261.222751 -310.915308) (xy 261.206683 -310.968715) (xy 261.183011 -311.019212)
			(xy 261.152238 -311.065725) (xy 261.115021 -311.107262) (xy 261.072153 -311.142937) (xy 261.024547 -311.171991)
			(xy 260.973218 -311.193803) (xy 260.919261 -311.207909) (xy 260.863824 -311.214009) (xy 260.80809 -311.211972)
			(xy 260.753247 -311.201842) (xy 260.700463 -311.183835) (xy 260.650863 -311.158334) (xy 260.605505 -311.125883)
			(xy 260.565356 -311.087174) (xy 260.53127 -311.043031) (xy 260.503974 -310.994396) (xy 260.484051 -310.942305)
			(xy 260.471925 -310.887868) (xy 260.467854 -310.832246) (xy 248.814844 -310.832246) (xy 248.814844 -311.7342)
			(xy 264.689334 -311.7342) (xy 264.693405 -311.678578) (xy 264.705531 -311.624141) (xy 264.725454 -311.57205)
			(xy 264.75275 -311.523415) (xy 264.786836 -311.479272) (xy 264.826985 -311.440563) (xy 264.872343 -311.408112)
			(xy 264.921943 -311.382611) (xy 264.974727 -311.364604) (xy 265.02957 -311.354474) (xy 265.085304 -311.352437)
			(xy 265.140741 -311.358537) (xy 265.194698 -311.372643) (xy 265.246027 -311.394455) (xy 265.293633 -311.423509)
			(xy 265.336501 -311.459184) (xy 265.373718 -311.500721) (xy 265.404491 -311.547234) (xy 265.428163 -311.597731)
			(xy 265.444231 -311.651138) (xy 265.452351 -311.706314) (xy 265.45286 -311.7342) (xy 265.452351 -311.762086)
			(xy 265.444231 -311.817262) (xy 265.428163 -311.870669) (xy 265.404491 -311.921166) (xy 265.373718 -311.967679)
			(xy 265.336501 -312.009216) (xy 265.293633 -312.044891) (xy 265.246027 -312.073945) (xy 265.194698 -312.095757)
			(xy 265.140741 -312.109863) (xy 265.085304 -312.115963) (xy 265.02957 -312.113926) (xy 264.974727 -312.103796)
			(xy 264.921943 -312.085789) (xy 264.872343 -312.060288) (xy 264.826985 -312.027837) (xy 264.786836 -311.989128)
			(xy 264.75275 -311.944985) (xy 264.725454 -311.89635) (xy 264.705531 -311.844259) (xy 264.693405 -311.789822)
			(xy 264.689334 -311.7342) (xy 248.814844 -311.7342) (xy 248.814844 -312.523378) (xy 263.931906 -312.523378)
			(xy 263.935977 -312.467756) (xy 263.948103 -312.413319) (xy 263.968026 -312.361228) (xy 263.995322 -312.312593)
			(xy 264.029408 -312.26845) (xy 264.069557 -312.229741) (xy 264.114915 -312.19729) (xy 264.164515 -312.171789)
			(xy 264.217299 -312.153782) (xy 264.272142 -312.143652) (xy 264.327876 -312.141615) (xy 264.383313 -312.147715)
			(xy 264.43727 -312.161821) (xy 264.488599 -312.183633) (xy 264.536205 -312.212687) (xy 264.579073 -312.248362)
			(xy 264.596765 -312.268108) (xy 266.259562 -312.268108) (xy 266.263633 -312.212486) (xy 266.275759 -312.158049)
			(xy 266.295682 -312.105958) (xy 266.322978 -312.057323) (xy 266.357064 -312.01318) (xy 266.397213 -311.974471)
			(xy 266.442571 -311.94202) (xy 266.492171 -311.916519) (xy 266.544955 -311.898512) (xy 266.599798 -311.888382)
			(xy 266.655532 -311.886345) (xy 266.710969 -311.892445) (xy 266.764926 -311.906551) (xy 266.816255 -311.928363)
			(xy 266.863861 -311.957417) (xy 266.906729 -311.993092) (xy 266.943946 -312.034629) (xy 266.953896 -312.049668)
			(xy 267.793736 -312.049668) (xy 267.797696 -312.000614) (xy 267.809473 -311.95283) (xy 267.828764 -311.907554)
			(xy 267.855067 -311.865958) (xy 267.887702 -311.829121) (xy 267.925823 -311.797996) (xy 267.968444 -311.773389)
			(xy 268.01446 -311.755937) (xy 268.062679 -311.746093) (xy 268.111854 -311.744112) (xy 268.160709 -311.750044)
			(xy 268.20798 -311.763736) (xy 268.252442 -311.784834) (xy 268.292945 -311.81279) (xy 268.328438 -311.846882)
			(xy 268.358003 -311.886226) (xy 268.380874 -311.929803) (xy 268.396458 -311.976484) (xy 268.404353 -312.025061)
			(xy 268.404848 -312.049668) (xy 268.404353 -312.074275) (xy 268.404133 -312.07563) (xy 268.723106 -312.07563)
			(xy 268.723106 -312.024214) (xy 268.731149 -311.973432) (xy 268.747037 -311.924533) (xy 268.77038 -311.878721)
			(xy 268.800601 -311.837125) (xy 268.836957 -311.800769) (xy 268.878553 -311.770548) (xy 268.924365 -311.747205)
			(xy 268.973264 -311.731317) (xy 269.024046 -311.723274) (xy 269.075462 -311.723274) (xy 269.126244 -311.731317)
			(xy 269.175143 -311.747205) (xy 269.220955 -311.770548) (xy 269.262551 -311.800769) (xy 269.298907 -311.837125)
			(xy 269.329128 -311.878721) (xy 269.352471 -311.924533) (xy 269.368359 -311.973432) (xy 269.376402 -312.024214)
			(xy 269.376906 -312.049922) (xy 269.376402 -312.07563) (xy 269.673066 -312.07563) (xy 269.673066 -312.024214)
			(xy 269.681109 -311.973432) (xy 269.696997 -311.924533) (xy 269.72034 -311.878721) (xy 269.750561 -311.837125)
			(xy 269.786917 -311.800769) (xy 269.828513 -311.770548) (xy 269.874325 -311.747205) (xy 269.923224 -311.731317)
			(xy 269.974006 -311.723274) (xy 270.025422 -311.723274) (xy 270.076204 -311.731317) (xy 270.125103 -311.747205)
			(xy 270.170915 -311.770548) (xy 270.212511 -311.800769) (xy 270.248867 -311.837125) (xy 270.279088 -311.878721)
			(xy 270.302431 -311.924533) (xy 270.318319 -311.973432) (xy 270.326362 -312.024214) (xy 270.326866 -312.049922)
			(xy 270.644124 -312.049922) (xy 270.648084 -312.000868) (xy 270.659861 -311.953084) (xy 270.679152 -311.907808)
			(xy 270.705455 -311.866212) (xy 270.73809 -311.829375) (xy 270.776211 -311.79825) (xy 270.818832 -311.773643)
			(xy 270.864848 -311.756191) (xy 270.913067 -311.746347) (xy 270.962242 -311.744366) (xy 271.011097 -311.750298)
			(xy 271.058368 -311.76399) (xy 271.10283 -311.785088) (xy 271.143333 -311.813044) (xy 271.178826 -311.847136)
			(xy 271.208391 -311.88648) (xy 271.231262 -311.930057) (xy 271.246846 -311.976738) (xy 271.254741 -312.025315)
			(xy 271.255236 -312.049922) (xy 271.254741 -312.074529) (xy 271.254562 -312.07563) (xy 271.57324 -312.07563)
			(xy 271.57324 -312.024214) (xy 271.581283 -311.973432) (xy 271.597171 -311.924533) (xy 271.620514 -311.878721)
			(xy 271.650735 -311.837125) (xy 271.687091 -311.800769) (xy 271.728687 -311.770548) (xy 271.774499 -311.747205)
			(xy 271.823398 -311.731317) (xy 271.87418 -311.723274) (xy 271.925596 -311.723274) (xy 271.976378 -311.731317)
			(xy 272.025277 -311.747205) (xy 272.071089 -311.770548) (xy 272.112685 -311.800769) (xy 272.149041 -311.837125)
			(xy 272.179262 -311.878721) (xy 272.202605 -311.924533) (xy 272.218493 -311.973432) (xy 272.226536 -312.024214)
			(xy 272.22704 -312.049922) (xy 272.544044 -312.049922) (xy 272.548004 -312.000868) (xy 272.559781 -311.953084)
			(xy 272.579072 -311.907808) (xy 272.605375 -311.866212) (xy 272.63801 -311.829375) (xy 272.676131 -311.79825)
			(xy 272.718752 -311.773643) (xy 272.764768 -311.756191) (xy 272.812987 -311.746347) (xy 272.862162 -311.744366)
			(xy 272.911017 -311.750298) (xy 272.958288 -311.76399) (xy 273.00275 -311.785088) (xy 273.043253 -311.813044)
			(xy 273.078746 -311.847136) (xy 273.108311 -311.88648) (xy 273.131182 -311.930057) (xy 273.146766 -311.976738)
			(xy 273.154661 -312.025315) (xy 273.155156 -312.049922) (xy 273.154661 -312.074529) (xy 273.154482 -312.07563)
			(xy 273.47316 -312.07563) (xy 273.47316 -312.024214) (xy 273.481203 -311.973432) (xy 273.497091 -311.924533)
			(xy 273.520434 -311.878721) (xy 273.550655 -311.837125) (xy 273.587011 -311.800769) (xy 273.628607 -311.770548)
			(xy 273.674419 -311.747205) (xy 273.723318 -311.731317) (xy 273.7741 -311.723274) (xy 273.825516 -311.723274)
			(xy 273.876298 -311.731317) (xy 273.925197 -311.747205) (xy 273.971009 -311.770548) (xy 274.012605 -311.800769)
			(xy 274.048961 -311.837125) (xy 274.079182 -311.878721) (xy 274.102525 -311.924533) (xy 274.118413 -311.973432)
			(xy 274.126456 -312.024214) (xy 274.12696 -312.049922) (xy 274.443964 -312.049922) (xy 274.447924 -312.000868)
			(xy 274.459701 -311.953084) (xy 274.478992 -311.907808) (xy 274.505295 -311.866212) (xy 274.53793 -311.829375)
			(xy 274.576051 -311.79825) (xy 274.618672 -311.773643) (xy 274.664688 -311.756191) (xy 274.712907 -311.746347)
			(xy 274.762082 -311.744366) (xy 274.810937 -311.750298) (xy 274.858208 -311.76399) (xy 274.90267 -311.785088)
			(xy 274.943173 -311.813044) (xy 274.978666 -311.847136) (xy 275.008231 -311.88648) (xy 275.031102 -311.930057)
			(xy 275.046686 -311.976738) (xy 275.054581 -312.025315) (xy 275.055076 -312.049922) (xy 275.393924 -312.049922)
			(xy 275.397884 -312.000868) (xy 275.409661 -311.953084) (xy 275.428952 -311.907808) (xy 275.455255 -311.866212)
			(xy 275.48789 -311.829375) (xy 275.526011 -311.79825) (xy 275.568632 -311.773643) (xy 275.614648 -311.756191)
			(xy 275.662867 -311.746347) (xy 275.712042 -311.744366) (xy 275.760897 -311.750298) (xy 275.808168 -311.76399)
			(xy 275.85263 -311.785088) (xy 275.893133 -311.813044) (xy 275.928626 -311.847136) (xy 275.958191 -311.88648)
			(xy 275.981062 -311.930057) (xy 275.996646 -311.976738) (xy 276.004541 -312.025315) (xy 276.005036 -312.049922)
			(xy 276.343884 -312.049922) (xy 276.347844 -312.000868) (xy 276.359621 -311.953084) (xy 276.378912 -311.907808)
			(xy 276.405215 -311.866212) (xy 276.43785 -311.829375) (xy 276.475971 -311.79825) (xy 276.518592 -311.773643)
			(xy 276.564608 -311.756191) (xy 276.612827 -311.746347) (xy 276.662002 -311.744366) (xy 276.710857 -311.750298)
			(xy 276.758128 -311.76399) (xy 276.80259 -311.785088) (xy 276.843093 -311.813044) (xy 276.878586 -311.847136)
			(xy 276.908151 -311.88648) (xy 276.931022 -311.930057) (xy 276.946606 -311.976738) (xy 276.954501 -312.025315)
			(xy 276.954996 -312.049922) (xy 277.294098 -312.049922) (xy 277.298058 -312.000868) (xy 277.309835 -311.953084)
			(xy 277.329126 -311.907808) (xy 277.355429 -311.866212) (xy 277.388064 -311.829375) (xy 277.426185 -311.79825)
			(xy 277.468806 -311.773643) (xy 277.514822 -311.756191) (xy 277.563041 -311.746347) (xy 277.612216 -311.744366)
			(xy 277.661071 -311.750298) (xy 277.708342 -311.76399) (xy 277.752804 -311.785088) (xy 277.793307 -311.813044)
			(xy 277.8288 -311.847136) (xy 277.858365 -311.88648) (xy 277.881236 -311.930057) (xy 277.89682 -311.976738)
			(xy 277.904715 -312.025315) (xy 277.90521 -312.049922) (xy 278.244058 -312.049922) (xy 278.248018 -312.000868)
			(xy 278.259795 -311.953084) (xy 278.279086 -311.907808) (xy 278.305389 -311.866212) (xy 278.338024 -311.829375)
			(xy 278.376145 -311.79825) (xy 278.418766 -311.773643) (xy 278.464782 -311.756191) (xy 278.513001 -311.746347)
			(xy 278.562176 -311.744366) (xy 278.611031 -311.750298) (xy 278.658302 -311.76399) (xy 278.702764 -311.785088)
			(xy 278.743267 -311.813044) (xy 278.77876 -311.847136) (xy 278.808325 -311.88648) (xy 278.831196 -311.930057)
			(xy 278.84678 -311.976738) (xy 278.854675 -312.025315) (xy 278.85517 -312.049922) (xy 279.194018 -312.049922)
			(xy 279.197978 -312.000868) (xy 279.209755 -311.953084) (xy 279.229046 -311.907808) (xy 279.255349 -311.866212)
			(xy 279.287984 -311.829375) (xy 279.326105 -311.79825) (xy 279.368726 -311.773643) (xy 279.414742 -311.756191)
			(xy 279.462961 -311.746347) (xy 279.512136 -311.744366) (xy 279.560991 -311.750298) (xy 279.608262 -311.76399)
			(xy 279.652724 -311.785088) (xy 279.693227 -311.813044) (xy 279.72872 -311.847136) (xy 279.758285 -311.88648)
			(xy 279.781156 -311.930057) (xy 279.79674 -311.976738) (xy 279.804635 -312.025315) (xy 279.80513 -312.049922)
			(xy 280.143978 -312.049922) (xy 280.147938 -312.000868) (xy 280.159715 -311.953084) (xy 280.179006 -311.907808)
			(xy 280.205309 -311.866212) (xy 280.237944 -311.829375) (xy 280.276065 -311.79825) (xy 280.318686 -311.773643)
			(xy 280.364702 -311.756191) (xy 280.412921 -311.746347) (xy 280.462096 -311.744366) (xy 280.510951 -311.750298)
			(xy 280.558222 -311.76399) (xy 280.602684 -311.785088) (xy 280.643187 -311.813044) (xy 280.67868 -311.847136)
			(xy 280.708245 -311.88648) (xy 280.731116 -311.930057) (xy 280.7467 -311.976738) (xy 280.754595 -312.025315)
			(xy 280.75509 -312.049922) (xy 281.093938 -312.049922) (xy 281.097898 -312.000868) (xy 281.109675 -311.953084)
			(xy 281.128966 -311.907808) (xy 281.155269 -311.866212) (xy 281.187904 -311.829375) (xy 281.226025 -311.79825)
			(xy 281.268646 -311.773643) (xy 281.314662 -311.756191) (xy 281.362881 -311.746347) (xy 281.412056 -311.744366)
			(xy 281.460911 -311.750298) (xy 281.508182 -311.76399) (xy 281.552644 -311.785088) (xy 281.593147 -311.813044)
			(xy 281.62864 -311.847136) (xy 281.658205 -311.88648) (xy 281.681076 -311.930057) (xy 281.69666 -311.976738)
			(xy 281.704555 -312.025315) (xy 281.70505 -312.049922) (xy 282.043898 -312.049922) (xy 282.047858 -312.000868)
			(xy 282.059635 -311.953084) (xy 282.078926 -311.907808) (xy 282.105229 -311.866212) (xy 282.137864 -311.829375)
			(xy 282.175985 -311.79825) (xy 282.218606 -311.773643) (xy 282.264622 -311.756191) (xy 282.312841 -311.746347)
			(xy 282.362016 -311.744366) (xy 282.410871 -311.750298) (xy 282.458142 -311.76399) (xy 282.502604 -311.785088)
			(xy 282.543107 -311.813044) (xy 282.5786 -311.847136) (xy 282.608165 -311.88648) (xy 282.631036 -311.930057)
			(xy 282.64662 -311.976738) (xy 282.654515 -312.025315) (xy 282.65501 -312.049922) (xy 282.994112 -312.049922)
			(xy 282.998072 -312.000868) (xy 283.009849 -311.953084) (xy 283.02914 -311.907808) (xy 283.055443 -311.866212)
			(xy 283.088078 -311.829375) (xy 283.126199 -311.79825) (xy 283.16882 -311.773643) (xy 283.214836 -311.756191)
			(xy 283.263055 -311.746347) (xy 283.31223 -311.744366) (xy 283.361085 -311.750298) (xy 283.408356 -311.76399)
			(xy 283.452818 -311.785088) (xy 283.493321 -311.813044) (xy 283.528814 -311.847136) (xy 283.558379 -311.88648)
			(xy 283.58125 -311.930057) (xy 283.596834 -311.976738) (xy 283.604729 -312.025315) (xy 283.605224 -312.049922)
			(xy 283.944072 -312.049922) (xy 283.948032 -312.000868) (xy 283.959809 -311.953084) (xy 283.9791 -311.907808)
			(xy 284.005403 -311.866212) (xy 284.038038 -311.829375) (xy 284.076159 -311.79825) (xy 284.11878 -311.773643)
			(xy 284.164796 -311.756191) (xy 284.213015 -311.746347) (xy 284.26219 -311.744366) (xy 284.311045 -311.750298)
			(xy 284.358316 -311.76399) (xy 284.402778 -311.785088) (xy 284.443281 -311.813044) (xy 284.478774 -311.847136)
			(xy 284.508339 -311.88648) (xy 284.53121 -311.930057) (xy 284.546794 -311.976738) (xy 284.554689 -312.025315)
			(xy 284.555184 -312.049922) (xy 284.894032 -312.049922) (xy 284.897992 -312.000868) (xy 284.909769 -311.953084)
			(xy 284.92906 -311.907808) (xy 284.955363 -311.866212) (xy 284.987998 -311.829375) (xy 285.026119 -311.79825)
			(xy 285.06874 -311.773643) (xy 285.114756 -311.756191) (xy 285.162975 -311.746347) (xy 285.21215 -311.744366)
			(xy 285.261005 -311.750298) (xy 285.308276 -311.76399) (xy 285.352738 -311.785088) (xy 285.393241 -311.813044)
			(xy 285.428734 -311.847136) (xy 285.458299 -311.88648) (xy 285.48117 -311.930057) (xy 285.496754 -311.976738)
			(xy 285.504649 -312.025315) (xy 285.505144 -312.049922) (xy 285.843992 -312.049922) (xy 285.847952 -312.000868)
			(xy 285.859729 -311.953084) (xy 285.87902 -311.907808) (xy 285.905323 -311.866212) (xy 285.937958 -311.829375)
			(xy 285.976079 -311.79825) (xy 286.0187 -311.773643) (xy 286.064716 -311.756191) (xy 286.112935 -311.746347)
			(xy 286.16211 -311.744366) (xy 286.210965 -311.750298) (xy 286.258236 -311.76399) (xy 286.302698 -311.785088)
			(xy 286.343201 -311.813044) (xy 286.378694 -311.847136) (xy 286.408259 -311.88648) (xy 286.43113 -311.930057)
			(xy 286.446714 -311.976738) (xy 286.454609 -312.025315) (xy 286.455104 -312.049922) (xy 286.793952 -312.049922)
			(xy 286.797912 -312.000868) (xy 286.809689 -311.953084) (xy 286.82898 -311.907808) (xy 286.855283 -311.866212)
			(xy 286.887918 -311.829375) (xy 286.926039 -311.79825) (xy 286.96866 -311.773643) (xy 287.014676 -311.756191)
			(xy 287.062895 -311.746347) (xy 287.11207 -311.744366) (xy 287.160925 -311.750298) (xy 287.208196 -311.76399)
			(xy 287.252658 -311.785088) (xy 287.293161 -311.813044) (xy 287.328654 -311.847136) (xy 287.358219 -311.88648)
			(xy 287.38109 -311.930057) (xy 287.396674 -311.976738) (xy 287.404569 -312.025315) (xy 287.405064 -312.049922)
			(xy 287.743912 -312.049922) (xy 287.747872 -312.000868) (xy 287.759649 -311.953084) (xy 287.77894 -311.907808)
			(xy 287.805243 -311.866212) (xy 287.837878 -311.829375) (xy 287.875999 -311.79825) (xy 287.91862 -311.773643)
			(xy 287.964636 -311.756191) (xy 288.012855 -311.746347) (xy 288.06203 -311.744366) (xy 288.110885 -311.750298)
			(xy 288.158156 -311.76399) (xy 288.202618 -311.785088) (xy 288.243121 -311.813044) (xy 288.278614 -311.847136)
			(xy 288.308179 -311.88648) (xy 288.33105 -311.930057) (xy 288.346634 -311.976738) (xy 288.354529 -312.025315)
			(xy 288.355024 -312.049922) (xy 288.694126 -312.049922) (xy 288.698086 -312.000868) (xy 288.709863 -311.953084)
			(xy 288.729154 -311.907808) (xy 288.755457 -311.866212) (xy 288.788092 -311.829375) (xy 288.826213 -311.79825)
			(xy 288.868834 -311.773643) (xy 288.91485 -311.756191) (xy 288.963069 -311.746347) (xy 289.012244 -311.744366)
			(xy 289.061099 -311.750298) (xy 289.10837 -311.76399) (xy 289.152832 -311.785088) (xy 289.193335 -311.813044)
			(xy 289.228828 -311.847136) (xy 289.258393 -311.88648) (xy 289.281264 -311.930057) (xy 289.296848 -311.976738)
			(xy 289.304743 -312.025315) (xy 289.305238 -312.049922) (xy 289.644086 -312.049922) (xy 289.648046 -312.000868)
			(xy 289.659823 -311.953084) (xy 289.679114 -311.907808) (xy 289.705417 -311.866212) (xy 289.738052 -311.829375)
			(xy 289.776173 -311.79825) (xy 289.818794 -311.773643) (xy 289.86481 -311.756191) (xy 289.913029 -311.746347)
			(xy 289.962204 -311.744366) (xy 290.011059 -311.750298) (xy 290.05833 -311.76399) (xy 290.102792 -311.785088)
			(xy 290.143295 -311.813044) (xy 290.178788 -311.847136) (xy 290.208353 -311.88648) (xy 290.231224 -311.930057)
			(xy 290.246808 -311.976738) (xy 290.254703 -312.025315) (xy 290.255198 -312.049922) (xy 290.254703 -312.074529)
			(xy 290.254524 -312.07563) (xy 290.573202 -312.07563) (xy 290.573202 -312.024214) (xy 290.581245 -311.973432)
			(xy 290.597133 -311.924533) (xy 290.620476 -311.878721) (xy 290.650697 -311.837125) (xy 290.687053 -311.800769)
			(xy 290.728649 -311.770548) (xy 290.774461 -311.747205) (xy 290.82336 -311.731317) (xy 290.874142 -311.723274)
			(xy 290.925558 -311.723274) (xy 290.97634 -311.731317) (xy 291.025239 -311.747205) (xy 291.071051 -311.770548)
			(xy 291.112647 -311.800769) (xy 291.149003 -311.837125) (xy 291.179224 -311.878721) (xy 291.202567 -311.924533)
			(xy 291.218455 -311.973432) (xy 291.226498 -312.024214) (xy 291.227002 -312.049922) (xy 291.544006 -312.049922)
			(xy 291.547966 -312.000868) (xy 291.559743 -311.953084) (xy 291.579034 -311.907808) (xy 291.605337 -311.866212)
			(xy 291.637972 -311.829375) (xy 291.676093 -311.79825) (xy 291.718714 -311.773643) (xy 291.76473 -311.756191)
			(xy 291.812949 -311.746347) (xy 291.862124 -311.744366) (xy 291.910979 -311.750298) (xy 291.95825 -311.76399)
			(xy 292.002712 -311.785088) (xy 292.043215 -311.813044) (xy 292.078708 -311.847136) (xy 292.108273 -311.88648)
			(xy 292.131144 -311.930057) (xy 292.146728 -311.976738) (xy 292.154623 -312.025315) (xy 292.155118 -312.049922)
			(xy 292.154623 -312.074529) (xy 292.154444 -312.07563) (xy 292.473122 -312.07563) (xy 292.473122 -312.024214)
			(xy 292.481165 -311.973432) (xy 292.497053 -311.924533) (xy 292.520396 -311.878721) (xy 292.550617 -311.837125)
			(xy 292.586973 -311.800769) (xy 292.628569 -311.770548) (xy 292.674381 -311.747205) (xy 292.72328 -311.731317)
			(xy 292.774062 -311.723274) (xy 292.825478 -311.723274) (xy 292.87626 -311.731317) (xy 292.925159 -311.747205)
			(xy 292.970971 -311.770548) (xy 293.012567 -311.800769) (xy 293.048923 -311.837125) (xy 293.079144 -311.878721)
			(xy 293.102487 -311.924533) (xy 293.118375 -311.973432) (xy 293.126418 -312.024214) (xy 293.126922 -312.049922)
			(xy 293.443926 -312.049922) (xy 293.447886 -312.000868) (xy 293.459663 -311.953084) (xy 293.478954 -311.907808)
			(xy 293.505257 -311.866212) (xy 293.537892 -311.829375) (xy 293.576013 -311.79825) (xy 293.618634 -311.773643)
			(xy 293.66465 -311.756191) (xy 293.712869 -311.746347) (xy 293.762044 -311.744366) (xy 293.810899 -311.750298)
			(xy 293.85817 -311.76399) (xy 293.902632 -311.785088) (xy 293.943135 -311.813044) (xy 293.978628 -311.847136)
			(xy 294.008193 -311.88648) (xy 294.031064 -311.930057) (xy 294.046648 -311.976738) (xy 294.054543 -312.025315)
			(xy 294.055038 -312.049922) (xy 294.054543 -312.074529) (xy 294.054364 -312.07563) (xy 294.373042 -312.07563)
			(xy 294.373042 -312.024214) (xy 294.381085 -311.973432) (xy 294.396973 -311.924533) (xy 294.420316 -311.878721)
			(xy 294.450537 -311.837125) (xy 294.486893 -311.800769) (xy 294.528489 -311.770548) (xy 294.574301 -311.747205)
			(xy 294.6232 -311.731317) (xy 294.673982 -311.723274) (xy 294.725398 -311.723274) (xy 294.77618 -311.731317)
			(xy 294.825079 -311.747205) (xy 294.870891 -311.770548) (xy 294.912487 -311.800769) (xy 294.948843 -311.837125)
			(xy 294.979064 -311.878721) (xy 295.002407 -311.924533) (xy 295.018295 -311.973432) (xy 295.026338 -312.024214)
			(xy 295.026842 -312.049922) (xy 295.3441 -312.049922) (xy 295.34806 -312.000868) (xy 295.359837 -311.953084)
			(xy 295.379128 -311.907808) (xy 295.405431 -311.866212) (xy 295.438066 -311.829375) (xy 295.476187 -311.79825)
			(xy 295.518808 -311.773643) (xy 295.564824 -311.756191) (xy 295.613043 -311.746347) (xy 295.662218 -311.744366)
			(xy 295.711073 -311.750298) (xy 295.758344 -311.76399) (xy 295.802806 -311.785088) (xy 295.843309 -311.813044)
			(xy 295.878802 -311.847136) (xy 295.908367 -311.88648) (xy 295.931238 -311.930057) (xy 295.946822 -311.976738)
			(xy 295.954717 -312.025315) (xy 295.955212 -312.049922) (xy 295.954717 -312.074529) (xy 295.954538 -312.07563)
			(xy 296.273216 -312.07563) (xy 296.273216 -312.024214) (xy 296.281259 -311.973432) (xy 296.297147 -311.924533)
			(xy 296.32049 -311.878721) (xy 296.350711 -311.837125) (xy 296.387067 -311.800769) (xy 296.428663 -311.770548)
			(xy 296.474475 -311.747205) (xy 296.523374 -311.731317) (xy 296.574156 -311.723274) (xy 296.625572 -311.723274)
			(xy 296.676354 -311.731317) (xy 296.725253 -311.747205) (xy 296.771065 -311.770548) (xy 296.812661 -311.800769)
			(xy 296.849017 -311.837125) (xy 296.879238 -311.878721) (xy 296.902581 -311.924533) (xy 296.918469 -311.973432)
			(xy 296.926512 -312.024214) (xy 296.927016 -312.049922) (xy 297.24402 -312.049922) (xy 297.24798 -312.000868)
			(xy 297.259757 -311.953084) (xy 297.279048 -311.907808) (xy 297.305351 -311.866212) (xy 297.337986 -311.829375)
			(xy 297.376107 -311.79825) (xy 297.418728 -311.773643) (xy 297.464744 -311.756191) (xy 297.512963 -311.746347)
			(xy 297.562138 -311.744366) (xy 297.610993 -311.750298) (xy 297.658264 -311.76399) (xy 297.702726 -311.785088)
			(xy 297.743229 -311.813044) (xy 297.778722 -311.847136) (xy 297.808287 -311.88648) (xy 297.831158 -311.930057)
			(xy 297.846742 -311.976738) (xy 297.854637 -312.025315) (xy 297.855132 -312.049922) (xy 297.854637 -312.074529)
			(xy 297.854458 -312.07563) (xy 298.173136 -312.07563) (xy 298.173136 -312.024214) (xy 298.181179 -311.973432)
			(xy 298.197067 -311.924533) (xy 298.22041 -311.878721) (xy 298.250631 -311.837125) (xy 298.286987 -311.800769)
			(xy 298.328583 -311.770548) (xy 298.374395 -311.747205) (xy 298.423294 -311.731317) (xy 298.474076 -311.723274)
			(xy 298.525492 -311.723274) (xy 298.576274 -311.731317) (xy 298.625173 -311.747205) (xy 298.670985 -311.770548)
			(xy 298.712581 -311.800769) (xy 298.748937 -311.837125) (xy 298.779158 -311.878721) (xy 298.802501 -311.924533)
			(xy 298.818389 -311.973432) (xy 298.826432 -312.024214) (xy 298.826936 -312.049922) (xy 299.14394 -312.049922)
			(xy 299.1479 -312.000868) (xy 299.159677 -311.953084) (xy 299.178968 -311.907808) (xy 299.205271 -311.866212)
			(xy 299.237906 -311.829375) (xy 299.276027 -311.79825) (xy 299.318648 -311.773643) (xy 299.364664 -311.756191)
			(xy 299.412883 -311.746347) (xy 299.462058 -311.744366) (xy 299.510913 -311.750298) (xy 299.558184 -311.76399)
			(xy 299.602646 -311.785088) (xy 299.643149 -311.813044) (xy 299.678642 -311.847136) (xy 299.708207 -311.88648)
			(xy 299.731078 -311.930057) (xy 299.746662 -311.976738) (xy 299.754557 -312.025315) (xy 299.755052 -312.049922)
			(xy 299.754557 -312.074529) (xy 299.754378 -312.07563) (xy 300.073056 -312.07563) (xy 300.073056 -312.024214)
			(xy 300.081099 -311.973432) (xy 300.096987 -311.924533) (xy 300.12033 -311.878721) (xy 300.150551 -311.837125)
			(xy 300.186907 -311.800769) (xy 300.228503 -311.770548) (xy 300.274315 -311.747205) (xy 300.323214 -311.731317)
			(xy 300.373996 -311.723274) (xy 300.425412 -311.723274) (xy 300.476194 -311.731317) (xy 300.525093 -311.747205)
			(xy 300.570905 -311.770548) (xy 300.612501 -311.800769) (xy 300.648857 -311.837125) (xy 300.679078 -311.878721)
			(xy 300.702421 -311.924533) (xy 300.718309 -311.973432) (xy 300.726352 -312.024214) (xy 300.726856 -312.049922)
			(xy 301.044114 -312.049922) (xy 301.048074 -312.000868) (xy 301.059851 -311.953084) (xy 301.079142 -311.907808)
			(xy 301.105445 -311.866212) (xy 301.13808 -311.829375) (xy 301.176201 -311.79825) (xy 301.218822 -311.773643)
			(xy 301.264838 -311.756191) (xy 301.313057 -311.746347) (xy 301.362232 -311.744366) (xy 301.411087 -311.750298)
			(xy 301.458358 -311.76399) (xy 301.50282 -311.785088) (xy 301.543323 -311.813044) (xy 301.578816 -311.847136)
			(xy 301.608381 -311.88648) (xy 301.631252 -311.930057) (xy 301.646836 -311.976738) (xy 301.654731 -312.025315)
			(xy 301.655226 -312.049922) (xy 301.654731 -312.074529) (xy 301.654552 -312.07563) (xy 301.97323 -312.07563)
			(xy 301.97323 -312.024214) (xy 301.981273 -311.973432) (xy 301.997161 -311.924533) (xy 302.020504 -311.878721)
			(xy 302.050725 -311.837125) (xy 302.087081 -311.800769) (xy 302.128677 -311.770548) (xy 302.174489 -311.747205)
			(xy 302.223388 -311.731317) (xy 302.27417 -311.723274) (xy 302.325586 -311.723274) (xy 302.376368 -311.731317)
			(xy 302.425267 -311.747205) (xy 302.471079 -311.770548) (xy 302.512675 -311.800769) (xy 302.549031 -311.837125)
			(xy 302.579252 -311.878721) (xy 302.602595 -311.924533) (xy 302.618483 -311.973432) (xy 302.626526 -312.024214)
			(xy 302.62703 -312.049922) (xy 302.944034 -312.049922) (xy 302.947994 -312.000868) (xy 302.959771 -311.953084)
			(xy 302.979062 -311.907808) (xy 303.005365 -311.866212) (xy 303.038 -311.829375) (xy 303.076121 -311.79825)
			(xy 303.118742 -311.773643) (xy 303.164758 -311.756191) (xy 303.212977 -311.746347) (xy 303.262152 -311.744366)
			(xy 303.311007 -311.750298) (xy 303.358278 -311.76399) (xy 303.40274 -311.785088) (xy 303.443243 -311.813044)
			(xy 303.478736 -311.847136) (xy 303.508301 -311.88648) (xy 303.531172 -311.930057) (xy 303.546756 -311.976738)
			(xy 303.554651 -312.025315) (xy 303.555146 -312.049922) (xy 303.554651 -312.074529) (xy 303.546756 -312.123106)
			(xy 303.531172 -312.169787) (xy 303.508301 -312.213364) (xy 303.478736 -312.252708) (xy 303.443243 -312.2868)
			(xy 303.40274 -312.314756) (xy 303.358278 -312.335854) (xy 303.311007 -312.349546) (xy 303.262152 -312.355478)
			(xy 303.212977 -312.353497) (xy 303.164758 -312.343653) (xy 303.118742 -312.326201) (xy 303.076121 -312.301594)
			(xy 303.038 -312.270469) (xy 303.005365 -312.233632) (xy 302.979062 -312.192036) (xy 302.959771 -312.14676)
			(xy 302.947994 -312.098976) (xy 302.944034 -312.049922) (xy 302.62703 -312.049922) (xy 302.626526 -312.07563)
			(xy 302.618483 -312.126412) (xy 302.602595 -312.175311) (xy 302.579252 -312.221123) (xy 302.549031 -312.262719)
			(xy 302.512675 -312.299075) (xy 302.471079 -312.329296) (xy 302.425267 -312.352639) (xy 302.376368 -312.368527)
			(xy 302.325586 -312.37657) (xy 302.27417 -312.37657) (xy 302.223388 -312.368527) (xy 302.174489 -312.352639)
			(xy 302.128677 -312.329296) (xy 302.087081 -312.299075) (xy 302.050725 -312.262719) (xy 302.020504 -312.221123)
			(xy 301.997161 -312.175311) (xy 301.981273 -312.126412) (xy 301.97323 -312.07563) (xy 301.654552 -312.07563)
			(xy 301.646836 -312.123106) (xy 301.631252 -312.169787) (xy 301.608381 -312.213364) (xy 301.578816 -312.252708)
			(xy 301.543323 -312.2868) (xy 301.50282 -312.314756) (xy 301.458358 -312.335854) (xy 301.411087 -312.349546)
			(xy 301.362232 -312.355478) (xy 301.313057 -312.353497) (xy 301.264838 -312.343653) (xy 301.218822 -312.326201)
			(xy 301.176201 -312.301594) (xy 301.13808 -312.270469) (xy 301.105445 -312.233632) (xy 301.079142 -312.192036)
			(xy 301.059851 -312.14676) (xy 301.048074 -312.098976) (xy 301.044114 -312.049922) (xy 300.726856 -312.049922)
			(xy 300.726352 -312.07563) (xy 300.718309 -312.126412) (xy 300.702421 -312.175311) (xy 300.679078 -312.221123)
			(xy 300.648857 -312.262719) (xy 300.612501 -312.299075) (xy 300.570905 -312.329296) (xy 300.525093 -312.352639)
			(xy 300.476194 -312.368527) (xy 300.425412 -312.37657) (xy 300.373996 -312.37657) (xy 300.323214 -312.368527)
			(xy 300.274315 -312.352639) (xy 300.228503 -312.329296) (xy 300.186907 -312.299075) (xy 300.150551 -312.262719)
			(xy 300.12033 -312.221123) (xy 300.096987 -312.175311) (xy 300.081099 -312.126412) (xy 300.073056 -312.07563)
			(xy 299.754378 -312.07563) (xy 299.746662 -312.123106) (xy 299.731078 -312.169787) (xy 299.708207 -312.213364)
			(xy 299.678642 -312.252708) (xy 299.643149 -312.2868) (xy 299.602646 -312.314756) (xy 299.558184 -312.335854)
			(xy 299.510913 -312.349546) (xy 299.462058 -312.355478) (xy 299.412883 -312.353497) (xy 299.364664 -312.343653)
			(xy 299.318648 -312.326201) (xy 299.276027 -312.301594) (xy 299.237906 -312.270469) (xy 299.205271 -312.233632)
			(xy 299.178968 -312.192036) (xy 299.159677 -312.14676) (xy 299.1479 -312.098976) (xy 299.14394 -312.049922)
			(xy 298.826936 -312.049922) (xy 298.826432 -312.07563) (xy 298.818389 -312.126412) (xy 298.802501 -312.175311)
			(xy 298.779158 -312.221123) (xy 298.748937 -312.262719) (xy 298.712581 -312.299075) (xy 298.670985 -312.329296)
			(xy 298.625173 -312.352639) (xy 298.576274 -312.368527) (xy 298.525492 -312.37657) (xy 298.474076 -312.37657)
			(xy 298.423294 -312.368527) (xy 298.374395 -312.352639) (xy 298.328583 -312.329296) (xy 298.286987 -312.299075)
			(xy 298.250631 -312.262719) (xy 298.22041 -312.221123) (xy 298.197067 -312.175311) (xy 298.181179 -312.126412)
			(xy 298.173136 -312.07563) (xy 297.854458 -312.07563) (xy 297.846742 -312.123106) (xy 297.831158 -312.169787)
			(xy 297.808287 -312.213364) (xy 297.778722 -312.252708) (xy 297.743229 -312.2868) (xy 297.702726 -312.314756)
			(xy 297.658264 -312.335854) (xy 297.610993 -312.349546) (xy 297.562138 -312.355478) (xy 297.512963 -312.353497)
			(xy 297.464744 -312.343653) (xy 297.418728 -312.326201) (xy 297.376107 -312.301594) (xy 297.337986 -312.270469)
			(xy 297.305351 -312.233632) (xy 297.279048 -312.192036) (xy 297.259757 -312.14676) (xy 297.24798 -312.098976)
			(xy 297.24402 -312.049922) (xy 296.927016 -312.049922) (xy 296.926512 -312.07563) (xy 296.918469 -312.126412)
			(xy 296.902581 -312.175311) (xy 296.879238 -312.221123) (xy 296.849017 -312.262719) (xy 296.812661 -312.299075)
			(xy 296.771065 -312.329296) (xy 296.725253 -312.352639) (xy 296.676354 -312.368527) (xy 296.625572 -312.37657)
			(xy 296.574156 -312.37657) (xy 296.523374 -312.368527) (xy 296.474475 -312.352639) (xy 296.428663 -312.329296)
			(xy 296.387067 -312.299075) (xy 296.350711 -312.262719) (xy 296.32049 -312.221123) (xy 296.297147 -312.175311)
			(xy 296.281259 -312.126412) (xy 296.273216 -312.07563) (xy 295.954538 -312.07563) (xy 295.946822 -312.123106)
			(xy 295.931238 -312.169787) (xy 295.908367 -312.213364) (xy 295.878802 -312.252708) (xy 295.843309 -312.2868)
			(xy 295.802806 -312.314756) (xy 295.758344 -312.335854) (xy 295.711073 -312.349546) (xy 295.662218 -312.355478)
			(xy 295.613043 -312.353497) (xy 295.564824 -312.343653) (xy 295.518808 -312.326201) (xy 295.476187 -312.301594)
			(xy 295.438066 -312.270469) (xy 295.405431 -312.233632) (xy 295.379128 -312.192036) (xy 295.359837 -312.14676)
			(xy 295.34806 -312.098976) (xy 295.3441 -312.049922) (xy 295.026842 -312.049922) (xy 295.026338 -312.07563)
			(xy 295.018295 -312.126412) (xy 295.002407 -312.175311) (xy 294.979064 -312.221123) (xy 294.948843 -312.262719)
			(xy 294.912487 -312.299075) (xy 294.870891 -312.329296) (xy 294.825079 -312.352639) (xy 294.77618 -312.368527)
			(xy 294.725398 -312.37657) (xy 294.673982 -312.37657) (xy 294.6232 -312.368527) (xy 294.574301 -312.352639)
			(xy 294.528489 -312.329296) (xy 294.486893 -312.299075) (xy 294.450537 -312.262719) (xy 294.420316 -312.221123)
			(xy 294.396973 -312.175311) (xy 294.381085 -312.126412) (xy 294.373042 -312.07563) (xy 294.054364 -312.07563)
			(xy 294.046648 -312.123106) (xy 294.031064 -312.169787) (xy 294.008193 -312.213364) (xy 293.978628 -312.252708)
			(xy 293.943135 -312.2868) (xy 293.902632 -312.314756) (xy 293.85817 -312.335854) (xy 293.810899 -312.349546)
			(xy 293.762044 -312.355478) (xy 293.712869 -312.353497) (xy 293.66465 -312.343653) (xy 293.618634 -312.326201)
			(xy 293.576013 -312.301594) (xy 293.537892 -312.270469) (xy 293.505257 -312.233632) (xy 293.478954 -312.192036)
			(xy 293.459663 -312.14676) (xy 293.447886 -312.098976) (xy 293.443926 -312.049922) (xy 293.126922 -312.049922)
			(xy 293.126418 -312.07563) (xy 293.118375 -312.126412) (xy 293.102487 -312.175311) (xy 293.079144 -312.221123)
			(xy 293.048923 -312.262719) (xy 293.012567 -312.299075) (xy 292.970971 -312.329296) (xy 292.925159 -312.352639)
			(xy 292.87626 -312.368527) (xy 292.825478 -312.37657) (xy 292.774062 -312.37657) (xy 292.72328 -312.368527)
			(xy 292.674381 -312.352639) (xy 292.628569 -312.329296) (xy 292.586973 -312.299075) (xy 292.550617 -312.262719)
			(xy 292.520396 -312.221123) (xy 292.497053 -312.175311) (xy 292.481165 -312.126412) (xy 292.473122 -312.07563)
			(xy 292.154444 -312.07563) (xy 292.146728 -312.123106) (xy 292.131144 -312.169787) (xy 292.108273 -312.213364)
			(xy 292.078708 -312.252708) (xy 292.043215 -312.2868) (xy 292.002712 -312.314756) (xy 291.95825 -312.335854)
			(xy 291.910979 -312.349546) (xy 291.862124 -312.355478) (xy 291.812949 -312.353497) (xy 291.76473 -312.343653)
			(xy 291.718714 -312.326201) (xy 291.676093 -312.301594) (xy 291.637972 -312.270469) (xy 291.605337 -312.233632)
			(xy 291.579034 -312.192036) (xy 291.559743 -312.14676) (xy 291.547966 -312.098976) (xy 291.544006 -312.049922)
			(xy 291.227002 -312.049922) (xy 291.226498 -312.07563) (xy 291.218455 -312.126412) (xy 291.202567 -312.175311)
			(xy 291.179224 -312.221123) (xy 291.149003 -312.262719) (xy 291.112647 -312.299075) (xy 291.071051 -312.329296)
			(xy 291.025239 -312.352639) (xy 290.97634 -312.368527) (xy 290.925558 -312.37657) (xy 290.874142 -312.37657)
			(xy 290.82336 -312.368527) (xy 290.774461 -312.352639) (xy 290.728649 -312.329296) (xy 290.687053 -312.299075)
			(xy 290.650697 -312.262719) (xy 290.620476 -312.221123) (xy 290.597133 -312.175311) (xy 290.581245 -312.126412)
			(xy 290.573202 -312.07563) (xy 290.254524 -312.07563) (xy 290.246808 -312.123106) (xy 290.231224 -312.169787)
			(xy 290.208353 -312.213364) (xy 290.178788 -312.252708) (xy 290.143295 -312.2868) (xy 290.102792 -312.314756)
			(xy 290.05833 -312.335854) (xy 290.011059 -312.349546) (xy 289.962204 -312.355478) (xy 289.913029 -312.353497)
			(xy 289.86481 -312.343653) (xy 289.818794 -312.326201) (xy 289.776173 -312.301594) (xy 289.738052 -312.270469)
			(xy 289.705417 -312.233632) (xy 289.679114 -312.192036) (xy 289.659823 -312.14676) (xy 289.648046 -312.098976)
			(xy 289.644086 -312.049922) (xy 289.305238 -312.049922) (xy 289.304743 -312.074529) (xy 289.296848 -312.123106)
			(xy 289.281264 -312.169787) (xy 289.258393 -312.213364) (xy 289.228828 -312.252708) (xy 289.193335 -312.2868)
			(xy 289.152832 -312.314756) (xy 289.10837 -312.335854) (xy 289.061099 -312.349546) (xy 289.012244 -312.355478)
			(xy 288.963069 -312.353497) (xy 288.91485 -312.343653) (xy 288.868834 -312.326201) (xy 288.826213 -312.301594)
			(xy 288.788092 -312.270469) (xy 288.755457 -312.233632) (xy 288.729154 -312.192036) (xy 288.709863 -312.14676)
			(xy 288.698086 -312.098976) (xy 288.694126 -312.049922) (xy 288.355024 -312.049922) (xy 288.354529 -312.074529)
			(xy 288.346634 -312.123106) (xy 288.33105 -312.169787) (xy 288.308179 -312.213364) (xy 288.278614 -312.252708)
			(xy 288.243121 -312.2868) (xy 288.202618 -312.314756) (xy 288.158156 -312.335854) (xy 288.110885 -312.349546)
			(xy 288.06203 -312.355478) (xy 288.012855 -312.353497) (xy 287.964636 -312.343653) (xy 287.91862 -312.326201)
			(xy 287.875999 -312.301594) (xy 287.837878 -312.270469) (xy 287.805243 -312.233632) (xy 287.77894 -312.192036)
			(xy 287.759649 -312.14676) (xy 287.747872 -312.098976) (xy 287.743912 -312.049922) (xy 287.405064 -312.049922)
			(xy 287.404569 -312.074529) (xy 287.396674 -312.123106) (xy 287.38109 -312.169787) (xy 287.358219 -312.213364)
			(xy 287.328654 -312.252708) (xy 287.293161 -312.2868) (xy 287.252658 -312.314756) (xy 287.208196 -312.335854)
			(xy 287.160925 -312.349546) (xy 287.11207 -312.355478) (xy 287.062895 -312.353497) (xy 287.014676 -312.343653)
			(xy 286.96866 -312.326201) (xy 286.926039 -312.301594) (xy 286.887918 -312.270469) (xy 286.855283 -312.233632)
			(xy 286.82898 -312.192036) (xy 286.809689 -312.14676) (xy 286.797912 -312.098976) (xy 286.793952 -312.049922)
			(xy 286.455104 -312.049922) (xy 286.454609 -312.074529) (xy 286.446714 -312.123106) (xy 286.43113 -312.169787)
			(xy 286.408259 -312.213364) (xy 286.378694 -312.252708) (xy 286.343201 -312.2868) (xy 286.302698 -312.314756)
			(xy 286.258236 -312.335854) (xy 286.210965 -312.349546) (xy 286.16211 -312.355478) (xy 286.112935 -312.353497)
			(xy 286.064716 -312.343653) (xy 286.0187 -312.326201) (xy 285.976079 -312.301594) (xy 285.937958 -312.270469)
			(xy 285.905323 -312.233632) (xy 285.87902 -312.192036) (xy 285.859729 -312.14676) (xy 285.847952 -312.098976)
			(xy 285.843992 -312.049922) (xy 285.505144 -312.049922) (xy 285.504649 -312.074529) (xy 285.496754 -312.123106)
			(xy 285.48117 -312.169787) (xy 285.458299 -312.213364) (xy 285.428734 -312.252708) (xy 285.393241 -312.2868)
			(xy 285.352738 -312.314756) (xy 285.308276 -312.335854) (xy 285.261005 -312.349546) (xy 285.21215 -312.355478)
			(xy 285.162975 -312.353497) (xy 285.114756 -312.343653) (xy 285.06874 -312.326201) (xy 285.026119 -312.301594)
			(xy 284.987998 -312.270469) (xy 284.955363 -312.233632) (xy 284.92906 -312.192036) (xy 284.909769 -312.14676)
			(xy 284.897992 -312.098976) (xy 284.894032 -312.049922) (xy 284.555184 -312.049922) (xy 284.554689 -312.074529)
			(xy 284.546794 -312.123106) (xy 284.53121 -312.169787) (xy 284.508339 -312.213364) (xy 284.478774 -312.252708)
			(xy 284.443281 -312.2868) (xy 284.402778 -312.314756) (xy 284.358316 -312.335854) (xy 284.311045 -312.349546)
			(xy 284.26219 -312.355478) (xy 284.213015 -312.353497) (xy 284.164796 -312.343653) (xy 284.11878 -312.326201)
			(xy 284.076159 -312.301594) (xy 284.038038 -312.270469) (xy 284.005403 -312.233632) (xy 283.9791 -312.192036)
			(xy 283.959809 -312.14676) (xy 283.948032 -312.098976) (xy 283.944072 -312.049922) (xy 283.605224 -312.049922)
			(xy 283.604729 -312.074529) (xy 283.596834 -312.123106) (xy 283.58125 -312.169787) (xy 283.558379 -312.213364)
			(xy 283.528814 -312.252708) (xy 283.493321 -312.2868) (xy 283.452818 -312.314756) (xy 283.408356 -312.335854)
			(xy 283.361085 -312.349546) (xy 283.31223 -312.355478) (xy 283.263055 -312.353497) (xy 283.214836 -312.343653)
			(xy 283.16882 -312.326201) (xy 283.126199 -312.301594) (xy 283.088078 -312.270469) (xy 283.055443 -312.233632)
			(xy 283.02914 -312.192036) (xy 283.009849 -312.14676) (xy 282.998072 -312.098976) (xy 282.994112 -312.049922)
			(xy 282.65501 -312.049922) (xy 282.654515 -312.074529) (xy 282.64662 -312.123106) (xy 282.631036 -312.169787)
			(xy 282.608165 -312.213364) (xy 282.5786 -312.252708) (xy 282.543107 -312.2868) (xy 282.502604 -312.314756)
			(xy 282.458142 -312.335854) (xy 282.410871 -312.349546) (xy 282.362016 -312.355478) (xy 282.312841 -312.353497)
			(xy 282.264622 -312.343653) (xy 282.218606 -312.326201) (xy 282.175985 -312.301594) (xy 282.137864 -312.270469)
			(xy 282.105229 -312.233632) (xy 282.078926 -312.192036) (xy 282.059635 -312.14676) (xy 282.047858 -312.098976)
			(xy 282.043898 -312.049922) (xy 281.70505 -312.049922) (xy 281.704555 -312.074529) (xy 281.69666 -312.123106)
			(xy 281.681076 -312.169787) (xy 281.658205 -312.213364) (xy 281.62864 -312.252708) (xy 281.593147 -312.2868)
			(xy 281.552644 -312.314756) (xy 281.508182 -312.335854) (xy 281.460911 -312.349546) (xy 281.412056 -312.355478)
			(xy 281.362881 -312.353497) (xy 281.314662 -312.343653) (xy 281.268646 -312.326201) (xy 281.226025 -312.301594)
			(xy 281.187904 -312.270469) (xy 281.155269 -312.233632) (xy 281.128966 -312.192036) (xy 281.109675 -312.14676)
			(xy 281.097898 -312.098976) (xy 281.093938 -312.049922) (xy 280.75509 -312.049922) (xy 280.754595 -312.074529)
			(xy 280.7467 -312.123106) (xy 280.731116 -312.169787) (xy 280.708245 -312.213364) (xy 280.67868 -312.252708)
			(xy 280.643187 -312.2868) (xy 280.602684 -312.314756) (xy 280.558222 -312.335854) (xy 280.510951 -312.349546)
			(xy 280.462096 -312.355478) (xy 280.412921 -312.353497) (xy 280.364702 -312.343653) (xy 280.318686 -312.326201)
			(xy 280.276065 -312.301594) (xy 280.237944 -312.270469) (xy 280.205309 -312.233632) (xy 280.179006 -312.192036)
			(xy 280.159715 -312.14676) (xy 280.147938 -312.098976) (xy 280.143978 -312.049922) (xy 279.80513 -312.049922)
			(xy 279.804635 -312.074529) (xy 279.79674 -312.123106) (xy 279.781156 -312.169787) (xy 279.758285 -312.213364)
			(xy 279.72872 -312.252708) (xy 279.693227 -312.2868) (xy 279.652724 -312.314756) (xy 279.608262 -312.335854)
			(xy 279.560991 -312.349546) (xy 279.512136 -312.355478) (xy 279.462961 -312.353497) (xy 279.414742 -312.343653)
			(xy 279.368726 -312.326201) (xy 279.326105 -312.301594) (xy 279.287984 -312.270469) (xy 279.255349 -312.233632)
			(xy 279.229046 -312.192036) (xy 279.209755 -312.14676) (xy 279.197978 -312.098976) (xy 279.194018 -312.049922)
			(xy 278.85517 -312.049922) (xy 278.854675 -312.074529) (xy 278.84678 -312.123106) (xy 278.831196 -312.169787)
			(xy 278.808325 -312.213364) (xy 278.77876 -312.252708) (xy 278.743267 -312.2868) (xy 278.702764 -312.314756)
			(xy 278.658302 -312.335854) (xy 278.611031 -312.349546) (xy 278.562176 -312.355478) (xy 278.513001 -312.353497)
			(xy 278.464782 -312.343653) (xy 278.418766 -312.326201) (xy 278.376145 -312.301594) (xy 278.338024 -312.270469)
			(xy 278.305389 -312.233632) (xy 278.279086 -312.192036) (xy 278.259795 -312.14676) (xy 278.248018 -312.098976)
			(xy 278.244058 -312.049922) (xy 277.90521 -312.049922) (xy 277.904715 -312.074529) (xy 277.89682 -312.123106)
			(xy 277.881236 -312.169787) (xy 277.858365 -312.213364) (xy 277.8288 -312.252708) (xy 277.793307 -312.2868)
			(xy 277.752804 -312.314756) (xy 277.708342 -312.335854) (xy 277.661071 -312.349546) (xy 277.612216 -312.355478)
			(xy 277.563041 -312.353497) (xy 277.514822 -312.343653) (xy 277.468806 -312.326201) (xy 277.426185 -312.301594)
			(xy 277.388064 -312.270469) (xy 277.355429 -312.233632) (xy 277.329126 -312.192036) (xy 277.309835 -312.14676)
			(xy 277.298058 -312.098976) (xy 277.294098 -312.049922) (xy 276.954996 -312.049922) (xy 276.954501 -312.074529)
			(xy 276.946606 -312.123106) (xy 276.931022 -312.169787) (xy 276.908151 -312.213364) (xy 276.878586 -312.252708)
			(xy 276.843093 -312.2868) (xy 276.80259 -312.314756) (xy 276.758128 -312.335854) (xy 276.710857 -312.349546)
			(xy 276.662002 -312.355478) (xy 276.612827 -312.353497) (xy 276.564608 -312.343653) (xy 276.518592 -312.326201)
			(xy 276.475971 -312.301594) (xy 276.43785 -312.270469) (xy 276.405215 -312.233632) (xy 276.378912 -312.192036)
			(xy 276.359621 -312.14676) (xy 276.347844 -312.098976) (xy 276.343884 -312.049922) (xy 276.005036 -312.049922)
			(xy 276.004541 -312.074529) (xy 275.996646 -312.123106) (xy 275.981062 -312.169787) (xy 275.958191 -312.213364)
			(xy 275.928626 -312.252708) (xy 275.893133 -312.2868) (xy 275.85263 -312.314756) (xy 275.808168 -312.335854)
			(xy 275.760897 -312.349546) (xy 275.712042 -312.355478) (xy 275.662867 -312.353497) (xy 275.614648 -312.343653)
			(xy 275.568632 -312.326201) (xy 275.526011 -312.301594) (xy 275.48789 -312.270469) (xy 275.455255 -312.233632)
			(xy 275.428952 -312.192036) (xy 275.409661 -312.14676) (xy 275.397884 -312.098976) (xy 275.393924 -312.049922)
			(xy 275.055076 -312.049922) (xy 275.054581 -312.074529) (xy 275.046686 -312.123106) (xy 275.031102 -312.169787)
			(xy 275.008231 -312.213364) (xy 274.978666 -312.252708) (xy 274.943173 -312.2868) (xy 274.90267 -312.314756)
			(xy 274.858208 -312.335854) (xy 274.810937 -312.349546) (xy 274.762082 -312.355478) (xy 274.712907 -312.353497)
			(xy 274.664688 -312.343653) (xy 274.618672 -312.326201) (xy 274.576051 -312.301594) (xy 274.53793 -312.270469)
			(xy 274.505295 -312.233632) (xy 274.478992 -312.192036) (xy 274.459701 -312.14676) (xy 274.447924 -312.098976)
			(xy 274.443964 -312.049922) (xy 274.12696 -312.049922) (xy 274.126456 -312.07563) (xy 274.118413 -312.126412)
			(xy 274.102525 -312.175311) (xy 274.079182 -312.221123) (xy 274.048961 -312.262719) (xy 274.012605 -312.299075)
			(xy 273.971009 -312.329296) (xy 273.925197 -312.352639) (xy 273.876298 -312.368527) (xy 273.825516 -312.37657)
			(xy 273.7741 -312.37657) (xy 273.723318 -312.368527) (xy 273.674419 -312.352639) (xy 273.628607 -312.329296)
			(xy 273.587011 -312.299075) (xy 273.550655 -312.262719) (xy 273.520434 -312.221123) (xy 273.497091 -312.175311)
			(xy 273.481203 -312.126412) (xy 273.47316 -312.07563) (xy 273.154482 -312.07563) (xy 273.146766 -312.123106)
			(xy 273.131182 -312.169787) (xy 273.108311 -312.213364) (xy 273.078746 -312.252708) (xy 273.043253 -312.2868)
			(xy 273.00275 -312.314756) (xy 272.958288 -312.335854) (xy 272.911017 -312.349546) (xy 272.862162 -312.355478)
			(xy 272.812987 -312.353497) (xy 272.764768 -312.343653) (xy 272.718752 -312.326201) (xy 272.676131 -312.301594)
			(xy 272.63801 -312.270469) (xy 272.605375 -312.233632) (xy 272.579072 -312.192036) (xy 272.559781 -312.14676)
			(xy 272.548004 -312.098976) (xy 272.544044 -312.049922) (xy 272.22704 -312.049922) (xy 272.226536 -312.07563)
			(xy 272.218493 -312.126412) (xy 272.202605 -312.175311) (xy 272.179262 -312.221123) (xy 272.149041 -312.262719)
			(xy 272.112685 -312.299075) (xy 272.071089 -312.329296) (xy 272.025277 -312.352639) (xy 271.976378 -312.368527)
			(xy 271.925596 -312.37657) (xy 271.87418 -312.37657) (xy 271.823398 -312.368527) (xy 271.774499 -312.352639)
			(xy 271.728687 -312.329296) (xy 271.687091 -312.299075) (xy 271.650735 -312.262719) (xy 271.620514 -312.221123)
			(xy 271.597171 -312.175311) (xy 271.581283 -312.126412) (xy 271.57324 -312.07563) (xy 271.254562 -312.07563)
			(xy 271.246846 -312.123106) (xy 271.231262 -312.169787) (xy 271.208391 -312.213364) (xy 271.178826 -312.252708)
			(xy 271.143333 -312.2868) (xy 271.10283 -312.314756) (xy 271.058368 -312.335854) (xy 271.011097 -312.349546)
			(xy 270.962242 -312.355478) (xy 270.913067 -312.353497) (xy 270.864848 -312.343653) (xy 270.818832 -312.326201)
			(xy 270.776211 -312.301594) (xy 270.73809 -312.270469) (xy 270.705455 -312.233632) (xy 270.679152 -312.192036)
			(xy 270.659861 -312.14676) (xy 270.648084 -312.098976) (xy 270.644124 -312.049922) (xy 270.326866 -312.049922)
			(xy 270.326362 -312.07563) (xy 270.318319 -312.126412) (xy 270.302431 -312.175311) (xy 270.279088 -312.221123)
			(xy 270.248867 -312.262719) (xy 270.212511 -312.299075) (xy 270.170915 -312.329296) (xy 270.125103 -312.352639)
			(xy 270.076204 -312.368527) (xy 270.025422 -312.37657) (xy 269.974006 -312.37657) (xy 269.923224 -312.368527)
			(xy 269.874325 -312.352639) (xy 269.828513 -312.329296) (xy 269.786917 -312.299075) (xy 269.750561 -312.262719)
			(xy 269.72034 -312.221123) (xy 269.696997 -312.175311) (xy 269.681109 -312.126412) (xy 269.673066 -312.07563)
			(xy 269.376402 -312.07563) (xy 269.368359 -312.126412) (xy 269.352471 -312.175311) (xy 269.329128 -312.221123)
			(xy 269.298907 -312.262719) (xy 269.262551 -312.299075) (xy 269.220955 -312.329296) (xy 269.175143 -312.352639)
			(xy 269.126244 -312.368527) (xy 269.075462 -312.37657) (xy 269.024046 -312.37657) (xy 268.973264 -312.368527)
			(xy 268.924365 -312.352639) (xy 268.878553 -312.329296) (xy 268.836957 -312.299075) (xy 268.800601 -312.262719)
			(xy 268.77038 -312.221123) (xy 268.747037 -312.175311) (xy 268.731149 -312.126412) (xy 268.723106 -312.07563)
			(xy 268.404133 -312.07563) (xy 268.396458 -312.122852) (xy 268.380874 -312.169533) (xy 268.358003 -312.21311)
			(xy 268.328438 -312.252454) (xy 268.292945 -312.286546) (xy 268.252442 -312.314502) (xy 268.20798 -312.3356)
			(xy 268.160709 -312.349292) (xy 268.111854 -312.355224) (xy 268.062679 -312.353243) (xy 268.01446 -312.343399)
			(xy 267.968444 -312.325947) (xy 267.925823 -312.30134) (xy 267.887702 -312.270215) (xy 267.855067 -312.233378)
			(xy 267.828764 -312.191782) (xy 267.809473 -312.146506) (xy 267.797696 -312.098722) (xy 267.793736 -312.049668)
			(xy 266.953896 -312.049668) (xy 266.974719 -312.081142) (xy 266.998391 -312.131639) (xy 267.014459 -312.185046)
			(xy 267.022579 -312.240222) (xy 267.023088 -312.268108) (xy 267.022579 -312.295994) (xy 267.014459 -312.35117)
			(xy 266.998391 -312.404577) (xy 266.974719 -312.455074) (xy 266.943946 -312.501587) (xy 266.906729 -312.543124)
			(xy 266.863861 -312.578799) (xy 266.816255 -312.607853) (xy 266.764926 -312.629665) (xy 266.710969 -312.643771)
			(xy 266.655532 -312.649871) (xy 266.599798 -312.647834) (xy 266.544955 -312.637704) (xy 266.492171 -312.619697)
			(xy 266.442571 -312.594196) (xy 266.397213 -312.561745) (xy 266.357064 -312.523036) (xy 266.322978 -312.478893)
			(xy 266.295682 -312.430258) (xy 266.275759 -312.378167) (xy 266.263633 -312.32373) (xy 266.259562 -312.268108)
			(xy 264.596765 -312.268108) (xy 264.61629 -312.289899) (xy 264.647063 -312.336412) (xy 264.670735 -312.386909)
			(xy 264.686803 -312.440316) (xy 264.694923 -312.495492) (xy 264.695432 -312.523378) (xy 264.694923 -312.551264)
			(xy 264.686803 -312.60644) (xy 264.670735 -312.659847) (xy 264.647063 -312.710344) (xy 264.61629 -312.756857)
			(xy 264.579073 -312.798394) (xy 264.536205 -312.834069) (xy 264.488599 -312.863123) (xy 264.43727 -312.884935)
			(xy 264.383313 -312.899041) (xy 264.327876 -312.905141) (xy 264.272142 -312.903104) (xy 264.217299 -312.892974)
			(xy 264.164515 -312.874967) (xy 264.114915 -312.849466) (xy 264.069557 -312.817015) (xy 264.029408 -312.778306)
			(xy 263.995322 -312.734163) (xy 263.968026 -312.685528) (xy 263.948103 -312.633437) (xy 263.935977 -312.579)
			(xy 263.931906 -312.523378) (xy 248.814844 -312.523378) (xy 248.814844 -312.999882) (xy 268.74395 -312.999882)
			(xy 268.74791 -312.950828) (xy 268.759687 -312.903044) (xy 268.778978 -312.857768) (xy 268.805281 -312.816172)
			(xy 268.837916 -312.779335) (xy 268.876037 -312.74821) (xy 268.918658 -312.723603) (xy 268.964674 -312.706151)
			(xy 269.012893 -312.696307) (xy 269.062068 -312.694326) (xy 269.110923 -312.700258) (xy 269.158194 -312.71395)
			(xy 269.202656 -312.735048) (xy 269.243159 -312.763004) (xy 269.278652 -312.797096) (xy 269.308217 -312.83644)
			(xy 269.331088 -312.880017) (xy 269.346672 -312.926698) (xy 269.354567 -312.975275) (xy 269.355062 -312.999882)
			(xy 269.69391 -312.999882) (xy 269.69787 -312.950828) (xy 269.709647 -312.903044) (xy 269.728938 -312.857768)
			(xy 269.755241 -312.816172) (xy 269.787876 -312.779335) (xy 269.825997 -312.74821) (xy 269.868618 -312.723603)
			(xy 269.914634 -312.706151) (xy 269.962853 -312.696307) (xy 270.012028 -312.694326) (xy 270.060883 -312.700258)
			(xy 270.108154 -312.71395) (xy 270.152616 -312.735048) (xy 270.193119 -312.763004) (xy 270.228612 -312.797096)
			(xy 270.258177 -312.83644) (xy 270.281048 -312.880017) (xy 270.296632 -312.926698) (xy 270.304527 -312.975275)
			(xy 270.305022 -312.999882) (xy 270.304527 -313.024489) (xy 270.304348 -313.02559) (xy 270.62328 -313.02559)
			(xy 270.62328 -312.974174) (xy 270.631323 -312.923392) (xy 270.647211 -312.874493) (xy 270.670554 -312.828681)
			(xy 270.700775 -312.787085) (xy 270.737131 -312.750729) (xy 270.778727 -312.720508) (xy 270.824539 -312.697165)
			(xy 270.873438 -312.681277) (xy 270.92422 -312.673234) (xy 270.975636 -312.673234) (xy 271.026418 -312.681277)
			(xy 271.075317 -312.697165) (xy 271.121129 -312.720508) (xy 271.162725 -312.750729) (xy 271.199081 -312.787085)
			(xy 271.229302 -312.828681) (xy 271.252645 -312.874493) (xy 271.268533 -312.923392) (xy 271.276576 -312.974174)
			(xy 271.27708 -312.999882) (xy 271.594084 -312.999882) (xy 271.598044 -312.950828) (xy 271.609821 -312.903044)
			(xy 271.629112 -312.857768) (xy 271.655415 -312.816172) (xy 271.68805 -312.779335) (xy 271.726171 -312.74821)
			(xy 271.768792 -312.723603) (xy 271.814808 -312.706151) (xy 271.863027 -312.696307) (xy 271.912202 -312.694326)
			(xy 271.961057 -312.700258) (xy 272.008328 -312.71395) (xy 272.05279 -312.735048) (xy 272.093293 -312.763004)
			(xy 272.128786 -312.797096) (xy 272.158351 -312.83644) (xy 272.181222 -312.880017) (xy 272.196806 -312.926698)
			(xy 272.204701 -312.975275) (xy 272.205196 -312.999882) (xy 272.204701 -313.024489) (xy 272.204522 -313.02559)
			(xy 272.5232 -313.02559) (xy 272.5232 -312.974174) (xy 272.531243 -312.923392) (xy 272.547131 -312.874493)
			(xy 272.570474 -312.828681) (xy 272.600695 -312.787085) (xy 272.637051 -312.750729) (xy 272.678647 -312.720508)
			(xy 272.724459 -312.697165) (xy 272.773358 -312.681277) (xy 272.82414 -312.673234) (xy 272.875556 -312.673234)
			(xy 272.926338 -312.681277) (xy 272.975237 -312.697165) (xy 273.021049 -312.720508) (xy 273.062645 -312.750729)
			(xy 273.099001 -312.787085) (xy 273.129222 -312.828681) (xy 273.152565 -312.874493) (xy 273.168453 -312.923392)
			(xy 273.176496 -312.974174) (xy 273.177 -312.999882) (xy 273.494004 -312.999882) (xy 273.497964 -312.950828)
			(xy 273.509741 -312.903044) (xy 273.529032 -312.857768) (xy 273.555335 -312.816172) (xy 273.58797 -312.779335)
			(xy 273.626091 -312.74821) (xy 273.668712 -312.723603) (xy 273.714728 -312.706151) (xy 273.762947 -312.696307)
			(xy 273.812122 -312.694326) (xy 273.860977 -312.700258) (xy 273.908248 -312.71395) (xy 273.95271 -312.735048)
			(xy 273.993213 -312.763004) (xy 274.028706 -312.797096) (xy 274.058271 -312.83644) (xy 274.081142 -312.880017)
			(xy 274.096726 -312.926698) (xy 274.104621 -312.975275) (xy 274.105116 -312.999882) (xy 274.104621 -313.024489)
			(xy 274.104442 -313.02559) (xy 274.42312 -313.02559) (xy 274.42312 -312.974174) (xy 274.431163 -312.923392)
			(xy 274.447051 -312.874493) (xy 274.470394 -312.828681) (xy 274.500615 -312.787085) (xy 274.536971 -312.750729)
			(xy 274.578567 -312.720508) (xy 274.624379 -312.697165) (xy 274.673278 -312.681277) (xy 274.72406 -312.673234)
			(xy 274.775476 -312.673234) (xy 274.826258 -312.681277) (xy 274.875157 -312.697165) (xy 274.920969 -312.720508)
			(xy 274.962565 -312.750729) (xy 274.998921 -312.787085) (xy 275.029142 -312.828681) (xy 275.052485 -312.874493)
			(xy 275.068373 -312.923392) (xy 275.076416 -312.974174) (xy 275.07692 -312.999882) (xy 275.393924 -312.999882)
			(xy 275.397884 -312.950828) (xy 275.409661 -312.903044) (xy 275.428952 -312.857768) (xy 275.455255 -312.816172)
			(xy 275.48789 -312.779335) (xy 275.526011 -312.74821) (xy 275.568632 -312.723603) (xy 275.614648 -312.706151)
			(xy 275.662867 -312.696307) (xy 275.712042 -312.694326) (xy 275.760897 -312.700258) (xy 275.808168 -312.71395)
			(xy 275.85263 -312.735048) (xy 275.893133 -312.763004) (xy 275.928626 -312.797096) (xy 275.958191 -312.83644)
			(xy 275.981062 -312.880017) (xy 275.996646 -312.926698) (xy 276.004541 -312.975275) (xy 276.005036 -312.999882)
			(xy 276.343884 -312.999882) (xy 276.347844 -312.950828) (xy 276.359621 -312.903044) (xy 276.378912 -312.857768)
			(xy 276.405215 -312.816172) (xy 276.43785 -312.779335) (xy 276.475971 -312.74821) (xy 276.518592 -312.723603)
			(xy 276.564608 -312.706151) (xy 276.612827 -312.696307) (xy 276.662002 -312.694326) (xy 276.710857 -312.700258)
			(xy 276.758128 -312.71395) (xy 276.80259 -312.735048) (xy 276.843093 -312.763004) (xy 276.878586 -312.797096)
			(xy 276.908151 -312.83644) (xy 276.931022 -312.880017) (xy 276.946606 -312.926698) (xy 276.954501 -312.975275)
			(xy 276.954996 -312.999882) (xy 277.294098 -312.999882) (xy 277.298058 -312.950828) (xy 277.309835 -312.903044)
			(xy 277.329126 -312.857768) (xy 277.355429 -312.816172) (xy 277.388064 -312.779335) (xy 277.426185 -312.74821)
			(xy 277.468806 -312.723603) (xy 277.514822 -312.706151) (xy 277.563041 -312.696307) (xy 277.612216 -312.694326)
			(xy 277.661071 -312.700258) (xy 277.708342 -312.71395) (xy 277.752804 -312.735048) (xy 277.793307 -312.763004)
			(xy 277.8288 -312.797096) (xy 277.858365 -312.83644) (xy 277.881236 -312.880017) (xy 277.89682 -312.926698)
			(xy 277.904715 -312.975275) (xy 277.90521 -312.999882) (xy 278.244058 -312.999882) (xy 278.248018 -312.950828)
			(xy 278.259795 -312.903044) (xy 278.279086 -312.857768) (xy 278.305389 -312.816172) (xy 278.338024 -312.779335)
			(xy 278.376145 -312.74821) (xy 278.418766 -312.723603) (xy 278.464782 -312.706151) (xy 278.513001 -312.696307)
			(xy 278.562176 -312.694326) (xy 278.611031 -312.700258) (xy 278.658302 -312.71395) (xy 278.702764 -312.735048)
			(xy 278.743267 -312.763004) (xy 278.77876 -312.797096) (xy 278.808325 -312.83644) (xy 278.831196 -312.880017)
			(xy 278.84678 -312.926698) (xy 278.854675 -312.975275) (xy 278.85517 -312.999882) (xy 279.194018 -312.999882)
			(xy 279.197978 -312.950828) (xy 279.209755 -312.903044) (xy 279.229046 -312.857768) (xy 279.255349 -312.816172)
			(xy 279.287984 -312.779335) (xy 279.326105 -312.74821) (xy 279.368726 -312.723603) (xy 279.414742 -312.706151)
			(xy 279.462961 -312.696307) (xy 279.512136 -312.694326) (xy 279.560991 -312.700258) (xy 279.608262 -312.71395)
			(xy 279.652724 -312.735048) (xy 279.693227 -312.763004) (xy 279.72872 -312.797096) (xy 279.758285 -312.83644)
			(xy 279.781156 -312.880017) (xy 279.79674 -312.926698) (xy 279.804635 -312.975275) (xy 279.80513 -312.999882)
			(xy 280.143978 -312.999882) (xy 280.147938 -312.950828) (xy 280.159715 -312.903044) (xy 280.179006 -312.857768)
			(xy 280.205309 -312.816172) (xy 280.237944 -312.779335) (xy 280.276065 -312.74821) (xy 280.318686 -312.723603)
			(xy 280.364702 -312.706151) (xy 280.412921 -312.696307) (xy 280.462096 -312.694326) (xy 280.510951 -312.700258)
			(xy 280.558222 -312.71395) (xy 280.602684 -312.735048) (xy 280.643187 -312.763004) (xy 280.67868 -312.797096)
			(xy 280.708245 -312.83644) (xy 280.731116 -312.880017) (xy 280.7467 -312.926698) (xy 280.754595 -312.975275)
			(xy 280.75509 -312.999882) (xy 281.093938 -312.999882) (xy 281.097898 -312.950828) (xy 281.109675 -312.903044)
			(xy 281.128966 -312.857768) (xy 281.155269 -312.816172) (xy 281.187904 -312.779335) (xy 281.226025 -312.74821)
			(xy 281.268646 -312.723603) (xy 281.314662 -312.706151) (xy 281.362881 -312.696307) (xy 281.412056 -312.694326)
			(xy 281.460911 -312.700258) (xy 281.508182 -312.71395) (xy 281.552644 -312.735048) (xy 281.593147 -312.763004)
			(xy 281.62864 -312.797096) (xy 281.658205 -312.83644) (xy 281.681076 -312.880017) (xy 281.69666 -312.926698)
			(xy 281.704555 -312.975275) (xy 281.70505 -312.999882) (xy 282.043898 -312.999882) (xy 282.047858 -312.950828)
			(xy 282.059635 -312.903044) (xy 282.078926 -312.857768) (xy 282.105229 -312.816172) (xy 282.137864 -312.779335)
			(xy 282.175985 -312.74821) (xy 282.218606 -312.723603) (xy 282.264622 -312.706151) (xy 282.312841 -312.696307)
			(xy 282.362016 -312.694326) (xy 282.410871 -312.700258) (xy 282.458142 -312.71395) (xy 282.502604 -312.735048)
			(xy 282.543107 -312.763004) (xy 282.5786 -312.797096) (xy 282.608165 -312.83644) (xy 282.631036 -312.880017)
			(xy 282.64662 -312.926698) (xy 282.654515 -312.975275) (xy 282.65501 -312.999882) (xy 282.994112 -312.999882)
			(xy 282.998072 -312.950828) (xy 283.009849 -312.903044) (xy 283.02914 -312.857768) (xy 283.055443 -312.816172)
			(xy 283.088078 -312.779335) (xy 283.126199 -312.74821) (xy 283.16882 -312.723603) (xy 283.214836 -312.706151)
			(xy 283.263055 -312.696307) (xy 283.31223 -312.694326) (xy 283.361085 -312.700258) (xy 283.408356 -312.71395)
			(xy 283.452818 -312.735048) (xy 283.493321 -312.763004) (xy 283.528814 -312.797096) (xy 283.558379 -312.83644)
			(xy 283.58125 -312.880017) (xy 283.596834 -312.926698) (xy 283.604729 -312.975275) (xy 283.605224 -312.999882)
			(xy 283.944072 -312.999882) (xy 283.948032 -312.950828) (xy 283.959809 -312.903044) (xy 283.9791 -312.857768)
			(xy 284.005403 -312.816172) (xy 284.038038 -312.779335) (xy 284.076159 -312.74821) (xy 284.11878 -312.723603)
			(xy 284.164796 -312.706151) (xy 284.213015 -312.696307) (xy 284.26219 -312.694326) (xy 284.311045 -312.700258)
			(xy 284.358316 -312.71395) (xy 284.402778 -312.735048) (xy 284.443281 -312.763004) (xy 284.478774 -312.797096)
			(xy 284.508339 -312.83644) (xy 284.53121 -312.880017) (xy 284.546794 -312.926698) (xy 284.554689 -312.975275)
			(xy 284.555184 -312.999882) (xy 284.894032 -312.999882) (xy 284.897992 -312.950828) (xy 284.909769 -312.903044)
			(xy 284.92906 -312.857768) (xy 284.955363 -312.816172) (xy 284.987998 -312.779335) (xy 285.026119 -312.74821)
			(xy 285.06874 -312.723603) (xy 285.114756 -312.706151) (xy 285.162975 -312.696307) (xy 285.21215 -312.694326)
			(xy 285.261005 -312.700258) (xy 285.308276 -312.71395) (xy 285.352738 -312.735048) (xy 285.393241 -312.763004)
			(xy 285.428734 -312.797096) (xy 285.458299 -312.83644) (xy 285.48117 -312.880017) (xy 285.496754 -312.926698)
			(xy 285.504649 -312.975275) (xy 285.505144 -312.999882) (xy 285.843992 -312.999882) (xy 285.847952 -312.950828)
			(xy 285.859729 -312.903044) (xy 285.87902 -312.857768) (xy 285.905323 -312.816172) (xy 285.937958 -312.779335)
			(xy 285.976079 -312.74821) (xy 286.0187 -312.723603) (xy 286.064716 -312.706151) (xy 286.112935 -312.696307)
			(xy 286.16211 -312.694326) (xy 286.210965 -312.700258) (xy 286.258236 -312.71395) (xy 286.302698 -312.735048)
			(xy 286.343201 -312.763004) (xy 286.378694 -312.797096) (xy 286.408259 -312.83644) (xy 286.43113 -312.880017)
			(xy 286.446714 -312.926698) (xy 286.454609 -312.975275) (xy 286.455104 -312.999882) (xy 286.793952 -312.999882)
			(xy 286.797912 -312.950828) (xy 286.809689 -312.903044) (xy 286.82898 -312.857768) (xy 286.855283 -312.816172)
			(xy 286.887918 -312.779335) (xy 286.926039 -312.74821) (xy 286.96866 -312.723603) (xy 287.014676 -312.706151)
			(xy 287.062895 -312.696307) (xy 287.11207 -312.694326) (xy 287.160925 -312.700258) (xy 287.208196 -312.71395)
			(xy 287.252658 -312.735048) (xy 287.293161 -312.763004) (xy 287.328654 -312.797096) (xy 287.358219 -312.83644)
			(xy 287.38109 -312.880017) (xy 287.396674 -312.926698) (xy 287.404569 -312.975275) (xy 287.405064 -312.999882)
			(xy 287.743912 -312.999882) (xy 287.747872 -312.950828) (xy 287.759649 -312.903044) (xy 287.77894 -312.857768)
			(xy 287.805243 -312.816172) (xy 287.837878 -312.779335) (xy 287.875999 -312.74821) (xy 287.91862 -312.723603)
			(xy 287.964636 -312.706151) (xy 288.012855 -312.696307) (xy 288.06203 -312.694326) (xy 288.110885 -312.700258)
			(xy 288.158156 -312.71395) (xy 288.202618 -312.735048) (xy 288.243121 -312.763004) (xy 288.278614 -312.797096)
			(xy 288.308179 -312.83644) (xy 288.33105 -312.880017) (xy 288.346634 -312.926698) (xy 288.354529 -312.975275)
			(xy 288.355024 -312.999882) (xy 288.694126 -312.999882) (xy 288.698086 -312.950828) (xy 288.709863 -312.903044)
			(xy 288.729154 -312.857768) (xy 288.755457 -312.816172) (xy 288.788092 -312.779335) (xy 288.826213 -312.74821)
			(xy 288.868834 -312.723603) (xy 288.91485 -312.706151) (xy 288.963069 -312.696307) (xy 289.012244 -312.694326)
			(xy 289.061099 -312.700258) (xy 289.10837 -312.71395) (xy 289.152832 -312.735048) (xy 289.193335 -312.763004)
			(xy 289.228828 -312.797096) (xy 289.258393 -312.83644) (xy 289.281264 -312.880017) (xy 289.296848 -312.926698)
			(xy 289.304743 -312.975275) (xy 289.305238 -312.999882) (xy 289.644086 -312.999882) (xy 289.648046 -312.950828)
			(xy 289.659823 -312.903044) (xy 289.679114 -312.857768) (xy 289.705417 -312.816172) (xy 289.738052 -312.779335)
			(xy 289.776173 -312.74821) (xy 289.818794 -312.723603) (xy 289.86481 -312.706151) (xy 289.913029 -312.696307)
			(xy 289.962204 -312.694326) (xy 290.011059 -312.700258) (xy 290.05833 -312.71395) (xy 290.102792 -312.735048)
			(xy 290.143295 -312.763004) (xy 290.178788 -312.797096) (xy 290.208353 -312.83644) (xy 290.231224 -312.880017)
			(xy 290.246808 -312.926698) (xy 290.254703 -312.975275) (xy 290.255198 -312.999882) (xy 290.594046 -312.999882)
			(xy 290.598006 -312.950828) (xy 290.609783 -312.903044) (xy 290.629074 -312.857768) (xy 290.655377 -312.816172)
			(xy 290.688012 -312.779335) (xy 290.726133 -312.74821) (xy 290.768754 -312.723603) (xy 290.81477 -312.706151)
			(xy 290.862989 -312.696307) (xy 290.912164 -312.694326) (xy 290.961019 -312.700258) (xy 291.00829 -312.71395)
			(xy 291.052752 -312.735048) (xy 291.093255 -312.763004) (xy 291.128748 -312.797096) (xy 291.158313 -312.83644)
			(xy 291.181184 -312.880017) (xy 291.196768 -312.926698) (xy 291.204663 -312.975275) (xy 291.205158 -312.999882)
			(xy 291.204663 -313.024489) (xy 291.204484 -313.02559) (xy 291.523162 -313.02559) (xy 291.523162 -312.974174)
			(xy 291.531205 -312.923392) (xy 291.547093 -312.874493) (xy 291.570436 -312.828681) (xy 291.600657 -312.787085)
			(xy 291.637013 -312.750729) (xy 291.678609 -312.720508) (xy 291.724421 -312.697165) (xy 291.77332 -312.681277)
			(xy 291.824102 -312.673234) (xy 291.875518 -312.673234) (xy 291.9263 -312.681277) (xy 291.975199 -312.697165)
			(xy 292.021011 -312.720508) (xy 292.062607 -312.750729) (xy 292.098963 -312.787085) (xy 292.129184 -312.828681)
			(xy 292.152527 -312.874493) (xy 292.168415 -312.923392) (xy 292.176458 -312.974174) (xy 292.176962 -312.999882)
			(xy 292.493966 -312.999882) (xy 292.497926 -312.950828) (xy 292.509703 -312.903044) (xy 292.528994 -312.857768)
			(xy 292.555297 -312.816172) (xy 292.587932 -312.779335) (xy 292.626053 -312.74821) (xy 292.668674 -312.723603)
			(xy 292.71469 -312.706151) (xy 292.762909 -312.696307) (xy 292.812084 -312.694326) (xy 292.860939 -312.700258)
			(xy 292.90821 -312.71395) (xy 292.952672 -312.735048) (xy 292.993175 -312.763004) (xy 293.028668 -312.797096)
			(xy 293.058233 -312.83644) (xy 293.081104 -312.880017) (xy 293.096688 -312.926698) (xy 293.104583 -312.975275)
			(xy 293.105078 -312.999882) (xy 293.104583 -313.024489) (xy 293.104404 -313.02559) (xy 293.423082 -313.02559)
			(xy 293.423082 -312.974174) (xy 293.431125 -312.923392) (xy 293.447013 -312.874493) (xy 293.470356 -312.828681)
			(xy 293.500577 -312.787085) (xy 293.536933 -312.750729) (xy 293.578529 -312.720508) (xy 293.624341 -312.697165)
			(xy 293.67324 -312.681277) (xy 293.724022 -312.673234) (xy 293.775438 -312.673234) (xy 293.82622 -312.681277)
			(xy 293.875119 -312.697165) (xy 293.920931 -312.720508) (xy 293.962527 -312.750729) (xy 293.998883 -312.787085)
			(xy 294.029104 -312.828681) (xy 294.052447 -312.874493) (xy 294.068335 -312.923392) (xy 294.076378 -312.974174)
			(xy 294.076882 -312.999882) (xy 294.393886 -312.999882) (xy 294.397846 -312.950828) (xy 294.409623 -312.903044)
			(xy 294.428914 -312.857768) (xy 294.455217 -312.816172) (xy 294.487852 -312.779335) (xy 294.525973 -312.74821)
			(xy 294.568594 -312.723603) (xy 294.61461 -312.706151) (xy 294.662829 -312.696307) (xy 294.712004 -312.694326)
			(xy 294.760859 -312.700258) (xy 294.80813 -312.71395) (xy 294.852592 -312.735048) (xy 294.893095 -312.763004)
			(xy 294.928588 -312.797096) (xy 294.958153 -312.83644) (xy 294.981024 -312.880017) (xy 294.996608 -312.926698)
			(xy 295.004503 -312.975275) (xy 295.004998 -312.999882) (xy 295.004503 -313.024489) (xy 295.004324 -313.02559)
			(xy 295.323256 -313.02559) (xy 295.323256 -312.974174) (xy 295.331299 -312.923392) (xy 295.347187 -312.874493)
			(xy 295.37053 -312.828681) (xy 295.400751 -312.787085) (xy 295.437107 -312.750729) (xy 295.478703 -312.720508)
			(xy 295.524515 -312.697165) (xy 295.573414 -312.681277) (xy 295.624196 -312.673234) (xy 295.675612 -312.673234)
			(xy 295.726394 -312.681277) (xy 295.775293 -312.697165) (xy 295.821105 -312.720508) (xy 295.862701 -312.750729)
			(xy 295.899057 -312.787085) (xy 295.929278 -312.828681) (xy 295.952621 -312.874493) (xy 295.968509 -312.923392)
			(xy 295.976552 -312.974174) (xy 295.977056 -312.999882) (xy 296.29406 -312.999882) (xy 296.29802 -312.950828)
			(xy 296.309797 -312.903044) (xy 296.329088 -312.857768) (xy 296.355391 -312.816172) (xy 296.388026 -312.779335)
			(xy 296.426147 -312.74821) (xy 296.468768 -312.723603) (xy 296.514784 -312.706151) (xy 296.563003 -312.696307)
			(xy 296.612178 -312.694326) (xy 296.661033 -312.700258) (xy 296.708304 -312.71395) (xy 296.752766 -312.735048)
			(xy 296.793269 -312.763004) (xy 296.828762 -312.797096) (xy 296.858327 -312.83644) (xy 296.881198 -312.880017)
			(xy 296.896782 -312.926698) (xy 296.904677 -312.975275) (xy 296.905172 -312.999882) (xy 296.904677 -313.024489)
			(xy 296.904498 -313.02559) (xy 297.223176 -313.02559) (xy 297.223176 -312.974174) (xy 297.231219 -312.923392)
			(xy 297.247107 -312.874493) (xy 297.27045 -312.828681) (xy 297.300671 -312.787085) (xy 297.337027 -312.750729)
			(xy 297.378623 -312.720508) (xy 297.424435 -312.697165) (xy 297.473334 -312.681277) (xy 297.524116 -312.673234)
			(xy 297.575532 -312.673234) (xy 297.626314 -312.681277) (xy 297.675213 -312.697165) (xy 297.721025 -312.720508)
			(xy 297.762621 -312.750729) (xy 297.798977 -312.787085) (xy 297.829198 -312.828681) (xy 297.852541 -312.874493)
			(xy 297.868429 -312.923392) (xy 297.876472 -312.974174) (xy 297.876976 -312.999882) (xy 298.19398 -312.999882)
			(xy 298.19794 -312.950828) (xy 298.209717 -312.903044) (xy 298.229008 -312.857768) (xy 298.255311 -312.816172)
			(xy 298.287946 -312.779335) (xy 298.326067 -312.74821) (xy 298.368688 -312.723603) (xy 298.414704 -312.706151)
			(xy 298.462923 -312.696307) (xy 298.512098 -312.694326) (xy 298.560953 -312.700258) (xy 298.608224 -312.71395)
			(xy 298.652686 -312.735048) (xy 298.693189 -312.763004) (xy 298.728682 -312.797096) (xy 298.758247 -312.83644)
			(xy 298.781118 -312.880017) (xy 298.796702 -312.926698) (xy 298.804597 -312.975275) (xy 298.805092 -312.999882)
			(xy 298.804597 -313.024489) (xy 298.804418 -313.02559) (xy 299.123096 -313.02559) (xy 299.123096 -312.974174)
			(xy 299.131139 -312.923392) (xy 299.147027 -312.874493) (xy 299.17037 -312.828681) (xy 299.200591 -312.787085)
			(xy 299.236947 -312.750729) (xy 299.278543 -312.720508) (xy 299.324355 -312.697165) (xy 299.373254 -312.681277)
			(xy 299.424036 -312.673234) (xy 299.475452 -312.673234) (xy 299.526234 -312.681277) (xy 299.575133 -312.697165)
			(xy 299.620945 -312.720508) (xy 299.662541 -312.750729) (xy 299.698897 -312.787085) (xy 299.729118 -312.828681)
			(xy 299.752461 -312.874493) (xy 299.768349 -312.923392) (xy 299.776392 -312.974174) (xy 299.776896 -312.999882)
			(xy 300.0939 -312.999882) (xy 300.09786 -312.950828) (xy 300.109637 -312.903044) (xy 300.128928 -312.857768)
			(xy 300.155231 -312.816172) (xy 300.187866 -312.779335) (xy 300.225987 -312.74821) (xy 300.268608 -312.723603)
			(xy 300.314624 -312.706151) (xy 300.362843 -312.696307) (xy 300.412018 -312.694326) (xy 300.460873 -312.700258)
			(xy 300.508144 -312.71395) (xy 300.552606 -312.735048) (xy 300.593109 -312.763004) (xy 300.628602 -312.797096)
			(xy 300.658167 -312.83644) (xy 300.681038 -312.880017) (xy 300.696622 -312.926698) (xy 300.704517 -312.975275)
			(xy 300.705012 -312.999882) (xy 300.704517 -313.024489) (xy 300.704338 -313.02559) (xy 301.02327 -313.02559)
			(xy 301.02327 -312.974174) (xy 301.031313 -312.923392) (xy 301.047201 -312.874493) (xy 301.070544 -312.828681)
			(xy 301.100765 -312.787085) (xy 301.137121 -312.750729) (xy 301.178717 -312.720508) (xy 301.224529 -312.697165)
			(xy 301.273428 -312.681277) (xy 301.32421 -312.673234) (xy 301.375626 -312.673234) (xy 301.426408 -312.681277)
			(xy 301.475307 -312.697165) (xy 301.521119 -312.720508) (xy 301.562715 -312.750729) (xy 301.599071 -312.787085)
			(xy 301.629292 -312.828681) (xy 301.652635 -312.874493) (xy 301.668523 -312.923392) (xy 301.676566 -312.974174)
			(xy 301.67707 -312.999882) (xy 301.994074 -312.999882) (xy 301.998034 -312.950828) (xy 302.009811 -312.903044)
			(xy 302.029102 -312.857768) (xy 302.055405 -312.816172) (xy 302.08804 -312.779335) (xy 302.126161 -312.74821)
			(xy 302.168782 -312.723603) (xy 302.214798 -312.706151) (xy 302.263017 -312.696307) (xy 302.312192 -312.694326)
			(xy 302.361047 -312.700258) (xy 302.408318 -312.71395) (xy 302.45278 -312.735048) (xy 302.493283 -312.763004)
			(xy 302.528776 -312.797096) (xy 302.558341 -312.83644) (xy 302.581212 -312.880017) (xy 302.596796 -312.926698)
			(xy 302.604691 -312.975275) (xy 302.605186 -312.999882) (xy 302.604691 -313.024489) (xy 302.604512 -313.02559)
			(xy 302.92319 -313.02559) (xy 302.92319 -312.974174) (xy 302.931233 -312.923392) (xy 302.947121 -312.874493)
			(xy 302.970464 -312.828681) (xy 303.000685 -312.787085) (xy 303.037041 -312.750729) (xy 303.078637 -312.720508)
			(xy 303.124449 -312.697165) (xy 303.173348 -312.681277) (xy 303.22413 -312.673234) (xy 303.275546 -312.673234)
			(xy 303.326328 -312.681277) (xy 303.375227 -312.697165) (xy 303.421039 -312.720508) (xy 303.462635 -312.750729)
			(xy 303.498991 -312.787085) (xy 303.529212 -312.828681) (xy 303.552555 -312.874493) (xy 303.568443 -312.923392)
			(xy 303.576486 -312.974174) (xy 303.57699 -312.999882) (xy 303.576486 -313.02559) (xy 303.568443 -313.076372)
			(xy 303.552555 -313.125271) (xy 303.529212 -313.171083) (xy 303.498991 -313.212679) (xy 303.462635 -313.249035)
			(xy 303.421039 -313.279256) (xy 303.375227 -313.302599) (xy 303.326328 -313.318487) (xy 303.275546 -313.32653)
			(xy 303.22413 -313.32653) (xy 303.173348 -313.318487) (xy 303.124449 -313.302599) (xy 303.078637 -313.279256)
			(xy 303.037041 -313.249035) (xy 303.000685 -313.212679) (xy 302.970464 -313.171083) (xy 302.947121 -313.125271)
			(xy 302.931233 -313.076372) (xy 302.92319 -313.02559) (xy 302.604512 -313.02559) (xy 302.596796 -313.073066)
			(xy 302.581212 -313.119747) (xy 302.558341 -313.163324) (xy 302.528776 -313.202668) (xy 302.493283 -313.23676)
			(xy 302.45278 -313.264716) (xy 302.408318 -313.285814) (xy 302.361047 -313.299506) (xy 302.312192 -313.305438)
			(xy 302.263017 -313.303457) (xy 302.214798 -313.293613) (xy 302.168782 -313.276161) (xy 302.126161 -313.251554)
			(xy 302.08804 -313.220429) (xy 302.055405 -313.183592) (xy 302.029102 -313.141996) (xy 302.009811 -313.09672)
			(xy 301.998034 -313.048936) (xy 301.994074 -312.999882) (xy 301.67707 -312.999882) (xy 301.676566 -313.02559)
			(xy 301.668523 -313.076372) (xy 301.652635 -313.125271) (xy 301.629292 -313.171083) (xy 301.599071 -313.212679)
			(xy 301.562715 -313.249035) (xy 301.521119 -313.279256) (xy 301.475307 -313.302599) (xy 301.426408 -313.318487)
			(xy 301.375626 -313.32653) (xy 301.32421 -313.32653) (xy 301.273428 -313.318487) (xy 301.224529 -313.302599)
			(xy 301.178717 -313.279256) (xy 301.137121 -313.249035) (xy 301.100765 -313.212679) (xy 301.070544 -313.171083)
			(xy 301.047201 -313.125271) (xy 301.031313 -313.076372) (xy 301.02327 -313.02559) (xy 300.704338 -313.02559)
			(xy 300.696622 -313.073066) (xy 300.681038 -313.119747) (xy 300.658167 -313.163324) (xy 300.628602 -313.202668)
			(xy 300.593109 -313.23676) (xy 300.552606 -313.264716) (xy 300.508144 -313.285814) (xy 300.460873 -313.299506)
			(xy 300.412018 -313.305438) (xy 300.362843 -313.303457) (xy 300.314624 -313.293613) (xy 300.268608 -313.276161)
			(xy 300.225987 -313.251554) (xy 300.187866 -313.220429) (xy 300.155231 -313.183592) (xy 300.128928 -313.141996)
			(xy 300.109637 -313.09672) (xy 300.09786 -313.048936) (xy 300.0939 -312.999882) (xy 299.776896 -312.999882)
			(xy 299.776392 -313.02559) (xy 299.768349 -313.076372) (xy 299.752461 -313.125271) (xy 299.729118 -313.171083)
			(xy 299.698897 -313.212679) (xy 299.662541 -313.249035) (xy 299.620945 -313.279256) (xy 299.575133 -313.302599)
			(xy 299.526234 -313.318487) (xy 299.475452 -313.32653) (xy 299.424036 -313.32653) (xy 299.373254 -313.318487)
			(xy 299.324355 -313.302599) (xy 299.278543 -313.279256) (xy 299.236947 -313.249035) (xy 299.200591 -313.212679)
			(xy 299.17037 -313.171083) (xy 299.147027 -313.125271) (xy 299.131139 -313.076372) (xy 299.123096 -313.02559)
			(xy 298.804418 -313.02559) (xy 298.796702 -313.073066) (xy 298.781118 -313.119747) (xy 298.758247 -313.163324)
			(xy 298.728682 -313.202668) (xy 298.693189 -313.23676) (xy 298.652686 -313.264716) (xy 298.608224 -313.285814)
			(xy 298.560953 -313.299506) (xy 298.512098 -313.305438) (xy 298.462923 -313.303457) (xy 298.414704 -313.293613)
			(xy 298.368688 -313.276161) (xy 298.326067 -313.251554) (xy 298.287946 -313.220429) (xy 298.255311 -313.183592)
			(xy 298.229008 -313.141996) (xy 298.209717 -313.09672) (xy 298.19794 -313.048936) (xy 298.19398 -312.999882)
			(xy 297.876976 -312.999882) (xy 297.876472 -313.02559) (xy 297.868429 -313.076372) (xy 297.852541 -313.125271)
			(xy 297.829198 -313.171083) (xy 297.798977 -313.212679) (xy 297.762621 -313.249035) (xy 297.721025 -313.279256)
			(xy 297.675213 -313.302599) (xy 297.626314 -313.318487) (xy 297.575532 -313.32653) (xy 297.524116 -313.32653)
			(xy 297.473334 -313.318487) (xy 297.424435 -313.302599) (xy 297.378623 -313.279256) (xy 297.337027 -313.249035)
			(xy 297.300671 -313.212679) (xy 297.27045 -313.171083) (xy 297.247107 -313.125271) (xy 297.231219 -313.076372)
			(xy 297.223176 -313.02559) (xy 296.904498 -313.02559) (xy 296.896782 -313.073066) (xy 296.881198 -313.119747)
			(xy 296.858327 -313.163324) (xy 296.828762 -313.202668) (xy 296.793269 -313.23676) (xy 296.752766 -313.264716)
			(xy 296.708304 -313.285814) (xy 296.661033 -313.299506) (xy 296.612178 -313.305438) (xy 296.563003 -313.303457)
			(xy 296.514784 -313.293613) (xy 296.468768 -313.276161) (xy 296.426147 -313.251554) (xy 296.388026 -313.220429)
			(xy 296.355391 -313.183592) (xy 296.329088 -313.141996) (xy 296.309797 -313.09672) (xy 296.29802 -313.048936)
			(xy 296.29406 -312.999882) (xy 295.977056 -312.999882) (xy 295.976552 -313.02559) (xy 295.968509 -313.076372)
			(xy 295.952621 -313.125271) (xy 295.929278 -313.171083) (xy 295.899057 -313.212679) (xy 295.862701 -313.249035)
			(xy 295.821105 -313.279256) (xy 295.775293 -313.302599) (xy 295.726394 -313.318487) (xy 295.675612 -313.32653)
			(xy 295.624196 -313.32653) (xy 295.573414 -313.318487) (xy 295.524515 -313.302599) (xy 295.478703 -313.279256)
			(xy 295.437107 -313.249035) (xy 295.400751 -313.212679) (xy 295.37053 -313.171083) (xy 295.347187 -313.125271)
			(xy 295.331299 -313.076372) (xy 295.323256 -313.02559) (xy 295.004324 -313.02559) (xy 294.996608 -313.073066)
			(xy 294.981024 -313.119747) (xy 294.958153 -313.163324) (xy 294.928588 -313.202668) (xy 294.893095 -313.23676)
			(xy 294.852592 -313.264716) (xy 294.80813 -313.285814) (xy 294.760859 -313.299506) (xy 294.712004 -313.305438)
			(xy 294.662829 -313.303457) (xy 294.61461 -313.293613) (xy 294.568594 -313.276161) (xy 294.525973 -313.251554)
			(xy 294.487852 -313.220429) (xy 294.455217 -313.183592) (xy 294.428914 -313.141996) (xy 294.409623 -313.09672)
			(xy 294.397846 -313.048936) (xy 294.393886 -312.999882) (xy 294.076882 -312.999882) (xy 294.076378 -313.02559)
			(xy 294.068335 -313.076372) (xy 294.052447 -313.125271) (xy 294.029104 -313.171083) (xy 293.998883 -313.212679)
			(xy 293.962527 -313.249035) (xy 293.920931 -313.279256) (xy 293.875119 -313.302599) (xy 293.82622 -313.318487)
			(xy 293.775438 -313.32653) (xy 293.724022 -313.32653) (xy 293.67324 -313.318487) (xy 293.624341 -313.302599)
			(xy 293.578529 -313.279256) (xy 293.536933 -313.249035) (xy 293.500577 -313.212679) (xy 293.470356 -313.171083)
			(xy 293.447013 -313.125271) (xy 293.431125 -313.076372) (xy 293.423082 -313.02559) (xy 293.104404 -313.02559)
			(xy 293.096688 -313.073066) (xy 293.081104 -313.119747) (xy 293.058233 -313.163324) (xy 293.028668 -313.202668)
			(xy 292.993175 -313.23676) (xy 292.952672 -313.264716) (xy 292.90821 -313.285814) (xy 292.860939 -313.299506)
			(xy 292.812084 -313.305438) (xy 292.762909 -313.303457) (xy 292.71469 -313.293613) (xy 292.668674 -313.276161)
			(xy 292.626053 -313.251554) (xy 292.587932 -313.220429) (xy 292.555297 -313.183592) (xy 292.528994 -313.141996)
			(xy 292.509703 -313.09672) (xy 292.497926 -313.048936) (xy 292.493966 -312.999882) (xy 292.176962 -312.999882)
			(xy 292.176458 -313.02559) (xy 292.168415 -313.076372) (xy 292.152527 -313.125271) (xy 292.129184 -313.171083)
			(xy 292.098963 -313.212679) (xy 292.062607 -313.249035) (xy 292.021011 -313.279256) (xy 291.975199 -313.302599)
			(xy 291.9263 -313.318487) (xy 291.875518 -313.32653) (xy 291.824102 -313.32653) (xy 291.77332 -313.318487)
			(xy 291.724421 -313.302599) (xy 291.678609 -313.279256) (xy 291.637013 -313.249035) (xy 291.600657 -313.212679)
			(xy 291.570436 -313.171083) (xy 291.547093 -313.125271) (xy 291.531205 -313.076372) (xy 291.523162 -313.02559)
			(xy 291.204484 -313.02559) (xy 291.196768 -313.073066) (xy 291.181184 -313.119747) (xy 291.158313 -313.163324)
			(xy 291.128748 -313.202668) (xy 291.093255 -313.23676) (xy 291.052752 -313.264716) (xy 291.00829 -313.285814)
			(xy 290.961019 -313.299506) (xy 290.912164 -313.305438) (xy 290.862989 -313.303457) (xy 290.81477 -313.293613)
			(xy 290.768754 -313.276161) (xy 290.726133 -313.251554) (xy 290.688012 -313.220429) (xy 290.655377 -313.183592)
			(xy 290.629074 -313.141996) (xy 290.609783 -313.09672) (xy 290.598006 -313.048936) (xy 290.594046 -312.999882)
			(xy 290.255198 -312.999882) (xy 290.254703 -313.024489) (xy 290.246808 -313.073066) (xy 290.231224 -313.119747)
			(xy 290.208353 -313.163324) (xy 290.178788 -313.202668) (xy 290.143295 -313.23676) (xy 290.102792 -313.264716)
			(xy 290.05833 -313.285814) (xy 290.011059 -313.299506) (xy 289.962204 -313.305438) (xy 289.913029 -313.303457)
			(xy 289.86481 -313.293613) (xy 289.818794 -313.276161) (xy 289.776173 -313.251554) (xy 289.738052 -313.220429)
			(xy 289.705417 -313.183592) (xy 289.679114 -313.141996) (xy 289.659823 -313.09672) (xy 289.648046 -313.048936)
			(xy 289.644086 -312.999882) (xy 289.305238 -312.999882) (xy 289.304743 -313.024489) (xy 289.296848 -313.073066)
			(xy 289.281264 -313.119747) (xy 289.258393 -313.163324) (xy 289.228828 -313.202668) (xy 289.193335 -313.23676)
			(xy 289.152832 -313.264716) (xy 289.10837 -313.285814) (xy 289.061099 -313.299506) (xy 289.012244 -313.305438)
			(xy 288.963069 -313.303457) (xy 288.91485 -313.293613) (xy 288.868834 -313.276161) (xy 288.826213 -313.251554)
			(xy 288.788092 -313.220429) (xy 288.755457 -313.183592) (xy 288.729154 -313.141996) (xy 288.709863 -313.09672)
			(xy 288.698086 -313.048936) (xy 288.694126 -312.999882) (xy 288.355024 -312.999882) (xy 288.354529 -313.024489)
			(xy 288.346634 -313.073066) (xy 288.33105 -313.119747) (xy 288.308179 -313.163324) (xy 288.278614 -313.202668)
			(xy 288.243121 -313.23676) (xy 288.202618 -313.264716) (xy 288.158156 -313.285814) (xy 288.110885 -313.299506)
			(xy 288.06203 -313.305438) (xy 288.012855 -313.303457) (xy 287.964636 -313.293613) (xy 287.91862 -313.276161)
			(xy 287.875999 -313.251554) (xy 287.837878 -313.220429) (xy 287.805243 -313.183592) (xy 287.77894 -313.141996)
			(xy 287.759649 -313.09672) (xy 287.747872 -313.048936) (xy 287.743912 -312.999882) (xy 287.405064 -312.999882)
			(xy 287.404569 -313.024489) (xy 287.396674 -313.073066) (xy 287.38109 -313.119747) (xy 287.358219 -313.163324)
			(xy 287.328654 -313.202668) (xy 287.293161 -313.23676) (xy 287.252658 -313.264716) (xy 287.208196 -313.285814)
			(xy 287.160925 -313.299506) (xy 287.11207 -313.305438) (xy 287.062895 -313.303457) (xy 287.014676 -313.293613)
			(xy 286.96866 -313.276161) (xy 286.926039 -313.251554) (xy 286.887918 -313.220429) (xy 286.855283 -313.183592)
			(xy 286.82898 -313.141996) (xy 286.809689 -313.09672) (xy 286.797912 -313.048936) (xy 286.793952 -312.999882)
			(xy 286.455104 -312.999882) (xy 286.454609 -313.024489) (xy 286.446714 -313.073066) (xy 286.43113 -313.119747)
			(xy 286.408259 -313.163324) (xy 286.378694 -313.202668) (xy 286.343201 -313.23676) (xy 286.302698 -313.264716)
			(xy 286.258236 -313.285814) (xy 286.210965 -313.299506) (xy 286.16211 -313.305438) (xy 286.112935 -313.303457)
			(xy 286.064716 -313.293613) (xy 286.0187 -313.276161) (xy 285.976079 -313.251554) (xy 285.937958 -313.220429)
			(xy 285.905323 -313.183592) (xy 285.87902 -313.141996) (xy 285.859729 -313.09672) (xy 285.847952 -313.048936)
			(xy 285.843992 -312.999882) (xy 285.505144 -312.999882) (xy 285.504649 -313.024489) (xy 285.496754 -313.073066)
			(xy 285.48117 -313.119747) (xy 285.458299 -313.163324) (xy 285.428734 -313.202668) (xy 285.393241 -313.23676)
			(xy 285.352738 -313.264716) (xy 285.308276 -313.285814) (xy 285.261005 -313.299506) (xy 285.21215 -313.305438)
			(xy 285.162975 -313.303457) (xy 285.114756 -313.293613) (xy 285.06874 -313.276161) (xy 285.026119 -313.251554)
			(xy 284.987998 -313.220429) (xy 284.955363 -313.183592) (xy 284.92906 -313.141996) (xy 284.909769 -313.09672)
			(xy 284.897992 -313.048936) (xy 284.894032 -312.999882) (xy 284.555184 -312.999882) (xy 284.554689 -313.024489)
			(xy 284.546794 -313.073066) (xy 284.53121 -313.119747) (xy 284.508339 -313.163324) (xy 284.478774 -313.202668)
			(xy 284.443281 -313.23676) (xy 284.402778 -313.264716) (xy 284.358316 -313.285814) (xy 284.311045 -313.299506)
			(xy 284.26219 -313.305438) (xy 284.213015 -313.303457) (xy 284.164796 -313.293613) (xy 284.11878 -313.276161)
			(xy 284.076159 -313.251554) (xy 284.038038 -313.220429) (xy 284.005403 -313.183592) (xy 283.9791 -313.141996)
			(xy 283.959809 -313.09672) (xy 283.948032 -313.048936) (xy 283.944072 -312.999882) (xy 283.605224 -312.999882)
			(xy 283.604729 -313.024489) (xy 283.596834 -313.073066) (xy 283.58125 -313.119747) (xy 283.558379 -313.163324)
			(xy 283.528814 -313.202668) (xy 283.493321 -313.23676) (xy 283.452818 -313.264716) (xy 283.408356 -313.285814)
			(xy 283.361085 -313.299506) (xy 283.31223 -313.305438) (xy 283.263055 -313.303457) (xy 283.214836 -313.293613)
			(xy 283.16882 -313.276161) (xy 283.126199 -313.251554) (xy 283.088078 -313.220429) (xy 283.055443 -313.183592)
			(xy 283.02914 -313.141996) (xy 283.009849 -313.09672) (xy 282.998072 -313.048936) (xy 282.994112 -312.999882)
			(xy 282.65501 -312.999882) (xy 282.654515 -313.024489) (xy 282.64662 -313.073066) (xy 282.631036 -313.119747)
			(xy 282.608165 -313.163324) (xy 282.5786 -313.202668) (xy 282.543107 -313.23676) (xy 282.502604 -313.264716)
			(xy 282.458142 -313.285814) (xy 282.410871 -313.299506) (xy 282.362016 -313.305438) (xy 282.312841 -313.303457)
			(xy 282.264622 -313.293613) (xy 282.218606 -313.276161) (xy 282.175985 -313.251554) (xy 282.137864 -313.220429)
			(xy 282.105229 -313.183592) (xy 282.078926 -313.141996) (xy 282.059635 -313.09672) (xy 282.047858 -313.048936)
			(xy 282.043898 -312.999882) (xy 281.70505 -312.999882) (xy 281.704555 -313.024489) (xy 281.69666 -313.073066)
			(xy 281.681076 -313.119747) (xy 281.658205 -313.163324) (xy 281.62864 -313.202668) (xy 281.593147 -313.23676)
			(xy 281.552644 -313.264716) (xy 281.508182 -313.285814) (xy 281.460911 -313.299506) (xy 281.412056 -313.305438)
			(xy 281.362881 -313.303457) (xy 281.314662 -313.293613) (xy 281.268646 -313.276161) (xy 281.226025 -313.251554)
			(xy 281.187904 -313.220429) (xy 281.155269 -313.183592) (xy 281.128966 -313.141996) (xy 281.109675 -313.09672)
			(xy 281.097898 -313.048936) (xy 281.093938 -312.999882) (xy 280.75509 -312.999882) (xy 280.754595 -313.024489)
			(xy 280.7467 -313.073066) (xy 280.731116 -313.119747) (xy 280.708245 -313.163324) (xy 280.67868 -313.202668)
			(xy 280.643187 -313.23676) (xy 280.602684 -313.264716) (xy 280.558222 -313.285814) (xy 280.510951 -313.299506)
			(xy 280.462096 -313.305438) (xy 280.412921 -313.303457) (xy 280.364702 -313.293613) (xy 280.318686 -313.276161)
			(xy 280.276065 -313.251554) (xy 280.237944 -313.220429) (xy 280.205309 -313.183592) (xy 280.179006 -313.141996)
			(xy 280.159715 -313.09672) (xy 280.147938 -313.048936) (xy 280.143978 -312.999882) (xy 279.80513 -312.999882)
			(xy 279.804635 -313.024489) (xy 279.79674 -313.073066) (xy 279.781156 -313.119747) (xy 279.758285 -313.163324)
			(xy 279.72872 -313.202668) (xy 279.693227 -313.23676) (xy 279.652724 -313.264716) (xy 279.608262 -313.285814)
			(xy 279.560991 -313.299506) (xy 279.512136 -313.305438) (xy 279.462961 -313.303457) (xy 279.414742 -313.293613)
			(xy 279.368726 -313.276161) (xy 279.326105 -313.251554) (xy 279.287984 -313.220429) (xy 279.255349 -313.183592)
			(xy 279.229046 -313.141996) (xy 279.209755 -313.09672) (xy 279.197978 -313.048936) (xy 279.194018 -312.999882)
			(xy 278.85517 -312.999882) (xy 278.854675 -313.024489) (xy 278.84678 -313.073066) (xy 278.831196 -313.119747)
			(xy 278.808325 -313.163324) (xy 278.77876 -313.202668) (xy 278.743267 -313.23676) (xy 278.702764 -313.264716)
			(xy 278.658302 -313.285814) (xy 278.611031 -313.299506) (xy 278.562176 -313.305438) (xy 278.513001 -313.303457)
			(xy 278.464782 -313.293613) (xy 278.418766 -313.276161) (xy 278.376145 -313.251554) (xy 278.338024 -313.220429)
			(xy 278.305389 -313.183592) (xy 278.279086 -313.141996) (xy 278.259795 -313.09672) (xy 278.248018 -313.048936)
			(xy 278.244058 -312.999882) (xy 277.90521 -312.999882) (xy 277.904715 -313.024489) (xy 277.89682 -313.073066)
			(xy 277.881236 -313.119747) (xy 277.858365 -313.163324) (xy 277.8288 -313.202668) (xy 277.793307 -313.23676)
			(xy 277.752804 -313.264716) (xy 277.708342 -313.285814) (xy 277.661071 -313.299506) (xy 277.612216 -313.305438)
			(xy 277.563041 -313.303457) (xy 277.514822 -313.293613) (xy 277.468806 -313.276161) (xy 277.426185 -313.251554)
			(xy 277.388064 -313.220429) (xy 277.355429 -313.183592) (xy 277.329126 -313.141996) (xy 277.309835 -313.09672)
			(xy 277.298058 -313.048936) (xy 277.294098 -312.999882) (xy 276.954996 -312.999882) (xy 276.954501 -313.024489)
			(xy 276.946606 -313.073066) (xy 276.931022 -313.119747) (xy 276.908151 -313.163324) (xy 276.878586 -313.202668)
			(xy 276.843093 -313.23676) (xy 276.80259 -313.264716) (xy 276.758128 -313.285814) (xy 276.710857 -313.299506)
			(xy 276.662002 -313.305438) (xy 276.612827 -313.303457) (xy 276.564608 -313.293613) (xy 276.518592 -313.276161)
			(xy 276.475971 -313.251554) (xy 276.43785 -313.220429) (xy 276.405215 -313.183592) (xy 276.378912 -313.141996)
			(xy 276.359621 -313.09672) (xy 276.347844 -313.048936) (xy 276.343884 -312.999882) (xy 276.005036 -312.999882)
			(xy 276.004541 -313.024489) (xy 275.996646 -313.073066) (xy 275.981062 -313.119747) (xy 275.958191 -313.163324)
			(xy 275.928626 -313.202668) (xy 275.893133 -313.23676) (xy 275.85263 -313.264716) (xy 275.808168 -313.285814)
			(xy 275.760897 -313.299506) (xy 275.712042 -313.305438) (xy 275.662867 -313.303457) (xy 275.614648 -313.293613)
			(xy 275.568632 -313.276161) (xy 275.526011 -313.251554) (xy 275.48789 -313.220429) (xy 275.455255 -313.183592)
			(xy 275.428952 -313.141996) (xy 275.409661 -313.09672) (xy 275.397884 -313.048936) (xy 275.393924 -312.999882)
			(xy 275.07692 -312.999882) (xy 275.076416 -313.02559) (xy 275.068373 -313.076372) (xy 275.052485 -313.125271)
			(xy 275.029142 -313.171083) (xy 274.998921 -313.212679) (xy 274.962565 -313.249035) (xy 274.920969 -313.279256)
			(xy 274.875157 -313.302599) (xy 274.826258 -313.318487) (xy 274.775476 -313.32653) (xy 274.72406 -313.32653)
			(xy 274.673278 -313.318487) (xy 274.624379 -313.302599) (xy 274.578567 -313.279256) (xy 274.536971 -313.249035)
			(xy 274.500615 -313.212679) (xy 274.470394 -313.171083) (xy 274.447051 -313.125271) (xy 274.431163 -313.076372)
			(xy 274.42312 -313.02559) (xy 274.104442 -313.02559) (xy 274.096726 -313.073066) (xy 274.081142 -313.119747)
			(xy 274.058271 -313.163324) (xy 274.028706 -313.202668) (xy 273.993213 -313.23676) (xy 273.95271 -313.264716)
			(xy 273.908248 -313.285814) (xy 273.860977 -313.299506) (xy 273.812122 -313.305438) (xy 273.762947 -313.303457)
			(xy 273.714728 -313.293613) (xy 273.668712 -313.276161) (xy 273.626091 -313.251554) (xy 273.58797 -313.220429)
			(xy 273.555335 -313.183592) (xy 273.529032 -313.141996) (xy 273.509741 -313.09672) (xy 273.497964 -313.048936)
			(xy 273.494004 -312.999882) (xy 273.177 -312.999882) (xy 273.176496 -313.02559) (xy 273.168453 -313.076372)
			(xy 273.152565 -313.125271) (xy 273.129222 -313.171083) (xy 273.099001 -313.212679) (xy 273.062645 -313.249035)
			(xy 273.021049 -313.279256) (xy 272.975237 -313.302599) (xy 272.926338 -313.318487) (xy 272.875556 -313.32653)
			(xy 272.82414 -313.32653) (xy 272.773358 -313.318487) (xy 272.724459 -313.302599) (xy 272.678647 -313.279256)
			(xy 272.637051 -313.249035) (xy 272.600695 -313.212679) (xy 272.570474 -313.171083) (xy 272.547131 -313.125271)
			(xy 272.531243 -313.076372) (xy 272.5232 -313.02559) (xy 272.204522 -313.02559) (xy 272.196806 -313.073066)
			(xy 272.181222 -313.119747) (xy 272.158351 -313.163324) (xy 272.128786 -313.202668) (xy 272.093293 -313.23676)
			(xy 272.05279 -313.264716) (xy 272.008328 -313.285814) (xy 271.961057 -313.299506) (xy 271.912202 -313.305438)
			(xy 271.863027 -313.303457) (xy 271.814808 -313.293613) (xy 271.768792 -313.276161) (xy 271.726171 -313.251554)
			(xy 271.68805 -313.220429) (xy 271.655415 -313.183592) (xy 271.629112 -313.141996) (xy 271.609821 -313.09672)
			(xy 271.598044 -313.048936) (xy 271.594084 -312.999882) (xy 271.27708 -312.999882) (xy 271.276576 -313.02559)
			(xy 271.268533 -313.076372) (xy 271.252645 -313.125271) (xy 271.229302 -313.171083) (xy 271.199081 -313.212679)
			(xy 271.162725 -313.249035) (xy 271.121129 -313.279256) (xy 271.075317 -313.302599) (xy 271.026418 -313.318487)
			(xy 270.975636 -313.32653) (xy 270.92422 -313.32653) (xy 270.873438 -313.318487) (xy 270.824539 -313.302599)
			(xy 270.778727 -313.279256) (xy 270.737131 -313.249035) (xy 270.700775 -313.212679) (xy 270.670554 -313.171083)
			(xy 270.647211 -313.125271) (xy 270.631323 -313.076372) (xy 270.62328 -313.02559) (xy 270.304348 -313.02559)
			(xy 270.296632 -313.073066) (xy 270.281048 -313.119747) (xy 270.258177 -313.163324) (xy 270.228612 -313.202668)
			(xy 270.193119 -313.23676) (xy 270.152616 -313.264716) (xy 270.108154 -313.285814) (xy 270.060883 -313.299506)
			(xy 270.012028 -313.305438) (xy 269.962853 -313.303457) (xy 269.914634 -313.293613) (xy 269.868618 -313.276161)
			(xy 269.825997 -313.251554) (xy 269.787876 -313.220429) (xy 269.755241 -313.183592) (xy 269.728938 -313.141996)
			(xy 269.709647 -313.09672) (xy 269.69787 -313.048936) (xy 269.69391 -312.999882) (xy 269.355062 -312.999882)
			(xy 269.354567 -313.024489) (xy 269.346672 -313.073066) (xy 269.331088 -313.119747) (xy 269.308217 -313.163324)
			(xy 269.278652 -313.202668) (xy 269.243159 -313.23676) (xy 269.202656 -313.264716) (xy 269.158194 -313.285814)
			(xy 269.110923 -313.299506) (xy 269.062068 -313.305438) (xy 269.012893 -313.303457) (xy 268.964674 -313.293613)
			(xy 268.918658 -313.276161) (xy 268.876037 -313.251554) (xy 268.837916 -313.220429) (xy 268.805281 -313.183592)
			(xy 268.778978 -313.141996) (xy 268.759687 -313.09672) (xy 268.74791 -313.048936) (xy 268.74395 -312.999882)
			(xy 248.814844 -312.999882) (xy 248.814844 -313.669934) (xy 266.246862 -313.669934) (xy 266.250933 -313.614312)
			(xy 266.263059 -313.559875) (xy 266.282982 -313.507784) (xy 266.310278 -313.459149) (xy 266.344364 -313.415006)
			(xy 266.384513 -313.376297) (xy 266.429871 -313.343846) (xy 266.479471 -313.318345) (xy 266.532255 -313.300338)
			(xy 266.587098 -313.290208) (xy 266.642832 -313.288171) (xy 266.698269 -313.294271) (xy 266.752226 -313.308377)
			(xy 266.803555 -313.330189) (xy 266.851161 -313.359243) (xy 266.894029 -313.394918) (xy 266.931246 -313.436455)
			(xy 266.962019 -313.482968) (xy 266.985691 -313.533465) (xy 267.001759 -313.586872) (xy 267.009879 -313.642048)
			(xy 267.010388 -313.669934) (xy 267.009879 -313.69782) (xy 267.001759 -313.752996) (xy 266.985691 -313.806403)
			(xy 266.962019 -313.8569) (xy 266.931246 -313.903413) (xy 266.894029 -313.94495) (xy 266.888151 -313.949842)
			(xy 268.74395 -313.949842) (xy 268.74791 -313.900788) (xy 268.759687 -313.853004) (xy 268.778978 -313.807728)
			(xy 268.805281 -313.766132) (xy 268.837916 -313.729295) (xy 268.876037 -313.69817) (xy 268.918658 -313.673563)
			(xy 268.964674 -313.656111) (xy 269.012893 -313.646267) (xy 269.062068 -313.644286) (xy 269.110923 -313.650218)
			(xy 269.158194 -313.66391) (xy 269.202656 -313.685008) (xy 269.243159 -313.712964) (xy 269.278652 -313.747056)
			(xy 269.308217 -313.7864) (xy 269.331088 -313.829977) (xy 269.346672 -313.876658) (xy 269.354567 -313.925235)
			(xy 269.355062 -313.949842) (xy 269.69391 -313.949842) (xy 269.69787 -313.900788) (xy 269.709647 -313.853004)
			(xy 269.728938 -313.807728) (xy 269.755241 -313.766132) (xy 269.787876 -313.729295) (xy 269.825997 -313.69817)
			(xy 269.868618 -313.673563) (xy 269.914634 -313.656111) (xy 269.962853 -313.646267) (xy 270.012028 -313.644286)
			(xy 270.060883 -313.650218) (xy 270.108154 -313.66391) (xy 270.152616 -313.685008) (xy 270.193119 -313.712964)
			(xy 270.228612 -313.747056) (xy 270.258177 -313.7864) (xy 270.281048 -313.829977) (xy 270.296632 -313.876658)
			(xy 270.304527 -313.925235) (xy 270.305022 -313.949842) (xy 270.304527 -313.974449) (xy 270.304348 -313.97555)
			(xy 270.62328 -313.97555) (xy 270.62328 -313.924134) (xy 270.631323 -313.873352) (xy 270.647211 -313.824453)
			(xy 270.670554 -313.778641) (xy 270.700775 -313.737045) (xy 270.737131 -313.700689) (xy 270.778727 -313.670468)
			(xy 270.824539 -313.647125) (xy 270.873438 -313.631237) (xy 270.92422 -313.623194) (xy 270.975636 -313.623194)
			(xy 271.026418 -313.631237) (xy 271.075317 -313.647125) (xy 271.121129 -313.670468) (xy 271.162725 -313.700689)
			(xy 271.199081 -313.737045) (xy 271.229302 -313.778641) (xy 271.252645 -313.824453) (xy 271.268533 -313.873352)
			(xy 271.276576 -313.924134) (xy 271.27708 -313.949842) (xy 271.594084 -313.949842) (xy 271.598044 -313.900788)
			(xy 271.609821 -313.853004) (xy 271.629112 -313.807728) (xy 271.655415 -313.766132) (xy 271.68805 -313.729295)
			(xy 271.726171 -313.69817) (xy 271.768792 -313.673563) (xy 271.814808 -313.656111) (xy 271.863027 -313.646267)
			(xy 271.912202 -313.644286) (xy 271.961057 -313.650218) (xy 272.008328 -313.66391) (xy 272.05279 -313.685008)
			(xy 272.093293 -313.712964) (xy 272.128786 -313.747056) (xy 272.158351 -313.7864) (xy 272.181222 -313.829977)
			(xy 272.196806 -313.876658) (xy 272.204701 -313.925235) (xy 272.205196 -313.949842) (xy 272.204701 -313.974449)
			(xy 272.204522 -313.97555) (xy 272.5232 -313.97555) (xy 272.5232 -313.924134) (xy 272.531243 -313.873352)
			(xy 272.547131 -313.824453) (xy 272.570474 -313.778641) (xy 272.600695 -313.737045) (xy 272.637051 -313.700689)
			(xy 272.678647 -313.670468) (xy 272.724459 -313.647125) (xy 272.773358 -313.631237) (xy 272.82414 -313.623194)
			(xy 272.875556 -313.623194) (xy 272.926338 -313.631237) (xy 272.975237 -313.647125) (xy 273.021049 -313.670468)
			(xy 273.062645 -313.700689) (xy 273.099001 -313.737045) (xy 273.129222 -313.778641) (xy 273.152565 -313.824453)
			(xy 273.168453 -313.873352) (xy 273.176496 -313.924134) (xy 273.177 -313.949842) (xy 273.494004 -313.949842)
			(xy 273.497964 -313.900788) (xy 273.509741 -313.853004) (xy 273.529032 -313.807728) (xy 273.555335 -313.766132)
			(xy 273.58797 -313.729295) (xy 273.626091 -313.69817) (xy 273.668712 -313.673563) (xy 273.714728 -313.656111)
			(xy 273.762947 -313.646267) (xy 273.812122 -313.644286) (xy 273.860977 -313.650218) (xy 273.908248 -313.66391)
			(xy 273.95271 -313.685008) (xy 273.993213 -313.712964) (xy 274.028706 -313.747056) (xy 274.058271 -313.7864)
			(xy 274.081142 -313.829977) (xy 274.096726 -313.876658) (xy 274.104621 -313.925235) (xy 274.105116 -313.949842)
			(xy 274.104621 -313.974449) (xy 274.104442 -313.97555) (xy 274.42312 -313.97555) (xy 274.42312 -313.924134)
			(xy 274.431163 -313.873352) (xy 274.447051 -313.824453) (xy 274.470394 -313.778641) (xy 274.500615 -313.737045)
			(xy 274.536971 -313.700689) (xy 274.578567 -313.670468) (xy 274.624379 -313.647125) (xy 274.673278 -313.631237)
			(xy 274.72406 -313.623194) (xy 274.775476 -313.623194) (xy 274.826258 -313.631237) (xy 274.875157 -313.647125)
			(xy 274.920969 -313.670468) (xy 274.962565 -313.700689) (xy 274.998921 -313.737045) (xy 275.029142 -313.778641)
			(xy 275.052485 -313.824453) (xy 275.068373 -313.873352) (xy 275.076416 -313.924134) (xy 275.07692 -313.949842)
			(xy 275.393924 -313.949842) (xy 275.397884 -313.900788) (xy 275.409661 -313.853004) (xy 275.428952 -313.807728)
			(xy 275.455255 -313.766132) (xy 275.48789 -313.729295) (xy 275.526011 -313.69817) (xy 275.568632 -313.673563)
			(xy 275.614648 -313.656111) (xy 275.662867 -313.646267) (xy 275.712042 -313.644286) (xy 275.760897 -313.650218)
			(xy 275.808168 -313.66391) (xy 275.85263 -313.685008) (xy 275.893133 -313.712964) (xy 275.928626 -313.747056)
			(xy 275.958191 -313.7864) (xy 275.981062 -313.829977) (xy 275.996646 -313.876658) (xy 276.004541 -313.925235)
			(xy 276.005036 -313.949842) (xy 276.343884 -313.949842) (xy 276.347844 -313.900788) (xy 276.359621 -313.853004)
			(xy 276.378912 -313.807728) (xy 276.405215 -313.766132) (xy 276.43785 -313.729295) (xy 276.475971 -313.69817)
			(xy 276.518592 -313.673563) (xy 276.564608 -313.656111) (xy 276.612827 -313.646267) (xy 276.662002 -313.644286)
			(xy 276.710857 -313.650218) (xy 276.758128 -313.66391) (xy 276.80259 -313.685008) (xy 276.843093 -313.712964)
			(xy 276.878586 -313.747056) (xy 276.908151 -313.7864) (xy 276.931022 -313.829977) (xy 276.946606 -313.876658)
			(xy 276.954501 -313.925235) (xy 276.954996 -313.949842) (xy 277.294098 -313.949842) (xy 277.298058 -313.900788)
			(xy 277.309835 -313.853004) (xy 277.329126 -313.807728) (xy 277.355429 -313.766132) (xy 277.388064 -313.729295)
			(xy 277.426185 -313.69817) (xy 277.468806 -313.673563) (xy 277.514822 -313.656111) (xy 277.563041 -313.646267)
			(xy 277.612216 -313.644286) (xy 277.661071 -313.650218) (xy 277.708342 -313.66391) (xy 277.752804 -313.685008)
			(xy 277.793307 -313.712964) (xy 277.8288 -313.747056) (xy 277.858365 -313.7864) (xy 277.881236 -313.829977)
			(xy 277.89682 -313.876658) (xy 277.904715 -313.925235) (xy 277.90521 -313.949842) (xy 278.244058 -313.949842)
			(xy 278.248018 -313.900788) (xy 278.259795 -313.853004) (xy 278.279086 -313.807728) (xy 278.305389 -313.766132)
			(xy 278.338024 -313.729295) (xy 278.376145 -313.69817) (xy 278.418766 -313.673563) (xy 278.464782 -313.656111)
			(xy 278.513001 -313.646267) (xy 278.562176 -313.644286) (xy 278.611031 -313.650218) (xy 278.658302 -313.66391)
			(xy 278.702764 -313.685008) (xy 278.743267 -313.712964) (xy 278.77876 -313.747056) (xy 278.808325 -313.7864)
			(xy 278.831196 -313.829977) (xy 278.84678 -313.876658) (xy 278.854675 -313.925235) (xy 278.85517 -313.949842)
			(xy 279.194018 -313.949842) (xy 279.197978 -313.900788) (xy 279.209755 -313.853004) (xy 279.229046 -313.807728)
			(xy 279.255349 -313.766132) (xy 279.287984 -313.729295) (xy 279.326105 -313.69817) (xy 279.368726 -313.673563)
			(xy 279.414742 -313.656111) (xy 279.462961 -313.646267) (xy 279.512136 -313.644286) (xy 279.560991 -313.650218)
			(xy 279.608262 -313.66391) (xy 279.652724 -313.685008) (xy 279.693227 -313.712964) (xy 279.72872 -313.747056)
			(xy 279.758285 -313.7864) (xy 279.781156 -313.829977) (xy 279.79674 -313.876658) (xy 279.804635 -313.925235)
			(xy 279.80513 -313.949842) (xy 280.143978 -313.949842) (xy 280.147938 -313.900788) (xy 280.159715 -313.853004)
			(xy 280.179006 -313.807728) (xy 280.205309 -313.766132) (xy 280.237944 -313.729295) (xy 280.276065 -313.69817)
			(xy 280.318686 -313.673563) (xy 280.364702 -313.656111) (xy 280.412921 -313.646267) (xy 280.462096 -313.644286)
			(xy 280.510951 -313.650218) (xy 280.558222 -313.66391) (xy 280.602684 -313.685008) (xy 280.643187 -313.712964)
			(xy 280.67868 -313.747056) (xy 280.708245 -313.7864) (xy 280.731116 -313.829977) (xy 280.7467 -313.876658)
			(xy 280.754595 -313.925235) (xy 280.75509 -313.949842) (xy 281.093938 -313.949842) (xy 281.097898 -313.900788)
			(xy 281.109675 -313.853004) (xy 281.128966 -313.807728) (xy 281.155269 -313.766132) (xy 281.187904 -313.729295)
			(xy 281.226025 -313.69817) (xy 281.268646 -313.673563) (xy 281.314662 -313.656111) (xy 281.362881 -313.646267)
			(xy 281.412056 -313.644286) (xy 281.460911 -313.650218) (xy 281.508182 -313.66391) (xy 281.552644 -313.685008)
			(xy 281.593147 -313.712964) (xy 281.62864 -313.747056) (xy 281.658205 -313.7864) (xy 281.681076 -313.829977)
			(xy 281.69666 -313.876658) (xy 281.704555 -313.925235) (xy 281.70505 -313.949842) (xy 282.043898 -313.949842)
			(xy 282.047858 -313.900788) (xy 282.059635 -313.853004) (xy 282.078926 -313.807728) (xy 282.105229 -313.766132)
			(xy 282.137864 -313.729295) (xy 282.175985 -313.69817) (xy 282.218606 -313.673563) (xy 282.264622 -313.656111)
			(xy 282.312841 -313.646267) (xy 282.362016 -313.644286) (xy 282.410871 -313.650218) (xy 282.458142 -313.66391)
			(xy 282.502604 -313.685008) (xy 282.543107 -313.712964) (xy 282.5786 -313.747056) (xy 282.608165 -313.7864)
			(xy 282.631036 -313.829977) (xy 282.64662 -313.876658) (xy 282.654515 -313.925235) (xy 282.65501 -313.949842)
			(xy 282.994112 -313.949842) (xy 282.998072 -313.900788) (xy 283.009849 -313.853004) (xy 283.02914 -313.807728)
			(xy 283.055443 -313.766132) (xy 283.088078 -313.729295) (xy 283.126199 -313.69817) (xy 283.16882 -313.673563)
			(xy 283.214836 -313.656111) (xy 283.263055 -313.646267) (xy 283.31223 -313.644286) (xy 283.361085 -313.650218)
			(xy 283.408356 -313.66391) (xy 283.452818 -313.685008) (xy 283.493321 -313.712964) (xy 283.528814 -313.747056)
			(xy 283.558379 -313.7864) (xy 283.58125 -313.829977) (xy 283.596834 -313.876658) (xy 283.604729 -313.925235)
			(xy 283.605224 -313.949842) (xy 283.944072 -313.949842) (xy 283.948032 -313.900788) (xy 283.959809 -313.853004)
			(xy 283.9791 -313.807728) (xy 284.005403 -313.766132) (xy 284.038038 -313.729295) (xy 284.076159 -313.69817)
			(xy 284.11878 -313.673563) (xy 284.164796 -313.656111) (xy 284.213015 -313.646267) (xy 284.26219 -313.644286)
			(xy 284.311045 -313.650218) (xy 284.358316 -313.66391) (xy 284.402778 -313.685008) (xy 284.443281 -313.712964)
			(xy 284.478774 -313.747056) (xy 284.508339 -313.7864) (xy 284.53121 -313.829977) (xy 284.546794 -313.876658)
			(xy 284.554689 -313.925235) (xy 284.555184 -313.949842) (xy 284.894032 -313.949842) (xy 284.897992 -313.900788)
			(xy 284.909769 -313.853004) (xy 284.92906 -313.807728) (xy 284.955363 -313.766132) (xy 284.987998 -313.729295)
			(xy 285.026119 -313.69817) (xy 285.06874 -313.673563) (xy 285.114756 -313.656111) (xy 285.162975 -313.646267)
			(xy 285.21215 -313.644286) (xy 285.261005 -313.650218) (xy 285.308276 -313.66391) (xy 285.352738 -313.685008)
			(xy 285.393241 -313.712964) (xy 285.428734 -313.747056) (xy 285.458299 -313.7864) (xy 285.48117 -313.829977)
			(xy 285.496754 -313.876658) (xy 285.504649 -313.925235) (xy 285.505144 -313.949842) (xy 285.843992 -313.949842)
			(xy 285.847952 -313.900788) (xy 285.859729 -313.853004) (xy 285.87902 -313.807728) (xy 285.905323 -313.766132)
			(xy 285.937958 -313.729295) (xy 285.976079 -313.69817) (xy 286.0187 -313.673563) (xy 286.064716 -313.656111)
			(xy 286.112935 -313.646267) (xy 286.16211 -313.644286) (xy 286.210965 -313.650218) (xy 286.258236 -313.66391)
			(xy 286.302698 -313.685008) (xy 286.343201 -313.712964) (xy 286.378694 -313.747056) (xy 286.408259 -313.7864)
			(xy 286.43113 -313.829977) (xy 286.446714 -313.876658) (xy 286.454609 -313.925235) (xy 286.455104 -313.949842)
			(xy 286.793952 -313.949842) (xy 286.797912 -313.900788) (xy 286.809689 -313.853004) (xy 286.82898 -313.807728)
			(xy 286.855283 -313.766132) (xy 286.887918 -313.729295) (xy 286.926039 -313.69817) (xy 286.96866 -313.673563)
			(xy 287.014676 -313.656111) (xy 287.062895 -313.646267) (xy 287.11207 -313.644286) (xy 287.160925 -313.650218)
			(xy 287.208196 -313.66391) (xy 287.252658 -313.685008) (xy 287.293161 -313.712964) (xy 287.328654 -313.747056)
			(xy 287.358219 -313.7864) (xy 287.38109 -313.829977) (xy 287.396674 -313.876658) (xy 287.404569 -313.925235)
			(xy 287.405064 -313.949842) (xy 287.743912 -313.949842) (xy 287.747872 -313.900788) (xy 287.759649 -313.853004)
			(xy 287.77894 -313.807728) (xy 287.805243 -313.766132) (xy 287.837878 -313.729295) (xy 287.875999 -313.69817)
			(xy 287.91862 -313.673563) (xy 287.964636 -313.656111) (xy 288.012855 -313.646267) (xy 288.06203 -313.644286)
			(xy 288.110885 -313.650218) (xy 288.158156 -313.66391) (xy 288.202618 -313.685008) (xy 288.243121 -313.712964)
			(xy 288.278614 -313.747056) (xy 288.308179 -313.7864) (xy 288.33105 -313.829977) (xy 288.346634 -313.876658)
			(xy 288.354529 -313.925235) (xy 288.355024 -313.949842) (xy 288.694126 -313.949842) (xy 288.698086 -313.900788)
			(xy 288.709863 -313.853004) (xy 288.729154 -313.807728) (xy 288.755457 -313.766132) (xy 288.788092 -313.729295)
			(xy 288.826213 -313.69817) (xy 288.868834 -313.673563) (xy 288.91485 -313.656111) (xy 288.963069 -313.646267)
			(xy 289.012244 -313.644286) (xy 289.061099 -313.650218) (xy 289.10837 -313.66391) (xy 289.152832 -313.685008)
			(xy 289.193335 -313.712964) (xy 289.228828 -313.747056) (xy 289.258393 -313.7864) (xy 289.281264 -313.829977)
			(xy 289.296848 -313.876658) (xy 289.304743 -313.925235) (xy 289.305238 -313.949842) (xy 289.644086 -313.949842)
			(xy 289.648046 -313.900788) (xy 289.659823 -313.853004) (xy 289.679114 -313.807728) (xy 289.705417 -313.766132)
			(xy 289.738052 -313.729295) (xy 289.776173 -313.69817) (xy 289.818794 -313.673563) (xy 289.86481 -313.656111)
			(xy 289.913029 -313.646267) (xy 289.962204 -313.644286) (xy 290.011059 -313.650218) (xy 290.05833 -313.66391)
			(xy 290.102792 -313.685008) (xy 290.143295 -313.712964) (xy 290.178788 -313.747056) (xy 290.208353 -313.7864)
			(xy 290.231224 -313.829977) (xy 290.246808 -313.876658) (xy 290.254703 -313.925235) (xy 290.255198 -313.949842)
			(xy 290.594046 -313.949842) (xy 290.598006 -313.900788) (xy 290.609783 -313.853004) (xy 290.629074 -313.807728)
			(xy 290.655377 -313.766132) (xy 290.688012 -313.729295) (xy 290.726133 -313.69817) (xy 290.768754 -313.673563)
			(xy 290.81477 -313.656111) (xy 290.862989 -313.646267) (xy 290.912164 -313.644286) (xy 290.961019 -313.650218)
			(xy 291.00829 -313.66391) (xy 291.052752 -313.685008) (xy 291.093255 -313.712964) (xy 291.128748 -313.747056)
			(xy 291.158313 -313.7864) (xy 291.181184 -313.829977) (xy 291.196768 -313.876658) (xy 291.204663 -313.925235)
			(xy 291.205158 -313.949842) (xy 291.204663 -313.974449) (xy 291.204484 -313.97555) (xy 291.523162 -313.97555)
			(xy 291.523162 -313.924134) (xy 291.531205 -313.873352) (xy 291.547093 -313.824453) (xy 291.570436 -313.778641)
			(xy 291.600657 -313.737045) (xy 291.637013 -313.700689) (xy 291.678609 -313.670468) (xy 291.724421 -313.647125)
			(xy 291.77332 -313.631237) (xy 291.824102 -313.623194) (xy 291.875518 -313.623194) (xy 291.9263 -313.631237)
			(xy 291.975199 -313.647125) (xy 292.021011 -313.670468) (xy 292.062607 -313.700689) (xy 292.098963 -313.737045)
			(xy 292.129184 -313.778641) (xy 292.152527 -313.824453) (xy 292.168415 -313.873352) (xy 292.176458 -313.924134)
			(xy 292.176962 -313.949842) (xy 292.493966 -313.949842) (xy 292.497926 -313.900788) (xy 292.509703 -313.853004)
			(xy 292.528994 -313.807728) (xy 292.555297 -313.766132) (xy 292.587932 -313.729295) (xy 292.626053 -313.69817)
			(xy 292.668674 -313.673563) (xy 292.71469 -313.656111) (xy 292.762909 -313.646267) (xy 292.812084 -313.644286)
			(xy 292.860939 -313.650218) (xy 292.90821 -313.66391) (xy 292.952672 -313.685008) (xy 292.993175 -313.712964)
			(xy 293.028668 -313.747056) (xy 293.058233 -313.7864) (xy 293.081104 -313.829977) (xy 293.096688 -313.876658)
			(xy 293.104583 -313.925235) (xy 293.105078 -313.949842) (xy 293.104583 -313.974449) (xy 293.104404 -313.97555)
			(xy 293.423082 -313.97555) (xy 293.423082 -313.924134) (xy 293.431125 -313.873352) (xy 293.447013 -313.824453)
			(xy 293.470356 -313.778641) (xy 293.500577 -313.737045) (xy 293.536933 -313.700689) (xy 293.578529 -313.670468)
			(xy 293.624341 -313.647125) (xy 293.67324 -313.631237) (xy 293.724022 -313.623194) (xy 293.775438 -313.623194)
			(xy 293.82622 -313.631237) (xy 293.875119 -313.647125) (xy 293.920931 -313.670468) (xy 293.962527 -313.700689)
			(xy 293.998883 -313.737045) (xy 294.029104 -313.778641) (xy 294.052447 -313.824453) (xy 294.068335 -313.873352)
			(xy 294.076378 -313.924134) (xy 294.076882 -313.949842) (xy 294.393886 -313.949842) (xy 294.397846 -313.900788)
			(xy 294.409623 -313.853004) (xy 294.428914 -313.807728) (xy 294.455217 -313.766132) (xy 294.487852 -313.729295)
			(xy 294.525973 -313.69817) (xy 294.568594 -313.673563) (xy 294.61461 -313.656111) (xy 294.662829 -313.646267)
			(xy 294.712004 -313.644286) (xy 294.760859 -313.650218) (xy 294.80813 -313.66391) (xy 294.852592 -313.685008)
			(xy 294.893095 -313.712964) (xy 294.928588 -313.747056) (xy 294.958153 -313.7864) (xy 294.981024 -313.829977)
			(xy 294.996608 -313.876658) (xy 295.004503 -313.925235) (xy 295.004998 -313.949842) (xy 295.004503 -313.974449)
			(xy 295.004324 -313.97555) (xy 295.323256 -313.97555) (xy 295.323256 -313.924134) (xy 295.331299 -313.873352)
			(xy 295.347187 -313.824453) (xy 295.37053 -313.778641) (xy 295.400751 -313.737045) (xy 295.437107 -313.700689)
			(xy 295.478703 -313.670468) (xy 295.524515 -313.647125) (xy 295.573414 -313.631237) (xy 295.624196 -313.623194)
			(xy 295.675612 -313.623194) (xy 295.726394 -313.631237) (xy 295.775293 -313.647125) (xy 295.821105 -313.670468)
			(xy 295.862701 -313.700689) (xy 295.899057 -313.737045) (xy 295.929278 -313.778641) (xy 295.952621 -313.824453)
			(xy 295.968509 -313.873352) (xy 295.976552 -313.924134) (xy 295.977056 -313.949842) (xy 296.29406 -313.949842)
			(xy 296.29802 -313.900788) (xy 296.309797 -313.853004) (xy 296.329088 -313.807728) (xy 296.355391 -313.766132)
			(xy 296.388026 -313.729295) (xy 296.426147 -313.69817) (xy 296.468768 -313.673563) (xy 296.514784 -313.656111)
			(xy 296.563003 -313.646267) (xy 296.612178 -313.644286) (xy 296.661033 -313.650218) (xy 296.708304 -313.66391)
			(xy 296.752766 -313.685008) (xy 296.793269 -313.712964) (xy 296.828762 -313.747056) (xy 296.858327 -313.7864)
			(xy 296.881198 -313.829977) (xy 296.896782 -313.876658) (xy 296.904677 -313.925235) (xy 296.905172 -313.949842)
			(xy 296.904677 -313.974449) (xy 296.904498 -313.97555) (xy 297.223176 -313.97555) (xy 297.223176 -313.924134)
			(xy 297.231219 -313.873352) (xy 297.247107 -313.824453) (xy 297.27045 -313.778641) (xy 297.300671 -313.737045)
			(xy 297.337027 -313.700689) (xy 297.378623 -313.670468) (xy 297.424435 -313.647125) (xy 297.473334 -313.631237)
			(xy 297.524116 -313.623194) (xy 297.575532 -313.623194) (xy 297.626314 -313.631237) (xy 297.675213 -313.647125)
			(xy 297.721025 -313.670468) (xy 297.762621 -313.700689) (xy 297.798977 -313.737045) (xy 297.829198 -313.778641)
			(xy 297.852541 -313.824453) (xy 297.868429 -313.873352) (xy 297.876472 -313.924134) (xy 297.876976 -313.949842)
			(xy 298.19398 -313.949842) (xy 298.19794 -313.900788) (xy 298.209717 -313.853004) (xy 298.229008 -313.807728)
			(xy 298.255311 -313.766132) (xy 298.287946 -313.729295) (xy 298.326067 -313.69817) (xy 298.368688 -313.673563)
			(xy 298.414704 -313.656111) (xy 298.462923 -313.646267) (xy 298.512098 -313.644286) (xy 298.560953 -313.650218)
			(xy 298.608224 -313.66391) (xy 298.652686 -313.685008) (xy 298.693189 -313.712964) (xy 298.728682 -313.747056)
			(xy 298.758247 -313.7864) (xy 298.781118 -313.829977) (xy 298.796702 -313.876658) (xy 298.804597 -313.925235)
			(xy 298.805092 -313.949842) (xy 298.804597 -313.974449) (xy 298.804418 -313.97555) (xy 299.123096 -313.97555)
			(xy 299.123096 -313.924134) (xy 299.131139 -313.873352) (xy 299.147027 -313.824453) (xy 299.17037 -313.778641)
			(xy 299.200591 -313.737045) (xy 299.236947 -313.700689) (xy 299.278543 -313.670468) (xy 299.324355 -313.647125)
			(xy 299.373254 -313.631237) (xy 299.424036 -313.623194) (xy 299.475452 -313.623194) (xy 299.526234 -313.631237)
			(xy 299.575133 -313.647125) (xy 299.620945 -313.670468) (xy 299.662541 -313.700689) (xy 299.698897 -313.737045)
			(xy 299.729118 -313.778641) (xy 299.752461 -313.824453) (xy 299.768349 -313.873352) (xy 299.776392 -313.924134)
			(xy 299.776896 -313.949842) (xy 300.0939 -313.949842) (xy 300.09786 -313.900788) (xy 300.109637 -313.853004)
			(xy 300.128928 -313.807728) (xy 300.155231 -313.766132) (xy 300.187866 -313.729295) (xy 300.225987 -313.69817)
			(xy 300.268608 -313.673563) (xy 300.314624 -313.656111) (xy 300.362843 -313.646267) (xy 300.412018 -313.644286)
			(xy 300.460873 -313.650218) (xy 300.508144 -313.66391) (xy 300.552606 -313.685008) (xy 300.593109 -313.712964)
			(xy 300.628602 -313.747056) (xy 300.658167 -313.7864) (xy 300.681038 -313.829977) (xy 300.696622 -313.876658)
			(xy 300.704517 -313.925235) (xy 300.705012 -313.949842) (xy 300.704517 -313.974449) (xy 300.704338 -313.97555)
			(xy 301.02327 -313.97555) (xy 301.02327 -313.924134) (xy 301.031313 -313.873352) (xy 301.047201 -313.824453)
			(xy 301.070544 -313.778641) (xy 301.100765 -313.737045) (xy 301.137121 -313.700689) (xy 301.178717 -313.670468)
			(xy 301.224529 -313.647125) (xy 301.273428 -313.631237) (xy 301.32421 -313.623194) (xy 301.375626 -313.623194)
			(xy 301.426408 -313.631237) (xy 301.475307 -313.647125) (xy 301.521119 -313.670468) (xy 301.562715 -313.700689)
			(xy 301.599071 -313.737045) (xy 301.629292 -313.778641) (xy 301.652635 -313.824453) (xy 301.668523 -313.873352)
			(xy 301.676566 -313.924134) (xy 301.67707 -313.949842) (xy 301.994074 -313.949842) (xy 301.998034 -313.900788)
			(xy 302.009811 -313.853004) (xy 302.029102 -313.807728) (xy 302.055405 -313.766132) (xy 302.08804 -313.729295)
			(xy 302.126161 -313.69817) (xy 302.168782 -313.673563) (xy 302.214798 -313.656111) (xy 302.263017 -313.646267)
			(xy 302.312192 -313.644286) (xy 302.361047 -313.650218) (xy 302.408318 -313.66391) (xy 302.45278 -313.685008)
			(xy 302.493283 -313.712964) (xy 302.528776 -313.747056) (xy 302.558341 -313.7864) (xy 302.581212 -313.829977)
			(xy 302.596796 -313.876658) (xy 302.604691 -313.925235) (xy 302.605186 -313.949842) (xy 302.604691 -313.974449)
			(xy 302.604512 -313.97555) (xy 302.92319 -313.97555) (xy 302.92319 -313.924134) (xy 302.931233 -313.873352)
			(xy 302.947121 -313.824453) (xy 302.970464 -313.778641) (xy 303.000685 -313.737045) (xy 303.037041 -313.700689)
			(xy 303.078637 -313.670468) (xy 303.124449 -313.647125) (xy 303.173348 -313.631237) (xy 303.22413 -313.623194)
			(xy 303.275546 -313.623194) (xy 303.326328 -313.631237) (xy 303.375227 -313.647125) (xy 303.421039 -313.670468)
			(xy 303.462635 -313.700689) (xy 303.498991 -313.737045) (xy 303.529212 -313.778641) (xy 303.552555 -313.824453)
			(xy 303.568443 -313.873352) (xy 303.576486 -313.924134) (xy 303.57699 -313.949842) (xy 303.576486 -313.97555)
			(xy 303.568443 -314.026332) (xy 303.552555 -314.075231) (xy 303.529212 -314.121043) (xy 303.498991 -314.162639)
			(xy 303.462635 -314.198995) (xy 303.421039 -314.229216) (xy 303.375227 -314.252559) (xy 303.326328 -314.268447)
			(xy 303.275546 -314.27649) (xy 303.22413 -314.27649) (xy 303.173348 -314.268447) (xy 303.124449 -314.252559)
			(xy 303.078637 -314.229216) (xy 303.037041 -314.198995) (xy 303.000685 -314.162639) (xy 302.970464 -314.121043)
			(xy 302.947121 -314.075231) (xy 302.931233 -314.026332) (xy 302.92319 -313.97555) (xy 302.604512 -313.97555)
			(xy 302.596796 -314.023026) (xy 302.581212 -314.069707) (xy 302.558341 -314.113284) (xy 302.528776 -314.152628)
			(xy 302.493283 -314.18672) (xy 302.45278 -314.214676) (xy 302.408318 -314.235774) (xy 302.361047 -314.249466)
			(xy 302.312192 -314.255398) (xy 302.263017 -314.253417) (xy 302.214798 -314.243573) (xy 302.168782 -314.226121)
			(xy 302.126161 -314.201514) (xy 302.08804 -314.170389) (xy 302.055405 -314.133552) (xy 302.029102 -314.091956)
			(xy 302.009811 -314.04668) (xy 301.998034 -313.998896) (xy 301.994074 -313.949842) (xy 301.67707 -313.949842)
			(xy 301.676566 -313.97555) (xy 301.668523 -314.026332) (xy 301.652635 -314.075231) (xy 301.629292 -314.121043)
			(xy 301.599071 -314.162639) (xy 301.562715 -314.198995) (xy 301.521119 -314.229216) (xy 301.475307 -314.252559)
			(xy 301.426408 -314.268447) (xy 301.375626 -314.27649) (xy 301.32421 -314.27649) (xy 301.273428 -314.268447)
			(xy 301.224529 -314.252559) (xy 301.178717 -314.229216) (xy 301.137121 -314.198995) (xy 301.100765 -314.162639)
			(xy 301.070544 -314.121043) (xy 301.047201 -314.075231) (xy 301.031313 -314.026332) (xy 301.02327 -313.97555)
			(xy 300.704338 -313.97555) (xy 300.696622 -314.023026) (xy 300.681038 -314.069707) (xy 300.658167 -314.113284)
			(xy 300.628602 -314.152628) (xy 300.593109 -314.18672) (xy 300.552606 -314.214676) (xy 300.508144 -314.235774)
			(xy 300.460873 -314.249466) (xy 300.412018 -314.255398) (xy 300.362843 -314.253417) (xy 300.314624 -314.243573)
			(xy 300.268608 -314.226121) (xy 300.225987 -314.201514) (xy 300.187866 -314.170389) (xy 300.155231 -314.133552)
			(xy 300.128928 -314.091956) (xy 300.109637 -314.04668) (xy 300.09786 -313.998896) (xy 300.0939 -313.949842)
			(xy 299.776896 -313.949842) (xy 299.776392 -313.97555) (xy 299.768349 -314.026332) (xy 299.752461 -314.075231)
			(xy 299.729118 -314.121043) (xy 299.698897 -314.162639) (xy 299.662541 -314.198995) (xy 299.620945 -314.229216)
			(xy 299.575133 -314.252559) (xy 299.526234 -314.268447) (xy 299.475452 -314.27649) (xy 299.424036 -314.27649)
			(xy 299.373254 -314.268447) (xy 299.324355 -314.252559) (xy 299.278543 -314.229216) (xy 299.236947 -314.198995)
			(xy 299.200591 -314.162639) (xy 299.17037 -314.121043) (xy 299.147027 -314.075231) (xy 299.131139 -314.026332)
			(xy 299.123096 -313.97555) (xy 298.804418 -313.97555) (xy 298.796702 -314.023026) (xy 298.781118 -314.069707)
			(xy 298.758247 -314.113284) (xy 298.728682 -314.152628) (xy 298.693189 -314.18672) (xy 298.652686 -314.214676)
			(xy 298.608224 -314.235774) (xy 298.560953 -314.249466) (xy 298.512098 -314.255398) (xy 298.462923 -314.253417)
			(xy 298.414704 -314.243573) (xy 298.368688 -314.226121) (xy 298.326067 -314.201514) (xy 298.287946 -314.170389)
			(xy 298.255311 -314.133552) (xy 298.229008 -314.091956) (xy 298.209717 -314.04668) (xy 298.19794 -313.998896)
			(xy 298.19398 -313.949842) (xy 297.876976 -313.949842) (xy 297.876472 -313.97555) (xy 297.868429 -314.026332)
			(xy 297.852541 -314.075231) (xy 297.829198 -314.121043) (xy 297.798977 -314.162639) (xy 297.762621 -314.198995)
			(xy 297.721025 -314.229216) (xy 297.675213 -314.252559) (xy 297.626314 -314.268447) (xy 297.575532 -314.27649)
			(xy 297.524116 -314.27649) (xy 297.473334 -314.268447) (xy 297.424435 -314.252559) (xy 297.378623 -314.229216)
			(xy 297.337027 -314.198995) (xy 297.300671 -314.162639) (xy 297.27045 -314.121043) (xy 297.247107 -314.075231)
			(xy 297.231219 -314.026332) (xy 297.223176 -313.97555) (xy 296.904498 -313.97555) (xy 296.896782 -314.023026)
			(xy 296.881198 -314.069707) (xy 296.858327 -314.113284) (xy 296.828762 -314.152628) (xy 296.793269 -314.18672)
			(xy 296.752766 -314.214676) (xy 296.708304 -314.235774) (xy 296.661033 -314.249466) (xy 296.612178 -314.255398)
			(xy 296.563003 -314.253417) (xy 296.514784 -314.243573) (xy 296.468768 -314.226121) (xy 296.426147 -314.201514)
			(xy 296.388026 -314.170389) (xy 296.355391 -314.133552) (xy 296.329088 -314.091956) (xy 296.309797 -314.04668)
			(xy 296.29802 -313.998896) (xy 296.29406 -313.949842) (xy 295.977056 -313.949842) (xy 295.976552 -313.97555)
			(xy 295.968509 -314.026332) (xy 295.952621 -314.075231) (xy 295.929278 -314.121043) (xy 295.899057 -314.162639)
			(xy 295.862701 -314.198995) (xy 295.821105 -314.229216) (xy 295.775293 -314.252559) (xy 295.726394 -314.268447)
			(xy 295.675612 -314.27649) (xy 295.624196 -314.27649) (xy 295.573414 -314.268447) (xy 295.524515 -314.252559)
			(xy 295.478703 -314.229216) (xy 295.437107 -314.198995) (xy 295.400751 -314.162639) (xy 295.37053 -314.121043)
			(xy 295.347187 -314.075231) (xy 295.331299 -314.026332) (xy 295.323256 -313.97555) (xy 295.004324 -313.97555)
			(xy 294.996608 -314.023026) (xy 294.981024 -314.069707) (xy 294.958153 -314.113284) (xy 294.928588 -314.152628)
			(xy 294.893095 -314.18672) (xy 294.852592 -314.214676) (xy 294.80813 -314.235774) (xy 294.760859 -314.249466)
			(xy 294.712004 -314.255398) (xy 294.662829 -314.253417) (xy 294.61461 -314.243573) (xy 294.568594 -314.226121)
			(xy 294.525973 -314.201514) (xy 294.487852 -314.170389) (xy 294.455217 -314.133552) (xy 294.428914 -314.091956)
			(xy 294.409623 -314.04668) (xy 294.397846 -313.998896) (xy 294.393886 -313.949842) (xy 294.076882 -313.949842)
			(xy 294.076378 -313.97555) (xy 294.068335 -314.026332) (xy 294.052447 -314.075231) (xy 294.029104 -314.121043)
			(xy 293.998883 -314.162639) (xy 293.962527 -314.198995) (xy 293.920931 -314.229216) (xy 293.875119 -314.252559)
			(xy 293.82622 -314.268447) (xy 293.775438 -314.27649) (xy 293.724022 -314.27649) (xy 293.67324 -314.268447)
			(xy 293.624341 -314.252559) (xy 293.578529 -314.229216) (xy 293.536933 -314.198995) (xy 293.500577 -314.162639)
			(xy 293.470356 -314.121043) (xy 293.447013 -314.075231) (xy 293.431125 -314.026332) (xy 293.423082 -313.97555)
			(xy 293.104404 -313.97555) (xy 293.096688 -314.023026) (xy 293.081104 -314.069707) (xy 293.058233 -314.113284)
			(xy 293.028668 -314.152628) (xy 292.993175 -314.18672) (xy 292.952672 -314.214676) (xy 292.90821 -314.235774)
			(xy 292.860939 -314.249466) (xy 292.812084 -314.255398) (xy 292.762909 -314.253417) (xy 292.71469 -314.243573)
			(xy 292.668674 -314.226121) (xy 292.626053 -314.201514) (xy 292.587932 -314.170389) (xy 292.555297 -314.133552)
			(xy 292.528994 -314.091956) (xy 292.509703 -314.04668) (xy 292.497926 -313.998896) (xy 292.493966 -313.949842)
			(xy 292.176962 -313.949842) (xy 292.176458 -313.97555) (xy 292.168415 -314.026332) (xy 292.152527 -314.075231)
			(xy 292.129184 -314.121043) (xy 292.098963 -314.162639) (xy 292.062607 -314.198995) (xy 292.021011 -314.229216)
			(xy 291.975199 -314.252559) (xy 291.9263 -314.268447) (xy 291.875518 -314.27649) (xy 291.824102 -314.27649)
			(xy 291.77332 -314.268447) (xy 291.724421 -314.252559) (xy 291.678609 -314.229216) (xy 291.637013 -314.198995)
			(xy 291.600657 -314.162639) (xy 291.570436 -314.121043) (xy 291.547093 -314.075231) (xy 291.531205 -314.026332)
			(xy 291.523162 -313.97555) (xy 291.204484 -313.97555) (xy 291.196768 -314.023026) (xy 291.181184 -314.069707)
			(xy 291.158313 -314.113284) (xy 291.128748 -314.152628) (xy 291.093255 -314.18672) (xy 291.052752 -314.214676)
			(xy 291.00829 -314.235774) (xy 290.961019 -314.249466) (xy 290.912164 -314.255398) (xy 290.862989 -314.253417)
			(xy 290.81477 -314.243573) (xy 290.768754 -314.226121) (xy 290.726133 -314.201514) (xy 290.688012 -314.170389)
			(xy 290.655377 -314.133552) (xy 290.629074 -314.091956) (xy 290.609783 -314.04668) (xy 290.598006 -313.998896)
			(xy 290.594046 -313.949842) (xy 290.255198 -313.949842) (xy 290.254703 -313.974449) (xy 290.246808 -314.023026)
			(xy 290.231224 -314.069707) (xy 290.208353 -314.113284) (xy 290.178788 -314.152628) (xy 290.143295 -314.18672)
			(xy 290.102792 -314.214676) (xy 290.05833 -314.235774) (xy 290.011059 -314.249466) (xy 289.962204 -314.255398)
			(xy 289.913029 -314.253417) (xy 289.86481 -314.243573) (xy 289.818794 -314.226121) (xy 289.776173 -314.201514)
			(xy 289.738052 -314.170389) (xy 289.705417 -314.133552) (xy 289.679114 -314.091956) (xy 289.659823 -314.04668)
			(xy 289.648046 -313.998896) (xy 289.644086 -313.949842) (xy 289.305238 -313.949842) (xy 289.304743 -313.974449)
			(xy 289.296848 -314.023026) (xy 289.281264 -314.069707) (xy 289.258393 -314.113284) (xy 289.228828 -314.152628)
			(xy 289.193335 -314.18672) (xy 289.152832 -314.214676) (xy 289.10837 -314.235774) (xy 289.061099 -314.249466)
			(xy 289.012244 -314.255398) (xy 288.963069 -314.253417) (xy 288.91485 -314.243573) (xy 288.868834 -314.226121)
			(xy 288.826213 -314.201514) (xy 288.788092 -314.170389) (xy 288.755457 -314.133552) (xy 288.729154 -314.091956)
			(xy 288.709863 -314.04668) (xy 288.698086 -313.998896) (xy 288.694126 -313.949842) (xy 288.355024 -313.949842)
			(xy 288.354529 -313.974449) (xy 288.346634 -314.023026) (xy 288.33105 -314.069707) (xy 288.308179 -314.113284)
			(xy 288.278614 -314.152628) (xy 288.243121 -314.18672) (xy 288.202618 -314.214676) (xy 288.158156 -314.235774)
			(xy 288.110885 -314.249466) (xy 288.06203 -314.255398) (xy 288.012855 -314.253417) (xy 287.964636 -314.243573)
			(xy 287.91862 -314.226121) (xy 287.875999 -314.201514) (xy 287.837878 -314.170389) (xy 287.805243 -314.133552)
			(xy 287.77894 -314.091956) (xy 287.759649 -314.04668) (xy 287.747872 -313.998896) (xy 287.743912 -313.949842)
			(xy 287.405064 -313.949842) (xy 287.404569 -313.974449) (xy 287.396674 -314.023026) (xy 287.38109 -314.069707)
			(xy 287.358219 -314.113284) (xy 287.328654 -314.152628) (xy 287.293161 -314.18672) (xy 287.252658 -314.214676)
			(xy 287.208196 -314.235774) (xy 287.160925 -314.249466) (xy 287.11207 -314.255398) (xy 287.062895 -314.253417)
			(xy 287.014676 -314.243573) (xy 286.96866 -314.226121) (xy 286.926039 -314.201514) (xy 286.887918 -314.170389)
			(xy 286.855283 -314.133552) (xy 286.82898 -314.091956) (xy 286.809689 -314.04668) (xy 286.797912 -313.998896)
			(xy 286.793952 -313.949842) (xy 286.455104 -313.949842) (xy 286.454609 -313.974449) (xy 286.446714 -314.023026)
			(xy 286.43113 -314.069707) (xy 286.408259 -314.113284) (xy 286.378694 -314.152628) (xy 286.343201 -314.18672)
			(xy 286.302698 -314.214676) (xy 286.258236 -314.235774) (xy 286.210965 -314.249466) (xy 286.16211 -314.255398)
			(xy 286.112935 -314.253417) (xy 286.064716 -314.243573) (xy 286.0187 -314.226121) (xy 285.976079 -314.201514)
			(xy 285.937958 -314.170389) (xy 285.905323 -314.133552) (xy 285.87902 -314.091956) (xy 285.859729 -314.04668)
			(xy 285.847952 -313.998896) (xy 285.843992 -313.949842) (xy 285.505144 -313.949842) (xy 285.504649 -313.974449)
			(xy 285.496754 -314.023026) (xy 285.48117 -314.069707) (xy 285.458299 -314.113284) (xy 285.428734 -314.152628)
			(xy 285.393241 -314.18672) (xy 285.352738 -314.214676) (xy 285.308276 -314.235774) (xy 285.261005 -314.249466)
			(xy 285.21215 -314.255398) (xy 285.162975 -314.253417) (xy 285.114756 -314.243573) (xy 285.06874 -314.226121)
			(xy 285.026119 -314.201514) (xy 284.987998 -314.170389) (xy 284.955363 -314.133552) (xy 284.92906 -314.091956)
			(xy 284.909769 -314.04668) (xy 284.897992 -313.998896) (xy 284.894032 -313.949842) (xy 284.555184 -313.949842)
			(xy 284.554689 -313.974449) (xy 284.546794 -314.023026) (xy 284.53121 -314.069707) (xy 284.508339 -314.113284)
			(xy 284.478774 -314.152628) (xy 284.443281 -314.18672) (xy 284.402778 -314.214676) (xy 284.358316 -314.235774)
			(xy 284.311045 -314.249466) (xy 284.26219 -314.255398) (xy 284.213015 -314.253417) (xy 284.164796 -314.243573)
			(xy 284.11878 -314.226121) (xy 284.076159 -314.201514) (xy 284.038038 -314.170389) (xy 284.005403 -314.133552)
			(xy 283.9791 -314.091956) (xy 283.959809 -314.04668) (xy 283.948032 -313.998896) (xy 283.944072 -313.949842)
			(xy 283.605224 -313.949842) (xy 283.604729 -313.974449) (xy 283.596834 -314.023026) (xy 283.58125 -314.069707)
			(xy 283.558379 -314.113284) (xy 283.528814 -314.152628) (xy 283.493321 -314.18672) (xy 283.452818 -314.214676)
			(xy 283.408356 -314.235774) (xy 283.361085 -314.249466) (xy 283.31223 -314.255398) (xy 283.263055 -314.253417)
			(xy 283.214836 -314.243573) (xy 283.16882 -314.226121) (xy 283.126199 -314.201514) (xy 283.088078 -314.170389)
			(xy 283.055443 -314.133552) (xy 283.02914 -314.091956) (xy 283.009849 -314.04668) (xy 282.998072 -313.998896)
			(xy 282.994112 -313.949842) (xy 282.65501 -313.949842) (xy 282.654515 -313.974449) (xy 282.64662 -314.023026)
			(xy 282.631036 -314.069707) (xy 282.608165 -314.113284) (xy 282.5786 -314.152628) (xy 282.543107 -314.18672)
			(xy 282.502604 -314.214676) (xy 282.458142 -314.235774) (xy 282.410871 -314.249466) (xy 282.362016 -314.255398)
			(xy 282.312841 -314.253417) (xy 282.264622 -314.243573) (xy 282.218606 -314.226121) (xy 282.175985 -314.201514)
			(xy 282.137864 -314.170389) (xy 282.105229 -314.133552) (xy 282.078926 -314.091956) (xy 282.059635 -314.04668)
			(xy 282.047858 -313.998896) (xy 282.043898 -313.949842) (xy 281.70505 -313.949842) (xy 281.704555 -313.974449)
			(xy 281.69666 -314.023026) (xy 281.681076 -314.069707) (xy 281.658205 -314.113284) (xy 281.62864 -314.152628)
			(xy 281.593147 -314.18672) (xy 281.552644 -314.214676) (xy 281.508182 -314.235774) (xy 281.460911 -314.249466)
			(xy 281.412056 -314.255398) (xy 281.362881 -314.253417) (xy 281.314662 -314.243573) (xy 281.268646 -314.226121)
			(xy 281.226025 -314.201514) (xy 281.187904 -314.170389) (xy 281.155269 -314.133552) (xy 281.128966 -314.091956)
			(xy 281.109675 -314.04668) (xy 281.097898 -313.998896) (xy 281.093938 -313.949842) (xy 280.75509 -313.949842)
			(xy 280.754595 -313.974449) (xy 280.7467 -314.023026) (xy 280.731116 -314.069707) (xy 280.708245 -314.113284)
			(xy 280.67868 -314.152628) (xy 280.643187 -314.18672) (xy 280.602684 -314.214676) (xy 280.558222 -314.235774)
			(xy 280.510951 -314.249466) (xy 280.462096 -314.255398) (xy 280.412921 -314.253417) (xy 280.364702 -314.243573)
			(xy 280.318686 -314.226121) (xy 280.276065 -314.201514) (xy 280.237944 -314.170389) (xy 280.205309 -314.133552)
			(xy 280.179006 -314.091956) (xy 280.159715 -314.04668) (xy 280.147938 -313.998896) (xy 280.143978 -313.949842)
			(xy 279.80513 -313.949842) (xy 279.804635 -313.974449) (xy 279.79674 -314.023026) (xy 279.781156 -314.069707)
			(xy 279.758285 -314.113284) (xy 279.72872 -314.152628) (xy 279.693227 -314.18672) (xy 279.652724 -314.214676)
			(xy 279.608262 -314.235774) (xy 279.560991 -314.249466) (xy 279.512136 -314.255398) (xy 279.462961 -314.253417)
			(xy 279.414742 -314.243573) (xy 279.368726 -314.226121) (xy 279.326105 -314.201514) (xy 279.287984 -314.170389)
			(xy 279.255349 -314.133552) (xy 279.229046 -314.091956) (xy 279.209755 -314.04668) (xy 279.197978 -313.998896)
			(xy 279.194018 -313.949842) (xy 278.85517 -313.949842) (xy 278.854675 -313.974449) (xy 278.84678 -314.023026)
			(xy 278.831196 -314.069707) (xy 278.808325 -314.113284) (xy 278.77876 -314.152628) (xy 278.743267 -314.18672)
			(xy 278.702764 -314.214676) (xy 278.658302 -314.235774) (xy 278.611031 -314.249466) (xy 278.562176 -314.255398)
			(xy 278.513001 -314.253417) (xy 278.464782 -314.243573) (xy 278.418766 -314.226121) (xy 278.376145 -314.201514)
			(xy 278.338024 -314.170389) (xy 278.305389 -314.133552) (xy 278.279086 -314.091956) (xy 278.259795 -314.04668)
			(xy 278.248018 -313.998896) (xy 278.244058 -313.949842) (xy 277.90521 -313.949842) (xy 277.904715 -313.974449)
			(xy 277.89682 -314.023026) (xy 277.881236 -314.069707) (xy 277.858365 -314.113284) (xy 277.8288 -314.152628)
			(xy 277.793307 -314.18672) (xy 277.752804 -314.214676) (xy 277.708342 -314.235774) (xy 277.661071 -314.249466)
			(xy 277.612216 -314.255398) (xy 277.563041 -314.253417) (xy 277.514822 -314.243573) (xy 277.468806 -314.226121)
			(xy 277.426185 -314.201514) (xy 277.388064 -314.170389) (xy 277.355429 -314.133552) (xy 277.329126 -314.091956)
			(xy 277.309835 -314.04668) (xy 277.298058 -313.998896) (xy 277.294098 -313.949842) (xy 276.954996 -313.949842)
			(xy 276.954501 -313.974449) (xy 276.946606 -314.023026) (xy 276.931022 -314.069707) (xy 276.908151 -314.113284)
			(xy 276.878586 -314.152628) (xy 276.843093 -314.18672) (xy 276.80259 -314.214676) (xy 276.758128 -314.235774)
			(xy 276.710857 -314.249466) (xy 276.662002 -314.255398) (xy 276.612827 -314.253417) (xy 276.564608 -314.243573)
			(xy 276.518592 -314.226121) (xy 276.475971 -314.201514) (xy 276.43785 -314.170389) (xy 276.405215 -314.133552)
			(xy 276.378912 -314.091956) (xy 276.359621 -314.04668) (xy 276.347844 -313.998896) (xy 276.343884 -313.949842)
			(xy 276.005036 -313.949842) (xy 276.004541 -313.974449) (xy 275.996646 -314.023026) (xy 275.981062 -314.069707)
			(xy 275.958191 -314.113284) (xy 275.928626 -314.152628) (xy 275.893133 -314.18672) (xy 275.85263 -314.214676)
			(xy 275.808168 -314.235774) (xy 275.760897 -314.249466) (xy 275.712042 -314.255398) (xy 275.662867 -314.253417)
			(xy 275.614648 -314.243573) (xy 275.568632 -314.226121) (xy 275.526011 -314.201514) (xy 275.48789 -314.170389)
			(xy 275.455255 -314.133552) (xy 275.428952 -314.091956) (xy 275.409661 -314.04668) (xy 275.397884 -313.998896)
			(xy 275.393924 -313.949842) (xy 275.07692 -313.949842) (xy 275.076416 -313.97555) (xy 275.068373 -314.026332)
			(xy 275.052485 -314.075231) (xy 275.029142 -314.121043) (xy 274.998921 -314.162639) (xy 274.962565 -314.198995)
			(xy 274.920969 -314.229216) (xy 274.875157 -314.252559) (xy 274.826258 -314.268447) (xy 274.775476 -314.27649)
			(xy 274.72406 -314.27649) (xy 274.673278 -314.268447) (xy 274.624379 -314.252559) (xy 274.578567 -314.229216)
			(xy 274.536971 -314.198995) (xy 274.500615 -314.162639) (xy 274.470394 -314.121043) (xy 274.447051 -314.075231)
			(xy 274.431163 -314.026332) (xy 274.42312 -313.97555) (xy 274.104442 -313.97555) (xy 274.096726 -314.023026)
			(xy 274.081142 -314.069707) (xy 274.058271 -314.113284) (xy 274.028706 -314.152628) (xy 273.993213 -314.18672)
			(xy 273.95271 -314.214676) (xy 273.908248 -314.235774) (xy 273.860977 -314.249466) (xy 273.812122 -314.255398)
			(xy 273.762947 -314.253417) (xy 273.714728 -314.243573) (xy 273.668712 -314.226121) (xy 273.626091 -314.201514)
			(xy 273.58797 -314.170389) (xy 273.555335 -314.133552) (xy 273.529032 -314.091956) (xy 273.509741 -314.04668)
			(xy 273.497964 -313.998896) (xy 273.494004 -313.949842) (xy 273.177 -313.949842) (xy 273.176496 -313.97555)
			(xy 273.168453 -314.026332) (xy 273.152565 -314.075231) (xy 273.129222 -314.121043) (xy 273.099001 -314.162639)
			(xy 273.062645 -314.198995) (xy 273.021049 -314.229216) (xy 272.975237 -314.252559) (xy 272.926338 -314.268447)
			(xy 272.875556 -314.27649) (xy 272.82414 -314.27649) (xy 272.773358 -314.268447) (xy 272.724459 -314.252559)
			(xy 272.678647 -314.229216) (xy 272.637051 -314.198995) (xy 272.600695 -314.162639) (xy 272.570474 -314.121043)
			(xy 272.547131 -314.075231) (xy 272.531243 -314.026332) (xy 272.5232 -313.97555) (xy 272.204522 -313.97555)
			(xy 272.196806 -314.023026) (xy 272.181222 -314.069707) (xy 272.158351 -314.113284) (xy 272.128786 -314.152628)
			(xy 272.093293 -314.18672) (xy 272.05279 -314.214676) (xy 272.008328 -314.235774) (xy 271.961057 -314.249466)
			(xy 271.912202 -314.255398) (xy 271.863027 -314.253417) (xy 271.814808 -314.243573) (xy 271.768792 -314.226121)
			(xy 271.726171 -314.201514) (xy 271.68805 -314.170389) (xy 271.655415 -314.133552) (xy 271.629112 -314.091956)
			(xy 271.609821 -314.04668) (xy 271.598044 -313.998896) (xy 271.594084 -313.949842) (xy 271.27708 -313.949842)
			(xy 271.276576 -313.97555) (xy 271.268533 -314.026332) (xy 271.252645 -314.075231) (xy 271.229302 -314.121043)
			(xy 271.199081 -314.162639) (xy 271.162725 -314.198995) (xy 271.121129 -314.229216) (xy 271.075317 -314.252559)
			(xy 271.026418 -314.268447) (xy 270.975636 -314.27649) (xy 270.92422 -314.27649) (xy 270.873438 -314.268447)
			(xy 270.824539 -314.252559) (xy 270.778727 -314.229216) (xy 270.737131 -314.198995) (xy 270.700775 -314.162639)
			(xy 270.670554 -314.121043) (xy 270.647211 -314.075231) (xy 270.631323 -314.026332) (xy 270.62328 -313.97555)
			(xy 270.304348 -313.97555) (xy 270.296632 -314.023026) (xy 270.281048 -314.069707) (xy 270.258177 -314.113284)
			(xy 270.228612 -314.152628) (xy 270.193119 -314.18672) (xy 270.152616 -314.214676) (xy 270.108154 -314.235774)
			(xy 270.060883 -314.249466) (xy 270.012028 -314.255398) (xy 269.962853 -314.253417) (xy 269.914634 -314.243573)
			(xy 269.868618 -314.226121) (xy 269.825997 -314.201514) (xy 269.787876 -314.170389) (xy 269.755241 -314.133552)
			(xy 269.728938 -314.091956) (xy 269.709647 -314.04668) (xy 269.69787 -313.998896) (xy 269.69391 -313.949842)
			(xy 269.355062 -313.949842) (xy 269.354567 -313.974449) (xy 269.346672 -314.023026) (xy 269.331088 -314.069707)
			(xy 269.308217 -314.113284) (xy 269.278652 -314.152628) (xy 269.243159 -314.18672) (xy 269.202656 -314.214676)
			(xy 269.158194 -314.235774) (xy 269.110923 -314.249466) (xy 269.062068 -314.255398) (xy 269.012893 -314.253417)
			(xy 268.964674 -314.243573) (xy 268.918658 -314.226121) (xy 268.876037 -314.201514) (xy 268.837916 -314.170389)
			(xy 268.805281 -314.133552) (xy 268.778978 -314.091956) (xy 268.759687 -314.04668) (xy 268.74791 -313.998896)
			(xy 268.74395 -313.949842) (xy 266.888151 -313.949842) (xy 266.851161 -313.980625) (xy 266.803555 -314.009679)
			(xy 266.752226 -314.031491) (xy 266.698269 -314.045597) (xy 266.642832 -314.051697) (xy 266.587098 -314.04966)
			(xy 266.532255 -314.03953) (xy 266.479471 -314.021523) (xy 266.429871 -313.996022) (xy 266.384513 -313.963571)
			(xy 266.344364 -313.924862) (xy 266.310278 -313.880719) (xy 266.282982 -313.832084) (xy 266.263059 -313.779993)
			(xy 266.250933 -313.725556) (xy 266.246862 -313.669934) (xy 248.814844 -313.669934) (xy 248.814844 -314.899548)
			(xy 267.793482 -314.899548) (xy 267.797442 -314.850494) (xy 267.809219 -314.80271) (xy 267.82851 -314.757434)
			(xy 267.854813 -314.715838) (xy 267.887448 -314.679001) (xy 267.925569 -314.647876) (xy 267.96819 -314.623269)
			(xy 268.014206 -314.605817) (xy 268.062425 -314.595973) (xy 268.1116 -314.593992) (xy 268.160455 -314.599924)
			(xy 268.207726 -314.613616) (xy 268.252188 -314.634714) (xy 268.292691 -314.66267) (xy 268.328184 -314.696762)
			(xy 268.357749 -314.736106) (xy 268.38062 -314.779683) (xy 268.396204 -314.826364) (xy 268.404099 -314.874941)
			(xy 268.404594 -314.899548) (xy 268.404099 -314.924155) (xy 268.403879 -314.92551) (xy 268.723106 -314.92551)
			(xy 268.723106 -314.874094) (xy 268.731149 -314.823312) (xy 268.747037 -314.774413) (xy 268.77038 -314.728601)
			(xy 268.800601 -314.687005) (xy 268.836957 -314.650649) (xy 268.878553 -314.620428) (xy 268.924365 -314.597085)
			(xy 268.973264 -314.581197) (xy 269.024046 -314.573154) (xy 269.075462 -314.573154) (xy 269.126244 -314.581197)
			(xy 269.175143 -314.597085) (xy 269.220955 -314.620428) (xy 269.262551 -314.650649) (xy 269.298907 -314.687005)
			(xy 269.329128 -314.728601) (xy 269.352471 -314.774413) (xy 269.368359 -314.823312) (xy 269.376402 -314.874094)
			(xy 269.376906 -314.899802) (xy 269.376402 -314.92551) (xy 269.673066 -314.92551) (xy 269.673066 -314.874094)
			(xy 269.681109 -314.823312) (xy 269.696997 -314.774413) (xy 269.72034 -314.728601) (xy 269.750561 -314.687005)
			(xy 269.786917 -314.650649) (xy 269.828513 -314.620428) (xy 269.874325 -314.597085) (xy 269.923224 -314.581197)
			(xy 269.974006 -314.573154) (xy 270.025422 -314.573154) (xy 270.076204 -314.581197) (xy 270.125103 -314.597085)
			(xy 270.170915 -314.620428) (xy 270.212511 -314.650649) (xy 270.248867 -314.687005) (xy 270.279088 -314.728601)
			(xy 270.302431 -314.774413) (xy 270.318319 -314.823312) (xy 270.326362 -314.874094) (xy 270.326866 -314.899802)
			(xy 270.644124 -314.899802) (xy 270.648084 -314.850748) (xy 270.659861 -314.802964) (xy 270.679152 -314.757688)
			(xy 270.705455 -314.716092) (xy 270.73809 -314.679255) (xy 270.776211 -314.64813) (xy 270.818832 -314.623523)
			(xy 270.864848 -314.606071) (xy 270.913067 -314.596227) (xy 270.962242 -314.594246) (xy 271.011097 -314.600178)
			(xy 271.058368 -314.61387) (xy 271.10283 -314.634968) (xy 271.143333 -314.662924) (xy 271.178826 -314.697016)
			(xy 271.208391 -314.73636) (xy 271.231262 -314.779937) (xy 271.246846 -314.826618) (xy 271.254741 -314.875195)
			(xy 271.255236 -314.899802) (xy 271.594084 -314.899802) (xy 271.598044 -314.850748) (xy 271.609821 -314.802964)
			(xy 271.629112 -314.757688) (xy 271.655415 -314.716092) (xy 271.68805 -314.679255) (xy 271.726171 -314.64813)
			(xy 271.768792 -314.623523) (xy 271.814808 -314.606071) (xy 271.863027 -314.596227) (xy 271.912202 -314.594246)
			(xy 271.961057 -314.600178) (xy 272.008328 -314.61387) (xy 272.05279 -314.634968) (xy 272.093293 -314.662924)
			(xy 272.128786 -314.697016) (xy 272.158351 -314.73636) (xy 272.181222 -314.779937) (xy 272.196806 -314.826618)
			(xy 272.204701 -314.875195) (xy 272.205196 -314.899802) (xy 272.544044 -314.899802) (xy 272.548004 -314.850748)
			(xy 272.559781 -314.802964) (xy 272.579072 -314.757688) (xy 272.605375 -314.716092) (xy 272.63801 -314.679255)
			(xy 272.676131 -314.64813) (xy 272.718752 -314.623523) (xy 272.764768 -314.606071) (xy 272.812987 -314.596227)
			(xy 272.862162 -314.594246) (xy 272.911017 -314.600178) (xy 272.958288 -314.61387) (xy 273.00275 -314.634968)
			(xy 273.043253 -314.662924) (xy 273.078746 -314.697016) (xy 273.108311 -314.73636) (xy 273.131182 -314.779937)
			(xy 273.146766 -314.826618) (xy 273.154661 -314.875195) (xy 273.155156 -314.899802) (xy 273.494004 -314.899802)
			(xy 273.497964 -314.850748) (xy 273.509741 -314.802964) (xy 273.529032 -314.757688) (xy 273.555335 -314.716092)
			(xy 273.58797 -314.679255) (xy 273.626091 -314.64813) (xy 273.668712 -314.623523) (xy 273.714728 -314.606071)
			(xy 273.762947 -314.596227) (xy 273.812122 -314.594246) (xy 273.860977 -314.600178) (xy 273.908248 -314.61387)
			(xy 273.95271 -314.634968) (xy 273.993213 -314.662924) (xy 274.028706 -314.697016) (xy 274.058271 -314.73636)
			(xy 274.081142 -314.779937) (xy 274.096726 -314.826618) (xy 274.104621 -314.875195) (xy 274.105116 -314.899802)
			(xy 274.443964 -314.899802) (xy 274.447924 -314.850748) (xy 274.459701 -314.802964) (xy 274.478992 -314.757688)
			(xy 274.505295 -314.716092) (xy 274.53793 -314.679255) (xy 274.576051 -314.64813) (xy 274.618672 -314.623523)
			(xy 274.664688 -314.606071) (xy 274.712907 -314.596227) (xy 274.762082 -314.594246) (xy 274.810937 -314.600178)
			(xy 274.858208 -314.61387) (xy 274.90267 -314.634968) (xy 274.943173 -314.662924) (xy 274.978666 -314.697016)
			(xy 275.008231 -314.73636) (xy 275.031102 -314.779937) (xy 275.046686 -314.826618) (xy 275.054581 -314.875195)
			(xy 275.055076 -314.899802) (xy 275.393924 -314.899802) (xy 275.397884 -314.850748) (xy 275.409661 -314.802964)
			(xy 275.428952 -314.757688) (xy 275.455255 -314.716092) (xy 275.48789 -314.679255) (xy 275.526011 -314.64813)
			(xy 275.568632 -314.623523) (xy 275.614648 -314.606071) (xy 275.662867 -314.596227) (xy 275.712042 -314.594246)
			(xy 275.760897 -314.600178) (xy 275.808168 -314.61387) (xy 275.85263 -314.634968) (xy 275.893133 -314.662924)
			(xy 275.928626 -314.697016) (xy 275.958191 -314.73636) (xy 275.981062 -314.779937) (xy 275.996646 -314.826618)
			(xy 276.004541 -314.875195) (xy 276.005036 -314.899802) (xy 276.343884 -314.899802) (xy 276.347844 -314.850748)
			(xy 276.359621 -314.802964) (xy 276.378912 -314.757688) (xy 276.405215 -314.716092) (xy 276.43785 -314.679255)
			(xy 276.475971 -314.64813) (xy 276.518592 -314.623523) (xy 276.564608 -314.606071) (xy 276.612827 -314.596227)
			(xy 276.662002 -314.594246) (xy 276.710857 -314.600178) (xy 276.758128 -314.61387) (xy 276.80259 -314.634968)
			(xy 276.843093 -314.662924) (xy 276.878586 -314.697016) (xy 276.908151 -314.73636) (xy 276.931022 -314.779937)
			(xy 276.946606 -314.826618) (xy 276.954501 -314.875195) (xy 276.954996 -314.899802) (xy 277.294098 -314.899802)
			(xy 277.298058 -314.850748) (xy 277.309835 -314.802964) (xy 277.329126 -314.757688) (xy 277.355429 -314.716092)
			(xy 277.388064 -314.679255) (xy 277.426185 -314.64813) (xy 277.468806 -314.623523) (xy 277.514822 -314.606071)
			(xy 277.563041 -314.596227) (xy 277.612216 -314.594246) (xy 277.661071 -314.600178) (xy 277.708342 -314.61387)
			(xy 277.752804 -314.634968) (xy 277.793307 -314.662924) (xy 277.8288 -314.697016) (xy 277.858365 -314.73636)
			(xy 277.881236 -314.779937) (xy 277.89682 -314.826618) (xy 277.904715 -314.875195) (xy 277.90521 -314.899802)
			(xy 278.244058 -314.899802) (xy 278.248018 -314.850748) (xy 278.259795 -314.802964) (xy 278.279086 -314.757688)
			(xy 278.305389 -314.716092) (xy 278.338024 -314.679255) (xy 278.376145 -314.64813) (xy 278.418766 -314.623523)
			(xy 278.464782 -314.606071) (xy 278.513001 -314.596227) (xy 278.562176 -314.594246) (xy 278.611031 -314.600178)
			(xy 278.658302 -314.61387) (xy 278.702764 -314.634968) (xy 278.743267 -314.662924) (xy 278.77876 -314.697016)
			(xy 278.808325 -314.73636) (xy 278.831196 -314.779937) (xy 278.84678 -314.826618) (xy 278.854675 -314.875195)
			(xy 278.85517 -314.899802) (xy 279.194018 -314.899802) (xy 279.197978 -314.850748) (xy 279.209755 -314.802964)
			(xy 279.229046 -314.757688) (xy 279.255349 -314.716092) (xy 279.287984 -314.679255) (xy 279.326105 -314.64813)
			(xy 279.368726 -314.623523) (xy 279.414742 -314.606071) (xy 279.462961 -314.596227) (xy 279.512136 -314.594246)
			(xy 279.560991 -314.600178) (xy 279.608262 -314.61387) (xy 279.652724 -314.634968) (xy 279.693227 -314.662924)
			(xy 279.72872 -314.697016) (xy 279.758285 -314.73636) (xy 279.781156 -314.779937) (xy 279.79674 -314.826618)
			(xy 279.804635 -314.875195) (xy 279.80513 -314.899802) (xy 280.143978 -314.899802) (xy 280.147938 -314.850748)
			(xy 280.159715 -314.802964) (xy 280.179006 -314.757688) (xy 280.205309 -314.716092) (xy 280.237944 -314.679255)
			(xy 280.276065 -314.64813) (xy 280.318686 -314.623523) (xy 280.364702 -314.606071) (xy 280.412921 -314.596227)
			(xy 280.462096 -314.594246) (xy 280.510951 -314.600178) (xy 280.558222 -314.61387) (xy 280.602684 -314.634968)
			(xy 280.643187 -314.662924) (xy 280.67868 -314.697016) (xy 280.708245 -314.73636) (xy 280.731116 -314.779937)
			(xy 280.7467 -314.826618) (xy 280.754595 -314.875195) (xy 280.75509 -314.899802) (xy 281.093938 -314.899802)
			(xy 281.097898 -314.850748) (xy 281.109675 -314.802964) (xy 281.128966 -314.757688) (xy 281.155269 -314.716092)
			(xy 281.187904 -314.679255) (xy 281.226025 -314.64813) (xy 281.268646 -314.623523) (xy 281.314662 -314.606071)
			(xy 281.362881 -314.596227) (xy 281.412056 -314.594246) (xy 281.460911 -314.600178) (xy 281.508182 -314.61387)
			(xy 281.552644 -314.634968) (xy 281.593147 -314.662924) (xy 281.62864 -314.697016) (xy 281.658205 -314.73636)
			(xy 281.681076 -314.779937) (xy 281.69666 -314.826618) (xy 281.704555 -314.875195) (xy 281.70505 -314.899802)
			(xy 282.043898 -314.899802) (xy 282.047858 -314.850748) (xy 282.059635 -314.802964) (xy 282.078926 -314.757688)
			(xy 282.105229 -314.716092) (xy 282.137864 -314.679255) (xy 282.175985 -314.64813) (xy 282.218606 -314.623523)
			(xy 282.264622 -314.606071) (xy 282.312841 -314.596227) (xy 282.362016 -314.594246) (xy 282.410871 -314.600178)
			(xy 282.458142 -314.61387) (xy 282.502604 -314.634968) (xy 282.543107 -314.662924) (xy 282.5786 -314.697016)
			(xy 282.608165 -314.73636) (xy 282.631036 -314.779937) (xy 282.64662 -314.826618) (xy 282.654515 -314.875195)
			(xy 282.65501 -314.899802) (xy 282.994112 -314.899802) (xy 282.998072 -314.850748) (xy 283.009849 -314.802964)
			(xy 283.02914 -314.757688) (xy 283.055443 -314.716092) (xy 283.088078 -314.679255) (xy 283.126199 -314.64813)
			(xy 283.16882 -314.623523) (xy 283.214836 -314.606071) (xy 283.263055 -314.596227) (xy 283.31223 -314.594246)
			(xy 283.361085 -314.600178) (xy 283.408356 -314.61387) (xy 283.452818 -314.634968) (xy 283.493321 -314.662924)
			(xy 283.528814 -314.697016) (xy 283.558379 -314.73636) (xy 283.58125 -314.779937) (xy 283.596834 -314.826618)
			(xy 283.604729 -314.875195) (xy 283.605224 -314.899802) (xy 283.944072 -314.899802) (xy 283.948032 -314.850748)
			(xy 283.959809 -314.802964) (xy 283.9791 -314.757688) (xy 284.005403 -314.716092) (xy 284.038038 -314.679255)
			(xy 284.076159 -314.64813) (xy 284.11878 -314.623523) (xy 284.164796 -314.606071) (xy 284.213015 -314.596227)
			(xy 284.26219 -314.594246) (xy 284.311045 -314.600178) (xy 284.358316 -314.61387) (xy 284.402778 -314.634968)
			(xy 284.443281 -314.662924) (xy 284.478774 -314.697016) (xy 284.508339 -314.73636) (xy 284.53121 -314.779937)
			(xy 284.546794 -314.826618) (xy 284.554689 -314.875195) (xy 284.555184 -314.899802) (xy 284.894032 -314.899802)
			(xy 284.897992 -314.850748) (xy 284.909769 -314.802964) (xy 284.92906 -314.757688) (xy 284.955363 -314.716092)
			(xy 284.987998 -314.679255) (xy 285.026119 -314.64813) (xy 285.06874 -314.623523) (xy 285.114756 -314.606071)
			(xy 285.162975 -314.596227) (xy 285.21215 -314.594246) (xy 285.261005 -314.600178) (xy 285.308276 -314.61387)
			(xy 285.352738 -314.634968) (xy 285.393241 -314.662924) (xy 285.428734 -314.697016) (xy 285.458299 -314.73636)
			(xy 285.48117 -314.779937) (xy 285.496754 -314.826618) (xy 285.504649 -314.875195) (xy 285.505144 -314.899802)
			(xy 285.843992 -314.899802) (xy 285.847952 -314.850748) (xy 285.859729 -314.802964) (xy 285.87902 -314.757688)
			(xy 285.905323 -314.716092) (xy 285.937958 -314.679255) (xy 285.976079 -314.64813) (xy 286.0187 -314.623523)
			(xy 286.064716 -314.606071) (xy 286.112935 -314.596227) (xy 286.16211 -314.594246) (xy 286.210965 -314.600178)
			(xy 286.258236 -314.61387) (xy 286.302698 -314.634968) (xy 286.343201 -314.662924) (xy 286.378694 -314.697016)
			(xy 286.408259 -314.73636) (xy 286.43113 -314.779937) (xy 286.446714 -314.826618) (xy 286.454609 -314.875195)
			(xy 286.455104 -314.899802) (xy 286.793952 -314.899802) (xy 286.797912 -314.850748) (xy 286.809689 -314.802964)
			(xy 286.82898 -314.757688) (xy 286.855283 -314.716092) (xy 286.887918 -314.679255) (xy 286.926039 -314.64813)
			(xy 286.96866 -314.623523) (xy 287.014676 -314.606071) (xy 287.062895 -314.596227) (xy 287.11207 -314.594246)
			(xy 287.160925 -314.600178) (xy 287.208196 -314.61387) (xy 287.252658 -314.634968) (xy 287.293161 -314.662924)
			(xy 287.328654 -314.697016) (xy 287.358219 -314.73636) (xy 287.38109 -314.779937) (xy 287.396674 -314.826618)
			(xy 287.404569 -314.875195) (xy 287.405064 -314.899802) (xy 287.743912 -314.899802) (xy 287.747872 -314.850748)
			(xy 287.759649 -314.802964) (xy 287.77894 -314.757688) (xy 287.805243 -314.716092) (xy 287.837878 -314.679255)
			(xy 287.875999 -314.64813) (xy 287.91862 -314.623523) (xy 287.964636 -314.606071) (xy 288.012855 -314.596227)
			(xy 288.06203 -314.594246) (xy 288.110885 -314.600178) (xy 288.158156 -314.61387) (xy 288.202618 -314.634968)
			(xy 288.243121 -314.662924) (xy 288.278614 -314.697016) (xy 288.308179 -314.73636) (xy 288.33105 -314.779937)
			(xy 288.346634 -314.826618) (xy 288.354529 -314.875195) (xy 288.355024 -314.899802) (xy 288.694126 -314.899802)
			(xy 288.698086 -314.850748) (xy 288.709863 -314.802964) (xy 288.729154 -314.757688) (xy 288.755457 -314.716092)
			(xy 288.788092 -314.679255) (xy 288.826213 -314.64813) (xy 288.868834 -314.623523) (xy 288.91485 -314.606071)
			(xy 288.963069 -314.596227) (xy 289.012244 -314.594246) (xy 289.061099 -314.600178) (xy 289.10837 -314.61387)
			(xy 289.152832 -314.634968) (xy 289.193335 -314.662924) (xy 289.228828 -314.697016) (xy 289.258393 -314.73636)
			(xy 289.281264 -314.779937) (xy 289.296848 -314.826618) (xy 289.304743 -314.875195) (xy 289.305238 -314.899802)
			(xy 289.644086 -314.899802) (xy 289.648046 -314.850748) (xy 289.659823 -314.802964) (xy 289.679114 -314.757688)
			(xy 289.705417 -314.716092) (xy 289.738052 -314.679255) (xy 289.776173 -314.64813) (xy 289.818794 -314.623523)
			(xy 289.86481 -314.606071) (xy 289.913029 -314.596227) (xy 289.962204 -314.594246) (xy 290.011059 -314.600178)
			(xy 290.05833 -314.61387) (xy 290.102792 -314.634968) (xy 290.143295 -314.662924) (xy 290.178788 -314.697016)
			(xy 290.208353 -314.73636) (xy 290.231224 -314.779937) (xy 290.246808 -314.826618) (xy 290.254703 -314.875195)
			(xy 290.255198 -314.899802) (xy 290.594046 -314.899802) (xy 290.598006 -314.850748) (xy 290.609783 -314.802964)
			(xy 290.629074 -314.757688) (xy 290.655377 -314.716092) (xy 290.688012 -314.679255) (xy 290.726133 -314.64813)
			(xy 290.768754 -314.623523) (xy 290.81477 -314.606071) (xy 290.862989 -314.596227) (xy 290.912164 -314.594246)
			(xy 290.961019 -314.600178) (xy 291.00829 -314.61387) (xy 291.052752 -314.634968) (xy 291.093255 -314.662924)
			(xy 291.128748 -314.697016) (xy 291.158313 -314.73636) (xy 291.181184 -314.779937) (xy 291.196768 -314.826618)
			(xy 291.204663 -314.875195) (xy 291.205158 -314.899802) (xy 291.544006 -314.899802) (xy 291.547966 -314.850748)
			(xy 291.559743 -314.802964) (xy 291.579034 -314.757688) (xy 291.605337 -314.716092) (xy 291.637972 -314.679255)
			(xy 291.676093 -314.64813) (xy 291.718714 -314.623523) (xy 291.76473 -314.606071) (xy 291.812949 -314.596227)
			(xy 291.862124 -314.594246) (xy 291.910979 -314.600178) (xy 291.95825 -314.61387) (xy 292.002712 -314.634968)
			(xy 292.043215 -314.662924) (xy 292.078708 -314.697016) (xy 292.108273 -314.73636) (xy 292.131144 -314.779937)
			(xy 292.146728 -314.826618) (xy 292.154623 -314.875195) (xy 292.155118 -314.899802) (xy 292.493966 -314.899802)
			(xy 292.497926 -314.850748) (xy 292.509703 -314.802964) (xy 292.528994 -314.757688) (xy 292.555297 -314.716092)
			(xy 292.587932 -314.679255) (xy 292.626053 -314.64813) (xy 292.668674 -314.623523) (xy 292.71469 -314.606071)
			(xy 292.762909 -314.596227) (xy 292.812084 -314.594246) (xy 292.860939 -314.600178) (xy 292.90821 -314.61387)
			(xy 292.952672 -314.634968) (xy 292.993175 -314.662924) (xy 293.028668 -314.697016) (xy 293.058233 -314.73636)
			(xy 293.081104 -314.779937) (xy 293.096688 -314.826618) (xy 293.104583 -314.875195) (xy 293.105078 -314.899802)
			(xy 293.443926 -314.899802) (xy 293.447886 -314.850748) (xy 293.459663 -314.802964) (xy 293.478954 -314.757688)
			(xy 293.505257 -314.716092) (xy 293.537892 -314.679255) (xy 293.576013 -314.64813) (xy 293.618634 -314.623523)
			(xy 293.66465 -314.606071) (xy 293.712869 -314.596227) (xy 293.762044 -314.594246) (xy 293.810899 -314.600178)
			(xy 293.85817 -314.61387) (xy 293.902632 -314.634968) (xy 293.943135 -314.662924) (xy 293.978628 -314.697016)
			(xy 294.008193 -314.73636) (xy 294.031064 -314.779937) (xy 294.046648 -314.826618) (xy 294.054543 -314.875195)
			(xy 294.055038 -314.899802) (xy 294.393886 -314.899802) (xy 294.397846 -314.850748) (xy 294.409623 -314.802964)
			(xy 294.428914 -314.757688) (xy 294.455217 -314.716092) (xy 294.487852 -314.679255) (xy 294.525973 -314.64813)
			(xy 294.568594 -314.623523) (xy 294.61461 -314.606071) (xy 294.662829 -314.596227) (xy 294.712004 -314.594246)
			(xy 294.760859 -314.600178) (xy 294.80813 -314.61387) (xy 294.852592 -314.634968) (xy 294.893095 -314.662924)
			(xy 294.928588 -314.697016) (xy 294.958153 -314.73636) (xy 294.981024 -314.779937) (xy 294.996608 -314.826618)
			(xy 295.004503 -314.875195) (xy 295.004998 -314.899802) (xy 295.3441 -314.899802) (xy 295.34806 -314.850748)
			(xy 295.359837 -314.802964) (xy 295.379128 -314.757688) (xy 295.405431 -314.716092) (xy 295.438066 -314.679255)
			(xy 295.476187 -314.64813) (xy 295.518808 -314.623523) (xy 295.564824 -314.606071) (xy 295.613043 -314.596227)
			(xy 295.662218 -314.594246) (xy 295.711073 -314.600178) (xy 295.758344 -314.61387) (xy 295.802806 -314.634968)
			(xy 295.843309 -314.662924) (xy 295.878802 -314.697016) (xy 295.908367 -314.73636) (xy 295.931238 -314.779937)
			(xy 295.946822 -314.826618) (xy 295.954717 -314.875195) (xy 295.955212 -314.899802) (xy 296.29406 -314.899802)
			(xy 296.29802 -314.850748) (xy 296.309797 -314.802964) (xy 296.329088 -314.757688) (xy 296.355391 -314.716092)
			(xy 296.388026 -314.679255) (xy 296.426147 -314.64813) (xy 296.468768 -314.623523) (xy 296.514784 -314.606071)
			(xy 296.563003 -314.596227) (xy 296.612178 -314.594246) (xy 296.661033 -314.600178) (xy 296.708304 -314.61387)
			(xy 296.752766 -314.634968) (xy 296.793269 -314.662924) (xy 296.828762 -314.697016) (xy 296.858327 -314.73636)
			(xy 296.881198 -314.779937) (xy 296.896782 -314.826618) (xy 296.904677 -314.875195) (xy 296.905172 -314.899802)
			(xy 297.24402 -314.899802) (xy 297.24798 -314.850748) (xy 297.259757 -314.802964) (xy 297.279048 -314.757688)
			(xy 297.305351 -314.716092) (xy 297.337986 -314.679255) (xy 297.376107 -314.64813) (xy 297.418728 -314.623523)
			(xy 297.464744 -314.606071) (xy 297.512963 -314.596227) (xy 297.562138 -314.594246) (xy 297.610993 -314.600178)
			(xy 297.658264 -314.61387) (xy 297.702726 -314.634968) (xy 297.743229 -314.662924) (xy 297.778722 -314.697016)
			(xy 297.808287 -314.73636) (xy 297.831158 -314.779937) (xy 297.846742 -314.826618) (xy 297.854637 -314.875195)
			(xy 297.855132 -314.899802) (xy 298.19398 -314.899802) (xy 298.19794 -314.850748) (xy 298.209717 -314.802964)
			(xy 298.229008 -314.757688) (xy 298.255311 -314.716092) (xy 298.287946 -314.679255) (xy 298.326067 -314.64813)
			(xy 298.368688 -314.623523) (xy 298.414704 -314.606071) (xy 298.462923 -314.596227) (xy 298.512098 -314.594246)
			(xy 298.560953 -314.600178) (xy 298.608224 -314.61387) (xy 298.652686 -314.634968) (xy 298.693189 -314.662924)
			(xy 298.728682 -314.697016) (xy 298.758247 -314.73636) (xy 298.781118 -314.779937) (xy 298.796702 -314.826618)
			(xy 298.804597 -314.875195) (xy 298.805092 -314.899802) (xy 299.14394 -314.899802) (xy 299.1479 -314.850748)
			(xy 299.159677 -314.802964) (xy 299.178968 -314.757688) (xy 299.205271 -314.716092) (xy 299.237906 -314.679255)
			(xy 299.276027 -314.64813) (xy 299.318648 -314.623523) (xy 299.364664 -314.606071) (xy 299.412883 -314.596227)
			(xy 299.462058 -314.594246) (xy 299.510913 -314.600178) (xy 299.558184 -314.61387) (xy 299.602646 -314.634968)
			(xy 299.643149 -314.662924) (xy 299.678642 -314.697016) (xy 299.708207 -314.73636) (xy 299.731078 -314.779937)
			(xy 299.746662 -314.826618) (xy 299.754557 -314.875195) (xy 299.755052 -314.899802) (xy 300.0939 -314.899802)
			(xy 300.09786 -314.850748) (xy 300.109637 -314.802964) (xy 300.128928 -314.757688) (xy 300.155231 -314.716092)
			(xy 300.187866 -314.679255) (xy 300.225987 -314.64813) (xy 300.268608 -314.623523) (xy 300.314624 -314.606071)
			(xy 300.362843 -314.596227) (xy 300.412018 -314.594246) (xy 300.460873 -314.600178) (xy 300.508144 -314.61387)
			(xy 300.552606 -314.634968) (xy 300.593109 -314.662924) (xy 300.628602 -314.697016) (xy 300.658167 -314.73636)
			(xy 300.681038 -314.779937) (xy 300.696622 -314.826618) (xy 300.704517 -314.875195) (xy 300.705012 -314.899802)
			(xy 301.044114 -314.899802) (xy 301.048074 -314.850748) (xy 301.059851 -314.802964) (xy 301.079142 -314.757688)
			(xy 301.105445 -314.716092) (xy 301.13808 -314.679255) (xy 301.176201 -314.64813) (xy 301.218822 -314.623523)
			(xy 301.264838 -314.606071) (xy 301.313057 -314.596227) (xy 301.362232 -314.594246) (xy 301.411087 -314.600178)
			(xy 301.458358 -314.61387) (xy 301.50282 -314.634968) (xy 301.543323 -314.662924) (xy 301.578816 -314.697016)
			(xy 301.608381 -314.73636) (xy 301.631252 -314.779937) (xy 301.646836 -314.826618) (xy 301.654731 -314.875195)
			(xy 301.655226 -314.899802) (xy 301.994074 -314.899802) (xy 301.998034 -314.850748) (xy 302.009811 -314.802964)
			(xy 302.029102 -314.757688) (xy 302.055405 -314.716092) (xy 302.08804 -314.679255) (xy 302.126161 -314.64813)
			(xy 302.168782 -314.623523) (xy 302.214798 -314.606071) (xy 302.263017 -314.596227) (xy 302.312192 -314.594246)
			(xy 302.361047 -314.600178) (xy 302.408318 -314.61387) (xy 302.45278 -314.634968) (xy 302.493283 -314.662924)
			(xy 302.528776 -314.697016) (xy 302.558341 -314.73636) (xy 302.581212 -314.779937) (xy 302.596796 -314.826618)
			(xy 302.604691 -314.875195) (xy 302.605186 -314.899802) (xy 302.944034 -314.899802) (xy 302.947994 -314.850748)
			(xy 302.959771 -314.802964) (xy 302.979062 -314.757688) (xy 303.005365 -314.716092) (xy 303.038 -314.679255)
			(xy 303.076121 -314.64813) (xy 303.118742 -314.623523) (xy 303.164758 -314.606071) (xy 303.212977 -314.596227)
			(xy 303.262152 -314.594246) (xy 303.311007 -314.600178) (xy 303.358278 -314.61387) (xy 303.40274 -314.634968)
			(xy 303.443243 -314.662924) (xy 303.478736 -314.697016) (xy 303.508301 -314.73636) (xy 303.531172 -314.779937)
			(xy 303.546756 -314.826618) (xy 303.554651 -314.875195) (xy 303.555146 -314.899802) (xy 303.554651 -314.924409)
			(xy 303.546756 -314.972986) (xy 303.531172 -315.019667) (xy 303.508301 -315.063244) (xy 303.478736 -315.102588)
			(xy 303.443243 -315.13668) (xy 303.40274 -315.164636) (xy 303.358278 -315.185734) (xy 303.311007 -315.199426)
			(xy 303.262152 -315.205358) (xy 303.212977 -315.203377) (xy 303.164758 -315.193533) (xy 303.118742 -315.176081)
			(xy 303.076121 -315.151474) (xy 303.038 -315.120349) (xy 303.005365 -315.083512) (xy 302.979062 -315.041916)
			(xy 302.959771 -314.99664) (xy 302.947994 -314.948856) (xy 302.944034 -314.899802) (xy 302.605186 -314.899802)
			(xy 302.604691 -314.924409) (xy 302.596796 -314.972986) (xy 302.581212 -315.019667) (xy 302.558341 -315.063244)
			(xy 302.528776 -315.102588) (xy 302.493283 -315.13668) (xy 302.45278 -315.164636) (xy 302.408318 -315.185734)
			(xy 302.361047 -315.199426) (xy 302.312192 -315.205358) (xy 302.263017 -315.203377) (xy 302.214798 -315.193533)
			(xy 302.168782 -315.176081) (xy 302.126161 -315.151474) (xy 302.08804 -315.120349) (xy 302.055405 -315.083512)
			(xy 302.029102 -315.041916) (xy 302.009811 -314.99664) (xy 301.998034 -314.948856) (xy 301.994074 -314.899802)
			(xy 301.655226 -314.899802) (xy 301.654731 -314.924409) (xy 301.646836 -314.972986) (xy 301.631252 -315.019667)
			(xy 301.608381 -315.063244) (xy 301.578816 -315.102588) (xy 301.543323 -315.13668) (xy 301.50282 -315.164636)
			(xy 301.458358 -315.185734) (xy 301.411087 -315.199426) (xy 301.362232 -315.205358) (xy 301.313057 -315.203377)
			(xy 301.264838 -315.193533) (xy 301.218822 -315.176081) (xy 301.176201 -315.151474) (xy 301.13808 -315.120349)
			(xy 301.105445 -315.083512) (xy 301.079142 -315.041916) (xy 301.059851 -314.99664) (xy 301.048074 -314.948856)
			(xy 301.044114 -314.899802) (xy 300.705012 -314.899802) (xy 300.704517 -314.924409) (xy 300.696622 -314.972986)
			(xy 300.681038 -315.019667) (xy 300.658167 -315.063244) (xy 300.628602 -315.102588) (xy 300.593109 -315.13668)
			(xy 300.552606 -315.164636) (xy 300.508144 -315.185734) (xy 300.460873 -315.199426) (xy 300.412018 -315.205358)
			(xy 300.362843 -315.203377) (xy 300.314624 -315.193533) (xy 300.268608 -315.176081) (xy 300.225987 -315.151474)
			(xy 300.187866 -315.120349) (xy 300.155231 -315.083512) (xy 300.128928 -315.041916) (xy 300.109637 -314.99664)
			(xy 300.09786 -314.948856) (xy 300.0939 -314.899802) (xy 299.755052 -314.899802) (xy 299.754557 -314.924409)
			(xy 299.746662 -314.972986) (xy 299.731078 -315.019667) (xy 299.708207 -315.063244) (xy 299.678642 -315.102588)
			(xy 299.643149 -315.13668) (xy 299.602646 -315.164636) (xy 299.558184 -315.185734) (xy 299.510913 -315.199426)
			(xy 299.462058 -315.205358) (xy 299.412883 -315.203377) (xy 299.364664 -315.193533) (xy 299.318648 -315.176081)
			(xy 299.276027 -315.151474) (xy 299.237906 -315.120349) (xy 299.205271 -315.083512) (xy 299.178968 -315.041916)
			(xy 299.159677 -314.99664) (xy 299.1479 -314.948856) (xy 299.14394 -314.899802) (xy 298.805092 -314.899802)
			(xy 298.804597 -314.924409) (xy 298.796702 -314.972986) (xy 298.781118 -315.019667) (xy 298.758247 -315.063244)
			(xy 298.728682 -315.102588) (xy 298.693189 -315.13668) (xy 298.652686 -315.164636) (xy 298.608224 -315.185734)
			(xy 298.560953 -315.199426) (xy 298.512098 -315.205358) (xy 298.462923 -315.203377) (xy 298.414704 -315.193533)
			(xy 298.368688 -315.176081) (xy 298.326067 -315.151474) (xy 298.287946 -315.120349) (xy 298.255311 -315.083512)
			(xy 298.229008 -315.041916) (xy 298.209717 -314.99664) (xy 298.19794 -314.948856) (xy 298.19398 -314.899802)
			(xy 297.855132 -314.899802) (xy 297.854637 -314.924409) (xy 297.846742 -314.972986) (xy 297.831158 -315.019667)
			(xy 297.808287 -315.063244) (xy 297.778722 -315.102588) (xy 297.743229 -315.13668) (xy 297.702726 -315.164636)
			(xy 297.658264 -315.185734) (xy 297.610993 -315.199426) (xy 297.562138 -315.205358) (xy 297.512963 -315.203377)
			(xy 297.464744 -315.193533) (xy 297.418728 -315.176081) (xy 297.376107 -315.151474) (xy 297.337986 -315.120349)
			(xy 297.305351 -315.083512) (xy 297.279048 -315.041916) (xy 297.259757 -314.99664) (xy 297.24798 -314.948856)
			(xy 297.24402 -314.899802) (xy 296.905172 -314.899802) (xy 296.904677 -314.924409) (xy 296.896782 -314.972986)
			(xy 296.881198 -315.019667) (xy 296.858327 -315.063244) (xy 296.828762 -315.102588) (xy 296.793269 -315.13668)
			(xy 296.752766 -315.164636) (xy 296.708304 -315.185734) (xy 296.661033 -315.199426) (xy 296.612178 -315.205358)
			(xy 296.563003 -315.203377) (xy 296.514784 -315.193533) (xy 296.468768 -315.176081) (xy 296.426147 -315.151474)
			(xy 296.388026 -315.120349) (xy 296.355391 -315.083512) (xy 296.329088 -315.041916) (xy 296.309797 -314.99664)
			(xy 296.29802 -314.948856) (xy 296.29406 -314.899802) (xy 295.955212 -314.899802) (xy 295.954717 -314.924409)
			(xy 295.946822 -314.972986) (xy 295.931238 -315.019667) (xy 295.908367 -315.063244) (xy 295.878802 -315.102588)
			(xy 295.843309 -315.13668) (xy 295.802806 -315.164636) (xy 295.758344 -315.185734) (xy 295.711073 -315.199426)
			(xy 295.662218 -315.205358) (xy 295.613043 -315.203377) (xy 295.564824 -315.193533) (xy 295.518808 -315.176081)
			(xy 295.476187 -315.151474) (xy 295.438066 -315.120349) (xy 295.405431 -315.083512) (xy 295.379128 -315.041916)
			(xy 295.359837 -314.99664) (xy 295.34806 -314.948856) (xy 295.3441 -314.899802) (xy 295.004998 -314.899802)
			(xy 295.004503 -314.924409) (xy 294.996608 -314.972986) (xy 294.981024 -315.019667) (xy 294.958153 -315.063244)
			(xy 294.928588 -315.102588) (xy 294.893095 -315.13668) (xy 294.852592 -315.164636) (xy 294.80813 -315.185734)
			(xy 294.760859 -315.199426) (xy 294.712004 -315.205358) (xy 294.662829 -315.203377) (xy 294.61461 -315.193533)
			(xy 294.568594 -315.176081) (xy 294.525973 -315.151474) (xy 294.487852 -315.120349) (xy 294.455217 -315.083512)
			(xy 294.428914 -315.041916) (xy 294.409623 -314.99664) (xy 294.397846 -314.948856) (xy 294.393886 -314.899802)
			(xy 294.055038 -314.899802) (xy 294.054543 -314.924409) (xy 294.046648 -314.972986) (xy 294.031064 -315.019667)
			(xy 294.008193 -315.063244) (xy 293.978628 -315.102588) (xy 293.943135 -315.13668) (xy 293.902632 -315.164636)
			(xy 293.85817 -315.185734) (xy 293.810899 -315.199426) (xy 293.762044 -315.205358) (xy 293.712869 -315.203377)
			(xy 293.66465 -315.193533) (xy 293.618634 -315.176081) (xy 293.576013 -315.151474) (xy 293.537892 -315.120349)
			(xy 293.505257 -315.083512) (xy 293.478954 -315.041916) (xy 293.459663 -314.99664) (xy 293.447886 -314.948856)
			(xy 293.443926 -314.899802) (xy 293.105078 -314.899802) (xy 293.104583 -314.924409) (xy 293.096688 -314.972986)
			(xy 293.081104 -315.019667) (xy 293.058233 -315.063244) (xy 293.028668 -315.102588) (xy 292.993175 -315.13668)
			(xy 292.952672 -315.164636) (xy 292.90821 -315.185734) (xy 292.860939 -315.199426) (xy 292.812084 -315.205358)
			(xy 292.762909 -315.203377) (xy 292.71469 -315.193533) (xy 292.668674 -315.176081) (xy 292.626053 -315.151474)
			(xy 292.587932 -315.120349) (xy 292.555297 -315.083512) (xy 292.528994 -315.041916) (xy 292.509703 -314.99664)
			(xy 292.497926 -314.948856) (xy 292.493966 -314.899802) (xy 292.155118 -314.899802) (xy 292.154623 -314.924409)
			(xy 292.146728 -314.972986) (xy 292.131144 -315.019667) (xy 292.108273 -315.063244) (xy 292.078708 -315.102588)
			(xy 292.043215 -315.13668) (xy 292.002712 -315.164636) (xy 291.95825 -315.185734) (xy 291.910979 -315.199426)
			(xy 291.862124 -315.205358) (xy 291.812949 -315.203377) (xy 291.76473 -315.193533) (xy 291.718714 -315.176081)
			(xy 291.676093 -315.151474) (xy 291.637972 -315.120349) (xy 291.605337 -315.083512) (xy 291.579034 -315.041916)
			(xy 291.559743 -314.99664) (xy 291.547966 -314.948856) (xy 291.544006 -314.899802) (xy 291.205158 -314.899802)
			(xy 291.204663 -314.924409) (xy 291.196768 -314.972986) (xy 291.181184 -315.019667) (xy 291.158313 -315.063244)
			(xy 291.128748 -315.102588) (xy 291.093255 -315.13668) (xy 291.052752 -315.164636) (xy 291.00829 -315.185734)
			(xy 290.961019 -315.199426) (xy 290.912164 -315.205358) (xy 290.862989 -315.203377) (xy 290.81477 -315.193533)
			(xy 290.768754 -315.176081) (xy 290.726133 -315.151474) (xy 290.688012 -315.120349) (xy 290.655377 -315.083512)
			(xy 290.629074 -315.041916) (xy 290.609783 -314.99664) (xy 290.598006 -314.948856) (xy 290.594046 -314.899802)
			(xy 290.255198 -314.899802) (xy 290.254703 -314.924409) (xy 290.246808 -314.972986) (xy 290.231224 -315.019667)
			(xy 290.208353 -315.063244) (xy 290.178788 -315.102588) (xy 290.143295 -315.13668) (xy 290.102792 -315.164636)
			(xy 290.05833 -315.185734) (xy 290.011059 -315.199426) (xy 289.962204 -315.205358) (xy 289.913029 -315.203377)
			(xy 289.86481 -315.193533) (xy 289.818794 -315.176081) (xy 289.776173 -315.151474) (xy 289.738052 -315.120349)
			(xy 289.705417 -315.083512) (xy 289.679114 -315.041916) (xy 289.659823 -314.99664) (xy 289.648046 -314.948856)
			(xy 289.644086 -314.899802) (xy 289.305238 -314.899802) (xy 289.304743 -314.924409) (xy 289.296848 -314.972986)
			(xy 289.281264 -315.019667) (xy 289.258393 -315.063244) (xy 289.228828 -315.102588) (xy 289.193335 -315.13668)
			(xy 289.152832 -315.164636) (xy 289.10837 -315.185734) (xy 289.061099 -315.199426) (xy 289.012244 -315.205358)
			(xy 288.963069 -315.203377) (xy 288.91485 -315.193533) (xy 288.868834 -315.176081) (xy 288.826213 -315.151474)
			(xy 288.788092 -315.120349) (xy 288.755457 -315.083512) (xy 288.729154 -315.041916) (xy 288.709863 -314.99664)
			(xy 288.698086 -314.948856) (xy 288.694126 -314.899802) (xy 288.355024 -314.899802) (xy 288.354529 -314.924409)
			(xy 288.346634 -314.972986) (xy 288.33105 -315.019667) (xy 288.308179 -315.063244) (xy 288.278614 -315.102588)
			(xy 288.243121 -315.13668) (xy 288.202618 -315.164636) (xy 288.158156 -315.185734) (xy 288.110885 -315.199426)
			(xy 288.06203 -315.205358) (xy 288.012855 -315.203377) (xy 287.964636 -315.193533) (xy 287.91862 -315.176081)
			(xy 287.875999 -315.151474) (xy 287.837878 -315.120349) (xy 287.805243 -315.083512) (xy 287.77894 -315.041916)
			(xy 287.759649 -314.99664) (xy 287.747872 -314.948856) (xy 287.743912 -314.899802) (xy 287.405064 -314.899802)
			(xy 287.404569 -314.924409) (xy 287.396674 -314.972986) (xy 287.38109 -315.019667) (xy 287.358219 -315.063244)
			(xy 287.328654 -315.102588) (xy 287.293161 -315.13668) (xy 287.252658 -315.164636) (xy 287.208196 -315.185734)
			(xy 287.160925 -315.199426) (xy 287.11207 -315.205358) (xy 287.062895 -315.203377) (xy 287.014676 -315.193533)
			(xy 286.96866 -315.176081) (xy 286.926039 -315.151474) (xy 286.887918 -315.120349) (xy 286.855283 -315.083512)
			(xy 286.82898 -315.041916) (xy 286.809689 -314.99664) (xy 286.797912 -314.948856) (xy 286.793952 -314.899802)
			(xy 286.455104 -314.899802) (xy 286.454609 -314.924409) (xy 286.446714 -314.972986) (xy 286.43113 -315.019667)
			(xy 286.408259 -315.063244) (xy 286.378694 -315.102588) (xy 286.343201 -315.13668) (xy 286.302698 -315.164636)
			(xy 286.258236 -315.185734) (xy 286.210965 -315.199426) (xy 286.16211 -315.205358) (xy 286.112935 -315.203377)
			(xy 286.064716 -315.193533) (xy 286.0187 -315.176081) (xy 285.976079 -315.151474) (xy 285.937958 -315.120349)
			(xy 285.905323 -315.083512) (xy 285.87902 -315.041916) (xy 285.859729 -314.99664) (xy 285.847952 -314.948856)
			(xy 285.843992 -314.899802) (xy 285.505144 -314.899802) (xy 285.504649 -314.924409) (xy 285.496754 -314.972986)
			(xy 285.48117 -315.019667) (xy 285.458299 -315.063244) (xy 285.428734 -315.102588) (xy 285.393241 -315.13668)
			(xy 285.352738 -315.164636) (xy 285.308276 -315.185734) (xy 285.261005 -315.199426) (xy 285.21215 -315.205358)
			(xy 285.162975 -315.203377) (xy 285.114756 -315.193533) (xy 285.06874 -315.176081) (xy 285.026119 -315.151474)
			(xy 284.987998 -315.120349) (xy 284.955363 -315.083512) (xy 284.92906 -315.041916) (xy 284.909769 -314.99664)
			(xy 284.897992 -314.948856) (xy 284.894032 -314.899802) (xy 284.555184 -314.899802) (xy 284.554689 -314.924409)
			(xy 284.546794 -314.972986) (xy 284.53121 -315.019667) (xy 284.508339 -315.063244) (xy 284.478774 -315.102588)
			(xy 284.443281 -315.13668) (xy 284.402778 -315.164636) (xy 284.358316 -315.185734) (xy 284.311045 -315.199426)
			(xy 284.26219 -315.205358) (xy 284.213015 -315.203377) (xy 284.164796 -315.193533) (xy 284.11878 -315.176081)
			(xy 284.076159 -315.151474) (xy 284.038038 -315.120349) (xy 284.005403 -315.083512) (xy 283.9791 -315.041916)
			(xy 283.959809 -314.99664) (xy 283.948032 -314.948856) (xy 283.944072 -314.899802) (xy 283.605224 -314.899802)
			(xy 283.604729 -314.924409) (xy 283.596834 -314.972986) (xy 283.58125 -315.019667) (xy 283.558379 -315.063244)
			(xy 283.528814 -315.102588) (xy 283.493321 -315.13668) (xy 283.452818 -315.164636) (xy 283.408356 -315.185734)
			(xy 283.361085 -315.199426) (xy 283.31223 -315.205358) (xy 283.263055 -315.203377) (xy 283.214836 -315.193533)
			(xy 283.16882 -315.176081) (xy 283.126199 -315.151474) (xy 283.088078 -315.120349) (xy 283.055443 -315.083512)
			(xy 283.02914 -315.041916) (xy 283.009849 -314.99664) (xy 282.998072 -314.948856) (xy 282.994112 -314.899802)
			(xy 282.65501 -314.899802) (xy 282.654515 -314.924409) (xy 282.64662 -314.972986) (xy 282.631036 -315.019667)
			(xy 282.608165 -315.063244) (xy 282.5786 -315.102588) (xy 282.543107 -315.13668) (xy 282.502604 -315.164636)
			(xy 282.458142 -315.185734) (xy 282.410871 -315.199426) (xy 282.362016 -315.205358) (xy 282.312841 -315.203377)
			(xy 282.264622 -315.193533) (xy 282.218606 -315.176081) (xy 282.175985 -315.151474) (xy 282.137864 -315.120349)
			(xy 282.105229 -315.083512) (xy 282.078926 -315.041916) (xy 282.059635 -314.99664) (xy 282.047858 -314.948856)
			(xy 282.043898 -314.899802) (xy 281.70505 -314.899802) (xy 281.704555 -314.924409) (xy 281.69666 -314.972986)
			(xy 281.681076 -315.019667) (xy 281.658205 -315.063244) (xy 281.62864 -315.102588) (xy 281.593147 -315.13668)
			(xy 281.552644 -315.164636) (xy 281.508182 -315.185734) (xy 281.460911 -315.199426) (xy 281.412056 -315.205358)
			(xy 281.362881 -315.203377) (xy 281.314662 -315.193533) (xy 281.268646 -315.176081) (xy 281.226025 -315.151474)
			(xy 281.187904 -315.120349) (xy 281.155269 -315.083512) (xy 281.128966 -315.041916) (xy 281.109675 -314.99664)
			(xy 281.097898 -314.948856) (xy 281.093938 -314.899802) (xy 280.75509 -314.899802) (xy 280.754595 -314.924409)
			(xy 280.7467 -314.972986) (xy 280.731116 -315.019667) (xy 280.708245 -315.063244) (xy 280.67868 -315.102588)
			(xy 280.643187 -315.13668) (xy 280.602684 -315.164636) (xy 280.558222 -315.185734) (xy 280.510951 -315.199426)
			(xy 280.462096 -315.205358) (xy 280.412921 -315.203377) (xy 280.364702 -315.193533) (xy 280.318686 -315.176081)
			(xy 280.276065 -315.151474) (xy 280.237944 -315.120349) (xy 280.205309 -315.083512) (xy 280.179006 -315.041916)
			(xy 280.159715 -314.99664) (xy 280.147938 -314.948856) (xy 280.143978 -314.899802) (xy 279.80513 -314.899802)
			(xy 279.804635 -314.924409) (xy 279.79674 -314.972986) (xy 279.781156 -315.019667) (xy 279.758285 -315.063244)
			(xy 279.72872 -315.102588) (xy 279.693227 -315.13668) (xy 279.652724 -315.164636) (xy 279.608262 -315.185734)
			(xy 279.560991 -315.199426) (xy 279.512136 -315.205358) (xy 279.462961 -315.203377) (xy 279.414742 -315.193533)
			(xy 279.368726 -315.176081) (xy 279.326105 -315.151474) (xy 279.287984 -315.120349) (xy 279.255349 -315.083512)
			(xy 279.229046 -315.041916) (xy 279.209755 -314.99664) (xy 279.197978 -314.948856) (xy 279.194018 -314.899802)
			(xy 278.85517 -314.899802) (xy 278.854675 -314.924409) (xy 278.84678 -314.972986) (xy 278.831196 -315.019667)
			(xy 278.808325 -315.063244) (xy 278.77876 -315.102588) (xy 278.743267 -315.13668) (xy 278.702764 -315.164636)
			(xy 278.658302 -315.185734) (xy 278.611031 -315.199426) (xy 278.562176 -315.205358) (xy 278.513001 -315.203377)
			(xy 278.464782 -315.193533) (xy 278.418766 -315.176081) (xy 278.376145 -315.151474) (xy 278.338024 -315.120349)
			(xy 278.305389 -315.083512) (xy 278.279086 -315.041916) (xy 278.259795 -314.99664) (xy 278.248018 -314.948856)
			(xy 278.244058 -314.899802) (xy 277.90521 -314.899802) (xy 277.904715 -314.924409) (xy 277.89682 -314.972986)
			(xy 277.881236 -315.019667) (xy 277.858365 -315.063244) (xy 277.8288 -315.102588) (xy 277.793307 -315.13668)
			(xy 277.752804 -315.164636) (xy 277.708342 -315.185734) (xy 277.661071 -315.199426) (xy 277.612216 -315.205358)
			(xy 277.563041 -315.203377) (xy 277.514822 -315.193533) (xy 277.468806 -315.176081) (xy 277.426185 -315.151474)
			(xy 277.388064 -315.120349) (xy 277.355429 -315.083512) (xy 277.329126 -315.041916) (xy 277.309835 -314.99664)
			(xy 277.298058 -314.948856) (xy 277.294098 -314.899802) (xy 276.954996 -314.899802) (xy 276.954501 -314.924409)
			(xy 276.946606 -314.972986) (xy 276.931022 -315.019667) (xy 276.908151 -315.063244) (xy 276.878586 -315.102588)
			(xy 276.843093 -315.13668) (xy 276.80259 -315.164636) (xy 276.758128 -315.185734) (xy 276.710857 -315.199426)
			(xy 276.662002 -315.205358) (xy 276.612827 -315.203377) (xy 276.564608 -315.193533) (xy 276.518592 -315.176081)
			(xy 276.475971 -315.151474) (xy 276.43785 -315.120349) (xy 276.405215 -315.083512) (xy 276.378912 -315.041916)
			(xy 276.359621 -314.99664) (xy 276.347844 -314.948856) (xy 276.343884 -314.899802) (xy 276.005036 -314.899802)
			(xy 276.004541 -314.924409) (xy 275.996646 -314.972986) (xy 275.981062 -315.019667) (xy 275.958191 -315.063244)
			(xy 275.928626 -315.102588) (xy 275.893133 -315.13668) (xy 275.85263 -315.164636) (xy 275.808168 -315.185734)
			(xy 275.760897 -315.199426) (xy 275.712042 -315.205358) (xy 275.662867 -315.203377) (xy 275.614648 -315.193533)
			(xy 275.568632 -315.176081) (xy 275.526011 -315.151474) (xy 275.48789 -315.120349) (xy 275.455255 -315.083512)
			(xy 275.428952 -315.041916) (xy 275.409661 -314.99664) (xy 275.397884 -314.948856) (xy 275.393924 -314.899802)
			(xy 275.055076 -314.899802) (xy 275.054581 -314.924409) (xy 275.046686 -314.972986) (xy 275.031102 -315.019667)
			(xy 275.008231 -315.063244) (xy 274.978666 -315.102588) (xy 274.943173 -315.13668) (xy 274.90267 -315.164636)
			(xy 274.858208 -315.185734) (xy 274.810937 -315.199426) (xy 274.762082 -315.205358) (xy 274.712907 -315.203377)
			(xy 274.664688 -315.193533) (xy 274.618672 -315.176081) (xy 274.576051 -315.151474) (xy 274.53793 -315.120349)
			(xy 274.505295 -315.083512) (xy 274.478992 -315.041916) (xy 274.459701 -314.99664) (xy 274.447924 -314.948856)
			(xy 274.443964 -314.899802) (xy 274.105116 -314.899802) (xy 274.104621 -314.924409) (xy 274.096726 -314.972986)
			(xy 274.081142 -315.019667) (xy 274.058271 -315.063244) (xy 274.028706 -315.102588) (xy 273.993213 -315.13668)
			(xy 273.95271 -315.164636) (xy 273.908248 -315.185734) (xy 273.860977 -315.199426) (xy 273.812122 -315.205358)
			(xy 273.762947 -315.203377) (xy 273.714728 -315.193533) (xy 273.668712 -315.176081) (xy 273.626091 -315.151474)
			(xy 273.58797 -315.120349) (xy 273.555335 -315.083512) (xy 273.529032 -315.041916) (xy 273.509741 -314.99664)
			(xy 273.497964 -314.948856) (xy 273.494004 -314.899802) (xy 273.155156 -314.899802) (xy 273.154661 -314.924409)
			(xy 273.146766 -314.972986) (xy 273.131182 -315.019667) (xy 273.108311 -315.063244) (xy 273.078746 -315.102588)
			(xy 273.043253 -315.13668) (xy 273.00275 -315.164636) (xy 272.958288 -315.185734) (xy 272.911017 -315.199426)
			(xy 272.862162 -315.205358) (xy 272.812987 -315.203377) (xy 272.764768 -315.193533) (xy 272.718752 -315.176081)
			(xy 272.676131 -315.151474) (xy 272.63801 -315.120349) (xy 272.605375 -315.083512) (xy 272.579072 -315.041916)
			(xy 272.559781 -314.99664) (xy 272.548004 -314.948856) (xy 272.544044 -314.899802) (xy 272.205196 -314.899802)
			(xy 272.204701 -314.924409) (xy 272.196806 -314.972986) (xy 272.181222 -315.019667) (xy 272.158351 -315.063244)
			(xy 272.128786 -315.102588) (xy 272.093293 -315.13668) (xy 272.05279 -315.164636) (xy 272.008328 -315.185734)
			(xy 271.961057 -315.199426) (xy 271.912202 -315.205358) (xy 271.863027 -315.203377) (xy 271.814808 -315.193533)
			(xy 271.768792 -315.176081) (xy 271.726171 -315.151474) (xy 271.68805 -315.120349) (xy 271.655415 -315.083512)
			(xy 271.629112 -315.041916) (xy 271.609821 -314.99664) (xy 271.598044 -314.948856) (xy 271.594084 -314.899802)
			(xy 271.255236 -314.899802) (xy 271.254741 -314.924409) (xy 271.246846 -314.972986) (xy 271.231262 -315.019667)
			(xy 271.208391 -315.063244) (xy 271.178826 -315.102588) (xy 271.143333 -315.13668) (xy 271.10283 -315.164636)
			(xy 271.058368 -315.185734) (xy 271.011097 -315.199426) (xy 270.962242 -315.205358) (xy 270.913067 -315.203377)
			(xy 270.864848 -315.193533) (xy 270.818832 -315.176081) (xy 270.776211 -315.151474) (xy 270.73809 -315.120349)
			(xy 270.705455 -315.083512) (xy 270.679152 -315.041916) (xy 270.659861 -314.99664) (xy 270.648084 -314.948856)
			(xy 270.644124 -314.899802) (xy 270.326866 -314.899802) (xy 270.326362 -314.92551) (xy 270.318319 -314.976292)
			(xy 270.302431 -315.025191) (xy 270.279088 -315.071003) (xy 270.248867 -315.112599) (xy 270.212511 -315.148955)
			(xy 270.170915 -315.179176) (xy 270.125103 -315.202519) (xy 270.076204 -315.218407) (xy 270.025422 -315.22645)
			(xy 269.974006 -315.22645) (xy 269.923224 -315.218407) (xy 269.874325 -315.202519) (xy 269.828513 -315.179176)
			(xy 269.786917 -315.148955) (xy 269.750561 -315.112599) (xy 269.72034 -315.071003) (xy 269.696997 -315.025191)
			(xy 269.681109 -314.976292) (xy 269.673066 -314.92551) (xy 269.376402 -314.92551) (xy 269.368359 -314.976292)
			(xy 269.352471 -315.025191) (xy 269.329128 -315.071003) (xy 269.298907 -315.112599) (xy 269.262551 -315.148955)
			(xy 269.220955 -315.179176) (xy 269.175143 -315.202519) (xy 269.126244 -315.218407) (xy 269.075462 -315.22645)
			(xy 269.024046 -315.22645) (xy 268.973264 -315.218407) (xy 268.924365 -315.202519) (xy 268.878553 -315.179176)
			(xy 268.836957 -315.148955) (xy 268.800601 -315.112599) (xy 268.77038 -315.071003) (xy 268.747037 -315.025191)
			(xy 268.731149 -314.976292) (xy 268.723106 -314.92551) (xy 268.403879 -314.92551) (xy 268.396204 -314.972732)
			(xy 268.38062 -315.019413) (xy 268.357749 -315.06299) (xy 268.328184 -315.102334) (xy 268.292691 -315.136426)
			(xy 268.252188 -315.164382) (xy 268.207726 -315.18548) (xy 268.160455 -315.199172) (xy 268.1116 -315.205104)
			(xy 268.062425 -315.203123) (xy 268.014206 -315.193279) (xy 267.96819 -315.175827) (xy 267.925569 -315.15122)
			(xy 267.887448 -315.120095) (xy 267.854813 -315.083258) (xy 267.82851 -315.041662) (xy 267.809219 -314.996386)
			(xy 267.797442 -314.948602) (xy 267.793482 -314.899548) (xy 248.814844 -314.899548) (xy 248.814844 -315.849762)
			(xy 268.74395 -315.849762) (xy 268.74791 -315.800708) (xy 268.759687 -315.752924) (xy 268.778978 -315.707648)
			(xy 268.805281 -315.666052) (xy 268.837916 -315.629215) (xy 268.876037 -315.59809) (xy 268.918658 -315.573483)
			(xy 268.964674 -315.556031) (xy 269.012893 -315.546187) (xy 269.062068 -315.544206) (xy 269.110923 -315.550138)
			(xy 269.158194 -315.56383) (xy 269.202656 -315.584928) (xy 269.243159 -315.612884) (xy 269.278652 -315.646976)
			(xy 269.308217 -315.68632) (xy 269.331088 -315.729897) (xy 269.346672 -315.776578) (xy 269.354567 -315.825155)
			(xy 269.355062 -315.849762) (xy 269.69391 -315.849762) (xy 269.69787 -315.800708) (xy 269.709647 -315.752924)
			(xy 269.728938 -315.707648) (xy 269.755241 -315.666052) (xy 269.787876 -315.629215) (xy 269.825997 -315.59809)
			(xy 269.868618 -315.573483) (xy 269.914634 -315.556031) (xy 269.962853 -315.546187) (xy 270.012028 -315.544206)
			(xy 270.060883 -315.550138) (xy 270.108154 -315.56383) (xy 270.152616 -315.584928) (xy 270.193119 -315.612884)
			(xy 270.228612 -315.646976) (xy 270.258177 -315.68632) (xy 270.281048 -315.729897) (xy 270.296632 -315.776578)
			(xy 270.304527 -315.825155) (xy 270.305022 -315.849762) (xy 270.644124 -315.849762) (xy 270.648084 -315.800708)
			(xy 270.659861 -315.752924) (xy 270.679152 -315.707648) (xy 270.705455 -315.666052) (xy 270.73809 -315.629215)
			(xy 270.776211 -315.59809) (xy 270.818832 -315.573483) (xy 270.864848 -315.556031) (xy 270.913067 -315.546187)
			(xy 270.962242 -315.544206) (xy 271.011097 -315.550138) (xy 271.058368 -315.56383) (xy 271.10283 -315.584928)
			(xy 271.143333 -315.612884) (xy 271.178826 -315.646976) (xy 271.208391 -315.68632) (xy 271.231262 -315.729897)
			(xy 271.246846 -315.776578) (xy 271.254741 -315.825155) (xy 271.255236 -315.849762) (xy 271.254741 -315.874369)
			(xy 271.254562 -315.87547) (xy 271.57324 -315.87547) (xy 271.57324 -315.824054) (xy 271.581283 -315.773272)
			(xy 271.597171 -315.724373) (xy 271.620514 -315.678561) (xy 271.650735 -315.636965) (xy 271.687091 -315.600609)
			(xy 271.728687 -315.570388) (xy 271.774499 -315.547045) (xy 271.823398 -315.531157) (xy 271.87418 -315.523114)
			(xy 271.925596 -315.523114) (xy 271.976378 -315.531157) (xy 272.025277 -315.547045) (xy 272.071089 -315.570388)
			(xy 272.112685 -315.600609) (xy 272.149041 -315.636965) (xy 272.179262 -315.678561) (xy 272.202605 -315.724373)
			(xy 272.218493 -315.773272) (xy 272.226536 -315.824054) (xy 272.22704 -315.849762) (xy 272.544044 -315.849762)
			(xy 272.548004 -315.800708) (xy 272.559781 -315.752924) (xy 272.579072 -315.707648) (xy 272.605375 -315.666052)
			(xy 272.63801 -315.629215) (xy 272.676131 -315.59809) (xy 272.718752 -315.573483) (xy 272.764768 -315.556031)
			(xy 272.812987 -315.546187) (xy 272.862162 -315.544206) (xy 272.911017 -315.550138) (xy 272.958288 -315.56383)
			(xy 273.00275 -315.584928) (xy 273.043253 -315.612884) (xy 273.078746 -315.646976) (xy 273.108311 -315.68632)
			(xy 273.131182 -315.729897) (xy 273.146766 -315.776578) (xy 273.154661 -315.825155) (xy 273.155156 -315.849762)
			(xy 273.154661 -315.874369) (xy 273.154482 -315.87547) (xy 273.47316 -315.87547) (xy 273.47316 -315.824054)
			(xy 273.481203 -315.773272) (xy 273.497091 -315.724373) (xy 273.520434 -315.678561) (xy 273.550655 -315.636965)
			(xy 273.587011 -315.600609) (xy 273.628607 -315.570388) (xy 273.674419 -315.547045) (xy 273.723318 -315.531157)
			(xy 273.7741 -315.523114) (xy 273.825516 -315.523114) (xy 273.876298 -315.531157) (xy 273.925197 -315.547045)
			(xy 273.971009 -315.570388) (xy 274.012605 -315.600609) (xy 274.048961 -315.636965) (xy 274.079182 -315.678561)
			(xy 274.102525 -315.724373) (xy 274.118413 -315.773272) (xy 274.126456 -315.824054) (xy 274.12696 -315.849762)
			(xy 274.443964 -315.849762) (xy 274.447924 -315.800708) (xy 274.459701 -315.752924) (xy 274.478992 -315.707648)
			(xy 274.505295 -315.666052) (xy 274.53793 -315.629215) (xy 274.576051 -315.59809) (xy 274.618672 -315.573483)
			(xy 274.664688 -315.556031) (xy 274.712907 -315.546187) (xy 274.762082 -315.544206) (xy 274.810937 -315.550138)
			(xy 274.858208 -315.56383) (xy 274.90267 -315.584928) (xy 274.943173 -315.612884) (xy 274.978666 -315.646976)
			(xy 275.008231 -315.68632) (xy 275.031102 -315.729897) (xy 275.046686 -315.776578) (xy 275.054581 -315.825155)
			(xy 275.055076 -315.849762) (xy 275.054581 -315.874369) (xy 275.054402 -315.87547) (xy 275.37308 -315.87547)
			(xy 275.37308 -315.824054) (xy 275.381123 -315.773272) (xy 275.397011 -315.724373) (xy 275.420354 -315.678561)
			(xy 275.450575 -315.636965) (xy 275.486931 -315.600609) (xy 275.528527 -315.570388) (xy 275.574339 -315.547045)
			(xy 275.623238 -315.531157) (xy 275.67402 -315.523114) (xy 275.725436 -315.523114) (xy 275.776218 -315.531157)
			(xy 275.825117 -315.547045) (xy 275.870929 -315.570388) (xy 275.912525 -315.600609) (xy 275.948881 -315.636965)
			(xy 275.979102 -315.678561) (xy 276.002445 -315.724373) (xy 276.018333 -315.773272) (xy 276.026376 -315.824054)
			(xy 276.02688 -315.849762) (xy 276.343884 -315.849762) (xy 276.347844 -315.800708) (xy 276.359621 -315.752924)
			(xy 276.378912 -315.707648) (xy 276.405215 -315.666052) (xy 276.43785 -315.629215) (xy 276.475971 -315.59809)
			(xy 276.518592 -315.573483) (xy 276.564608 -315.556031) (xy 276.612827 -315.546187) (xy 276.662002 -315.544206)
			(xy 276.710857 -315.550138) (xy 276.758128 -315.56383) (xy 276.80259 -315.584928) (xy 276.843093 -315.612884)
			(xy 276.878586 -315.646976) (xy 276.908151 -315.68632) (xy 276.931022 -315.729897) (xy 276.946606 -315.776578)
			(xy 276.954501 -315.825155) (xy 276.954996 -315.849762) (xy 276.954501 -315.874369) (xy 276.954322 -315.87547)
			(xy 277.273254 -315.87547) (xy 277.273254 -315.824054) (xy 277.281297 -315.773272) (xy 277.297185 -315.724373)
			(xy 277.320528 -315.678561) (xy 277.350749 -315.636965) (xy 277.387105 -315.600609) (xy 277.428701 -315.570388)
			(xy 277.474513 -315.547045) (xy 277.523412 -315.531157) (xy 277.574194 -315.523114) (xy 277.62561 -315.523114)
			(xy 277.676392 -315.531157) (xy 277.725291 -315.547045) (xy 277.771103 -315.570388) (xy 277.812699 -315.600609)
			(xy 277.849055 -315.636965) (xy 277.879276 -315.678561) (xy 277.902619 -315.724373) (xy 277.918507 -315.773272)
			(xy 277.92655 -315.824054) (xy 277.927054 -315.849762) (xy 278.244058 -315.849762) (xy 278.248018 -315.800708)
			(xy 278.259795 -315.752924) (xy 278.279086 -315.707648) (xy 278.305389 -315.666052) (xy 278.338024 -315.629215)
			(xy 278.376145 -315.59809) (xy 278.418766 -315.573483) (xy 278.464782 -315.556031) (xy 278.513001 -315.546187)
			(xy 278.562176 -315.544206) (xy 278.611031 -315.550138) (xy 278.658302 -315.56383) (xy 278.702764 -315.584928)
			(xy 278.743267 -315.612884) (xy 278.77876 -315.646976) (xy 278.808325 -315.68632) (xy 278.831196 -315.729897)
			(xy 278.84678 -315.776578) (xy 278.854675 -315.825155) (xy 278.85517 -315.849762) (xy 278.854675 -315.874369)
			(xy 278.854496 -315.87547) (xy 279.173174 -315.87547) (xy 279.173174 -315.824054) (xy 279.181217 -315.773272)
			(xy 279.197105 -315.724373) (xy 279.220448 -315.678561) (xy 279.250669 -315.636965) (xy 279.287025 -315.600609)
			(xy 279.328621 -315.570388) (xy 279.374433 -315.547045) (xy 279.423332 -315.531157) (xy 279.474114 -315.523114)
			(xy 279.52553 -315.523114) (xy 279.576312 -315.531157) (xy 279.625211 -315.547045) (xy 279.671023 -315.570388)
			(xy 279.712619 -315.600609) (xy 279.748975 -315.636965) (xy 279.779196 -315.678561) (xy 279.802539 -315.724373)
			(xy 279.818427 -315.773272) (xy 279.82647 -315.824054) (xy 279.826974 -315.849762) (xy 280.143978 -315.849762)
			(xy 280.147938 -315.800708) (xy 280.159715 -315.752924) (xy 280.179006 -315.707648) (xy 280.205309 -315.666052)
			(xy 280.237944 -315.629215) (xy 280.276065 -315.59809) (xy 280.318686 -315.573483) (xy 280.364702 -315.556031)
			(xy 280.412921 -315.546187) (xy 280.462096 -315.544206) (xy 280.510951 -315.550138) (xy 280.558222 -315.56383)
			(xy 280.602684 -315.584928) (xy 280.643187 -315.612884) (xy 280.67868 -315.646976) (xy 280.708245 -315.68632)
			(xy 280.731116 -315.729897) (xy 280.7467 -315.776578) (xy 280.754595 -315.825155) (xy 280.75509 -315.849762)
			(xy 280.754595 -315.874369) (xy 280.754416 -315.87547) (xy 281.073094 -315.87547) (xy 281.073094 -315.824054)
			(xy 281.081137 -315.773272) (xy 281.097025 -315.724373) (xy 281.120368 -315.678561) (xy 281.150589 -315.636965)
			(xy 281.186945 -315.600609) (xy 281.228541 -315.570388) (xy 281.274353 -315.547045) (xy 281.323252 -315.531157)
			(xy 281.374034 -315.523114) (xy 281.42545 -315.523114) (xy 281.476232 -315.531157) (xy 281.525131 -315.547045)
			(xy 281.570943 -315.570388) (xy 281.612539 -315.600609) (xy 281.648895 -315.636965) (xy 281.679116 -315.678561)
			(xy 281.702459 -315.724373) (xy 281.718347 -315.773272) (xy 281.72639 -315.824054) (xy 281.726894 -315.849762)
			(xy 282.043898 -315.849762) (xy 282.047858 -315.800708) (xy 282.059635 -315.752924) (xy 282.078926 -315.707648)
			(xy 282.105229 -315.666052) (xy 282.137864 -315.629215) (xy 282.175985 -315.59809) (xy 282.218606 -315.573483)
			(xy 282.264622 -315.556031) (xy 282.312841 -315.546187) (xy 282.362016 -315.544206) (xy 282.410871 -315.550138)
			(xy 282.458142 -315.56383) (xy 282.502604 -315.584928) (xy 282.543107 -315.612884) (xy 282.5786 -315.646976)
			(xy 282.608165 -315.68632) (xy 282.631036 -315.729897) (xy 282.64662 -315.776578) (xy 282.654515 -315.825155)
			(xy 282.65501 -315.849762) (xy 282.654515 -315.874369) (xy 282.654336 -315.87547) (xy 282.973268 -315.87547)
			(xy 282.973268 -315.824054) (xy 282.981311 -315.773272) (xy 282.997199 -315.724373) (xy 283.020542 -315.678561)
			(xy 283.050763 -315.636965) (xy 283.087119 -315.600609) (xy 283.128715 -315.570388) (xy 283.174527 -315.547045)
			(xy 283.223426 -315.531157) (xy 283.274208 -315.523114) (xy 283.325624 -315.523114) (xy 283.376406 -315.531157)
			(xy 283.425305 -315.547045) (xy 283.471117 -315.570388) (xy 283.512713 -315.600609) (xy 283.549069 -315.636965)
			(xy 283.57929 -315.678561) (xy 283.602633 -315.724373) (xy 283.618521 -315.773272) (xy 283.626564 -315.824054)
			(xy 283.627068 -315.849762) (xy 283.944072 -315.849762) (xy 283.948032 -315.800708) (xy 283.959809 -315.752924)
			(xy 283.9791 -315.707648) (xy 284.005403 -315.666052) (xy 284.038038 -315.629215) (xy 284.076159 -315.59809)
			(xy 284.11878 -315.573483) (xy 284.164796 -315.556031) (xy 284.213015 -315.546187) (xy 284.26219 -315.544206)
			(xy 284.311045 -315.550138) (xy 284.358316 -315.56383) (xy 284.402778 -315.584928) (xy 284.443281 -315.612884)
			(xy 284.478774 -315.646976) (xy 284.508339 -315.68632) (xy 284.53121 -315.729897) (xy 284.546794 -315.776578)
			(xy 284.554689 -315.825155) (xy 284.555184 -315.849762) (xy 284.554689 -315.874369) (xy 284.55451 -315.87547)
			(xy 284.873188 -315.87547) (xy 284.873188 -315.824054) (xy 284.881231 -315.773272) (xy 284.897119 -315.724373)
			(xy 284.920462 -315.678561) (xy 284.950683 -315.636965) (xy 284.987039 -315.600609) (xy 285.028635 -315.570388)
			(xy 285.074447 -315.547045) (xy 285.123346 -315.531157) (xy 285.174128 -315.523114) (xy 285.225544 -315.523114)
			(xy 285.276326 -315.531157) (xy 285.325225 -315.547045) (xy 285.371037 -315.570388) (xy 285.412633 -315.600609)
			(xy 285.448989 -315.636965) (xy 285.47921 -315.678561) (xy 285.502553 -315.724373) (xy 285.518441 -315.773272)
			(xy 285.526484 -315.824054) (xy 285.526988 -315.849762) (xy 285.843992 -315.849762) (xy 285.847952 -315.800708)
			(xy 285.859729 -315.752924) (xy 285.87902 -315.707648) (xy 285.905323 -315.666052) (xy 285.937958 -315.629215)
			(xy 285.976079 -315.59809) (xy 286.0187 -315.573483) (xy 286.064716 -315.556031) (xy 286.112935 -315.546187)
			(xy 286.16211 -315.544206) (xy 286.210965 -315.550138) (xy 286.258236 -315.56383) (xy 286.302698 -315.584928)
			(xy 286.343201 -315.612884) (xy 286.378694 -315.646976) (xy 286.408259 -315.68632) (xy 286.43113 -315.729897)
			(xy 286.446714 -315.776578) (xy 286.454609 -315.825155) (xy 286.455104 -315.849762) (xy 286.454609 -315.874369)
			(xy 286.45443 -315.87547) (xy 286.773108 -315.87547) (xy 286.773108 -315.824054) (xy 286.781151 -315.773272)
			(xy 286.797039 -315.724373) (xy 286.820382 -315.678561) (xy 286.850603 -315.636965) (xy 286.886959 -315.600609)
			(xy 286.928555 -315.570388) (xy 286.974367 -315.547045) (xy 287.023266 -315.531157) (xy 287.074048 -315.523114)
			(xy 287.125464 -315.523114) (xy 287.176246 -315.531157) (xy 287.225145 -315.547045) (xy 287.270957 -315.570388)
			(xy 287.312553 -315.600609) (xy 287.348909 -315.636965) (xy 287.37913 -315.678561) (xy 287.402473 -315.724373)
			(xy 287.418361 -315.773272) (xy 287.426404 -315.824054) (xy 287.426908 -315.849762) (xy 287.743912 -315.849762)
			(xy 287.747872 -315.800708) (xy 287.759649 -315.752924) (xy 287.77894 -315.707648) (xy 287.805243 -315.666052)
			(xy 287.837878 -315.629215) (xy 287.875999 -315.59809) (xy 287.91862 -315.573483) (xy 287.964636 -315.556031)
			(xy 288.012855 -315.546187) (xy 288.06203 -315.544206) (xy 288.110885 -315.550138) (xy 288.158156 -315.56383)
			(xy 288.202618 -315.584928) (xy 288.243121 -315.612884) (xy 288.278614 -315.646976) (xy 288.308179 -315.68632)
			(xy 288.33105 -315.729897) (xy 288.346634 -315.776578) (xy 288.354529 -315.825155) (xy 288.355024 -315.849762)
			(xy 288.354529 -315.874369) (xy 288.35435 -315.87547) (xy 288.673282 -315.87547) (xy 288.673282 -315.824054)
			(xy 288.681325 -315.773272) (xy 288.697213 -315.724373) (xy 288.720556 -315.678561) (xy 288.750777 -315.636965)
			(xy 288.787133 -315.600609) (xy 288.828729 -315.570388) (xy 288.874541 -315.547045) (xy 288.92344 -315.531157)
			(xy 288.974222 -315.523114) (xy 289.025638 -315.523114) (xy 289.07642 -315.531157) (xy 289.125319 -315.547045)
			(xy 289.171131 -315.570388) (xy 289.212727 -315.600609) (xy 289.249083 -315.636965) (xy 289.279304 -315.678561)
			(xy 289.302647 -315.724373) (xy 289.318535 -315.773272) (xy 289.326578 -315.824054) (xy 289.327082 -315.849762)
			(xy 289.644086 -315.849762) (xy 289.648046 -315.800708) (xy 289.659823 -315.752924) (xy 289.679114 -315.707648)
			(xy 289.705417 -315.666052) (xy 289.738052 -315.629215) (xy 289.776173 -315.59809) (xy 289.818794 -315.573483)
			(xy 289.86481 -315.556031) (xy 289.913029 -315.546187) (xy 289.962204 -315.544206) (xy 290.011059 -315.550138)
			(xy 290.05833 -315.56383) (xy 290.102792 -315.584928) (xy 290.143295 -315.612884) (xy 290.178788 -315.646976)
			(xy 290.208353 -315.68632) (xy 290.231224 -315.729897) (xy 290.246808 -315.776578) (xy 290.254703 -315.825155)
			(xy 290.255198 -315.849762) (xy 290.254703 -315.874369) (xy 290.254524 -315.87547) (xy 290.573202 -315.87547)
			(xy 290.573202 -315.824054) (xy 290.581245 -315.773272) (xy 290.597133 -315.724373) (xy 290.620476 -315.678561)
			(xy 290.650697 -315.636965) (xy 290.687053 -315.600609) (xy 290.728649 -315.570388) (xy 290.774461 -315.547045)
			(xy 290.82336 -315.531157) (xy 290.874142 -315.523114) (xy 290.925558 -315.523114) (xy 290.97634 -315.531157)
			(xy 291.025239 -315.547045) (xy 291.071051 -315.570388) (xy 291.112647 -315.600609) (xy 291.149003 -315.636965)
			(xy 291.179224 -315.678561) (xy 291.202567 -315.724373) (xy 291.218455 -315.773272) (xy 291.226498 -315.824054)
			(xy 291.227002 -315.849762) (xy 291.544006 -315.849762) (xy 291.547966 -315.800708) (xy 291.559743 -315.752924)
			(xy 291.579034 -315.707648) (xy 291.605337 -315.666052) (xy 291.637972 -315.629215) (xy 291.676093 -315.59809)
			(xy 291.718714 -315.573483) (xy 291.76473 -315.556031) (xy 291.812949 -315.546187) (xy 291.862124 -315.544206)
			(xy 291.910979 -315.550138) (xy 291.95825 -315.56383) (xy 292.002712 -315.584928) (xy 292.043215 -315.612884)
			(xy 292.078708 -315.646976) (xy 292.108273 -315.68632) (xy 292.131144 -315.729897) (xy 292.146728 -315.776578)
			(xy 292.154623 -315.825155) (xy 292.155118 -315.849762) (xy 292.154623 -315.874369) (xy 292.154444 -315.87547)
			(xy 292.473122 -315.87547) (xy 292.473122 -315.824054) (xy 292.481165 -315.773272) (xy 292.497053 -315.724373)
			(xy 292.520396 -315.678561) (xy 292.550617 -315.636965) (xy 292.586973 -315.600609) (xy 292.628569 -315.570388)
			(xy 292.674381 -315.547045) (xy 292.72328 -315.531157) (xy 292.774062 -315.523114) (xy 292.825478 -315.523114)
			(xy 292.87626 -315.531157) (xy 292.925159 -315.547045) (xy 292.970971 -315.570388) (xy 293.012567 -315.600609)
			(xy 293.048923 -315.636965) (xy 293.079144 -315.678561) (xy 293.102487 -315.724373) (xy 293.118375 -315.773272)
			(xy 293.126418 -315.824054) (xy 293.126922 -315.849762) (xy 293.443926 -315.849762) (xy 293.447886 -315.800708)
			(xy 293.459663 -315.752924) (xy 293.478954 -315.707648) (xy 293.505257 -315.666052) (xy 293.537892 -315.629215)
			(xy 293.576013 -315.59809) (xy 293.618634 -315.573483) (xy 293.66465 -315.556031) (xy 293.712869 -315.546187)
			(xy 293.762044 -315.544206) (xy 293.810899 -315.550138) (xy 293.85817 -315.56383) (xy 293.902632 -315.584928)
			(xy 293.943135 -315.612884) (xy 293.978628 -315.646976) (xy 294.008193 -315.68632) (xy 294.031064 -315.729897)
			(xy 294.046648 -315.776578) (xy 294.054543 -315.825155) (xy 294.055038 -315.849762) (xy 294.054543 -315.874369)
			(xy 294.054364 -315.87547) (xy 294.373042 -315.87547) (xy 294.373042 -315.824054) (xy 294.381085 -315.773272)
			(xy 294.396973 -315.724373) (xy 294.420316 -315.678561) (xy 294.450537 -315.636965) (xy 294.486893 -315.600609)
			(xy 294.528489 -315.570388) (xy 294.574301 -315.547045) (xy 294.6232 -315.531157) (xy 294.673982 -315.523114)
			(xy 294.725398 -315.523114) (xy 294.77618 -315.531157) (xy 294.825079 -315.547045) (xy 294.870891 -315.570388)
			(xy 294.912487 -315.600609) (xy 294.948843 -315.636965) (xy 294.979064 -315.678561) (xy 295.002407 -315.724373)
			(xy 295.018295 -315.773272) (xy 295.026338 -315.824054) (xy 295.026842 -315.849762) (xy 295.3441 -315.849762)
			(xy 295.34806 -315.800708) (xy 295.359837 -315.752924) (xy 295.379128 -315.707648) (xy 295.405431 -315.666052)
			(xy 295.438066 -315.629215) (xy 295.476187 -315.59809) (xy 295.518808 -315.573483) (xy 295.564824 -315.556031)
			(xy 295.613043 -315.546187) (xy 295.662218 -315.544206) (xy 295.711073 -315.550138) (xy 295.758344 -315.56383)
			(xy 295.802806 -315.584928) (xy 295.843309 -315.612884) (xy 295.878802 -315.646976) (xy 295.908367 -315.68632)
			(xy 295.931238 -315.729897) (xy 295.946822 -315.776578) (xy 295.954717 -315.825155) (xy 295.955212 -315.849762)
			(xy 295.954717 -315.874369) (xy 295.954538 -315.87547) (xy 296.273216 -315.87547) (xy 296.273216 -315.824054)
			(xy 296.281259 -315.773272) (xy 296.297147 -315.724373) (xy 296.32049 -315.678561) (xy 296.350711 -315.636965)
			(xy 296.387067 -315.600609) (xy 296.428663 -315.570388) (xy 296.474475 -315.547045) (xy 296.523374 -315.531157)
			(xy 296.574156 -315.523114) (xy 296.625572 -315.523114) (xy 296.676354 -315.531157) (xy 296.725253 -315.547045)
			(xy 296.771065 -315.570388) (xy 296.812661 -315.600609) (xy 296.849017 -315.636965) (xy 296.879238 -315.678561)
			(xy 296.902581 -315.724373) (xy 296.918469 -315.773272) (xy 296.926512 -315.824054) (xy 296.927016 -315.849762)
			(xy 297.24402 -315.849762) (xy 297.24798 -315.800708) (xy 297.259757 -315.752924) (xy 297.279048 -315.707648)
			(xy 297.305351 -315.666052) (xy 297.337986 -315.629215) (xy 297.376107 -315.59809) (xy 297.418728 -315.573483)
			(xy 297.464744 -315.556031) (xy 297.512963 -315.546187) (xy 297.562138 -315.544206) (xy 297.610993 -315.550138)
			(xy 297.658264 -315.56383) (xy 297.702726 -315.584928) (xy 297.743229 -315.612884) (xy 297.778722 -315.646976)
			(xy 297.808287 -315.68632) (xy 297.831158 -315.729897) (xy 297.846742 -315.776578) (xy 297.854637 -315.825155)
			(xy 297.855132 -315.849762) (xy 297.854637 -315.874369) (xy 297.854458 -315.87547) (xy 298.173136 -315.87547)
			(xy 298.173136 -315.824054) (xy 298.181179 -315.773272) (xy 298.197067 -315.724373) (xy 298.22041 -315.678561)
			(xy 298.250631 -315.636965) (xy 298.286987 -315.600609) (xy 298.328583 -315.570388) (xy 298.374395 -315.547045)
			(xy 298.423294 -315.531157) (xy 298.474076 -315.523114) (xy 298.525492 -315.523114) (xy 298.576274 -315.531157)
			(xy 298.625173 -315.547045) (xy 298.670985 -315.570388) (xy 298.712581 -315.600609) (xy 298.748937 -315.636965)
			(xy 298.779158 -315.678561) (xy 298.802501 -315.724373) (xy 298.818389 -315.773272) (xy 298.826432 -315.824054)
			(xy 298.826936 -315.849762) (xy 299.14394 -315.849762) (xy 299.1479 -315.800708) (xy 299.159677 -315.752924)
			(xy 299.178968 -315.707648) (xy 299.205271 -315.666052) (xy 299.237906 -315.629215) (xy 299.276027 -315.59809)
			(xy 299.318648 -315.573483) (xy 299.364664 -315.556031) (xy 299.412883 -315.546187) (xy 299.462058 -315.544206)
			(xy 299.510913 -315.550138) (xy 299.558184 -315.56383) (xy 299.602646 -315.584928) (xy 299.643149 -315.612884)
			(xy 299.678642 -315.646976) (xy 299.708207 -315.68632) (xy 299.731078 -315.729897) (xy 299.746662 -315.776578)
			(xy 299.754557 -315.825155) (xy 299.755052 -315.849762) (xy 299.754557 -315.874369) (xy 299.754378 -315.87547)
			(xy 300.073056 -315.87547) (xy 300.073056 -315.824054) (xy 300.081099 -315.773272) (xy 300.096987 -315.724373)
			(xy 300.12033 -315.678561) (xy 300.150551 -315.636965) (xy 300.186907 -315.600609) (xy 300.228503 -315.570388)
			(xy 300.274315 -315.547045) (xy 300.323214 -315.531157) (xy 300.373996 -315.523114) (xy 300.425412 -315.523114)
			(xy 300.476194 -315.531157) (xy 300.525093 -315.547045) (xy 300.570905 -315.570388) (xy 300.612501 -315.600609)
			(xy 300.648857 -315.636965) (xy 300.679078 -315.678561) (xy 300.702421 -315.724373) (xy 300.718309 -315.773272)
			(xy 300.726352 -315.824054) (xy 300.726856 -315.849762) (xy 301.044114 -315.849762) (xy 301.048074 -315.800708)
			(xy 301.059851 -315.752924) (xy 301.079142 -315.707648) (xy 301.105445 -315.666052) (xy 301.13808 -315.629215)
			(xy 301.176201 -315.59809) (xy 301.218822 -315.573483) (xy 301.264838 -315.556031) (xy 301.313057 -315.546187)
			(xy 301.362232 -315.544206) (xy 301.411087 -315.550138) (xy 301.458358 -315.56383) (xy 301.50282 -315.584928)
			(xy 301.543323 -315.612884) (xy 301.578816 -315.646976) (xy 301.608381 -315.68632) (xy 301.631252 -315.729897)
			(xy 301.646836 -315.776578) (xy 301.654731 -315.825155) (xy 301.655226 -315.849762) (xy 301.654731 -315.874369)
			(xy 301.654552 -315.87547) (xy 301.97323 -315.87547) (xy 301.97323 -315.824054) (xy 301.981273 -315.773272)
			(xy 301.997161 -315.724373) (xy 302.020504 -315.678561) (xy 302.050725 -315.636965) (xy 302.087081 -315.600609)
			(xy 302.128677 -315.570388) (xy 302.174489 -315.547045) (xy 302.223388 -315.531157) (xy 302.27417 -315.523114)
			(xy 302.325586 -315.523114) (xy 302.376368 -315.531157) (xy 302.425267 -315.547045) (xy 302.471079 -315.570388)
			(xy 302.512675 -315.600609) (xy 302.549031 -315.636965) (xy 302.579252 -315.678561) (xy 302.602595 -315.724373)
			(xy 302.618483 -315.773272) (xy 302.626526 -315.824054) (xy 302.62703 -315.849762) (xy 302.944034 -315.849762)
			(xy 302.947994 -315.800708) (xy 302.959771 -315.752924) (xy 302.979062 -315.707648) (xy 303.005365 -315.666052)
			(xy 303.038 -315.629215) (xy 303.076121 -315.59809) (xy 303.118742 -315.573483) (xy 303.164758 -315.556031)
			(xy 303.212977 -315.546187) (xy 303.262152 -315.544206) (xy 303.311007 -315.550138) (xy 303.358278 -315.56383)
			(xy 303.40274 -315.584928) (xy 303.443243 -315.612884) (xy 303.478736 -315.646976) (xy 303.508301 -315.68632)
			(xy 303.531172 -315.729897) (xy 303.546756 -315.776578) (xy 303.554651 -315.825155) (xy 303.555146 -315.849762)
			(xy 303.554651 -315.874369) (xy 303.546756 -315.922946) (xy 303.531172 -315.969627) (xy 303.508301 -316.013204)
			(xy 303.478736 -316.052548) (xy 303.443243 -316.08664) (xy 303.40274 -316.114596) (xy 303.358278 -316.135694)
			(xy 303.311007 -316.149386) (xy 303.262152 -316.155318) (xy 303.212977 -316.153337) (xy 303.164758 -316.143493)
			(xy 303.118742 -316.126041) (xy 303.076121 -316.101434) (xy 303.038 -316.070309) (xy 303.005365 -316.033472)
			(xy 302.979062 -315.991876) (xy 302.959771 -315.9466) (xy 302.947994 -315.898816) (xy 302.944034 -315.849762)
			(xy 302.62703 -315.849762) (xy 302.626526 -315.87547) (xy 302.618483 -315.926252) (xy 302.602595 -315.975151)
			(xy 302.579252 -316.020963) (xy 302.549031 -316.062559) (xy 302.512675 -316.098915) (xy 302.471079 -316.129136)
			(xy 302.425267 -316.152479) (xy 302.376368 -316.168367) (xy 302.325586 -316.17641) (xy 302.27417 -316.17641)
			(xy 302.223388 -316.168367) (xy 302.174489 -316.152479) (xy 302.128677 -316.129136) (xy 302.087081 -316.098915)
			(xy 302.050725 -316.062559) (xy 302.020504 -316.020963) (xy 301.997161 -315.975151) (xy 301.981273 -315.926252)
			(xy 301.97323 -315.87547) (xy 301.654552 -315.87547) (xy 301.646836 -315.922946) (xy 301.631252 -315.969627)
			(xy 301.608381 -316.013204) (xy 301.578816 -316.052548) (xy 301.543323 -316.08664) (xy 301.50282 -316.114596)
			(xy 301.458358 -316.135694) (xy 301.411087 -316.149386) (xy 301.362232 -316.155318) (xy 301.313057 -316.153337)
			(xy 301.264838 -316.143493) (xy 301.218822 -316.126041) (xy 301.176201 -316.101434) (xy 301.13808 -316.070309)
			(xy 301.105445 -316.033472) (xy 301.079142 -315.991876) (xy 301.059851 -315.9466) (xy 301.048074 -315.898816)
			(xy 301.044114 -315.849762) (xy 300.726856 -315.849762) (xy 300.726352 -315.87547) (xy 300.718309 -315.926252)
			(xy 300.702421 -315.975151) (xy 300.679078 -316.020963) (xy 300.648857 -316.062559) (xy 300.612501 -316.098915)
			(xy 300.570905 -316.129136) (xy 300.525093 -316.152479) (xy 300.476194 -316.168367) (xy 300.425412 -316.17641)
			(xy 300.373996 -316.17641) (xy 300.323214 -316.168367) (xy 300.274315 -316.152479) (xy 300.228503 -316.129136)
			(xy 300.186907 -316.098915) (xy 300.150551 -316.062559) (xy 300.12033 -316.020963) (xy 300.096987 -315.975151)
			(xy 300.081099 -315.926252) (xy 300.073056 -315.87547) (xy 299.754378 -315.87547) (xy 299.746662 -315.922946)
			(xy 299.731078 -315.969627) (xy 299.708207 -316.013204) (xy 299.678642 -316.052548) (xy 299.643149 -316.08664)
			(xy 299.602646 -316.114596) (xy 299.558184 -316.135694) (xy 299.510913 -316.149386) (xy 299.462058 -316.155318)
			(xy 299.412883 -316.153337) (xy 299.364664 -316.143493) (xy 299.318648 -316.126041) (xy 299.276027 -316.101434)
			(xy 299.237906 -316.070309) (xy 299.205271 -316.033472) (xy 299.178968 -315.991876) (xy 299.159677 -315.9466)
			(xy 299.1479 -315.898816) (xy 299.14394 -315.849762) (xy 298.826936 -315.849762) (xy 298.826432 -315.87547)
			(xy 298.818389 -315.926252) (xy 298.802501 -315.975151) (xy 298.779158 -316.020963) (xy 298.748937 -316.062559)
			(xy 298.712581 -316.098915) (xy 298.670985 -316.129136) (xy 298.625173 -316.152479) (xy 298.576274 -316.168367)
			(xy 298.525492 -316.17641) (xy 298.474076 -316.17641) (xy 298.423294 -316.168367) (xy 298.374395 -316.152479)
			(xy 298.328583 -316.129136) (xy 298.286987 -316.098915) (xy 298.250631 -316.062559) (xy 298.22041 -316.020963)
			(xy 298.197067 -315.975151) (xy 298.181179 -315.926252) (xy 298.173136 -315.87547) (xy 297.854458 -315.87547)
			(xy 297.846742 -315.922946) (xy 297.831158 -315.969627) (xy 297.808287 -316.013204) (xy 297.778722 -316.052548)
			(xy 297.743229 -316.08664) (xy 297.702726 -316.114596) (xy 297.658264 -316.135694) (xy 297.610993 -316.149386)
			(xy 297.562138 -316.155318) (xy 297.512963 -316.153337) (xy 297.464744 -316.143493) (xy 297.418728 -316.126041)
			(xy 297.376107 -316.101434) (xy 297.337986 -316.070309) (xy 297.305351 -316.033472) (xy 297.279048 -315.991876)
			(xy 297.259757 -315.9466) (xy 297.24798 -315.898816) (xy 297.24402 -315.849762) (xy 296.927016 -315.849762)
			(xy 296.926512 -315.87547) (xy 296.918469 -315.926252) (xy 296.902581 -315.975151) (xy 296.879238 -316.020963)
			(xy 296.849017 -316.062559) (xy 296.812661 -316.098915) (xy 296.771065 -316.129136) (xy 296.725253 -316.152479)
			(xy 296.676354 -316.168367) (xy 296.625572 -316.17641) (xy 296.574156 -316.17641) (xy 296.523374 -316.168367)
			(xy 296.474475 -316.152479) (xy 296.428663 -316.129136) (xy 296.387067 -316.098915) (xy 296.350711 -316.062559)
			(xy 296.32049 -316.020963) (xy 296.297147 -315.975151) (xy 296.281259 -315.926252) (xy 296.273216 -315.87547)
			(xy 295.954538 -315.87547) (xy 295.946822 -315.922946) (xy 295.931238 -315.969627) (xy 295.908367 -316.013204)
			(xy 295.878802 -316.052548) (xy 295.843309 -316.08664) (xy 295.802806 -316.114596) (xy 295.758344 -316.135694)
			(xy 295.711073 -316.149386) (xy 295.662218 -316.155318) (xy 295.613043 -316.153337) (xy 295.564824 -316.143493)
			(xy 295.518808 -316.126041) (xy 295.476187 -316.101434) (xy 295.438066 -316.070309) (xy 295.405431 -316.033472)
			(xy 295.379128 -315.991876) (xy 295.359837 -315.9466) (xy 295.34806 -315.898816) (xy 295.3441 -315.849762)
			(xy 295.026842 -315.849762) (xy 295.026338 -315.87547) (xy 295.018295 -315.926252) (xy 295.002407 -315.975151)
			(xy 294.979064 -316.020963) (xy 294.948843 -316.062559) (xy 294.912487 -316.098915) (xy 294.870891 -316.129136)
			(xy 294.825079 -316.152479) (xy 294.77618 -316.168367) (xy 294.725398 -316.17641) (xy 294.673982 -316.17641)
			(xy 294.6232 -316.168367) (xy 294.574301 -316.152479) (xy 294.528489 -316.129136) (xy 294.486893 -316.098915)
			(xy 294.450537 -316.062559) (xy 294.420316 -316.020963) (xy 294.396973 -315.975151) (xy 294.381085 -315.926252)
			(xy 294.373042 -315.87547) (xy 294.054364 -315.87547) (xy 294.046648 -315.922946) (xy 294.031064 -315.969627)
			(xy 294.008193 -316.013204) (xy 293.978628 -316.052548) (xy 293.943135 -316.08664) (xy 293.902632 -316.114596)
			(xy 293.85817 -316.135694) (xy 293.810899 -316.149386) (xy 293.762044 -316.155318) (xy 293.712869 -316.153337)
			(xy 293.66465 -316.143493) (xy 293.618634 -316.126041) (xy 293.576013 -316.101434) (xy 293.537892 -316.070309)
			(xy 293.505257 -316.033472) (xy 293.478954 -315.991876) (xy 293.459663 -315.9466) (xy 293.447886 -315.898816)
			(xy 293.443926 -315.849762) (xy 293.126922 -315.849762) (xy 293.126418 -315.87547) (xy 293.118375 -315.926252)
			(xy 293.102487 -315.975151) (xy 293.079144 -316.020963) (xy 293.048923 -316.062559) (xy 293.012567 -316.098915)
			(xy 292.970971 -316.129136) (xy 292.925159 -316.152479) (xy 292.87626 -316.168367) (xy 292.825478 -316.17641)
			(xy 292.774062 -316.17641) (xy 292.72328 -316.168367) (xy 292.674381 -316.152479) (xy 292.628569 -316.129136)
			(xy 292.586973 -316.098915) (xy 292.550617 -316.062559) (xy 292.520396 -316.020963) (xy 292.497053 -315.975151)
			(xy 292.481165 -315.926252) (xy 292.473122 -315.87547) (xy 292.154444 -315.87547) (xy 292.146728 -315.922946)
			(xy 292.131144 -315.969627) (xy 292.108273 -316.013204) (xy 292.078708 -316.052548) (xy 292.043215 -316.08664)
			(xy 292.002712 -316.114596) (xy 291.95825 -316.135694) (xy 291.910979 -316.149386) (xy 291.862124 -316.155318)
			(xy 291.812949 -316.153337) (xy 291.76473 -316.143493) (xy 291.718714 -316.126041) (xy 291.676093 -316.101434)
			(xy 291.637972 -316.070309) (xy 291.605337 -316.033472) (xy 291.579034 -315.991876) (xy 291.559743 -315.9466)
			(xy 291.547966 -315.898816) (xy 291.544006 -315.849762) (xy 291.227002 -315.849762) (xy 291.226498 -315.87547)
			(xy 291.218455 -315.926252) (xy 291.202567 -315.975151) (xy 291.179224 -316.020963) (xy 291.149003 -316.062559)
			(xy 291.112647 -316.098915) (xy 291.071051 -316.129136) (xy 291.025239 -316.152479) (xy 290.97634 -316.168367)
			(xy 290.925558 -316.17641) (xy 290.874142 -316.17641) (xy 290.82336 -316.168367) (xy 290.774461 -316.152479)
			(xy 290.728649 -316.129136) (xy 290.687053 -316.098915) (xy 290.650697 -316.062559) (xy 290.620476 -316.020963)
			(xy 290.597133 -315.975151) (xy 290.581245 -315.926252) (xy 290.573202 -315.87547) (xy 290.254524 -315.87547)
			(xy 290.246808 -315.922946) (xy 290.231224 -315.969627) (xy 290.208353 -316.013204) (xy 290.178788 -316.052548)
			(xy 290.143295 -316.08664) (xy 290.102792 -316.114596) (xy 290.05833 -316.135694) (xy 290.011059 -316.149386)
			(xy 289.962204 -316.155318) (xy 289.913029 -316.153337) (xy 289.86481 -316.143493) (xy 289.818794 -316.126041)
			(xy 289.776173 -316.101434) (xy 289.738052 -316.070309) (xy 289.705417 -316.033472) (xy 289.679114 -315.991876)
			(xy 289.659823 -315.9466) (xy 289.648046 -315.898816) (xy 289.644086 -315.849762) (xy 289.327082 -315.849762)
			(xy 289.326578 -315.87547) (xy 289.318535 -315.926252) (xy 289.302647 -315.975151) (xy 289.279304 -316.020963)
			(xy 289.249083 -316.062559) (xy 289.212727 -316.098915) (xy 289.171131 -316.129136) (xy 289.125319 -316.152479)
			(xy 289.07642 -316.168367) (xy 289.025638 -316.17641) (xy 288.974222 -316.17641) (xy 288.92344 -316.168367)
			(xy 288.874541 -316.152479) (xy 288.828729 -316.129136) (xy 288.787133 -316.098915) (xy 288.750777 -316.062559)
			(xy 288.720556 -316.020963) (xy 288.697213 -315.975151) (xy 288.681325 -315.926252) (xy 288.673282 -315.87547)
			(xy 288.35435 -315.87547) (xy 288.346634 -315.922946) (xy 288.33105 -315.969627) (xy 288.308179 -316.013204)
			(xy 288.278614 -316.052548) (xy 288.243121 -316.08664) (xy 288.202618 -316.114596) (xy 288.158156 -316.135694)
			(xy 288.110885 -316.149386) (xy 288.06203 -316.155318) (xy 288.012855 -316.153337) (xy 287.964636 -316.143493)
			(xy 287.91862 -316.126041) (xy 287.875999 -316.101434) (xy 287.837878 -316.070309) (xy 287.805243 -316.033472)
			(xy 287.77894 -315.991876) (xy 287.759649 -315.9466) (xy 287.747872 -315.898816) (xy 287.743912 -315.849762)
			(xy 287.426908 -315.849762) (xy 287.426404 -315.87547) (xy 287.418361 -315.926252) (xy 287.402473 -315.975151)
			(xy 287.37913 -316.020963) (xy 287.348909 -316.062559) (xy 287.312553 -316.098915) (xy 287.270957 -316.129136)
			(xy 287.225145 -316.152479) (xy 287.176246 -316.168367) (xy 287.125464 -316.17641) (xy 287.074048 -316.17641)
			(xy 287.023266 -316.168367) (xy 286.974367 -316.152479) (xy 286.928555 -316.129136) (xy 286.886959 -316.098915)
			(xy 286.850603 -316.062559) (xy 286.820382 -316.020963) (xy 286.797039 -315.975151) (xy 286.781151 -315.926252)
			(xy 286.773108 -315.87547) (xy 286.45443 -315.87547) (xy 286.446714 -315.922946) (xy 286.43113 -315.969627)
			(xy 286.408259 -316.013204) (xy 286.378694 -316.052548) (xy 286.343201 -316.08664) (xy 286.302698 -316.114596)
			(xy 286.258236 -316.135694) (xy 286.210965 -316.149386) (xy 286.16211 -316.155318) (xy 286.112935 -316.153337)
			(xy 286.064716 -316.143493) (xy 286.0187 -316.126041) (xy 285.976079 -316.101434) (xy 285.937958 -316.070309)
			(xy 285.905323 -316.033472) (xy 285.87902 -315.991876) (xy 285.859729 -315.9466) (xy 285.847952 -315.898816)
			(xy 285.843992 -315.849762) (xy 285.526988 -315.849762) (xy 285.526484 -315.87547) (xy 285.518441 -315.926252)
			(xy 285.502553 -315.975151) (xy 285.47921 -316.020963) (xy 285.448989 -316.062559) (xy 285.412633 -316.098915)
			(xy 285.371037 -316.129136) (xy 285.325225 -316.152479) (xy 285.276326 -316.168367) (xy 285.225544 -316.17641)
			(xy 285.174128 -316.17641) (xy 285.123346 -316.168367) (xy 285.074447 -316.152479) (xy 285.028635 -316.129136)
			(xy 284.987039 -316.098915) (xy 284.950683 -316.062559) (xy 284.920462 -316.020963) (xy 284.897119 -315.975151)
			(xy 284.881231 -315.926252) (xy 284.873188 -315.87547) (xy 284.55451 -315.87547) (xy 284.546794 -315.922946)
			(xy 284.53121 -315.969627) (xy 284.508339 -316.013204) (xy 284.478774 -316.052548) (xy 284.443281 -316.08664)
			(xy 284.402778 -316.114596) (xy 284.358316 -316.135694) (xy 284.311045 -316.149386) (xy 284.26219 -316.155318)
			(xy 284.213015 -316.153337) (xy 284.164796 -316.143493) (xy 284.11878 -316.126041) (xy 284.076159 -316.101434)
			(xy 284.038038 -316.070309) (xy 284.005403 -316.033472) (xy 283.9791 -315.991876) (xy 283.959809 -315.9466)
			(xy 283.948032 -315.898816) (xy 283.944072 -315.849762) (xy 283.627068 -315.849762) (xy 283.626564 -315.87547)
			(xy 283.618521 -315.926252) (xy 283.602633 -315.975151) (xy 283.57929 -316.020963) (xy 283.549069 -316.062559)
			(xy 283.512713 -316.098915) (xy 283.471117 -316.129136) (xy 283.425305 -316.152479) (xy 283.376406 -316.168367)
			(xy 283.325624 -316.17641) (xy 283.274208 -316.17641) (xy 283.223426 -316.168367) (xy 283.174527 -316.152479)
			(xy 283.128715 -316.129136) (xy 283.087119 -316.098915) (xy 283.050763 -316.062559) (xy 283.020542 -316.020963)
			(xy 282.997199 -315.975151) (xy 282.981311 -315.926252) (xy 282.973268 -315.87547) (xy 282.654336 -315.87547)
			(xy 282.64662 -315.922946) (xy 282.631036 -315.969627) (xy 282.608165 -316.013204) (xy 282.5786 -316.052548)
			(xy 282.543107 -316.08664) (xy 282.502604 -316.114596) (xy 282.458142 -316.135694) (xy 282.410871 -316.149386)
			(xy 282.362016 -316.155318) (xy 282.312841 -316.153337) (xy 282.264622 -316.143493) (xy 282.218606 -316.126041)
			(xy 282.175985 -316.101434) (xy 282.137864 -316.070309) (xy 282.105229 -316.033472) (xy 282.078926 -315.991876)
			(xy 282.059635 -315.9466) (xy 282.047858 -315.898816) (xy 282.043898 -315.849762) (xy 281.726894 -315.849762)
			(xy 281.72639 -315.87547) (xy 281.718347 -315.926252) (xy 281.702459 -315.975151) (xy 281.679116 -316.020963)
			(xy 281.648895 -316.062559) (xy 281.612539 -316.098915) (xy 281.570943 -316.129136) (xy 281.525131 -316.152479)
			(xy 281.476232 -316.168367) (xy 281.42545 -316.17641) (xy 281.374034 -316.17641) (xy 281.323252 -316.168367)
			(xy 281.274353 -316.152479) (xy 281.228541 -316.129136) (xy 281.186945 -316.098915) (xy 281.150589 -316.062559)
			(xy 281.120368 -316.020963) (xy 281.097025 -315.975151) (xy 281.081137 -315.926252) (xy 281.073094 -315.87547)
			(xy 280.754416 -315.87547) (xy 280.7467 -315.922946) (xy 280.731116 -315.969627) (xy 280.708245 -316.013204)
			(xy 280.67868 -316.052548) (xy 280.643187 -316.08664) (xy 280.602684 -316.114596) (xy 280.558222 -316.135694)
			(xy 280.510951 -316.149386) (xy 280.462096 -316.155318) (xy 280.412921 -316.153337) (xy 280.364702 -316.143493)
			(xy 280.318686 -316.126041) (xy 280.276065 -316.101434) (xy 280.237944 -316.070309) (xy 280.205309 -316.033472)
			(xy 280.179006 -315.991876) (xy 280.159715 -315.9466) (xy 280.147938 -315.898816) (xy 280.143978 -315.849762)
			(xy 279.826974 -315.849762) (xy 279.82647 -315.87547) (xy 279.818427 -315.926252) (xy 279.802539 -315.975151)
			(xy 279.779196 -316.020963) (xy 279.748975 -316.062559) (xy 279.712619 -316.098915) (xy 279.671023 -316.129136)
			(xy 279.625211 -316.152479) (xy 279.576312 -316.168367) (xy 279.52553 -316.17641) (xy 279.474114 -316.17641)
			(xy 279.423332 -316.168367) (xy 279.374433 -316.152479) (xy 279.328621 -316.129136) (xy 279.287025 -316.098915)
			(xy 279.250669 -316.062559) (xy 279.220448 -316.020963) (xy 279.197105 -315.975151) (xy 279.181217 -315.926252)
			(xy 279.173174 -315.87547) (xy 278.854496 -315.87547) (xy 278.84678 -315.922946) (xy 278.831196 -315.969627)
			(xy 278.808325 -316.013204) (xy 278.77876 -316.052548) (xy 278.743267 -316.08664) (xy 278.702764 -316.114596)
			(xy 278.658302 -316.135694) (xy 278.611031 -316.149386) (xy 278.562176 -316.155318) (xy 278.513001 -316.153337)
			(xy 278.464782 -316.143493) (xy 278.418766 -316.126041) (xy 278.376145 -316.101434) (xy 278.338024 -316.070309)
			(xy 278.305389 -316.033472) (xy 278.279086 -315.991876) (xy 278.259795 -315.9466) (xy 278.248018 -315.898816)
			(xy 278.244058 -315.849762) (xy 277.927054 -315.849762) (xy 277.92655 -315.87547) (xy 277.918507 -315.926252)
			(xy 277.902619 -315.975151) (xy 277.879276 -316.020963) (xy 277.849055 -316.062559) (xy 277.812699 -316.098915)
			(xy 277.771103 -316.129136) (xy 277.725291 -316.152479) (xy 277.676392 -316.168367) (xy 277.62561 -316.17641)
			(xy 277.574194 -316.17641) (xy 277.523412 -316.168367) (xy 277.474513 -316.152479) (xy 277.428701 -316.129136)
			(xy 277.387105 -316.098915) (xy 277.350749 -316.062559) (xy 277.320528 -316.020963) (xy 277.297185 -315.975151)
			(xy 277.281297 -315.926252) (xy 277.273254 -315.87547) (xy 276.954322 -315.87547) (xy 276.946606 -315.922946)
			(xy 276.931022 -315.969627) (xy 276.908151 -316.013204) (xy 276.878586 -316.052548) (xy 276.843093 -316.08664)
			(xy 276.80259 -316.114596) (xy 276.758128 -316.135694) (xy 276.710857 -316.149386) (xy 276.662002 -316.155318)
			(xy 276.612827 -316.153337) (xy 276.564608 -316.143493) (xy 276.518592 -316.126041) (xy 276.475971 -316.101434)
			(xy 276.43785 -316.070309) (xy 276.405215 -316.033472) (xy 276.378912 -315.991876) (xy 276.359621 -315.9466)
			(xy 276.347844 -315.898816) (xy 276.343884 -315.849762) (xy 276.02688 -315.849762) (xy 276.026376 -315.87547)
			(xy 276.018333 -315.926252) (xy 276.002445 -315.975151) (xy 275.979102 -316.020963) (xy 275.948881 -316.062559)
			(xy 275.912525 -316.098915) (xy 275.870929 -316.129136) (xy 275.825117 -316.152479) (xy 275.776218 -316.168367)
			(xy 275.725436 -316.17641) (xy 275.67402 -316.17641) (xy 275.623238 -316.168367) (xy 275.574339 -316.152479)
			(xy 275.528527 -316.129136) (xy 275.486931 -316.098915) (xy 275.450575 -316.062559) (xy 275.420354 -316.020963)
			(xy 275.397011 -315.975151) (xy 275.381123 -315.926252) (xy 275.37308 -315.87547) (xy 275.054402 -315.87547)
			(xy 275.046686 -315.922946) (xy 275.031102 -315.969627) (xy 275.008231 -316.013204) (xy 274.978666 -316.052548)
			(xy 274.943173 -316.08664) (xy 274.90267 -316.114596) (xy 274.858208 -316.135694) (xy 274.810937 -316.149386)
			(xy 274.762082 -316.155318) (xy 274.712907 -316.153337) (xy 274.664688 -316.143493) (xy 274.618672 -316.126041)
			(xy 274.576051 -316.101434) (xy 274.53793 -316.070309) (xy 274.505295 -316.033472) (xy 274.478992 -315.991876)
			(xy 274.459701 -315.9466) (xy 274.447924 -315.898816) (xy 274.443964 -315.849762) (xy 274.12696 -315.849762)
			(xy 274.126456 -315.87547) (xy 274.118413 -315.926252) (xy 274.102525 -315.975151) (xy 274.079182 -316.020963)
			(xy 274.048961 -316.062559) (xy 274.012605 -316.098915) (xy 273.971009 -316.129136) (xy 273.925197 -316.152479)
			(xy 273.876298 -316.168367) (xy 273.825516 -316.17641) (xy 273.7741 -316.17641) (xy 273.723318 -316.168367)
			(xy 273.674419 -316.152479) (xy 273.628607 -316.129136) (xy 273.587011 -316.098915) (xy 273.550655 -316.062559)
			(xy 273.520434 -316.020963) (xy 273.497091 -315.975151) (xy 273.481203 -315.926252) (xy 273.47316 -315.87547)
			(xy 273.154482 -315.87547) (xy 273.146766 -315.922946) (xy 273.131182 -315.969627) (xy 273.108311 -316.013204)
			(xy 273.078746 -316.052548) (xy 273.043253 -316.08664) (xy 273.00275 -316.114596) (xy 272.958288 -316.135694)
			(xy 272.911017 -316.149386) (xy 272.862162 -316.155318) (xy 272.812987 -316.153337) (xy 272.764768 -316.143493)
			(xy 272.718752 -316.126041) (xy 272.676131 -316.101434) (xy 272.63801 -316.070309) (xy 272.605375 -316.033472)
			(xy 272.579072 -315.991876) (xy 272.559781 -315.9466) (xy 272.548004 -315.898816) (xy 272.544044 -315.849762)
			(xy 272.22704 -315.849762) (xy 272.226536 -315.87547) (xy 272.218493 -315.926252) (xy 272.202605 -315.975151)
			(xy 272.179262 -316.020963) (xy 272.149041 -316.062559) (xy 272.112685 -316.098915) (xy 272.071089 -316.129136)
			(xy 272.025277 -316.152479) (xy 271.976378 -316.168367) (xy 271.925596 -316.17641) (xy 271.87418 -316.17641)
			(xy 271.823398 -316.168367) (xy 271.774499 -316.152479) (xy 271.728687 -316.129136) (xy 271.687091 -316.098915)
			(xy 271.650735 -316.062559) (xy 271.620514 -316.020963) (xy 271.597171 -315.975151) (xy 271.581283 -315.926252)
			(xy 271.57324 -315.87547) (xy 271.254562 -315.87547) (xy 271.246846 -315.922946) (xy 271.231262 -315.969627)
			(xy 271.208391 -316.013204) (xy 271.178826 -316.052548) (xy 271.143333 -316.08664) (xy 271.10283 -316.114596)
			(xy 271.058368 -316.135694) (xy 271.011097 -316.149386) (xy 270.962242 -316.155318) (xy 270.913067 -316.153337)
			(xy 270.864848 -316.143493) (xy 270.818832 -316.126041) (xy 270.776211 -316.101434) (xy 270.73809 -316.070309)
			(xy 270.705455 -316.033472) (xy 270.679152 -315.991876) (xy 270.659861 -315.9466) (xy 270.648084 -315.898816)
			(xy 270.644124 -315.849762) (xy 270.305022 -315.849762) (xy 270.304527 -315.874369) (xy 270.296632 -315.922946)
			(xy 270.281048 -315.969627) (xy 270.258177 -316.013204) (xy 270.228612 -316.052548) (xy 270.193119 -316.08664)
			(xy 270.152616 -316.114596) (xy 270.108154 -316.135694) (xy 270.060883 -316.149386) (xy 270.012028 -316.155318)
			(xy 269.962853 -316.153337) (xy 269.914634 -316.143493) (xy 269.868618 -316.126041) (xy 269.825997 -316.101434)
			(xy 269.787876 -316.070309) (xy 269.755241 -316.033472) (xy 269.728938 -315.991876) (xy 269.709647 -315.9466)
			(xy 269.69787 -315.898816) (xy 269.69391 -315.849762) (xy 269.355062 -315.849762) (xy 269.354567 -315.874369)
			(xy 269.346672 -315.922946) (xy 269.331088 -315.969627) (xy 269.308217 -316.013204) (xy 269.278652 -316.052548)
			(xy 269.243159 -316.08664) (xy 269.202656 -316.114596) (xy 269.158194 -316.135694) (xy 269.110923 -316.149386)
			(xy 269.062068 -316.155318) (xy 269.012893 -316.153337) (xy 268.964674 -316.143493) (xy 268.918658 -316.126041)
			(xy 268.876037 -316.101434) (xy 268.837916 -316.070309) (xy 268.805281 -316.033472) (xy 268.778978 -315.991876)
			(xy 268.759687 -315.9466) (xy 268.74791 -315.898816) (xy 268.74395 -315.849762) (xy 248.814844 -315.849762)
			(xy 248.814844 -322.665344) (xy 248.815277 -322.67541) (xy 248.823007 -322.693998) (xy 248.82983 -322.701412)
			(xy 249.60453 -323.476112) (xy 249.611642 -323.483224) (xy 249.630184 -323.491098)
		)
		(stroke
			(width 0)
			(type solid)
		)
		(fill yes)
		(layer "In11.Cu")
		(net "P1V25_PEX2")
	)
	(gr_poly
		(pts
			(xy 25.455372 -323.491098) (xy 25.464261 -323.490761) (xy 25.480965 -323.484672) (xy 25.494566 -323.473222)
			(xy 25.499314 -323.465698) (xy 25.520396 -323.429376) (xy 25.520396 -323.428868) (xy 25.525476 -323.420232)
			(xy 25.542494 -323.395848) (xy 25.544018 -323.393562) (xy 25.548994 -323.384776) (xy 25.552279 -323.364868)
			(xy 25.550368 -323.354954) (xy 25.549368 -323.351076) (xy 25.546297 -323.343678) (xy 25.544272 -323.340222)
			(xy 25.535382 -323.32549) (xy 25.518364 -323.296534) (xy 25.470342 -323.212772) (xy 25.380289 -323.041955)
			(xy 25.297213 -322.867637) (xy 25.221251 -322.690105) (xy 25.152526 -322.509647) (xy 25.091151 -322.326559)
			(xy 25.037226 -322.14114) (xy 24.99084 -321.953693) (xy 24.952067 -321.764525) (xy 24.920972 -321.573944)
			(xy 24.897605 -321.382262) (xy 24.882004 -321.189792) (xy 24.874196 -320.996849) (xy 24.873712 -320.900298)
			(xy 24.873712 -320.900044) (xy 24.874209 -320.802611) (xy 24.882157 -320.607908) (xy 24.89804 -320.413691)
			(xy 24.921832 -320.220283) (xy 24.953493 -320.028007) (xy 24.992971 -319.837182) (xy 25.040199 -319.648126)
			(xy 25.095099 -319.461154) (xy 25.157579 -319.276577) (xy 25.227537 -319.094702) (xy 25.304854 -318.915831)
			(xy 25.389403 -318.740263) (xy 25.481043 -318.56829) (xy 25.579621 -318.400198) (xy 25.684973 -318.236267)
			(xy 25.796924 -318.076769) (xy 25.915288 -317.921971) (xy 26.039867 -317.772129) (xy 26.170454 -317.627493)
			(xy 26.306833 -317.488304) (xy 26.448775 -317.354793) (xy 26.596044 -317.227183) (xy 26.748396 -317.105687)
			(xy 26.905577 -316.990505) (xy 27.067325 -316.881831) (xy 27.233372 -316.779845) (xy 27.40344 -316.684716)
			(xy 27.577246 -316.596603) (xy 27.754502 -316.515653) (xy 27.934912 -316.442) (xy 28.118177 -316.375768)
			(xy 28.30399 -316.317065) (xy 28.492043 -316.265991) (xy 28.682023 -316.222629) (xy 28.873613 -316.187052)
			(xy 29.066496 -316.15932) (xy 29.260348 -316.139478) (xy 29.454849 -316.12756) (xy 29.649674 -316.123585)
			(xy 29.844499 -316.12756) (xy 30.039 -316.139478) (xy 30.232852 -316.15932) (xy 30.425735 -316.187052)
			(xy 30.617325 -316.222629) (xy 30.807305 -316.265991) (xy 30.995358 -316.317065) (xy 31.181171 -316.375768)
			(xy 31.364436 -316.442) (xy 31.544846 -316.515653) (xy 31.722102 -316.596603) (xy 31.895908 -316.684716)
			(xy 32.065976 -316.779845) (xy 32.097925 -316.799468) (xy 35.59354 -316.799468) (xy 35.5975 -316.750414)
			(xy 35.609277 -316.70263) (xy 35.628568 -316.657354) (xy 35.654871 -316.615758) (xy 35.687506 -316.578921)
			(xy 35.725627 -316.547796) (xy 35.768248 -316.523189) (xy 35.814264 -316.505737) (xy 35.862483 -316.495893)
			(xy 35.911658 -316.493912) (xy 35.960513 -316.499844) (xy 36.007784 -316.513536) (xy 36.052246 -316.534634)
			(xy 36.092749 -316.56259) (xy 36.128242 -316.596682) (xy 36.157807 -316.636026) (xy 36.180678 -316.679603)
			(xy 36.196262 -316.726284) (xy 36.204157 -316.774861) (xy 36.204652 -316.799468) (xy 36.204157 -316.824075)
			(xy 36.203937 -316.82543) (xy 36.523164 -316.82543) (xy 36.523164 -316.774014) (xy 36.531207 -316.723232)
			(xy 36.547095 -316.674333) (xy 36.570438 -316.628521) (xy 36.600659 -316.586925) (xy 36.637015 -316.550569)
			(xy 36.678611 -316.520348) (xy 36.724423 -316.497005) (xy 36.773322 -316.481117) (xy 36.824104 -316.473074)
			(xy 36.87552 -316.473074) (xy 36.926302 -316.481117) (xy 36.975201 -316.497005) (xy 37.021013 -316.520348)
			(xy 37.062609 -316.550569) (xy 37.098965 -316.586925) (xy 37.129186 -316.628521) (xy 37.152529 -316.674333)
			(xy 37.168417 -316.723232) (xy 37.17646 -316.774014) (xy 37.176964 -316.799722) (xy 37.17646 -316.82543)
			(xy 37.473124 -316.82543) (xy 37.473124 -316.774014) (xy 37.481167 -316.723232) (xy 37.497055 -316.674333)
			(xy 37.520398 -316.628521) (xy 37.550619 -316.586925) (xy 37.586975 -316.550569) (xy 37.628571 -316.520348)
			(xy 37.674383 -316.497005) (xy 37.723282 -316.481117) (xy 37.774064 -316.473074) (xy 37.82548 -316.473074)
			(xy 37.876262 -316.481117) (xy 37.925161 -316.497005) (xy 37.970973 -316.520348) (xy 38.012569 -316.550569)
			(xy 38.048925 -316.586925) (xy 38.079146 -316.628521) (xy 38.102489 -316.674333) (xy 38.118377 -316.723232)
			(xy 38.12642 -316.774014) (xy 38.126924 -316.799722) (xy 38.444182 -316.799722) (xy 38.448142 -316.750668)
			(xy 38.459919 -316.702884) (xy 38.47921 -316.657608) (xy 38.505513 -316.616012) (xy 38.538148 -316.579175)
			(xy 38.576269 -316.54805) (xy 38.61889 -316.523443) (xy 38.664906 -316.505991) (xy 38.713125 -316.496147)
			(xy 38.7623 -316.494166) (xy 38.811155 -316.500098) (xy 38.858426 -316.51379) (xy 38.902888 -316.534888)
			(xy 38.943391 -316.562844) (xy 38.978884 -316.596936) (xy 39.008449 -316.63628) (xy 39.03132 -316.679857)
			(xy 39.046904 -316.726538) (xy 39.054799 -316.775115) (xy 39.055294 -316.799722) (xy 39.054799 -316.824329)
			(xy 39.05462 -316.82543) (xy 39.373298 -316.82543) (xy 39.373298 -316.774014) (xy 39.381341 -316.723232)
			(xy 39.397229 -316.674333) (xy 39.420572 -316.628521) (xy 39.450793 -316.586925) (xy 39.487149 -316.550569)
			(xy 39.528745 -316.520348) (xy 39.574557 -316.497005) (xy 39.623456 -316.481117) (xy 39.674238 -316.473074)
			(xy 39.725654 -316.473074) (xy 39.776436 -316.481117) (xy 39.825335 -316.497005) (xy 39.871147 -316.520348)
			(xy 39.912743 -316.550569) (xy 39.949099 -316.586925) (xy 39.97932 -316.628521) (xy 40.002663 -316.674333)
			(xy 40.018551 -316.723232) (xy 40.026594 -316.774014) (xy 40.027098 -316.799722) (xy 40.344102 -316.799722)
			(xy 40.348062 -316.750668) (xy 40.359839 -316.702884) (xy 40.37913 -316.657608) (xy 40.405433 -316.616012)
			(xy 40.438068 -316.579175) (xy 40.476189 -316.54805) (xy 40.51881 -316.523443) (xy 40.564826 -316.505991)
			(xy 40.613045 -316.496147) (xy 40.66222 -316.494166) (xy 40.711075 -316.500098) (xy 40.758346 -316.51379)
			(xy 40.802808 -316.534888) (xy 40.843311 -316.562844) (xy 40.878804 -316.596936) (xy 40.908369 -316.63628)
			(xy 40.93124 -316.679857) (xy 40.946824 -316.726538) (xy 40.954719 -316.775115) (xy 40.955214 -316.799722)
			(xy 40.954719 -316.824329) (xy 40.95454 -316.82543) (xy 41.273218 -316.82543) (xy 41.273218 -316.774014)
			(xy 41.281261 -316.723232) (xy 41.297149 -316.674333) (xy 41.320492 -316.628521) (xy 41.350713 -316.586925)
			(xy 41.387069 -316.550569) (xy 41.428665 -316.520348) (xy 41.474477 -316.497005) (xy 41.523376 -316.481117)
			(xy 41.574158 -316.473074) (xy 41.625574 -316.473074) (xy 41.676356 -316.481117) (xy 41.725255 -316.497005)
			(xy 41.771067 -316.520348) (xy 41.812663 -316.550569) (xy 41.849019 -316.586925) (xy 41.87924 -316.628521)
			(xy 41.902583 -316.674333) (xy 41.918471 -316.723232) (xy 41.926514 -316.774014) (xy 41.927018 -316.799722)
			(xy 42.244022 -316.799722) (xy 42.247982 -316.750668) (xy 42.259759 -316.702884) (xy 42.27905 -316.657608)
			(xy 42.305353 -316.616012) (xy 42.337988 -316.579175) (xy 42.376109 -316.54805) (xy 42.41873 -316.523443)
			(xy 42.464746 -316.505991) (xy 42.512965 -316.496147) (xy 42.56214 -316.494166) (xy 42.610995 -316.500098)
			(xy 42.658266 -316.51379) (xy 42.702728 -316.534888) (xy 42.743231 -316.562844) (xy 42.778724 -316.596936)
			(xy 42.808289 -316.63628) (xy 42.83116 -316.679857) (xy 42.846744 -316.726538) (xy 42.854639 -316.775115)
			(xy 42.855134 -316.799722) (xy 42.854639 -316.824329) (xy 42.85446 -316.82543) (xy 43.173138 -316.82543)
			(xy 43.173138 -316.774014) (xy 43.181181 -316.723232) (xy 43.197069 -316.674333) (xy 43.220412 -316.628521)
			(xy 43.250633 -316.586925) (xy 43.286989 -316.550569) (xy 43.328585 -316.520348) (xy 43.374397 -316.497005)
			(xy 43.423296 -316.481117) (xy 43.474078 -316.473074) (xy 43.525494 -316.473074) (xy 43.576276 -316.481117)
			(xy 43.625175 -316.497005) (xy 43.670987 -316.520348) (xy 43.712583 -316.550569) (xy 43.748939 -316.586925)
			(xy 43.77916 -316.628521) (xy 43.802503 -316.674333) (xy 43.818391 -316.723232) (xy 43.826434 -316.774014)
			(xy 43.826938 -316.799722) (xy 44.143942 -316.799722) (xy 44.147902 -316.750668) (xy 44.159679 -316.702884)
			(xy 44.17897 -316.657608) (xy 44.205273 -316.616012) (xy 44.237908 -316.579175) (xy 44.276029 -316.54805)
			(xy 44.31865 -316.523443) (xy 44.364666 -316.505991) (xy 44.412885 -316.496147) (xy 44.46206 -316.494166)
			(xy 44.510915 -316.500098) (xy 44.558186 -316.51379) (xy 44.602648 -316.534888) (xy 44.643151 -316.562844)
			(xy 44.678644 -316.596936) (xy 44.708209 -316.63628) (xy 44.73108 -316.679857) (xy 44.746664 -316.726538)
			(xy 44.754559 -316.775115) (xy 44.755054 -316.799722) (xy 44.754559 -316.824329) (xy 44.75438 -316.82543)
			(xy 45.073312 -316.82543) (xy 45.073312 -316.774014) (xy 45.081355 -316.723232) (xy 45.097243 -316.674333)
			(xy 45.120586 -316.628521) (xy 45.150807 -316.586925) (xy 45.187163 -316.550569) (xy 45.228759 -316.520348)
			(xy 45.274571 -316.497005) (xy 45.32347 -316.481117) (xy 45.374252 -316.473074) (xy 45.425668 -316.473074)
			(xy 45.47645 -316.481117) (xy 45.525349 -316.497005) (xy 45.571161 -316.520348) (xy 45.612757 -316.550569)
			(xy 45.649113 -316.586925) (xy 45.679334 -316.628521) (xy 45.702677 -316.674333) (xy 45.718565 -316.723232)
			(xy 45.726608 -316.774014) (xy 45.727112 -316.799722) (xy 46.044116 -316.799722) (xy 46.048076 -316.750668)
			(xy 46.059853 -316.702884) (xy 46.079144 -316.657608) (xy 46.105447 -316.616012) (xy 46.138082 -316.579175)
			(xy 46.176203 -316.54805) (xy 46.218824 -316.523443) (xy 46.26484 -316.505991) (xy 46.313059 -316.496147)
			(xy 46.362234 -316.494166) (xy 46.411089 -316.500098) (xy 46.45836 -316.51379) (xy 46.502822 -316.534888)
			(xy 46.543325 -316.562844) (xy 46.578818 -316.596936) (xy 46.608383 -316.63628) (xy 46.631254 -316.679857)
			(xy 46.646838 -316.726538) (xy 46.654733 -316.775115) (xy 46.655228 -316.799722) (xy 46.654733 -316.824329)
			(xy 46.654554 -316.82543) (xy 46.973232 -316.82543) (xy 46.973232 -316.774014) (xy 46.981275 -316.723232)
			(xy 46.997163 -316.674333) (xy 47.020506 -316.628521) (xy 47.050727 -316.586925) (xy 47.087083 -316.550569)
			(xy 47.128679 -316.520348) (xy 47.174491 -316.497005) (xy 47.22339 -316.481117) (xy 47.274172 -316.473074)
			(xy 47.325588 -316.473074) (xy 47.37637 -316.481117) (xy 47.425269 -316.497005) (xy 47.471081 -316.520348)
			(xy 47.512677 -316.550569) (xy 47.549033 -316.586925) (xy 47.579254 -316.628521) (xy 47.602597 -316.674333)
			(xy 47.618485 -316.723232) (xy 47.626528 -316.774014) (xy 47.627032 -316.799722) (xy 47.944036 -316.799722)
			(xy 47.947996 -316.750668) (xy 47.959773 -316.702884) (xy 47.979064 -316.657608) (xy 48.005367 -316.616012)
			(xy 48.038002 -316.579175) (xy 48.076123 -316.54805) (xy 48.118744 -316.523443) (xy 48.16476 -316.505991)
			(xy 48.212979 -316.496147) (xy 48.262154 -316.494166) (xy 48.311009 -316.500098) (xy 48.35828 -316.51379)
			(xy 48.402742 -316.534888) (xy 48.443245 -316.562844) (xy 48.478738 -316.596936) (xy 48.508303 -316.63628)
			(xy 48.531174 -316.679857) (xy 48.546758 -316.726538) (xy 48.554653 -316.775115) (xy 48.555148 -316.799722)
			(xy 48.554653 -316.824329) (xy 48.554474 -316.82543) (xy 48.873152 -316.82543) (xy 48.873152 -316.774014)
			(xy 48.881195 -316.723232) (xy 48.897083 -316.674333) (xy 48.920426 -316.628521) (xy 48.950647 -316.586925)
			(xy 48.987003 -316.550569) (xy 49.028599 -316.520348) (xy 49.074411 -316.497005) (xy 49.12331 -316.481117)
			(xy 49.174092 -316.473074) (xy 49.225508 -316.473074) (xy 49.27629 -316.481117) (xy 49.325189 -316.497005)
			(xy 49.371001 -316.520348) (xy 49.412597 -316.550569) (xy 49.448953 -316.586925) (xy 49.479174 -316.628521)
			(xy 49.502517 -316.674333) (xy 49.518405 -316.723232) (xy 49.526448 -316.774014) (xy 49.526952 -316.799722)
			(xy 49.843956 -316.799722) (xy 49.847916 -316.750668) (xy 49.859693 -316.702884) (xy 49.878984 -316.657608)
			(xy 49.905287 -316.616012) (xy 49.937922 -316.579175) (xy 49.976043 -316.54805) (xy 50.018664 -316.523443)
			(xy 50.06468 -316.505991) (xy 50.112899 -316.496147) (xy 50.162074 -316.494166) (xy 50.210929 -316.500098)
			(xy 50.2582 -316.51379) (xy 50.302662 -316.534888) (xy 50.343165 -316.562844) (xy 50.378658 -316.596936)
			(xy 50.408223 -316.63628) (xy 50.431094 -316.679857) (xy 50.446678 -316.726538) (xy 50.454573 -316.775115)
			(xy 50.455068 -316.799722) (xy 50.454573 -316.824329) (xy 50.454394 -316.82543) (xy 50.773326 -316.82543)
			(xy 50.773326 -316.774014) (xy 50.781369 -316.723232) (xy 50.797257 -316.674333) (xy 50.8206 -316.628521)
			(xy 50.850821 -316.586925) (xy 50.887177 -316.550569) (xy 50.928773 -316.520348) (xy 50.974585 -316.497005)
			(xy 51.023484 -316.481117) (xy 51.074266 -316.473074) (xy 51.125682 -316.473074) (xy 51.176464 -316.481117)
			(xy 51.225363 -316.497005) (xy 51.271175 -316.520348) (xy 51.312771 -316.550569) (xy 51.349127 -316.586925)
			(xy 51.379348 -316.628521) (xy 51.402691 -316.674333) (xy 51.418579 -316.723232) (xy 51.426622 -316.774014)
			(xy 51.427126 -316.799722) (xy 51.74413 -316.799722) (xy 51.74809 -316.750668) (xy 51.759867 -316.702884)
			(xy 51.779158 -316.657608) (xy 51.805461 -316.616012) (xy 51.838096 -316.579175) (xy 51.876217 -316.54805)
			(xy 51.918838 -316.523443) (xy 51.964854 -316.505991) (xy 52.013073 -316.496147) (xy 52.062248 -316.494166)
			(xy 52.111103 -316.500098) (xy 52.158374 -316.51379) (xy 52.202836 -316.534888) (xy 52.243339 -316.562844)
			(xy 52.278832 -316.596936) (xy 52.308397 -316.63628) (xy 52.331268 -316.679857) (xy 52.346852 -316.726538)
			(xy 52.354747 -316.775115) (xy 52.355242 -316.799722) (xy 52.354747 -316.824329) (xy 52.354568 -316.82543)
			(xy 52.673246 -316.82543) (xy 52.673246 -316.774014) (xy 52.681289 -316.723232) (xy 52.697177 -316.674333)
			(xy 52.72052 -316.628521) (xy 52.750741 -316.586925) (xy 52.787097 -316.550569) (xy 52.828693 -316.520348)
			(xy 52.874505 -316.497005) (xy 52.923404 -316.481117) (xy 52.974186 -316.473074) (xy 53.025602 -316.473074)
			(xy 53.076384 -316.481117) (xy 53.125283 -316.497005) (xy 53.171095 -316.520348) (xy 53.212691 -316.550569)
			(xy 53.249047 -316.586925) (xy 53.279268 -316.628521) (xy 53.302611 -316.674333) (xy 53.318499 -316.723232)
			(xy 53.326542 -316.774014) (xy 53.327046 -316.799722) (xy 53.64405 -316.799722) (xy 53.64801 -316.750668)
			(xy 53.659787 -316.702884) (xy 53.679078 -316.657608) (xy 53.705381 -316.616012) (xy 53.738016 -316.579175)
			(xy 53.776137 -316.54805) (xy 53.818758 -316.523443) (xy 53.864774 -316.505991) (xy 53.912993 -316.496147)
			(xy 53.962168 -316.494166) (xy 54.011023 -316.500098) (xy 54.058294 -316.51379) (xy 54.102756 -316.534888)
			(xy 54.143259 -316.562844) (xy 54.178752 -316.596936) (xy 54.208317 -316.63628) (xy 54.231188 -316.679857)
			(xy 54.246772 -316.726538) (xy 54.254667 -316.775115) (xy 54.255162 -316.799722) (xy 54.254667 -316.824329)
			(xy 54.254488 -316.82543) (xy 54.573166 -316.82543) (xy 54.573166 -316.774014) (xy 54.581209 -316.723232)
			(xy 54.597097 -316.674333) (xy 54.62044 -316.628521) (xy 54.650661 -316.586925) (xy 54.687017 -316.550569)
			(xy 54.728613 -316.520348) (xy 54.774425 -316.497005) (xy 54.823324 -316.481117) (xy 54.874106 -316.473074)
			(xy 54.925522 -316.473074) (xy 54.976304 -316.481117) (xy 55.025203 -316.497005) (xy 55.071015 -316.520348)
			(xy 55.112611 -316.550569) (xy 55.148967 -316.586925) (xy 55.179188 -316.628521) (xy 55.202531 -316.674333)
			(xy 55.218419 -316.723232) (xy 55.226462 -316.774014) (xy 55.226966 -316.799722) (xy 55.54397 -316.799722)
			(xy 55.54793 -316.750668) (xy 55.559707 -316.702884) (xy 55.578998 -316.657608) (xy 55.605301 -316.616012)
			(xy 55.637936 -316.579175) (xy 55.676057 -316.54805) (xy 55.718678 -316.523443) (xy 55.764694 -316.505991)
			(xy 55.812913 -316.496147) (xy 55.862088 -316.494166) (xy 55.910943 -316.500098) (xy 55.958214 -316.51379)
			(xy 56.002676 -316.534888) (xy 56.043179 -316.562844) (xy 56.078672 -316.596936) (xy 56.108237 -316.63628)
			(xy 56.131108 -316.679857) (xy 56.146692 -316.726538) (xy 56.154587 -316.775115) (xy 56.155082 -316.799722)
			(xy 56.154587 -316.824329) (xy 56.154408 -316.82543) (xy 56.47334 -316.82543) (xy 56.47334 -316.774014)
			(xy 56.481383 -316.723232) (xy 56.497271 -316.674333) (xy 56.520614 -316.628521) (xy 56.550835 -316.586925)
			(xy 56.587191 -316.550569) (xy 56.628787 -316.520348) (xy 56.674599 -316.497005) (xy 56.723498 -316.481117)
			(xy 56.77428 -316.473074) (xy 56.825696 -316.473074) (xy 56.876478 -316.481117) (xy 56.925377 -316.497005)
			(xy 56.971189 -316.520348) (xy 57.012785 -316.550569) (xy 57.049141 -316.586925) (xy 57.079362 -316.628521)
			(xy 57.102705 -316.674333) (xy 57.118593 -316.723232) (xy 57.126636 -316.774014) (xy 57.12714 -316.799722)
			(xy 57.444144 -316.799722) (xy 57.448104 -316.750668) (xy 57.459881 -316.702884) (xy 57.479172 -316.657608)
			(xy 57.505475 -316.616012) (xy 57.53811 -316.579175) (xy 57.576231 -316.54805) (xy 57.618852 -316.523443)
			(xy 57.664868 -316.505991) (xy 57.713087 -316.496147) (xy 57.762262 -316.494166) (xy 57.811117 -316.500098)
			(xy 57.858388 -316.51379) (xy 57.90285 -316.534888) (xy 57.943353 -316.562844) (xy 57.978846 -316.596936)
			(xy 58.008411 -316.63628) (xy 58.031282 -316.679857) (xy 58.046866 -316.726538) (xy 58.054761 -316.775115)
			(xy 58.055256 -316.799722) (xy 58.054761 -316.824329) (xy 58.054582 -316.82543) (xy 58.37326 -316.82543)
			(xy 58.37326 -316.774014) (xy 58.381303 -316.723232) (xy 58.397191 -316.674333) (xy 58.420534 -316.628521)
			(xy 58.450755 -316.586925) (xy 58.487111 -316.550569) (xy 58.528707 -316.520348) (xy 58.574519 -316.497005)
			(xy 58.623418 -316.481117) (xy 58.6742 -316.473074) (xy 58.725616 -316.473074) (xy 58.776398 -316.481117)
			(xy 58.825297 -316.497005) (xy 58.871109 -316.520348) (xy 58.912705 -316.550569) (xy 58.949061 -316.586925)
			(xy 58.979282 -316.628521) (xy 59.002625 -316.674333) (xy 59.018513 -316.723232) (xy 59.026556 -316.774014)
			(xy 59.02706 -316.799722) (xy 59.344064 -316.799722) (xy 59.348024 -316.750668) (xy 59.359801 -316.702884)
			(xy 59.379092 -316.657608) (xy 59.405395 -316.616012) (xy 59.43803 -316.579175) (xy 59.476151 -316.54805)
			(xy 59.518772 -316.523443) (xy 59.564788 -316.505991) (xy 59.613007 -316.496147) (xy 59.662182 -316.494166)
			(xy 59.711037 -316.500098) (xy 59.758308 -316.51379) (xy 59.80277 -316.534888) (xy 59.843273 -316.562844)
			(xy 59.878766 -316.596936) (xy 59.908331 -316.63628) (xy 59.931202 -316.679857) (xy 59.946786 -316.726538)
			(xy 59.954681 -316.775115) (xy 59.955176 -316.799722) (xy 59.954681 -316.824329) (xy 59.954502 -316.82543)
			(xy 60.27318 -316.82543) (xy 60.27318 -316.774014) (xy 60.281223 -316.723232) (xy 60.297111 -316.674333)
			(xy 60.320454 -316.628521) (xy 60.350675 -316.586925) (xy 60.387031 -316.550569) (xy 60.428627 -316.520348)
			(xy 60.474439 -316.497005) (xy 60.523338 -316.481117) (xy 60.57412 -316.473074) (xy 60.625536 -316.473074)
			(xy 60.676318 -316.481117) (xy 60.725217 -316.497005) (xy 60.771029 -316.520348) (xy 60.812625 -316.550569)
			(xy 60.848981 -316.586925) (xy 60.879202 -316.628521) (xy 60.902545 -316.674333) (xy 60.918433 -316.723232)
			(xy 60.926476 -316.774014) (xy 60.92698 -316.799722) (xy 61.243984 -316.799722) (xy 61.247944 -316.750668)
			(xy 61.259721 -316.702884) (xy 61.279012 -316.657608) (xy 61.305315 -316.616012) (xy 61.33795 -316.579175)
			(xy 61.376071 -316.54805) (xy 61.418692 -316.523443) (xy 61.464708 -316.505991) (xy 61.512927 -316.496147)
			(xy 61.562102 -316.494166) (xy 61.610957 -316.500098) (xy 61.658228 -316.51379) (xy 61.70269 -316.534888)
			(xy 61.743193 -316.562844) (xy 61.778686 -316.596936) (xy 61.808251 -316.63628) (xy 61.831122 -316.679857)
			(xy 61.846706 -316.726538) (xy 61.854601 -316.775115) (xy 61.855096 -316.799722) (xy 61.854601 -316.824329)
			(xy 61.854422 -316.82543) (xy 62.1731 -316.82543) (xy 62.1731 -316.774014) (xy 62.181143 -316.723232)
			(xy 62.197031 -316.674333) (xy 62.220374 -316.628521) (xy 62.250595 -316.586925) (xy 62.286951 -316.550569)
			(xy 62.328547 -316.520348) (xy 62.374359 -316.497005) (xy 62.423258 -316.481117) (xy 62.47404 -316.473074)
			(xy 62.525456 -316.473074) (xy 62.576238 -316.481117) (xy 62.625137 -316.497005) (xy 62.670949 -316.520348)
			(xy 62.712545 -316.550569) (xy 62.748901 -316.586925) (xy 62.779122 -316.628521) (xy 62.802465 -316.674333)
			(xy 62.818353 -316.723232) (xy 62.826396 -316.774014) (xy 62.8269 -316.799722) (xy 63.144158 -316.799722)
			(xy 63.148118 -316.750668) (xy 63.159895 -316.702884) (xy 63.179186 -316.657608) (xy 63.205489 -316.616012)
			(xy 63.238124 -316.579175) (xy 63.276245 -316.54805) (xy 63.318866 -316.523443) (xy 63.364882 -316.505991)
			(xy 63.413101 -316.496147) (xy 63.462276 -316.494166) (xy 63.511131 -316.500098) (xy 63.558402 -316.51379)
			(xy 63.602864 -316.534888) (xy 63.643367 -316.562844) (xy 63.67886 -316.596936) (xy 63.708425 -316.63628)
			(xy 63.731296 -316.679857) (xy 63.74688 -316.726538) (xy 63.754775 -316.775115) (xy 63.75527 -316.799722)
			(xy 63.754775 -316.824329) (xy 63.754596 -316.82543) (xy 64.073274 -316.82543) (xy 64.073274 -316.774014)
			(xy 64.081317 -316.723232) (xy 64.097205 -316.674333) (xy 64.120548 -316.628521) (xy 64.150769 -316.586925)
			(xy 64.187125 -316.550569) (xy 64.228721 -316.520348) (xy 64.274533 -316.497005) (xy 64.323432 -316.481117)
			(xy 64.374214 -316.473074) (xy 64.42563 -316.473074) (xy 64.476412 -316.481117) (xy 64.525311 -316.497005)
			(xy 64.571123 -316.520348) (xy 64.612719 -316.550569) (xy 64.649075 -316.586925) (xy 64.679296 -316.628521)
			(xy 64.702639 -316.674333) (xy 64.718527 -316.723232) (xy 64.72657 -316.774014) (xy 64.727074 -316.799722)
			(xy 65.044078 -316.799722) (xy 65.048038 -316.750668) (xy 65.059815 -316.702884) (xy 65.079106 -316.657608)
			(xy 65.105409 -316.616012) (xy 65.138044 -316.579175) (xy 65.176165 -316.54805) (xy 65.218786 -316.523443)
			(xy 65.264802 -316.505991) (xy 65.313021 -316.496147) (xy 65.362196 -316.494166) (xy 65.411051 -316.500098)
			(xy 65.458322 -316.51379) (xy 65.502784 -316.534888) (xy 65.543287 -316.562844) (xy 65.57878 -316.596936)
			(xy 65.608345 -316.63628) (xy 65.631216 -316.679857) (xy 65.6468 -316.726538) (xy 65.654695 -316.775115)
			(xy 65.65519 -316.799722) (xy 65.654695 -316.824329) (xy 65.654516 -316.82543) (xy 65.973194 -316.82543)
			(xy 65.973194 -316.774014) (xy 65.981237 -316.723232) (xy 65.997125 -316.674333) (xy 66.020468 -316.628521)
			(xy 66.050689 -316.586925) (xy 66.087045 -316.550569) (xy 66.128641 -316.520348) (xy 66.174453 -316.497005)
			(xy 66.223352 -316.481117) (xy 66.274134 -316.473074) (xy 66.32555 -316.473074) (xy 66.376332 -316.481117)
			(xy 66.425231 -316.497005) (xy 66.471043 -316.520348) (xy 66.512639 -316.550569) (xy 66.548995 -316.586925)
			(xy 66.579216 -316.628521) (xy 66.602559 -316.674333) (xy 66.618447 -316.723232) (xy 66.62649 -316.774014)
			(xy 66.626994 -316.799722) (xy 66.943998 -316.799722) (xy 66.947958 -316.750668) (xy 66.959735 -316.702884)
			(xy 66.979026 -316.657608) (xy 67.005329 -316.616012) (xy 67.037964 -316.579175) (xy 67.076085 -316.54805)
			(xy 67.118706 -316.523443) (xy 67.164722 -316.505991) (xy 67.212941 -316.496147) (xy 67.262116 -316.494166)
			(xy 67.310971 -316.500098) (xy 67.358242 -316.51379) (xy 67.402704 -316.534888) (xy 67.443207 -316.562844)
			(xy 67.4787 -316.596936) (xy 67.508265 -316.63628) (xy 67.531136 -316.679857) (xy 67.54672 -316.726538)
			(xy 67.554615 -316.775115) (xy 67.55511 -316.799722) (xy 67.554615 -316.824329) (xy 67.554436 -316.82543)
			(xy 67.873114 -316.82543) (xy 67.873114 -316.774014) (xy 67.881157 -316.723232) (xy 67.897045 -316.674333)
			(xy 67.920388 -316.628521) (xy 67.950609 -316.586925) (xy 67.986965 -316.550569) (xy 68.028561 -316.520348)
			(xy 68.074373 -316.497005) (xy 68.123272 -316.481117) (xy 68.174054 -316.473074) (xy 68.22547 -316.473074)
			(xy 68.276252 -316.481117) (xy 68.325151 -316.497005) (xy 68.370963 -316.520348) (xy 68.412559 -316.550569)
			(xy 68.448915 -316.586925) (xy 68.479136 -316.628521) (xy 68.502479 -316.674333) (xy 68.518367 -316.723232)
			(xy 68.52641 -316.774014) (xy 68.526914 -316.799722) (xy 68.844172 -316.799722) (xy 68.848132 -316.750668)
			(xy 68.859909 -316.702884) (xy 68.8792 -316.657608) (xy 68.905503 -316.616012) (xy 68.938138 -316.579175)
			(xy 68.976259 -316.54805) (xy 69.01888 -316.523443) (xy 69.064896 -316.505991) (xy 69.113115 -316.496147)
			(xy 69.16229 -316.494166) (xy 69.211145 -316.500098) (xy 69.258416 -316.51379) (xy 69.302878 -316.534888)
			(xy 69.343381 -316.562844) (xy 69.378874 -316.596936) (xy 69.408439 -316.63628) (xy 69.43131 -316.679857)
			(xy 69.446894 -316.726538) (xy 69.454789 -316.775115) (xy 69.455284 -316.799722) (xy 69.454789 -316.824329)
			(xy 69.45461 -316.82543) (xy 69.773288 -316.82543) (xy 69.773288 -316.774014) (xy 69.781331 -316.723232)
			(xy 69.797219 -316.674333) (xy 69.820562 -316.628521) (xy 69.850783 -316.586925) (xy 69.887139 -316.550569)
			(xy 69.928735 -316.520348) (xy 69.974547 -316.497005) (xy 70.023446 -316.481117) (xy 70.074228 -316.473074)
			(xy 70.125644 -316.473074) (xy 70.176426 -316.481117) (xy 70.225325 -316.497005) (xy 70.271137 -316.520348)
			(xy 70.312733 -316.550569) (xy 70.349089 -316.586925) (xy 70.37931 -316.628521) (xy 70.402653 -316.674333)
			(xy 70.418541 -316.723232) (xy 70.426584 -316.774014) (xy 70.427088 -316.799722) (xy 70.744092 -316.799722)
			(xy 70.748052 -316.750668) (xy 70.759829 -316.702884) (xy 70.77912 -316.657608) (xy 70.805423 -316.616012)
			(xy 70.838058 -316.579175) (xy 70.876179 -316.54805) (xy 70.9188 -316.523443) (xy 70.964816 -316.505991)
			(xy 71.013035 -316.496147) (xy 71.06221 -316.494166) (xy 71.111065 -316.500098) (xy 71.158336 -316.51379)
			(xy 71.202798 -316.534888) (xy 71.243301 -316.562844) (xy 71.278794 -316.596936) (xy 71.308359 -316.63628)
			(xy 71.33123 -316.679857) (xy 71.346814 -316.726538) (xy 71.354709 -316.775115) (xy 71.355204 -316.799722)
			(xy 71.354709 -316.824329) (xy 71.346814 -316.872906) (xy 71.33123 -316.919587) (xy 71.308359 -316.963164)
			(xy 71.278794 -317.002508) (xy 71.243301 -317.0366) (xy 71.202798 -317.064556) (xy 71.158336 -317.085654)
			(xy 71.111065 -317.099346) (xy 71.06221 -317.105278) (xy 71.013035 -317.103297) (xy 70.964816 -317.093453)
			(xy 70.9188 -317.076001) (xy 70.876179 -317.051394) (xy 70.838058 -317.020269) (xy 70.805423 -316.983432)
			(xy 70.77912 -316.941836) (xy 70.759829 -316.89656) (xy 70.748052 -316.848776) (xy 70.744092 -316.799722)
			(xy 70.427088 -316.799722) (xy 70.426584 -316.82543) (xy 70.418541 -316.876212) (xy 70.402653 -316.925111)
			(xy 70.37931 -316.970923) (xy 70.349089 -317.012519) (xy 70.312733 -317.048875) (xy 70.271137 -317.079096)
			(xy 70.225325 -317.102439) (xy 70.176426 -317.118327) (xy 70.125644 -317.12637) (xy 70.074228 -317.12637)
			(xy 70.023446 -317.118327) (xy 69.974547 -317.102439) (xy 69.928735 -317.079096) (xy 69.887139 -317.048875)
			(xy 69.850783 -317.012519) (xy 69.820562 -316.970923) (xy 69.797219 -316.925111) (xy 69.781331 -316.876212)
			(xy 69.773288 -316.82543) (xy 69.45461 -316.82543) (xy 69.446894 -316.872906) (xy 69.43131 -316.919587)
			(xy 69.408439 -316.963164) (xy 69.378874 -317.002508) (xy 69.343381 -317.0366) (xy 69.302878 -317.064556)
			(xy 69.258416 -317.085654) (xy 69.211145 -317.099346) (xy 69.16229 -317.105278) (xy 69.113115 -317.103297)
			(xy 69.064896 -317.093453) (xy 69.01888 -317.076001) (xy 68.976259 -317.051394) (xy 68.938138 -317.020269)
			(xy 68.905503 -316.983432) (xy 68.8792 -316.941836) (xy 68.859909 -316.89656) (xy 68.848132 -316.848776)
			(xy 68.844172 -316.799722) (xy 68.526914 -316.799722) (xy 68.52641 -316.82543) (xy 68.518367 -316.876212)
			(xy 68.502479 -316.925111) (xy 68.479136 -316.970923) (xy 68.448915 -317.012519) (xy 68.412559 -317.048875)
			(xy 68.370963 -317.079096) (xy 68.325151 -317.102439) (xy 68.276252 -317.118327) (xy 68.22547 -317.12637)
			(xy 68.174054 -317.12637) (xy 68.123272 -317.118327) (xy 68.074373 -317.102439) (xy 68.028561 -317.079096)
			(xy 67.986965 -317.048875) (xy 67.950609 -317.012519) (xy 67.920388 -316.970923) (xy 67.897045 -316.925111)
			(xy 67.881157 -316.876212) (xy 67.873114 -316.82543) (xy 67.554436 -316.82543) (xy 67.54672 -316.872906)
			(xy 67.531136 -316.919587) (xy 67.508265 -316.963164) (xy 67.4787 -317.002508) (xy 67.443207 -317.0366)
			(xy 67.402704 -317.064556) (xy 67.358242 -317.085654) (xy 67.310971 -317.099346) (xy 67.262116 -317.105278)
			(xy 67.212941 -317.103297) (xy 67.164722 -317.093453) (xy 67.118706 -317.076001) (xy 67.076085 -317.051394)
			(xy 67.037964 -317.020269) (xy 67.005329 -316.983432) (xy 66.979026 -316.941836) (xy 66.959735 -316.89656)
			(xy 66.947958 -316.848776) (xy 66.943998 -316.799722) (xy 66.626994 -316.799722) (xy 66.62649 -316.82543)
			(xy 66.618447 -316.876212) (xy 66.602559 -316.925111) (xy 66.579216 -316.970923) (xy 66.548995 -317.012519)
			(xy 66.512639 -317.048875) (xy 66.471043 -317.079096) (xy 66.425231 -317.102439) (xy 66.376332 -317.118327)
			(xy 66.32555 -317.12637) (xy 66.274134 -317.12637) (xy 66.223352 -317.118327) (xy 66.174453 -317.102439)
			(xy 66.128641 -317.079096) (xy 66.087045 -317.048875) (xy 66.050689 -317.012519) (xy 66.020468 -316.970923)
			(xy 65.997125 -316.925111) (xy 65.981237 -316.876212) (xy 65.973194 -316.82543) (xy 65.654516 -316.82543)
			(xy 65.6468 -316.872906) (xy 65.631216 -316.919587) (xy 65.608345 -316.963164) (xy 65.57878 -317.002508)
			(xy 65.543287 -317.0366) (xy 65.502784 -317.064556) (xy 65.458322 -317.085654) (xy 65.411051 -317.099346)
			(xy 65.362196 -317.105278) (xy 65.313021 -317.103297) (xy 65.264802 -317.093453) (xy 65.218786 -317.076001)
			(xy 65.176165 -317.051394) (xy 65.138044 -317.020269) (xy 65.105409 -316.983432) (xy 65.079106 -316.941836)
			(xy 65.059815 -316.89656) (xy 65.048038 -316.848776) (xy 65.044078 -316.799722) (xy 64.727074 -316.799722)
			(xy 64.72657 -316.82543) (xy 64.718527 -316.876212) (xy 64.702639 -316.925111) (xy 64.679296 -316.970923)
			(xy 64.649075 -317.012519) (xy 64.612719 -317.048875) (xy 64.571123 -317.079096) (xy 64.525311 -317.102439)
			(xy 64.476412 -317.118327) (xy 64.42563 -317.12637) (xy 64.374214 -317.12637) (xy 64.323432 -317.118327)
			(xy 64.274533 -317.102439) (xy 64.228721 -317.079096) (xy 64.187125 -317.048875) (xy 64.150769 -317.012519)
			(xy 64.120548 -316.970923) (xy 64.097205 -316.925111) (xy 64.081317 -316.876212) (xy 64.073274 -316.82543)
			(xy 63.754596 -316.82543) (xy 63.74688 -316.872906) (xy 63.731296 -316.919587) (xy 63.708425 -316.963164)
			(xy 63.67886 -317.002508) (xy 63.643367 -317.0366) (xy 63.602864 -317.064556) (xy 63.558402 -317.085654)
			(xy 63.511131 -317.099346) (xy 63.462276 -317.105278) (xy 63.413101 -317.103297) (xy 63.364882 -317.093453)
			(xy 63.318866 -317.076001) (xy 63.276245 -317.051394) (xy 63.238124 -317.020269) (xy 63.205489 -316.983432)
			(xy 63.179186 -316.941836) (xy 63.159895 -316.89656) (xy 63.148118 -316.848776) (xy 63.144158 -316.799722)
			(xy 62.8269 -316.799722) (xy 62.826396 -316.82543) (xy 62.818353 -316.876212) (xy 62.802465 -316.925111)
			(xy 62.779122 -316.970923) (xy 62.748901 -317.012519) (xy 62.712545 -317.048875) (xy 62.670949 -317.079096)
			(xy 62.625137 -317.102439) (xy 62.576238 -317.118327) (xy 62.525456 -317.12637) (xy 62.47404 -317.12637)
			(xy 62.423258 -317.118327) (xy 62.374359 -317.102439) (xy 62.328547 -317.079096) (xy 62.286951 -317.048875)
			(xy 62.250595 -317.012519) (xy 62.220374 -316.970923) (xy 62.197031 -316.925111) (xy 62.181143 -316.876212)
			(xy 62.1731 -316.82543) (xy 61.854422 -316.82543) (xy 61.846706 -316.872906) (xy 61.831122 -316.919587)
			(xy 61.808251 -316.963164) (xy 61.778686 -317.002508) (xy 61.743193 -317.0366) (xy 61.70269 -317.064556)
			(xy 61.658228 -317.085654) (xy 61.610957 -317.099346) (xy 61.562102 -317.105278) (xy 61.512927 -317.103297)
			(xy 61.464708 -317.093453) (xy 61.418692 -317.076001) (xy 61.376071 -317.051394) (xy 61.33795 -317.020269)
			(xy 61.305315 -316.983432) (xy 61.279012 -316.941836) (xy 61.259721 -316.89656) (xy 61.247944 -316.848776)
			(xy 61.243984 -316.799722) (xy 60.92698 -316.799722) (xy 60.926476 -316.82543) (xy 60.918433 -316.876212)
			(xy 60.902545 -316.925111) (xy 60.879202 -316.970923) (xy 60.848981 -317.012519) (xy 60.812625 -317.048875)
			(xy 60.771029 -317.079096) (xy 60.725217 -317.102439) (xy 60.676318 -317.118327) (xy 60.625536 -317.12637)
			(xy 60.57412 -317.12637) (xy 60.523338 -317.118327) (xy 60.474439 -317.102439) (xy 60.428627 -317.079096)
			(xy 60.387031 -317.048875) (xy 60.350675 -317.012519) (xy 60.320454 -316.970923) (xy 60.297111 -316.925111)
			(xy 60.281223 -316.876212) (xy 60.27318 -316.82543) (xy 59.954502 -316.82543) (xy 59.946786 -316.872906)
			(xy 59.931202 -316.919587) (xy 59.908331 -316.963164) (xy 59.878766 -317.002508) (xy 59.843273 -317.0366)
			(xy 59.80277 -317.064556) (xy 59.758308 -317.085654) (xy 59.711037 -317.099346) (xy 59.662182 -317.105278)
			(xy 59.613007 -317.103297) (xy 59.564788 -317.093453) (xy 59.518772 -317.076001) (xy 59.476151 -317.051394)
			(xy 59.43803 -317.020269) (xy 59.405395 -316.983432) (xy 59.379092 -316.941836) (xy 59.359801 -316.89656)
			(xy 59.348024 -316.848776) (xy 59.344064 -316.799722) (xy 59.02706 -316.799722) (xy 59.026556 -316.82543)
			(xy 59.018513 -316.876212) (xy 59.002625 -316.925111) (xy 58.979282 -316.970923) (xy 58.949061 -317.012519)
			(xy 58.912705 -317.048875) (xy 58.871109 -317.079096) (xy 58.825297 -317.102439) (xy 58.776398 -317.118327)
			(xy 58.725616 -317.12637) (xy 58.6742 -317.12637) (xy 58.623418 -317.118327) (xy 58.574519 -317.102439)
			(xy 58.528707 -317.079096) (xy 58.487111 -317.048875) (xy 58.450755 -317.012519) (xy 58.420534 -316.970923)
			(xy 58.397191 -316.925111) (xy 58.381303 -316.876212) (xy 58.37326 -316.82543) (xy 58.054582 -316.82543)
			(xy 58.046866 -316.872906) (xy 58.031282 -316.919587) (xy 58.008411 -316.963164) (xy 57.978846 -317.002508)
			(xy 57.943353 -317.0366) (xy 57.90285 -317.064556) (xy 57.858388 -317.085654) (xy 57.811117 -317.099346)
			(xy 57.762262 -317.105278) (xy 57.713087 -317.103297) (xy 57.664868 -317.093453) (xy 57.618852 -317.076001)
			(xy 57.576231 -317.051394) (xy 57.53811 -317.020269) (xy 57.505475 -316.983432) (xy 57.479172 -316.941836)
			(xy 57.459881 -316.89656) (xy 57.448104 -316.848776) (xy 57.444144 -316.799722) (xy 57.12714 -316.799722)
			(xy 57.126636 -316.82543) (xy 57.118593 -316.876212) (xy 57.102705 -316.925111) (xy 57.079362 -316.970923)
			(xy 57.049141 -317.012519) (xy 57.012785 -317.048875) (xy 56.971189 -317.079096) (xy 56.925377 -317.102439)
			(xy 56.876478 -317.118327) (xy 56.825696 -317.12637) (xy 56.77428 -317.12637) (xy 56.723498 -317.118327)
			(xy 56.674599 -317.102439) (xy 56.628787 -317.079096) (xy 56.587191 -317.048875) (xy 56.550835 -317.012519)
			(xy 56.520614 -316.970923) (xy 56.497271 -316.925111) (xy 56.481383 -316.876212) (xy 56.47334 -316.82543)
			(xy 56.154408 -316.82543) (xy 56.146692 -316.872906) (xy 56.131108 -316.919587) (xy 56.108237 -316.963164)
			(xy 56.078672 -317.002508) (xy 56.043179 -317.0366) (xy 56.002676 -317.064556) (xy 55.958214 -317.085654)
			(xy 55.910943 -317.099346) (xy 55.862088 -317.105278) (xy 55.812913 -317.103297) (xy 55.764694 -317.093453)
			(xy 55.718678 -317.076001) (xy 55.676057 -317.051394) (xy 55.637936 -317.020269) (xy 55.605301 -316.983432)
			(xy 55.578998 -316.941836) (xy 55.559707 -316.89656) (xy 55.54793 -316.848776) (xy 55.54397 -316.799722)
			(xy 55.226966 -316.799722) (xy 55.226462 -316.82543) (xy 55.218419 -316.876212) (xy 55.202531 -316.925111)
			(xy 55.179188 -316.970923) (xy 55.148967 -317.012519) (xy 55.112611 -317.048875) (xy 55.071015 -317.079096)
			(xy 55.025203 -317.102439) (xy 54.976304 -317.118327) (xy 54.925522 -317.12637) (xy 54.874106 -317.12637)
			(xy 54.823324 -317.118327) (xy 54.774425 -317.102439) (xy 54.728613 -317.079096) (xy 54.687017 -317.048875)
			(xy 54.650661 -317.012519) (xy 54.62044 -316.970923) (xy 54.597097 -316.925111) (xy 54.581209 -316.876212)
			(xy 54.573166 -316.82543) (xy 54.254488 -316.82543) (xy 54.246772 -316.872906) (xy 54.231188 -316.919587)
			(xy 54.208317 -316.963164) (xy 54.178752 -317.002508) (xy 54.143259 -317.0366) (xy 54.102756 -317.064556)
			(xy 54.058294 -317.085654) (xy 54.011023 -317.099346) (xy 53.962168 -317.105278) (xy 53.912993 -317.103297)
			(xy 53.864774 -317.093453) (xy 53.818758 -317.076001) (xy 53.776137 -317.051394) (xy 53.738016 -317.020269)
			(xy 53.705381 -316.983432) (xy 53.679078 -316.941836) (xy 53.659787 -316.89656) (xy 53.64801 -316.848776)
			(xy 53.64405 -316.799722) (xy 53.327046 -316.799722) (xy 53.326542 -316.82543) (xy 53.318499 -316.876212)
			(xy 53.302611 -316.925111) (xy 53.279268 -316.970923) (xy 53.249047 -317.012519) (xy 53.212691 -317.048875)
			(xy 53.171095 -317.079096) (xy 53.125283 -317.102439) (xy 53.076384 -317.118327) (xy 53.025602 -317.12637)
			(xy 52.974186 -317.12637) (xy 52.923404 -317.118327) (xy 52.874505 -317.102439) (xy 52.828693 -317.079096)
			(xy 52.787097 -317.048875) (xy 52.750741 -317.012519) (xy 52.72052 -316.970923) (xy 52.697177 -316.925111)
			(xy 52.681289 -316.876212) (xy 52.673246 -316.82543) (xy 52.354568 -316.82543) (xy 52.346852 -316.872906)
			(xy 52.331268 -316.919587) (xy 52.308397 -316.963164) (xy 52.278832 -317.002508) (xy 52.243339 -317.0366)
			(xy 52.202836 -317.064556) (xy 52.158374 -317.085654) (xy 52.111103 -317.099346) (xy 52.062248 -317.105278)
			(xy 52.013073 -317.103297) (xy 51.964854 -317.093453) (xy 51.918838 -317.076001) (xy 51.876217 -317.051394)
			(xy 51.838096 -317.020269) (xy 51.805461 -316.983432) (xy 51.779158 -316.941836) (xy 51.759867 -316.89656)
			(xy 51.74809 -316.848776) (xy 51.74413 -316.799722) (xy 51.427126 -316.799722) (xy 51.426622 -316.82543)
			(xy 51.418579 -316.876212) (xy 51.402691 -316.925111) (xy 51.379348 -316.970923) (xy 51.349127 -317.012519)
			(xy 51.312771 -317.048875) (xy 51.271175 -317.079096) (xy 51.225363 -317.102439) (xy 51.176464 -317.118327)
			(xy 51.125682 -317.12637) (xy 51.074266 -317.12637) (xy 51.023484 -317.118327) (xy 50.974585 -317.102439)
			(xy 50.928773 -317.079096) (xy 50.887177 -317.048875) (xy 50.850821 -317.012519) (xy 50.8206 -316.970923)
			(xy 50.797257 -316.925111) (xy 50.781369 -316.876212) (xy 50.773326 -316.82543) (xy 50.454394 -316.82543)
			(xy 50.446678 -316.872906) (xy 50.431094 -316.919587) (xy 50.408223 -316.963164) (xy 50.378658 -317.002508)
			(xy 50.343165 -317.0366) (xy 50.302662 -317.064556) (xy 50.2582 -317.085654) (xy 50.210929 -317.099346)
			(xy 50.162074 -317.105278) (xy 50.112899 -317.103297) (xy 50.06468 -317.093453) (xy 50.018664 -317.076001)
			(xy 49.976043 -317.051394) (xy 49.937922 -317.020269) (xy 49.905287 -316.983432) (xy 49.878984 -316.941836)
			(xy 49.859693 -316.89656) (xy 49.847916 -316.848776) (xy 49.843956 -316.799722) (xy 49.526952 -316.799722)
			(xy 49.526448 -316.82543) (xy 49.518405 -316.876212) (xy 49.502517 -316.925111) (xy 49.479174 -316.970923)
			(xy 49.448953 -317.012519) (xy 49.412597 -317.048875) (xy 49.371001 -317.079096) (xy 49.325189 -317.102439)
			(xy 49.27629 -317.118327) (xy 49.225508 -317.12637) (xy 49.174092 -317.12637) (xy 49.12331 -317.118327)
			(xy 49.074411 -317.102439) (xy 49.028599 -317.079096) (xy 48.987003 -317.048875) (xy 48.950647 -317.012519)
			(xy 48.920426 -316.970923) (xy 48.897083 -316.925111) (xy 48.881195 -316.876212) (xy 48.873152 -316.82543)
			(xy 48.554474 -316.82543) (xy 48.546758 -316.872906) (xy 48.531174 -316.919587) (xy 48.508303 -316.963164)
			(xy 48.478738 -317.002508) (xy 48.443245 -317.0366) (xy 48.402742 -317.064556) (xy 48.35828 -317.085654)
			(xy 48.311009 -317.099346) (xy 48.262154 -317.105278) (xy 48.212979 -317.103297) (xy 48.16476 -317.093453)
			(xy 48.118744 -317.076001) (xy 48.076123 -317.051394) (xy 48.038002 -317.020269) (xy 48.005367 -316.983432)
			(xy 47.979064 -316.941836) (xy 47.959773 -316.89656) (xy 47.947996 -316.848776) (xy 47.944036 -316.799722)
			(xy 47.627032 -316.799722) (xy 47.626528 -316.82543) (xy 47.618485 -316.876212) (xy 47.602597 -316.925111)
			(xy 47.579254 -316.970923) (xy 47.549033 -317.012519) (xy 47.512677 -317.048875) (xy 47.471081 -317.079096)
			(xy 47.425269 -317.102439) (xy 47.37637 -317.118327) (xy 47.325588 -317.12637) (xy 47.274172 -317.12637)
			(xy 47.22339 -317.118327) (xy 47.174491 -317.102439) (xy 47.128679 -317.079096) (xy 47.087083 -317.048875)
			(xy 47.050727 -317.012519) (xy 47.020506 -316.970923) (xy 46.997163 -316.925111) (xy 46.981275 -316.876212)
			(xy 46.973232 -316.82543) (xy 46.654554 -316.82543) (xy 46.646838 -316.872906) (xy 46.631254 -316.919587)
			(xy 46.608383 -316.963164) (xy 46.578818 -317.002508) (xy 46.543325 -317.0366) (xy 46.502822 -317.064556)
			(xy 46.45836 -317.085654) (xy 46.411089 -317.099346) (xy 46.362234 -317.105278) (xy 46.313059 -317.103297)
			(xy 46.26484 -317.093453) (xy 46.218824 -317.076001) (xy 46.176203 -317.051394) (xy 46.138082 -317.020269)
			(xy 46.105447 -316.983432) (xy 46.079144 -316.941836) (xy 46.059853 -316.89656) (xy 46.048076 -316.848776)
			(xy 46.044116 -316.799722) (xy 45.727112 -316.799722) (xy 45.726608 -316.82543) (xy 45.718565 -316.876212)
			(xy 45.702677 -316.925111) (xy 45.679334 -316.970923) (xy 45.649113 -317.012519) (xy 45.612757 -317.048875)
			(xy 45.571161 -317.079096) (xy 45.525349 -317.102439) (xy 45.47645 -317.118327) (xy 45.425668 -317.12637)
			(xy 45.374252 -317.12637) (xy 45.32347 -317.118327) (xy 45.274571 -317.102439) (xy 45.228759 -317.079096)
			(xy 45.187163 -317.048875) (xy 45.150807 -317.012519) (xy 45.120586 -316.970923) (xy 45.097243 -316.925111)
			(xy 45.081355 -316.876212) (xy 45.073312 -316.82543) (xy 44.75438 -316.82543) (xy 44.746664 -316.872906)
			(xy 44.73108 -316.919587) (xy 44.708209 -316.963164) (xy 44.678644 -317.002508) (xy 44.643151 -317.0366)
			(xy 44.602648 -317.064556) (xy 44.558186 -317.085654) (xy 44.510915 -317.099346) (xy 44.46206 -317.105278)
			(xy 44.412885 -317.103297) (xy 44.364666 -317.093453) (xy 44.31865 -317.076001) (xy 44.276029 -317.051394)
			(xy 44.237908 -317.020269) (xy 44.205273 -316.983432) (xy 44.17897 -316.941836) (xy 44.159679 -316.89656)
			(xy 44.147902 -316.848776) (xy 44.143942 -316.799722) (xy 43.826938 -316.799722) (xy 43.826434 -316.82543)
			(xy 43.818391 -316.876212) (xy 43.802503 -316.925111) (xy 43.77916 -316.970923) (xy 43.748939 -317.012519)
			(xy 43.712583 -317.048875) (xy 43.670987 -317.079096) (xy 43.625175 -317.102439) (xy 43.576276 -317.118327)
			(xy 43.525494 -317.12637) (xy 43.474078 -317.12637) (xy 43.423296 -317.118327) (xy 43.374397 -317.102439)
			(xy 43.328585 -317.079096) (xy 43.286989 -317.048875) (xy 43.250633 -317.012519) (xy 43.220412 -316.970923)
			(xy 43.197069 -316.925111) (xy 43.181181 -316.876212) (xy 43.173138 -316.82543) (xy 42.85446 -316.82543)
			(xy 42.846744 -316.872906) (xy 42.83116 -316.919587) (xy 42.808289 -316.963164) (xy 42.778724 -317.002508)
			(xy 42.743231 -317.0366) (xy 42.702728 -317.064556) (xy 42.658266 -317.085654) (xy 42.610995 -317.099346)
			(xy 42.56214 -317.105278) (xy 42.512965 -317.103297) (xy 42.464746 -317.093453) (xy 42.41873 -317.076001)
			(xy 42.376109 -317.051394) (xy 42.337988 -317.020269) (xy 42.305353 -316.983432) (xy 42.27905 -316.941836)
			(xy 42.259759 -316.89656) (xy 42.247982 -316.848776) (xy 42.244022 -316.799722) (xy 41.927018 -316.799722)
			(xy 41.926514 -316.82543) (xy 41.918471 -316.876212) (xy 41.902583 -316.925111) (xy 41.87924 -316.970923)
			(xy 41.849019 -317.012519) (xy 41.812663 -317.048875) (xy 41.771067 -317.079096) (xy 41.725255 -317.102439)
			(xy 41.676356 -317.118327) (xy 41.625574 -317.12637) (xy 41.574158 -317.12637) (xy 41.523376 -317.118327)
			(xy 41.474477 -317.102439) (xy 41.428665 -317.079096) (xy 41.387069 -317.048875) (xy 41.350713 -317.012519)
			(xy 41.320492 -316.970923) (xy 41.297149 -316.925111) (xy 41.281261 -316.876212) (xy 41.273218 -316.82543)
			(xy 40.95454 -316.82543) (xy 40.946824 -316.872906) (xy 40.93124 -316.919587) (xy 40.908369 -316.963164)
			(xy 40.878804 -317.002508) (xy 40.843311 -317.0366) (xy 40.802808 -317.064556) (xy 40.758346 -317.085654)
			(xy 40.711075 -317.099346) (xy 40.66222 -317.105278) (xy 40.613045 -317.103297) (xy 40.564826 -317.093453)
			(xy 40.51881 -317.076001) (xy 40.476189 -317.051394) (xy 40.438068 -317.020269) (xy 40.405433 -316.983432)
			(xy 40.37913 -316.941836) (xy 40.359839 -316.89656) (xy 40.348062 -316.848776) (xy 40.344102 -316.799722)
			(xy 40.027098 -316.799722) (xy 40.026594 -316.82543) (xy 40.018551 -316.876212) (xy 40.002663 -316.925111)
			(xy 39.97932 -316.970923) (xy 39.949099 -317.012519) (xy 39.912743 -317.048875) (xy 39.871147 -317.079096)
			(xy 39.825335 -317.102439) (xy 39.776436 -317.118327) (xy 39.725654 -317.12637) (xy 39.674238 -317.12637)
			(xy 39.623456 -317.118327) (xy 39.574557 -317.102439) (xy 39.528745 -317.079096) (xy 39.487149 -317.048875)
			(xy 39.450793 -317.012519) (xy 39.420572 -316.970923) (xy 39.397229 -316.925111) (xy 39.381341 -316.876212)
			(xy 39.373298 -316.82543) (xy 39.05462 -316.82543) (xy 39.046904 -316.872906) (xy 39.03132 -316.919587)
			(xy 39.008449 -316.963164) (xy 38.978884 -317.002508) (xy 38.943391 -317.0366) (xy 38.902888 -317.064556)
			(xy 38.858426 -317.085654) (xy 38.811155 -317.099346) (xy 38.7623 -317.105278) (xy 38.713125 -317.103297)
			(xy 38.664906 -317.093453) (xy 38.61889 -317.076001) (xy 38.576269 -317.051394) (xy 38.538148 -317.020269)
			(xy 38.505513 -316.983432) (xy 38.47921 -316.941836) (xy 38.459919 -316.89656) (xy 38.448142 -316.848776)
			(xy 38.444182 -316.799722) (xy 38.126924 -316.799722) (xy 38.12642 -316.82543) (xy 38.118377 -316.876212)
			(xy 38.102489 -316.925111) (xy 38.079146 -316.970923) (xy 38.048925 -317.012519) (xy 38.012569 -317.048875)
			(xy 37.970973 -317.079096) (xy 37.925161 -317.102439) (xy 37.876262 -317.118327) (xy 37.82548 -317.12637)
			(xy 37.774064 -317.12637) (xy 37.723282 -317.118327) (xy 37.674383 -317.102439) (xy 37.628571 -317.079096)
			(xy 37.586975 -317.048875) (xy 37.550619 -317.012519) (xy 37.520398 -316.970923) (xy 37.497055 -316.925111)
			(xy 37.481167 -316.876212) (xy 37.473124 -316.82543) (xy 37.17646 -316.82543) (xy 37.168417 -316.876212)
			(xy 37.152529 -316.925111) (xy 37.129186 -316.970923) (xy 37.098965 -317.012519) (xy 37.062609 -317.048875)
			(xy 37.021013 -317.079096) (xy 36.975201 -317.102439) (xy 36.926302 -317.118327) (xy 36.87552 -317.12637)
			(xy 36.824104 -317.12637) (xy 36.773322 -317.118327) (xy 36.724423 -317.102439) (xy 36.678611 -317.079096)
			(xy 36.637015 -317.048875) (xy 36.600659 -317.012519) (xy 36.570438 -316.970923) (xy 36.547095 -316.925111)
			(xy 36.531207 -316.876212) (xy 36.523164 -316.82543) (xy 36.203937 -316.82543) (xy 36.196262 -316.872652)
			(xy 36.180678 -316.919333) (xy 36.157807 -316.96291) (xy 36.128242 -317.002254) (xy 36.092749 -317.036346)
			(xy 36.052246 -317.064302) (xy 36.007784 -317.0854) (xy 35.960513 -317.099092) (xy 35.911658 -317.105024)
			(xy 35.862483 -317.103043) (xy 35.814264 -317.093199) (xy 35.768248 -317.075747) (xy 35.725627 -317.05114)
			(xy 35.687506 -317.020015) (xy 35.654871 -316.983178) (xy 35.628568 -316.941582) (xy 35.609277 -316.896306)
			(xy 35.5975 -316.848522) (xy 35.59354 -316.799468) (xy 32.097925 -316.799468) (xy 32.232023 -316.881831)
			(xy 32.393771 -316.990505) (xy 32.550952 -317.105687) (xy 32.703304 -317.227183) (xy 32.850573 -317.354793)
			(xy 32.992515 -317.488304) (xy 33.128894 -317.627493) (xy 33.239444 -317.749936) (xy 36.544008 -317.749936)
			(xy 36.547968 -317.700882) (xy 36.559745 -317.653098) (xy 36.579036 -317.607822) (xy 36.605339 -317.566226)
			(xy 36.637974 -317.529389) (xy 36.676095 -317.498264) (xy 36.718716 -317.473657) (xy 36.764732 -317.456205)
			(xy 36.812951 -317.446361) (xy 36.862126 -317.44438) (xy 36.910981 -317.450312) (xy 36.958252 -317.464004)
			(xy 37.002714 -317.485102) (xy 37.043217 -317.513058) (xy 37.07871 -317.54715) (xy 37.108275 -317.586494)
			(xy 37.131146 -317.630071) (xy 37.14673 -317.676752) (xy 37.154625 -317.725329) (xy 37.15512 -317.749936)
			(xy 37.493968 -317.749936) (xy 37.497928 -317.700882) (xy 37.509705 -317.653098) (xy 37.528996 -317.607822)
			(xy 37.555299 -317.566226) (xy 37.587934 -317.529389) (xy 37.626055 -317.498264) (xy 37.668676 -317.473657)
			(xy 37.714692 -317.456205) (xy 37.762911 -317.446361) (xy 37.812086 -317.44438) (xy 37.860941 -317.450312)
			(xy 37.908212 -317.464004) (xy 37.952674 -317.485102) (xy 37.993177 -317.513058) (xy 38.02867 -317.54715)
			(xy 38.058235 -317.586494) (xy 38.081106 -317.630071) (xy 38.09669 -317.676752) (xy 38.104585 -317.725329)
			(xy 38.10508 -317.749936) (xy 38.104585 -317.774543) (xy 38.104406 -317.775644) (xy 38.423338 -317.775644)
			(xy 38.423338 -317.724228) (xy 38.431381 -317.673446) (xy 38.447269 -317.624547) (xy 38.470612 -317.578735)
			(xy 38.500833 -317.537139) (xy 38.537189 -317.500783) (xy 38.578785 -317.470562) (xy 38.624597 -317.447219)
			(xy 38.673496 -317.431331) (xy 38.724278 -317.423288) (xy 38.775694 -317.423288) (xy 38.826476 -317.431331)
			(xy 38.875375 -317.447219) (xy 38.921187 -317.470562) (xy 38.962783 -317.500783) (xy 38.999139 -317.537139)
			(xy 39.02936 -317.578735) (xy 39.052703 -317.624547) (xy 39.068591 -317.673446) (xy 39.076634 -317.724228)
			(xy 39.077138 -317.749936) (xy 39.394142 -317.749936) (xy 39.398102 -317.700882) (xy 39.409879 -317.653098)
			(xy 39.42917 -317.607822) (xy 39.455473 -317.566226) (xy 39.488108 -317.529389) (xy 39.526229 -317.498264)
			(xy 39.56885 -317.473657) (xy 39.614866 -317.456205) (xy 39.663085 -317.446361) (xy 39.71226 -317.44438)
			(xy 39.761115 -317.450312) (xy 39.808386 -317.464004) (xy 39.852848 -317.485102) (xy 39.893351 -317.513058)
			(xy 39.928844 -317.54715) (xy 39.958409 -317.586494) (xy 39.98128 -317.630071) (xy 39.996864 -317.676752)
			(xy 40.004759 -317.725329) (xy 40.005254 -317.749936) (xy 40.004759 -317.774543) (xy 40.00458 -317.775644)
			(xy 40.323258 -317.775644) (xy 40.323258 -317.724228) (xy 40.331301 -317.673446) (xy 40.347189 -317.624547)
			(xy 40.370532 -317.578735) (xy 40.400753 -317.537139) (xy 40.437109 -317.500783) (xy 40.478705 -317.470562)
			(xy 40.524517 -317.447219) (xy 40.573416 -317.431331) (xy 40.624198 -317.423288) (xy 40.675614 -317.423288)
			(xy 40.726396 -317.431331) (xy 40.775295 -317.447219) (xy 40.821107 -317.470562) (xy 40.862703 -317.500783)
			(xy 40.899059 -317.537139) (xy 40.92928 -317.578735) (xy 40.952623 -317.624547) (xy 40.968511 -317.673446)
			(xy 40.976554 -317.724228) (xy 40.977058 -317.749936) (xy 41.294062 -317.749936) (xy 41.298022 -317.700882)
			(xy 41.309799 -317.653098) (xy 41.32909 -317.607822) (xy 41.355393 -317.566226) (xy 41.388028 -317.529389)
			(xy 41.426149 -317.498264) (xy 41.46877 -317.473657) (xy 41.514786 -317.456205) (xy 41.563005 -317.446361)
			(xy 41.61218 -317.44438) (xy 41.661035 -317.450312) (xy 41.708306 -317.464004) (xy 41.752768 -317.485102)
			(xy 41.793271 -317.513058) (xy 41.828764 -317.54715) (xy 41.858329 -317.586494) (xy 41.8812 -317.630071)
			(xy 41.896784 -317.676752) (xy 41.904679 -317.725329) (xy 41.905174 -317.749936) (xy 41.904679 -317.774543)
			(xy 41.9045 -317.775644) (xy 42.223178 -317.775644) (xy 42.223178 -317.724228) (xy 42.231221 -317.673446)
			(xy 42.247109 -317.624547) (xy 42.270452 -317.578735) (xy 42.300673 -317.537139) (xy 42.337029 -317.500783)
			(xy 42.378625 -317.470562) (xy 42.424437 -317.447219) (xy 42.473336 -317.431331) (xy 42.524118 -317.423288)
			(xy 42.575534 -317.423288) (xy 42.626316 -317.431331) (xy 42.675215 -317.447219) (xy 42.721027 -317.470562)
			(xy 42.762623 -317.500783) (xy 42.798979 -317.537139) (xy 42.8292 -317.578735) (xy 42.852543 -317.624547)
			(xy 42.868431 -317.673446) (xy 42.876474 -317.724228) (xy 42.876978 -317.749936) (xy 43.193982 -317.749936)
			(xy 43.197942 -317.700882) (xy 43.209719 -317.653098) (xy 43.22901 -317.607822) (xy 43.255313 -317.566226)
			(xy 43.287948 -317.529389) (xy 43.326069 -317.498264) (xy 43.36869 -317.473657) (xy 43.414706 -317.456205)
			(xy 43.462925 -317.446361) (xy 43.5121 -317.44438) (xy 43.560955 -317.450312) (xy 43.608226 -317.464004)
			(xy 43.652688 -317.485102) (xy 43.693191 -317.513058) (xy 43.728684 -317.54715) (xy 43.758249 -317.586494)
			(xy 43.78112 -317.630071) (xy 43.796704 -317.676752) (xy 43.804599 -317.725329) (xy 43.805094 -317.749936)
			(xy 43.804599 -317.774543) (xy 43.80442 -317.775644) (xy 44.123098 -317.775644) (xy 44.123098 -317.724228)
			(xy 44.131141 -317.673446) (xy 44.147029 -317.624547) (xy 44.170372 -317.578735) (xy 44.200593 -317.537139)
			(xy 44.236949 -317.500783) (xy 44.278545 -317.470562) (xy 44.324357 -317.447219) (xy 44.373256 -317.431331)
			(xy 44.424038 -317.423288) (xy 44.475454 -317.423288) (xy 44.526236 -317.431331) (xy 44.575135 -317.447219)
			(xy 44.620947 -317.470562) (xy 44.662543 -317.500783) (xy 44.698899 -317.537139) (xy 44.72912 -317.578735)
			(xy 44.752463 -317.624547) (xy 44.768351 -317.673446) (xy 44.776394 -317.724228) (xy 44.776898 -317.749936)
			(xy 45.094156 -317.749936) (xy 45.098116 -317.700882) (xy 45.109893 -317.653098) (xy 45.129184 -317.607822)
			(xy 45.155487 -317.566226) (xy 45.188122 -317.529389) (xy 45.226243 -317.498264) (xy 45.268864 -317.473657)
			(xy 45.31488 -317.456205) (xy 45.363099 -317.446361) (xy 45.412274 -317.44438) (xy 45.461129 -317.450312)
			(xy 45.5084 -317.464004) (xy 45.552862 -317.485102) (xy 45.593365 -317.513058) (xy 45.628858 -317.54715)
			(xy 45.658423 -317.586494) (xy 45.681294 -317.630071) (xy 45.696878 -317.676752) (xy 45.704773 -317.725329)
			(xy 45.705268 -317.749936) (xy 45.704773 -317.774543) (xy 45.704594 -317.775644) (xy 46.023272 -317.775644)
			(xy 46.023272 -317.724228) (xy 46.031315 -317.673446) (xy 46.047203 -317.624547) (xy 46.070546 -317.578735)
			(xy 46.100767 -317.537139) (xy 46.137123 -317.500783) (xy 46.178719 -317.470562) (xy 46.224531 -317.447219)
			(xy 46.27343 -317.431331) (xy 46.324212 -317.423288) (xy 46.375628 -317.423288) (xy 46.42641 -317.431331)
			(xy 46.475309 -317.447219) (xy 46.521121 -317.470562) (xy 46.562717 -317.500783) (xy 46.599073 -317.537139)
			(xy 46.629294 -317.578735) (xy 46.652637 -317.624547) (xy 46.668525 -317.673446) (xy 46.676568 -317.724228)
			(xy 46.677072 -317.749936) (xy 46.994076 -317.749936) (xy 46.998036 -317.700882) (xy 47.009813 -317.653098)
			(xy 47.029104 -317.607822) (xy 47.055407 -317.566226) (xy 47.088042 -317.529389) (xy 47.126163 -317.498264)
			(xy 47.168784 -317.473657) (xy 47.2148 -317.456205) (xy 47.263019 -317.446361) (xy 47.312194 -317.44438)
			(xy 47.361049 -317.450312) (xy 47.40832 -317.464004) (xy 47.452782 -317.485102) (xy 47.493285 -317.513058)
			(xy 47.528778 -317.54715) (xy 47.558343 -317.586494) (xy 47.581214 -317.630071) (xy 47.596798 -317.676752)
			(xy 47.604693 -317.725329) (xy 47.605188 -317.749936) (xy 47.604693 -317.774543) (xy 47.604514 -317.775644)
			(xy 47.923192 -317.775644) (xy 47.923192 -317.724228) (xy 47.931235 -317.673446) (xy 47.947123 -317.624547)
			(xy 47.970466 -317.578735) (xy 48.000687 -317.537139) (xy 48.037043 -317.500783) (xy 48.078639 -317.470562)
			(xy 48.124451 -317.447219) (xy 48.17335 -317.431331) (xy 48.224132 -317.423288) (xy 48.275548 -317.423288)
			(xy 48.32633 -317.431331) (xy 48.375229 -317.447219) (xy 48.421041 -317.470562) (xy 48.462637 -317.500783)
			(xy 48.498993 -317.537139) (xy 48.529214 -317.578735) (xy 48.552557 -317.624547) (xy 48.568445 -317.673446)
			(xy 48.576488 -317.724228) (xy 48.576992 -317.749936) (xy 48.893996 -317.749936) (xy 48.897956 -317.700882)
			(xy 48.909733 -317.653098) (xy 48.929024 -317.607822) (xy 48.955327 -317.566226) (xy 48.987962 -317.529389)
			(xy 49.026083 -317.498264) (xy 49.068704 -317.473657) (xy 49.11472 -317.456205) (xy 49.162939 -317.446361)
			(xy 49.212114 -317.44438) (xy 49.260969 -317.450312) (xy 49.30824 -317.464004) (xy 49.352702 -317.485102)
			(xy 49.393205 -317.513058) (xy 49.428698 -317.54715) (xy 49.458263 -317.586494) (xy 49.481134 -317.630071)
			(xy 49.496718 -317.676752) (xy 49.504613 -317.725329) (xy 49.505108 -317.749936) (xy 49.504613 -317.774543)
			(xy 49.504434 -317.775644) (xy 49.823112 -317.775644) (xy 49.823112 -317.724228) (xy 49.831155 -317.673446)
			(xy 49.847043 -317.624547) (xy 49.870386 -317.578735) (xy 49.900607 -317.537139) (xy 49.936963 -317.500783)
			(xy 49.978559 -317.470562) (xy 50.024371 -317.447219) (xy 50.07327 -317.431331) (xy 50.124052 -317.423288)
			(xy 50.175468 -317.423288) (xy 50.22625 -317.431331) (xy 50.275149 -317.447219) (xy 50.320961 -317.470562)
			(xy 50.362557 -317.500783) (xy 50.398913 -317.537139) (xy 50.429134 -317.578735) (xy 50.452477 -317.624547)
			(xy 50.468365 -317.673446) (xy 50.476408 -317.724228) (xy 50.476912 -317.749936) (xy 50.79417 -317.749936)
			(xy 50.79813 -317.700882) (xy 50.809907 -317.653098) (xy 50.829198 -317.607822) (xy 50.855501 -317.566226)
			(xy 50.888136 -317.529389) (xy 50.926257 -317.498264) (xy 50.968878 -317.473657) (xy 51.014894 -317.456205)
			(xy 51.063113 -317.446361) (xy 51.112288 -317.44438) (xy 51.161143 -317.450312) (xy 51.208414 -317.464004)
			(xy 51.252876 -317.485102) (xy 51.293379 -317.513058) (xy 51.328872 -317.54715) (xy 51.358437 -317.586494)
			(xy 51.381308 -317.630071) (xy 51.396892 -317.676752) (xy 51.404787 -317.725329) (xy 51.405282 -317.749936)
			(xy 51.404787 -317.774543) (xy 51.404608 -317.775644) (xy 51.723286 -317.775644) (xy 51.723286 -317.724228)
			(xy 51.731329 -317.673446) (xy 51.747217 -317.624547) (xy 51.77056 -317.578735) (xy 51.800781 -317.537139)
			(xy 51.837137 -317.500783) (xy 51.878733 -317.470562) (xy 51.924545 -317.447219) (xy 51.973444 -317.431331)
			(xy 52.024226 -317.423288) (xy 52.075642 -317.423288) (xy 52.126424 -317.431331) (xy 52.175323 -317.447219)
			(xy 52.221135 -317.470562) (xy 52.262731 -317.500783) (xy 52.299087 -317.537139) (xy 52.329308 -317.578735)
			(xy 52.352651 -317.624547) (xy 52.368539 -317.673446) (xy 52.376582 -317.724228) (xy 52.377086 -317.749936)
			(xy 52.69409 -317.749936) (xy 52.69805 -317.700882) (xy 52.709827 -317.653098) (xy 52.729118 -317.607822)
			(xy 52.755421 -317.566226) (xy 52.788056 -317.529389) (xy 52.826177 -317.498264) (xy 52.868798 -317.473657)
			(xy 52.914814 -317.456205) (xy 52.963033 -317.446361) (xy 53.012208 -317.44438) (xy 53.061063 -317.450312)
			(xy 53.108334 -317.464004) (xy 53.152796 -317.485102) (xy 53.193299 -317.513058) (xy 53.228792 -317.54715)
			(xy 53.258357 -317.586494) (xy 53.281228 -317.630071) (xy 53.296812 -317.676752) (xy 53.304707 -317.725329)
			(xy 53.305202 -317.749936) (xy 53.304707 -317.774543) (xy 53.304528 -317.775644) (xy 53.623206 -317.775644)
			(xy 53.623206 -317.724228) (xy 53.631249 -317.673446) (xy 53.647137 -317.624547) (xy 53.67048 -317.578735)
			(xy 53.700701 -317.537139) (xy 53.737057 -317.500783) (xy 53.778653 -317.470562) (xy 53.824465 -317.447219)
			(xy 53.873364 -317.431331) (xy 53.924146 -317.423288) (xy 53.975562 -317.423288) (xy 54.026344 -317.431331)
			(xy 54.075243 -317.447219) (xy 54.121055 -317.470562) (xy 54.162651 -317.500783) (xy 54.199007 -317.537139)
			(xy 54.229228 -317.578735) (xy 54.252571 -317.624547) (xy 54.268459 -317.673446) (xy 54.276502 -317.724228)
			(xy 54.277006 -317.749936) (xy 54.59401 -317.749936) (xy 54.59797 -317.700882) (xy 54.609747 -317.653098)
			(xy 54.629038 -317.607822) (xy 54.655341 -317.566226) (xy 54.687976 -317.529389) (xy 54.726097 -317.498264)
			(xy 54.768718 -317.473657) (xy 54.814734 -317.456205) (xy 54.862953 -317.446361) (xy 54.912128 -317.44438)
			(xy 54.960983 -317.450312) (xy 55.008254 -317.464004) (xy 55.052716 -317.485102) (xy 55.093219 -317.513058)
			(xy 55.128712 -317.54715) (xy 55.158277 -317.586494) (xy 55.181148 -317.630071) (xy 55.196732 -317.676752)
			(xy 55.204627 -317.725329) (xy 55.205122 -317.749936) (xy 55.204627 -317.774543) (xy 55.204448 -317.775644)
			(xy 55.523126 -317.775644) (xy 55.523126 -317.724228) (xy 55.531169 -317.673446) (xy 55.547057 -317.624547)
			(xy 55.5704 -317.578735) (xy 55.600621 -317.537139) (xy 55.636977 -317.500783) (xy 55.678573 -317.470562)
			(xy 55.724385 -317.447219) (xy 55.773284 -317.431331) (xy 55.824066 -317.423288) (xy 55.875482 -317.423288)
			(xy 55.926264 -317.431331) (xy 55.975163 -317.447219) (xy 56.020975 -317.470562) (xy 56.062571 -317.500783)
			(xy 56.098927 -317.537139) (xy 56.129148 -317.578735) (xy 56.152491 -317.624547) (xy 56.168379 -317.673446)
			(xy 56.176422 -317.724228) (xy 56.176926 -317.749936) (xy 56.494184 -317.749936) (xy 56.498144 -317.700882)
			(xy 56.509921 -317.653098) (xy 56.529212 -317.607822) (xy 56.555515 -317.566226) (xy 56.58815 -317.529389)
			(xy 56.626271 -317.498264) (xy 56.668892 -317.473657) (xy 56.714908 -317.456205) (xy 56.763127 -317.446361)
			(xy 56.812302 -317.44438) (xy 56.861157 -317.450312) (xy 56.908428 -317.464004) (xy 56.95289 -317.485102)
			(xy 56.993393 -317.513058) (xy 57.028886 -317.54715) (xy 57.058451 -317.586494) (xy 57.081322 -317.630071)
			(xy 57.096906 -317.676752) (xy 57.104801 -317.725329) (xy 57.105296 -317.749936) (xy 57.104801 -317.774543)
			(xy 57.104622 -317.775644) (xy 57.4233 -317.775644) (xy 57.4233 -317.724228) (xy 57.431343 -317.673446)
			(xy 57.447231 -317.624547) (xy 57.470574 -317.578735) (xy 57.500795 -317.537139) (xy 57.537151 -317.500783)
			(xy 57.578747 -317.470562) (xy 57.624559 -317.447219) (xy 57.673458 -317.431331) (xy 57.72424 -317.423288)
			(xy 57.775656 -317.423288) (xy 57.826438 -317.431331) (xy 57.875337 -317.447219) (xy 57.921149 -317.470562)
			(xy 57.962745 -317.500783) (xy 57.999101 -317.537139) (xy 58.029322 -317.578735) (xy 58.052665 -317.624547)
			(xy 58.068553 -317.673446) (xy 58.076596 -317.724228) (xy 58.0771 -317.749936) (xy 58.394104 -317.749936)
			(xy 58.398064 -317.700882) (xy 58.409841 -317.653098) (xy 58.429132 -317.607822) (xy 58.455435 -317.566226)
			(xy 58.48807 -317.529389) (xy 58.526191 -317.498264) (xy 58.568812 -317.473657) (xy 58.614828 -317.456205)
			(xy 58.663047 -317.446361) (xy 58.712222 -317.44438) (xy 58.761077 -317.450312) (xy 58.808348 -317.464004)
			(xy 58.85281 -317.485102) (xy 58.893313 -317.513058) (xy 58.928806 -317.54715) (xy 58.958371 -317.586494)
			(xy 58.981242 -317.630071) (xy 58.996826 -317.676752) (xy 59.004721 -317.725329) (xy 59.005216 -317.749936)
			(xy 59.004721 -317.774543) (xy 59.004542 -317.775644) (xy 59.32322 -317.775644) (xy 59.32322 -317.724228)
			(xy 59.331263 -317.673446) (xy 59.347151 -317.624547) (xy 59.370494 -317.578735) (xy 59.400715 -317.537139)
			(xy 59.437071 -317.500783) (xy 59.478667 -317.470562) (xy 59.524479 -317.447219) (xy 59.573378 -317.431331)
			(xy 59.62416 -317.423288) (xy 59.675576 -317.423288) (xy 59.726358 -317.431331) (xy 59.775257 -317.447219)
			(xy 59.821069 -317.470562) (xy 59.862665 -317.500783) (xy 59.899021 -317.537139) (xy 59.929242 -317.578735)
			(xy 59.952585 -317.624547) (xy 59.968473 -317.673446) (xy 59.976516 -317.724228) (xy 59.97702 -317.749936)
			(xy 60.294024 -317.749936) (xy 60.297984 -317.700882) (xy 60.309761 -317.653098) (xy 60.329052 -317.607822)
			(xy 60.355355 -317.566226) (xy 60.38799 -317.529389) (xy 60.426111 -317.498264) (xy 60.468732 -317.473657)
			(xy 60.514748 -317.456205) (xy 60.562967 -317.446361) (xy 60.612142 -317.44438) (xy 60.660997 -317.450312)
			(xy 60.708268 -317.464004) (xy 60.75273 -317.485102) (xy 60.793233 -317.513058) (xy 60.828726 -317.54715)
			(xy 60.858291 -317.586494) (xy 60.881162 -317.630071) (xy 60.896746 -317.676752) (xy 60.904641 -317.725329)
			(xy 60.905136 -317.749936) (xy 60.904641 -317.774543) (xy 60.904462 -317.775644) (xy 61.22314 -317.775644)
			(xy 61.22314 -317.724228) (xy 61.231183 -317.673446) (xy 61.247071 -317.624547) (xy 61.270414 -317.578735)
			(xy 61.300635 -317.537139) (xy 61.336991 -317.500783) (xy 61.378587 -317.470562) (xy 61.424399 -317.447219)
			(xy 61.473298 -317.431331) (xy 61.52408 -317.423288) (xy 61.575496 -317.423288) (xy 61.626278 -317.431331)
			(xy 61.675177 -317.447219) (xy 61.720989 -317.470562) (xy 61.762585 -317.500783) (xy 61.798941 -317.537139)
			(xy 61.829162 -317.578735) (xy 61.852505 -317.624547) (xy 61.868393 -317.673446) (xy 61.876436 -317.724228)
			(xy 61.87694 -317.749936) (xy 62.193944 -317.749936) (xy 62.197904 -317.700882) (xy 62.209681 -317.653098)
			(xy 62.228972 -317.607822) (xy 62.255275 -317.566226) (xy 62.28791 -317.529389) (xy 62.326031 -317.498264)
			(xy 62.368652 -317.473657) (xy 62.414668 -317.456205) (xy 62.462887 -317.446361) (xy 62.512062 -317.44438)
			(xy 62.560917 -317.450312) (xy 62.608188 -317.464004) (xy 62.65265 -317.485102) (xy 62.693153 -317.513058)
			(xy 62.728646 -317.54715) (xy 62.758211 -317.586494) (xy 62.781082 -317.630071) (xy 62.796666 -317.676752)
			(xy 62.804561 -317.725329) (xy 62.805056 -317.749936) (xy 62.804561 -317.774543) (xy 62.804382 -317.775644)
			(xy 63.123314 -317.775644) (xy 63.123314 -317.724228) (xy 63.131357 -317.673446) (xy 63.147245 -317.624547)
			(xy 63.170588 -317.578735) (xy 63.200809 -317.537139) (xy 63.237165 -317.500783) (xy 63.278761 -317.470562)
			(xy 63.324573 -317.447219) (xy 63.373472 -317.431331) (xy 63.424254 -317.423288) (xy 63.47567 -317.423288)
			(xy 63.526452 -317.431331) (xy 63.575351 -317.447219) (xy 63.621163 -317.470562) (xy 63.662759 -317.500783)
			(xy 63.699115 -317.537139) (xy 63.729336 -317.578735) (xy 63.752679 -317.624547) (xy 63.768567 -317.673446)
			(xy 63.77661 -317.724228) (xy 63.777114 -317.749936) (xy 64.094118 -317.749936) (xy 64.098078 -317.700882)
			(xy 64.109855 -317.653098) (xy 64.129146 -317.607822) (xy 64.155449 -317.566226) (xy 64.188084 -317.529389)
			(xy 64.226205 -317.498264) (xy 64.268826 -317.473657) (xy 64.314842 -317.456205) (xy 64.363061 -317.446361)
			(xy 64.412236 -317.44438) (xy 64.461091 -317.450312) (xy 64.508362 -317.464004) (xy 64.552824 -317.485102)
			(xy 64.593327 -317.513058) (xy 64.62882 -317.54715) (xy 64.658385 -317.586494) (xy 64.681256 -317.630071)
			(xy 64.69684 -317.676752) (xy 64.704735 -317.725329) (xy 64.70523 -317.749936) (xy 64.704735 -317.774543)
			(xy 64.704556 -317.775644) (xy 65.023234 -317.775644) (xy 65.023234 -317.724228) (xy 65.031277 -317.673446)
			(xy 65.047165 -317.624547) (xy 65.070508 -317.578735) (xy 65.100729 -317.537139) (xy 65.137085 -317.500783)
			(xy 65.178681 -317.470562) (xy 65.224493 -317.447219) (xy 65.273392 -317.431331) (xy 65.324174 -317.423288)
			(xy 65.37559 -317.423288) (xy 65.426372 -317.431331) (xy 65.475271 -317.447219) (xy 65.521083 -317.470562)
			(xy 65.562679 -317.500783) (xy 65.599035 -317.537139) (xy 65.629256 -317.578735) (xy 65.652599 -317.624547)
			(xy 65.668487 -317.673446) (xy 65.67653 -317.724228) (xy 65.677034 -317.749936) (xy 65.994038 -317.749936)
			(xy 65.997998 -317.700882) (xy 66.009775 -317.653098) (xy 66.029066 -317.607822) (xy 66.055369 -317.566226)
			(xy 66.088004 -317.529389) (xy 66.126125 -317.498264) (xy 66.168746 -317.473657) (xy 66.214762 -317.456205)
			(xy 66.262981 -317.446361) (xy 66.312156 -317.44438) (xy 66.361011 -317.450312) (xy 66.408282 -317.464004)
			(xy 66.452744 -317.485102) (xy 66.493247 -317.513058) (xy 66.52874 -317.54715) (xy 66.558305 -317.586494)
			(xy 66.581176 -317.630071) (xy 66.59676 -317.676752) (xy 66.604655 -317.725329) (xy 66.60515 -317.749936)
			(xy 66.604655 -317.774543) (xy 66.604476 -317.775644) (xy 66.923154 -317.775644) (xy 66.923154 -317.724228)
			(xy 66.931197 -317.673446) (xy 66.947085 -317.624547) (xy 66.970428 -317.578735) (xy 67.000649 -317.537139)
			(xy 67.037005 -317.500783) (xy 67.078601 -317.470562) (xy 67.124413 -317.447219) (xy 67.173312 -317.431331)
			(xy 67.224094 -317.423288) (xy 67.27551 -317.423288) (xy 67.326292 -317.431331) (xy 67.375191 -317.447219)
			(xy 67.421003 -317.470562) (xy 67.462599 -317.500783) (xy 67.498955 -317.537139) (xy 67.529176 -317.578735)
			(xy 67.552519 -317.624547) (xy 67.568407 -317.673446) (xy 67.57645 -317.724228) (xy 67.576954 -317.749936)
			(xy 67.893958 -317.749936) (xy 67.897918 -317.700882) (xy 67.909695 -317.653098) (xy 67.928986 -317.607822)
			(xy 67.955289 -317.566226) (xy 67.987924 -317.529389) (xy 68.026045 -317.498264) (xy 68.068666 -317.473657)
			(xy 68.114682 -317.456205) (xy 68.162901 -317.446361) (xy 68.212076 -317.44438) (xy 68.260931 -317.450312)
			(xy 68.308202 -317.464004) (xy 68.352664 -317.485102) (xy 68.393167 -317.513058) (xy 68.42866 -317.54715)
			(xy 68.458225 -317.586494) (xy 68.481096 -317.630071) (xy 68.49668 -317.676752) (xy 68.504575 -317.725329)
			(xy 68.50507 -317.749936) (xy 68.504575 -317.774543) (xy 68.504396 -317.775644) (xy 68.823328 -317.775644)
			(xy 68.823328 -317.724228) (xy 68.831371 -317.673446) (xy 68.847259 -317.624547) (xy 68.870602 -317.578735)
			(xy 68.900823 -317.537139) (xy 68.937179 -317.500783) (xy 68.978775 -317.470562) (xy 69.024587 -317.447219)
			(xy 69.073486 -317.431331) (xy 69.124268 -317.423288) (xy 69.175684 -317.423288) (xy 69.226466 -317.431331)
			(xy 69.275365 -317.447219) (xy 69.321177 -317.470562) (xy 69.362773 -317.500783) (xy 69.399129 -317.537139)
			(xy 69.42935 -317.578735) (xy 69.452693 -317.624547) (xy 69.468581 -317.673446) (xy 69.476624 -317.724228)
			(xy 69.477128 -317.749936) (xy 69.794132 -317.749936) (xy 69.798092 -317.700882) (xy 69.809869 -317.653098)
			(xy 69.82916 -317.607822) (xy 69.855463 -317.566226) (xy 69.888098 -317.529389) (xy 69.926219 -317.498264)
			(xy 69.96884 -317.473657) (xy 70.014856 -317.456205) (xy 70.063075 -317.446361) (xy 70.11225 -317.44438)
			(xy 70.161105 -317.450312) (xy 70.208376 -317.464004) (xy 70.252838 -317.485102) (xy 70.293341 -317.513058)
			(xy 70.328834 -317.54715) (xy 70.358399 -317.586494) (xy 70.38127 -317.630071) (xy 70.396854 -317.676752)
			(xy 70.404749 -317.725329) (xy 70.405244 -317.749936) (xy 70.404749 -317.774543) (xy 70.40457 -317.775644)
			(xy 70.723248 -317.775644) (xy 70.723248 -317.724228) (xy 70.731291 -317.673446) (xy 70.747179 -317.624547)
			(xy 70.770522 -317.578735) (xy 70.800743 -317.537139) (xy 70.837099 -317.500783) (xy 70.878695 -317.470562)
			(xy 70.924507 -317.447219) (xy 70.973406 -317.431331) (xy 71.024188 -317.423288) (xy 71.075604 -317.423288)
			(xy 71.126386 -317.431331) (xy 71.175285 -317.447219) (xy 71.221097 -317.470562) (xy 71.262693 -317.500783)
			(xy 71.299049 -317.537139) (xy 71.32927 -317.578735) (xy 71.352613 -317.624547) (xy 71.368501 -317.673446)
			(xy 71.376544 -317.724228) (xy 71.377048 -317.749936) (xy 71.376544 -317.775644) (xy 71.368501 -317.826426)
			(xy 71.352613 -317.875325) (xy 71.32927 -317.921137) (xy 71.299049 -317.962733) (xy 71.262693 -317.999089)
			(xy 71.221097 -318.02931) (xy 71.175285 -318.052653) (xy 71.126386 -318.068541) (xy 71.075604 -318.076584)
			(xy 71.024188 -318.076584) (xy 70.973406 -318.068541) (xy 70.924507 -318.052653) (xy 70.878695 -318.02931)
			(xy 70.837099 -317.999089) (xy 70.800743 -317.962733) (xy 70.770522 -317.921137) (xy 70.747179 -317.875325)
			(xy 70.731291 -317.826426) (xy 70.723248 -317.775644) (xy 70.40457 -317.775644) (xy 70.396854 -317.82312)
			(xy 70.38127 -317.869801) (xy 70.358399 -317.913378) (xy 70.328834 -317.952722) (xy 70.293341 -317.986814)
			(xy 70.252838 -318.01477) (xy 70.208376 -318.035868) (xy 70.161105 -318.04956) (xy 70.11225 -318.055492)
			(xy 70.063075 -318.053511) (xy 70.014856 -318.043667) (xy 69.96884 -318.026215) (xy 69.926219 -318.001608)
			(xy 69.888098 -317.970483) (xy 69.855463 -317.933646) (xy 69.82916 -317.89205) (xy 69.809869 -317.846774)
			(xy 69.798092 -317.79899) (xy 69.794132 -317.749936) (xy 69.477128 -317.749936) (xy 69.476624 -317.775644)
			(xy 69.468581 -317.826426) (xy 69.452693 -317.875325) (xy 69.42935 -317.921137) (xy 69.399129 -317.962733)
			(xy 69.362773 -317.999089) (xy 69.321177 -318.02931) (xy 69.275365 -318.052653) (xy 69.226466 -318.068541)
			(xy 69.175684 -318.076584) (xy 69.124268 -318.076584) (xy 69.073486 -318.068541) (xy 69.024587 -318.052653)
			(xy 68.978775 -318.02931) (xy 68.937179 -317.999089) (xy 68.900823 -317.962733) (xy 68.870602 -317.921137)
			(xy 68.847259 -317.875325) (xy 68.831371 -317.826426) (xy 68.823328 -317.775644) (xy 68.504396 -317.775644)
			(xy 68.49668 -317.82312) (xy 68.481096 -317.869801) (xy 68.458225 -317.913378) (xy 68.42866 -317.952722)
			(xy 68.393167 -317.986814) (xy 68.352664 -318.01477) (xy 68.308202 -318.035868) (xy 68.260931 -318.04956)
			(xy 68.212076 -318.055492) (xy 68.162901 -318.053511) (xy 68.114682 -318.043667) (xy 68.068666 -318.026215)
			(xy 68.026045 -318.001608) (xy 67.987924 -317.970483) (xy 67.955289 -317.933646) (xy 67.928986 -317.89205)
			(xy 67.909695 -317.846774) (xy 67.897918 -317.79899) (xy 67.893958 -317.749936) (xy 67.576954 -317.749936)
			(xy 67.57645 -317.775644) (xy 67.568407 -317.826426) (xy 67.552519 -317.875325) (xy 67.529176 -317.921137)
			(xy 67.498955 -317.962733) (xy 67.462599 -317.999089) (xy 67.421003 -318.02931) (xy 67.375191 -318.052653)
			(xy 67.326292 -318.068541) (xy 67.27551 -318.076584) (xy 67.224094 -318.076584) (xy 67.173312 -318.068541)
			(xy 67.124413 -318.052653) (xy 67.078601 -318.02931) (xy 67.037005 -317.999089) (xy 67.000649 -317.962733)
			(xy 66.970428 -317.921137) (xy 66.947085 -317.875325) (xy 66.931197 -317.826426) (xy 66.923154 -317.775644)
			(xy 66.604476 -317.775644) (xy 66.59676 -317.82312) (xy 66.581176 -317.869801) (xy 66.558305 -317.913378)
			(xy 66.52874 -317.952722) (xy 66.493247 -317.986814) (xy 66.452744 -318.01477) (xy 66.408282 -318.035868)
			(xy 66.361011 -318.04956) (xy 66.312156 -318.055492) (xy 66.262981 -318.053511) (xy 66.214762 -318.043667)
			(xy 66.168746 -318.026215) (xy 66.126125 -318.001608) (xy 66.088004 -317.970483) (xy 66.055369 -317.933646)
			(xy 66.029066 -317.89205) (xy 66.009775 -317.846774) (xy 65.997998 -317.79899) (xy 65.994038 -317.749936)
			(xy 65.677034 -317.749936) (xy 65.67653 -317.775644) (xy 65.668487 -317.826426) (xy 65.652599 -317.875325)
			(xy 65.629256 -317.921137) (xy 65.599035 -317.962733) (xy 65.562679 -317.999089) (xy 65.521083 -318.02931)
			(xy 65.475271 -318.052653) (xy 65.426372 -318.068541) (xy 65.37559 -318.076584) (xy 65.324174 -318.076584)
			(xy 65.273392 -318.068541) (xy 65.224493 -318.052653) (xy 65.178681 -318.02931) (xy 65.137085 -317.999089)
			(xy 65.100729 -317.962733) (xy 65.070508 -317.921137) (xy 65.047165 -317.875325) (xy 65.031277 -317.826426)
			(xy 65.023234 -317.775644) (xy 64.704556 -317.775644) (xy 64.69684 -317.82312) (xy 64.681256 -317.869801)
			(xy 64.658385 -317.913378) (xy 64.62882 -317.952722) (xy 64.593327 -317.986814) (xy 64.552824 -318.01477)
			(xy 64.508362 -318.035868) (xy 64.461091 -318.04956) (xy 64.412236 -318.055492) (xy 64.363061 -318.053511)
			(xy 64.314842 -318.043667) (xy 64.268826 -318.026215) (xy 64.226205 -318.001608) (xy 64.188084 -317.970483)
			(xy 64.155449 -317.933646) (xy 64.129146 -317.89205) (xy 64.109855 -317.846774) (xy 64.098078 -317.79899)
			(xy 64.094118 -317.749936) (xy 63.777114 -317.749936) (xy 63.77661 -317.775644) (xy 63.768567 -317.826426)
			(xy 63.752679 -317.875325) (xy 63.729336 -317.921137) (xy 63.699115 -317.962733) (xy 63.662759 -317.999089)
			(xy 63.621163 -318.02931) (xy 63.575351 -318.052653) (xy 63.526452 -318.068541) (xy 63.47567 -318.076584)
			(xy 63.424254 -318.076584) (xy 63.373472 -318.068541) (xy 63.324573 -318.052653) (xy 63.278761 -318.02931)
			(xy 63.237165 -317.999089) (xy 63.200809 -317.962733) (xy 63.170588 -317.921137) (xy 63.147245 -317.875325)
			(xy 63.131357 -317.826426) (xy 63.123314 -317.775644) (xy 62.804382 -317.775644) (xy 62.796666 -317.82312)
			(xy 62.781082 -317.869801) (xy 62.758211 -317.913378) (xy 62.728646 -317.952722) (xy 62.693153 -317.986814)
			(xy 62.65265 -318.01477) (xy 62.608188 -318.035868) (xy 62.560917 -318.04956) (xy 62.512062 -318.055492)
			(xy 62.462887 -318.053511) (xy 62.414668 -318.043667) (xy 62.368652 -318.026215) (xy 62.326031 -318.001608)
			(xy 62.28791 -317.970483) (xy 62.255275 -317.933646) (xy 62.228972 -317.89205) (xy 62.209681 -317.846774)
			(xy 62.197904 -317.79899) (xy 62.193944 -317.749936) (xy 61.87694 -317.749936) (xy 61.876436 -317.775644)
			(xy 61.868393 -317.826426) (xy 61.852505 -317.875325) (xy 61.829162 -317.921137) (xy 61.798941 -317.962733)
			(xy 61.762585 -317.999089) (xy 61.720989 -318.02931) (xy 61.675177 -318.052653) (xy 61.626278 -318.068541)
			(xy 61.575496 -318.076584) (xy 61.52408 -318.076584) (xy 61.473298 -318.068541) (xy 61.424399 -318.052653)
			(xy 61.378587 -318.02931) (xy 61.336991 -317.999089) (xy 61.300635 -317.962733) (xy 61.270414 -317.921137)
			(xy 61.247071 -317.875325) (xy 61.231183 -317.826426) (xy 61.22314 -317.775644) (xy 60.904462 -317.775644)
			(xy 60.896746 -317.82312) (xy 60.881162 -317.869801) (xy 60.858291 -317.913378) (xy 60.828726 -317.952722)
			(xy 60.793233 -317.986814) (xy 60.75273 -318.01477) (xy 60.708268 -318.035868) (xy 60.660997 -318.04956)
			(xy 60.612142 -318.055492) (xy 60.562967 -318.053511) (xy 60.514748 -318.043667) (xy 60.468732 -318.026215)
			(xy 60.426111 -318.001608) (xy 60.38799 -317.970483) (xy 60.355355 -317.933646) (xy 60.329052 -317.89205)
			(xy 60.309761 -317.846774) (xy 60.297984 -317.79899) (xy 60.294024 -317.749936) (xy 59.97702 -317.749936)
			(xy 59.976516 -317.775644) (xy 59.968473 -317.826426) (xy 59.952585 -317.875325) (xy 59.929242 -317.921137)
			(xy 59.899021 -317.962733) (xy 59.862665 -317.999089) (xy 59.821069 -318.02931) (xy 59.775257 -318.052653)
			(xy 59.726358 -318.068541) (xy 59.675576 -318.076584) (xy 59.62416 -318.076584) (xy 59.573378 -318.068541)
			(xy 59.524479 -318.052653) (xy 59.478667 -318.02931) (xy 59.437071 -317.999089) (xy 59.400715 -317.962733)
			(xy 59.370494 -317.921137) (xy 59.347151 -317.875325) (xy 59.331263 -317.826426) (xy 59.32322 -317.775644)
			(xy 59.004542 -317.775644) (xy 58.996826 -317.82312) (xy 58.981242 -317.869801) (xy 58.958371 -317.913378)
			(xy 58.928806 -317.952722) (xy 58.893313 -317.986814) (xy 58.85281 -318.01477) (xy 58.808348 -318.035868)
			(xy 58.761077 -318.04956) (xy 58.712222 -318.055492) (xy 58.663047 -318.053511) (xy 58.614828 -318.043667)
			(xy 58.568812 -318.026215) (xy 58.526191 -318.001608) (xy 58.48807 -317.970483) (xy 58.455435 -317.933646)
			(xy 58.429132 -317.89205) (xy 58.409841 -317.846774) (xy 58.398064 -317.79899) (xy 58.394104 -317.749936)
			(xy 58.0771 -317.749936) (xy 58.076596 -317.775644) (xy 58.068553 -317.826426) (xy 58.052665 -317.875325)
			(xy 58.029322 -317.921137) (xy 57.999101 -317.962733) (xy 57.962745 -317.999089) (xy 57.921149 -318.02931)
			(xy 57.875337 -318.052653) (xy 57.826438 -318.068541) (xy 57.775656 -318.076584) (xy 57.72424 -318.076584)
			(xy 57.673458 -318.068541) (xy 57.624559 -318.052653) (xy 57.578747 -318.02931) (xy 57.537151 -317.999089)
			(xy 57.500795 -317.962733) (xy 57.470574 -317.921137) (xy 57.447231 -317.875325) (xy 57.431343 -317.826426)
			(xy 57.4233 -317.775644) (xy 57.104622 -317.775644) (xy 57.096906 -317.82312) (xy 57.081322 -317.869801)
			(xy 57.058451 -317.913378) (xy 57.028886 -317.952722) (xy 56.993393 -317.986814) (xy 56.95289 -318.01477)
			(xy 56.908428 -318.035868) (xy 56.861157 -318.04956) (xy 56.812302 -318.055492) (xy 56.763127 -318.053511)
			(xy 56.714908 -318.043667) (xy 56.668892 -318.026215) (xy 56.626271 -318.001608) (xy 56.58815 -317.970483)
			(xy 56.555515 -317.933646) (xy 56.529212 -317.89205) (xy 56.509921 -317.846774) (xy 56.498144 -317.79899)
			(xy 56.494184 -317.749936) (xy 56.176926 -317.749936) (xy 56.176422 -317.775644) (xy 56.168379 -317.826426)
			(xy 56.152491 -317.875325) (xy 56.129148 -317.921137) (xy 56.098927 -317.962733) (xy 56.062571 -317.999089)
			(xy 56.020975 -318.02931) (xy 55.975163 -318.052653) (xy 55.926264 -318.068541) (xy 55.875482 -318.076584)
			(xy 55.824066 -318.076584) (xy 55.773284 -318.068541) (xy 55.724385 -318.052653) (xy 55.678573 -318.02931)
			(xy 55.636977 -317.999089) (xy 55.600621 -317.962733) (xy 55.5704 -317.921137) (xy 55.547057 -317.875325)
			(xy 55.531169 -317.826426) (xy 55.523126 -317.775644) (xy 55.204448 -317.775644) (xy 55.196732 -317.82312)
			(xy 55.181148 -317.869801) (xy 55.158277 -317.913378) (xy 55.128712 -317.952722) (xy 55.093219 -317.986814)
			(xy 55.052716 -318.01477) (xy 55.008254 -318.035868) (xy 54.960983 -318.04956) (xy 54.912128 -318.055492)
			(xy 54.862953 -318.053511) (xy 54.814734 -318.043667) (xy 54.768718 -318.026215) (xy 54.726097 -318.001608)
			(xy 54.687976 -317.970483) (xy 54.655341 -317.933646) (xy 54.629038 -317.89205) (xy 54.609747 -317.846774)
			(xy 54.59797 -317.79899) (xy 54.59401 -317.749936) (xy 54.277006 -317.749936) (xy 54.276502 -317.775644)
			(xy 54.268459 -317.826426) (xy 54.252571 -317.875325) (xy 54.229228 -317.921137) (xy 54.199007 -317.962733)
			(xy 54.162651 -317.999089) (xy 54.121055 -318.02931) (xy 54.075243 -318.052653) (xy 54.026344 -318.068541)
			(xy 53.975562 -318.076584) (xy 53.924146 -318.076584) (xy 53.873364 -318.068541) (xy 53.824465 -318.052653)
			(xy 53.778653 -318.02931) (xy 53.737057 -317.999089) (xy 53.700701 -317.962733) (xy 53.67048 -317.921137)
			(xy 53.647137 -317.875325) (xy 53.631249 -317.826426) (xy 53.623206 -317.775644) (xy 53.304528 -317.775644)
			(xy 53.296812 -317.82312) (xy 53.281228 -317.869801) (xy 53.258357 -317.913378) (xy 53.228792 -317.952722)
			(xy 53.193299 -317.986814) (xy 53.152796 -318.01477) (xy 53.108334 -318.035868) (xy 53.061063 -318.04956)
			(xy 53.012208 -318.055492) (xy 52.963033 -318.053511) (xy 52.914814 -318.043667) (xy 52.868798 -318.026215)
			(xy 52.826177 -318.001608) (xy 52.788056 -317.970483) (xy 52.755421 -317.933646) (xy 52.729118 -317.89205)
			(xy 52.709827 -317.846774) (xy 52.69805 -317.79899) (xy 52.69409 -317.749936) (xy 52.377086 -317.749936)
			(xy 52.376582 -317.775644) (xy 52.368539 -317.826426) (xy 52.352651 -317.875325) (xy 52.329308 -317.921137)
			(xy 52.299087 -317.962733) (xy 52.262731 -317.999089) (xy 52.221135 -318.02931) (xy 52.175323 -318.052653)
			(xy 52.126424 -318.068541) (xy 52.075642 -318.076584) (xy 52.024226 -318.076584) (xy 51.973444 -318.068541)
			(xy 51.924545 -318.052653) (xy 51.878733 -318.02931) (xy 51.837137 -317.999089) (xy 51.800781 -317.962733)
			(xy 51.77056 -317.921137) (xy 51.747217 -317.875325) (xy 51.731329 -317.826426) (xy 51.723286 -317.775644)
			(xy 51.404608 -317.775644) (xy 51.396892 -317.82312) (xy 51.381308 -317.869801) (xy 51.358437 -317.913378)
			(xy 51.328872 -317.952722) (xy 51.293379 -317.986814) (xy 51.252876 -318.01477) (xy 51.208414 -318.035868)
			(xy 51.161143 -318.04956) (xy 51.112288 -318.055492) (xy 51.063113 -318.053511) (xy 51.014894 -318.043667)
			(xy 50.968878 -318.026215) (xy 50.926257 -318.001608) (xy 50.888136 -317.970483) (xy 50.855501 -317.933646)
			(xy 50.829198 -317.89205) (xy 50.809907 -317.846774) (xy 50.79813 -317.79899) (xy 50.79417 -317.749936)
			(xy 50.476912 -317.749936) (xy 50.476408 -317.775644) (xy 50.468365 -317.826426) (xy 50.452477 -317.875325)
			(xy 50.429134 -317.921137) (xy 50.398913 -317.962733) (xy 50.362557 -317.999089) (xy 50.320961 -318.02931)
			(xy 50.275149 -318.052653) (xy 50.22625 -318.068541) (xy 50.175468 -318.076584) (xy 50.124052 -318.076584)
			(xy 50.07327 -318.068541) (xy 50.024371 -318.052653) (xy 49.978559 -318.02931) (xy 49.936963 -317.999089)
			(xy 49.900607 -317.962733) (xy 49.870386 -317.921137) (xy 49.847043 -317.875325) (xy 49.831155 -317.826426)
			(xy 49.823112 -317.775644) (xy 49.504434 -317.775644) (xy 49.496718 -317.82312) (xy 49.481134 -317.869801)
			(xy 49.458263 -317.913378) (xy 49.428698 -317.952722) (xy 49.393205 -317.986814) (xy 49.352702 -318.01477)
			(xy 49.30824 -318.035868) (xy 49.260969 -318.04956) (xy 49.212114 -318.055492) (xy 49.162939 -318.053511)
			(xy 49.11472 -318.043667) (xy 49.068704 -318.026215) (xy 49.026083 -318.001608) (xy 48.987962 -317.970483)
			(xy 48.955327 -317.933646) (xy 48.929024 -317.89205) (xy 48.909733 -317.846774) (xy 48.897956 -317.79899)
			(xy 48.893996 -317.749936) (xy 48.576992 -317.749936) (xy 48.576488 -317.775644) (xy 48.568445 -317.826426)
			(xy 48.552557 -317.875325) (xy 48.529214 -317.921137) (xy 48.498993 -317.962733) (xy 48.462637 -317.999089)
			(xy 48.421041 -318.02931) (xy 48.375229 -318.052653) (xy 48.32633 -318.068541) (xy 48.275548 -318.076584)
			(xy 48.224132 -318.076584) (xy 48.17335 -318.068541) (xy 48.124451 -318.052653) (xy 48.078639 -318.02931)
			(xy 48.037043 -317.999089) (xy 48.000687 -317.962733) (xy 47.970466 -317.921137) (xy 47.947123 -317.875325)
			(xy 47.931235 -317.826426) (xy 47.923192 -317.775644) (xy 47.604514 -317.775644) (xy 47.596798 -317.82312)
			(xy 47.581214 -317.869801) (xy 47.558343 -317.913378) (xy 47.528778 -317.952722) (xy 47.493285 -317.986814)
			(xy 47.452782 -318.01477) (xy 47.40832 -318.035868) (xy 47.361049 -318.04956) (xy 47.312194 -318.055492)
			(xy 47.263019 -318.053511) (xy 47.2148 -318.043667) (xy 47.168784 -318.026215) (xy 47.126163 -318.001608)
			(xy 47.088042 -317.970483) (xy 47.055407 -317.933646) (xy 47.029104 -317.89205) (xy 47.009813 -317.846774)
			(xy 46.998036 -317.79899) (xy 46.994076 -317.749936) (xy 46.677072 -317.749936) (xy 46.676568 -317.775644)
			(xy 46.668525 -317.826426) (xy 46.652637 -317.875325) (xy 46.629294 -317.921137) (xy 46.599073 -317.962733)
			(xy 46.562717 -317.999089) (xy 46.521121 -318.02931) (xy 46.475309 -318.052653) (xy 46.42641 -318.068541)
			(xy 46.375628 -318.076584) (xy 46.324212 -318.076584) (xy 46.27343 -318.068541) (xy 46.224531 -318.052653)
			(xy 46.178719 -318.02931) (xy 46.137123 -317.999089) (xy 46.100767 -317.962733) (xy 46.070546 -317.921137)
			(xy 46.047203 -317.875325) (xy 46.031315 -317.826426) (xy 46.023272 -317.775644) (xy 45.704594 -317.775644)
			(xy 45.696878 -317.82312) (xy 45.681294 -317.869801) (xy 45.658423 -317.913378) (xy 45.628858 -317.952722)
			(xy 45.593365 -317.986814) (xy 45.552862 -318.01477) (xy 45.5084 -318.035868) (xy 45.461129 -318.04956)
			(xy 45.412274 -318.055492) (xy 45.363099 -318.053511) (xy 45.31488 -318.043667) (xy 45.268864 -318.026215)
			(xy 45.226243 -318.001608) (xy 45.188122 -317.970483) (xy 45.155487 -317.933646) (xy 45.129184 -317.89205)
			(xy 45.109893 -317.846774) (xy 45.098116 -317.79899) (xy 45.094156 -317.749936) (xy 44.776898 -317.749936)
			(xy 44.776394 -317.775644) (xy 44.768351 -317.826426) (xy 44.752463 -317.875325) (xy 44.72912 -317.921137)
			(xy 44.698899 -317.962733) (xy 44.662543 -317.999089) (xy 44.620947 -318.02931) (xy 44.575135 -318.052653)
			(xy 44.526236 -318.068541) (xy 44.475454 -318.076584) (xy 44.424038 -318.076584) (xy 44.373256 -318.068541)
			(xy 44.324357 -318.052653) (xy 44.278545 -318.02931) (xy 44.236949 -317.999089) (xy 44.200593 -317.962733)
			(xy 44.170372 -317.921137) (xy 44.147029 -317.875325) (xy 44.131141 -317.826426) (xy 44.123098 -317.775644)
			(xy 43.80442 -317.775644) (xy 43.796704 -317.82312) (xy 43.78112 -317.869801) (xy 43.758249 -317.913378)
			(xy 43.728684 -317.952722) (xy 43.693191 -317.986814) (xy 43.652688 -318.01477) (xy 43.608226 -318.035868)
			(xy 43.560955 -318.04956) (xy 43.5121 -318.055492) (xy 43.462925 -318.053511) (xy 43.414706 -318.043667)
			(xy 43.36869 -318.026215) (xy 43.326069 -318.001608) (xy 43.287948 -317.970483) (xy 43.255313 -317.933646)
			(xy 43.22901 -317.89205) (xy 43.209719 -317.846774) (xy 43.197942 -317.79899) (xy 43.193982 -317.749936)
			(xy 42.876978 -317.749936) (xy 42.876474 -317.775644) (xy 42.868431 -317.826426) (xy 42.852543 -317.875325)
			(xy 42.8292 -317.921137) (xy 42.798979 -317.962733) (xy 42.762623 -317.999089) (xy 42.721027 -318.02931)
			(xy 42.675215 -318.052653) (xy 42.626316 -318.068541) (xy 42.575534 -318.076584) (xy 42.524118 -318.076584)
			(xy 42.473336 -318.068541) (xy 42.424437 -318.052653) (xy 42.378625 -318.02931) (xy 42.337029 -317.999089)
			(xy 42.300673 -317.962733) (xy 42.270452 -317.921137) (xy 42.247109 -317.875325) (xy 42.231221 -317.826426)
			(xy 42.223178 -317.775644) (xy 41.9045 -317.775644) (xy 41.896784 -317.82312) (xy 41.8812 -317.869801)
			(xy 41.858329 -317.913378) (xy 41.828764 -317.952722) (xy 41.793271 -317.986814) (xy 41.752768 -318.01477)
			(xy 41.708306 -318.035868) (xy 41.661035 -318.04956) (xy 41.61218 -318.055492) (xy 41.563005 -318.053511)
			(xy 41.514786 -318.043667) (xy 41.46877 -318.026215) (xy 41.426149 -318.001608) (xy 41.388028 -317.970483)
			(xy 41.355393 -317.933646) (xy 41.32909 -317.89205) (xy 41.309799 -317.846774) (xy 41.298022 -317.79899)
			(xy 41.294062 -317.749936) (xy 40.977058 -317.749936) (xy 40.976554 -317.775644) (xy 40.968511 -317.826426)
			(xy 40.952623 -317.875325) (xy 40.92928 -317.921137) (xy 40.899059 -317.962733) (xy 40.862703 -317.999089)
			(xy 40.821107 -318.02931) (xy 40.775295 -318.052653) (xy 40.726396 -318.068541) (xy 40.675614 -318.076584)
			(xy 40.624198 -318.076584) (xy 40.573416 -318.068541) (xy 40.524517 -318.052653) (xy 40.478705 -318.02931)
			(xy 40.437109 -317.999089) (xy 40.400753 -317.962733) (xy 40.370532 -317.921137) (xy 40.347189 -317.875325)
			(xy 40.331301 -317.826426) (xy 40.323258 -317.775644) (xy 40.00458 -317.775644) (xy 39.996864 -317.82312)
			(xy 39.98128 -317.869801) (xy 39.958409 -317.913378) (xy 39.928844 -317.952722) (xy 39.893351 -317.986814)
			(xy 39.852848 -318.01477) (xy 39.808386 -318.035868) (xy 39.761115 -318.04956) (xy 39.71226 -318.055492)
			(xy 39.663085 -318.053511) (xy 39.614866 -318.043667) (xy 39.56885 -318.026215) (xy 39.526229 -318.001608)
			(xy 39.488108 -317.970483) (xy 39.455473 -317.933646) (xy 39.42917 -317.89205) (xy 39.409879 -317.846774)
			(xy 39.398102 -317.79899) (xy 39.394142 -317.749936) (xy 39.077138 -317.749936) (xy 39.076634 -317.775644)
			(xy 39.068591 -317.826426) (xy 39.052703 -317.875325) (xy 39.02936 -317.921137) (xy 38.999139 -317.962733)
			(xy 38.962783 -317.999089) (xy 38.921187 -318.02931) (xy 38.875375 -318.052653) (xy 38.826476 -318.068541)
			(xy 38.775694 -318.076584) (xy 38.724278 -318.076584) (xy 38.673496 -318.068541) (xy 38.624597 -318.052653)
			(xy 38.578785 -318.02931) (xy 38.537189 -317.999089) (xy 38.500833 -317.962733) (xy 38.470612 -317.921137)
			(xy 38.447269 -317.875325) (xy 38.431381 -317.826426) (xy 38.423338 -317.775644) (xy 38.104406 -317.775644)
			(xy 38.09669 -317.82312) (xy 38.081106 -317.869801) (xy 38.058235 -317.913378) (xy 38.02867 -317.952722)
			(xy 37.993177 -317.986814) (xy 37.952674 -318.01477) (xy 37.908212 -318.035868) (xy 37.860941 -318.04956)
			(xy 37.812086 -318.055492) (xy 37.762911 -318.053511) (xy 37.714692 -318.043667) (xy 37.668676 -318.026215)
			(xy 37.626055 -318.001608) (xy 37.587934 -317.970483) (xy 37.555299 -317.933646) (xy 37.528996 -317.89205)
			(xy 37.509705 -317.846774) (xy 37.497928 -317.79899) (xy 37.493968 -317.749936) (xy 37.15512 -317.749936)
			(xy 37.154625 -317.774543) (xy 37.14673 -317.82312) (xy 37.131146 -317.869801) (xy 37.108275 -317.913378)
			(xy 37.07871 -317.952722) (xy 37.043217 -317.986814) (xy 37.002714 -318.01477) (xy 36.958252 -318.035868)
			(xy 36.910981 -318.04956) (xy 36.862126 -318.055492) (xy 36.812951 -318.053511) (xy 36.764732 -318.043667)
			(xy 36.718716 -318.026215) (xy 36.676095 -318.001608) (xy 36.637974 -317.970483) (xy 36.605339 -317.933646)
			(xy 36.579036 -317.89205) (xy 36.559745 -317.846774) (xy 36.547968 -317.79899) (xy 36.544008 -317.749936)
			(xy 33.239444 -317.749936) (xy 33.259481 -317.772129) (xy 33.38406 -317.921971) (xy 33.502424 -318.076769)
			(xy 33.614375 -318.236267) (xy 33.719727 -318.400198) (xy 33.818305 -318.56829) (xy 33.888434 -318.699896)
			(xy 37.493968 -318.699896) (xy 37.497928 -318.650842) (xy 37.509705 -318.603058) (xy 37.528996 -318.557782)
			(xy 37.555299 -318.516186) (xy 37.587934 -318.479349) (xy 37.626055 -318.448224) (xy 37.668676 -318.423617)
			(xy 37.714692 -318.406165) (xy 37.762911 -318.396321) (xy 37.812086 -318.39434) (xy 37.860941 -318.400272)
			(xy 37.908212 -318.413964) (xy 37.952674 -318.435062) (xy 37.993177 -318.463018) (xy 38.02867 -318.49711)
			(xy 38.058235 -318.536454) (xy 38.081106 -318.580031) (xy 38.09669 -318.626712) (xy 38.104585 -318.675289)
			(xy 38.10508 -318.699896) (xy 38.104585 -318.724503) (xy 38.104406 -318.725604) (xy 38.423338 -318.725604)
			(xy 38.423338 -318.674188) (xy 38.431381 -318.623406) (xy 38.447269 -318.574507) (xy 38.470612 -318.528695)
			(xy 38.500833 -318.487099) (xy 38.537189 -318.450743) (xy 38.578785 -318.420522) (xy 38.624597 -318.397179)
			(xy 38.673496 -318.381291) (xy 38.724278 -318.373248) (xy 38.775694 -318.373248) (xy 38.826476 -318.381291)
			(xy 38.875375 -318.397179) (xy 38.921187 -318.420522) (xy 38.962783 -318.450743) (xy 38.999139 -318.487099)
			(xy 39.02936 -318.528695) (xy 39.052703 -318.574507) (xy 39.068591 -318.623406) (xy 39.076634 -318.674188)
			(xy 39.077138 -318.699896) (xy 39.394142 -318.699896) (xy 39.398102 -318.650842) (xy 39.409879 -318.603058)
			(xy 39.42917 -318.557782) (xy 39.455473 -318.516186) (xy 39.488108 -318.479349) (xy 39.526229 -318.448224)
			(xy 39.56885 -318.423617) (xy 39.614866 -318.406165) (xy 39.663085 -318.396321) (xy 39.71226 -318.39434)
			(xy 39.761115 -318.400272) (xy 39.808386 -318.413964) (xy 39.852848 -318.435062) (xy 39.893351 -318.463018)
			(xy 39.928844 -318.49711) (xy 39.958409 -318.536454) (xy 39.98128 -318.580031) (xy 39.996864 -318.626712)
			(xy 40.004759 -318.675289) (xy 40.005254 -318.699896) (xy 40.004759 -318.724503) (xy 40.00458 -318.725604)
			(xy 40.323258 -318.725604) (xy 40.323258 -318.674188) (xy 40.331301 -318.623406) (xy 40.347189 -318.574507)
			(xy 40.370532 -318.528695) (xy 40.400753 -318.487099) (xy 40.437109 -318.450743) (xy 40.478705 -318.420522)
			(xy 40.524517 -318.397179) (xy 40.573416 -318.381291) (xy 40.624198 -318.373248) (xy 40.675614 -318.373248)
			(xy 40.726396 -318.381291) (xy 40.775295 -318.397179) (xy 40.821107 -318.420522) (xy 40.862703 -318.450743)
			(xy 40.899059 -318.487099) (xy 40.92928 -318.528695) (xy 40.952623 -318.574507) (xy 40.968511 -318.623406)
			(xy 40.976554 -318.674188) (xy 40.977058 -318.699896) (xy 41.294062 -318.699896) (xy 41.298022 -318.650842)
			(xy 41.309799 -318.603058) (xy 41.32909 -318.557782) (xy 41.355393 -318.516186) (xy 41.388028 -318.479349)
			(xy 41.426149 -318.448224) (xy 41.46877 -318.423617) (xy 41.514786 -318.406165) (xy 41.563005 -318.396321)
			(xy 41.61218 -318.39434) (xy 41.661035 -318.400272) (xy 41.708306 -318.413964) (xy 41.752768 -318.435062)
			(xy 41.793271 -318.463018) (xy 41.828764 -318.49711) (xy 41.858329 -318.536454) (xy 41.8812 -318.580031)
			(xy 41.896784 -318.626712) (xy 41.904679 -318.675289) (xy 41.905174 -318.699896) (xy 41.904679 -318.724503)
			(xy 41.9045 -318.725604) (xy 42.223178 -318.725604) (xy 42.223178 -318.674188) (xy 42.231221 -318.623406)
			(xy 42.247109 -318.574507) (xy 42.270452 -318.528695) (xy 42.300673 -318.487099) (xy 42.337029 -318.450743)
			(xy 42.378625 -318.420522) (xy 42.424437 -318.397179) (xy 42.473336 -318.381291) (xy 42.524118 -318.373248)
			(xy 42.575534 -318.373248) (xy 42.626316 -318.381291) (xy 42.675215 -318.397179) (xy 42.721027 -318.420522)
			(xy 42.762623 -318.450743) (xy 42.798979 -318.487099) (xy 42.8292 -318.528695) (xy 42.852543 -318.574507)
			(xy 42.868431 -318.623406) (xy 42.876474 -318.674188) (xy 42.876978 -318.699896) (xy 43.193982 -318.699896)
			(xy 43.197942 -318.650842) (xy 43.209719 -318.603058) (xy 43.22901 -318.557782) (xy 43.255313 -318.516186)
			(xy 43.287948 -318.479349) (xy 43.326069 -318.448224) (xy 43.36869 -318.423617) (xy 43.414706 -318.406165)
			(xy 43.462925 -318.396321) (xy 43.5121 -318.39434) (xy 43.560955 -318.400272) (xy 43.608226 -318.413964)
			(xy 43.652688 -318.435062) (xy 43.693191 -318.463018) (xy 43.728684 -318.49711) (xy 43.758249 -318.536454)
			(xy 43.78112 -318.580031) (xy 43.796704 -318.626712) (xy 43.804599 -318.675289) (xy 43.805094 -318.699896)
			(xy 43.804599 -318.724503) (xy 43.80442 -318.725604) (xy 44.123098 -318.725604) (xy 44.123098 -318.674188)
			(xy 44.131141 -318.623406) (xy 44.147029 -318.574507) (xy 44.170372 -318.528695) (xy 44.200593 -318.487099)
			(xy 44.236949 -318.450743) (xy 44.278545 -318.420522) (xy 44.324357 -318.397179) (xy 44.373256 -318.381291)
			(xy 44.424038 -318.373248) (xy 44.475454 -318.373248) (xy 44.526236 -318.381291) (xy 44.575135 -318.397179)
			(xy 44.620947 -318.420522) (xy 44.662543 -318.450743) (xy 44.698899 -318.487099) (xy 44.72912 -318.528695)
			(xy 44.752463 -318.574507) (xy 44.768351 -318.623406) (xy 44.776394 -318.674188) (xy 44.776898 -318.699896)
			(xy 45.094156 -318.699896) (xy 45.098116 -318.650842) (xy 45.109893 -318.603058) (xy 45.129184 -318.557782)
			(xy 45.155487 -318.516186) (xy 45.188122 -318.479349) (xy 45.226243 -318.448224) (xy 45.268864 -318.423617)
			(xy 45.31488 -318.406165) (xy 45.363099 -318.396321) (xy 45.412274 -318.39434) (xy 45.461129 -318.400272)
			(xy 45.5084 -318.413964) (xy 45.552862 -318.435062) (xy 45.593365 -318.463018) (xy 45.628858 -318.49711)
			(xy 45.658423 -318.536454) (xy 45.681294 -318.580031) (xy 45.696878 -318.626712) (xy 45.704773 -318.675289)
			(xy 45.705268 -318.699896) (xy 45.704773 -318.724503) (xy 45.704594 -318.725604) (xy 46.023272 -318.725604)
			(xy 46.023272 -318.674188) (xy 46.031315 -318.623406) (xy 46.047203 -318.574507) (xy 46.070546 -318.528695)
			(xy 46.100767 -318.487099) (xy 46.137123 -318.450743) (xy 46.178719 -318.420522) (xy 46.224531 -318.397179)
			(xy 46.27343 -318.381291) (xy 46.324212 -318.373248) (xy 46.375628 -318.373248) (xy 46.42641 -318.381291)
			(xy 46.475309 -318.397179) (xy 46.521121 -318.420522) (xy 46.562717 -318.450743) (xy 46.599073 -318.487099)
			(xy 46.629294 -318.528695) (xy 46.652637 -318.574507) (xy 46.668525 -318.623406) (xy 46.676568 -318.674188)
			(xy 46.677072 -318.699896) (xy 46.994076 -318.699896) (xy 46.998036 -318.650842) (xy 47.009813 -318.603058)
			(xy 47.029104 -318.557782) (xy 47.055407 -318.516186) (xy 47.088042 -318.479349) (xy 47.126163 -318.448224)
			(xy 47.168784 -318.423617) (xy 47.2148 -318.406165) (xy 47.263019 -318.396321) (xy 47.312194 -318.39434)
			(xy 47.361049 -318.400272) (xy 47.40832 -318.413964) (xy 47.452782 -318.435062) (xy 47.493285 -318.463018)
			(xy 47.528778 -318.49711) (xy 47.558343 -318.536454) (xy 47.581214 -318.580031) (xy 47.596798 -318.626712)
			(xy 47.604693 -318.675289) (xy 47.605188 -318.699896) (xy 47.604693 -318.724503) (xy 47.604514 -318.725604)
			(xy 47.923192 -318.725604) (xy 47.923192 -318.674188) (xy 47.931235 -318.623406) (xy 47.947123 -318.574507)
			(xy 47.970466 -318.528695) (xy 48.000687 -318.487099) (xy 48.037043 -318.450743) (xy 48.078639 -318.420522)
			(xy 48.124451 -318.397179) (xy 48.17335 -318.381291) (xy 48.224132 -318.373248) (xy 48.275548 -318.373248)
			(xy 48.32633 -318.381291) (xy 48.375229 -318.397179) (xy 48.421041 -318.420522) (xy 48.462637 -318.450743)
			(xy 48.498993 -318.487099) (xy 48.529214 -318.528695) (xy 48.552557 -318.574507) (xy 48.568445 -318.623406)
			(xy 48.576488 -318.674188) (xy 48.576992 -318.699896) (xy 48.893996 -318.699896) (xy 48.897956 -318.650842)
			(xy 48.909733 -318.603058) (xy 48.929024 -318.557782) (xy 48.955327 -318.516186) (xy 48.987962 -318.479349)
			(xy 49.026083 -318.448224) (xy 49.068704 -318.423617) (xy 49.11472 -318.406165) (xy 49.162939 -318.396321)
			(xy 49.212114 -318.39434) (xy 49.260969 -318.400272) (xy 49.30824 -318.413964) (xy 49.352702 -318.435062)
			(xy 49.393205 -318.463018) (xy 49.428698 -318.49711) (xy 49.458263 -318.536454) (xy 49.481134 -318.580031)
			(xy 49.496718 -318.626712) (xy 49.504613 -318.675289) (xy 49.505108 -318.699896) (xy 49.504613 -318.724503)
			(xy 49.504434 -318.725604) (xy 49.823112 -318.725604) (xy 49.823112 -318.674188) (xy 49.831155 -318.623406)
			(xy 49.847043 -318.574507) (xy 49.870386 -318.528695) (xy 49.900607 -318.487099) (xy 49.936963 -318.450743)
			(xy 49.978559 -318.420522) (xy 50.024371 -318.397179) (xy 50.07327 -318.381291) (xy 50.124052 -318.373248)
			(xy 50.175468 -318.373248) (xy 50.22625 -318.381291) (xy 50.275149 -318.397179) (xy 50.320961 -318.420522)
			(xy 50.362557 -318.450743) (xy 50.398913 -318.487099) (xy 50.429134 -318.528695) (xy 50.452477 -318.574507)
			(xy 50.468365 -318.623406) (xy 50.476408 -318.674188) (xy 50.476912 -318.699896) (xy 50.79417 -318.699896)
			(xy 50.79813 -318.650842) (xy 50.809907 -318.603058) (xy 50.829198 -318.557782) (xy 50.855501 -318.516186)
			(xy 50.888136 -318.479349) (xy 50.926257 -318.448224) (xy 50.968878 -318.423617) (xy 51.014894 -318.406165)
			(xy 51.063113 -318.396321) (xy 51.112288 -318.39434) (xy 51.161143 -318.400272) (xy 51.208414 -318.413964)
			(xy 51.252876 -318.435062) (xy 51.293379 -318.463018) (xy 51.328872 -318.49711) (xy 51.358437 -318.536454)
			(xy 51.381308 -318.580031) (xy 51.396892 -318.626712) (xy 51.404787 -318.675289) (xy 51.405282 -318.699896)
			(xy 51.404787 -318.724503) (xy 51.404608 -318.725604) (xy 51.723286 -318.725604) (xy 51.723286 -318.674188)
			(xy 51.731329 -318.623406) (xy 51.747217 -318.574507) (xy 51.77056 -318.528695) (xy 51.800781 -318.487099)
			(xy 51.837137 -318.450743) (xy 51.878733 -318.420522) (xy 51.924545 -318.397179) (xy 51.973444 -318.381291)
			(xy 52.024226 -318.373248) (xy 52.075642 -318.373248) (xy 52.126424 -318.381291) (xy 52.175323 -318.397179)
			(xy 52.221135 -318.420522) (xy 52.262731 -318.450743) (xy 52.299087 -318.487099) (xy 52.329308 -318.528695)
			(xy 52.352651 -318.574507) (xy 52.368539 -318.623406) (xy 52.376582 -318.674188) (xy 52.377086 -318.699896)
			(xy 52.69409 -318.699896) (xy 52.69805 -318.650842) (xy 52.709827 -318.603058) (xy 52.729118 -318.557782)
			(xy 52.755421 -318.516186) (xy 52.788056 -318.479349) (xy 52.826177 -318.448224) (xy 52.868798 -318.423617)
			(xy 52.914814 -318.406165) (xy 52.963033 -318.396321) (xy 53.012208 -318.39434) (xy 53.061063 -318.400272)
			(xy 53.108334 -318.413964) (xy 53.152796 -318.435062) (xy 53.193299 -318.463018) (xy 53.228792 -318.49711)
			(xy 53.258357 -318.536454) (xy 53.281228 -318.580031) (xy 53.296812 -318.626712) (xy 53.304707 -318.675289)
			(xy 53.305202 -318.699896) (xy 53.304707 -318.724503) (xy 53.304528 -318.725604) (xy 53.623206 -318.725604)
			(xy 53.623206 -318.674188) (xy 53.631249 -318.623406) (xy 53.647137 -318.574507) (xy 53.67048 -318.528695)
			(xy 53.700701 -318.487099) (xy 53.737057 -318.450743) (xy 53.778653 -318.420522) (xy 53.824465 -318.397179)
			(xy 53.873364 -318.381291) (xy 53.924146 -318.373248) (xy 53.975562 -318.373248) (xy 54.026344 -318.381291)
			(xy 54.075243 -318.397179) (xy 54.121055 -318.420522) (xy 54.162651 -318.450743) (xy 54.199007 -318.487099)
			(xy 54.229228 -318.528695) (xy 54.252571 -318.574507) (xy 54.268459 -318.623406) (xy 54.276502 -318.674188)
			(xy 54.277006 -318.699896) (xy 54.59401 -318.699896) (xy 54.59797 -318.650842) (xy 54.609747 -318.603058)
			(xy 54.629038 -318.557782) (xy 54.655341 -318.516186) (xy 54.687976 -318.479349) (xy 54.726097 -318.448224)
			(xy 54.768718 -318.423617) (xy 54.814734 -318.406165) (xy 54.862953 -318.396321) (xy 54.912128 -318.39434)
			(xy 54.960983 -318.400272) (xy 55.008254 -318.413964) (xy 55.052716 -318.435062) (xy 55.093219 -318.463018)
			(xy 55.128712 -318.49711) (xy 55.158277 -318.536454) (xy 55.181148 -318.580031) (xy 55.196732 -318.626712)
			(xy 55.204627 -318.675289) (xy 55.205122 -318.699896) (xy 55.204627 -318.724503) (xy 55.204448 -318.725604)
			(xy 55.523126 -318.725604) (xy 55.523126 -318.674188) (xy 55.531169 -318.623406) (xy 55.547057 -318.574507)
			(xy 55.5704 -318.528695) (xy 55.600621 -318.487099) (xy 55.636977 -318.450743) (xy 55.678573 -318.420522)
			(xy 55.724385 -318.397179) (xy 55.773284 -318.381291) (xy 55.824066 -318.373248) (xy 55.875482 -318.373248)
			(xy 55.926264 -318.381291) (xy 55.975163 -318.397179) (xy 56.020975 -318.420522) (xy 56.062571 -318.450743)
			(xy 56.098927 -318.487099) (xy 56.129148 -318.528695) (xy 56.152491 -318.574507) (xy 56.168379 -318.623406)
			(xy 56.176422 -318.674188) (xy 56.176926 -318.699896) (xy 56.494184 -318.699896) (xy 56.498144 -318.650842)
			(xy 56.509921 -318.603058) (xy 56.529212 -318.557782) (xy 56.555515 -318.516186) (xy 56.58815 -318.479349)
			(xy 56.626271 -318.448224) (xy 56.668892 -318.423617) (xy 56.714908 -318.406165) (xy 56.763127 -318.396321)
			(xy 56.812302 -318.39434) (xy 56.861157 -318.400272) (xy 56.908428 -318.413964) (xy 56.95289 -318.435062)
			(xy 56.993393 -318.463018) (xy 57.028886 -318.49711) (xy 57.058451 -318.536454) (xy 57.081322 -318.580031)
			(xy 57.096906 -318.626712) (xy 57.104801 -318.675289) (xy 57.105296 -318.699896) (xy 57.104801 -318.724503)
			(xy 57.104622 -318.725604) (xy 57.4233 -318.725604) (xy 57.4233 -318.674188) (xy 57.431343 -318.623406)
			(xy 57.447231 -318.574507) (xy 57.470574 -318.528695) (xy 57.500795 -318.487099) (xy 57.537151 -318.450743)
			(xy 57.578747 -318.420522) (xy 57.624559 -318.397179) (xy 57.673458 -318.381291) (xy 57.72424 -318.373248)
			(xy 57.775656 -318.373248) (xy 57.826438 -318.381291) (xy 57.875337 -318.397179) (xy 57.921149 -318.420522)
			(xy 57.962745 -318.450743) (xy 57.999101 -318.487099) (xy 58.029322 -318.528695) (xy 58.052665 -318.574507)
			(xy 58.068553 -318.623406) (xy 58.076596 -318.674188) (xy 58.0771 -318.699896) (xy 58.394104 -318.699896)
			(xy 58.398064 -318.650842) (xy 58.409841 -318.603058) (xy 58.429132 -318.557782) (xy 58.455435 -318.516186)
			(xy 58.48807 -318.479349) (xy 58.526191 -318.448224) (xy 58.568812 -318.423617) (xy 58.614828 -318.406165)
			(xy 58.663047 -318.396321) (xy 58.712222 -318.39434) (xy 58.761077 -318.400272) (xy 58.808348 -318.413964)
			(xy 58.85281 -318.435062) (xy 58.893313 -318.463018) (xy 58.928806 -318.49711) (xy 58.958371 -318.536454)
			(xy 58.981242 -318.580031) (xy 58.996826 -318.626712) (xy 59.004721 -318.675289) (xy 59.005216 -318.699896)
			(xy 59.004721 -318.724503) (xy 59.004542 -318.725604) (xy 59.32322 -318.725604) (xy 59.32322 -318.674188)
			(xy 59.331263 -318.623406) (xy 59.347151 -318.574507) (xy 59.370494 -318.528695) (xy 59.400715 -318.487099)
			(xy 59.437071 -318.450743) (xy 59.478667 -318.420522) (xy 59.524479 -318.397179) (xy 59.573378 -318.381291)
			(xy 59.62416 -318.373248) (xy 59.675576 -318.373248) (xy 59.726358 -318.381291) (xy 59.775257 -318.397179)
			(xy 59.821069 -318.420522) (xy 59.862665 -318.450743) (xy 59.899021 -318.487099) (xy 59.929242 -318.528695)
			(xy 59.952585 -318.574507) (xy 59.968473 -318.623406) (xy 59.976516 -318.674188) (xy 59.97702 -318.699896)
			(xy 60.294024 -318.699896) (xy 60.297984 -318.650842) (xy 60.309761 -318.603058) (xy 60.329052 -318.557782)
			(xy 60.355355 -318.516186) (xy 60.38799 -318.479349) (xy 60.426111 -318.448224) (xy 60.468732 -318.423617)
			(xy 60.514748 -318.406165) (xy 60.562967 -318.396321) (xy 60.612142 -318.39434) (xy 60.660997 -318.400272)
			(xy 60.708268 -318.413964) (xy 60.75273 -318.435062) (xy 60.793233 -318.463018) (xy 60.828726 -318.49711)
			(xy 60.858291 -318.536454) (xy 60.881162 -318.580031) (xy 60.896746 -318.626712) (xy 60.904641 -318.675289)
			(xy 60.905136 -318.699896) (xy 60.904641 -318.724503) (xy 60.904462 -318.725604) (xy 61.22314 -318.725604)
			(xy 61.22314 -318.674188) (xy 61.231183 -318.623406) (xy 61.247071 -318.574507) (xy 61.270414 -318.528695)
			(xy 61.300635 -318.487099) (xy 61.336991 -318.450743) (xy 61.378587 -318.420522) (xy 61.424399 -318.397179)
			(xy 61.473298 -318.381291) (xy 61.52408 -318.373248) (xy 61.575496 -318.373248) (xy 61.626278 -318.381291)
			(xy 61.675177 -318.397179) (xy 61.720989 -318.420522) (xy 61.762585 -318.450743) (xy 61.798941 -318.487099)
			(xy 61.829162 -318.528695) (xy 61.852505 -318.574507) (xy 61.868393 -318.623406) (xy 61.876436 -318.674188)
			(xy 61.87694 -318.699896) (xy 62.193944 -318.699896) (xy 62.197904 -318.650842) (xy 62.209681 -318.603058)
			(xy 62.228972 -318.557782) (xy 62.255275 -318.516186) (xy 62.28791 -318.479349) (xy 62.326031 -318.448224)
			(xy 62.368652 -318.423617) (xy 62.414668 -318.406165) (xy 62.462887 -318.396321) (xy 62.512062 -318.39434)
			(xy 62.560917 -318.400272) (xy 62.608188 -318.413964) (xy 62.65265 -318.435062) (xy 62.693153 -318.463018)
			(xy 62.728646 -318.49711) (xy 62.758211 -318.536454) (xy 62.781082 -318.580031) (xy 62.796666 -318.626712)
			(xy 62.804561 -318.675289) (xy 62.805056 -318.699896) (xy 62.804561 -318.724503) (xy 62.804382 -318.725604)
			(xy 63.123314 -318.725604) (xy 63.123314 -318.674188) (xy 63.131357 -318.623406) (xy 63.147245 -318.574507)
			(xy 63.170588 -318.528695) (xy 63.200809 -318.487099) (xy 63.237165 -318.450743) (xy 63.278761 -318.420522)
			(xy 63.324573 -318.397179) (xy 63.373472 -318.381291) (xy 63.424254 -318.373248) (xy 63.47567 -318.373248)
			(xy 63.526452 -318.381291) (xy 63.575351 -318.397179) (xy 63.621163 -318.420522) (xy 63.662759 -318.450743)
			(xy 63.699115 -318.487099) (xy 63.729336 -318.528695) (xy 63.752679 -318.574507) (xy 63.768567 -318.623406)
			(xy 63.77661 -318.674188) (xy 63.777114 -318.699896) (xy 64.094118 -318.699896) (xy 64.098078 -318.650842)
			(xy 64.109855 -318.603058) (xy 64.129146 -318.557782) (xy 64.155449 -318.516186) (xy 64.188084 -318.479349)
			(xy 64.226205 -318.448224) (xy 64.268826 -318.423617) (xy 64.314842 -318.406165) (xy 64.363061 -318.396321)
			(xy 64.412236 -318.39434) (xy 64.461091 -318.400272) (xy 64.508362 -318.413964) (xy 64.552824 -318.435062)
			(xy 64.593327 -318.463018) (xy 64.62882 -318.49711) (xy 64.658385 -318.536454) (xy 64.681256 -318.580031)
			(xy 64.69684 -318.626712) (xy 64.704735 -318.675289) (xy 64.70523 -318.699896) (xy 64.704735 -318.724503)
			(xy 64.704556 -318.725604) (xy 65.023234 -318.725604) (xy 65.023234 -318.674188) (xy 65.031277 -318.623406)
			(xy 65.047165 -318.574507) (xy 65.070508 -318.528695) (xy 65.100729 -318.487099) (xy 65.137085 -318.450743)
			(xy 65.178681 -318.420522) (xy 65.224493 -318.397179) (xy 65.273392 -318.381291) (xy 65.324174 -318.373248)
			(xy 65.37559 -318.373248) (xy 65.426372 -318.381291) (xy 65.475271 -318.397179) (xy 65.521083 -318.420522)
			(xy 65.562679 -318.450743) (xy 65.599035 -318.487099) (xy 65.629256 -318.528695) (xy 65.652599 -318.574507)
			(xy 65.668487 -318.623406) (xy 65.67653 -318.674188) (xy 65.677034 -318.699896) (xy 65.994038 -318.699896)
			(xy 65.997998 -318.650842) (xy 66.009775 -318.603058) (xy 66.029066 -318.557782) (xy 66.055369 -318.516186)
			(xy 66.088004 -318.479349) (xy 66.126125 -318.448224) (xy 66.168746 -318.423617) (xy 66.214762 -318.406165)
			(xy 66.262981 -318.396321) (xy 66.312156 -318.39434) (xy 66.361011 -318.400272) (xy 66.408282 -318.413964)
			(xy 66.452744 -318.435062) (xy 66.493247 -318.463018) (xy 66.52874 -318.49711) (xy 66.558305 -318.536454)
			(xy 66.581176 -318.580031) (xy 66.59676 -318.626712) (xy 66.604655 -318.675289) (xy 66.60515 -318.699896)
			(xy 66.604655 -318.724503) (xy 66.604476 -318.725604) (xy 66.923154 -318.725604) (xy 66.923154 -318.674188)
			(xy 66.931197 -318.623406) (xy 66.947085 -318.574507) (xy 66.970428 -318.528695) (xy 67.000649 -318.487099)
			(xy 67.037005 -318.450743) (xy 67.078601 -318.420522) (xy 67.124413 -318.397179) (xy 67.173312 -318.381291)
			(xy 67.224094 -318.373248) (xy 67.27551 -318.373248) (xy 67.326292 -318.381291) (xy 67.375191 -318.397179)
			(xy 67.421003 -318.420522) (xy 67.462599 -318.450743) (xy 67.498955 -318.487099) (xy 67.529176 -318.528695)
			(xy 67.552519 -318.574507) (xy 67.568407 -318.623406) (xy 67.57645 -318.674188) (xy 67.576954 -318.699896)
			(xy 67.893958 -318.699896) (xy 67.897918 -318.650842) (xy 67.909695 -318.603058) (xy 67.928986 -318.557782)
			(xy 67.955289 -318.516186) (xy 67.987924 -318.479349) (xy 68.026045 -318.448224) (xy 68.068666 -318.423617)
			(xy 68.114682 -318.406165) (xy 68.162901 -318.396321) (xy 68.212076 -318.39434) (xy 68.260931 -318.400272)
			(xy 68.308202 -318.413964) (xy 68.352664 -318.435062) (xy 68.393167 -318.463018) (xy 68.42866 -318.49711)
			(xy 68.458225 -318.536454) (xy 68.481096 -318.580031) (xy 68.49668 -318.626712) (xy 68.504575 -318.675289)
			(xy 68.50507 -318.699896) (xy 68.504575 -318.724503) (xy 68.504396 -318.725604) (xy 68.823328 -318.725604)
			(xy 68.823328 -318.674188) (xy 68.831371 -318.623406) (xy 68.847259 -318.574507) (xy 68.870602 -318.528695)
			(xy 68.900823 -318.487099) (xy 68.937179 -318.450743) (xy 68.978775 -318.420522) (xy 69.024587 -318.397179)
			(xy 69.073486 -318.381291) (xy 69.124268 -318.373248) (xy 69.175684 -318.373248) (xy 69.226466 -318.381291)
			(xy 69.275365 -318.397179) (xy 69.321177 -318.420522) (xy 69.362773 -318.450743) (xy 69.399129 -318.487099)
			(xy 69.42935 -318.528695) (xy 69.452693 -318.574507) (xy 69.468581 -318.623406) (xy 69.476624 -318.674188)
			(xy 69.477128 -318.699896) (xy 69.794132 -318.699896) (xy 69.798092 -318.650842) (xy 69.809869 -318.603058)
			(xy 69.82916 -318.557782) (xy 69.855463 -318.516186) (xy 69.888098 -318.479349) (xy 69.926219 -318.448224)
			(xy 69.96884 -318.423617) (xy 70.014856 -318.406165) (xy 70.063075 -318.396321) (xy 70.11225 -318.39434)
			(xy 70.161105 -318.400272) (xy 70.208376 -318.413964) (xy 70.252838 -318.435062) (xy 70.293341 -318.463018)
			(xy 70.328834 -318.49711) (xy 70.358399 -318.536454) (xy 70.38127 -318.580031) (xy 70.396854 -318.626712)
			(xy 70.404749 -318.675289) (xy 70.405244 -318.699896) (xy 70.404749 -318.724503) (xy 70.40457 -318.725604)
			(xy 70.723248 -318.725604) (xy 70.723248 -318.674188) (xy 70.731291 -318.623406) (xy 70.747179 -318.574507)
			(xy 70.770522 -318.528695) (xy 70.800743 -318.487099) (xy 70.837099 -318.450743) (xy 70.878695 -318.420522)
			(xy 70.924507 -318.397179) (xy 70.973406 -318.381291) (xy 71.024188 -318.373248) (xy 71.075604 -318.373248)
			(xy 71.126386 -318.381291) (xy 71.175285 -318.397179) (xy 71.221097 -318.420522) (xy 71.262693 -318.450743)
			(xy 71.299049 -318.487099) (xy 71.32927 -318.528695) (xy 71.352613 -318.574507) (xy 71.368501 -318.623406)
			(xy 71.376544 -318.674188) (xy 71.377048 -318.699896) (xy 71.376544 -318.725604) (xy 71.368501 -318.776386)
			(xy 71.352613 -318.825285) (xy 71.32927 -318.871097) (xy 71.299049 -318.912693) (xy 71.262693 -318.949049)
			(xy 71.221097 -318.97927) (xy 71.175285 -319.002613) (xy 71.126386 -319.018501) (xy 71.075604 -319.026544)
			(xy 71.024188 -319.026544) (xy 70.973406 -319.018501) (xy 70.924507 -319.002613) (xy 70.878695 -318.97927)
			(xy 70.837099 -318.949049) (xy 70.800743 -318.912693) (xy 70.770522 -318.871097) (xy 70.747179 -318.825285)
			(xy 70.731291 -318.776386) (xy 70.723248 -318.725604) (xy 70.40457 -318.725604) (xy 70.396854 -318.77308)
			(xy 70.38127 -318.819761) (xy 70.358399 -318.863338) (xy 70.328834 -318.902682) (xy 70.293341 -318.936774)
			(xy 70.252838 -318.96473) (xy 70.208376 -318.985828) (xy 70.161105 -318.99952) (xy 70.11225 -319.005452)
			(xy 70.063075 -319.003471) (xy 70.014856 -318.993627) (xy 69.96884 -318.976175) (xy 69.926219 -318.951568)
			(xy 69.888098 -318.920443) (xy 69.855463 -318.883606) (xy 69.82916 -318.84201) (xy 69.809869 -318.796734)
			(xy 69.798092 -318.74895) (xy 69.794132 -318.699896) (xy 69.477128 -318.699896) (xy 69.476624 -318.725604)
			(xy 69.468581 -318.776386) (xy 69.452693 -318.825285) (xy 69.42935 -318.871097) (xy 69.399129 -318.912693)
			(xy 69.362773 -318.949049) (xy 69.321177 -318.97927) (xy 69.275365 -319.002613) (xy 69.226466 -319.018501)
			(xy 69.175684 -319.026544) (xy 69.124268 -319.026544) (xy 69.073486 -319.018501) (xy 69.024587 -319.002613)
			(xy 68.978775 -318.97927) (xy 68.937179 -318.949049) (xy 68.900823 -318.912693) (xy 68.870602 -318.871097)
			(xy 68.847259 -318.825285) (xy 68.831371 -318.776386) (xy 68.823328 -318.725604) (xy 68.504396 -318.725604)
			(xy 68.49668 -318.77308) (xy 68.481096 -318.819761) (xy 68.458225 -318.863338) (xy 68.42866 -318.902682)
			(xy 68.393167 -318.936774) (xy 68.352664 -318.96473) (xy 68.308202 -318.985828) (xy 68.260931 -318.99952)
			(xy 68.212076 -319.005452) (xy 68.162901 -319.003471) (xy 68.114682 -318.993627) (xy 68.068666 -318.976175)
			(xy 68.026045 -318.951568) (xy 67.987924 -318.920443) (xy 67.955289 -318.883606) (xy 67.928986 -318.84201)
			(xy 67.909695 -318.796734) (xy 67.897918 -318.74895) (xy 67.893958 -318.699896) (xy 67.576954 -318.699896)
			(xy 67.57645 -318.725604) (xy 67.568407 -318.776386) (xy 67.552519 -318.825285) (xy 67.529176 -318.871097)
			(xy 67.498955 -318.912693) (xy 67.462599 -318.949049) (xy 67.421003 -318.97927) (xy 67.375191 -319.002613)
			(xy 67.326292 -319.018501) (xy 67.27551 -319.026544) (xy 67.224094 -319.026544) (xy 67.173312 -319.018501)
			(xy 67.124413 -319.002613) (xy 67.078601 -318.97927) (xy 67.037005 -318.949049) (xy 67.000649 -318.912693)
			(xy 66.970428 -318.871097) (xy 66.947085 -318.825285) (xy 66.931197 -318.776386) (xy 66.923154 -318.725604)
			(xy 66.604476 -318.725604) (xy 66.59676 -318.77308) (xy 66.581176 -318.819761) (xy 66.558305 -318.863338)
			(xy 66.52874 -318.902682) (xy 66.493247 -318.936774) (xy 66.452744 -318.96473) (xy 66.408282 -318.985828)
			(xy 66.361011 -318.99952) (xy 66.312156 -319.005452) (xy 66.262981 -319.003471) (xy 66.214762 -318.993627)
			(xy 66.168746 -318.976175) (xy 66.126125 -318.951568) (xy 66.088004 -318.920443) (xy 66.055369 -318.883606)
			(xy 66.029066 -318.84201) (xy 66.009775 -318.796734) (xy 65.997998 -318.74895) (xy 65.994038 -318.699896)
			(xy 65.677034 -318.699896) (xy 65.67653 -318.725604) (xy 65.668487 -318.776386) (xy 65.652599 -318.825285)
			(xy 65.629256 -318.871097) (xy 65.599035 -318.912693) (xy 65.562679 -318.949049) (xy 65.521083 -318.97927)
			(xy 65.475271 -319.002613) (xy 65.426372 -319.018501) (xy 65.37559 -319.026544) (xy 65.324174 -319.026544)
			(xy 65.273392 -319.018501) (xy 65.224493 -319.002613) (xy 65.178681 -318.97927) (xy 65.137085 -318.949049)
			(xy 65.100729 -318.912693) (xy 65.070508 -318.871097) (xy 65.047165 -318.825285) (xy 65.031277 -318.776386)
			(xy 65.023234 -318.725604) (xy 64.704556 -318.725604) (xy 64.69684 -318.77308) (xy 64.681256 -318.819761)
			(xy 64.658385 -318.863338) (xy 64.62882 -318.902682) (xy 64.593327 -318.936774) (xy 64.552824 -318.96473)
			(xy 64.508362 -318.985828) (xy 64.461091 -318.99952) (xy 64.412236 -319.005452) (xy 64.363061 -319.003471)
			(xy 64.314842 -318.993627) (xy 64.268826 -318.976175) (xy 64.226205 -318.951568) (xy 64.188084 -318.920443)
			(xy 64.155449 -318.883606) (xy 64.129146 -318.84201) (xy 64.109855 -318.796734) (xy 64.098078 -318.74895)
			(xy 64.094118 -318.699896) (xy 63.777114 -318.699896) (xy 63.77661 -318.725604) (xy 63.768567 -318.776386)
			(xy 63.752679 -318.825285) (xy 63.729336 -318.871097) (xy 63.699115 -318.912693) (xy 63.662759 -318.949049)
			(xy 63.621163 -318.97927) (xy 63.575351 -319.002613) (xy 63.526452 -319.018501) (xy 63.47567 -319.026544)
			(xy 63.424254 -319.026544) (xy 63.373472 -319.018501) (xy 63.324573 -319.002613) (xy 63.278761 -318.97927)
			(xy 63.237165 -318.949049) (xy 63.200809 -318.912693) (xy 63.170588 -318.871097) (xy 63.147245 -318.825285)
			(xy 63.131357 -318.776386) (xy 63.123314 -318.725604) (xy 62.804382 -318.725604) (xy 62.796666 -318.77308)
			(xy 62.781082 -318.819761) (xy 62.758211 -318.863338) (xy 62.728646 -318.902682) (xy 62.693153 -318.936774)
			(xy 62.65265 -318.96473) (xy 62.608188 -318.985828) (xy 62.560917 -318.99952) (xy 62.512062 -319.005452)
			(xy 62.462887 -319.003471) (xy 62.414668 -318.993627) (xy 62.368652 -318.976175) (xy 62.326031 -318.951568)
			(xy 62.28791 -318.920443) (xy 62.255275 -318.883606) (xy 62.228972 -318.84201) (xy 62.209681 -318.796734)
			(xy 62.197904 -318.74895) (xy 62.193944 -318.699896) (xy 61.87694 -318.699896) (xy 61.876436 -318.725604)
			(xy 61.868393 -318.776386) (xy 61.852505 -318.825285) (xy 61.829162 -318.871097) (xy 61.798941 -318.912693)
			(xy 61.762585 -318.949049) (xy 61.720989 -318.97927) (xy 61.675177 -319.002613) (xy 61.626278 -319.018501)
			(xy 61.575496 -319.026544) (xy 61.52408 -319.026544) (xy 61.473298 -319.018501) (xy 61.424399 -319.002613)
			(xy 61.378587 -318.97927) (xy 61.336991 -318.949049) (xy 61.300635 -318.912693) (xy 61.270414 -318.871097)
			(xy 61.247071 -318.825285) (xy 61.231183 -318.776386) (xy 61.22314 -318.725604) (xy 60.904462 -318.725604)
			(xy 60.896746 -318.77308) (xy 60.881162 -318.819761) (xy 60.858291 -318.863338) (xy 60.828726 -318.902682)
			(xy 60.793233 -318.936774) (xy 60.75273 -318.96473) (xy 60.708268 -318.985828) (xy 60.660997 -318.99952)
			(xy 60.612142 -319.005452) (xy 60.562967 -319.003471) (xy 60.514748 -318.993627) (xy 60.468732 -318.976175)
			(xy 60.426111 -318.951568) (xy 60.38799 -318.920443) (xy 60.355355 -318.883606) (xy 60.329052 -318.84201)
			(xy 60.309761 -318.796734) (xy 60.297984 -318.74895) (xy 60.294024 -318.699896) (xy 59.97702 -318.699896)
			(xy 59.976516 -318.725604) (xy 59.968473 -318.776386) (xy 59.952585 -318.825285) (xy 59.929242 -318.871097)
			(xy 59.899021 -318.912693) (xy 59.862665 -318.949049) (xy 59.821069 -318.97927) (xy 59.775257 -319.002613)
			(xy 59.726358 -319.018501) (xy 59.675576 -319.026544) (xy 59.62416 -319.026544) (xy 59.573378 -319.018501)
			(xy 59.524479 -319.002613) (xy 59.478667 -318.97927) (xy 59.437071 -318.949049) (xy 59.400715 -318.912693)
			(xy 59.370494 -318.871097) (xy 59.347151 -318.825285) (xy 59.331263 -318.776386) (xy 59.32322 -318.725604)
			(xy 59.004542 -318.725604) (xy 58.996826 -318.77308) (xy 58.981242 -318.819761) (xy 58.958371 -318.863338)
			(xy 58.928806 -318.902682) (xy 58.893313 -318.936774) (xy 58.85281 -318.96473) (xy 58.808348 -318.985828)
			(xy 58.761077 -318.99952) (xy 58.712222 -319.005452) (xy 58.663047 -319.003471) (xy 58.614828 -318.993627)
			(xy 58.568812 -318.976175) (xy 58.526191 -318.951568) (xy 58.48807 -318.920443) (xy 58.455435 -318.883606)
			(xy 58.429132 -318.84201) (xy 58.409841 -318.796734) (xy 58.398064 -318.74895) (xy 58.394104 -318.699896)
			(xy 58.0771 -318.699896) (xy 58.076596 -318.725604) (xy 58.068553 -318.776386) (xy 58.052665 -318.825285)
			(xy 58.029322 -318.871097) (xy 57.999101 -318.912693) (xy 57.962745 -318.949049) (xy 57.921149 -318.97927)
			(xy 57.875337 -319.002613) (xy 57.826438 -319.018501) (xy 57.775656 -319.026544) (xy 57.72424 -319.026544)
			(xy 57.673458 -319.018501) (xy 57.624559 -319.002613) (xy 57.578747 -318.97927) (xy 57.537151 -318.949049)
			(xy 57.500795 -318.912693) (xy 57.470574 -318.871097) (xy 57.447231 -318.825285) (xy 57.431343 -318.776386)
			(xy 57.4233 -318.725604) (xy 57.104622 -318.725604) (xy 57.096906 -318.77308) (xy 57.081322 -318.819761)
			(xy 57.058451 -318.863338) (xy 57.028886 -318.902682) (xy 56.993393 -318.936774) (xy 56.95289 -318.96473)
			(xy 56.908428 -318.985828) (xy 56.861157 -318.99952) (xy 56.812302 -319.005452) (xy 56.763127 -319.003471)
			(xy 56.714908 -318.993627) (xy 56.668892 -318.976175) (xy 56.626271 -318.951568) (xy 56.58815 -318.920443)
			(xy 56.555515 -318.883606) (xy 56.529212 -318.84201) (xy 56.509921 -318.796734) (xy 56.498144 -318.74895)
			(xy 56.494184 -318.699896) (xy 56.176926 -318.699896) (xy 56.176422 -318.725604) (xy 56.168379 -318.776386)
			(xy 56.152491 -318.825285) (xy 56.129148 -318.871097) (xy 56.098927 -318.912693) (xy 56.062571 -318.949049)
			(xy 56.020975 -318.97927) (xy 55.975163 -319.002613) (xy 55.926264 -319.018501) (xy 55.875482 -319.026544)
			(xy 55.824066 -319.026544) (xy 55.773284 -319.018501) (xy 55.724385 -319.002613) (xy 55.678573 -318.97927)
			(xy 55.636977 -318.949049) (xy 55.600621 -318.912693) (xy 55.5704 -318.871097) (xy 55.547057 -318.825285)
			(xy 55.531169 -318.776386) (xy 55.523126 -318.725604) (xy 55.204448 -318.725604) (xy 55.196732 -318.77308)
			(xy 55.181148 -318.819761) (xy 55.158277 -318.863338) (xy 55.128712 -318.902682) (xy 55.093219 -318.936774)
			(xy 55.052716 -318.96473) (xy 55.008254 -318.985828) (xy 54.960983 -318.99952) (xy 54.912128 -319.005452)
			(xy 54.862953 -319.003471) (xy 54.814734 -318.993627) (xy 54.768718 -318.976175) (xy 54.726097 -318.951568)
			(xy 54.687976 -318.920443) (xy 54.655341 -318.883606) (xy 54.629038 -318.84201) (xy 54.609747 -318.796734)
			(xy 54.59797 -318.74895) (xy 54.59401 -318.699896) (xy 54.277006 -318.699896) (xy 54.276502 -318.725604)
			(xy 54.268459 -318.776386) (xy 54.252571 -318.825285) (xy 54.229228 -318.871097) (xy 54.199007 -318.912693)
			(xy 54.162651 -318.949049) (xy 54.121055 -318.97927) (xy 54.075243 -319.002613) (xy 54.026344 -319.018501)
			(xy 53.975562 -319.026544) (xy 53.924146 -319.026544) (xy 53.873364 -319.018501) (xy 53.824465 -319.002613)
			(xy 53.778653 -318.97927) (xy 53.737057 -318.949049) (xy 53.700701 -318.912693) (xy 53.67048 -318.871097)
			(xy 53.647137 -318.825285) (xy 53.631249 -318.776386) (xy 53.623206 -318.725604) (xy 53.304528 -318.725604)
			(xy 53.296812 -318.77308) (xy 53.281228 -318.819761) (xy 53.258357 -318.863338) (xy 53.228792 -318.902682)
			(xy 53.193299 -318.936774) (xy 53.152796 -318.96473) (xy 53.108334 -318.985828) (xy 53.061063 -318.99952)
			(xy 53.012208 -319.005452) (xy 52.963033 -319.003471) (xy 52.914814 -318.993627) (xy 52.868798 -318.976175)
			(xy 52.826177 -318.951568) (xy 52.788056 -318.920443) (xy 52.755421 -318.883606) (xy 52.729118 -318.84201)
			(xy 52.709827 -318.796734) (xy 52.69805 -318.74895) (xy 52.69409 -318.699896) (xy 52.377086 -318.699896)
			(xy 52.376582 -318.725604) (xy 52.368539 -318.776386) (xy 52.352651 -318.825285) (xy 52.329308 -318.871097)
			(xy 52.299087 -318.912693) (xy 52.262731 -318.949049) (xy 52.221135 -318.97927) (xy 52.175323 -319.002613)
			(xy 52.126424 -319.018501) (xy 52.075642 -319.026544) (xy 52.024226 -319.026544) (xy 51.973444 -319.018501)
			(xy 51.924545 -319.002613) (xy 51.878733 -318.97927) (xy 51.837137 -318.949049) (xy 51.800781 -318.912693)
			(xy 51.77056 -318.871097) (xy 51.747217 -318.825285) (xy 51.731329 -318.776386) (xy 51.723286 -318.725604)
			(xy 51.404608 -318.725604) (xy 51.396892 -318.77308) (xy 51.381308 -318.819761) (xy 51.358437 -318.863338)
			(xy 51.328872 -318.902682) (xy 51.293379 -318.936774) (xy 51.252876 -318.96473) (xy 51.208414 -318.985828)
			(xy 51.161143 -318.99952) (xy 51.112288 -319.005452) (xy 51.063113 -319.003471) (xy 51.014894 -318.993627)
			(xy 50.968878 -318.976175) (xy 50.926257 -318.951568) (xy 50.888136 -318.920443) (xy 50.855501 -318.883606)
			(xy 50.829198 -318.84201) (xy 50.809907 -318.796734) (xy 50.79813 -318.74895) (xy 50.79417 -318.699896)
			(xy 50.476912 -318.699896) (xy 50.476408 -318.725604) (xy 50.468365 -318.776386) (xy 50.452477 -318.825285)
			(xy 50.429134 -318.871097) (xy 50.398913 -318.912693) (xy 50.362557 -318.949049) (xy 50.320961 -318.97927)
			(xy 50.275149 -319.002613) (xy 50.22625 -319.018501) (xy 50.175468 -319.026544) (xy 50.124052 -319.026544)
			(xy 50.07327 -319.018501) (xy 50.024371 -319.002613) (xy 49.978559 -318.97927) (xy 49.936963 -318.949049)
			(xy 49.900607 -318.912693) (xy 49.870386 -318.871097) (xy 49.847043 -318.825285) (xy 49.831155 -318.776386)
			(xy 49.823112 -318.725604) (xy 49.504434 -318.725604) (xy 49.496718 -318.77308) (xy 49.481134 -318.819761)
			(xy 49.458263 -318.863338) (xy 49.428698 -318.902682) (xy 49.393205 -318.936774) (xy 49.352702 -318.96473)
			(xy 49.30824 -318.985828) (xy 49.260969 -318.99952) (xy 49.212114 -319.005452) (xy 49.162939 -319.003471)
			(xy 49.11472 -318.993627) (xy 49.068704 -318.976175) (xy 49.026083 -318.951568) (xy 48.987962 -318.920443)
			(xy 48.955327 -318.883606) (xy 48.929024 -318.84201) (xy 48.909733 -318.796734) (xy 48.897956 -318.74895)
			(xy 48.893996 -318.699896) (xy 48.576992 -318.699896) (xy 48.576488 -318.725604) (xy 48.568445 -318.776386)
			(xy 48.552557 -318.825285) (xy 48.529214 -318.871097) (xy 48.498993 -318.912693) (xy 48.462637 -318.949049)
			(xy 48.421041 -318.97927) (xy 48.375229 -319.002613) (xy 48.32633 -319.018501) (xy 48.275548 -319.026544)
			(xy 48.224132 -319.026544) (xy 48.17335 -319.018501) (xy 48.124451 -319.002613) (xy 48.078639 -318.97927)
			(xy 48.037043 -318.949049) (xy 48.000687 -318.912693) (xy 47.970466 -318.871097) (xy 47.947123 -318.825285)
			(xy 47.931235 -318.776386) (xy 47.923192 -318.725604) (xy 47.604514 -318.725604) (xy 47.596798 -318.77308)
			(xy 47.581214 -318.819761) (xy 47.558343 -318.863338) (xy 47.528778 -318.902682) (xy 47.493285 -318.936774)
			(xy 47.452782 -318.96473) (xy 47.40832 -318.985828) (xy 47.361049 -318.99952) (xy 47.312194 -319.005452)
			(xy 47.263019 -319.003471) (xy 47.2148 -318.993627) (xy 47.168784 -318.976175) (xy 47.126163 -318.951568)
			(xy 47.088042 -318.920443) (xy 47.055407 -318.883606) (xy 47.029104 -318.84201) (xy 47.009813 -318.796734)
			(xy 46.998036 -318.74895) (xy 46.994076 -318.699896) (xy 46.677072 -318.699896) (xy 46.676568 -318.725604)
			(xy 46.668525 -318.776386) (xy 46.652637 -318.825285) (xy 46.629294 -318.871097) (xy 46.599073 -318.912693)
			(xy 46.562717 -318.949049) (xy 46.521121 -318.97927) (xy 46.475309 -319.002613) (xy 46.42641 -319.018501)
			(xy 46.375628 -319.026544) (xy 46.324212 -319.026544) (xy 46.27343 -319.018501) (xy 46.224531 -319.002613)
			(xy 46.178719 -318.97927) (xy 46.137123 -318.949049) (xy 46.100767 -318.912693) (xy 46.070546 -318.871097)
			(xy 46.047203 -318.825285) (xy 46.031315 -318.776386) (xy 46.023272 -318.725604) (xy 45.704594 -318.725604)
			(xy 45.696878 -318.77308) (xy 45.681294 -318.819761) (xy 45.658423 -318.863338) (xy 45.628858 -318.902682)
			(xy 45.593365 -318.936774) (xy 45.552862 -318.96473) (xy 45.5084 -318.985828) (xy 45.461129 -318.99952)
			(xy 45.412274 -319.005452) (xy 45.363099 -319.003471) (xy 45.31488 -318.993627) (xy 45.268864 -318.976175)
			(xy 45.226243 -318.951568) (xy 45.188122 -318.920443) (xy 45.155487 -318.883606) (xy 45.129184 -318.84201)
			(xy 45.109893 -318.796734) (xy 45.098116 -318.74895) (xy 45.094156 -318.699896) (xy 44.776898 -318.699896)
			(xy 44.776394 -318.725604) (xy 44.768351 -318.776386) (xy 44.752463 -318.825285) (xy 44.72912 -318.871097)
			(xy 44.698899 -318.912693) (xy 44.662543 -318.949049) (xy 44.620947 -318.97927) (xy 44.575135 -319.002613)
			(xy 44.526236 -319.018501) (xy 44.475454 -319.026544) (xy 44.424038 -319.026544) (xy 44.373256 -319.018501)
			(xy 44.324357 -319.002613) (xy 44.278545 -318.97927) (xy 44.236949 -318.949049) (xy 44.200593 -318.912693)
			(xy 44.170372 -318.871097) (xy 44.147029 -318.825285) (xy 44.131141 -318.776386) (xy 44.123098 -318.725604)
			(xy 43.80442 -318.725604) (xy 43.796704 -318.77308) (xy 43.78112 -318.819761) (xy 43.758249 -318.863338)
			(xy 43.728684 -318.902682) (xy 43.693191 -318.936774) (xy 43.652688 -318.96473) (xy 43.608226 -318.985828)
			(xy 43.560955 -318.99952) (xy 43.5121 -319.005452) (xy 43.462925 -319.003471) (xy 43.414706 -318.993627)
			(xy 43.36869 -318.976175) (xy 43.326069 -318.951568) (xy 43.287948 -318.920443) (xy 43.255313 -318.883606)
			(xy 43.22901 -318.84201) (xy 43.209719 -318.796734) (xy 43.197942 -318.74895) (xy 43.193982 -318.699896)
			(xy 42.876978 -318.699896) (xy 42.876474 -318.725604) (xy 42.868431 -318.776386) (xy 42.852543 -318.825285)
			(xy 42.8292 -318.871097) (xy 42.798979 -318.912693) (xy 42.762623 -318.949049) (xy 42.721027 -318.97927)
			(xy 42.675215 -319.002613) (xy 42.626316 -319.018501) (xy 42.575534 -319.026544) (xy 42.524118 -319.026544)
			(xy 42.473336 -319.018501) (xy 42.424437 -319.002613) (xy 42.378625 -318.97927) (xy 42.337029 -318.949049)
			(xy 42.300673 -318.912693) (xy 42.270452 -318.871097) (xy 42.247109 -318.825285) (xy 42.231221 -318.776386)
			(xy 42.223178 -318.725604) (xy 41.9045 -318.725604) (xy 41.896784 -318.77308) (xy 41.8812 -318.819761)
			(xy 41.858329 -318.863338) (xy 41.828764 -318.902682) (xy 41.793271 -318.936774) (xy 41.752768 -318.96473)
			(xy 41.708306 -318.985828) (xy 41.661035 -318.99952) (xy 41.61218 -319.005452) (xy 41.563005 -319.003471)
			(xy 41.514786 -318.993627) (xy 41.46877 -318.976175) (xy 41.426149 -318.951568) (xy 41.388028 -318.920443)
			(xy 41.355393 -318.883606) (xy 41.32909 -318.84201) (xy 41.309799 -318.796734) (xy 41.298022 -318.74895)
			(xy 41.294062 -318.699896) (xy 40.977058 -318.699896) (xy 40.976554 -318.725604) (xy 40.968511 -318.776386)
			(xy 40.952623 -318.825285) (xy 40.92928 -318.871097) (xy 40.899059 -318.912693) (xy 40.862703 -318.949049)
			(xy 40.821107 -318.97927) (xy 40.775295 -319.002613) (xy 40.726396 -319.018501) (xy 40.675614 -319.026544)
			(xy 40.624198 -319.026544) (xy 40.573416 -319.018501) (xy 40.524517 -319.002613) (xy 40.478705 -318.97927)
			(xy 40.437109 -318.949049) (xy 40.400753 -318.912693) (xy 40.370532 -318.871097) (xy 40.347189 -318.825285)
			(xy 40.331301 -318.776386) (xy 40.323258 -318.725604) (xy 40.00458 -318.725604) (xy 39.996864 -318.77308)
			(xy 39.98128 -318.819761) (xy 39.958409 -318.863338) (xy 39.928844 -318.902682) (xy 39.893351 -318.936774)
			(xy 39.852848 -318.96473) (xy 39.808386 -318.985828) (xy 39.761115 -318.99952) (xy 39.71226 -319.005452)
			(xy 39.663085 -319.003471) (xy 39.614866 -318.993627) (xy 39.56885 -318.976175) (xy 39.526229 -318.951568)
			(xy 39.488108 -318.920443) (xy 39.455473 -318.883606) (xy 39.42917 -318.84201) (xy 39.409879 -318.796734)
			(xy 39.398102 -318.74895) (xy 39.394142 -318.699896) (xy 39.077138 -318.699896) (xy 39.076634 -318.725604)
			(xy 39.068591 -318.776386) (xy 39.052703 -318.825285) (xy 39.02936 -318.871097) (xy 38.999139 -318.912693)
			(xy 38.962783 -318.949049) (xy 38.921187 -318.97927) (xy 38.875375 -319.002613) (xy 38.826476 -319.018501)
			(xy 38.775694 -319.026544) (xy 38.724278 -319.026544) (xy 38.673496 -319.018501) (xy 38.624597 -319.002613)
			(xy 38.578785 -318.97927) (xy 38.537189 -318.949049) (xy 38.500833 -318.912693) (xy 38.470612 -318.871097)
			(xy 38.447269 -318.825285) (xy 38.431381 -318.776386) (xy 38.423338 -318.725604) (xy 38.104406 -318.725604)
			(xy 38.09669 -318.77308) (xy 38.081106 -318.819761) (xy 38.058235 -318.863338) (xy 38.02867 -318.902682)
			(xy 37.993177 -318.936774) (xy 37.952674 -318.96473) (xy 37.908212 -318.985828) (xy 37.860941 -318.99952)
			(xy 37.812086 -319.005452) (xy 37.762911 -319.003471) (xy 37.714692 -318.993627) (xy 37.668676 -318.976175)
			(xy 37.626055 -318.951568) (xy 37.587934 -318.920443) (xy 37.555299 -318.883606) (xy 37.528996 -318.84201)
			(xy 37.509705 -318.796734) (xy 37.497928 -318.74895) (xy 37.493968 -318.699896) (xy 33.888434 -318.699896)
			(xy 33.909945 -318.740263) (xy 33.994494 -318.915831) (xy 34.071811 -319.094702) (xy 34.141769 -319.276577)
			(xy 34.204249 -319.461154) (xy 34.259149 -319.648126) (xy 34.259645 -319.65011) (xy 38.444182 -319.65011)
			(xy 38.448142 -319.601056) (xy 38.459919 -319.553272) (xy 38.47921 -319.507996) (xy 38.505513 -319.4664)
			(xy 38.538148 -319.429563) (xy 38.576269 -319.398438) (xy 38.61889 -319.373831) (xy 38.664906 -319.356379)
			(xy 38.713125 -319.346535) (xy 38.7623 -319.344554) (xy 38.811155 -319.350486) (xy 38.858426 -319.364178)
			(xy 38.902888 -319.385276) (xy 38.943391 -319.413232) (xy 38.978884 -319.447324) (xy 39.008449 -319.486668)
			(xy 39.03132 -319.530245) (xy 39.046904 -319.576926) (xy 39.054799 -319.625503) (xy 39.055294 -319.65011)
			(xy 40.344102 -319.65011) (xy 40.348062 -319.601056) (xy 40.359839 -319.553272) (xy 40.37913 -319.507996)
			(xy 40.405433 -319.4664) (xy 40.438068 -319.429563) (xy 40.476189 -319.398438) (xy 40.51881 -319.373831)
			(xy 40.564826 -319.356379) (xy 40.613045 -319.346535) (xy 40.66222 -319.344554) (xy 40.711075 -319.350486)
			(xy 40.758346 -319.364178) (xy 40.802808 -319.385276) (xy 40.843311 -319.413232) (xy 40.878804 -319.447324)
			(xy 40.908369 -319.486668) (xy 40.93124 -319.530245) (xy 40.946824 -319.576926) (xy 40.954719 -319.625503)
			(xy 40.955214 -319.65011) (xy 42.244022 -319.65011) (xy 42.247982 -319.601056) (xy 42.259759 -319.553272)
			(xy 42.27905 -319.507996) (xy 42.305353 -319.4664) (xy 42.337988 -319.429563) (xy 42.376109 -319.398438)
			(xy 42.41873 -319.373831) (xy 42.464746 -319.356379) (xy 42.512965 -319.346535) (xy 42.56214 -319.344554)
			(xy 42.610995 -319.350486) (xy 42.658266 -319.364178) (xy 42.702728 -319.385276) (xy 42.743231 -319.413232)
			(xy 42.778724 -319.447324) (xy 42.808289 -319.486668) (xy 42.83116 -319.530245) (xy 42.846744 -319.576926)
			(xy 42.854639 -319.625503) (xy 42.855134 -319.65011) (xy 44.144196 -319.65011) (xy 44.148156 -319.601056)
			(xy 44.159933 -319.553272) (xy 44.179224 -319.507996) (xy 44.205527 -319.4664) (xy 44.238162 -319.429563)
			(xy 44.276283 -319.398438) (xy 44.318904 -319.373831) (xy 44.36492 -319.356379) (xy 44.413139 -319.346535)
			(xy 44.462314 -319.344554) (xy 44.511169 -319.350486) (xy 44.55844 -319.364178) (xy 44.602902 -319.385276)
			(xy 44.643405 -319.413232) (xy 44.678898 -319.447324) (xy 44.708463 -319.486668) (xy 44.731334 -319.530245)
			(xy 44.746918 -319.576926) (xy 44.754813 -319.625503) (xy 44.755308 -319.65011) (xy 46.044116 -319.65011)
			(xy 46.048076 -319.601056) (xy 46.059853 -319.553272) (xy 46.079144 -319.507996) (xy 46.105447 -319.4664)
			(xy 46.138082 -319.429563) (xy 46.176203 -319.398438) (xy 46.218824 -319.373831) (xy 46.26484 -319.356379)
			(xy 46.313059 -319.346535) (xy 46.362234 -319.344554) (xy 46.411089 -319.350486) (xy 46.45836 -319.364178)
			(xy 46.502822 -319.385276) (xy 46.543325 -319.413232) (xy 46.578818 -319.447324) (xy 46.608383 -319.486668)
			(xy 46.631254 -319.530245) (xy 46.646838 -319.576926) (xy 46.654733 -319.625503) (xy 46.655228 -319.65011)
			(xy 47.944036 -319.65011) (xy 47.947996 -319.601056) (xy 47.959773 -319.553272) (xy 47.979064 -319.507996)
			(xy 48.005367 -319.4664) (xy 48.038002 -319.429563) (xy 48.076123 -319.398438) (xy 48.118744 -319.373831)
			(xy 48.16476 -319.356379) (xy 48.212979 -319.346535) (xy 48.262154 -319.344554) (xy 48.311009 -319.350486)
			(xy 48.35828 -319.364178) (xy 48.402742 -319.385276) (xy 48.443245 -319.413232) (xy 48.478738 -319.447324)
			(xy 48.508303 -319.486668) (xy 48.531174 -319.530245) (xy 48.546758 -319.576926) (xy 48.554653 -319.625503)
			(xy 48.555148 -319.65011) (xy 49.84421 -319.65011) (xy 49.84817 -319.601056) (xy 49.859947 -319.553272)
			(xy 49.879238 -319.507996) (xy 49.905541 -319.4664) (xy 49.938176 -319.429563) (xy 49.976297 -319.398438)
			(xy 50.018918 -319.373831) (xy 50.064934 -319.356379) (xy 50.113153 -319.346535) (xy 50.162328 -319.344554)
			(xy 50.211183 -319.350486) (xy 50.258454 -319.364178) (xy 50.302916 -319.385276) (xy 50.343419 -319.413232)
			(xy 50.378912 -319.447324) (xy 50.408477 -319.486668) (xy 50.431348 -319.530245) (xy 50.446932 -319.576926)
			(xy 50.454827 -319.625503) (xy 50.455322 -319.65011) (xy 51.74413 -319.65011) (xy 51.74809 -319.601056)
			(xy 51.759867 -319.553272) (xy 51.779158 -319.507996) (xy 51.805461 -319.4664) (xy 51.838096 -319.429563)
			(xy 51.876217 -319.398438) (xy 51.918838 -319.373831) (xy 51.964854 -319.356379) (xy 52.013073 -319.346535)
			(xy 52.062248 -319.344554) (xy 52.111103 -319.350486) (xy 52.158374 -319.364178) (xy 52.202836 -319.385276)
			(xy 52.243339 -319.413232) (xy 52.278832 -319.447324) (xy 52.308397 -319.486668) (xy 52.331268 -319.530245)
			(xy 52.346852 -319.576926) (xy 52.354747 -319.625503) (xy 52.355242 -319.65011) (xy 53.64405 -319.65011)
			(xy 53.64801 -319.601056) (xy 53.659787 -319.553272) (xy 53.679078 -319.507996) (xy 53.705381 -319.4664)
			(xy 53.738016 -319.429563) (xy 53.776137 -319.398438) (xy 53.818758 -319.373831) (xy 53.864774 -319.356379)
			(xy 53.912993 -319.346535) (xy 53.962168 -319.344554) (xy 54.011023 -319.350486) (xy 54.058294 -319.364178)
			(xy 54.102756 -319.385276) (xy 54.143259 -319.413232) (xy 54.178752 -319.447324) (xy 54.208317 -319.486668)
			(xy 54.231188 -319.530245) (xy 54.246772 -319.576926) (xy 54.254667 -319.625503) (xy 54.255162 -319.65011)
			(xy 55.544224 -319.65011) (xy 55.548184 -319.601056) (xy 55.559961 -319.553272) (xy 55.579252 -319.507996)
			(xy 55.605555 -319.4664) (xy 55.63819 -319.429563) (xy 55.676311 -319.398438) (xy 55.718932 -319.373831)
			(xy 55.764948 -319.356379) (xy 55.813167 -319.346535) (xy 55.862342 -319.344554) (xy 55.911197 -319.350486)
			(xy 55.958468 -319.364178) (xy 56.00293 -319.385276) (xy 56.043433 -319.413232) (xy 56.078926 -319.447324)
			(xy 56.108491 -319.486668) (xy 56.131362 -319.530245) (xy 56.146946 -319.576926) (xy 56.154841 -319.625503)
			(xy 56.155336 -319.65011) (xy 57.444398 -319.65011) (xy 57.448358 -319.601056) (xy 57.460135 -319.553272)
			(xy 57.479426 -319.507996) (xy 57.505729 -319.4664) (xy 57.538364 -319.429563) (xy 57.576485 -319.398438)
			(xy 57.619106 -319.373831) (xy 57.665122 -319.356379) (xy 57.713341 -319.346535) (xy 57.762516 -319.344554)
			(xy 57.811371 -319.350486) (xy 57.858642 -319.364178) (xy 57.903104 -319.385276) (xy 57.943607 -319.413232)
			(xy 57.9791 -319.447324) (xy 58.008665 -319.486668) (xy 58.031536 -319.530245) (xy 58.04712 -319.576926)
			(xy 58.055015 -319.625503) (xy 58.05551 -319.65011) (xy 59.344064 -319.65011) (xy 59.348024 -319.601056)
			(xy 59.359801 -319.553272) (xy 59.379092 -319.507996) (xy 59.405395 -319.4664) (xy 59.43803 -319.429563)
			(xy 59.476151 -319.398438) (xy 59.518772 -319.373831) (xy 59.564788 -319.356379) (xy 59.613007 -319.346535)
			(xy 59.662182 -319.344554) (xy 59.711037 -319.350486) (xy 59.758308 -319.364178) (xy 59.80277 -319.385276)
			(xy 59.843273 -319.413232) (xy 59.878766 -319.447324) (xy 59.908331 -319.486668) (xy 59.931202 -319.530245)
			(xy 59.946786 -319.576926) (xy 59.954681 -319.625503) (xy 59.955176 -319.65011) (xy 61.243984 -319.65011)
			(xy 61.247944 -319.601056) (xy 61.259721 -319.553272) (xy 61.279012 -319.507996) (xy 61.305315 -319.4664)
			(xy 61.33795 -319.429563) (xy 61.376071 -319.398438) (xy 61.418692 -319.373831) (xy 61.464708 -319.356379)
			(xy 61.512927 -319.346535) (xy 61.562102 -319.344554) (xy 61.610957 -319.350486) (xy 61.658228 -319.364178)
			(xy 61.70269 -319.385276) (xy 61.743193 -319.413232) (xy 61.778686 -319.447324) (xy 61.808251 -319.486668)
			(xy 61.831122 -319.530245) (xy 61.846706 -319.576926) (xy 61.854601 -319.625503) (xy 61.855096 -319.65011)
			(xy 63.144158 -319.65011) (xy 63.148118 -319.601056) (xy 63.159895 -319.553272) (xy 63.179186 -319.507996)
			(xy 63.205489 -319.4664) (xy 63.238124 -319.429563) (xy 63.276245 -319.398438) (xy 63.318866 -319.373831)
			(xy 63.364882 -319.356379) (xy 63.413101 -319.346535) (xy 63.462276 -319.344554) (xy 63.511131 -319.350486)
			(xy 63.558402 -319.364178) (xy 63.602864 -319.385276) (xy 63.643367 -319.413232) (xy 63.67886 -319.447324)
			(xy 63.708425 -319.486668) (xy 63.731296 -319.530245) (xy 63.74688 -319.576926) (xy 63.754775 -319.625503)
			(xy 63.75527 -319.65011) (xy 65.044078 -319.65011) (xy 65.048038 -319.601056) (xy 65.059815 -319.553272)
			(xy 65.079106 -319.507996) (xy 65.105409 -319.4664) (xy 65.138044 -319.429563) (xy 65.176165 -319.398438)
			(xy 65.218786 -319.373831) (xy 65.264802 -319.356379) (xy 65.313021 -319.346535) (xy 65.362196 -319.344554)
			(xy 65.411051 -319.350486) (xy 65.458322 -319.364178) (xy 65.502784 -319.385276) (xy 65.543287 -319.413232)
			(xy 65.57878 -319.447324) (xy 65.608345 -319.486668) (xy 65.631216 -319.530245) (xy 65.6468 -319.576926)
			(xy 65.654695 -319.625503) (xy 65.65519 -319.65011) (xy 66.943998 -319.65011) (xy 66.947958 -319.601056)
			(xy 66.959735 -319.553272) (xy 66.979026 -319.507996) (xy 67.005329 -319.4664) (xy 67.037964 -319.429563)
			(xy 67.076085 -319.398438) (xy 67.118706 -319.373831) (xy 67.164722 -319.356379) (xy 67.212941 -319.346535)
			(xy 67.262116 -319.344554) (xy 67.310971 -319.350486) (xy 67.358242 -319.364178) (xy 67.402704 -319.385276)
			(xy 67.443207 -319.413232) (xy 67.4787 -319.447324) (xy 67.508265 -319.486668) (xy 67.531136 -319.530245)
			(xy 67.54672 -319.576926) (xy 67.554615 -319.625503) (xy 67.55511 -319.65011) (xy 68.844172 -319.65011)
			(xy 68.848132 -319.601056) (xy 68.859909 -319.553272) (xy 68.8792 -319.507996) (xy 68.905503 -319.4664)
			(xy 68.938138 -319.429563) (xy 68.976259 -319.398438) (xy 69.01888 -319.373831) (xy 69.064896 -319.356379)
			(xy 69.113115 -319.346535) (xy 69.16229 -319.344554) (xy 69.211145 -319.350486) (xy 69.258416 -319.364178)
			(xy 69.302878 -319.385276) (xy 69.343381 -319.413232) (xy 69.378874 -319.447324) (xy 69.408439 -319.486668)
			(xy 69.43131 -319.530245) (xy 69.446894 -319.576926) (xy 69.454789 -319.625503) (xy 69.455284 -319.65011)
			(xy 70.744092 -319.65011) (xy 70.748052 -319.601056) (xy 70.759829 -319.553272) (xy 70.77912 -319.507996)
			(xy 70.805423 -319.4664) (xy 70.838058 -319.429563) (xy 70.876179 -319.398438) (xy 70.9188 -319.373831)
			(xy 70.964816 -319.356379) (xy 71.013035 -319.346535) (xy 71.06221 -319.344554) (xy 71.111065 -319.350486)
			(xy 71.158336 -319.364178) (xy 71.202798 -319.385276) (xy 71.243301 -319.413232) (xy 71.278794 -319.447324)
			(xy 71.308359 -319.486668) (xy 71.33123 -319.530245) (xy 71.346814 -319.576926) (xy 71.354709 -319.625503)
			(xy 71.355204 -319.65011) (xy 71.354709 -319.674717) (xy 71.346814 -319.723294) (xy 71.33123 -319.769975)
			(xy 71.308359 -319.813552) (xy 71.278794 -319.852896) (xy 71.243301 -319.886988) (xy 71.202798 -319.914944)
			(xy 71.158336 -319.936042) (xy 71.111065 -319.949734) (xy 71.06221 -319.955666) (xy 71.013035 -319.953685)
			(xy 70.964816 -319.943841) (xy 70.9188 -319.926389) (xy 70.876179 -319.901782) (xy 70.838058 -319.870657)
			(xy 70.805423 -319.83382) (xy 70.77912 -319.792224) (xy 70.759829 -319.746948) (xy 70.748052 -319.699164)
			(xy 70.744092 -319.65011) (xy 69.455284 -319.65011) (xy 69.454789 -319.674717) (xy 69.446894 -319.723294)
			(xy 69.43131 -319.769975) (xy 69.408439 -319.813552) (xy 69.378874 -319.852896) (xy 69.343381 -319.886988)
			(xy 69.302878 -319.914944) (xy 69.258416 -319.936042) (xy 69.211145 -319.949734) (xy 69.16229 -319.955666)
			(xy 69.113115 -319.953685) (xy 69.064896 -319.943841) (xy 69.01888 -319.926389) (xy 68.976259 -319.901782)
			(xy 68.938138 -319.870657) (xy 68.905503 -319.83382) (xy 68.8792 -319.792224) (xy 68.859909 -319.746948)
			(xy 68.848132 -319.699164) (xy 68.844172 -319.65011) (xy 67.55511 -319.65011) (xy 67.554615 -319.674717)
			(xy 67.54672 -319.723294) (xy 67.531136 -319.769975) (xy 67.508265 -319.813552) (xy 67.4787 -319.852896)
			(xy 67.443207 -319.886988) (xy 67.402704 -319.914944) (xy 67.358242 -319.936042) (xy 67.310971 -319.949734)
			(xy 67.262116 -319.955666) (xy 67.212941 -319.953685) (xy 67.164722 -319.943841) (xy 67.118706 -319.926389)
			(xy 67.076085 -319.901782) (xy 67.037964 -319.870657) (xy 67.005329 -319.83382) (xy 66.979026 -319.792224)
			(xy 66.959735 -319.746948) (xy 66.947958 -319.699164) (xy 66.943998 -319.65011) (xy 65.65519 -319.65011)
			(xy 65.654695 -319.674717) (xy 65.6468 -319.723294) (xy 65.631216 -319.769975) (xy 65.608345 -319.813552)
			(xy 65.57878 -319.852896) (xy 65.543287 -319.886988) (xy 65.502784 -319.914944) (xy 65.458322 -319.936042)
			(xy 65.411051 -319.949734) (xy 65.362196 -319.955666) (xy 65.313021 -319.953685) (xy 65.264802 -319.943841)
			(xy 65.218786 -319.926389) (xy 65.176165 -319.901782) (xy 65.138044 -319.870657) (xy 65.105409 -319.83382)
			(xy 65.079106 -319.792224) (xy 65.059815 -319.746948) (xy 65.048038 -319.699164) (xy 65.044078 -319.65011)
			(xy 63.75527 -319.65011) (xy 63.754775 -319.674717) (xy 63.74688 -319.723294) (xy 63.731296 -319.769975)
			(xy 63.708425 -319.813552) (xy 63.67886 -319.852896) (xy 63.643367 -319.886988) (xy 63.602864 -319.914944)
			(xy 63.558402 -319.936042) (xy 63.511131 -319.949734) (xy 63.462276 -319.955666) (xy 63.413101 -319.953685)
			(xy 63.364882 -319.943841) (xy 63.318866 -319.926389) (xy 63.276245 -319.901782) (xy 63.238124 -319.870657)
			(xy 63.205489 -319.83382) (xy 63.179186 -319.792224) (xy 63.159895 -319.746948) (xy 63.148118 -319.699164)
			(xy 63.144158 -319.65011) (xy 61.855096 -319.65011) (xy 61.854601 -319.674717) (xy 61.846706 -319.723294)
			(xy 61.831122 -319.769975) (xy 61.808251 -319.813552) (xy 61.778686 -319.852896) (xy 61.743193 -319.886988)
			(xy 61.70269 -319.914944) (xy 61.658228 -319.936042) (xy 61.610957 -319.949734) (xy 61.562102 -319.955666)
			(xy 61.512927 -319.953685) (xy 61.464708 -319.943841) (xy 61.418692 -319.926389) (xy 61.376071 -319.901782)
			(xy 61.33795 -319.870657) (xy 61.305315 -319.83382) (xy 61.279012 -319.792224) (xy 61.259721 -319.746948)
			(xy 61.247944 -319.699164) (xy 61.243984 -319.65011) (xy 59.955176 -319.65011) (xy 59.954681 -319.674717)
			(xy 59.946786 -319.723294) (xy 59.931202 -319.769975) (xy 59.908331 -319.813552) (xy 59.878766 -319.852896)
			(xy 59.843273 -319.886988) (xy 59.80277 -319.914944) (xy 59.758308 -319.936042) (xy 59.711037 -319.949734)
			(xy 59.662182 -319.955666) (xy 59.613007 -319.953685) (xy 59.564788 -319.943841) (xy 59.518772 -319.926389)
			(xy 59.476151 -319.901782) (xy 59.43803 -319.870657) (xy 59.405395 -319.83382) (xy 59.379092 -319.792224)
			(xy 59.359801 -319.746948) (xy 59.348024 -319.699164) (xy 59.344064 -319.65011) (xy 58.05551 -319.65011)
			(xy 58.055015 -319.674717) (xy 58.04712 -319.723294) (xy 58.031536 -319.769975) (xy 58.008665 -319.813552)
			(xy 57.9791 -319.852896) (xy 57.943607 -319.886988) (xy 57.903104 -319.914944) (xy 57.858642 -319.936042)
			(xy 57.811371 -319.949734) (xy 57.762516 -319.955666) (xy 57.713341 -319.953685) (xy 57.665122 -319.943841)
			(xy 57.619106 -319.926389) (xy 57.576485 -319.901782) (xy 57.538364 -319.870657) (xy 57.505729 -319.83382)
			(xy 57.479426 -319.792224) (xy 57.460135 -319.746948) (xy 57.448358 -319.699164) (xy 57.444398 -319.65011)
			(xy 56.155336 -319.65011) (xy 56.154841 -319.674717) (xy 56.146946 -319.723294) (xy 56.131362 -319.769975)
			(xy 56.108491 -319.813552) (xy 56.078926 -319.852896) (xy 56.043433 -319.886988) (xy 56.00293 -319.914944)
			(xy 55.958468 -319.936042) (xy 55.911197 -319.949734) (xy 55.862342 -319.955666) (xy 55.813167 -319.953685)
			(xy 55.764948 -319.943841) (xy 55.718932 -319.926389) (xy 55.676311 -319.901782) (xy 55.63819 -319.870657)
			(xy 55.605555 -319.83382) (xy 55.579252 -319.792224) (xy 55.559961 -319.746948) (xy 55.548184 -319.699164)
			(xy 55.544224 -319.65011) (xy 54.255162 -319.65011) (xy 54.254667 -319.674717) (xy 54.246772 -319.723294)
			(xy 54.231188 -319.769975) (xy 54.208317 -319.813552) (xy 54.178752 -319.852896) (xy 54.143259 -319.886988)
			(xy 54.102756 -319.914944) (xy 54.058294 -319.936042) (xy 54.011023 -319.949734) (xy 53.962168 -319.955666)
			(xy 53.912993 -319.953685) (xy 53.864774 -319.943841) (xy 53.818758 -319.926389) (xy 53.776137 -319.901782)
			(xy 53.738016 -319.870657) (xy 53.705381 -319.83382) (xy 53.679078 -319.792224) (xy 53.659787 -319.746948)
			(xy 53.64801 -319.699164) (xy 53.64405 -319.65011) (xy 52.355242 -319.65011) (xy 52.354747 -319.674717)
			(xy 52.346852 -319.723294) (xy 52.331268 -319.769975) (xy 52.308397 -319.813552) (xy 52.278832 -319.852896)
			(xy 52.243339 -319.886988) (xy 52.202836 -319.914944) (xy 52.158374 -319.936042) (xy 52.111103 -319.949734)
			(xy 52.062248 -319.955666) (xy 52.013073 -319.953685) (xy 51.964854 -319.943841) (xy 51.918838 -319.926389)
			(xy 51.876217 -319.901782) (xy 51.838096 -319.870657) (xy 51.805461 -319.83382) (xy 51.779158 -319.792224)
			(xy 51.759867 -319.746948) (xy 51.74809 -319.699164) (xy 51.74413 -319.65011) (xy 50.455322 -319.65011)
			(xy 50.454827 -319.674717) (xy 50.446932 -319.723294) (xy 50.431348 -319.769975) (xy 50.408477 -319.813552)
			(xy 50.378912 -319.852896) (xy 50.343419 -319.886988) (xy 50.302916 -319.914944) (xy 50.258454 -319.936042)
			(xy 50.211183 -319.949734) (xy 50.162328 -319.955666) (xy 50.113153 -319.953685) (xy 50.064934 -319.943841)
			(xy 50.018918 -319.926389) (xy 49.976297 -319.901782) (xy 49.938176 -319.870657) (xy 49.905541 -319.83382)
			(xy 49.879238 -319.792224) (xy 49.859947 -319.746948) (xy 49.84817 -319.699164) (xy 49.84421 -319.65011)
			(xy 48.555148 -319.65011) (xy 48.554653 -319.674717) (xy 48.546758 -319.723294) (xy 48.531174 -319.769975)
			(xy 48.508303 -319.813552) (xy 48.478738 -319.852896) (xy 48.443245 -319.886988) (xy 48.402742 -319.914944)
			(xy 48.35828 -319.936042) (xy 48.311009 -319.949734) (xy 48.262154 -319.955666) (xy 48.212979 -319.953685)
			(xy 48.16476 -319.943841) (xy 48.118744 -319.926389) (xy 48.076123 -319.901782) (xy 48.038002 -319.870657)
			(xy 48.005367 -319.83382) (xy 47.979064 -319.792224) (xy 47.959773 -319.746948) (xy 47.947996 -319.699164)
			(xy 47.944036 -319.65011) (xy 46.655228 -319.65011) (xy 46.654733 -319.674717) (xy 46.646838 -319.723294)
			(xy 46.631254 -319.769975) (xy 46.608383 -319.813552) (xy 46.578818 -319.852896) (xy 46.543325 -319.886988)
			(xy 46.502822 -319.914944) (xy 46.45836 -319.936042) (xy 46.411089 -319.949734) (xy 46.362234 -319.955666)
			(xy 46.313059 -319.953685) (xy 46.26484 -319.943841) (xy 46.218824 -319.926389) (xy 46.176203 -319.901782)
			(xy 46.138082 -319.870657) (xy 46.105447 -319.83382) (xy 46.079144 -319.792224) (xy 46.059853 -319.746948)
			(xy 46.048076 -319.699164) (xy 46.044116 -319.65011) (xy 44.755308 -319.65011) (xy 44.754813 -319.674717)
			(xy 44.746918 -319.723294) (xy 44.731334 -319.769975) (xy 44.708463 -319.813552) (xy 44.678898 -319.852896)
			(xy 44.643405 -319.886988) (xy 44.602902 -319.914944) (xy 44.55844 -319.936042) (xy 44.511169 -319.949734)
			(xy 44.462314 -319.955666) (xy 44.413139 -319.953685) (xy 44.36492 -319.943841) (xy 44.318904 -319.926389)
			(xy 44.276283 -319.901782) (xy 44.238162 -319.870657) (xy 44.205527 -319.83382) (xy 44.179224 -319.792224)
			(xy 44.159933 -319.746948) (xy 44.148156 -319.699164) (xy 44.144196 -319.65011) (xy 42.855134 -319.65011)
			(xy 42.854639 -319.674717) (xy 42.846744 -319.723294) (xy 42.83116 -319.769975) (xy 42.808289 -319.813552)
			(xy 42.778724 -319.852896) (xy 42.743231 -319.886988) (xy 42.702728 -319.914944) (xy 42.658266 -319.936042)
			(xy 42.610995 -319.949734) (xy 42.56214 -319.955666) (xy 42.512965 -319.953685) (xy 42.464746 -319.943841)
			(xy 42.41873 -319.926389) (xy 42.376109 -319.901782) (xy 42.337988 -319.870657) (xy 42.305353 -319.83382)
			(xy 42.27905 -319.792224) (xy 42.259759 -319.746948) (xy 42.247982 -319.699164) (xy 42.244022 -319.65011)
			(xy 40.955214 -319.65011) (xy 40.954719 -319.674717) (xy 40.946824 -319.723294) (xy 40.93124 -319.769975)
			(xy 40.908369 -319.813552) (xy 40.878804 -319.852896) (xy 40.843311 -319.886988) (xy 40.802808 -319.914944)
			(xy 40.758346 -319.936042) (xy 40.711075 -319.949734) (xy 40.66222 -319.955666) (xy 40.613045 -319.953685)
			(xy 40.564826 -319.943841) (xy 40.51881 -319.926389) (xy 40.476189 -319.901782) (xy 40.438068 -319.870657)
			(xy 40.405433 -319.83382) (xy 40.37913 -319.792224) (xy 40.359839 -319.746948) (xy 40.348062 -319.699164)
			(xy 40.344102 -319.65011) (xy 39.055294 -319.65011) (xy 39.054799 -319.674717) (xy 39.046904 -319.723294)
			(xy 39.03132 -319.769975) (xy 39.008449 -319.813552) (xy 38.978884 -319.852896) (xy 38.943391 -319.886988)
			(xy 38.902888 -319.914944) (xy 38.858426 -319.936042) (xy 38.811155 -319.949734) (xy 38.7623 -319.955666)
			(xy 38.713125 -319.953685) (xy 38.664906 -319.943841) (xy 38.61889 -319.926389) (xy 38.576269 -319.901782)
			(xy 38.538148 -319.870657) (xy 38.505513 -319.83382) (xy 38.47921 -319.792224) (xy 38.459919 -319.746948)
			(xy 38.448142 -319.699164) (xy 38.444182 -319.65011) (xy 34.259645 -319.65011) (xy 34.306377 -319.837182)
			(xy 34.345855 -320.028007) (xy 34.377516 -320.220283) (xy 34.401308 -320.413691) (xy 34.417191 -320.607908)
			(xy 34.425139 -320.802611) (xy 34.425636 -320.900044) (xy 34.425125 -320.998442) (xy 34.417006 -321.195069)
			(xy 34.400794 -321.391196) (xy 34.376518 -321.586488) (xy 34.344219 -321.780615) (xy 34.303951 -321.973247)
			(xy 34.255784 -322.164056) (xy 34.199798 -322.35272) (xy 34.13609 -322.538918) (xy 34.064766 -322.722334)
			(xy 33.985948 -322.902656) (xy 33.89977 -323.079579) (xy 33.806377 -323.252802) (xy 33.7566 -323.337682)
			(xy 33.753298 -323.343524) (xy 33.749742 -323.35597) (xy 33.749488 -323.363082) (xy 33.749545 -323.367153)
			(xy 33.750828 -323.375193) (xy 33.752028 -323.379084) (xy 33.753552 -323.383148) (xy 33.75533 -323.387212)
			(xy 33.755838 -323.388228) (xy 33.756092 -323.388736) (xy 33.788096 -323.445124) (xy 33.788604 -323.445632)
			(xy 33.800034 -323.465698) (xy 33.802624 -323.469905) (xy 33.809143 -323.477328) (xy 33.812988 -323.48043)
			(xy 33.819084 -323.484494) (xy 33.822499 -323.486373) (xy 33.829772 -323.489174) (xy 33.833562 -323.490082)
			(xy 33.843214 -323.491098) (xy 56.445404 -323.491098) (xy 56.45531 -323.490082) (xy 70.999858 -320.597022)
			(xy 71.00697 -320.59499) (xy 72.27189 -320.142362) (xy 72.278158 -320.139953) (xy 72.28922 -320.132349)
			(xy 72.293734 -320.127376) (xy 72.297798 -320.122296) (xy 72.303386 -320.110612) (xy 72.304656 -320.104008)
			(xy 72.313604 -320.060308) (xy 72.338282 -319.974583) (xy 72.353932 -319.932812) (xy 72.357488 -319.923922)
			(xy 72.357488 -319.488312) (xy 72.357271 -319.481503) (xy 72.353665 -319.46837) (xy 72.350376 -319.462404)
			(xy 72.343518 -319.45072) (xy 72.339708 -319.448688) (xy 72.317918 -319.437367) (xy 72.27795 -319.408845)
			(xy 72.243055 -319.374301) (xy 72.214132 -319.334622) (xy 72.191924 -319.29083) (xy 72.184006 -319.267586)
			(xy 72.175908 -319.239959) (xy 72.169013 -319.18281) (xy 72.17029 -319.154048) (xy 72.17029 -319.152016)
			(xy 72.170798 -319.149222) (xy 72.170798 -319.147698) (xy 72.171652 -319.138553) (xy 72.174318 -319.12038)
			(xy 72.176132 -319.111376) (xy 72.176132 -319.110614) (xy 72.177148 -319.106296) (xy 72.173338 -319.094104)
			(xy 72.170798 -319.0875) (xy 72.168794 -319.08359) (xy 72.163684 -319.076443) (xy 72.160638 -319.073276)
			(xy 72.101202 -319.01384) (xy 72.09196 -319.005699) (xy 72.068474 -318.998407) (xy 72.056244 -318.99987)
			(xy 72.05599 -318.99987) (xy 72.042088 -319.002346) (xy 72.013975 -319.005019) (xy 71.999856 -319.005204)
			(xy 71.974603 -319.004679) (xy 71.924788 -318.99636) (xy 71.877021 -318.979955) (xy 71.832605 -318.955913)
			(xy 71.792752 -318.924889) (xy 71.758548 -318.887728) (xy 71.730927 -318.845445) (xy 71.710641 -318.799193)
			(xy 71.698243 -318.750233) (xy 71.694073 -318.6999) (xy 71.698243 -318.649567) (xy 71.710641 -318.600607)
			(xy 71.730927 -318.554355) (xy 71.758548 -318.512072) (xy 71.792752 -318.474911) (xy 71.832605 -318.443887)
			(xy 71.877021 -318.419845) (xy 71.924788 -318.40344) (xy 71.974603 -318.395121) (xy 71.999856 -318.394588)
			(xy 72.013911 -318.394794) (xy 72.041896 -318.397463) (xy 72.055736 -318.399922) (xy 72.056244 -318.399922)
			(xy 72.068476 -318.401422) (xy 72.09197 -318.394117) (xy 72.101202 -318.385952) (xy 72.160638 -318.326516)
			(xy 72.165718 -318.320674) (xy 72.168227 -318.317058) (xy 72.172067 -318.30914) (xy 72.173338 -318.304926)
			(xy 72.176894 -318.293496) (xy 72.174608 -318.28105) (xy 72.170058 -318.253163) (xy 72.170056 -318.196668)
			(xy 72.174608 -318.168782) (xy 72.176894 -318.156336) (xy 72.173338 -318.144906) (xy 72.172036 -318.140704)
			(xy 72.168205 -318.132786) (xy 72.165718 -318.129158) (xy 72.160638 -318.123316) (xy 72.101202 -318.06388)
			(xy 72.091962 -318.055733) (xy 72.068474 -318.048436) (xy 72.056244 -318.04991) (xy 72.05599 -318.04991)
			(xy 72.042088 -318.052386) (xy 72.013975 -318.055058) (xy 71.999856 -318.055244) (xy 71.975866 -318.05477)
			(xy 71.928478 -318.047259) (xy 71.882847 -318.032428) (xy 71.840098 -318.010643) (xy 71.801282 -317.982439)
			(xy 71.767356 -317.948512) (xy 71.739153 -317.909695) (xy 71.717369 -317.866946) (xy 71.702539 -317.821315)
			(xy 71.695029 -317.773926) (xy 71.694548 -317.749936) (xy 71.695015 -317.725954) (xy 71.702508 -317.67858)
			(xy 71.717317 -317.63296) (xy 71.739075 -317.590216) (xy 71.76725 -317.5514) (xy 71.801146 -317.517467)
			(xy 71.839931 -317.48925) (xy 71.882651 -317.467445) (xy 71.928255 -317.452587) (xy 71.975621 -317.445041)
			(xy 71.999602 -317.444628) (xy 72.00011 -317.444628) (xy 72.009023 -317.444745) (xy 72.026815 -317.44589)
			(xy 72.03567 -317.446914) (xy 72.035924 -317.446914) (xy 72.04366 -317.447568) (xy 72.058914 -317.44472)
			(xy 72.065896 -317.441326) (xy 72.06938 -317.439349) (xy 72.07576 -317.434503) (xy 72.078596 -317.431674)
			(xy 72.135238 -317.372492) (xy 72.138032 -317.36919) (xy 72.140919 -317.365455) (xy 72.145394 -317.357146)
			(xy 72.146922 -317.35268) (xy 72.150478 -317.34125) (xy 72.149462 -317.3349) (xy 72.146882 -317.320175)
			(xy 72.14408 -317.290411) (xy 72.143874 -317.275464) (xy 72.143874 -317.223648) (xy 72.143203 -317.215879)
			(xy 72.137769 -317.20127) (xy 72.133206 -317.194946) (xy 72.12711 -317.188342) (xy 72.071484 -317.13805)
			(xy 72.067392 -317.134532) (xy 72.058038 -317.129156) (xy 72.052942 -317.127382) (xy 72.043036 -317.12408)
			(xy 72.032368 -317.125096) (xy 71.999856 -317.12662) (xy 71.974169 -317.126113) (xy 71.923428 -317.11807)
			(xy 71.874569 -317.102189) (xy 71.828796 -317.078861) (xy 71.787236 -317.048661) (xy 71.750911 -317.012331)
			(xy 71.720716 -316.970766) (xy 71.697394 -316.92499) (xy 71.68152 -316.87613) (xy 71.673484 -316.825387)
			(xy 71.673484 -316.774013) (xy 71.68152 -316.72327) (xy 71.697394 -316.67441) (xy 71.720716 -316.628634)
			(xy 71.750911 -316.587069) (xy 71.787236 -316.550739) (xy 71.828796 -316.520539) (xy 71.874569 -316.497211)
			(xy 71.923428 -316.48133) (xy 71.974169 -316.473287) (xy 71.999856 -316.472824) (xy 72.032368 -316.474348)
			(xy 72.032622 -316.474348) (xy 72.04329 -316.474966) (xy 72.063562 -316.468271) (xy 72.071738 -316.461394)
			(xy 72.127364 -316.411102) (xy 72.133568 -316.405057) (xy 72.141876 -316.389869) (xy 72.14362 -316.381384)
			(xy 72.144128 -316.37351) (xy 72.144128 -316.324742) (xy 72.144173 -316.315388) (xy 72.145192 -316.296708)
			(xy 72.14616 -316.287404) (xy 72.14696 -316.275936) (xy 72.139431 -316.254239) (xy 72.131682 -316.245748)
			(xy 72.075802 -316.189614) (xy 72.067374 -316.181989) (xy 72.046006 -316.174333) (xy 72.034654 -316.174882)
			(xy 72.0344 -316.174882) (xy 71.999856 -316.17666) (xy 71.974173 -316.176153) (xy 71.923442 -316.168112)
			(xy 71.874592 -316.152234) (xy 71.828828 -316.12891) (xy 71.787275 -316.098715) (xy 71.750956 -316.062392)
			(xy 71.720767 -316.020835) (xy 71.697449 -315.975067) (xy 71.681578 -315.926216) (xy 71.673543 -315.875483)
			(xy 71.673543 -315.824117) (xy 71.681578 -315.773384) (xy 71.697449 -315.724533) (xy 71.720767 -315.678765)
			(xy 71.750956 -315.637208) (xy 71.787275 -315.600885) (xy 71.828828 -315.57069) (xy 71.874592 -315.547366)
			(xy 71.923442 -315.531488) (xy 71.974173 -315.523447) (xy 71.999856 -315.522864) (xy 72.013506 -315.522955)
			(xy 72.040719 -315.525118) (xy 72.054212 -315.527182) (xy 72.054466 -315.527182) (xy 72.066323 -315.528511)
			(xy 72.089092 -315.521483) (xy 72.098154 -315.51372) (xy 72.156828 -315.457332) (xy 72.16521 -315.446664)
			(xy 72.169528 -315.437774) (xy 72.173592 -315.426598) (xy 72.172322 -315.416692) (xy 72.170974 -315.406076)
			(xy 72.169573 -315.384721) (xy 72.169528 -315.37402) (xy 72.169528 -315.367416) (xy 72.170798 -315.347604)
			(xy 72.171052 -315.346588) (xy 72.171052 -315.34481) (xy 72.174354 -315.318394) (xy 72.175116 -315.3156)
			(xy 72.17537 -315.313822) (xy 72.178672 -315.299344) (xy 72.178926 -315.298836) (xy 72.182384 -315.285811)
			(xy 72.191284 -315.260373) (xy 72.196706 -315.248036) (xy 72.197214 -315.247274) (xy 72.200516 -315.237622)
			(xy 72.201278 -315.233812) (xy 72.202792 -315.225347) (xy 72.200735 -315.208285) (xy 72.193183 -315.192847)
			(xy 72.187308 -315.186568) (xy 72.187054 -315.186314) (xy 72.182465 -315.182069) (xy 72.171673 -315.175769)
			(xy 72.165718 -315.173868) (xy 72.159622 -315.17209) (xy 72.146922 -315.171836) (xy 72.131682 -315.175392)
			(xy 72.126856 -315.177424) (xy 72.106873 -315.186141) (xy 72.065054 -315.198462) (xy 72.021908 -315.204715)
			(xy 72.00011 -315.20511) (xy 71.999856 -315.20511) (xy 71.974603 -315.204585) (xy 71.924786 -315.196265)
			(xy 71.877019 -315.179861) (xy 71.832602 -315.155818) (xy 71.792748 -315.124793) (xy 71.758543 -315.087632)
			(xy 71.730921 -315.045348) (xy 71.710635 -314.999095) (xy 71.698237 -314.950134) (xy 71.694067 -314.8998)
			(xy 71.698237 -314.849466) (xy 71.710635 -314.800505) (xy 71.730921 -314.754252) (xy 71.758543 -314.711968)
			(xy 71.792748 -314.674807) (xy 71.832602 -314.643782) (xy 71.877019 -314.619739) (xy 71.924786 -314.603335)
			(xy 71.974603 -314.595015) (xy 71.999856 -314.594494) (xy 72.013911 -314.5947) (xy 72.041896 -314.597369)
			(xy 72.055736 -314.599828) (xy 72.056244 -314.599828) (xy 72.068476 -314.601328) (xy 72.091971 -314.594023)
			(xy 72.101202 -314.585858) (xy 72.160638 -314.526422) (xy 72.165718 -314.52058) (xy 72.168228 -314.516964)
			(xy 72.172069 -314.509046) (xy 72.173338 -314.504832) (xy 72.176894 -314.493402) (xy 72.174608 -314.480956)
			(xy 72.170058 -314.453069) (xy 72.170054 -314.396574) (xy 72.174608 -314.368688) (xy 72.176894 -314.356242)
			(xy 72.173338 -314.344812) (xy 72.172036 -314.34061) (xy 72.168207 -314.332691) (xy 72.165718 -314.329064)
			(xy 72.160638 -314.323222) (xy 72.101202 -314.263786) (xy 72.091962 -314.255639) (xy 72.068474 -314.24834)
			(xy 72.056244 -314.249816) (xy 72.05599 -314.249816) (xy 72.042088 -314.252292) (xy 72.013975 -314.254964)
			(xy 71.999856 -314.25515) (xy 71.9746 -314.254625) (xy 71.924777 -314.246304) (xy 71.877002 -314.229897)
			(xy 71.83258 -314.205851) (xy 71.792721 -314.174822) (xy 71.758512 -314.137656) (xy 71.730886 -314.095367)
			(xy 71.710597 -314.049108) (xy 71.698198 -314.00014) (xy 71.694027 -313.9498) (xy 71.698198 -313.89946)
			(xy 71.710597 -313.850492) (xy 71.730886 -313.804233) (xy 71.758512 -313.761944) (xy 71.792721 -313.724778)
			(xy 71.83258 -313.693749) (xy 71.877002 -313.669703) (xy 71.924777 -313.653296) (xy 71.9746 -313.644975)
			(xy 71.999856 -313.644534) (xy 72.013911 -313.64474) (xy 72.041896 -313.647409) (xy 72.055736 -313.649868)
			(xy 72.056244 -313.649868) (xy 72.068477 -313.651368) (xy 72.091974 -313.644068) (xy 72.101202 -313.635898)
			(xy 72.160638 -313.576462) (xy 72.165718 -313.57062) (xy 72.168224 -313.567003) (xy 72.172055 -313.559082)
			(xy 72.173338 -313.554872) (xy 72.176894 -313.543442) (xy 72.174608 -313.530996) (xy 72.170063 -313.50311)
			(xy 72.17007 -313.446616) (xy 72.174608 -313.418728) (xy 72.176894 -313.406282) (xy 72.173338 -313.394852)
			(xy 72.172032 -313.390652) (xy 72.168195 -313.382739) (xy 72.165718 -313.379104) (xy 72.160638 -313.373262)
			(xy 72.101202 -313.313826) (xy 72.091964 -313.305673) (xy 72.068474 -313.298369) (xy 72.056244 -313.299856)
			(xy 72.05599 -313.299856) (xy 72.042088 -313.302333) (xy 72.013975 -313.305005) (xy 71.999856 -313.30519)
			(xy 71.974605 -313.304665) (xy 71.924791 -313.296346) (xy 71.877027 -313.279942) (xy 71.832613 -313.255901)
			(xy 71.792761 -313.224878) (xy 71.758559 -313.18772) (xy 71.730939 -313.145439) (xy 71.710654 -313.099189)
			(xy 71.698257 -313.050231) (xy 71.694087 -312.9999) (xy 71.698257 -312.949569) (xy 71.710654 -312.900611)
			(xy 71.730939 -312.854361) (xy 71.758559 -312.81208) (xy 71.792761 -312.774922) (xy 71.832613 -312.743899)
			(xy 71.877027 -312.719858) (xy 71.924791 -312.703454) (xy 71.974605 -312.695135) (xy 71.999856 -312.694574)
			(xy 72.013911 -312.69478) (xy 72.041896 -312.697449) (xy 72.055736 -312.699908) (xy 72.056244 -312.699908)
			(xy 72.068478 -312.701408) (xy 72.091978 -312.694112) (xy 72.101202 -312.685938) (xy 72.160638 -312.626502)
			(xy 72.165718 -312.62066) (xy 72.168226 -312.617044) (xy 72.172064 -312.609125) (xy 72.173338 -312.604912)
			(xy 72.176894 -312.593482) (xy 72.174608 -312.581036) (xy 72.171032 -312.559639) (xy 72.169246 -312.516295)
			(xy 72.171052 -312.494676) (xy 72.171052 -312.493152) (xy 72.171814 -312.489088) (xy 72.171814 -312.487564)
			(xy 72.172576 -312.481976) (xy 72.173592 -312.473594) (xy 72.169782 -312.462418) (xy 72.16813 -312.457774)
			(xy 72.163266 -312.449202) (xy 72.16013 -312.4454) (xy 72.156828 -312.442098) (xy 72.097646 -312.38571)
			(xy 72.093285 -312.381739) (xy 72.083149 -312.375715) (xy 72.07758 -312.373772) (xy 72.06615 -312.370216)
			(xy 72.054212 -312.372248) (xy 72.040786 -312.374365) (xy 72.013701 -312.376653) (xy 72.00011 -312.37682)
			(xy 71.999856 -312.37682) (xy 71.974169 -312.376313) (xy 71.923428 -312.36827) (xy 71.874569 -312.352389)
			(xy 71.828796 -312.329061) (xy 71.787236 -312.298861) (xy 71.750911 -312.262531) (xy 71.720716 -312.220966)
			(xy 71.697394 -312.17519) (xy 71.68152 -312.12633) (xy 71.673484 -312.075587) (xy 71.673484 -312.024213)
			(xy 71.68152 -311.97347) (xy 71.697394 -311.92461) (xy 71.720716 -311.878834) (xy 71.750911 -311.837269)
			(xy 71.787236 -311.800939) (xy 71.828796 -311.770739) (xy 71.874569 -311.747411) (xy 71.923428 -311.73153)
			(xy 71.974169 -311.723487) (xy 71.999856 -311.723024) (xy 72.000364 -311.723024) (xy 72.034146 -311.724802)
			(xy 72.045576 -311.726072) (xy 72.056498 -311.722008) (xy 72.061645 -311.719987) (xy 72.071001 -311.7141)
			(xy 72.07504 -311.710324) (xy 72.131174 -311.653936) (xy 72.135207 -311.649732) (xy 72.141371 -311.639851)
			(xy 72.143366 -311.634378) (xy 72.146922 -311.62371) (xy 72.145652 -311.61228) (xy 72.144677 -311.602913)
			(xy 72.143662 -311.584106) (xy 72.14362 -311.574688) (xy 72.14362 -311.526428) (xy 72.143112 -311.518554)
			(xy 72.141388 -311.510063) (xy 72.133066 -311.494879) (xy 72.126856 -311.488836) (xy 72.070976 -311.43829)
			(xy 72.062829 -311.43162) (xy 72.042889 -311.424925) (xy 72.032368 -311.425336) (xy 72.032114 -311.425336)
			(xy 71.999856 -311.42686) (xy 71.974173 -311.426353) (xy 71.923442 -311.418312) (xy 71.874592 -311.402434)
			(xy 71.828828 -311.37911) (xy 71.787275 -311.348915) (xy 71.750956 -311.312592) (xy 71.720767 -311.271035)
			(xy 71.697449 -311.225267) (xy 71.681578 -311.176416) (xy 71.673543 -311.125683) (xy 71.673543 -311.074317)
			(xy 71.681578 -311.023584) (xy 71.697449 -310.974733) (xy 71.720767 -310.928965) (xy 71.750956 -310.887408)
			(xy 71.787275 -310.851085) (xy 71.828828 -310.82089) (xy 71.874592 -310.797566) (xy 71.923442 -310.781688)
			(xy 71.974173 -310.773647) (xy 71.999856 -310.773064) (xy 72.03186 -310.774588) (xy 72.032368 -310.774588)
			(xy 72.042895 -310.775023) (xy 72.06285 -310.768339) (xy 72.070976 -310.761634) (xy 72.126856 -310.711088)
			(xy 72.133059 -310.705042) (xy 72.141364 -310.689854) (xy 72.143112 -310.68137) (xy 72.14362 -310.673496)
			(xy 72.14362 -310.623966) (xy 72.143819 -310.608829) (xy 72.146616 -310.578683) (xy 72.149208 -310.563768)
			(xy 72.149208 -310.563006) (xy 72.14997 -310.558434) (xy 72.146668 -310.547512) (xy 72.145395 -310.543452)
			(xy 72.141696 -310.535789) (xy 72.139302 -310.532272) (xy 72.13473 -310.526684) (xy 72.078342 -310.468264)
			(xy 72.074206 -310.464145) (xy 72.064462 -310.45772) (xy 72.059038 -310.455564) (xy 72.047862 -310.4515)
			(xy 72.035924 -310.453024) (xy 72.02694 -310.454007) (xy 72.008894 -310.455023) (xy 71.999856 -310.455056)
			(xy 71.974599 -310.454531) (xy 71.924775 -310.446211) (xy 71.877 -310.429803) (xy 71.832576 -310.405757)
			(xy 71.792716 -310.374727) (xy 71.758507 -310.33756) (xy 71.73088 -310.29527) (xy 71.710591 -310.24901)
			(xy 71.698192 -310.200042) (xy 71.69402 -310.1497) (xy 71.698192 -310.099358) (xy 71.710591 -310.05039)
			(xy 71.73088 -310.00413) (xy 71.758507 -309.96184) (xy 71.792716 -309.924673) (xy 71.832576 -309.893643)
			(xy 71.877 -309.869597) (xy 71.924775 -309.853189) (xy 71.974599 -309.844869) (xy 71.999856 -309.84444)
			(xy 72.013911 -309.844646) (xy 72.041896 -309.847315) (xy 72.055736 -309.849774) (xy 72.056244 -309.849774)
			(xy 72.068477 -309.851274) (xy 72.091975 -309.843975) (xy 72.101202 -309.835804) (xy 72.160638 -309.776368)
			(xy 72.16372 -309.773232) (xy 72.168831 -309.766077) (xy 72.170798 -309.762144) (xy 72.173338 -309.75554)
			(xy 72.177148 -309.743348) (xy 72.176132 -309.738522) (xy 72.171491 -309.714433) (xy 72.169055 -309.665438)
			(xy 72.174484 -309.616685) (xy 72.18764 -309.569427) (xy 72.208184 -309.52488) (xy 72.235586 -309.484192)
			(xy 72.269142 -309.44841) (xy 72.307988 -309.418453) (xy 72.329294 -309.40629) (xy 72.33749 -309.401369)
			(xy 72.349755 -309.386724) (xy 72.355809 -309.368605) (xy 72.35571 -309.359046) (xy 72.355202 -309.348378)
			(xy 72.361044 -309.348124) (xy 72.37476 -309.333646) (xy 72.381102 -309.326377) (xy 72.388273 -309.308485)
			(xy 72.38873 -309.298848) (xy 72.38873 -309.052214) (xy 72.387968 -309.044086) (xy 72.385345 -309.033192)
			(xy 72.372306 -309.015) (xy 72.362822 -309.009034) (xy 72.357488 -309.007002) (xy 72.334 -308.996632)
			(xy 72.290587 -308.969223) (xy 72.252364 -308.934947) (xy 72.220404 -308.894767) (xy 72.195606 -308.849812)
			(xy 72.178667 -308.801347) (xy 72.170063 -308.750732) (xy 72.169528 -308.725062) (xy 72.169528 -308.724554)
			(xy 72.170051 -308.69888) (xy 72.17863 -308.648254) (xy 72.195556 -308.599775) (xy 72.220351 -308.554811)
			(xy 72.252318 -308.514627) (xy 72.290555 -308.480355) (xy 72.333986 -308.452962) (xy 72.357488 -308.442614)
			(xy 72.362822 -308.440582) (xy 72.372296 -308.434607) (xy 72.385319 -308.416416) (xy 72.387968 -308.40553)
			(xy 72.38873 -308.397402) (xy 72.38873 -308.102254) (xy 72.387968 -308.094126) (xy 72.385334 -308.08324)
			(xy 72.372286 -308.065067) (xy 72.362822 -308.059074) (xy 72.357488 -308.057042) (xy 72.333998 -308.046673)
			(xy 72.290582 -308.019265) (xy 72.252354 -307.98499) (xy 72.220389 -307.944811) (xy 72.195585 -307.899856)
			(xy 72.17864 -307.85139) (xy 72.17003 -307.800773) (xy 72.169528 -307.775102) (xy 72.169528 -307.774594)
			(xy 72.170047 -307.748918) (xy 72.178621 -307.698287) (xy 72.195543 -307.649804) (xy 72.220336 -307.604834)
			(xy 72.252301 -307.564644) (xy 72.290539 -307.530368) (xy 72.333971 -307.50297) (xy 72.357488 -307.492654)
			(xy 72.362822 -307.490622) (xy 72.372302 -307.48465) (xy 72.385338 -307.466462) (xy 72.387968 -307.45557)
			(xy 72.38873 -307.447442) (xy 72.38873 -307.152294) (xy 72.387968 -307.144166) (xy 72.385341 -307.133275)
			(xy 72.372299 -307.115089) (xy 72.362822 -307.109114) (xy 72.357488 -307.107082) (xy 72.334001 -307.096712)
			(xy 72.29059 -307.069302) (xy 72.252369 -307.035026) (xy 72.220412 -306.994845) (xy 72.195617 -306.949891)
			(xy 72.178681 -306.901425) (xy 72.17008 -306.850811) (xy 72.169528 -306.825142) (xy 72.169528 -306.824634)
			(xy 72.170052 -306.798961) (xy 72.178634 -306.748337) (xy 72.195562 -306.699861) (xy 72.220359 -306.654899)
			(xy 72.252326 -306.614718) (xy 72.290564 -306.580449) (xy 72.333994 -306.553058) (xy 72.357488 -306.542694)
			(xy 72.362822 -306.540662) (xy 72.372307 -306.534693) (xy 72.385356 -306.516508) (xy 72.387968 -306.50561)
			(xy 72.38873 -306.497482) (xy 72.38873 -306.202334) (xy 72.387968 -306.194206) (xy 72.385331 -306.183322)
			(xy 72.372279 -306.165156) (xy 72.362822 -306.159154) (xy 72.357488 -306.157122) (xy 72.333999 -306.146752)
			(xy 72.290584 -306.119344) (xy 72.252359 -306.085069) (xy 72.220397 -306.044889) (xy 72.195596 -305.999934)
			(xy 72.178654 -305.951468) (xy 72.170046 -305.900853) (xy 72.169528 -305.875182) (xy 72.169528 -305.874674)
			(xy 72.170049 -305.848999) (xy 72.178626 -305.79837) (xy 72.195549 -305.74989) (xy 72.220344 -305.704922)
			(xy 72.25231 -305.664736) (xy 72.290547 -305.630462) (xy 72.333979 -305.603066) (xy 72.357488 -305.592734)
			(xy 72.362822 -305.590702) (xy 72.372299 -305.584729) (xy 72.385328 -305.566539) (xy 72.387968 -305.55565)
			(xy 72.38873 -305.547522) (xy 72.38873 -305.25339) (xy 72.388222 -305.246532) (xy 72.385682 -305.236118)
			(xy 72.38228 -305.227777) (xy 72.370703 -305.213987) (xy 72.363076 -305.209194) (xy 72.358504 -305.207162)
			(xy 72.3349 -305.196842) (xy 72.291254 -305.169482) (xy 72.252814 -305.13519) (xy 72.220667 -305.094939)
			(xy 72.195725 -305.049868) (xy 72.178693 -305.001253) (xy 72.170054 -304.95047) (xy 72.169528 -304.924714)
			(xy 72.169973 -304.900721) (xy 72.177478 -304.853326) (xy 72.192306 -304.807689) (xy 72.214091 -304.764933)
			(xy 72.242297 -304.726113) (xy 72.27623 -304.692183) (xy 72.315052 -304.66398) (xy 72.357809 -304.642198)
			(xy 72.403448 -304.627373) (xy 72.450843 -304.619871) (xy 72.474836 -304.619406) (xy 72.47509 -304.619406)
			(xy 72.494612 -304.619718) (xy 72.533337 -304.624688) (xy 72.552306 -304.629312) (xy 72.558656 -304.63109)
			(xy 72.573642 -304.63109) (xy 72.583517 -304.630625) (xy 72.601808 -304.623175) (xy 72.609202 -304.616612)
			(xy 72.942704 -304.28311) (xy 72.950102 -304.276263) (xy 72.9687 -304.268529) (xy 72.978772 -304.268124)
			(xy 73.065894 -304.268124) (xy 73.074625 -304.267776) (xy 73.091068 -304.261899) (xy 73.104551 -304.250803)
			(xy 73.109328 -304.243486) (xy 73.13168 -304.206148) (xy 73.13168 -304.20564) (xy 73.149206 -304.17643)
			(xy 73.15188 -304.170959) (xy 73.154836 -304.159148) (xy 73.155048 -304.153062) (xy 73.155048 -304.124614)
			(xy 73.15327 -304.116994) (xy 73.151492 -304.11166) (xy 73.149968 -304.108104) (xy 73.14027 -304.087227)
			(xy 73.126576 -304.043279) (xy 73.119653 -303.99777) (xy 73.119234 -303.974754) (xy 73.119234 -303.96942)
			(xy 73.119996 -303.955704) (xy 73.122111 -303.930182) (xy 73.133784 -303.880321) (xy 73.153615 -303.833108)
			(xy 73.181047 -303.789866) (xy 73.215312 -303.75181) (xy 73.255448 -303.720006) (xy 73.300328 -303.695347)
			(xy 73.348695 -303.678525) (xy 73.399191 -303.67001) (xy 73.424796 -303.669446) (xy 73.425558 -303.669446)
			(xy 73.439545 -303.669591) (xy 73.467402 -303.672135) (xy 73.481184 -303.674526) (xy 73.493376 -303.676812)
			(xy 73.504806 -303.673256) (xy 73.509008 -303.671953) (xy 73.516925 -303.668123) (xy 73.520554 -303.665636)
			(xy 73.526396 -303.660556) (xy 73.585832 -303.60112) (xy 73.593981 -303.59188) (xy 73.601285 -303.568392)
			(xy 73.599802 -303.556162) (xy 73.599802 -303.555654) (xy 73.597337 -303.541815) (xy 73.59467 -303.51383)
			(xy 73.594468 -303.499774) (xy 73.59499 -303.474519) (xy 73.603303 -303.424697) (xy 73.619704 -303.376923)
			(xy 73.643745 -303.3325) (xy 73.674769 -303.29264) (xy 73.711931 -303.25843) (xy 73.754217 -303.230804)
			(xy 73.800473 -303.210514) (xy 73.849438 -303.198114) (xy 73.899776 -303.193943) (xy 73.950114 -303.198114)
			(xy 73.999079 -303.210514) (xy 74.045335 -303.230804) (xy 74.087621 -303.25843) (xy 74.124783 -303.29264)
			(xy 74.155807 -303.3325) (xy 74.179848 -303.376923) (xy 74.196249 -303.424697) (xy 74.204562 -303.474519)
			(xy 74.205084 -303.499774) (xy 74.204391 -303.52861) (xy 74.193521 -303.58525) (xy 74.183494 -303.612296)
			(xy 74.183494 -303.612804) (xy 74.1807 -303.621694) (xy 74.177906 -303.636426) (xy 74.178399 -303.64643)
			(xy 74.186063 -303.664912) (xy 74.200215 -303.679055) (xy 74.218702 -303.686708) (xy 74.228706 -303.687226)
			(xy 74.248264 -303.683162) (xy 74.252328 -303.681384) (xy 74.252836 -303.681384) (xy 74.257154 -303.679606)
			(xy 74.289949 -303.654915) (xy 74.359007 -303.610521) (xy 74.431563 -303.572108) (xy 74.507099 -303.539951)
			(xy 74.545952 -303.526698) (xy 74.544682 -303.499774) (xy 74.545155 -303.475784) (xy 74.552664 -303.428395)
			(xy 74.567493 -303.382764) (xy 74.589278 -303.340014) (xy 74.617482 -303.301198) (xy 74.65141 -303.267271)
			(xy 74.690227 -303.23907) (xy 74.732978 -303.217287) (xy 74.77861 -303.20246) (xy 74.826 -303.194953)
			(xy 74.84999 -303.194466) (xy 74.876145 -303.19501) (xy 74.927688 -303.203934) (xy 74.976958 -303.221506)
			(xy 75.022516 -303.247213) (xy 75.063029 -303.280303) (xy 75.097315 -303.31981) (xy 75.124372 -303.364579)
			(xy 75.143409 -303.413302) (xy 75.149202 -303.438814) (xy 75.152249 -303.450408) (xy 75.167096 -303.469192)
			(xy 75.17765 -303.474882) (xy 75.18206 -303.4768) (xy 75.191397 -303.479093) (xy 75.196192 -303.479454)
			(xy 75.226272 -303.48138) (xy 75.286133 -303.488498) (xy 75.315826 -303.493678) (xy 75.320369 -303.494408)
			(xy 75.329571 -303.494408) (xy 75.334114 -303.493678) (xy 75.363808 -303.488503) (xy 75.423668 -303.481386)
			(xy 75.453748 -303.479454) (xy 75.45854 -303.479077) (xy 75.467872 -303.476777) (xy 75.47229 -303.474882)
			(xy 75.48292 -303.469282) (xy 75.497797 -303.45046) (xy 75.500738 -303.438814) (xy 75.506484 -303.413288)
			(xy 75.525508 -303.364552) (xy 75.552561 -303.319772) (xy 75.586852 -303.280259) (xy 75.627377 -303.24717)
			(xy 75.672949 -303.221473) (xy 75.722235 -303.203921) (xy 75.773791 -303.195028) (xy 75.79995 -303.194466)
			(xy 75.823939 -303.19494) (xy 75.871327 -303.202452) (xy 75.916956 -303.217284) (xy 75.959703 -303.23907)
			(xy 75.998517 -303.267274) (xy 76.032442 -303.301201) (xy 76.060643 -303.340017) (xy 76.082425 -303.382767)
			(xy 76.097253 -303.428397) (xy 76.104762 -303.475785) (xy 76.105258 -303.499774) (xy 76.103988 -303.526698)
			(xy 76.149342 -303.542232) (xy 76.237015 -303.581027) (xy 76.320441 -303.62827) (xy 76.398807 -303.683501)
			(xy 76.435458 -303.714404) (xy 76.440792 -303.718468) (xy 76.4413 -303.718722) (xy 76.45902 -303.730652)
			(xy 76.491259 -303.758678) (xy 76.51928 -303.790922) (xy 76.531216 -303.808638) (xy 76.53528 -303.813972)
			(xy 76.535534 -303.814226) (xy 76.5556 -303.83861) (xy 76.559156 -303.84242) (xy 76.559664 -303.842928)
			(xy 76.566582 -303.849197) (xy 76.583646 -303.856736) (xy 76.592938 -303.85766) (xy 76.910946 -303.85766)
			(xy 76.916534 -303.857406) (xy 76.920402 -303.856906) (xy 76.927928 -303.854862) (xy 76.93152 -303.853342)
			(xy 76.937362 -303.850294) (xy 76.949046 -303.843182) (xy 76.950316 -303.840896) (xy 76.961444 -303.819195)
			(xy 76.989532 -303.779331) (xy 77.023595 -303.744434) (xy 77.062768 -303.71539) (xy 77.106056 -303.692936)
			(xy 77.152361 -303.677641) (xy 77.200507 -303.669895) (xy 77.22489 -303.669446) (xy 77.248812 -303.669904)
			(xy 77.296072 -303.677356) (xy 77.341589 -303.692095) (xy 77.384248 -303.713759) (xy 77.423001 -303.741817)
			(xy 77.456898 -303.77558) (xy 77.485109 -303.814222) (xy 77.496416 -303.835308) (xy 77.496924 -303.835816)
			(xy 77.500734 -303.843182) (xy 77.512418 -303.850294) (xy 77.51826 -303.853342) (xy 77.521856 -303.854848)
			(xy 77.529382 -303.856882) (xy 77.533246 -303.857406) (xy 77.538834 -303.85766) (xy 77.860906 -303.85766)
			(xy 77.866494 -303.857406) (xy 77.870363 -303.856909) (xy 77.877891 -303.85487) (xy 77.88148 -303.853342)
			(xy 77.887322 -303.850294) (xy 77.899006 -303.843182) (xy 77.900276 -303.840896) (xy 77.911405 -303.819198)
			(xy 77.939495 -303.77934) (xy 77.973559 -303.74445) (xy 78.012733 -303.715413) (xy 78.056021 -303.692967)
			(xy 78.102325 -303.677681) (xy 78.150469 -303.669944) (xy 78.17485 -303.669446) (xy 78.19877 -303.669908)
			(xy 78.246024 -303.677368) (xy 78.291534 -303.692113) (xy 78.334185 -303.713781) (xy 78.37293 -303.741842)
			(xy 78.406821 -303.775607) (xy 78.435025 -303.814247) (xy 78.446376 -303.835308) (xy 78.446884 -303.835816)
			(xy 78.450694 -303.843182) (xy 78.462378 -303.850294) (xy 78.46822 -303.853342) (xy 78.471816 -303.85485)
			(xy 78.479341 -303.856891) (xy 78.483206 -303.857406) (xy 78.488794 -303.85766) (xy 78.810866 -303.85766)
			(xy 78.816454 -303.857406) (xy 78.820322 -303.856905) (xy 78.827846 -303.854857) (xy 78.83144 -303.853342)
			(xy 78.837282 -303.850294) (xy 78.848966 -303.843182) (xy 78.850236 -303.840896) (xy 78.861364 -303.819196)
			(xy 78.889453 -303.779334) (xy 78.923516 -303.74444) (xy 78.962689 -303.715398) (xy 79.005978 -303.692946)
			(xy 79.052282 -303.677654) (xy 79.100428 -303.669911) (xy 79.12481 -303.669446) (xy 79.148677 -303.669907)
			(xy 79.195829 -303.677333) (xy 79.241252 -303.692004) (xy 79.28384 -303.713562) (xy 79.322556 -303.741483)
			(xy 79.356457 -303.775085) (xy 79.384719 -303.813553) (xy 79.396082 -303.834546) (xy 79.39659 -303.835054)
			(xy 79.400908 -303.843436) (xy 79.412846 -303.850548) (xy 79.418688 -303.853596) (xy 79.423488 -303.855486)
			(xy 79.433597 -303.857535) (xy 79.438754 -303.85766) (xy 79.760826 -303.85766) (xy 79.766414 -303.857406)
			(xy 79.770282 -303.856908) (xy 79.77781 -303.854866) (xy 79.7814 -303.853342) (xy 79.787242 -303.850294)
			(xy 79.798926 -303.843182) (xy 79.800196 -303.840896) (xy 79.811325 -303.819199) (xy 79.839416 -303.779343)
			(xy 79.873481 -303.744455) (xy 79.912655 -303.71542) (xy 79.955943 -303.692977) (xy 80.002246 -303.677694)
			(xy 80.05039 -303.66996) (xy 80.07477 -303.669446) (xy 80.098689 -303.66991) (xy 80.145941 -303.677372)
			(xy 80.191449 -303.692119) (xy 80.234097 -303.713789) (xy 80.27284 -303.74185) (xy 80.306728 -303.775615)
			(xy 80.33493 -303.814256) (xy 80.346296 -303.835308) (xy 80.346804 -303.835816) (xy 80.350614 -303.843182)
			(xy 80.362298 -303.850294) (xy 80.36814 -303.853342) (xy 80.371736 -303.854849) (xy 80.379262 -303.856887)
			(xy 80.383126 -303.857406) (xy 80.388714 -303.85766) (xy 80.71104 -303.85766) (xy 80.716628 -303.857406)
			(xy 80.720496 -303.856907) (xy 80.728022 -303.854863) (xy 80.731614 -303.853342) (xy 80.737456 -303.850294)
			(xy 80.74914 -303.843182) (xy 80.75041 -303.840896) (xy 80.761539 -303.8192) (xy 80.789631 -303.779345)
			(xy 80.823696 -303.744458) (xy 80.86287 -303.715426) (xy 80.906158 -303.692984) (xy 80.952461 -303.677704)
			(xy 81.000604 -303.669972) (xy 81.024984 -303.669446) (xy 81.048902 -303.669911) (xy 81.096153 -303.677375)
			(xy 81.14166 -303.692124) (xy 81.184306 -303.713794) (xy 81.223047 -303.741856) (xy 81.256933 -303.775621)
			(xy 81.285134 -303.814262) (xy 81.29651 -303.835308) (xy 81.297018 -303.835816) (xy 81.300828 -303.843182)
			(xy 81.312512 -303.850294) (xy 81.318354 -303.853342) (xy 81.32195 -303.854848) (xy 81.329476 -303.856884)
			(xy 81.33334 -303.857406) (xy 81.338928 -303.85766) (xy 81.632298 -303.85766) (xy 81.637886 -303.857406)
			(xy 81.643465 -303.856606) (xy 81.654101 -303.852883) (xy 81.658968 -303.85004) (xy 81.665064 -303.84623)
			(xy 81.674716 -303.835308) (xy 81.67751 -303.829212) (xy 81.689578 -303.805751) (xy 81.720012 -303.762659)
			(xy 81.756894 -303.72494) (xy 81.799292 -303.693546) (xy 81.846131 -303.669273) (xy 81.896228 -303.652736)
			(xy 81.948313 -303.644353) (xy 81.97469 -303.643792) (xy 82.924904 -303.643792) (xy 82.949442 -303.644238)
			(xy 82.997981 -303.651482) (xy 83.044918 -303.665812) (xy 83.089227 -303.686913) (xy 83.129935 -303.714322)
			(xy 83.166152 -303.747441) (xy 83.181952 -303.76622) (xy 83.187032 -303.77257) (xy 83.189318 -303.775872)
			(xy 83.192381 -303.779861) (xy 83.199797 -303.786652) (xy 83.20405 -303.789334) (xy 83.215734 -303.796192)
			(xy 83.226656 -303.801018) (xy 83.237578 -303.802796) (xy 83.271614 -303.802796) (xy 83.281266 -303.80178)
			(xy 83.292188 -303.79797) (xy 83.301586 -303.793398) (xy 83.308444 -303.790096) (xy 83.313778 -303.787556)
			(xy 83.318103 -303.785055) (xy 83.325775 -303.778657) (xy 83.329018 -303.774856) (xy 83.329272 -303.774348)
			(xy 83.347974 -303.753797) (xy 83.391424 -303.719171) (xy 83.440407 -303.692949) (xy 83.466686 -303.683924)
			(xy 83.489331 -303.677167) (xy 83.536023 -303.669897) (xy 83.55965 -303.669446) (xy 83.559904 -303.669446)
			(xy 83.585435 -303.669937) (xy 83.635793 -303.678384) (xy 83.684043 -303.695093) (xy 83.72884 -303.719596)
			(xy 83.768936 -303.751213) (xy 83.786472 -303.769776) (xy 83.794016 -303.777288) (xy 83.813435 -303.785955)
			(xy 83.824064 -303.78654) (xy 84.093304 -303.78654) (xy 84.101498 -303.786231) (xy 84.117045 -303.781051)
			(xy 84.123784 -303.77638) (xy 84.129372 -303.771554) (xy 84.756244 -303.144682) (xy 84.758964 -303.141772)
			(xy 84.763558 -303.135266) (xy 84.765388 -303.131728) (xy 84.768436 -303.123854) (xy 84.769584 -303.120082)
			(xy 84.770864 -303.112301) (xy 84.770976 -303.10836) (xy 84.770976 -299.600366) (xy 84.770661 -299.592175)
			(xy 84.765469 -299.576636) (xy 84.760816 -299.569886) (xy 84.75599 -299.564298) (xy 84.0105 -298.818808)
			(xy 84.003986 -298.812723) (xy 83.98785 -298.805176) (xy 83.979004 -298.804076) (xy 83.946693 -298.800577)
			(xy 83.883357 -298.786009) (xy 83.822546 -298.763081) (xy 83.765357 -298.732207) (xy 83.712824 -298.693944)
			(xy 83.665895 -298.648985) (xy 83.625417 -298.598139) (xy 83.592121 -298.542326) (xy 83.566608 -298.482553)
			(xy 83.549339 -298.419899) (xy 83.540626 -298.355495) (xy 83.540092 -298.323) (xy 83.540609 -298.291369)
			(xy 83.548866 -298.228649) (xy 83.565239 -298.167543) (xy 83.589449 -298.109097) (xy 83.621079 -298.054312)
			(xy 83.65959 -298.004123) (xy 83.704323 -297.95939) (xy 83.754512 -297.920879) (xy 83.809297 -297.889249)
			(xy 83.867743 -297.865039) (xy 83.928849 -297.848666) (xy 83.991569 -297.840409) (xy 84.0232 -297.839892)
			(xy 84.197698 -297.839892) (xy 84.22933 -297.840409) (xy 84.292053 -297.848663) (xy 84.353163 -297.865031)
			(xy 84.411615 -297.889232) (xy 84.46641 -297.920853) (xy 84.51661 -297.959353) (xy 84.539328 -297.98137)
			(xy 84.684362 -298.126404) (xy 84.691688 -298.133198) (xy 84.710106 -298.140902) (xy 84.73007 -298.140946)
			(xy 84.73948 -298.13758) (xy 84.746592 -298.134786) (xy 84.758276 -298.125134) (xy 84.762594 -298.118784)
			(xy 84.76646 -298.112455) (xy 84.770722 -298.098256) (xy 84.770976 -298.090844) (xy 84.770976 -298.082208)
			(xy 84.769706 -298.071032) (xy 84.769706 -298.070778) (xy 84.768944 -298.068746) (xy 84.768944 -298.068238)
			(xy 84.76146 -298.041361) (xy 84.753421 -297.986153) (xy 84.753427 -297.930363) (xy 84.761478 -297.875156)
			(xy 84.768944 -297.848274) (xy 84.770976 -297.841162) (xy 84.770976 -296.304208) (xy 84.769706 -296.293032)
			(xy 84.769706 -296.292778) (xy 84.768944 -296.290746) (xy 84.768944 -296.290238) (xy 84.76146 -296.263361)
			(xy 84.753421 -296.208153) (xy 84.753427 -296.152363) (xy 84.761478 -296.097156) (xy 84.768944 -296.070274)
			(xy 84.770976 -296.063162) (xy 84.770976 -295.810178) (xy 84.769706 -295.799002) (xy 84.765896 -295.78808)
			(xy 84.753958 -295.76395) (xy 84.747608 -295.755822) (xy 84.74456 -295.753028) (xy 84.742274 -295.75125)
			(xy 84.735416 -295.745408) (xy 84.734654 -295.744646) (xy 84.72805 -295.739058) (xy 84.725002 -295.73601)
			(xy 84.700837 -295.713056) (xy 84.658417 -295.661649) (xy 84.62347 -295.604897) (xy 84.596661 -295.543877)
			(xy 84.5785 -295.47975) (xy 84.569331 -295.413735) (xy 84.568792 -295.38041) (xy 84.569308 -295.348778)
			(xy 84.577561 -295.286054) (xy 84.593928 -295.224943) (xy 84.618129 -295.166491) (xy 84.64975 -295.111695)
			(xy 84.68825 -295.061494) (xy 84.71027 -295.03878) (xy 84.75599 -294.993314) (xy 84.756752 -294.992552)
			(xy 84.762141 -294.98656) (xy 84.769132 -294.972051) (xy 84.770468 -294.964104) (xy 84.770976 -294.957246)
			(xy 84.770976 -283.403548) (xy 84.770643 -283.394944) (xy 84.764932 -283.378712) (xy 84.7598 -283.371798)
			(xy 84.759292 -283.37129) (xy 84.756752 -283.36875) (xy 84.75345 -283.36494) (xy 83.34756 -281.95905)
			(xy 83.344512 -281.956256) (xy 83.335876 -281.950414) (xy 83.324192 -281.945842) (xy 83.301736 -281.939622)
			(xy 83.25889 -281.92131) (xy 83.219326 -281.896698) (xy 83.183962 -281.866359) (xy 83.153619 -281.830998)
			(xy 83.129004 -281.791436) (xy 83.110688 -281.748592) (xy 83.104482 -281.726132) (xy 83.104482 -281.725624)
			(xy 83.102521 -281.719232) (xy 83.095823 -281.707665) (xy 83.091274 -281.702764) (xy 82.944462 -281.555952)
			(xy 82.940729 -281.552434) (xy 82.932152 -281.546812) (xy 82.927444 -281.544776) (xy 82.918808 -281.54122)
			(xy 82.874866 -281.54122) (xy 82.865731 -281.542234) (xy 82.849048 -281.54991) (xy 82.842354 -281.556206)
			(xy 82.8421 -281.55646) (xy 82.792062 -281.607514) (xy 82.785249 -281.615128) (xy 82.777787 -281.634128)
			(xy 82.777584 -281.644344) (xy 82.777584 -281.650186) (xy 82.77706 -281.675921) (xy 82.768973 -281.726751)
			(xy 82.753037 -281.775692) (xy 82.729646 -281.82154) (xy 82.699373 -281.863166) (xy 82.662964 -281.899546)
			(xy 82.621315 -281.929787) (xy 82.575449 -281.953143) (xy 82.526496 -281.96904) (xy 82.475659 -281.977088)
			(xy 82.424189 -281.977088) (xy 82.373352 -281.96904) (xy 82.324399 -281.953143) (xy 82.278533 -281.929787)
			(xy 82.236884 -281.899546) (xy 82.200475 -281.863166) (xy 82.170202 -281.82154) (xy 82.146811 -281.775692)
			(xy 82.130875 -281.726751) (xy 82.122788 -281.675921) (xy 82.122264 -281.650186) (xy 82.122264 -281.644344)
			(xy 82.12206 -281.634131) (xy 82.114586 -281.615138) (xy 82.107786 -281.607514) (xy 82.057748 -281.55646)
			(xy 82.057494 -281.556206) (xy 82.050756 -281.549972) (xy 82.034098 -281.542291) (xy 82.024982 -281.54122)
			(xy 81.924906 -281.54122) (xy 81.915776 -281.542244) (xy 81.899108 -281.549934) (xy 81.892394 -281.556206)
			(xy 81.89214 -281.55646) (xy 81.842102 -281.607514) (xy 81.835285 -281.615126) (xy 81.827817 -281.634127)
			(xy 81.827624 -281.644344) (xy 81.827624 -281.650186) (xy 81.8271 -281.675921) (xy 81.819013 -281.726751)
			(xy 81.803077 -281.775692) (xy 81.779686 -281.82154) (xy 81.749413 -281.863166) (xy 81.713004 -281.899546)
			(xy 81.671355 -281.929787) (xy 81.625489 -281.953143) (xy 81.576536 -281.96904) (xy 81.525699 -281.977088)
			(xy 81.474229 -281.977088) (xy 81.423392 -281.96904) (xy 81.374439 -281.953143) (xy 81.328573 -281.929787)
			(xy 81.286924 -281.899546) (xy 81.250515 -281.863166) (xy 81.220242 -281.82154) (xy 81.196851 -281.775692)
			(xy 81.180915 -281.726751) (xy 81.172828 -281.675921) (xy 81.172304 -281.650186) (xy 81.172304 -281.644344)
			(xy 81.172101 -281.63413) (xy 81.164631 -281.615134) (xy 81.157826 -281.607514) (xy 81.107788 -281.55646)
			(xy 81.107534 -281.556206) (xy 81.100798 -281.549967) (xy 81.084142 -281.542273) (xy 81.075022 -281.54122)
			(xy 80.956658 -281.54122) (xy 80.946503 -281.541669) (xy 80.927774 -281.549531) (xy 80.920336 -281.55646)
			(xy 80.869536 -281.608022) (xy 80.866742 -281.61107) (xy 80.864238 -281.614197) (xy 80.860153 -281.621087)
			(xy 80.858614 -281.624786) (xy 80.854804 -281.634438) (xy 80.855058 -281.644598) (xy 80.855058 -281.649932)
			(xy 80.854536 -281.675187) (xy 80.846223 -281.725009) (xy 80.829822 -281.772783) (xy 80.805781 -281.817206)
			(xy 80.774757 -281.857066) (xy 80.737595 -281.891276) (xy 80.695309 -281.918902) (xy 80.649053 -281.939192)
			(xy 80.600088 -281.951592) (xy 80.54975 -281.955763) (xy 80.499412 -281.951592) (xy 80.450447 -281.939192)
			(xy 80.404191 -281.918902) (xy 80.361905 -281.891276) (xy 80.324743 -281.857066) (xy 80.293719 -281.817206)
			(xy 80.269678 -281.772783) (xy 80.253277 -281.725009) (xy 80.244964 -281.675187) (xy 80.244442 -281.649932)
			(xy 80.244442 -281.644598) (xy 80.244696 -281.634438) (xy 80.240886 -281.624786) (xy 80.239331 -281.621095)
			(xy 80.235248 -281.614206) (xy 80.232758 -281.61107) (xy 80.229964 -281.608022) (xy 80.179164 -281.55646)
			(xy 80.171734 -281.549523) (xy 80.152998 -281.541686) (xy 80.142842 -281.54122) (xy 80.006698 -281.54122)
			(xy 79.996539 -281.541662) (xy 79.9778 -281.549513) (xy 79.970376 -281.55646) (xy 79.919576 -281.608022)
			(xy 79.916782 -281.61107) (xy 79.914276 -281.614196) (xy 79.910188 -281.621085) (xy 79.908654 -281.624786)
			(xy 79.904844 -281.634438) (xy 79.905098 -281.644598) (xy 79.905098 -281.649932) (xy 79.904576 -281.675187)
			(xy 79.896263 -281.725009) (xy 79.879862 -281.772783) (xy 79.855821 -281.817206) (xy 79.824797 -281.857066)
			(xy 79.787635 -281.891276) (xy 79.745349 -281.918902) (xy 79.699093 -281.939192) (xy 79.650128 -281.951592)
			(xy 79.59979 -281.955763) (xy 79.549452 -281.951592) (xy 79.500487 -281.939192) (xy 79.454231 -281.918902)
			(xy 79.411945 -281.891276) (xy 79.374783 -281.857066) (xy 79.343759 -281.817206) (xy 79.319718 -281.772783)
			(xy 79.303317 -281.725009) (xy 79.295004 -281.675187) (xy 79.294482 -281.649932) (xy 79.294482 -281.644598)
			(xy 79.294736 -281.634438) (xy 79.290926 -281.624786) (xy 79.289373 -281.621095) (xy 79.285292 -281.614203)
			(xy 79.282798 -281.61107) (xy 79.280004 -281.608022) (xy 79.229204 -281.55646) (xy 79.221776 -281.549517)
			(xy 79.20304 -281.541665) (xy 79.192882 -281.54122) (xy 79.056484 -281.54122) (xy 79.046326 -281.541664)
			(xy 79.027591 -281.549519) (xy 79.020162 -281.55646) (xy 78.969362 -281.608022) (xy 78.966568 -281.61107)
			(xy 78.964063 -281.614196) (xy 78.959976 -281.621086) (xy 78.95844 -281.624786) (xy 78.95463 -281.634438)
			(xy 78.954884 -281.644598) (xy 78.954884 -281.649932) (xy 78.954362 -281.675187) (xy 78.946049 -281.725009)
			(xy 78.929648 -281.772783) (xy 78.905607 -281.817206) (xy 78.874583 -281.857066) (xy 78.837421 -281.891276)
			(xy 78.795135 -281.918902) (xy 78.748879 -281.939192) (xy 78.699914 -281.951592) (xy 78.649576 -281.955763)
			(xy 78.599238 -281.951592) (xy 78.550273 -281.939192) (xy 78.504017 -281.918902) (xy 78.461731 -281.891276)
			(xy 78.424569 -281.857066) (xy 78.393545 -281.817206) (xy 78.369504 -281.772783) (xy 78.353103 -281.725009)
			(xy 78.34479 -281.675187) (xy 78.344268 -281.649932) (xy 78.344268 -281.644598) (xy 78.344522 -281.634438)
			(xy 78.340712 -281.624786) (xy 78.339158 -281.621095) (xy 78.335077 -281.614204) (xy 78.332584 -281.61107)
			(xy 78.32979 -281.608022) (xy 78.27899 -281.55646) (xy 78.271562 -281.549519) (xy 78.252826 -281.541672)
			(xy 78.242668 -281.54122) (xy 78.106524 -281.54122) (xy 78.096371 -281.541675) (xy 78.077652 -281.549546)
			(xy 78.070202 -281.55646) (xy 78.019402 -281.608022) (xy 78.016608 -281.61107) (xy 78.014101 -281.614195)
			(xy 78.010011 -281.621084) (xy 78.00848 -281.624786) (xy 78.00467 -281.634438) (xy 78.004924 -281.644598)
			(xy 78.004924 -281.649678) (xy 78.004402 -281.674933) (xy 77.996089 -281.724755) (xy 77.979688 -281.772529)
			(xy 77.955647 -281.816952) (xy 77.924623 -281.856812) (xy 77.887461 -281.891022) (xy 77.845175 -281.918648)
			(xy 77.798919 -281.938938) (xy 77.749954 -281.951338) (xy 77.699616 -281.955509) (xy 77.649278 -281.951338)
			(xy 77.600313 -281.938938) (xy 77.554057 -281.918648) (xy 77.511771 -281.891022) (xy 77.474609 -281.856812)
			(xy 77.443585 -281.816952) (xy 77.419544 -281.772529) (xy 77.403143 -281.724755) (xy 77.39483 -281.674933)
			(xy 77.394308 -281.649678) (xy 77.394308 -281.644598) (xy 77.394562 -281.634438) (xy 77.390752 -281.624786)
			(xy 77.389196 -281.621096) (xy 77.385111 -281.614209) (xy 77.382624 -281.61107) (xy 77.37983 -281.608022)
			(xy 77.32903 -281.55646) (xy 77.321604 -281.549513) (xy 77.302868 -281.541651) (xy 77.292708 -281.54122)
			(xy 77.156818 -281.54122) (xy 77.146666 -281.541677) (xy 77.127948 -281.549548) (xy 77.120496 -281.55646)
			(xy 77.069696 -281.608022) (xy 77.066902 -281.61107) (xy 77.064396 -281.614196) (xy 77.060306 -281.621084)
			(xy 77.058774 -281.624786) (xy 77.054964 -281.634438) (xy 77.055218 -281.644598) (xy 77.055218 -281.649932)
			(xy 77.054696 -281.675187) (xy 77.046383 -281.725009) (xy 77.029982 -281.772783) (xy 77.005941 -281.817206)
			(xy 76.974917 -281.857066) (xy 76.937755 -281.891276) (xy 76.895469 -281.918902) (xy 76.849213 -281.939192)
			(xy 76.800248 -281.951592) (xy 76.74991 -281.955763) (xy 76.699572 -281.951592) (xy 76.650607 -281.939192)
			(xy 76.604351 -281.918902) (xy 76.562065 -281.891276) (xy 76.524903 -281.857066) (xy 76.493879 -281.817206)
			(xy 76.469838 -281.772783) (xy 76.453437 -281.725009) (xy 76.445124 -281.675187) (xy 76.444602 -281.649932)
			(xy 76.444602 -281.644598) (xy 76.444856 -281.634438) (xy 76.441046 -281.624786) (xy 76.43949 -281.621096)
			(xy 76.435405 -281.614209) (xy 76.432918 -281.61107) (xy 76.430124 -281.608022) (xy 76.379324 -281.55646)
			(xy 76.371897 -281.549514) (xy 76.353162 -281.541654) (xy 76.343002 -281.54122) (xy 76.206858 -281.54122)
			(xy 76.196703 -281.541669) (xy 76.177974 -281.549531) (xy 76.170536 -281.55646) (xy 76.119736 -281.608022)
			(xy 76.116942 -281.61107) (xy 76.114438 -281.614197) (xy 76.110353 -281.621087) (xy 76.108814 -281.624786)
			(xy 76.105004 -281.634438) (xy 76.105258 -281.644598) (xy 76.105258 -281.649932) (xy 76.104736 -281.675187)
			(xy 76.096423 -281.725009) (xy 76.080022 -281.772783) (xy 76.055981 -281.817206) (xy 76.024957 -281.857066)
			(xy 75.987795 -281.891276) (xy 75.945509 -281.918902) (xy 75.899253 -281.939192) (xy 75.850288 -281.951592)
			(xy 75.79995 -281.955763) (xy 75.749612 -281.951592) (xy 75.700647 -281.939192) (xy 75.654391 -281.918902)
			(xy 75.612105 -281.891276) (xy 75.574943 -281.857066) (xy 75.543919 -281.817206) (xy 75.519878 -281.772783)
			(xy 75.503477 -281.725009) (xy 75.495164 -281.675187) (xy 75.494642 -281.649932) (xy 75.494642 -281.644598)
			(xy 75.494896 -281.634438) (xy 75.491086 -281.624786) (xy 75.489531 -281.621095) (xy 75.485448 -281.614206)
			(xy 75.482958 -281.61107) (xy 75.480164 -281.608022) (xy 75.429364 -281.55646) (xy 75.421934 -281.549523)
			(xy 75.403198 -281.541686) (xy 75.393042 -281.54122) (xy 75.256898 -281.54122) (xy 75.246739 -281.541662)
			(xy 75.228 -281.549513) (xy 75.220576 -281.55646) (xy 75.169776 -281.608022) (xy 75.166982 -281.61107)
			(xy 75.164476 -281.614196) (xy 75.160388 -281.621085) (xy 75.158854 -281.624786) (xy 75.155044 -281.634438)
			(xy 75.155298 -281.644598) (xy 75.155298 -281.649932) (xy 75.154776 -281.675187) (xy 75.146463 -281.725009)
			(xy 75.130062 -281.772783) (xy 75.106021 -281.817206) (xy 75.074997 -281.857066) (xy 75.037835 -281.891276)
			(xy 74.995549 -281.918902) (xy 74.949293 -281.939192) (xy 74.900328 -281.951592) (xy 74.84999 -281.955763)
			(xy 74.799652 -281.951592) (xy 74.750687 -281.939192) (xy 74.704431 -281.918902) (xy 74.662145 -281.891276)
			(xy 74.624983 -281.857066) (xy 74.593959 -281.817206) (xy 74.569918 -281.772783) (xy 74.553517 -281.725009)
			(xy 74.545204 -281.675187) (xy 74.544682 -281.649932) (xy 74.544682 -281.644598) (xy 74.544936 -281.634438)
			(xy 74.541126 -281.624786) (xy 74.539573 -281.621095) (xy 74.535492 -281.614203) (xy 74.532998 -281.61107)
			(xy 74.530204 -281.608022) (xy 74.479404 -281.55646) (xy 74.471976 -281.549517) (xy 74.45324 -281.541665)
			(xy 74.443082 -281.54122) (xy 74.306684 -281.54122) (xy 74.296526 -281.541664) (xy 74.277791 -281.549519)
			(xy 74.270362 -281.55646) (xy 74.219562 -281.608022) (xy 74.216768 -281.61107) (xy 74.214263 -281.614196)
			(xy 74.210176 -281.621086) (xy 74.20864 -281.624786) (xy 74.20483 -281.634438) (xy 74.205084 -281.644598)
			(xy 74.205084 -281.649932) (xy 74.204562 -281.675187) (xy 74.196249 -281.725009) (xy 74.179848 -281.772783)
			(xy 74.155807 -281.817206) (xy 74.124783 -281.857066) (xy 74.087621 -281.891276) (xy 74.045335 -281.918902)
			(xy 73.999079 -281.939192) (xy 73.950114 -281.951592) (xy 73.899776 -281.955763) (xy 73.849438 -281.951592)
			(xy 73.800473 -281.939192) (xy 73.754217 -281.918902) (xy 73.711931 -281.891276) (xy 73.674769 -281.857066)
			(xy 73.643745 -281.817206) (xy 73.619704 -281.772783) (xy 73.603303 -281.725009) (xy 73.59499 -281.675187)
			(xy 73.594468 -281.649932) (xy 73.594468 -281.644598) (xy 73.594722 -281.634438) (xy 73.590912 -281.624786)
			(xy 73.589358 -281.621095) (xy 73.585277 -281.614204) (xy 73.582784 -281.61107) (xy 73.57999 -281.608022)
			(xy 73.52919 -281.55646) (xy 73.521762 -281.549519) (xy 73.503026 -281.541672) (xy 73.492868 -281.54122)
			(xy 73.356724 -281.54122) (xy 73.346571 -281.541675) (xy 73.327852 -281.549546) (xy 73.320402 -281.55646)
			(xy 73.269602 -281.608022) (xy 73.266808 -281.61107) (xy 73.264301 -281.614195) (xy 73.260211 -281.621084)
			(xy 73.25868 -281.624786) (xy 73.25487 -281.634438) (xy 73.255124 -281.644598) (xy 73.255124 -281.649932)
			(xy 73.254602 -281.675187) (xy 73.246289 -281.725009) (xy 73.229888 -281.772783) (xy 73.205847 -281.817206)
			(xy 73.174823 -281.857066) (xy 73.137661 -281.891276) (xy 73.095375 -281.918902) (xy 73.049119 -281.939192)
			(xy 73.000154 -281.951592) (xy 72.949816 -281.955763) (xy 72.899478 -281.951592) (xy 72.850513 -281.939192)
			(xy 72.804257 -281.918902) (xy 72.761971 -281.891276) (xy 72.724809 -281.857066) (xy 72.693785 -281.817206)
			(xy 72.669744 -281.772783) (xy 72.653343 -281.725009) (xy 72.64503 -281.675187) (xy 72.644508 -281.649932)
			(xy 72.644508 -281.644598) (xy 72.644762 -281.634438) (xy 72.640952 -281.624786) (xy 72.639396 -281.621096)
			(xy 72.635311 -281.614209) (xy 72.632824 -281.61107) (xy 72.63003 -281.608022) (xy 72.57923 -281.55646)
			(xy 72.571804 -281.549513) (xy 72.553068 -281.541651) (xy 72.542908 -281.54122) (xy 72.406764 -281.54122)
			(xy 72.396608 -281.541668) (xy 72.377878 -281.549528) (xy 72.370442 -281.55646) (xy 72.319642 -281.608022)
			(xy 72.316848 -281.61107) (xy 72.314344 -281.614197) (xy 72.310258 -281.621087) (xy 72.30872 -281.624786)
			(xy 72.30491 -281.634438) (xy 72.305164 -281.644598) (xy 72.305164 -281.649932) (xy 72.304642 -281.675187)
			(xy 72.296329 -281.725009) (xy 72.279928 -281.772783) (xy 72.255887 -281.817206) (xy 72.224863 -281.857066)
			(xy 72.187701 -281.891276) (xy 72.145415 -281.918902) (xy 72.099159 -281.939192) (xy 72.050194 -281.951592)
			(xy 71.999856 -281.955763) (xy 71.949518 -281.951592) (xy 71.900553 -281.939192) (xy 71.854297 -281.918902)
			(xy 71.812011 -281.891276) (xy 71.774849 -281.857066) (xy 71.743825 -281.817206) (xy 71.719784 -281.772783)
			(xy 71.703383 -281.725009) (xy 71.69507 -281.675187) (xy 71.694548 -281.649932) (xy 71.694548 -281.644598)
			(xy 71.694802 -281.634438) (xy 71.690992 -281.624786) (xy 71.689437 -281.621095) (xy 71.685355 -281.614206)
			(xy 71.682864 -281.61107) (xy 71.68007 -281.608022) (xy 71.62927 -281.55646) (xy 71.62184 -281.549523)
			(xy 71.603104 -281.541683) (xy 71.592948 -281.54122) (xy 71.456804 -281.54122) (xy 71.446645 -281.541661)
			(xy 71.427904 -281.549511) (xy 71.420482 -281.55646) (xy 71.369682 -281.608022) (xy 71.366888 -281.61107)
			(xy 71.364382 -281.614196) (xy 71.360293 -281.621085) (xy 71.35876 -281.624786) (xy 71.35495 -281.634438)
			(xy 71.355204 -281.644598) (xy 71.355204 -281.649932) (xy 71.354682 -281.675187) (xy 71.346369 -281.725009)
			(xy 71.329968 -281.772783) (xy 71.305927 -281.817206) (xy 71.274903 -281.857066) (xy 71.237741 -281.891276)
			(xy 71.195455 -281.918902) (xy 71.149199 -281.939192) (xy 71.100234 -281.951592) (xy 71.049896 -281.955763)
			(xy 70.999558 -281.951592) (xy 70.950593 -281.939192) (xy 70.904337 -281.918902) (xy 70.862051 -281.891276)
			(xy 70.824889 -281.857066) (xy 70.793865 -281.817206) (xy 70.769824 -281.772783) (xy 70.753423 -281.725009)
			(xy 70.74511 -281.675187) (xy 70.744588 -281.649932) (xy 70.744588 -281.644598) (xy 70.744842 -281.634438)
			(xy 70.741032 -281.624786) (xy 70.739479 -281.621094) (xy 70.735399 -281.614203) (xy 70.732904 -281.61107)
			(xy 70.73011 -281.608022) (xy 70.67931 -281.55646) (xy 70.671883 -281.549516) (xy 70.653147 -281.541662)
			(xy 70.642988 -281.54122) (xy 70.506844 -281.54122) (xy 70.49669 -281.541672) (xy 70.477965 -281.549537)
			(xy 70.470522 -281.55646) (xy 70.419722 -281.608022) (xy 70.416928 -281.61107) (xy 70.414425 -281.614197)
			(xy 70.41034 -281.621088) (xy 70.4088 -281.624786) (xy 70.40499 -281.634438) (xy 70.405244 -281.644598)
			(xy 70.405244 -281.649932) (xy 70.404722 -281.675187) (xy 70.396409 -281.725009) (xy 70.380008 -281.772783)
			(xy 70.355967 -281.817206) (xy 70.324943 -281.857066) (xy 70.287781 -281.891276) (xy 70.245495 -281.918902)
			(xy 70.199239 -281.939192) (xy 70.150274 -281.951592) (xy 70.099936 -281.955763) (xy 70.049598 -281.951592)
			(xy 70.000633 -281.939192) (xy 69.954377 -281.918902) (xy 69.912091 -281.891276) (xy 69.874929 -281.857066)
			(xy 69.843905 -281.817206) (xy 69.819864 -281.772783) (xy 69.803463 -281.725009) (xy 69.79515 -281.675187)
			(xy 69.794628 -281.649932) (xy 69.794628 -281.644598) (xy 69.794882 -281.634438) (xy 69.791072 -281.624786)
			(xy 69.789517 -281.621096) (xy 69.785433 -281.614207) (xy 69.782944 -281.61107) (xy 69.78015 -281.608022)
			(xy 69.72935 -281.55646) (xy 69.721925 -281.54951) (xy 69.703189 -281.54164) (xy 69.693028 -281.54122)
			(xy 69.556884 -281.54122) (xy 69.546726 -281.541664) (xy 69.527991 -281.549519) (xy 69.520562 -281.55646)
			(xy 69.469762 -281.608022) (xy 69.466968 -281.61107) (xy 69.464463 -281.614196) (xy 69.460376 -281.621086)
			(xy 69.45884 -281.624786) (xy 69.45503 -281.634438) (xy 69.455284 -281.644598) (xy 69.455284 -281.649932)
			(xy 69.454762 -281.675187) (xy 69.446449 -281.725009) (xy 69.430048 -281.772783) (xy 69.406007 -281.817206)
			(xy 69.374983 -281.857066) (xy 69.337821 -281.891276) (xy 69.295535 -281.918902) (xy 69.249279 -281.939192)
			(xy 69.200314 -281.951592) (xy 69.149976 -281.955763) (xy 69.099638 -281.951592) (xy 69.050673 -281.939192)
			(xy 69.004417 -281.918902) (xy 68.962131 -281.891276) (xy 68.924969 -281.857066) (xy 68.893945 -281.817206)
			(xy 68.869904 -281.772783) (xy 68.853503 -281.725009) (xy 68.84519 -281.675187) (xy 68.844668 -281.649932)
			(xy 68.844668 -281.644598) (xy 68.844922 -281.634438) (xy 68.841112 -281.624786) (xy 68.839558 -281.621095)
			(xy 68.835477 -281.614204) (xy 68.832984 -281.61107) (xy 68.83019 -281.608022) (xy 68.77939 -281.55646)
			(xy 68.771962 -281.549519) (xy 68.753226 -281.541672) (xy 68.743068 -281.54122) (xy 68.60667 -281.54122)
			(xy 68.596514 -281.541667) (xy 68.577782 -281.549526) (xy 68.570348 -281.55646) (xy 68.519548 -281.608022)
			(xy 68.516754 -281.61107) (xy 68.51425 -281.614197) (xy 68.510163 -281.621087) (xy 68.508626 -281.624786)
			(xy 68.504816 -281.634438) (xy 68.50507 -281.644598) (xy 68.50507 -281.649932) (xy 68.504548 -281.675187)
			(xy 68.496235 -281.725009) (xy 68.479834 -281.772783) (xy 68.455793 -281.817206) (xy 68.424769 -281.857066)
			(xy 68.387607 -281.891276) (xy 68.345321 -281.918902) (xy 68.299065 -281.939192) (xy 68.2501 -281.951592)
			(xy 68.199762 -281.955763) (xy 68.149424 -281.951592) (xy 68.100459 -281.939192) (xy 68.054203 -281.918902)
			(xy 68.011917 -281.891276) (xy 67.974755 -281.857066) (xy 67.943731 -281.817206) (xy 67.91969 -281.772783)
			(xy 67.903289 -281.725009) (xy 67.894976 -281.675187) (xy 67.894454 -281.649932) (xy 67.894454 -281.644598)
			(xy 67.894708 -281.634438) (xy 67.890898 -281.624786) (xy 67.889343 -281.621095) (xy 67.885261 -281.614206)
			(xy 67.88277 -281.61107) (xy 67.879976 -281.608022) (xy 67.829176 -281.55646) (xy 67.821747 -281.549522)
			(xy 67.803011 -281.54168) (xy 67.792854 -281.54122) (xy 67.65671 -281.54122) (xy 67.646559 -281.541678)
			(xy 67.627843 -281.549552) (xy 67.620388 -281.55646) (xy 67.569588 -281.608022) (xy 67.566794 -281.61107)
			(xy 67.564288 -281.614196) (xy 67.560199 -281.621085) (xy 67.558666 -281.624786) (xy 67.554856 -281.634438)
			(xy 67.55511 -281.644598) (xy 67.55511 -281.649932) (xy 67.554588 -281.675187) (xy 67.546275 -281.725009)
			(xy 67.529874 -281.772783) (xy 67.505833 -281.817206) (xy 67.474809 -281.857066) (xy 67.437647 -281.891276)
			(xy 67.395361 -281.918902) (xy 67.349105 -281.939192) (xy 67.30014 -281.951592) (xy 67.249802 -281.955763)
			(xy 67.199464 -281.951592) (xy 67.150499 -281.939192) (xy 67.104243 -281.918902) (xy 67.061957 -281.891276)
			(xy 67.024795 -281.857066) (xy 66.993771 -281.817206) (xy 66.96973 -281.772783) (xy 66.953329 -281.725009)
			(xy 66.945016 -281.675187) (xy 66.944494 -281.649932) (xy 66.944494 -281.644598) (xy 66.944748 -281.634438)
			(xy 66.940938 -281.624786) (xy 66.939382 -281.621096) (xy 66.935296 -281.61421) (xy 66.93281 -281.61107)
			(xy 66.930016 -281.608022) (xy 66.879216 -281.55646) (xy 66.871789 -281.549515) (xy 66.853053 -281.541659)
			(xy 66.842894 -281.54122) (xy 66.70675 -281.54122) (xy 66.696595 -281.541671) (xy 66.677869 -281.549534)
			(xy 66.670428 -281.55646) (xy 66.619628 -281.608022) (xy 66.616834 -281.61107) (xy 66.61433 -281.614197)
			(xy 66.610246 -281.621088) (xy 66.608706 -281.624786) (xy 66.604896 -281.634438) (xy 66.60515 -281.644598)
			(xy 66.60515 -281.649932) (xy 66.604628 -281.675187) (xy 66.596315 -281.725009) (xy 66.579914 -281.772783)
			(xy 66.555873 -281.817206) (xy 66.524849 -281.857066) (xy 66.487687 -281.891276) (xy 66.445401 -281.918902)
			(xy 66.399145 -281.939192) (xy 66.35018 -281.951592) (xy 66.299842 -281.955763) (xy 66.249504 -281.951592)
			(xy 66.200539 -281.939192) (xy 66.154283 -281.918902) (xy 66.111997 -281.891276) (xy 66.074835 -281.857066)
			(xy 66.043811 -281.817206) (xy 66.01977 -281.772783) (xy 66.003369 -281.725009) (xy 65.995056 -281.675187)
			(xy 65.994534 -281.649932) (xy 65.994534 -281.644598) (xy 65.994788 -281.634438) (xy 65.990978 -281.624786)
			(xy 65.989423 -281.621096) (xy 65.985339 -281.614207) (xy 65.98285 -281.61107) (xy 65.980056 -281.608022)
			(xy 65.929256 -281.55646) (xy 65.921831 -281.549509) (xy 65.903096 -281.541637) (xy 65.892934 -281.54122)
			(xy 65.75679 -281.54122) (xy 65.746632 -281.541663) (xy 65.727895 -281.549517) (xy 65.720468 -281.55646)
			(xy 65.669668 -281.608022) (xy 65.666874 -281.61107) (xy 65.664369 -281.614196) (xy 65.660281 -281.621086)
			(xy 65.658746 -281.624786) (xy 65.654936 -281.634438) (xy 65.65519 -281.644598) (xy 65.65519 -281.649932)
			(xy 65.654668 -281.675187) (xy 65.646355 -281.725009) (xy 65.629954 -281.772783) (xy 65.605913 -281.817206)
			(xy 65.574889 -281.857066) (xy 65.537727 -281.891276) (xy 65.495441 -281.918902) (xy 65.449185 -281.939192)
			(xy 65.40022 -281.951592) (xy 65.349882 -281.955763) (xy 65.299544 -281.951592) (xy 65.250579 -281.939192)
			(xy 65.204323 -281.918902) (xy 65.162037 -281.891276) (xy 65.124875 -281.857066) (xy 65.093851 -281.817206)
			(xy 65.06981 -281.772783) (xy 65.053409 -281.725009) (xy 65.045096 -281.675187) (xy 65.044574 -281.649932)
			(xy 65.044574 -281.644598) (xy 65.044828 -281.634438) (xy 65.041018 -281.624786) (xy 65.039464 -281.621095)
			(xy 65.035383 -281.614204) (xy 65.03289 -281.61107) (xy 65.030096 -281.608022) (xy 64.979296 -281.55646)
			(xy 64.971868 -281.549518) (xy 64.953132 -281.541669) (xy 64.942974 -281.54122) (xy 64.80683 -281.54122)
			(xy 64.796677 -281.541674) (xy 64.777956 -281.549543) (xy 64.770508 -281.55646) (xy 64.719708 -281.608022)
			(xy 64.716914 -281.61107) (xy 64.714411 -281.614198) (xy 64.710328 -281.621089) (xy 64.708786 -281.624786)
			(xy 64.704976 -281.634438) (xy 64.70523 -281.644598) (xy 64.70523 -281.649932) (xy 64.704708 -281.675187)
			(xy 64.696395 -281.725009) (xy 64.679994 -281.772783) (xy 64.655953 -281.817206) (xy 64.624929 -281.857066)
			(xy 64.587767 -281.891276) (xy 64.545481 -281.918902) (xy 64.499225 -281.939192) (xy 64.45026 -281.951592)
			(xy 64.399922 -281.955763) (xy 64.349584 -281.951592) (xy 64.300619 -281.939192) (xy 64.254363 -281.918902)
			(xy 64.212077 -281.891276) (xy 64.174915 -281.857066) (xy 64.143891 -281.817206) (xy 64.11985 -281.772783)
			(xy 64.103449 -281.725009) (xy 64.095136 -281.675187) (xy 64.094614 -281.649932) (xy 64.094614 -281.644598)
			(xy 64.094868 -281.634438) (xy 64.091058 -281.624786) (xy 64.089502 -281.621096) (xy 64.085418 -281.614208)
			(xy 64.08293 -281.61107) (xy 64.080136 -281.608022) (xy 64.029336 -281.55646) (xy 64.02191 -281.549512)
			(xy 64.003174 -281.541648) (xy 63.993014 -281.54122) (xy 63.85687 -281.54122) (xy 63.846714 -281.541667)
			(xy 63.827982 -281.549526) (xy 63.820548 -281.55646) (xy 63.769748 -281.608022) (xy 63.766954 -281.61107)
			(xy 63.76445 -281.614197) (xy 63.760363 -281.621087) (xy 63.758826 -281.624786) (xy 63.755016 -281.634438)
			(xy 63.75527 -281.644598) (xy 63.75527 -281.649932) (xy 63.754748 -281.675187) (xy 63.746435 -281.725009)
			(xy 63.730034 -281.772783) (xy 63.705993 -281.817206) (xy 63.674969 -281.857066) (xy 63.637807 -281.891276)
			(xy 63.595521 -281.918902) (xy 63.549265 -281.939192) (xy 63.5003 -281.951592) (xy 63.449962 -281.955763)
			(xy 63.399624 -281.951592) (xy 63.350659 -281.939192) (xy 63.304403 -281.918902) (xy 63.262117 -281.891276)
			(xy 63.224955 -281.857066) (xy 63.193931 -281.817206) (xy 63.16989 -281.772783) (xy 63.153489 -281.725009)
			(xy 63.145176 -281.675187) (xy 63.144654 -281.649932) (xy 63.144654 -281.644598) (xy 63.144908 -281.634438)
			(xy 63.141098 -281.624786) (xy 63.139543 -281.621095) (xy 63.135461 -281.614206) (xy 63.13297 -281.61107)
			(xy 63.130176 -281.608022) (xy 63.079376 -281.55646) (xy 63.071947 -281.549522) (xy 63.053211 -281.54168)
			(xy 63.043054 -281.54122) (xy 62.906656 -281.54122) (xy 62.896501 -281.54167) (xy 62.877773 -281.549532)
			(xy 62.870334 -281.55646) (xy 62.819534 -281.608022) (xy 62.81674 -281.61107) (xy 62.814236 -281.614197)
			(xy 62.810151 -281.621088) (xy 62.808612 -281.624786) (xy 62.804802 -281.634438) (xy 62.805056 -281.644598)
			(xy 62.805056 -281.649932) (xy 62.804534 -281.675187) (xy 62.796221 -281.725009) (xy 62.77982 -281.772783)
			(xy 62.755779 -281.817206) (xy 62.724755 -281.857066) (xy 62.687593 -281.891276) (xy 62.645307 -281.918902)
			(xy 62.599051 -281.939192) (xy 62.550086 -281.951592) (xy 62.499748 -281.955763) (xy 62.44941 -281.951592)
			(xy 62.400445 -281.939192) (xy 62.354189 -281.918902) (xy 62.311903 -281.891276) (xy 62.274741 -281.857066)
			(xy 62.243717 -281.817206) (xy 62.219676 -281.772783) (xy 62.203275 -281.725009) (xy 62.194962 -281.675187)
			(xy 62.19444 -281.649932) (xy 62.19444 -281.644598) (xy 62.194694 -281.634438) (xy 62.190884 -281.624786)
			(xy 62.189329 -281.621095) (xy 62.185246 -281.614207) (xy 62.182756 -281.61107) (xy 62.179962 -281.608022)
			(xy 62.129162 -281.55646) (xy 62.121732 -281.549524) (xy 62.102996 -281.541687) (xy 62.09284 -281.54122)
			(xy 61.956696 -281.54122) (xy 61.946537 -281.541662) (xy 61.927799 -281.549514) (xy 61.920374 -281.55646)
			(xy 61.869574 -281.608022) (xy 61.86678 -281.61107) (xy 61.864275 -281.614196) (xy 61.860186 -281.621085)
			(xy 61.858652 -281.624786) (xy 61.854842 -281.634438) (xy 61.855096 -281.644598) (xy 61.855096 -281.649932)
			(xy 61.854574 -281.675187) (xy 61.846261 -281.725009) (xy 61.82986 -281.772783) (xy 61.805819 -281.817206)
			(xy 61.774795 -281.857066) (xy 61.737633 -281.891276) (xy 61.695347 -281.918902) (xy 61.649091 -281.939192)
			(xy 61.600126 -281.951592) (xy 61.549788 -281.955763) (xy 61.49945 -281.951592) (xy 61.450485 -281.939192)
			(xy 61.404229 -281.918902) (xy 61.361943 -281.891276) (xy 61.324781 -281.857066) (xy 61.293757 -281.817206)
			(xy 61.269716 -281.772783) (xy 61.253315 -281.725009) (xy 61.245002 -281.675187) (xy 61.24448 -281.649932)
			(xy 61.24448 -281.644598) (xy 61.244734 -281.634438) (xy 61.240924 -281.624786) (xy 61.239371 -281.621095)
			(xy 61.23529 -281.614204) (xy 61.232796 -281.61107) (xy 61.230002 -281.608022) (xy 61.179202 -281.55646)
			(xy 61.171774 -281.549517) (xy 61.153038 -281.541666) (xy 61.14288 -281.54122) (xy 61.006736 -281.54122)
			(xy 60.996582 -281.541673) (xy 60.97786 -281.549541) (xy 60.970414 -281.55646) (xy 60.919614 -281.608022)
			(xy 60.91682 -281.61107) (xy 60.914317 -281.614198) (xy 60.910233 -281.621089) (xy 60.908692 -281.624786)
			(xy 60.904882 -281.634438) (xy 60.905136 -281.644598) (xy 60.905136 -281.649932) (xy 60.904614 -281.675187)
			(xy 60.896301 -281.725009) (xy 60.8799 -281.772783) (xy 60.855859 -281.817206) (xy 60.824835 -281.857066)
			(xy 60.787673 -281.891276) (xy 60.745387 -281.918902) (xy 60.699131 -281.939192) (xy 60.650166 -281.951592)
			(xy 60.599828 -281.955763) (xy 60.54949 -281.951592) (xy 60.500525 -281.939192) (xy 60.454269 -281.918902)
			(xy 60.411983 -281.891276) (xy 60.374821 -281.857066) (xy 60.343797 -281.817206) (xy 60.319756 -281.772783)
			(xy 60.303355 -281.725009) (xy 60.295042 -281.675187) (xy 60.29452 -281.649932) (xy 60.29452 -281.644598)
			(xy 60.294774 -281.634438) (xy 60.290964 -281.624786) (xy 60.289409 -281.621096) (xy 60.285324 -281.614208)
			(xy 60.282836 -281.61107) (xy 60.280042 -281.608022) (xy 60.229242 -281.55646) (xy 60.221816 -281.549511)
			(xy 60.203081 -281.541645) (xy 60.19292 -281.54122) (xy 60.056776 -281.54122) (xy 60.046619 -281.541666)
			(xy 60.027886 -281.549523) (xy 60.020454 -281.55646) (xy 59.969654 -281.608022) (xy 59.96686 -281.61107)
			(xy 59.964355 -281.614197) (xy 59.960269 -281.621086) (xy 59.958732 -281.624786) (xy 59.954922 -281.634438)
			(xy 59.955176 -281.644598) (xy 59.955176 -281.649932) (xy 59.954654 -281.675187) (xy 59.946341 -281.725009)
			(xy 59.92994 -281.772783) (xy 59.905899 -281.817206) (xy 59.874875 -281.857066) (xy 59.837713 -281.891276)
			(xy 59.795427 -281.918902) (xy 59.749171 -281.939192) (xy 59.700206 -281.951592) (xy 59.649868 -281.955763)
			(xy 59.59953 -281.951592) (xy 59.550565 -281.939192) (xy 59.504309 -281.918902) (xy 59.462023 -281.891276)
			(xy 59.424861 -281.857066) (xy 59.393837 -281.817206) (xy 59.369796 -281.772783) (xy 59.353395 -281.725009)
			(xy 59.345082 -281.675187) (xy 59.34456 -281.649932) (xy 59.34456 -281.644598) (xy 59.344814 -281.634438)
			(xy 59.341004 -281.624786) (xy 59.33945 -281.621095) (xy 59.335368 -281.614205) (xy 59.332876 -281.61107)
			(xy 59.330082 -281.608022) (xy 59.279282 -281.55646) (xy 59.271853 -281.549521) (xy 59.253117 -281.541677)
			(xy 59.24296 -281.54122) (xy 59.19978 -281.54122) (xy 59.19342 -281.541381) (xy 59.181081 -281.544461)
			(xy 59.175396 -281.547316) (xy 59.175142 -281.54757) (xy 59.159839 -281.556057) (xy 59.128718 -281.572065)
			(xy 59.112912 -281.579574) (xy 59.101228 -281.587194) (xy 59.097348 -281.590655) (xy 59.090947 -281.598847)
			(xy 59.088528 -281.60345) (xy 59.067446 -281.64409) (xy 59.057032 -281.662378) (xy 59.039604 -281.691602)
			(xy 59.001215 -281.747789) (xy 58.980324 -281.774646) (xy 58.974482 -281.78379) (xy 58.96292 -281.80636)
			(xy 58.933475 -281.847642) (xy 58.897618 -281.883496) (xy 58.856332 -281.912937) (xy 58.833766 -281.924506)
			(xy 58.824622 -281.930348) (xy 58.784855 -281.96106) (xy 58.700051 -282.01496) (xy 58.610093 -282.05973)
			(xy 58.563256 -282.077922) (xy 58.553786 -282.081989) (xy 58.538895 -282.09621) (xy 58.530764 -282.115127)
			(xy 58.530236 -282.12542) (xy 58.529675 -282.150648) (xy 58.521296 -282.200405) (xy 58.504849 -282.248106)
			(xy 58.480784 -282.292455) (xy 58.449754 -282.332243) (xy 58.412604 -282.366388) (xy 58.370346 -282.393959)
			(xy 58.32413 -282.414207) (xy 58.275213 -282.426581) (xy 58.224928 -282.430743) (xy 58.174643 -282.426581)
			(xy 58.125726 -282.414207) (xy 58.07951 -282.393959) (xy 58.037252 -282.366388) (xy 58.000102 -282.332243)
			(xy 57.969072 -282.292455) (xy 57.945007 -282.248106) (xy 57.92856 -282.200405) (xy 57.920181 -282.150648)
			(xy 57.91962 -282.12542) (xy 57.919158 -282.115109) (xy 57.91105 -282.096149) (xy 57.896108 -282.081938)
			(xy 57.8866 -282.077922) (xy 57.847018 -282.062609) (xy 57.770453 -282.025979) (xy 57.733692 -282.00477)
			(xy 57.73293 -282.004516) (xy 57.730898 -282.003246) (xy 57.73039 -282.002992) (xy 57.729628 -282.002484)
			(xy 57.724617 -282.000058) (xy 57.713848 -281.997249) (xy 57.708292 -281.996896) (xy 57.705244 -281.996896)
			(xy 57.701025 -281.99704) (xy 57.692725 -281.998569) (xy 57.688734 -281.999944) (xy 57.680098 -282.004262)
			(xy 57.636156 -282.031694) (xy 57.613296 -282.045918) (xy 57.606946 -282.049982) (xy 57.606184 -282.05049)
			(xy 57.60466 -282.051252) (xy 57.597303 -282.055831) (xy 57.586007 -282.068954) (xy 57.582562 -282.076906)
			(xy 57.580474 -282.082829) (xy 57.578937 -282.09529) (xy 57.579514 -282.101544) (xy 57.579514 -282.103068)
			(xy 57.580276 -282.123388) (xy 57.580276 -282.125928) (xy 57.579729 -282.149865) (xy 57.572095 -282.197131)
			(xy 57.557176 -282.242626) (xy 57.535338 -282.285234) (xy 57.507116 -282.32391) (xy 57.473203 -282.357706)
			(xy 57.434429 -282.385793) (xy 57.391745 -282.407483) (xy 57.346199 -282.422244) (xy 57.298907 -282.429714)
			(xy 57.274968 -282.43022) (xy 57.251092 -282.429756) (xy 57.203923 -282.422317) (xy 57.158488 -282.407625)
			(xy 57.115894 -282.38604) (xy 57.077179 -282.358086) (xy 57.043289 -282.324446) (xy 57.015048 -282.28594)
			(xy 56.993147 -282.243507) (xy 56.978119 -282.198182) (xy 56.97033 -282.151069) (xy 56.96966 -282.127198)
			(xy 56.96966 -282.124404) (xy 56.970422 -282.101544) (xy 56.970676 -282.099766) (xy 56.970676 -282.099258)
			(xy 56.97093 -282.096464) (xy 56.970872 -282.090197) (xy 56.968041 -282.077991) (xy 56.965342 -282.072334)
			(xy 56.962548 -282.066492) (xy 56.957976 -282.061666) (xy 56.947562 -282.05303) (xy 56.86933 -282.004008)
			(xy 56.865964 -282.002258) (xy 56.85882 -281.999704) (xy 56.855106 -281.998928) (xy 56.850314 -281.998114)
			(xy 56.840594 -281.998114) (xy 56.835802 -281.998928) (xy 56.818022 -282.003754) (xy 56.812434 -282.007056)
			(xy 56.788144 -282.021023) (xy 56.7382 -282.046438) (xy 56.712612 -282.057856) (xy 56.663082 -282.077922)
			(xy 56.653608 -282.081985) (xy 56.63871 -282.096205) (xy 56.630574 -282.115124) (xy 56.630062 -282.12542)
			(xy 56.629501 -282.150648) (xy 56.621122 -282.200405) (xy 56.604675 -282.248106) (xy 56.58061 -282.292455)
			(xy 56.54958 -282.332243) (xy 56.51243 -282.366388) (xy 56.470172 -282.393959) (xy 56.423956 -282.414207)
			(xy 56.375039 -282.426581) (xy 56.324754 -282.430743) (xy 56.274469 -282.426581) (xy 56.225552 -282.414207)
			(xy 56.179336 -282.393959) (xy 56.137078 -282.366388) (xy 56.099928 -282.332243) (xy 56.068898 -282.292455)
			(xy 56.044833 -282.248106) (xy 56.028386 -282.200405) (xy 56.020007 -282.150648) (xy 56.019446 -282.12542)
			(xy 56.018984 -282.115107) (xy 56.010879 -282.096144) (xy 55.995939 -282.081927) (xy 55.986426 -282.077922)
			(xy 55.946844 -282.06261) (xy 55.870278 -282.025982) (xy 55.833518 -282.00477) (xy 55.832756 -282.004516)
			(xy 55.830724 -282.003246) (xy 55.830216 -282.002992) (xy 55.829454 -282.002484) (xy 55.824444 -282.000056)
			(xy 55.813675 -281.997241) (xy 55.808118 -281.996896) (xy 55.80507 -281.996896) (xy 55.800851 -281.997038)
			(xy 55.792549 -281.998563) (xy 55.78856 -281.999944) (xy 55.779924 -282.004262) (xy 55.735982 -282.031694)
			(xy 55.713122 -282.045918) (xy 55.706772 -282.049982) (xy 55.70601 -282.05049) (xy 55.704486 -282.051252)
			(xy 55.697127 -282.055829) (xy 55.685824 -282.06895) (xy 55.682388 -282.076906) (xy 55.6803 -282.082829)
			(xy 55.678762 -282.09529) (xy 55.67934 -282.101544) (xy 55.67934 -282.103068) (xy 55.680102 -282.123388)
			(xy 55.680102 -282.125928) (xy 55.679501 -282.151128) (xy 55.671057 -282.20082) (xy 55.654565 -282.24845)
			(xy 55.630475 -282.292724) (xy 55.599439 -282.332441) (xy 55.562302 -282.36652) (xy 55.520072 -282.394037)
			(xy 55.473895 -282.414243) (xy 55.425027 -282.426591) (xy 55.374794 -282.430745) (xy 55.324561 -282.426591)
			(xy 55.275693 -282.414243) (xy 55.229516 -282.394037) (xy 55.187286 -282.36652) (xy 55.150149 -282.332441)
			(xy 55.119113 -282.292724) (xy 55.095023 -282.24845) (xy 55.078531 -282.20082) (xy 55.070087 -282.151128)
			(xy 55.069486 -282.125928) (xy 55.069486 -282.124658) (xy 55.070248 -282.101798) (xy 55.071264 -282.094178)
			(xy 55.070248 -282.08732) (xy 55.06959 -282.083565) (xy 55.06729 -282.076296) (xy 55.065676 -282.072842)
			(xy 55.062374 -282.066238) (xy 55.05196 -282.055316) (xy 55.045356 -282.051506) (xy 54.973728 -282.006802)
			(xy 54.97322 -282.006548) (xy 54.969664 -282.004262) (xy 54.962156 -282.000134) (xy 54.945392 -281.996648)
			(xy 54.928416 -281.998886) (xy 54.920642 -282.002484) (xy 54.916324 -282.00477) (xy 54.914038 -282.00604)
			(xy 54.912514 -282.007056) (xy 54.90083 -282.01366) (xy 54.867566 -282.03209) (xy 54.798651 -282.064259)
			(xy 54.763162 -282.077922) (xy 54.753691 -282.081988) (xy 54.738799 -282.096208) (xy 54.730666 -282.115126)
			(xy 54.730142 -282.12542) (xy 54.729581 -282.150648) (xy 54.721202 -282.200405) (xy 54.704755 -282.248106)
			(xy 54.68069 -282.292455) (xy 54.64966 -282.332243) (xy 54.61251 -282.366388) (xy 54.570252 -282.393959)
			(xy 54.524036 -282.414207) (xy 54.475119 -282.426581) (xy 54.424834 -282.430743) (xy 54.374549 -282.426581)
			(xy 54.325632 -282.414207) (xy 54.279416 -282.393959) (xy 54.237158 -282.366388) (xy 54.200008 -282.332243)
			(xy 54.168978 -282.292455) (xy 54.144913 -282.248106) (xy 54.128466 -282.200405) (xy 54.120087 -282.150648)
			(xy 54.119526 -282.12542) (xy 54.119064 -282.115108) (xy 54.110957 -282.096147) (xy 54.096015 -282.081936)
			(xy 54.086506 -282.077922) (xy 54.046648 -282.062533) (xy 53.969573 -282.025644) (xy 53.932582 -282.004262)
			(xy 53.920136 -281.996896) (xy 53.905658 -281.99715) (xy 53.899427 -281.997361) (xy 53.887351 -282.000444)
			(xy 53.881782 -282.003246) (xy 53.869082 -282.01112) (xy 53.838602 -282.03017) (xy 53.825902 -282.038044)
			(xy 53.817774 -282.043124) (xy 53.806852 -282.049982) (xy 53.80609 -282.05049) (xy 53.804566 -282.051252)
			(xy 53.797209 -282.055831) (xy 53.785911 -282.068953) (xy 53.782468 -282.076906) (xy 53.78038 -282.082829)
			(xy 53.778843 -282.09529) (xy 53.77942 -282.101544) (xy 53.77942 -282.103068) (xy 53.780182 -282.123388)
			(xy 53.780182 -282.125928) (xy 53.779581 -282.151128) (xy 53.771137 -282.20082) (xy 53.754645 -282.24845)
			(xy 53.730555 -282.292724) (xy 53.699519 -282.332441) (xy 53.662382 -282.36652) (xy 53.620152 -282.394037)
			(xy 53.573975 -282.414243) (xy 53.525107 -282.426591) (xy 53.474874 -282.430745) (xy 53.424641 -282.426591)
			(xy 53.375773 -282.414243) (xy 53.329596 -282.394037) (xy 53.287366 -282.36652) (xy 53.250229 -282.332441)
			(xy 53.219193 -282.292724) (xy 53.195103 -282.24845) (xy 53.178611 -282.20082) (xy 53.170167 -282.151128)
			(xy 53.169566 -282.125928) (xy 53.169566 -282.124658) (xy 53.170328 -282.101798) (xy 53.171344 -282.094178)
			(xy 53.170328 -282.08732) (xy 53.169669 -282.083565) (xy 53.167369 -282.076297) (xy 53.165756 -282.072842)
			(xy 53.162454 -282.066238) (xy 53.15204 -282.055316) (xy 53.145436 -282.051506) (xy 53.073808 -282.006802)
			(xy 53.0733 -282.006548) (xy 53.069744 -282.004262) (xy 53.062236 -282.000138) (xy 53.045474 -281.996658)
			(xy 53.028502 -281.998902) (xy 53.020722 -282.002484) (xy 53.016404 -282.00477) (xy 53.014118 -282.00604)
			(xy 53.012594 -282.007056) (xy 53.00091 -282.01366) (xy 52.967646 -282.032089) (xy 52.89873 -282.064257)
			(xy 52.863242 -282.077922) (xy 52.853774 -282.08199) (xy 52.838888 -282.096212) (xy 52.830759 -282.115128)
			(xy 52.830222 -282.12542) (xy 52.829661 -282.150648) (xy 52.821282 -282.200405) (xy 52.804835 -282.248106)
			(xy 52.78077 -282.292455) (xy 52.74974 -282.332243) (xy 52.71259 -282.366388) (xy 52.670332 -282.393959)
			(xy 52.624116 -282.414207) (xy 52.575199 -282.426581) (xy 52.524914 -282.430743) (xy 52.474629 -282.426581)
			(xy 52.425712 -282.414207) (xy 52.379496 -282.393959) (xy 52.337238 -282.366388) (xy 52.300088 -282.332243)
			(xy 52.269058 -282.292455) (xy 52.244993 -282.248106) (xy 52.228546 -282.200405) (xy 52.220167 -282.150648)
			(xy 52.219606 -282.12542) (xy 52.219146 -282.115104) (xy 52.211045 -282.096132) (xy 52.196111 -282.081901)
			(xy 52.186586 -282.077922) (xy 52.146726 -282.062536) (xy 52.069649 -282.025652) (xy 52.032662 -282.004262)
			(xy 52.020216 -281.996896) (xy 52.005738 -281.99715) (xy 51.999508 -281.997363) (xy 51.987434 -282.000451)
			(xy 51.981862 -282.003246) (xy 51.969162 -282.01112) (xy 51.938682 -282.03017) (xy 51.925982 -282.038044)
			(xy 51.917854 -282.043124) (xy 51.906932 -282.049982) (xy 51.90617 -282.05049) (xy 51.904646 -282.051252)
			(xy 51.897291 -282.055833) (xy 51.885997 -282.068956) (xy 51.882548 -282.076906) (xy 51.880461 -282.082829)
			(xy 51.878924 -282.09529) (xy 51.8795 -282.101544) (xy 51.8795 -282.103068) (xy 51.880262 -282.123388)
			(xy 51.880262 -282.125928) (xy 51.879661 -282.151128) (xy 51.871217 -282.20082) (xy 51.854725 -282.24845)
			(xy 51.830635 -282.292724) (xy 51.799599 -282.332441) (xy 51.762462 -282.36652) (xy 51.720232 -282.394037)
			(xy 51.674055 -282.414243) (xy 51.625187 -282.426591) (xy 51.574954 -282.430745) (xy 51.524721 -282.426591)
			(xy 51.475853 -282.414243) (xy 51.429676 -282.394037) (xy 51.387446 -282.36652) (xy 51.350309 -282.332441)
			(xy 51.319273 -282.292724) (xy 51.295183 -282.24845) (xy 51.278691 -282.20082) (xy 51.270247 -282.151128)
			(xy 51.269646 -282.125928) (xy 51.269646 -282.124658) (xy 51.270408 -282.101798) (xy 51.270662 -282.099766)
			(xy 51.270662 -282.095448) (xy 51.270368 -282.088188) (xy 51.26625 -282.074259) (xy 51.262534 -282.068016)
			(xy 51.261264 -282.06573) (xy 51.25847 -282.062682) (xy 51.252628 -282.057094) (xy 51.2445 -282.050744)
			(xy 51.206146 -282.026868) (xy 51.172364 -282.005786) (xy 51.170332 -282.004516) (xy 51.162234 -281.999939)
			(xy 51.143992 -281.996378) (xy 51.125685 -281.999587) (xy 51.1175 -282.004008) (xy 51.080453 -282.025463)
			(xy 51.003248 -282.062472) (xy 50.963322 -282.077922) (xy 50.953857 -282.081993) (xy 50.938976 -282.096216)
			(xy 50.930851 -282.115129) (xy 50.930302 -282.12542) (xy 50.929741 -282.150648) (xy 50.921362 -282.200405)
			(xy 50.904915 -282.248106) (xy 50.88085 -282.292455) (xy 50.84982 -282.332243) (xy 50.81267 -282.366388)
			(xy 50.770412 -282.393959) (xy 50.724196 -282.414207) (xy 50.675279 -282.426581) (xy 50.624994 -282.430743)
			(xy 50.574709 -282.426581) (xy 50.525792 -282.414207) (xy 50.479576 -282.393959) (xy 50.437318 -282.366388)
			(xy 50.400168 -282.332243) (xy 50.369138 -282.292455) (xy 50.345073 -282.248106) (xy 50.328626 -282.200405)
			(xy 50.320247 -282.150648) (xy 50.319686 -282.12542) (xy 50.319229 -282.115582) (xy 50.3118 -282.097364)
			(xy 50.298036 -282.083304) (xy 50.289206 -282.078938) (xy 50.286666 -282.077922) (xy 50.246608 -282.062493)
			(xy 50.169149 -282.025481) (xy 50.13198 -282.004008) (xy 50.126138 -282.000706) (xy 50.114655 -281.99659)
			(xy 50.09037 -281.998434) (xy 50.079656 -282.004262) (xy 50.041302 -282.028392) (xy 50.040794 -282.028392)
			(xy 49.999646 -282.054808) (xy 49.989948 -282.062785) (xy 49.979165 -282.08543) (xy 49.979072 -282.097988)
			(xy 49.979834 -282.10891) (xy 49.980088 -282.123896) (xy 49.980088 -282.124912) (xy 49.979641 -282.148904)
			(xy 49.972133 -282.196297) (xy 49.957303 -282.241932) (xy 49.935516 -282.284685) (xy 49.90731 -282.323503)
			(xy 49.873379 -282.357431) (xy 49.834557 -282.385633) (xy 49.791802 -282.407415) (xy 49.746166 -282.42224)
			(xy 49.698772 -282.429743) (xy 49.67478 -282.43022) (xy 49.65084 -282.429752) (xy 49.603548 -282.422275)
			(xy 49.558002 -282.407508) (xy 49.51532 -282.385812) (xy 49.476548 -282.35772) (xy 49.442636 -282.323919)
			(xy 49.414416 -282.28524) (xy 49.392579 -282.24263) (xy 49.377662 -282.197133) (xy 49.370029 -282.149866)
			(xy 49.369472 -282.125928) (xy 49.369472 -282.124658) (xy 49.370234 -282.101798) (xy 49.37125 -282.094178)
			(xy 49.370234 -282.08732) (xy 49.369575 -282.083565) (xy 49.367275 -282.076297) (xy 49.365662 -282.072842)
			(xy 49.36236 -282.066238) (xy 49.351946 -282.055316) (xy 49.345342 -282.051506) (xy 49.273714 -282.006802)
			(xy 49.273206 -282.006548) (xy 49.26965 -282.004262) (xy 49.262142 -282.000137) (xy 49.245379 -281.996655)
			(xy 49.228406 -281.998897) (xy 49.220628 -282.002484) (xy 49.21631 -282.00477) (xy 49.214024 -282.00604)
			(xy 49.2125 -282.007056) (xy 49.200816 -282.01366) (xy 49.167552 -282.03209) (xy 49.098637 -282.064257)
			(xy 49.063148 -282.077922) (xy 49.053679 -282.08199) (xy 49.038791 -282.096211) (xy 49.030661 -282.115127)
			(xy 49.030128 -282.12542) (xy 49.029567 -282.150648) (xy 49.021188 -282.200405) (xy 49.004741 -282.248106)
			(xy 48.980676 -282.292455) (xy 48.949646 -282.332243) (xy 48.912496 -282.366388) (xy 48.870238 -282.393959)
			(xy 48.824022 -282.414207) (xy 48.775105 -282.426581) (xy 48.72482 -282.430743) (xy 48.674535 -282.426581)
			(xy 48.625618 -282.414207) (xy 48.579402 -282.393959) (xy 48.537144 -282.366388) (xy 48.499994 -282.332243)
			(xy 48.468964 -282.292455) (xy 48.444899 -282.248106) (xy 48.428452 -282.200405) (xy 48.420073 -282.150648)
			(xy 48.419512 -282.12542) (xy 48.419052 -282.115104) (xy 48.410952 -282.096131) (xy 48.396019 -282.081898)
			(xy 48.386492 -282.077922) (xy 48.346632 -282.062536) (xy 48.269554 -282.025653) (xy 48.232568 -282.004262)
			(xy 48.220122 -281.996896) (xy 48.205644 -281.99715) (xy 48.199414 -281.997362) (xy 48.187339 -282.000449)
			(xy 48.181768 -282.003246) (xy 48.169068 -282.01112) (xy 48.138588 -282.03017) (xy 48.125888 -282.038044)
			(xy 48.11776 -282.043124) (xy 48.106838 -282.049982) (xy 48.106076 -282.05049) (xy 48.104552 -282.051252)
			(xy 48.097196 -282.055832) (xy 48.085901 -282.068955) (xy 48.082454 -282.076906) (xy 48.080367 -282.082829)
			(xy 48.07883 -282.09529) (xy 48.079406 -282.101544) (xy 48.079406 -282.103068) (xy 48.080168 -282.123388)
			(xy 48.080168 -282.125928) (xy 48.079567 -282.151128) (xy 48.071123 -282.20082) (xy 48.054631 -282.24845)
			(xy 48.030541 -282.292724) (xy 47.999505 -282.332441) (xy 47.962368 -282.36652) (xy 47.920138 -282.394037)
			(xy 47.873961 -282.414243) (xy 47.825093 -282.426591) (xy 47.77486 -282.430745) (xy 47.724627 -282.426591)
			(xy 47.675759 -282.414243) (xy 47.629582 -282.394037) (xy 47.587352 -282.36652) (xy 47.550215 -282.332441)
			(xy 47.519179 -282.292724) (xy 47.495089 -282.24845) (xy 47.478597 -282.20082) (xy 47.470153 -282.151128)
			(xy 47.469552 -282.125928) (xy 47.469552 -282.124658) (xy 47.470314 -282.101798) (xy 47.47133 -282.094178)
			(xy 47.470314 -282.08732) (xy 47.469655 -282.083565) (xy 47.467354 -282.076297) (xy 47.465742 -282.072842)
			(xy 47.46244 -282.066238) (xy 47.452026 -282.055316) (xy 47.445422 -282.051506) (xy 47.373794 -282.006802)
			(xy 47.373286 -282.006548) (xy 47.36973 -282.004262) (xy 47.362222 -282.00014) (xy 47.345461 -281.996665)
			(xy 47.328492 -281.998912) (xy 47.320708 -282.002484) (xy 47.31639 -282.00477) (xy 47.314104 -282.00604)
			(xy 47.31258 -282.007056) (xy 47.300896 -282.01366) (xy 47.267633 -282.032092) (xy 47.19872 -282.064265)
			(xy 47.163228 -282.077922) (xy 47.153762 -282.081992) (xy 47.13888 -282.096215) (xy 47.130754 -282.115129)
			(xy 47.130208 -282.12542) (xy 47.129675 -282.149971) (xy 47.121731 -282.198427) (xy 47.106131 -282.244987)
			(xy 47.083278 -282.288448) (xy 47.053762 -282.32769) (xy 47.018343 -282.361699) (xy 46.977937 -282.3896)
			(xy 46.933584 -282.410671) (xy 46.88643 -282.424369) (xy 46.837691 -282.430341) (xy 46.788625 -282.428433)
			(xy 46.764448 -282.424124) (xy 46.763686 -282.424124) (xy 46.756066 -282.4226) (xy 46.74489 -282.425902)
			(xy 46.739807 -282.427615) (xy 46.730462 -282.432874) (xy 46.726348 -282.436316) (xy 46.723554 -282.438856)
			(xy 46.663864 -282.498546) (xy 46.655729 -282.507789) (xy 46.648456 -282.531272) (xy 46.649894 -282.543504)
			(xy 46.649894 -282.544012) (xy 46.652347 -282.557789) (xy 46.655017 -282.585646) (xy 46.655228 -282.599638)
			(xy 46.655228 -282.599892) (xy 73.593972 -282.599892) (xy 73.597932 -282.550838) (xy 73.609709 -282.503054)
			(xy 73.629 -282.457778) (xy 73.655303 -282.416182) (xy 73.687938 -282.379345) (xy 73.726059 -282.34822)
			(xy 73.76868 -282.323613) (xy 73.814696 -282.306161) (xy 73.862915 -282.296317) (xy 73.91209 -282.294336)
			(xy 73.960945 -282.300268) (xy 74.008216 -282.31396) (xy 74.052678 -282.335058) (xy 74.093181 -282.363014)
			(xy 74.128674 -282.397106) (xy 74.158239 -282.43645) (xy 74.18111 -282.480027) (xy 74.196694 -282.526708)
			(xy 74.204589 -282.575285) (xy 74.205084 -282.599892) (xy 74.543932 -282.599892) (xy 74.547892 -282.550838)
			(xy 74.559669 -282.503054) (xy 74.57896 -282.457778) (xy 74.605263 -282.416182) (xy 74.637898 -282.379345)
			(xy 74.676019 -282.34822) (xy 74.71864 -282.323613) (xy 74.764656 -282.306161) (xy 74.812875 -282.296317)
			(xy 74.86205 -282.294336) (xy 74.910905 -282.300268) (xy 74.958176 -282.31396) (xy 75.002638 -282.335058)
			(xy 75.043141 -282.363014) (xy 75.078634 -282.397106) (xy 75.108199 -282.43645) (xy 75.13107 -282.480027)
			(xy 75.146654 -282.526708) (xy 75.154549 -282.575285) (xy 75.155044 -282.599892) (xy 75.494146 -282.599892)
			(xy 75.498106 -282.550838) (xy 75.509883 -282.503054) (xy 75.529174 -282.457778) (xy 75.555477 -282.416182)
			(xy 75.588112 -282.379345) (xy 75.626233 -282.34822) (xy 75.668854 -282.323613) (xy 75.71487 -282.306161)
			(xy 75.763089 -282.296317) (xy 75.812264 -282.294336) (xy 75.861119 -282.300268) (xy 75.90839 -282.31396)
			(xy 75.952852 -282.335058) (xy 75.993355 -282.363014) (xy 76.028848 -282.397106) (xy 76.058413 -282.43645)
			(xy 76.081284 -282.480027) (xy 76.096868 -282.526708) (xy 76.104763 -282.575285) (xy 76.105258 -282.599892)
			(xy 76.104763 -282.624499) (xy 76.104584 -282.6256) (xy 76.423262 -282.6256) (xy 76.423262 -282.574184)
			(xy 76.431305 -282.523402) (xy 76.447193 -282.474503) (xy 76.470536 -282.428691) (xy 76.500757 -282.387095)
			(xy 76.537113 -282.350739) (xy 76.578709 -282.320518) (xy 76.624521 -282.297175) (xy 76.67342 -282.281287)
			(xy 76.724202 -282.273244) (xy 76.775618 -282.273244) (xy 76.8264 -282.281287) (xy 76.875299 -282.297175)
			(xy 76.921111 -282.320518) (xy 76.962707 -282.350739) (xy 76.999063 -282.387095) (xy 77.029284 -282.428691)
			(xy 77.052627 -282.474503) (xy 77.068515 -282.523402) (xy 77.076558 -282.574184) (xy 77.077062 -282.599892)
			(xy 77.076558 -282.6256) (xy 77.373222 -282.6256) (xy 77.373222 -282.574184) (xy 77.381265 -282.523402)
			(xy 77.397153 -282.474503) (xy 77.420496 -282.428691) (xy 77.450717 -282.387095) (xy 77.487073 -282.350739)
			(xy 77.528669 -282.320518) (xy 77.574481 -282.297175) (xy 77.62338 -282.281287) (xy 77.674162 -282.273244)
			(xy 77.725578 -282.273244) (xy 77.77636 -282.281287) (xy 77.825259 -282.297175) (xy 77.871071 -282.320518)
			(xy 77.912667 -282.350739) (xy 77.949023 -282.387095) (xy 77.979244 -282.428691) (xy 78.002587 -282.474503)
			(xy 78.018475 -282.523402) (xy 78.026518 -282.574184) (xy 78.027022 -282.599892) (xy 78.344026 -282.599892)
			(xy 78.347986 -282.550838) (xy 78.359763 -282.503054) (xy 78.379054 -282.457778) (xy 78.405357 -282.416182)
			(xy 78.437992 -282.379345) (xy 78.476113 -282.34822) (xy 78.518734 -282.323613) (xy 78.56475 -282.306161)
			(xy 78.612969 -282.296317) (xy 78.662144 -282.294336) (xy 78.710999 -282.300268) (xy 78.75827 -282.31396)
			(xy 78.802732 -282.335058) (xy 78.843235 -282.363014) (xy 78.878728 -282.397106) (xy 78.908293 -282.43645)
			(xy 78.931164 -282.480027) (xy 78.946748 -282.526708) (xy 78.954643 -282.575285) (xy 78.955138 -282.599892)
			(xy 78.954643 -282.624499) (xy 78.954464 -282.6256) (xy 79.273142 -282.6256) (xy 79.273142 -282.574184)
			(xy 79.281185 -282.523402) (xy 79.297073 -282.474503) (xy 79.320416 -282.428691) (xy 79.350637 -282.387095)
			(xy 79.386993 -282.350739) (xy 79.428589 -282.320518) (xy 79.474401 -282.297175) (xy 79.5233 -282.281287)
			(xy 79.574082 -282.273244) (xy 79.625498 -282.273244) (xy 79.67628 -282.281287) (xy 79.725179 -282.297175)
			(xy 79.770991 -282.320518) (xy 79.812587 -282.350739) (xy 79.848943 -282.387095) (xy 79.879164 -282.428691)
			(xy 79.902507 -282.474503) (xy 79.918395 -282.523402) (xy 79.926438 -282.574184) (xy 79.926942 -282.599892)
			(xy 79.926438 -282.6256) (xy 80.223102 -282.6256) (xy 80.223102 -282.574184) (xy 80.231145 -282.523402)
			(xy 80.247033 -282.474503) (xy 80.270376 -282.428691) (xy 80.300597 -282.387095) (xy 80.336953 -282.350739)
			(xy 80.378549 -282.320518) (xy 80.424361 -282.297175) (xy 80.47326 -282.281287) (xy 80.524042 -282.273244)
			(xy 80.575458 -282.273244) (xy 80.62624 -282.281287) (xy 80.675139 -282.297175) (xy 80.720951 -282.320518)
			(xy 80.762547 -282.350739) (xy 80.798903 -282.387095) (xy 80.829124 -282.428691) (xy 80.852467 -282.474503)
			(xy 80.868355 -282.523402) (xy 80.876398 -282.574184) (xy 80.876902 -282.599892) (xy 81.19416 -282.599892)
			(xy 81.19812 -282.550838) (xy 81.209897 -282.503054) (xy 81.229188 -282.457778) (xy 81.255491 -282.416182)
			(xy 81.288126 -282.379345) (xy 81.326247 -282.34822) (xy 81.368868 -282.323613) (xy 81.414884 -282.306161)
			(xy 81.463103 -282.296317) (xy 81.512278 -282.294336) (xy 81.561133 -282.300268) (xy 81.608404 -282.31396)
			(xy 81.652866 -282.335058) (xy 81.693369 -282.363014) (xy 81.728862 -282.397106) (xy 81.758427 -282.43645)
			(xy 81.781298 -282.480027) (xy 81.796882 -282.526708) (xy 81.804777 -282.575285) (xy 81.805272 -282.599892)
			(xy 82.14412 -282.599892) (xy 82.14808 -282.550838) (xy 82.159857 -282.503054) (xy 82.179148 -282.457778)
			(xy 82.205451 -282.416182) (xy 82.238086 -282.379345) (xy 82.276207 -282.34822) (xy 82.318828 -282.323613)
			(xy 82.364844 -282.306161) (xy 82.413063 -282.296317) (xy 82.462238 -282.294336) (xy 82.511093 -282.300268)
			(xy 82.558364 -282.31396) (xy 82.602826 -282.335058) (xy 82.643329 -282.363014) (xy 82.678822 -282.397106)
			(xy 82.708387 -282.43645) (xy 82.731258 -282.480027) (xy 82.746842 -282.526708) (xy 82.754737 -282.575285)
			(xy 82.755232 -282.599892) (xy 82.754737 -282.624499) (xy 82.746842 -282.673076) (xy 82.731258 -282.719757)
			(xy 82.708387 -282.763334) (xy 82.678822 -282.802678) (xy 82.643329 -282.83677) (xy 82.602826 -282.864726)
			(xy 82.558364 -282.885824) (xy 82.511093 -282.899516) (xy 82.462238 -282.905448) (xy 82.413063 -282.903467)
			(xy 82.364844 -282.893623) (xy 82.318828 -282.876171) (xy 82.276207 -282.851564) (xy 82.238086 -282.820439)
			(xy 82.205451 -282.783602) (xy 82.179148 -282.742006) (xy 82.159857 -282.69673) (xy 82.14808 -282.648946)
			(xy 82.14412 -282.599892) (xy 81.805272 -282.599892) (xy 81.804777 -282.624499) (xy 81.796882 -282.673076)
			(xy 81.781298 -282.719757) (xy 81.758427 -282.763334) (xy 81.728862 -282.802678) (xy 81.693369 -282.83677)
			(xy 81.652866 -282.864726) (xy 81.608404 -282.885824) (xy 81.561133 -282.899516) (xy 81.512278 -282.905448)
			(xy 81.463103 -282.903467) (xy 81.414884 -282.893623) (xy 81.368868 -282.876171) (xy 81.326247 -282.851564)
			(xy 81.288126 -282.820439) (xy 81.255491 -282.783602) (xy 81.229188 -282.742006) (xy 81.209897 -282.69673)
			(xy 81.19812 -282.648946) (xy 81.19416 -282.599892) (xy 80.876902 -282.599892) (xy 80.876398 -282.6256)
			(xy 80.868355 -282.676382) (xy 80.852467 -282.725281) (xy 80.829124 -282.771093) (xy 80.798903 -282.812689)
			(xy 80.762547 -282.849045) (xy 80.720951 -282.879266) (xy 80.675139 -282.902609) (xy 80.62624 -282.918497)
			(xy 80.575458 -282.92654) (xy 80.524042 -282.92654) (xy 80.47326 -282.918497) (xy 80.424361 -282.902609)
			(xy 80.378549 -282.879266) (xy 80.336953 -282.849045) (xy 80.300597 -282.812689) (xy 80.270376 -282.771093)
			(xy 80.247033 -282.725281) (xy 80.231145 -282.676382) (xy 80.223102 -282.6256) (xy 79.926438 -282.6256)
			(xy 79.918395 -282.676382) (xy 79.902507 -282.725281) (xy 79.879164 -282.771093) (xy 79.848943 -282.812689)
			(xy 79.812587 -282.849045) (xy 79.770991 -282.879266) (xy 79.725179 -282.902609) (xy 79.67628 -282.918497)
			(xy 79.625498 -282.92654) (xy 79.574082 -282.92654) (xy 79.5233 -282.918497) (xy 79.474401 -282.902609)
			(xy 79.428589 -282.879266) (xy 79.386993 -282.849045) (xy 79.350637 -282.812689) (xy 79.320416 -282.771093)
			(xy 79.297073 -282.725281) (xy 79.281185 -282.676382) (xy 79.273142 -282.6256) (xy 78.954464 -282.6256)
			(xy 78.946748 -282.673076) (xy 78.931164 -282.719757) (xy 78.908293 -282.763334) (xy 78.878728 -282.802678)
			(xy 78.843235 -282.83677) (xy 78.802732 -282.864726) (xy 78.75827 -282.885824) (xy 78.710999 -282.899516)
			(xy 78.662144 -282.905448) (xy 78.612969 -282.903467) (xy 78.56475 -282.893623) (xy 78.518734 -282.876171)
			(xy 78.476113 -282.851564) (xy 78.437992 -282.820439) (xy 78.405357 -282.783602) (xy 78.379054 -282.742006)
			(xy 78.359763 -282.69673) (xy 78.347986 -282.648946) (xy 78.344026 -282.599892) (xy 78.027022 -282.599892)
			(xy 78.026518 -282.6256) (xy 78.018475 -282.676382) (xy 78.002587 -282.725281) (xy 77.979244 -282.771093)
			(xy 77.949023 -282.812689) (xy 77.912667 -282.849045) (xy 77.871071 -282.879266) (xy 77.825259 -282.902609)
			(xy 77.77636 -282.918497) (xy 77.725578 -282.92654) (xy 77.674162 -282.92654) (xy 77.62338 -282.918497)
			(xy 77.574481 -282.902609) (xy 77.528669 -282.879266) (xy 77.487073 -282.849045) (xy 77.450717 -282.812689)
			(xy 77.420496 -282.771093) (xy 77.397153 -282.725281) (xy 77.381265 -282.676382) (xy 77.373222 -282.6256)
			(xy 77.076558 -282.6256) (xy 77.068515 -282.676382) (xy 77.052627 -282.725281) (xy 77.029284 -282.771093)
			(xy 76.999063 -282.812689) (xy 76.962707 -282.849045) (xy 76.921111 -282.879266) (xy 76.875299 -282.902609)
			(xy 76.8264 -282.918497) (xy 76.775618 -282.92654) (xy 76.724202 -282.92654) (xy 76.67342 -282.918497)
			(xy 76.624521 -282.902609) (xy 76.578709 -282.879266) (xy 76.537113 -282.849045) (xy 76.500757 -282.812689)
			(xy 76.470536 -282.771093) (xy 76.447193 -282.725281) (xy 76.431305 -282.676382) (xy 76.423262 -282.6256)
			(xy 76.104584 -282.6256) (xy 76.096868 -282.673076) (xy 76.081284 -282.719757) (xy 76.058413 -282.763334)
			(xy 76.028848 -282.802678) (xy 75.993355 -282.83677) (xy 75.952852 -282.864726) (xy 75.90839 -282.885824)
			(xy 75.861119 -282.899516) (xy 75.812264 -282.905448) (xy 75.763089 -282.903467) (xy 75.71487 -282.893623)
			(xy 75.668854 -282.876171) (xy 75.626233 -282.851564) (xy 75.588112 -282.820439) (xy 75.555477 -282.783602)
			(xy 75.529174 -282.742006) (xy 75.509883 -282.69673) (xy 75.498106 -282.648946) (xy 75.494146 -282.599892)
			(xy 75.155044 -282.599892) (xy 75.154549 -282.624499) (xy 75.146654 -282.673076) (xy 75.13107 -282.719757)
			(xy 75.108199 -282.763334) (xy 75.078634 -282.802678) (xy 75.043141 -282.83677) (xy 75.002638 -282.864726)
			(xy 74.958176 -282.885824) (xy 74.910905 -282.899516) (xy 74.86205 -282.905448) (xy 74.812875 -282.903467)
			(xy 74.764656 -282.893623) (xy 74.71864 -282.876171) (xy 74.676019 -282.851564) (xy 74.637898 -282.820439)
			(xy 74.605263 -282.783602) (xy 74.57896 -282.742006) (xy 74.559669 -282.69673) (xy 74.547892 -282.648946)
			(xy 74.543932 -282.599892) (xy 74.205084 -282.599892) (xy 74.204589 -282.624499) (xy 74.196694 -282.673076)
			(xy 74.18111 -282.719757) (xy 74.158239 -282.763334) (xy 74.128674 -282.802678) (xy 74.093181 -282.83677)
			(xy 74.052678 -282.864726) (xy 74.008216 -282.885824) (xy 73.960945 -282.899516) (xy 73.91209 -282.905448)
			(xy 73.862915 -282.903467) (xy 73.814696 -282.893623) (xy 73.76868 -282.876171) (xy 73.726059 -282.851564)
			(xy 73.687938 -282.820439) (xy 73.655303 -282.783602) (xy 73.629 -282.742006) (xy 73.609709 -282.69673)
			(xy 73.597932 -282.648946) (xy 73.593972 -282.599892) (xy 46.655228 -282.599892) (xy 46.655228 -282.600146)
			(xy 46.655011 -282.614137) (xy 46.652339 -282.641994) (xy 46.649894 -282.655772) (xy 46.649894 -282.65628)
			(xy 46.648403 -282.668511) (xy 46.655711 -282.691999) (xy 46.663864 -282.701238) (xy 46.723554 -282.760928)
			(xy 46.732793 -282.769083) (xy 46.756283 -282.776399) (xy 46.768512 -282.774898) (xy 46.768766 -282.774898)
			(xy 46.782668 -282.77242) (xy 46.81078 -282.769744) (xy 46.8249 -282.769564) (xy 46.849724 -282.77005)
			(xy 46.898717 -282.778082) (xy 46.945765 -282.793935) (xy 46.989629 -282.817191) (xy 47.029152 -282.847236)
			(xy 47.063294 -282.88328) (xy 47.091155 -282.924373) (xy 47.112 -282.969432) (xy 47.125281 -283.01727)
			(xy 47.130647 -283.066627) (xy 47.1302 -283.074872) (xy 47.469056 -283.074872) (xy 47.473016 -283.025818)
			(xy 47.484793 -282.978034) (xy 47.504084 -282.932758) (xy 47.530387 -282.891162) (xy 47.563022 -282.854325)
			(xy 47.601143 -282.8232) (xy 47.643764 -282.798593) (xy 47.68978 -282.781141) (xy 47.737999 -282.771297)
			(xy 47.787174 -282.769316) (xy 47.836029 -282.775248) (xy 47.8833 -282.78894) (xy 47.927762 -282.810038)
			(xy 47.968265 -282.837994) (xy 48.003758 -282.872086) (xy 48.033323 -282.91143) (xy 48.056194 -282.955007)
			(xy 48.071778 -283.001688) (xy 48.079673 -283.050265) (xy 48.080168 -283.074872) (xy 48.419016 -283.074872)
			(xy 48.422976 -283.025818) (xy 48.434753 -282.978034) (xy 48.454044 -282.932758) (xy 48.480347 -282.891162)
			(xy 48.512982 -282.854325) (xy 48.551103 -282.8232) (xy 48.593724 -282.798593) (xy 48.63974 -282.781141)
			(xy 48.687959 -282.771297) (xy 48.737134 -282.769316) (xy 48.785989 -282.775248) (xy 48.83326 -282.78894)
			(xy 48.877722 -282.810038) (xy 48.918225 -282.837994) (xy 48.953718 -282.872086) (xy 48.983283 -282.91143)
			(xy 49.006154 -282.955007) (xy 49.021738 -283.001688) (xy 49.029633 -283.050265) (xy 49.030128 -283.074872)
			(xy 49.368976 -283.074872) (xy 49.372936 -283.025818) (xy 49.384713 -282.978034) (xy 49.404004 -282.932758)
			(xy 49.430307 -282.891162) (xy 49.462942 -282.854325) (xy 49.501063 -282.8232) (xy 49.543684 -282.798593)
			(xy 49.5897 -282.781141) (xy 49.637919 -282.771297) (xy 49.687094 -282.769316) (xy 49.735949 -282.775248)
			(xy 49.78322 -282.78894) (xy 49.827682 -282.810038) (xy 49.868185 -282.837994) (xy 49.903678 -282.872086)
			(xy 49.933243 -282.91143) (xy 49.956114 -282.955007) (xy 49.971698 -283.001688) (xy 49.979593 -283.050265)
			(xy 49.980088 -283.074872) (xy 50.31919 -283.074872) (xy 50.32315 -283.025818) (xy 50.334927 -282.978034)
			(xy 50.354218 -282.932758) (xy 50.380521 -282.891162) (xy 50.413156 -282.854325) (xy 50.451277 -282.8232)
			(xy 50.493898 -282.798593) (xy 50.539914 -282.781141) (xy 50.588133 -282.771297) (xy 50.637308 -282.769316)
			(xy 50.686163 -282.775248) (xy 50.733434 -282.78894) (xy 50.777896 -282.810038) (xy 50.818399 -282.837994)
			(xy 50.853892 -282.872086) (xy 50.883457 -282.91143) (xy 50.906328 -282.955007) (xy 50.921912 -283.001688)
			(xy 50.929807 -283.050265) (xy 50.930302 -283.074872) (xy 51.26915 -283.074872) (xy 51.27311 -283.025818)
			(xy 51.284887 -282.978034) (xy 51.304178 -282.932758) (xy 51.330481 -282.891162) (xy 51.363116 -282.854325)
			(xy 51.401237 -282.8232) (xy 51.443858 -282.798593) (xy 51.489874 -282.781141) (xy 51.538093 -282.771297)
			(xy 51.587268 -282.769316) (xy 51.636123 -282.775248) (xy 51.683394 -282.78894) (xy 51.727856 -282.810038)
			(xy 51.768359 -282.837994) (xy 51.803852 -282.872086) (xy 51.833417 -282.91143) (xy 51.856288 -282.955007)
			(xy 51.871872 -283.001688) (xy 51.879767 -283.050265) (xy 51.880262 -283.074872) (xy 52.21911 -283.074872)
			(xy 52.22307 -283.025818) (xy 52.234847 -282.978034) (xy 52.254138 -282.932758) (xy 52.280441 -282.891162)
			(xy 52.313076 -282.854325) (xy 52.351197 -282.8232) (xy 52.393818 -282.798593) (xy 52.439834 -282.781141)
			(xy 52.488053 -282.771297) (xy 52.537228 -282.769316) (xy 52.586083 -282.775248) (xy 52.633354 -282.78894)
			(xy 52.677816 -282.810038) (xy 52.718319 -282.837994) (xy 52.753812 -282.872086) (xy 52.783377 -282.91143)
			(xy 52.806248 -282.955007) (xy 52.821832 -283.001688) (xy 52.829727 -283.050265) (xy 52.830222 -283.074872)
			(xy 53.16907 -283.074872) (xy 53.17303 -283.025818) (xy 53.184807 -282.978034) (xy 53.204098 -282.932758)
			(xy 53.230401 -282.891162) (xy 53.263036 -282.854325) (xy 53.301157 -282.8232) (xy 53.343778 -282.798593)
			(xy 53.389794 -282.781141) (xy 53.438013 -282.771297) (xy 53.487188 -282.769316) (xy 53.536043 -282.775248)
			(xy 53.583314 -282.78894) (xy 53.627776 -282.810038) (xy 53.668279 -282.837994) (xy 53.703772 -282.872086)
			(xy 53.733337 -282.91143) (xy 53.756208 -282.955007) (xy 53.771792 -283.001688) (xy 53.779687 -283.050265)
			(xy 53.780182 -283.074872) (xy 54.11903 -283.074872) (xy 54.12299 -283.025818) (xy 54.134767 -282.978034)
			(xy 54.154058 -282.932758) (xy 54.180361 -282.891162) (xy 54.212996 -282.854325) (xy 54.251117 -282.8232)
			(xy 54.293738 -282.798593) (xy 54.339754 -282.781141) (xy 54.387973 -282.771297) (xy 54.437148 -282.769316)
			(xy 54.486003 -282.775248) (xy 54.533274 -282.78894) (xy 54.577736 -282.810038) (xy 54.618239 -282.837994)
			(xy 54.653732 -282.872086) (xy 54.683297 -282.91143) (xy 54.706168 -282.955007) (xy 54.721752 -283.001688)
			(xy 54.729647 -283.050265) (xy 54.730142 -283.074872) (xy 55.06899 -283.074872) (xy 55.07295 -283.025818)
			(xy 55.084727 -282.978034) (xy 55.104018 -282.932758) (xy 55.130321 -282.891162) (xy 55.162956 -282.854325)
			(xy 55.201077 -282.8232) (xy 55.243698 -282.798593) (xy 55.289714 -282.781141) (xy 55.337933 -282.771297)
			(xy 55.387108 -282.769316) (xy 55.435963 -282.775248) (xy 55.483234 -282.78894) (xy 55.527696 -282.810038)
			(xy 55.568199 -282.837994) (xy 55.603692 -282.872086) (xy 55.633257 -282.91143) (xy 55.656128 -282.955007)
			(xy 55.671712 -283.001688) (xy 55.679607 -283.050265) (xy 55.680102 -283.074872) (xy 56.019204 -283.074872)
			(xy 56.023164 -283.025818) (xy 56.034941 -282.978034) (xy 56.054232 -282.932758) (xy 56.080535 -282.891162)
			(xy 56.11317 -282.854325) (xy 56.151291 -282.8232) (xy 56.193912 -282.798593) (xy 56.239928 -282.781141)
			(xy 56.288147 -282.771297) (xy 56.337322 -282.769316) (xy 56.386177 -282.775248) (xy 56.433448 -282.78894)
			(xy 56.47791 -282.810038) (xy 56.518413 -282.837994) (xy 56.553906 -282.872086) (xy 56.583471 -282.91143)
			(xy 56.606342 -282.955007) (xy 56.621926 -283.001688) (xy 56.629821 -283.050265) (xy 56.630316 -283.074872)
			(xy 56.969164 -283.074872) (xy 56.973124 -283.025818) (xy 56.984901 -282.978034) (xy 57.004192 -282.932758)
			(xy 57.030495 -282.891162) (xy 57.06313 -282.854325) (xy 57.101251 -282.8232) (xy 57.143872 -282.798593)
			(xy 57.189888 -282.781141) (xy 57.238107 -282.771297) (xy 57.287282 -282.769316) (xy 57.336137 -282.775248)
			(xy 57.383408 -282.78894) (xy 57.42787 -282.810038) (xy 57.468373 -282.837994) (xy 57.503866 -282.872086)
			(xy 57.533431 -282.91143) (xy 57.556302 -282.955007) (xy 57.571886 -283.001688) (xy 57.579781 -283.050265)
			(xy 57.580276 -283.074872) (xy 57.919124 -283.074872) (xy 57.923084 -283.025818) (xy 57.934861 -282.978034)
			(xy 57.954152 -282.932758) (xy 57.980455 -282.891162) (xy 58.01309 -282.854325) (xy 58.051211 -282.8232)
			(xy 58.093832 -282.798593) (xy 58.139848 -282.781141) (xy 58.188067 -282.771297) (xy 58.237242 -282.769316)
			(xy 58.286097 -282.775248) (xy 58.333368 -282.78894) (xy 58.37783 -282.810038) (xy 58.418333 -282.837994)
			(xy 58.453826 -282.872086) (xy 58.483391 -282.91143) (xy 58.506262 -282.955007) (xy 58.521846 -283.001688)
			(xy 58.529741 -283.050265) (xy 58.530236 -283.074872) (xy 59.819044 -283.074872) (xy 59.823004 -283.025818)
			(xy 59.834781 -282.978034) (xy 59.854072 -282.932758) (xy 59.880375 -282.891162) (xy 59.91301 -282.854325)
			(xy 59.951131 -282.8232) (xy 59.993752 -282.798593) (xy 60.039768 -282.781141) (xy 60.087987 -282.771297)
			(xy 60.137162 -282.769316) (xy 60.186017 -282.775248) (xy 60.233288 -282.78894) (xy 60.27775 -282.810038)
			(xy 60.318253 -282.837994) (xy 60.353746 -282.872086) (xy 60.383311 -282.91143) (xy 60.406182 -282.955007)
			(xy 60.421766 -283.001688) (xy 60.429661 -283.050265) (xy 60.430156 -283.074872) (xy 60.769004 -283.074872)
			(xy 60.772964 -283.025818) (xy 60.784741 -282.978034) (xy 60.804032 -282.932758) (xy 60.830335 -282.891162)
			(xy 60.86297 -282.854325) (xy 60.901091 -282.8232) (xy 60.943712 -282.798593) (xy 60.989728 -282.781141)
			(xy 61.037947 -282.771297) (xy 61.087122 -282.769316) (xy 61.135977 -282.775248) (xy 61.183248 -282.78894)
			(xy 61.22771 -282.810038) (xy 61.268213 -282.837994) (xy 61.303706 -282.872086) (xy 61.333271 -282.91143)
			(xy 61.356142 -282.955007) (xy 61.371726 -283.001688) (xy 61.379621 -283.050265) (xy 61.380116 -283.074872)
			(xy 61.718964 -283.074872) (xy 61.722924 -283.025818) (xy 61.734701 -282.978034) (xy 61.753992 -282.932758)
			(xy 61.780295 -282.891162) (xy 61.81293 -282.854325) (xy 61.851051 -282.8232) (xy 61.893672 -282.798593)
			(xy 61.939688 -282.781141) (xy 61.987907 -282.771297) (xy 62.037082 -282.769316) (xy 62.085937 -282.775248)
			(xy 62.133208 -282.78894) (xy 62.17767 -282.810038) (xy 62.218173 -282.837994) (xy 62.253666 -282.872086)
			(xy 62.283231 -282.91143) (xy 62.306102 -282.955007) (xy 62.321686 -283.001688) (xy 62.329581 -283.050265)
			(xy 62.330076 -283.074872) (xy 62.669178 -283.074872) (xy 62.673138 -283.025818) (xy 62.684915 -282.978034)
			(xy 62.704206 -282.932758) (xy 62.730509 -282.891162) (xy 62.763144 -282.854325) (xy 62.801265 -282.8232)
			(xy 62.843886 -282.798593) (xy 62.889902 -282.781141) (xy 62.938121 -282.771297) (xy 62.987296 -282.769316)
			(xy 63.036151 -282.775248) (xy 63.083422 -282.78894) (xy 63.127884 -282.810038) (xy 63.168387 -282.837994)
			(xy 63.20388 -282.872086) (xy 63.233445 -282.91143) (xy 63.256316 -282.955007) (xy 63.2719 -283.001688)
			(xy 63.279795 -283.050265) (xy 63.28029 -283.074872) (xy 63.619138 -283.074872) (xy 63.623098 -283.025818)
			(xy 63.634875 -282.978034) (xy 63.654166 -282.932758) (xy 63.680469 -282.891162) (xy 63.713104 -282.854325)
			(xy 63.751225 -282.8232) (xy 63.793846 -282.798593) (xy 63.839862 -282.781141) (xy 63.888081 -282.771297)
			(xy 63.937256 -282.769316) (xy 63.986111 -282.775248) (xy 64.033382 -282.78894) (xy 64.077844 -282.810038)
			(xy 64.118347 -282.837994) (xy 64.15384 -282.872086) (xy 64.183405 -282.91143) (xy 64.206276 -282.955007)
			(xy 64.22186 -283.001688) (xy 64.229755 -283.050265) (xy 64.23025 -283.074872) (xy 64.569098 -283.074872)
			(xy 64.573058 -283.025818) (xy 64.584835 -282.978034) (xy 64.604126 -282.932758) (xy 64.630429 -282.891162)
			(xy 64.663064 -282.854325) (xy 64.701185 -282.8232) (xy 64.743806 -282.798593) (xy 64.789822 -282.781141)
			(xy 64.838041 -282.771297) (xy 64.887216 -282.769316) (xy 64.936071 -282.775248) (xy 64.983342 -282.78894)
			(xy 65.027804 -282.810038) (xy 65.068307 -282.837994) (xy 65.1038 -282.872086) (xy 65.133365 -282.91143)
			(xy 65.156236 -282.955007) (xy 65.17182 -283.001688) (xy 65.179715 -283.050265) (xy 65.18021 -283.074872)
			(xy 65.519058 -283.074872) (xy 65.523018 -283.025818) (xy 65.534795 -282.978034) (xy 65.554086 -282.932758)
			(xy 65.580389 -282.891162) (xy 65.613024 -282.854325) (xy 65.651145 -282.8232) (xy 65.693766 -282.798593)
			(xy 65.739782 -282.781141) (xy 65.788001 -282.771297) (xy 65.837176 -282.769316) (xy 65.886031 -282.775248)
			(xy 65.933302 -282.78894) (xy 65.977764 -282.810038) (xy 66.018267 -282.837994) (xy 66.05376 -282.872086)
			(xy 66.083325 -282.91143) (xy 66.106196 -282.955007) (xy 66.12178 -283.001688) (xy 66.129675 -283.050265)
			(xy 66.13017 -283.074872) (xy 66.469018 -283.074872) (xy 66.472978 -283.025818) (xy 66.484755 -282.978034)
			(xy 66.504046 -282.932758) (xy 66.530349 -282.891162) (xy 66.562984 -282.854325) (xy 66.601105 -282.8232)
			(xy 66.643726 -282.798593) (xy 66.689742 -282.781141) (xy 66.737961 -282.771297) (xy 66.787136 -282.769316)
			(xy 66.835991 -282.775248) (xy 66.883262 -282.78894) (xy 66.927724 -282.810038) (xy 66.968227 -282.837994)
			(xy 67.00372 -282.872086) (xy 67.033285 -282.91143) (xy 67.056156 -282.955007) (xy 67.07174 -283.001688)
			(xy 67.079635 -283.050265) (xy 67.08013 -283.074872) (xy 68.368938 -283.074872) (xy 68.372898 -283.025818)
			(xy 68.384675 -282.978034) (xy 68.403966 -282.932758) (xy 68.430269 -282.891162) (xy 68.462904 -282.854325)
			(xy 68.501025 -282.8232) (xy 68.543646 -282.798593) (xy 68.589662 -282.781141) (xy 68.637881 -282.771297)
			(xy 68.687056 -282.769316) (xy 68.735911 -282.775248) (xy 68.783182 -282.78894) (xy 68.827644 -282.810038)
			(xy 68.868147 -282.837994) (xy 68.90364 -282.872086) (xy 68.933205 -282.91143) (xy 68.956076 -282.955007)
			(xy 68.97166 -283.001688) (xy 68.979555 -283.050265) (xy 68.98005 -283.074872) (xy 69.319152 -283.074872)
			(xy 69.323112 -283.025818) (xy 69.334889 -282.978034) (xy 69.35418 -282.932758) (xy 69.380483 -282.891162)
			(xy 69.413118 -282.854325) (xy 69.451239 -282.8232) (xy 69.49386 -282.798593) (xy 69.539876 -282.781141)
			(xy 69.588095 -282.771297) (xy 69.63727 -282.769316) (xy 69.686125 -282.775248) (xy 69.733396 -282.78894)
			(xy 69.777858 -282.810038) (xy 69.818361 -282.837994) (xy 69.853854 -282.872086) (xy 69.883419 -282.91143)
			(xy 69.90629 -282.955007) (xy 69.921874 -283.001688) (xy 69.929769 -283.050265) (xy 69.930264 -283.074872)
			(xy 70.269112 -283.074872) (xy 70.273072 -283.025818) (xy 70.284849 -282.978034) (xy 70.30414 -282.932758)
			(xy 70.330443 -282.891162) (xy 70.363078 -282.854325) (xy 70.401199 -282.8232) (xy 70.44382 -282.798593)
			(xy 70.489836 -282.781141) (xy 70.538055 -282.771297) (xy 70.58723 -282.769316) (xy 70.636085 -282.775248)
			(xy 70.683356 -282.78894) (xy 70.727818 -282.810038) (xy 70.768321 -282.837994) (xy 70.803814 -282.872086)
			(xy 70.833379 -282.91143) (xy 70.85625 -282.955007) (xy 70.871834 -283.001688) (xy 70.879729 -283.050265)
			(xy 70.880224 -283.074872) (xy 71.219072 -283.074872) (xy 71.223032 -283.025818) (xy 71.234809 -282.978034)
			(xy 71.2541 -282.932758) (xy 71.280403 -282.891162) (xy 71.313038 -282.854325) (xy 71.351159 -282.8232)
			(xy 71.39378 -282.798593) (xy 71.439796 -282.781141) (xy 71.488015 -282.771297) (xy 71.53719 -282.769316)
			(xy 71.586045 -282.775248) (xy 71.633316 -282.78894) (xy 71.677778 -282.810038) (xy 71.718281 -282.837994)
			(xy 71.753774 -282.872086) (xy 71.783339 -282.91143) (xy 71.80621 -282.955007) (xy 71.821794 -283.001688)
			(xy 71.829689 -283.050265) (xy 71.830184 -283.074872) (xy 72.169032 -283.074872) (xy 72.172992 -283.025818)
			(xy 72.184769 -282.978034) (xy 72.20406 -282.932758) (xy 72.230363 -282.891162) (xy 72.262998 -282.854325)
			(xy 72.301119 -282.8232) (xy 72.34374 -282.798593) (xy 72.389756 -282.781141) (xy 72.437975 -282.771297)
			(xy 72.48715 -282.769316) (xy 72.536005 -282.775248) (xy 72.583276 -282.78894) (xy 72.627738 -282.810038)
			(xy 72.668241 -282.837994) (xy 72.703734 -282.872086) (xy 72.733299 -282.91143) (xy 72.75617 -282.955007)
			(xy 72.771754 -283.001688) (xy 72.779649 -283.050265) (xy 72.780144 -283.074872) (xy 72.779649 -283.099479)
			(xy 72.771754 -283.148056) (xy 72.75617 -283.194737) (xy 72.733299 -283.238314) (xy 72.703734 -283.277658)
			(xy 72.668241 -283.31175) (xy 72.627738 -283.339706) (xy 72.583276 -283.360804) (xy 72.536005 -283.374496)
			(xy 72.48715 -283.380428) (xy 72.437975 -283.378447) (xy 72.389756 -283.368603) (xy 72.34374 -283.351151)
			(xy 72.301119 -283.326544) (xy 72.262998 -283.295419) (xy 72.230363 -283.258582) (xy 72.20406 -283.216986)
			(xy 72.184769 -283.17171) (xy 72.172992 -283.123926) (xy 72.169032 -283.074872) (xy 71.830184 -283.074872)
			(xy 71.829689 -283.099479) (xy 71.821794 -283.148056) (xy 71.80621 -283.194737) (xy 71.783339 -283.238314)
			(xy 71.753774 -283.277658) (xy 71.718281 -283.31175) (xy 71.677778 -283.339706) (xy 71.633316 -283.360804)
			(xy 71.586045 -283.374496) (xy 71.53719 -283.380428) (xy 71.488015 -283.378447) (xy 71.439796 -283.368603)
			(xy 71.39378 -283.351151) (xy 71.351159 -283.326544) (xy 71.313038 -283.295419) (xy 71.280403 -283.258582)
			(xy 71.2541 -283.216986) (xy 71.234809 -283.17171) (xy 71.223032 -283.123926) (xy 71.219072 -283.074872)
			(xy 70.880224 -283.074872) (xy 70.879729 -283.099479) (xy 70.871834 -283.148056) (xy 70.85625 -283.194737)
			(xy 70.833379 -283.238314) (xy 70.803814 -283.277658) (xy 70.768321 -283.31175) (xy 70.727818 -283.339706)
			(xy 70.683356 -283.360804) (xy 70.636085 -283.374496) (xy 70.58723 -283.380428) (xy 70.538055 -283.378447)
			(xy 70.489836 -283.368603) (xy 70.44382 -283.351151) (xy 70.401199 -283.326544) (xy 70.363078 -283.295419)
			(xy 70.330443 -283.258582) (xy 70.30414 -283.216986) (xy 70.284849 -283.17171) (xy 70.273072 -283.123926)
			(xy 70.269112 -283.074872) (xy 69.930264 -283.074872) (xy 69.929769 -283.099479) (xy 69.921874 -283.148056)
			(xy 69.90629 -283.194737) (xy 69.883419 -283.238314) (xy 69.853854 -283.277658) (xy 69.818361 -283.31175)
			(xy 69.777858 -283.339706) (xy 69.733396 -283.360804) (xy 69.686125 -283.374496) (xy 69.63727 -283.380428)
			(xy 69.588095 -283.378447) (xy 69.539876 -283.368603) (xy 69.49386 -283.351151) (xy 69.451239 -283.326544)
			(xy 69.413118 -283.295419) (xy 69.380483 -283.258582) (xy 69.35418 -283.216986) (xy 69.334889 -283.17171)
			(xy 69.323112 -283.123926) (xy 69.319152 -283.074872) (xy 68.98005 -283.074872) (xy 68.979555 -283.099479)
			(xy 68.97166 -283.148056) (xy 68.956076 -283.194737) (xy 68.933205 -283.238314) (xy 68.90364 -283.277658)
			(xy 68.868147 -283.31175) (xy 68.827644 -283.339706) (xy 68.783182 -283.360804) (xy 68.735911 -283.374496)
			(xy 68.687056 -283.380428) (xy 68.637881 -283.378447) (xy 68.589662 -283.368603) (xy 68.543646 -283.351151)
			(xy 68.501025 -283.326544) (xy 68.462904 -283.295419) (xy 68.430269 -283.258582) (xy 68.403966 -283.216986)
			(xy 68.384675 -283.17171) (xy 68.372898 -283.123926) (xy 68.368938 -283.074872) (xy 67.08013 -283.074872)
			(xy 67.079635 -283.099479) (xy 67.07174 -283.148056) (xy 67.056156 -283.194737) (xy 67.033285 -283.238314)
			(xy 67.00372 -283.277658) (xy 66.968227 -283.31175) (xy 66.927724 -283.339706) (xy 66.883262 -283.360804)
			(xy 66.835991 -283.374496) (xy 66.787136 -283.380428) (xy 66.737961 -283.378447) (xy 66.689742 -283.368603)
			(xy 66.643726 -283.351151) (xy 66.601105 -283.326544) (xy 66.562984 -283.295419) (xy 66.530349 -283.258582)
			(xy 66.504046 -283.216986) (xy 66.484755 -283.17171) (xy 66.472978 -283.123926) (xy 66.469018 -283.074872)
			(xy 66.13017 -283.074872) (xy 66.129675 -283.099479) (xy 66.12178 -283.148056) (xy 66.106196 -283.194737)
			(xy 66.083325 -283.238314) (xy 66.05376 -283.277658) (xy 66.018267 -283.31175) (xy 65.977764 -283.339706)
			(xy 65.933302 -283.360804) (xy 65.886031 -283.374496) (xy 65.837176 -283.380428) (xy 65.788001 -283.378447)
			(xy 65.739782 -283.368603) (xy 65.693766 -283.351151) (xy 65.651145 -283.326544) (xy 65.613024 -283.295419)
			(xy 65.580389 -283.258582) (xy 65.554086 -283.216986) (xy 65.534795 -283.17171) (xy 65.523018 -283.123926)
			(xy 65.519058 -283.074872) (xy 65.18021 -283.074872) (xy 65.179715 -283.099479) (xy 65.17182 -283.148056)
			(xy 65.156236 -283.194737) (xy 65.133365 -283.238314) (xy 65.1038 -283.277658) (xy 65.068307 -283.31175)
			(xy 65.027804 -283.339706) (xy 64.983342 -283.360804) (xy 64.936071 -283.374496) (xy 64.887216 -283.380428)
			(xy 64.838041 -283.378447) (xy 64.789822 -283.368603) (xy 64.743806 -283.351151) (xy 64.701185 -283.326544)
			(xy 64.663064 -283.295419) (xy 64.630429 -283.258582) (xy 64.604126 -283.216986) (xy 64.584835 -283.17171)
			(xy 64.573058 -283.123926) (xy 64.569098 -283.074872) (xy 64.23025 -283.074872) (xy 64.229755 -283.099479)
			(xy 64.22186 -283.148056) (xy 64.206276 -283.194737) (xy 64.183405 -283.238314) (xy 64.15384 -283.277658)
			(xy 64.118347 -283.31175) (xy 64.077844 -283.339706) (xy 64.033382 -283.360804) (xy 63.986111 -283.374496)
			(xy 63.937256 -283.380428) (xy 63.888081 -283.378447) (xy 63.839862 -283.368603) (xy 63.793846 -283.351151)
			(xy 63.751225 -283.326544) (xy 63.713104 -283.295419) (xy 63.680469 -283.258582) (xy 63.654166 -283.216986)
			(xy 63.634875 -283.17171) (xy 63.623098 -283.123926) (xy 63.619138 -283.074872) (xy 63.28029 -283.074872)
			(xy 63.279795 -283.099479) (xy 63.2719 -283.148056) (xy 63.256316 -283.194737) (xy 63.233445 -283.238314)
			(xy 63.20388 -283.277658) (xy 63.168387 -283.31175) (xy 63.127884 -283.339706) (xy 63.083422 -283.360804)
			(xy 63.036151 -283.374496) (xy 62.987296 -283.380428) (xy 62.938121 -283.378447) (xy 62.889902 -283.368603)
			(xy 62.843886 -283.351151) (xy 62.801265 -283.326544) (xy 62.763144 -283.295419) (xy 62.730509 -283.258582)
			(xy 62.704206 -283.216986) (xy 62.684915 -283.17171) (xy 62.673138 -283.123926) (xy 62.669178 -283.074872)
			(xy 62.330076 -283.074872) (xy 62.329581 -283.099479) (xy 62.321686 -283.148056) (xy 62.306102 -283.194737)
			(xy 62.283231 -283.238314) (xy 62.253666 -283.277658) (xy 62.218173 -283.31175) (xy 62.17767 -283.339706)
			(xy 62.133208 -283.360804) (xy 62.085937 -283.374496) (xy 62.037082 -283.380428) (xy 61.987907 -283.378447)
			(xy 61.939688 -283.368603) (xy 61.893672 -283.351151) (xy 61.851051 -283.326544) (xy 61.81293 -283.295419)
			(xy 61.780295 -283.258582) (xy 61.753992 -283.216986) (xy 61.734701 -283.17171) (xy 61.722924 -283.123926)
			(xy 61.718964 -283.074872) (xy 61.380116 -283.074872) (xy 61.379621 -283.099479) (xy 61.371726 -283.148056)
			(xy 61.356142 -283.194737) (xy 61.333271 -283.238314) (xy 61.303706 -283.277658) (xy 61.268213 -283.31175)
			(xy 61.22771 -283.339706) (xy 61.183248 -283.360804) (xy 61.135977 -283.374496) (xy 61.087122 -283.380428)
			(xy 61.037947 -283.378447) (xy 60.989728 -283.368603) (xy 60.943712 -283.351151) (xy 60.901091 -283.326544)
			(xy 60.86297 -283.295419) (xy 60.830335 -283.258582) (xy 60.804032 -283.216986) (xy 60.784741 -283.17171)
			(xy 60.772964 -283.123926) (xy 60.769004 -283.074872) (xy 60.430156 -283.074872) (xy 60.429661 -283.099479)
			(xy 60.421766 -283.148056) (xy 60.406182 -283.194737) (xy 60.383311 -283.238314) (xy 60.353746 -283.277658)
			(xy 60.318253 -283.31175) (xy 60.27775 -283.339706) (xy 60.233288 -283.360804) (xy 60.186017 -283.374496)
			(xy 60.137162 -283.380428) (xy 60.087987 -283.378447) (xy 60.039768 -283.368603) (xy 59.993752 -283.351151)
			(xy 59.951131 -283.326544) (xy 59.91301 -283.295419) (xy 59.880375 -283.258582) (xy 59.854072 -283.216986)
			(xy 59.834781 -283.17171) (xy 59.823004 -283.123926) (xy 59.819044 -283.074872) (xy 58.530236 -283.074872)
			(xy 58.529741 -283.099479) (xy 58.521846 -283.148056) (xy 58.506262 -283.194737) (xy 58.483391 -283.238314)
			(xy 58.453826 -283.277658) (xy 58.418333 -283.31175) (xy 58.37783 -283.339706) (xy 58.333368 -283.360804)
			(xy 58.286097 -283.374496) (xy 58.237242 -283.380428) (xy 58.188067 -283.378447) (xy 58.139848 -283.368603)
			(xy 58.093832 -283.351151) (xy 58.051211 -283.326544) (xy 58.01309 -283.295419) (xy 57.980455 -283.258582)
			(xy 57.954152 -283.216986) (xy 57.934861 -283.17171) (xy 57.923084 -283.123926) (xy 57.919124 -283.074872)
			(xy 57.580276 -283.074872) (xy 57.579781 -283.099479) (xy 57.571886 -283.148056) (xy 57.556302 -283.194737)
			(xy 57.533431 -283.238314) (xy 57.503866 -283.277658) (xy 57.468373 -283.31175) (xy 57.42787 -283.339706)
			(xy 57.383408 -283.360804) (xy 57.336137 -283.374496) (xy 57.287282 -283.380428) (xy 57.238107 -283.378447)
			(xy 57.189888 -283.368603) (xy 57.143872 -283.351151) (xy 57.101251 -283.326544) (xy 57.06313 -283.295419)
			(xy 57.030495 -283.258582) (xy 57.004192 -283.216986) (xy 56.984901 -283.17171) (xy 56.973124 -283.123926)
			(xy 56.969164 -283.074872) (xy 56.630316 -283.074872) (xy 56.629821 -283.099479) (xy 56.621926 -283.148056)
			(xy 56.606342 -283.194737) (xy 56.583471 -283.238314) (xy 56.553906 -283.277658) (xy 56.518413 -283.31175)
			(xy 56.47791 -283.339706) (xy 56.433448 -283.360804) (xy 56.386177 -283.374496) (xy 56.337322 -283.380428)
			(xy 56.288147 -283.378447) (xy 56.239928 -283.368603) (xy 56.193912 -283.351151) (xy 56.151291 -283.326544)
			(xy 56.11317 -283.295419) (xy 56.080535 -283.258582) (xy 56.054232 -283.216986) (xy 56.034941 -283.17171)
			(xy 56.023164 -283.123926) (xy 56.019204 -283.074872) (xy 55.680102 -283.074872) (xy 55.679607 -283.099479)
			(xy 55.671712 -283.148056) (xy 55.656128 -283.194737) (xy 55.633257 -283.238314) (xy 55.603692 -283.277658)
			(xy 55.568199 -283.31175) (xy 55.527696 -283.339706) (xy 55.483234 -283.360804) (xy 55.435963 -283.374496)
			(xy 55.387108 -283.380428) (xy 55.337933 -283.378447) (xy 55.289714 -283.368603) (xy 55.243698 -283.351151)
			(xy 55.201077 -283.326544) (xy 55.162956 -283.295419) (xy 55.130321 -283.258582) (xy 55.104018 -283.216986)
			(xy 55.084727 -283.17171) (xy 55.07295 -283.123926) (xy 55.06899 -283.074872) (xy 54.730142 -283.074872)
			(xy 54.729647 -283.099479) (xy 54.721752 -283.148056) (xy 54.706168 -283.194737) (xy 54.683297 -283.238314)
			(xy 54.653732 -283.277658) (xy 54.618239 -283.31175) (xy 54.577736 -283.339706) (xy 54.533274 -283.360804)
			(xy 54.486003 -283.374496) (xy 54.437148 -283.380428) (xy 54.387973 -283.378447) (xy 54.339754 -283.368603)
			(xy 54.293738 -283.351151) (xy 54.251117 -283.326544) (xy 54.212996 -283.295419) (xy 54.180361 -283.258582)
			(xy 54.154058 -283.216986) (xy 54.134767 -283.17171) (xy 54.12299 -283.123926) (xy 54.11903 -283.074872)
			(xy 53.780182 -283.074872) (xy 53.779687 -283.099479) (xy 53.771792 -283.148056) (xy 53.756208 -283.194737)
			(xy 53.733337 -283.238314) (xy 53.703772 -283.277658) (xy 53.668279 -283.31175) (xy 53.627776 -283.339706)
			(xy 53.583314 -283.360804) (xy 53.536043 -283.374496) (xy 53.487188 -283.380428) (xy 53.438013 -283.378447)
			(xy 53.389794 -283.368603) (xy 53.343778 -283.351151) (xy 53.301157 -283.326544) (xy 53.263036 -283.295419)
			(xy 53.230401 -283.258582) (xy 53.204098 -283.216986) (xy 53.184807 -283.17171) (xy 53.17303 -283.123926)
			(xy 53.16907 -283.074872) (xy 52.830222 -283.074872) (xy 52.829727 -283.099479) (xy 52.821832 -283.148056)
			(xy 52.806248 -283.194737) (xy 52.783377 -283.238314) (xy 52.753812 -283.277658) (xy 52.718319 -283.31175)
			(xy 52.677816 -283.339706) (xy 52.633354 -283.360804) (xy 52.586083 -283.374496) (xy 52.537228 -283.380428)
			(xy 52.488053 -283.378447) (xy 52.439834 -283.368603) (xy 52.393818 -283.351151) (xy 52.351197 -283.326544)
			(xy 52.313076 -283.295419) (xy 52.280441 -283.258582) (xy 52.254138 -283.216986) (xy 52.234847 -283.17171)
			(xy 52.22307 -283.123926) (xy 52.21911 -283.074872) (xy 51.880262 -283.074872) (xy 51.879767 -283.099479)
			(xy 51.871872 -283.148056) (xy 51.856288 -283.194737) (xy 51.833417 -283.238314) (xy 51.803852 -283.277658)
			(xy 51.768359 -283.31175) (xy 51.727856 -283.339706) (xy 51.683394 -283.360804) (xy 51.636123 -283.374496)
			(xy 51.587268 -283.380428) (xy 51.538093 -283.378447) (xy 51.489874 -283.368603) (xy 51.443858 -283.351151)
			(xy 51.401237 -283.326544) (xy 51.363116 -283.295419) (xy 51.330481 -283.258582) (xy 51.304178 -283.216986)
			(xy 51.284887 -283.17171) (xy 51.27311 -283.123926) (xy 51.26915 -283.074872) (xy 50.930302 -283.074872)
			(xy 50.929807 -283.099479) (xy 50.921912 -283.148056) (xy 50.906328 -283.194737) (xy 50.883457 -283.238314)
			(xy 50.853892 -283.277658) (xy 50.818399 -283.31175) (xy 50.777896 -283.339706) (xy 50.733434 -283.360804)
			(xy 50.686163 -283.374496) (xy 50.637308 -283.380428) (xy 50.588133 -283.378447) (xy 50.539914 -283.368603)
			(xy 50.493898 -283.351151) (xy 50.451277 -283.326544) (xy 50.413156 -283.295419) (xy 50.380521 -283.258582)
			(xy 50.354218 -283.216986) (xy 50.334927 -283.17171) (xy 50.32315 -283.123926) (xy 50.31919 -283.074872)
			(xy 49.980088 -283.074872) (xy 49.979593 -283.099479) (xy 49.971698 -283.148056) (xy 49.956114 -283.194737)
			(xy 49.933243 -283.238314) (xy 49.903678 -283.277658) (xy 49.868185 -283.31175) (xy 49.827682 -283.339706)
			(xy 49.78322 -283.360804) (xy 49.735949 -283.374496) (xy 49.687094 -283.380428) (xy 49.637919 -283.378447)
			(xy 49.5897 -283.368603) (xy 49.543684 -283.351151) (xy 49.501063 -283.326544) (xy 49.462942 -283.295419)
			(xy 49.430307 -283.258582) (xy 49.404004 -283.216986) (xy 49.384713 -283.17171) (xy 49.372936 -283.123926)
			(xy 49.368976 -283.074872) (xy 49.030128 -283.074872) (xy 49.029633 -283.099479) (xy 49.021738 -283.148056)
			(xy 49.006154 -283.194737) (xy 48.983283 -283.238314) (xy 48.953718 -283.277658) (xy 48.918225 -283.31175)
			(xy 48.877722 -283.339706) (xy 48.83326 -283.360804) (xy 48.785989 -283.374496) (xy 48.737134 -283.380428)
			(xy 48.687959 -283.378447) (xy 48.63974 -283.368603) (xy 48.593724 -283.351151) (xy 48.551103 -283.326544)
			(xy 48.512982 -283.295419) (xy 48.480347 -283.258582) (xy 48.454044 -283.216986) (xy 48.434753 -283.17171)
			(xy 48.422976 -283.123926) (xy 48.419016 -283.074872) (xy 48.080168 -283.074872) (xy 48.079673 -283.099479)
			(xy 48.071778 -283.148056) (xy 48.056194 -283.194737) (xy 48.033323 -283.238314) (xy 48.003758 -283.277658)
			(xy 47.968265 -283.31175) (xy 47.927762 -283.339706) (xy 47.8833 -283.360804) (xy 47.836029 -283.374496)
			(xy 47.787174 -283.380428) (xy 47.737999 -283.378447) (xy 47.68978 -283.368603) (xy 47.643764 -283.351151)
			(xy 47.601143 -283.326544) (xy 47.563022 -283.295419) (xy 47.530387 -283.258582) (xy 47.504084 -283.216986)
			(xy 47.484793 -283.17171) (xy 47.473016 -283.123926) (xy 47.469056 -283.074872) (xy 47.1302 -283.074872)
			(xy 47.127958 -283.116201) (xy 47.117283 -283.164687) (xy 47.098905 -283.210808) (xy 47.073308 -283.253347)
			(xy 47.041165 -283.291185) (xy 47.003324 -283.323324) (xy 46.960782 -283.348918) (xy 46.91466 -283.367292)
			(xy 46.866173 -283.377961) (xy 46.816599 -283.380646) (xy 46.767243 -283.375275) (xy 46.719406 -283.36199)
			(xy 46.674349 -283.341141) (xy 46.633259 -283.313276) (xy 46.597217 -283.279131) (xy 46.567175 -283.239605)
			(xy 46.543924 -283.195739) (xy 46.528075 -283.14869) (xy 46.520048 -283.099696) (xy 46.519592 -283.074872)
			(xy 46.519802 -283.060817) (xy 46.522477 -283.032834) (xy 46.524926 -283.018992) (xy 46.524926 -283.018484)
			(xy 46.526433 -283.006249) (xy 46.519137 -282.982746) (xy 46.510956 -282.973526) (xy 46.451266 -282.913836)
			(xy 46.442022 -282.905703) (xy 46.418539 -282.898428) (xy 46.406308 -282.899866) (xy 46.406054 -282.899866)
			(xy 46.392215 -282.902331) (xy 46.36423 -282.904999) (xy 46.350174 -282.9052) (xy 46.349666 -282.9052)
			(xy 46.335674 -282.904984) (xy 46.307818 -282.902312) (xy 46.29404 -282.899866) (xy 46.293532 -282.899866)
			(xy 46.281302 -282.898372) (xy 46.257815 -282.905684) (xy 46.248574 -282.913836) (xy 46.188884 -282.973526)
			(xy 46.180742 -282.982767) (xy 46.173457 -283.006253) (xy 46.174914 -283.018484) (xy 46.174914 -283.018992)
			(xy 46.177381 -283.032831) (xy 46.180053 -283.060816) (xy 46.180248 -283.074872) (xy 46.179726 -283.100127)
			(xy 46.171413 -283.149949) (xy 46.155012 -283.197723) (xy 46.130971 -283.242146) (xy 46.099947 -283.282006)
			(xy 46.062785 -283.316216) (xy 46.020499 -283.343842) (xy 45.974243 -283.364132) (xy 45.925278 -283.376532)
			(xy 45.87494 -283.380703) (xy 45.824602 -283.376532) (xy 45.775637 -283.364132) (xy 45.729381 -283.343842)
			(xy 45.687095 -283.316216) (xy 45.649933 -283.282006) (xy 45.618909 -283.242146) (xy 45.594868 -283.197723)
			(xy 45.578467 -283.149949) (xy 45.570154 -283.100127) (xy 45.569632 -283.074872) (xy 45.569842 -283.060817)
			(xy 45.572517 -283.032833) (xy 45.574966 -283.018992) (xy 45.574966 -283.018484) (xy 45.576473 -283.006249)
			(xy 45.569181 -282.982742) (xy 45.560996 -282.973526) (xy 45.501306 -282.913836) (xy 45.492064 -282.905694)
			(xy 45.468578 -282.898402) (xy 45.456348 -282.899866) (xy 45.456094 -282.899866) (xy 45.442255 -282.902333)
			(xy 45.41427 -282.905004) (xy 45.400214 -282.9052) (xy 45.399706 -282.9052) (xy 45.385714 -282.904986)
			(xy 45.357857 -282.902318) (xy 45.34408 -282.899866) (xy 45.343572 -282.899866) (xy 45.331338 -282.898362)
			(xy 45.307838 -282.905661) (xy 45.298614 -282.913836) (xy 45.238924 -282.973526) (xy 45.230777 -282.982765)
			(xy 45.223486 -283.006253) (xy 45.224954 -283.018484) (xy 45.224954 -283.018992) (xy 45.227422 -283.032831)
			(xy 45.230094 -283.060816) (xy 45.230288 -283.074872) (xy 45.229804 -283.099691) (xy 45.221778 -283.148677)
			(xy 45.205933 -283.195719) (xy 45.182685 -283.239577) (xy 45.152649 -283.279097) (xy 45.116614 -283.313237)
			(xy 45.075531 -283.341097) (xy 45.030482 -283.361943) (xy 44.982654 -283.375227) (xy 44.933307 -283.380598)
			(xy 44.88374 -283.377915) (xy 44.835261 -283.367248) (xy 44.789147 -283.348879) (xy 44.746611 -283.32329)
			(xy 44.708776 -283.291158) (xy 44.676638 -283.253328) (xy 44.651043 -283.210796) (xy 44.632666 -283.164685)
			(xy 44.621992 -283.116207) (xy 44.619301 -283.066641) (xy 44.624664 -283.017293) (xy 44.63794 -282.969463)
			(xy 44.65878 -282.924411) (xy 44.686633 -282.883323) (xy 44.720767 -282.847283) (xy 44.760282 -282.81724)
			(xy 44.804137 -282.793986) (xy 44.851176 -282.778133) (xy 44.900161 -282.770099) (xy 44.92498 -282.769564)
			(xy 44.939035 -282.769772) (xy 44.96702 -282.772442) (xy 44.98086 -282.774898) (xy 44.981368 -282.774898)
			(xy 44.993599 -282.776392) (xy 45.017091 -282.769087) (xy 45.026326 -282.760928) (xy 45.086016 -282.701238)
			(xy 45.094171 -282.692) (xy 45.101485 -282.668509) (xy 45.099986 -282.65628) (xy 45.099986 -282.655772)
			(xy 45.097534 -282.641995) (xy 45.094865 -282.614138) (xy 45.094652 -282.600146) (xy 45.094652 -282.599638)
			(xy 45.094869 -282.585647) (xy 45.097543 -282.55779) (xy 45.099986 -282.544012) (xy 45.099986 -282.543504)
			(xy 45.101474 -282.531275) (xy 45.094158 -282.507794) (xy 45.086016 -282.498546) (xy 45.026326 -282.438856)
			(xy 45.023532 -282.436316) (xy 45.019411 -282.432886) (xy 45.010062 -282.427642) (xy 45.00499 -282.425902)
			(xy 44.993814 -282.4226) (xy 44.985686 -282.424124) (xy 44.961512 -282.428525) (xy 44.912418 -282.430453)
			(xy 44.863648 -282.424495) (xy 44.816461 -282.410803) (xy 44.772077 -282.389732) (xy 44.73164 -282.361824)
			(xy 44.696193 -282.327801) (xy 44.666653 -282.288541) (xy 44.643782 -282.245056) (xy 44.628169 -282.19847)
			(xy 44.620218 -282.149985) (xy 44.619672 -282.12542) (xy 44.619215 -282.115583) (xy 44.611785 -282.097366)
			(xy 44.598019 -282.08331) (xy 44.589192 -282.078938) (xy 44.586652 -282.077922) (xy 44.546595 -282.062493)
			(xy 44.469136 -282.02548) (xy 44.431966 -282.004008) (xy 44.426124 -282.000706) (xy 44.414642 -281.996593)
			(xy 44.39036 -281.998443) (xy 44.379642 -282.004262) (xy 44.341288 -282.028392) (xy 44.34078 -282.028392)
			(xy 44.30141 -282.053538) (xy 44.296157 -282.057307) (xy 44.287544 -282.066943) (xy 44.284392 -282.072588)
			(xy 44.281344 -282.078684) (xy 44.278804 -282.092654) (xy 44.279312 -282.099512) (xy 44.279312 -282.099766)
			(xy 44.280328 -282.124404) (xy 44.280328 -282.124912) (xy 44.279806 -282.150188) (xy 44.271485 -282.200052)
			(xy 44.255071 -282.247865) (xy 44.231011 -282.292325) (xy 44.19996 -282.332218) (xy 44.162768 -282.366456)
			(xy 44.120447 -282.394106) (xy 44.074152 -282.414413) (xy 44.025146 -282.426823) (xy 43.974766 -282.430998)
			(xy 43.924386 -282.426823) (xy 43.87538 -282.414413) (xy 43.829085 -282.394106) (xy 43.786764 -282.366456)
			(xy 43.749572 -282.332218) (xy 43.718521 -282.292325) (xy 43.694461 -282.247865) (xy 43.678047 -282.200052)
			(xy 43.669726 -282.150188) (xy 43.669204 -282.124912) (xy 43.669673 -282.100912) (xy 43.677176 -282.053502)
			(xy 43.691999 -282.007848) (xy 43.713777 -281.965072) (xy 43.741975 -281.926228) (xy 43.7759 -281.89227)
			(xy 43.814716 -281.864034) (xy 43.85747 -281.842214) (xy 43.90311 -281.827346) (xy 43.950512 -281.819797)
			(xy 43.974512 -281.81935) (xy 43.97502 -281.81935) (xy 43.99788 -281.820366) (xy 43.998388 -281.820366)
			(xy 44.00042 -281.82062) (xy 44.003722 -281.820874) (xy 44.017946 -281.819858) (xy 44.026836 -281.81554)
			(xy 44.031787 -281.81291) (xy 44.040501 -281.805861) (xy 44.044108 -281.80157) (xy 44.062396 -281.773376)
			(xy 44.062396 -281.772868) (xy 44.077382 -281.749246) (xy 44.077382 -281.748738) (xy 44.090336 -281.728672)
			(xy 44.090336 -281.728164) (xy 44.096686 -281.718258) (xy 44.099717 -281.712552) (xy 44.10306 -281.700077)
			(xy 44.10329 -281.69362) (xy 44.10329 -281.680158) (xy 44.09567 -281.667458) (xy 44.08297 -281.64536)
			(xy 44.08297 -281.64409) (xy 44.075858 -281.632152) (xy 44.07408 -281.629104) (xy 44.07408 -281.62885)
			(xy 44.067984 -281.61742) (xy 44.064936 -281.611578) (xy 44.049696 -281.594306) (xy 44.04487 -281.591004)
			(xy 44.013177 -281.567782) (xy 43.953287 -281.516915) (xy 43.925236 -281.489404) (xy 43.91914 -281.483308)
			(xy 43.910758 -281.476704) (xy 43.90263 -281.471878) (xy 43.891708 -281.46883) (xy 43.890692 -281.468322)
			(xy 43.869742 -281.461987) (xy 43.829778 -281.444145) (xy 43.792775 -281.420772) (xy 43.775884 -281.406854)
			(xy 43.758611 -281.391567) (xy 43.728427 -281.356688) (xy 43.703848 -281.317658) (xy 43.685435 -281.275367)
			(xy 43.67911 -281.253184) (xy 43.677332 -281.24658) (xy 43.670728 -281.234896) (xy 43.663362 -281.22753)
			(xy 43.633683 -281.196903) (xy 43.579242 -281.131247) (xy 43.53081 -281.061041) (xy 43.488767 -280.986833)
			(xy 43.45344 -280.909202) (xy 43.438826 -280.869136) (xy 43.425716 -280.830549) (xy 43.405273 -280.751652)
			(xy 43.391557 -280.671312) (xy 43.384663 -280.590101) (xy 43.384216 -280.54935) (xy 43.384216 -280.539444)
			(xy 43.383863 -280.530491) (xy 43.377709 -280.513676) (xy 43.366165 -280.499987) (xy 43.358562 -280.495248)
			(xy 43.318938 -280.476706) (xy 43.281346 -280.45918) (xy 43.276288 -280.456974) (xy 43.265525 -280.454544)
			(xy 43.26001 -280.454354) (xy 43.245532 -280.454354) (xy 43.235372 -280.45537) (xy 43.230546 -280.45664)
			(xy 43.229276 -280.457148) (xy 43.22826 -280.457402) (xy 43.218862 -280.460704) (xy 43.212258 -280.466038)
			(xy 43.192006 -280.481111) (xy 43.147593 -280.505105) (xy 43.09984 -280.521472) (xy 43.050046 -280.529769)
			(xy 43.024806 -280.5303) (xy 43.018964 -280.5303) (xy 43.005502 -280.529538) (xy 42.980577 -280.527458)
			(xy 42.931846 -280.516205) (xy 42.8856 -280.497161) (xy 42.843076 -280.470836) (xy 42.80541 -280.437933)
			(xy 42.77361 -280.399331) (xy 42.748526 -280.356063) (xy 42.730828 -280.309286) (xy 42.72099 -280.26025)
			(xy 42.719274 -280.210266) (xy 42.725727 -280.16067) (xy 42.740176 -280.11279) (xy 42.75074 -280.090118)
			(xy 42.762583 -280.06724) (xy 42.792733 -280.025473) (xy 42.82945 -279.989344) (xy 42.871698 -279.95987)
			(xy 42.894758 -279.948386) (xy 42.899076 -279.946354) (xy 42.905192 -279.94245) (xy 42.915114 -279.931872)
			(xy 42.918634 -279.925526) (xy 42.92219 -279.916382) (xy 42.930572 -279.870154) (xy 42.938192 -279.827228)
			(xy 42.939172 -279.817092) (xy 42.933921 -279.797437) (xy 42.928032 -279.789128) (xy 42.926 -279.786588)
			(xy 42.515028 -279.375616) (xy 42.51198 -279.372822) (xy 42.502328 -279.366472) (xy 42.494832 -279.363005)
			(xy 42.47851 -279.360549) (xy 42.470324 -279.361646) (xy 42.42943 -279.369012) (xy 42.385996 -279.376886)
			(xy 42.381402 -279.378002) (xy 42.372705 -279.381703) (xy 42.368724 -279.384252) (xy 42.35323 -279.400762)
			(xy 42.349928 -279.407874) (xy 42.338817 -279.429661) (xy 42.31073 -279.469694) (xy 42.276631 -279.504748)
			(xy 42.237388 -279.533929) (xy 42.194001 -279.556493) (xy 42.147577 -279.571866) (xy 42.099298 -279.579655)
			(xy 42.074846 -279.580086) (xy 42.050851 -279.579643) (xy 42.003451 -279.572142) (xy 41.957809 -279.557317)
			(xy 41.915048 -279.535534) (xy 41.876222 -279.507329) (xy 41.842287 -279.473396) (xy 41.814078 -279.434572)
			(xy 41.792292 -279.391813) (xy 41.777464 -279.346172) (xy 41.769959 -279.298773) (xy 41.769538 -279.274778)
			(xy 41.770028 -279.249917) (xy 41.778081 -279.200853) (xy 41.793972 -279.15374) (xy 41.817282 -279.109821)
			(xy 41.847394 -279.070256) (xy 41.883515 -279.036088) (xy 41.924692 -279.008218) (xy 41.947084 -278.99741)
			(xy 41.954958 -278.993854) (xy 41.955466 -278.9936) (xy 41.980612 -278.984202) (xy 41.980866 -278.984202)
			(xy 41.984422 -278.982932) (xy 41.988927 -278.980922) (xy 41.997116 -278.975423) (xy 42.000678 -278.97201)
			(xy 42.13479 -278.837898) (xy 42.137495 -278.835046) (xy 42.142085 -278.828667) (xy 42.143934 -278.825198)
			(xy 42.14652 -278.819772) (xy 42.149351 -278.808092) (xy 42.149522 -278.802084) (xy 42.149522 -278.729948)
			(xy 42.149014 -278.72309) (xy 42.147975 -278.717158) (xy 42.143485 -278.705989) (xy 42.140124 -278.700992)
			(xy 42.135806 -278.695912) (xy 42.135298 -278.695404) (xy 42.129456 -278.689308) (xy 42.085768 -278.642826)
			(xy 42.079882 -278.637683) (xy 42.065784 -278.630949) (xy 42.058082 -278.629618) (xy 42.054272 -278.629364)
			(xy 42.030204 -278.627298) (xy 41.983115 -278.61653) (xy 41.93831 -278.59848) (xy 41.896907 -278.573599)
			(xy 41.85994 -278.542508) (xy 41.82833 -278.505982) (xy 41.802868 -278.464934) (xy 41.784189 -278.420388)
			(xy 41.772758 -278.373456) (xy 41.768862 -278.325309) (xy 41.772598 -278.277149) (xy 41.783872 -278.230179)
			(xy 41.802403 -278.185571) (xy 41.827728 -278.144439) (xy 41.859216 -278.107808) (xy 41.89608 -278.076594)
			(xy 41.9374 -278.051575) (xy 41.982145 -278.033376) (xy 42.029197 -278.022452) (xy 42.053256 -278.020272)
			(xy 42.054272 -278.020272) (xy 42.056558 -278.020018) (xy 42.064744 -278.018839) (xy 42.079783 -278.011983)
			(xy 42.086022 -278.006556) (xy 42.129456 -277.960328) (xy 42.135298 -277.954232) (xy 42.135806 -277.953724)
			(xy 42.140124 -277.948644) (xy 42.143471 -277.94364) (xy 42.147955 -277.932472) (xy 42.149014 -277.926546)
			(xy 42.149522 -277.919688) (xy 42.149522 -277.779988) (xy 42.149014 -277.77313) (xy 42.14798 -277.767197)
			(xy 42.143496 -277.756022) (xy 42.140124 -277.751032) (xy 42.135806 -277.745952) (xy 42.135298 -277.745444)
			(xy 42.129456 -277.739348) (xy 42.085768 -277.692866) (xy 42.079883 -277.687719) (xy 42.065786 -277.68098)
			(xy 42.058082 -277.679658) (xy 42.054272 -277.679404) (xy 42.030201 -277.677338) (xy 41.983106 -277.666569)
			(xy 41.938295 -277.648517) (xy 41.896886 -277.623633) (xy 41.859914 -277.592538) (xy 41.8283 -277.556008)
			(xy 41.802834 -277.514955) (xy 41.784152 -277.470403) (xy 41.772719 -277.423465) (xy 41.768822 -277.375312)
			(xy 41.772558 -277.327146) (xy 41.783833 -277.28017) (xy 41.802366 -277.235556) (xy 41.827695 -277.194417)
			(xy 41.859186 -277.157781) (xy 41.896055 -277.126563) (xy 41.93738 -277.10154) (xy 41.98213 -277.083339)
			(xy 42.029189 -277.072413) (xy 42.053256 -277.070312) (xy 42.054272 -277.070312) (xy 42.056558 -277.070058)
			(xy 42.064742 -277.068877) (xy 42.079777 -277.062015) (xy 42.086022 -277.056596) (xy 42.129456 -277.010368)
			(xy 42.135298 -277.004272) (xy 42.135806 -277.003764) (xy 42.140124 -276.998684) (xy 42.143474 -276.993682)
			(xy 42.147967 -276.982515) (xy 42.149014 -276.976586) (xy 42.149522 -276.969728) (xy 42.149522 -276.830028)
			(xy 42.149014 -276.82317) (xy 42.147973 -276.817239) (xy 42.143479 -276.806072) (xy 42.140124 -276.801072)
			(xy 42.135806 -276.795992) (xy 42.135298 -276.795484) (xy 42.129456 -276.789388) (xy 42.085768 -276.742906)
			(xy 42.079881 -276.737764) (xy 42.065783 -276.731033) (xy 42.058082 -276.729698) (xy 42.054272 -276.729444)
			(xy 42.030206 -276.727378) (xy 41.98312 -276.716611) (xy 41.938318 -276.698562) (xy 41.896918 -276.673682)
			(xy 41.859953 -276.642593) (xy 41.828345 -276.606069) (xy 41.802885 -276.565024) (xy 41.784207 -276.52048)
			(xy 41.772778 -276.473551) (xy 41.768882 -276.425407) (xy 41.772618 -276.377251) (xy 41.783891 -276.330284)
			(xy 41.802421 -276.285679) (xy 41.827745 -276.244549) (xy 41.859231 -276.207921) (xy 41.896093 -276.176709)
			(xy 41.93741 -276.151692) (xy 41.982152 -276.133495) (xy 42.029202 -276.122571) (xy 42.053256 -276.120352)
			(xy 42.054272 -276.120352) (xy 42.056558 -276.120098) (xy 42.064743 -276.118918) (xy 42.079781 -276.11206)
			(xy 42.086022 -276.106636) (xy 42.129456 -276.060408) (xy 42.135298 -276.054312) (xy 42.135806 -276.053804)
			(xy 42.140124 -276.048724) (xy 42.143469 -276.04372) (xy 42.147948 -276.032551) (xy 42.149014 -276.026626)
			(xy 42.149522 -276.019768) (xy 42.149522 -275.880068) (xy 42.149014 -275.87321) (xy 42.147977 -275.867278)
			(xy 42.143491 -275.856105) (xy 42.140124 -275.851112) (xy 42.135806 -275.846032) (xy 42.135298 -275.845524)
			(xy 42.129456 -275.839428) (xy 42.085768 -275.792946) (xy 42.079883 -275.787801) (xy 42.065785 -275.781065)
			(xy 42.058082 -275.779738) (xy 42.054272 -275.779484) (xy 42.030203 -275.777418) (xy 41.983111 -275.766649)
			(xy 41.938303 -275.748599) (xy 41.896897 -275.723716) (xy 41.859927 -275.692623) (xy 41.828315 -275.656095)
			(xy 41.802851 -275.615044) (xy 41.78417 -275.570495) (xy 41.772739 -275.52356) (xy 41.768842 -275.47541)
			(xy 41.772578 -275.427248) (xy 41.783853 -275.380275) (xy 41.802385 -275.335663) (xy 41.827712 -275.294528)
			(xy 41.859201 -275.257895) (xy 41.896067 -275.226678) (xy 41.93739 -275.201658) (xy 41.982138 -275.183458)
			(xy 42.029193 -275.172532) (xy 42.053256 -275.170392) (xy 42.054272 -275.170392) (xy 42.056558 -275.170138)
			(xy 42.064744 -275.168959) (xy 42.079785 -275.162106) (xy 42.086022 -275.156676) (xy 42.129456 -275.110448)
			(xy 42.135298 -275.104352) (xy 42.135806 -275.103844) (xy 42.140124 -275.098764) (xy 42.143472 -275.093761)
			(xy 42.147961 -275.082594) (xy 42.149014 -275.076666) (xy 42.149522 -275.069808) (xy 42.149522 -274.930108)
			(xy 42.149014 -274.92325) (xy 42.147971 -274.91732) (xy 42.143473 -274.906156) (xy 42.140124 -274.901152)
			(xy 42.135806 -274.896072) (xy 42.135298 -274.895564) (xy 42.129456 -274.889468) (xy 42.085768 -274.842986)
			(xy 42.079884 -274.837837) (xy 42.065787 -274.831096) (xy 42.058082 -274.829778) (xy 42.054272 -274.829524)
			(xy 42.030199 -274.827457) (xy 41.983101 -274.816688) (xy 41.938287 -274.798636) (xy 41.896876 -274.77375)
			(xy 41.8599 -274.742653) (xy 41.828284 -274.706121) (xy 41.802817 -274.665065) (xy 41.784133 -274.62051)
			(xy 41.7727 -274.573569) (xy 41.768802 -274.525413) (xy 41.772538 -274.477244) (xy 41.783814 -274.430265)
			(xy 41.802348 -274.385648) (xy 41.827678 -274.344507) (xy 41.859171 -274.307868) (xy 41.896042 -274.276647)
			(xy 41.93737 -274.251623) (xy 41.982123 -274.23342) (xy 42.029184 -274.222493) (xy 42.053256 -274.220432)
			(xy 42.054272 -274.220432) (xy 42.056558 -274.220178) (xy 42.064743 -274.218997) (xy 42.079779 -274.212138)
			(xy 42.086022 -274.206716) (xy 42.129456 -274.160488) (xy 42.135298 -274.154392) (xy 42.135806 -274.153884)
			(xy 42.140124 -274.148804) (xy 42.143476 -274.143802) (xy 42.147973 -274.132636) (xy 42.149014 -274.126706)
			(xy 42.149522 -274.119848) (xy 42.149522 -273.979894) (xy 42.149014 -273.973036) (xy 42.14798 -273.967102)
			(xy 42.143498 -273.955926) (xy 42.140124 -273.950938) (xy 42.135806 -273.945858) (xy 42.135298 -273.94535)
			(xy 42.129456 -273.939254) (xy 42.085768 -273.892772) (xy 42.079884 -273.887624) (xy 42.065787 -273.880885)
			(xy 42.058082 -273.879564) (xy 42.054272 -273.87931) (xy 42.030201 -273.877243) (xy 41.983105 -273.866475)
			(xy 41.938293 -273.848423) (xy 41.896883 -273.823538) (xy 41.85991 -273.792443) (xy 41.828295 -273.755912)
			(xy 41.802829 -273.714858) (xy 41.784146 -273.670305) (xy 41.772713 -273.623366) (xy 41.768816 -273.575212)
			(xy 41.772552 -273.527045) (xy 41.783827 -273.480068) (xy 41.802361 -273.435453) (xy 41.82769 -273.394314)
			(xy 41.859182 -273.357677) (xy 41.896051 -273.326458) (xy 41.937377 -273.301435) (xy 41.982128 -273.283233)
			(xy 42.029187 -273.272307) (xy 42.053256 -273.270218) (xy 42.054272 -273.270218) (xy 42.056558 -273.269964)
			(xy 42.064742 -273.268783) (xy 42.079778 -273.261922) (xy 42.086022 -273.256502) (xy 42.129456 -273.210274)
			(xy 42.135298 -273.204178) (xy 42.135806 -273.20367) (xy 42.140124 -273.19859) (xy 42.143475 -273.193588)
			(xy 42.147969 -273.182421) (xy 42.149014 -273.176492) (xy 42.149522 -273.169634) (xy 42.149522 -273.029934)
			(xy 42.149014 -273.023076) (xy 42.147974 -273.017145) (xy 42.143481 -273.005977) (xy 42.140124 -273.000978)
			(xy 42.135806 -272.995898) (xy 42.135298 -272.99539) (xy 42.129456 -272.989294) (xy 42.085768 -272.942812)
			(xy 42.079881 -272.937669) (xy 42.065784 -272.930938) (xy 42.058082 -272.929604) (xy 42.054272 -272.92935)
			(xy 42.030205 -272.927284) (xy 41.983119 -272.916516) (xy 41.938316 -272.898467) (xy 41.896915 -272.873587)
			(xy 41.859949 -272.842497) (xy 41.828341 -272.805973) (xy 41.80288 -272.764927) (xy 41.784202 -272.720382)
			(xy 41.772772 -272.673452) (xy 41.768876 -272.625308) (xy 41.772612 -272.577151) (xy 41.783886 -272.530183)
			(xy 41.802416 -272.485577) (xy 41.82774 -272.444446) (xy 41.859227 -272.407817) (xy 41.896089 -272.376604)
			(xy 41.937407 -272.351587) (xy 41.98215 -272.333389) (xy 42.029201 -272.322465) (xy 42.053256 -272.320258)
			(xy 42.054272 -272.320258) (xy 42.056558 -272.320004) (xy 42.064743 -272.318824) (xy 42.079782 -272.311967)
			(xy 42.086022 -272.306542) (xy 42.129456 -272.260314) (xy 42.135298 -272.254218) (xy 42.135806 -272.25371)
			(xy 42.140124 -272.24863) (xy 42.143469 -272.243626) (xy 42.14795 -272.232457) (xy 42.149014 -272.226532)
			(xy 42.149522 -272.219674) (xy 42.149522 -271.321276) (xy 42.148951 -271.310159) (xy 42.139547 -271.290011)
			(xy 42.12251 -271.275724) (xy 42.11193 -271.272254) (xy 42.085621 -271.264644) (xy 42.035347 -271.24292)
			(xy 41.9887 -271.214225) (xy 41.946639 -271.179149) (xy 41.910031 -271.138415) (xy 41.87963 -271.092861)
			(xy 41.85606 -271.043426) (xy 41.839808 -270.991126) (xy 41.83507 -270.964152) (xy 41.83507 -270.963898)
			(xy 41.832744 -270.952672) (xy 41.819664 -270.933872) (xy 41.809924 -270.92783) (xy 41.804082 -270.925036)
			(xy 41.724326 -270.89227) (xy 41.716224 -270.889297) (xy 41.699 -270.888402) (xy 41.682461 -270.893293)
			(xy 41.675304 -270.898112) (xy 41.67505 -270.898112) (xy 41.650475 -270.915248) (xy 41.597105 -270.942461)
			(xy 41.540139 -270.961001) (xy 41.480975 -270.970412) (xy 41.451022 -270.97101) (xy 41.450514 -270.97101)
			(xy 41.42326 -270.970548) (xy 41.369308 -270.962792) (xy 41.317008 -270.947437) (xy 41.267426 -270.924796)
			(xy 41.221571 -270.895328) (xy 41.180376 -270.859634) (xy 41.144681 -270.818441) (xy 41.115211 -270.772587)
			(xy 41.092568 -270.723005) (xy 41.077211 -270.670706) (xy 41.069453 -270.616754) (xy 41.069453 -270.562246)
			(xy 41.077211 -270.508294) (xy 41.092568 -270.455995) (xy 41.115211 -270.406413) (xy 41.144681 -270.360559)
			(xy 41.180376 -270.319366) (xy 41.221571 -270.283672) (xy 41.267426 -270.254204) (xy 41.317008 -270.231563)
			(xy 41.369308 -270.216208) (xy 41.42326 -270.208452) (xy 41.450514 -270.207994) (xy 41.477464 -270.20846)
			(xy 41.530827 -270.21605) (xy 41.582589 -270.231078) (xy 41.63172 -270.253243) (xy 41.677242 -270.282105)
			(xy 41.718246 -270.317088) (xy 41.753918 -270.357495) (xy 41.783545 -270.402522) (xy 41.806538 -270.451271)
			(xy 41.822438 -270.502772) (xy 41.827196 -270.529304) (xy 41.827196 -270.529558) (xy 41.829536 -270.540773)
			(xy 41.842635 -270.55954) (xy 41.852342 -270.565626) (xy 41.858184 -270.56842) (xy 41.938194 -270.601186)
			(xy 41.9442 -270.603492) (xy 41.956932 -270.605302) (xy 41.96334 -270.604742) (xy 41.976548 -270.603218)
			(xy 41.987216 -270.595344) (xy 42.006169 -270.581996) (xy 42.046696 -270.559488) (xy 42.089648 -270.542048)
			(xy 42.11193 -270.535654) (xy 42.122519 -270.532216) (xy 42.139542 -270.517906) (xy 42.148938 -270.497751)
			(xy 42.149522 -270.486632) (xy 42.149522 -267.793978) (xy 42.149268 -267.791692) (xy 42.149268 -267.790676)
			(xy 42.08653 -267.07846) (xy 41.944036 -265.45921) (xy 41.943528 -265.455146) (xy 41.86047 -264.954512)
			(xy 41.859451 -264.94953) (xy 41.855745 -264.940062) (xy 41.853104 -264.935716) (xy 41.84777 -264.92708)
			(xy 41.841674 -264.923016) (xy 41.811956 -264.90295) (xy 41.806478 -264.900035) (xy 41.79453 -264.896696)
			(xy 41.788334 -264.896346) (xy 41.772586 -264.898378) (xy 41.76903 -264.899394) (xy 41.743115 -264.90641)
			(xy 41.689956 -264.913935) (xy 41.663112 -264.91438) (xy 41.635859 -264.913917) (xy 41.581909 -264.906162)
			(xy 41.529611 -264.890806) (xy 41.480031 -264.868164) (xy 41.434178 -264.838696) (xy 41.392987 -264.803002)
			(xy 41.357294 -264.761809) (xy 41.327828 -264.715955) (xy 41.305188 -264.666374) (xy 41.289835 -264.614076)
			(xy 41.282081 -264.560125) (xy 41.281604 -264.532872) (xy 41.282074 -264.505873) (xy 41.289689 -264.452416)
			(xy 41.304765 -264.400566) (xy 41.326999 -264.351359) (xy 41.355949 -264.305778) (xy 41.391034 -264.264733)
			(xy 41.431555 -264.229044) (xy 41.476703 -264.199423) (xy 41.525575 -264.176463) (xy 41.577196 -264.160622)
			(xy 41.630535 -264.152215) (xy 41.657524 -264.151364) (xy 41.668192 -264.151364) (xy 41.67759 -264.147046)
			(xy 41.6823 -264.144782) (xy 41.690749 -264.138637) (xy 41.694354 -264.134854) (xy 41.744138 -264.079736)
			(xy 41.74683 -264.076635) (xy 41.751294 -264.069742) (xy 41.753028 -264.06602) (xy 41.755413 -264.060031)
			(xy 41.757466 -264.04731) (xy 41.757092 -264.040874) (xy 41.127934 -256.946654) (xy 41.126764 -256.937923)
			(xy 41.119356 -256.921954) (xy 41.113456 -256.915412) (xy 39.19982 -255.001776) (xy 39.196971 -254.999067)
			(xy 39.190595 -254.994469) (xy 39.18712 -254.992632) (xy 39.181693 -254.990051) (xy 39.170013 -254.987234)
			(xy 39.164006 -254.987044) (xy 1.841246 -254.987044) (xy 1.835236 -254.987211) (xy 1.823553 -254.990033)
			(xy 1.818132 -254.992632) (xy 1.814657 -254.99447) (xy 1.808275 -254.999061) (xy 1.805432 -255.001776)
			(xy 1.449578 -255.35763) (xy 1.446876 -255.360484) (xy 1.442291 -255.366866) (xy 1.440434 -255.37033)
			(xy 1.437848 -255.375756) (xy 1.435019 -255.387436) (xy 1.434846 -255.393444) (xy 1.434846 -255.910588)
			(xy 21.87651 -255.910588) (xy 21.880581 -255.854966) (xy 21.892707 -255.800529) (xy 21.91263 -255.748438)
			(xy 21.939926 -255.699803) (xy 21.974012 -255.65566) (xy 22.014161 -255.616951) (xy 22.059519 -255.5845)
			(xy 22.109119 -255.558999) (xy 22.161903 -255.540992) (xy 22.216746 -255.530862) (xy 22.27248 -255.528825)
			(xy 22.327917 -255.534925) (xy 22.381874 -255.549031) (xy 22.433203 -255.570843) (xy 22.480809 -255.599897)
			(xy 22.523677 -255.635572) (xy 22.558963 -255.674954) (xy 22.765453 -255.674954) (xy 22.765453 -255.620446)
			(xy 22.773211 -255.566494) (xy 22.788567 -255.514195) (xy 22.811211 -255.464614) (xy 22.84068 -255.41876)
			(xy 22.876375 -255.377567) (xy 22.91757 -255.341873) (xy 22.963424 -255.312405) (xy 23.013006 -255.289763)
			(xy 23.065306 -255.274408) (xy 23.119258 -255.266653) (xy 23.146512 -255.26619) (xy 23.176121 -255.266801)
			(xy 23.23463 -255.275939) (xy 23.291025 -255.29401) (xy 23.343949 -255.320578) (xy 23.392131 -255.355006)
			(xy 23.434414 -255.396466) (xy 23.469782 -255.443963) (xy 23.484078 -255.469898) (xy 23.491605 -255.482931)
			(xy 23.512833 -255.504246) (xy 23.539345 -255.518463) (xy 23.568845 -255.524353) (xy 23.598783 -255.521405)
			(xy 23.626568 -255.509874) (xy 23.649797 -255.490759) (xy 23.658576 -255.478534) (xy 23.673758 -255.456285)
			(xy 23.709456 -255.415951) (xy 23.750471 -255.381036) (xy 23.795986 -255.352233) (xy 23.845098 -255.330115)
			(xy 23.896832 -255.31512) (xy 23.95016 -255.307547) (xy 23.977092 -255.307084) (xy 24.004345 -255.307563)
			(xy 24.058295 -255.315319) (xy 24.110593 -255.330674) (xy 24.160173 -255.353315) (xy 24.206026 -255.382782)
			(xy 24.247219 -255.418475) (xy 24.282913 -255.459667) (xy 24.312381 -255.50552) (xy 24.335024 -255.555099)
			(xy 24.35038 -255.607397) (xy 24.358137 -255.661347) (xy 24.358137 -255.715853) (xy 24.35038 -255.769803)
			(xy 24.335024 -255.822101) (xy 24.312381 -255.87168) (xy 24.282913 -255.917533) (xy 24.247219 -255.958725)
			(xy 24.206026 -255.994418) (xy 24.160173 -256.023885) (xy 24.110593 -256.046526) (xy 24.058295 -256.061881)
			(xy 24.004345 -256.069637) (xy 23.977092 -256.0701) (xy 23.947483 -256.06949) (xy 23.888973 -256.060353)
			(xy 23.832579 -256.042282) (xy 23.779655 -256.015714) (xy 23.731472 -255.981286) (xy 23.68919 -255.939825)
			(xy 23.653822 -255.892327) (xy 23.639526 -255.866392) (xy 23.631993 -255.853363) (xy 23.610765 -255.83205)
			(xy 23.584256 -255.817834) (xy 23.554757 -255.811945) (xy 23.524821 -255.814892) (xy 23.497037 -255.82642)
			(xy 23.473808 -255.845532) (xy 23.465028 -255.857756) (xy 23.44984 -255.88) (xy 23.414143 -255.920335)
			(xy 23.37313 -255.955251) (xy 23.327616 -255.984055) (xy 23.278504 -256.006174) (xy 23.226771 -256.021169)
			(xy 23.173443 -256.028743) (xy 23.146512 -256.029206) (xy 23.119258 -256.028747) (xy 23.065306 -256.020992)
			(xy 23.013006 -256.005637) (xy 22.963424 -255.982995) (xy 22.91757 -255.953527) (xy 22.876375 -255.917833)
			(xy 22.84068 -255.87664) (xy 22.811211 -255.830786) (xy 22.788567 -255.781205) (xy 22.773211 -255.728906)
			(xy 22.765453 -255.674954) (xy 22.558963 -255.674954) (xy 22.560894 -255.677109) (xy 22.591667 -255.723622)
			(xy 22.615339 -255.774119) (xy 22.631407 -255.827526) (xy 22.639527 -255.882702) (xy 22.640036 -255.910588)
			(xy 22.639527 -255.938474) (xy 22.631407 -255.99365) (xy 22.615339 -256.047057) (xy 22.591667 -256.097554)
			(xy 22.560894 -256.144067) (xy 22.523677 -256.185604) (xy 22.480809 -256.221279) (xy 22.433203 -256.250333)
			(xy 22.381874 -256.272145) (xy 22.327917 -256.286251) (xy 22.27248 -256.292351) (xy 22.216746 -256.290314)
			(xy 22.161903 -256.280184) (xy 22.109119 -256.262177) (xy 22.059519 -256.236676) (xy 22.014161 -256.204225)
			(xy 21.974012 -256.165516) (xy 21.939926 -256.121373) (xy 21.91263 -256.072738) (xy 21.892707 -256.020647)
			(xy 21.880581 -255.96621) (xy 21.87651 -255.910588) (xy 1.434846 -255.910588) (xy 1.434846 -256.440178)
			(xy 1.431529 -256.443706) (xy 1.426155 -256.45176) (xy 1.424178 -256.45618) (xy 1.420114 -256.465832)
			(xy 1.420114 -256.479621) (xy 25.279328 -256.479621) (xy 25.279328 -256.425119) (xy 25.287084 -256.371171)
			(xy 25.302439 -256.318876) (xy 25.325081 -256.269299) (xy 25.354547 -256.223449) (xy 25.390238 -256.182258)
			(xy 25.431429 -256.146567) (xy 25.477279 -256.117101) (xy 25.526856 -256.094459) (xy 25.579151 -256.079104)
			(xy 25.633099 -256.071348) (xy 25.66035 -256.070862) (xy 25.686666 -256.071276) (xy 25.738798 -256.078519)
			(xy 25.789442 -256.092847) (xy 25.837641 -256.11399) (xy 25.882483 -256.141546) (xy 25.92312 -256.174995)
			(xy 25.941274 -256.194052) (xy 25.94881 -256.201437) (xy 25.968079 -256.209972) (xy 25.978612 -256.210562)
			(xy 26.053288 -256.210562) (xy 26.06384 -256.210051) (xy 26.083136 -256.201504) (xy 26.090626 -256.194052)
			(xy 26.108767 -256.174982) (xy 26.149401 -256.141528) (xy 26.194244 -256.113972) (xy 26.242448 -256.092836)
			(xy 26.293097 -256.078522) (xy 26.345233 -256.071299) (xy 26.37155 -256.070862) (xy 26.398801 -256.071348)
			(xy 26.452749 -256.079104) (xy 26.505044 -256.094459) (xy 26.513997 -256.098548) (xy 27.881832 -256.098548)
			(xy 27.885903 -256.042926) (xy 27.898029 -255.988489) (xy 27.917952 -255.936398) (xy 27.945248 -255.887763)
			(xy 27.979334 -255.84362) (xy 28.019483 -255.804911) (xy 28.064841 -255.77246) (xy 28.114441 -255.746959)
			(xy 28.167225 -255.728952) (xy 28.222068 -255.718822) (xy 28.277802 -255.716785) (xy 28.333239 -255.722885)
			(xy 28.387196 -255.736991) (xy 28.438525 -255.758803) (xy 28.486131 -255.787857) (xy 28.528999 -255.823532)
			(xy 28.566216 -255.865069) (xy 28.596989 -255.911582) (xy 28.620661 -255.962079) (xy 28.636729 -256.015486)
			(xy 28.644849 -256.070662) (xy 28.645358 -256.098548) (xy 28.644849 -256.126434) (xy 28.636729 -256.18161)
			(xy 28.620661 -256.235017) (xy 28.596989 -256.285514) (xy 28.566216 -256.332027) (xy 28.528999 -256.373564)
			(xy 28.526173 -256.375916) (xy 28.769562 -256.375916) (xy 28.773633 -256.320294) (xy 28.785759 -256.265857)
			(xy 28.805682 -256.213766) (xy 28.832978 -256.165131) (xy 28.867064 -256.120988) (xy 28.907213 -256.082279)
			(xy 28.952571 -256.049828) (xy 29.002171 -256.024327) (xy 29.054955 -256.00632) (xy 29.109798 -255.99619)
			(xy 29.165532 -255.994153) (xy 29.220969 -256.000253) (xy 29.274926 -256.014359) (xy 29.326255 -256.036171)
			(xy 29.373861 -256.065225) (xy 29.416729 -256.1009) (xy 29.453946 -256.142437) (xy 29.484719 -256.18895)
			(xy 29.508391 -256.239447) (xy 29.524459 -256.292854) (xy 29.532579 -256.34803) (xy 29.533088 -256.375916)
			(xy 30.245048 -256.375916) (xy 30.249119 -256.320294) (xy 30.261245 -256.265857) (xy 30.281168 -256.213766)
			(xy 30.308464 -256.165131) (xy 30.34255 -256.120988) (xy 30.382699 -256.082279) (xy 30.428057 -256.049828)
			(xy 30.477657 -256.024327) (xy 30.530441 -256.00632) (xy 30.585284 -255.99619) (xy 30.641018 -255.994153)
			(xy 30.696455 -256.000253) (xy 30.750412 -256.014359) (xy 30.801741 -256.036171) (xy 30.849347 -256.065225)
			(xy 30.892215 -256.1009) (xy 30.929432 -256.142437) (xy 30.960205 -256.18895) (xy 30.983877 -256.239447)
			(xy 30.999945 -256.292854) (xy 31.008065 -256.34803) (xy 31.008574 -256.375916) (xy 31.134048 -256.375916)
			(xy 31.138119 -256.320294) (xy 31.150245 -256.265857) (xy 31.170168 -256.213766) (xy 31.197464 -256.165131)
			(xy 31.23155 -256.120988) (xy 31.271699 -256.082279) (xy 31.317057 -256.049828) (xy 31.366657 -256.024327)
			(xy 31.419441 -256.00632) (xy 31.474284 -255.99619) (xy 31.530018 -255.994153) (xy 31.585455 -256.000253)
			(xy 31.639412 -256.014359) (xy 31.690741 -256.036171) (xy 31.738347 -256.065225) (xy 31.781215 -256.1009)
			(xy 31.818432 -256.142437) (xy 31.849205 -256.18895) (xy 31.872877 -256.239447) (xy 31.888945 -256.292854)
			(xy 31.897065 -256.34803) (xy 31.897574 -256.375916) (xy 31.897065 -256.403802) (xy 31.888945 -256.458978)
			(xy 31.872877 -256.512385) (xy 31.849205 -256.562882) (xy 31.818432 -256.609395) (xy 31.781215 -256.650932)
			(xy 31.738347 -256.686607) (xy 31.690741 -256.715661) (xy 31.639412 -256.737473) (xy 31.585455 -256.751579)
			(xy 31.530018 -256.757679) (xy 31.474284 -256.755642) (xy 31.419441 -256.745512) (xy 31.366657 -256.727505)
			(xy 31.317057 -256.702004) (xy 31.271699 -256.669553) (xy 31.23155 -256.630844) (xy 31.197464 -256.586701)
			(xy 31.170168 -256.538066) (xy 31.150245 -256.485975) (xy 31.138119 -256.431538) (xy 31.134048 -256.375916)
			(xy 31.008574 -256.375916) (xy 31.008065 -256.403802) (xy 30.999945 -256.458978) (xy 30.983877 -256.512385)
			(xy 30.960205 -256.562882) (xy 30.929432 -256.609395) (xy 30.892215 -256.650932) (xy 30.849347 -256.686607)
			(xy 30.801741 -256.715661) (xy 30.750412 -256.737473) (xy 30.696455 -256.751579) (xy 30.641018 -256.757679)
			(xy 30.585284 -256.755642) (xy 30.530441 -256.745512) (xy 30.477657 -256.727505) (xy 30.428057 -256.702004)
			(xy 30.382699 -256.669553) (xy 30.34255 -256.630844) (xy 30.308464 -256.586701) (xy 30.281168 -256.538066)
			(xy 30.261245 -256.485975) (xy 30.249119 -256.431538) (xy 30.245048 -256.375916) (xy 29.533088 -256.375916)
			(xy 29.532579 -256.403802) (xy 29.524459 -256.458978) (xy 29.508391 -256.512385) (xy 29.484719 -256.562882)
			(xy 29.453946 -256.609395) (xy 29.416729 -256.650932) (xy 29.373861 -256.686607) (xy 29.326255 -256.715661)
			(xy 29.274926 -256.737473) (xy 29.220969 -256.751579) (xy 29.165532 -256.757679) (xy 29.109798 -256.755642)
			(xy 29.054955 -256.745512) (xy 29.002171 -256.727505) (xy 28.952571 -256.702004) (xy 28.907213 -256.669553)
			(xy 28.867064 -256.630844) (xy 28.832978 -256.586701) (xy 28.805682 -256.538066) (xy 28.785759 -256.485975)
			(xy 28.773633 -256.431538) (xy 28.769562 -256.375916) (xy 28.526173 -256.375916) (xy 28.486131 -256.409239)
			(xy 28.438525 -256.438293) (xy 28.387196 -256.460105) (xy 28.333239 -256.474211) (xy 28.277802 -256.480311)
			(xy 28.222068 -256.478274) (xy 28.167225 -256.468144) (xy 28.114441 -256.450137) (xy 28.064841 -256.424636)
			(xy 28.019483 -256.392185) (xy 27.979334 -256.353476) (xy 27.945248 -256.309333) (xy 27.917952 -256.260698)
			(xy 27.898029 -256.208607) (xy 27.885903 -256.15417) (xy 27.881832 -256.098548) (xy 26.513997 -256.098548)
			(xy 26.554621 -256.117101) (xy 26.600471 -256.146567) (xy 26.641662 -256.182258) (xy 26.677353 -256.223449)
			(xy 26.706819 -256.269299) (xy 26.729461 -256.318876) (xy 26.744816 -256.371171) (xy 26.752572 -256.425119)
			(xy 26.752572 -256.479621) (xy 26.744816 -256.533569) (xy 26.729461 -256.585864) (xy 26.706819 -256.635441)
			(xy 26.677353 -256.681291) (xy 26.641662 -256.722482) (xy 26.600471 -256.758173) (xy 26.554621 -256.787639)
			(xy 26.505044 -256.810281) (xy 26.452749 -256.825636) (xy 26.398801 -256.833392) (xy 26.37155 -256.833878)
			(xy 26.345235 -256.833451) (xy 26.293104 -256.826209) (xy 26.24246 -256.811882) (xy 26.194261 -256.790742)
			(xy 26.149419 -256.763189) (xy 26.108781 -256.729743) (xy 26.090626 -256.710688) (xy 26.083098 -256.703294)
			(xy 26.063823 -256.694766) (xy 26.053288 -256.694178) (xy 25.978612 -256.694178) (xy 25.968062 -256.694706)
			(xy 25.948767 -256.703243) (xy 25.941274 -256.710688) (xy 25.923122 -256.729747) (xy 25.882492 -256.763204)
			(xy 25.837651 -256.790763) (xy 25.789449 -256.811901) (xy 25.738801 -256.826217) (xy 25.686666 -256.83344)
			(xy 25.66035 -256.833878) (xy 25.633099 -256.833392) (xy 25.579151 -256.825636) (xy 25.526856 -256.810281)
			(xy 25.477279 -256.787639) (xy 25.431429 -256.758173) (xy 25.390238 -256.722482) (xy 25.354547 -256.681291)
			(xy 25.325081 -256.635441) (xy 25.302439 -256.585864) (xy 25.287084 -256.533569) (xy 25.279328 -256.479621)
			(xy 1.420114 -256.479621) (xy 1.420114 -256.987548) (xy 27.881832 -256.987548) (xy 27.885903 -256.931926)
			(xy 27.898029 -256.877489) (xy 27.917952 -256.825398) (xy 27.945248 -256.776763) (xy 27.979334 -256.73262)
			(xy 28.019483 -256.693911) (xy 28.064841 -256.66146) (xy 28.114441 -256.635959) (xy 28.167225 -256.617952)
			(xy 28.222068 -256.607822) (xy 28.277802 -256.605785) (xy 28.333239 -256.611885) (xy 28.387196 -256.625991)
			(xy 28.438525 -256.647803) (xy 28.486131 -256.676857) (xy 28.528999 -256.712532) (xy 28.566216 -256.754069)
			(xy 28.596989 -256.800582) (xy 28.620661 -256.851079) (xy 28.636729 -256.904486) (xy 28.644849 -256.959662)
			(xy 28.645358 -256.987548) (xy 28.644849 -257.015434) (xy 28.636729 -257.07061) (xy 28.620661 -257.124017)
			(xy 28.614145 -257.137916) (xy 34.296096 -257.137916) (xy 34.296647 -257.108534) (xy 34.305675 -257.050468)
			(xy 34.323505 -256.994474) (xy 34.349715 -256.941879) (xy 34.383683 -256.893927) (xy 34.424606 -256.851754)
			(xy 34.447734 -256.833624) (xy 34.456655 -256.826141) (xy 34.467116 -256.805369) (xy 34.4678 -256.793746)
			(xy 34.46907 -256.70764) (xy 34.46653 -256.696464) (xy 34.464244 -256.691384) (xy 34.46164 -256.6862)
			(xy 34.45445 -256.677097) (xy 34.45002 -256.67335) (xy 34.42817 -256.655146) (xy 34.389629 -256.613328)
			(xy 34.357722 -256.566252) (xy 34.333155 -256.514962) (xy 34.316472 -256.460593) (xy 34.308044 -256.404351)
			(xy 34.307526 -256.375916) (xy 34.308012 -256.348665) (xy 34.315768 -256.294717) (xy 34.331123 -256.242422)
			(xy 34.353765 -256.192845) (xy 34.383231 -256.146995) (xy 34.418922 -256.105804) (xy 34.460113 -256.070113)
			(xy 34.505963 -256.040647) (xy 34.55554 -256.018005) (xy 34.607835 -256.00265) (xy 34.661783 -255.994894)
			(xy 34.716285 -255.994894) (xy 34.770233 -256.00265) (xy 34.822528 -256.018005) (xy 34.872105 -256.040647)
			(xy 34.917955 -256.070113) (xy 34.959146 -256.105804) (xy 34.994837 -256.146995) (xy 35.024303 -256.192845)
			(xy 35.046945 -256.242422) (xy 35.0623 -256.294717) (xy 35.070056 -256.348665) (xy 35.070542 -256.375916)
			(xy 35.069999 -256.405298) (xy 35.060967 -256.463364) (xy 35.043134 -256.519357) (xy 35.016923 -256.571952)
			(xy 34.982954 -256.619904) (xy 34.942031 -256.662077) (xy 34.918904 -256.680208) (xy 34.909958 -256.687666)
			(xy 34.899513 -256.708457) (xy 34.898838 -256.720086) (xy 34.897568 -256.806192) (xy 34.900108 -256.817368)
			(xy 34.902394 -256.822448) (xy 34.905003 -256.827629) (xy 34.912191 -256.836733) (xy 34.916618 -256.840482)
			(xy 34.938443 -256.858714) (xy 34.976984 -256.900528) (xy 35.008893 -256.947598) (xy 35.033464 -256.998883)
			(xy 35.050153 -257.053245) (xy 35.058589 -257.109483) (xy 35.059112 -257.137916) (xy 35.692586 -257.137916)
			(xy 35.696657 -257.082294) (xy 35.708783 -257.027857) (xy 35.728706 -256.975766) (xy 35.756002 -256.927131)
			(xy 35.790088 -256.882988) (xy 35.830237 -256.844279) (xy 35.875595 -256.811828) (xy 35.925195 -256.786327)
			(xy 35.977979 -256.76832) (xy 36.032822 -256.75819) (xy 36.088556 -256.756153) (xy 36.143993 -256.762253)
			(xy 36.19795 -256.776359) (xy 36.249279 -256.798171) (xy 36.296885 -256.827225) (xy 36.339753 -256.8629)
			(xy 36.37697 -256.904437) (xy 36.407743 -256.95095) (xy 36.431415 -257.001447) (xy 36.447483 -257.054854)
			(xy 36.455603 -257.11003) (xy 36.456112 -257.137916) (xy 36.579046 -257.137916) (xy 36.583117 -257.082294)
			(xy 36.595243 -257.027857) (xy 36.615166 -256.975766) (xy 36.642462 -256.927131) (xy 36.676548 -256.882988)
			(xy 36.716697 -256.844279) (xy 36.762055 -256.811828) (xy 36.811655 -256.786327) (xy 36.864439 -256.76832)
			(xy 36.919282 -256.75819) (xy 36.975016 -256.756153) (xy 37.030453 -256.762253) (xy 37.08441 -256.776359)
			(xy 37.135739 -256.798171) (xy 37.183345 -256.827225) (xy 37.226213 -256.8629) (xy 37.26343 -256.904437)
			(xy 37.294203 -256.95095) (xy 37.317875 -257.001447) (xy 37.333943 -257.054854) (xy 37.342063 -257.11003)
			(xy 37.342572 -257.137916) (xy 37.342063 -257.165802) (xy 37.333943 -257.220978) (xy 37.317875 -257.274385)
			(xy 37.294203 -257.324882) (xy 37.26343 -257.371395) (xy 37.226213 -257.412932) (xy 37.183345 -257.448607)
			(xy 37.135739 -257.477661) (xy 37.08441 -257.499473) (xy 37.030453 -257.513579) (xy 36.975016 -257.519679)
			(xy 36.919282 -257.517642) (xy 36.864439 -257.507512) (xy 36.811655 -257.489505) (xy 36.762055 -257.464004)
			(xy 36.716697 -257.431553) (xy 36.676548 -257.392844) (xy 36.642462 -257.348701) (xy 36.615166 -257.300066)
			(xy 36.595243 -257.247975) (xy 36.583117 -257.193538) (xy 36.579046 -257.137916) (xy 36.456112 -257.137916)
			(xy 36.455603 -257.165802) (xy 36.447483 -257.220978) (xy 36.431415 -257.274385) (xy 36.407743 -257.324882)
			(xy 36.37697 -257.371395) (xy 36.339753 -257.412932) (xy 36.296885 -257.448607) (xy 36.249279 -257.477661)
			(xy 36.19795 -257.499473) (xy 36.143993 -257.513579) (xy 36.088556 -257.519679) (xy 36.032822 -257.517642)
			(xy 35.977979 -257.507512) (xy 35.925195 -257.489505) (xy 35.875595 -257.464004) (xy 35.830237 -257.431553)
			(xy 35.790088 -257.392844) (xy 35.756002 -257.348701) (xy 35.728706 -257.300066) (xy 35.708783 -257.247975)
			(xy 35.696657 -257.193538) (xy 35.692586 -257.137916) (xy 35.059112 -257.137916) (xy 35.058626 -257.165167)
			(xy 35.05087 -257.219115) (xy 35.035515 -257.27141) (xy 35.012873 -257.320987) (xy 34.983407 -257.366837)
			(xy 34.947716 -257.408028) (xy 34.906525 -257.443719) (xy 34.860675 -257.473185) (xy 34.811098 -257.495827)
			(xy 34.758803 -257.511182) (xy 34.704855 -257.518938) (xy 34.650353 -257.518938) (xy 34.596405 -257.511182)
			(xy 34.54411 -257.495827) (xy 34.494533 -257.473185) (xy 34.448683 -257.443719) (xy 34.407492 -257.408028)
			(xy 34.371801 -257.366837) (xy 34.342335 -257.320987) (xy 34.319693 -257.27141) (xy 34.304338 -257.219115)
			(xy 34.296582 -257.165167) (xy 34.296096 -257.137916) (xy 28.614145 -257.137916) (xy 28.596989 -257.174514)
			(xy 28.566216 -257.221027) (xy 28.528999 -257.262564) (xy 28.486131 -257.298239) (xy 28.438525 -257.327293)
			(xy 28.387196 -257.349105) (xy 28.333239 -257.363211) (xy 28.277802 -257.369311) (xy 28.222068 -257.367274)
			(xy 28.167225 -257.357144) (xy 28.114441 -257.339137) (xy 28.064841 -257.313636) (xy 28.019483 -257.281185)
			(xy 27.979334 -257.242476) (xy 27.945248 -257.198333) (xy 27.917952 -257.149698) (xy 27.898029 -257.097607)
			(xy 27.885903 -257.04317) (xy 27.881832 -256.987548) (xy 1.420114 -256.987548) (xy 1.420114 -257.474212)
			(xy 21.97176 -257.474212) (xy 21.975831 -257.41859) (xy 21.987957 -257.364153) (xy 22.00788 -257.312062)
			(xy 22.035176 -257.263427) (xy 22.069262 -257.219284) (xy 22.109411 -257.180575) (xy 22.154769 -257.148124)
			(xy 22.204369 -257.122623) (xy 22.257153 -257.104616) (xy 22.311996 -257.094486) (xy 22.36773 -257.092449)
			(xy 22.423167 -257.098549) (xy 22.477124 -257.112655) (xy 22.528453 -257.134467) (xy 22.576059 -257.163521)
			(xy 22.618927 -257.199196) (xy 22.656144 -257.240733) (xy 22.686917 -257.287246) (xy 22.710589 -257.337743)
			(xy 22.726657 -257.39115) (xy 22.734777 -257.446326) (xy 22.735286 -257.474212) (xy 22.734777 -257.502098)
			(xy 22.726657 -257.557274) (xy 22.710589 -257.610681) (xy 22.686917 -257.661178) (xy 22.656144 -257.707691)
			(xy 22.618927 -257.749228) (xy 22.576059 -257.784903) (xy 22.528453 -257.813957) (xy 22.477124 -257.835769)
			(xy 22.423167 -257.849875) (xy 22.36773 -257.855975) (xy 22.311996 -257.853938) (xy 22.257153 -257.843808)
			(xy 22.204369 -257.825801) (xy 22.154769 -257.8003) (xy 22.109411 -257.767849) (xy 22.069262 -257.72914)
			(xy 22.035176 -257.684997) (xy 22.00788 -257.636362) (xy 21.987957 -257.584271) (xy 21.975831 -257.529834)
			(xy 21.97176 -257.474212) (xy 1.420114 -257.474212) (xy 1.420114 -258.665472) (xy 21.126448 -258.665472)
			(xy 21.130519 -258.60985) (xy 21.142645 -258.555413) (xy 21.162568 -258.503322) (xy 21.189864 -258.454687)
			(xy 21.22395 -258.410544) (xy 21.264099 -258.371835) (xy 21.309457 -258.339384) (xy 21.359057 -258.313883)
			(xy 21.411841 -258.295876) (xy 21.466684 -258.285746) (xy 21.522418 -258.283709) (xy 21.577855 -258.289809)
			(xy 21.631812 -258.303915) (xy 21.683141 -258.325727) (xy 21.730747 -258.354781) (xy 21.773615 -258.390456)
			(xy 21.810832 -258.431993) (xy 21.841605 -258.478506) (xy 21.865277 -258.529003) (xy 21.881345 -258.58241)
			(xy 21.889465 -258.637586) (xy 21.889691 -258.649978) (xy 22.926292 -258.649978) (xy 22.930363 -258.594356)
			(xy 22.942489 -258.539919) (xy 22.962412 -258.487828) (xy 22.989708 -258.439193) (xy 23.023794 -258.39505)
			(xy 23.063943 -258.356341) (xy 23.109301 -258.32389) (xy 23.158901 -258.298389) (xy 23.211685 -258.280382)
			(xy 23.266528 -258.270252) (xy 23.322262 -258.268215) (xy 23.375363 -258.274058) (xy 28.769562 -258.274058)
			(xy 28.773633 -258.218436) (xy 28.785759 -258.163999) (xy 28.805682 -258.111908) (xy 28.832978 -258.063273)
			(xy 28.867064 -258.01913) (xy 28.907213 -257.980421) (xy 28.952571 -257.94797) (xy 29.002171 -257.922469)
			(xy 29.054955 -257.904462) (xy 29.109798 -257.894332) (xy 29.165532 -257.892295) (xy 29.220969 -257.898395)
			(xy 29.274926 -257.912501) (xy 29.326255 -257.934313) (xy 29.373861 -257.963367) (xy 29.416729 -257.999042)
			(xy 29.453946 -258.040579) (xy 29.484719 -258.087092) (xy 29.508391 -258.137589) (xy 29.524459 -258.190996)
			(xy 29.532579 -258.246172) (xy 29.533088 -258.274058) (xy 30.2547 -258.274058) (xy 30.258771 -258.218436)
			(xy 30.270897 -258.163999) (xy 30.29082 -258.111908) (xy 30.318116 -258.063273) (xy 30.352202 -258.01913)
			(xy 30.392351 -257.980421) (xy 30.437709 -257.94797) (xy 30.487309 -257.922469) (xy 30.540093 -257.904462)
			(xy 30.594936 -257.894332) (xy 30.65067 -257.892295) (xy 30.706107 -257.898395) (xy 30.760064 -257.912501)
			(xy 30.811393 -257.934313) (xy 30.858999 -257.963367) (xy 30.901867 -257.999042) (xy 30.939084 -258.040579)
			(xy 30.969857 -258.087092) (xy 30.993529 -258.137589) (xy 31.009597 -258.190996) (xy 31.017717 -258.246172)
			(xy 31.018226 -258.274058) (xy 31.017717 -258.301944) (xy 31.009597 -258.35712) (xy 30.993529 -258.410527)
			(xy 30.969857 -258.461024) (xy 30.939084 -258.507537) (xy 30.901867 -258.549074) (xy 30.858999 -258.584749)
			(xy 30.811393 -258.613803) (xy 30.760064 -258.635615) (xy 30.706107 -258.649721) (xy 30.65067 -258.655821)
			(xy 30.594936 -258.653784) (xy 30.540093 -258.643654) (xy 30.487309 -258.625647) (xy 30.437709 -258.600146)
			(xy 30.392351 -258.567695) (xy 30.352202 -258.528986) (xy 30.318116 -258.484843) (xy 30.29082 -258.436208)
			(xy 30.270897 -258.384117) (xy 30.258771 -258.32968) (xy 30.2547 -258.274058) (xy 29.533088 -258.274058)
			(xy 29.532579 -258.301944) (xy 29.524459 -258.35712) (xy 29.508391 -258.410527) (xy 29.484719 -258.461024)
			(xy 29.453946 -258.507537) (xy 29.416729 -258.549074) (xy 29.373861 -258.584749) (xy 29.326255 -258.613803)
			(xy 29.274926 -258.635615) (xy 29.220969 -258.649721) (xy 29.165532 -258.655821) (xy 29.109798 -258.653784)
			(xy 29.054955 -258.643654) (xy 29.002171 -258.625647) (xy 28.952571 -258.600146) (xy 28.907213 -258.567695)
			(xy 28.867064 -258.528986) (xy 28.832978 -258.484843) (xy 28.805682 -258.436208) (xy 28.785759 -258.384117)
			(xy 28.773633 -258.32968) (xy 28.769562 -258.274058) (xy 23.375363 -258.274058) (xy 23.377699 -258.274315)
			(xy 23.431656 -258.288421) (xy 23.482985 -258.310233) (xy 23.530591 -258.339287) (xy 23.573459 -258.374962)
			(xy 23.610676 -258.416499) (xy 23.641449 -258.463012) (xy 23.665121 -258.513509) (xy 23.681189 -258.566916)
			(xy 23.689309 -258.622092) (xy 23.689818 -258.649978) (xy 23.689309 -258.677864) (xy 23.687357 -258.691126)
			(xy 24.410668 -258.691126) (xy 24.414739 -258.635504) (xy 24.426865 -258.581067) (xy 24.446788 -258.528976)
			(xy 24.474084 -258.480341) (xy 24.50817 -258.436198) (xy 24.548319 -258.397489) (xy 24.593677 -258.365038)
			(xy 24.643277 -258.339537) (xy 24.696061 -258.32153) (xy 24.750904 -258.3114) (xy 24.806638 -258.309363)
			(xy 24.862075 -258.315463) (xy 24.916032 -258.329569) (xy 24.967361 -258.351381) (xy 25.014967 -258.380435)
			(xy 25.057835 -258.41611) (xy 25.095052 -258.457647) (xy 25.125825 -258.50416) (xy 25.149497 -258.554657)
			(xy 25.165565 -258.608064) (xy 25.173685 -258.66324) (xy 25.174194 -258.691126) (xy 25.173685 -258.719012)
			(xy 25.165565 -258.774188) (xy 25.149497 -258.827595) (xy 25.125825 -258.878092) (xy 25.095052 -258.924605)
			(xy 25.057835 -258.966142) (xy 25.014967 -259.001817) (xy 24.967361 -259.030871) (xy 24.916032 -259.052683)
			(xy 24.862075 -259.066789) (xy 24.806638 -259.072889) (xy 24.750904 -259.070852) (xy 24.696061 -259.060722)
			(xy 24.643277 -259.042715) (xy 24.593677 -259.017214) (xy 24.548319 -258.984763) (xy 24.50817 -258.946054)
			(xy 24.474084 -258.901911) (xy 24.446788 -258.853276) (xy 24.426865 -258.801185) (xy 24.414739 -258.746748)
			(xy 24.410668 -258.691126) (xy 23.687357 -258.691126) (xy 23.681189 -258.73304) (xy 23.665121 -258.786447)
			(xy 23.641449 -258.836944) (xy 23.610676 -258.883457) (xy 23.573459 -258.924994) (xy 23.530591 -258.960669)
			(xy 23.482985 -258.989723) (xy 23.431656 -259.011535) (xy 23.377699 -259.025641) (xy 23.322262 -259.031741)
			(xy 23.266528 -259.029704) (xy 23.211685 -259.019574) (xy 23.158901 -259.001567) (xy 23.109301 -258.976066)
			(xy 23.063943 -258.943615) (xy 23.023794 -258.904906) (xy 22.989708 -258.860763) (xy 22.962412 -258.812128)
			(xy 22.942489 -258.760037) (xy 22.930363 -258.7056) (xy 22.926292 -258.649978) (xy 21.889691 -258.649978)
			(xy 21.889974 -258.665472) (xy 21.889465 -258.693358) (xy 21.881345 -258.748534) (xy 21.865277 -258.801941)
			(xy 21.841605 -258.852438) (xy 21.810832 -258.898951) (xy 21.773615 -258.940488) (xy 21.730747 -258.976163)
			(xy 21.683141 -259.005217) (xy 21.631812 -259.027029) (xy 21.577855 -259.041135) (xy 21.522418 -259.047235)
			(xy 21.466684 -259.045198) (xy 21.411841 -259.035068) (xy 21.359057 -259.017061) (xy 21.309457 -258.99156)
			(xy 21.264099 -258.959109) (xy 21.22395 -258.9204) (xy 21.189864 -258.876257) (xy 21.162568 -258.827622)
			(xy 21.142645 -258.775531) (xy 21.130519 -258.721094) (xy 21.126448 -258.665472) (xy 1.420114 -258.665472)
			(xy 1.420114 -259.576316) (xy 30.245048 -259.576316) (xy 30.249119 -259.520694) (xy 30.261245 -259.466257)
			(xy 30.281168 -259.414166) (xy 30.308464 -259.365531) (xy 30.34255 -259.321388) (xy 30.382699 -259.282679)
			(xy 30.428057 -259.250228) (xy 30.477657 -259.224727) (xy 30.530441 -259.20672) (xy 30.585284 -259.19659)
			(xy 30.641018 -259.194553) (xy 30.696455 -259.200653) (xy 30.750412 -259.214759) (xy 30.801741 -259.236571)
			(xy 30.849347 -259.265625) (xy 30.892215 -259.3013) (xy 30.929432 -259.342837) (xy 30.960205 -259.38935)
			(xy 30.983877 -259.439847) (xy 30.999945 -259.493254) (xy 31.008065 -259.54843) (xy 31.008574 -259.576316)
			(xy 31.134048 -259.576316) (xy 31.138119 -259.520694) (xy 31.150245 -259.466257) (xy 31.170168 -259.414166)
			(xy 31.197464 -259.365531) (xy 31.23155 -259.321388) (xy 31.271699 -259.282679) (xy 31.317057 -259.250228)
			(xy 31.366657 -259.224727) (xy 31.419441 -259.20672) (xy 31.474284 -259.19659) (xy 31.530018 -259.194553)
			(xy 31.585455 -259.200653) (xy 31.639412 -259.214759) (xy 31.690741 -259.236571) (xy 31.738347 -259.265625)
			(xy 31.781215 -259.3013) (xy 31.818432 -259.342837) (xy 31.849205 -259.38935) (xy 31.872877 -259.439847)
			(xy 31.888945 -259.493254) (xy 31.897065 -259.54843) (xy 31.897574 -259.576316) (xy 31.897065 -259.604202)
			(xy 31.888945 -259.659378) (xy 31.872877 -259.712785) (xy 31.849205 -259.763282) (xy 31.818432 -259.809795)
			(xy 31.781215 -259.851332) (xy 31.738347 -259.887007) (xy 31.690741 -259.916061) (xy 31.639412 -259.937873)
			(xy 31.585455 -259.951979) (xy 31.530018 -259.958079) (xy 31.474284 -259.956042) (xy 31.419441 -259.945912)
			(xy 31.366657 -259.927905) (xy 31.317057 -259.902404) (xy 31.271699 -259.869953) (xy 31.23155 -259.831244)
			(xy 31.197464 -259.787101) (xy 31.170168 -259.738466) (xy 31.150245 -259.686375) (xy 31.138119 -259.631938)
			(xy 31.134048 -259.576316) (xy 31.008574 -259.576316) (xy 31.008065 -259.604202) (xy 30.999945 -259.659378)
			(xy 30.983877 -259.712785) (xy 30.960205 -259.763282) (xy 30.929432 -259.809795) (xy 30.892215 -259.851332)
			(xy 30.849347 -259.887007) (xy 30.801741 -259.916061) (xy 30.750412 -259.937873) (xy 30.696455 -259.951979)
			(xy 30.641018 -259.958079) (xy 30.585284 -259.956042) (xy 30.530441 -259.945912) (xy 30.477657 -259.927905)
			(xy 30.428057 -259.902404) (xy 30.382699 -259.869953) (xy 30.34255 -259.831244) (xy 30.308464 -259.787101)
			(xy 30.281168 -259.738466) (xy 30.261245 -259.686375) (xy 30.249119 -259.631938) (xy 30.245048 -259.576316)
			(xy 1.420114 -259.576316) (xy 1.420114 -260.740398) (xy 22.04339 -260.740398) (xy 22.043956 -260.711756)
			(xy 22.05252 -260.655116) (xy 22.069455 -260.600392) (xy 22.09438 -260.548815) (xy 22.126735 -260.501543)
			(xy 22.165793 -260.459639) (xy 22.187916 -260.44144) (xy 22.191053 -260.438781) (xy 22.196539 -260.432657)
			(xy 22.198838 -260.429248) (xy 22.202203 -260.423747) (xy 22.206322 -260.411534) (xy 22.206966 -260.405118)
			(xy 22.212046 -260.330188) (xy 22.212206 -260.319574) (xy 22.204991 -260.299634) (xy 22.198076 -260.29158)
			(xy 22.178306 -260.270146) (xy 22.144874 -260.222374) (xy 22.119096 -260.170073) (xy 22.101571 -260.11446)
			(xy 22.092708 -260.056828) (xy 22.092158 -260.027674) (xy 22.092644 -260.000423) (xy 22.1004 -259.946475)
			(xy 22.115755 -259.89418) (xy 22.138397 -259.844603) (xy 22.167863 -259.798753) (xy 22.203554 -259.757562)
			(xy 22.244745 -259.721871) (xy 22.290595 -259.692405) (xy 22.340172 -259.669763) (xy 22.392467 -259.654408)
			(xy 22.446415 -259.646652) (xy 22.500917 -259.646652) (xy 22.554865 -259.654408) (xy 22.60716 -259.669763)
			(xy 22.656737 -259.692405) (xy 22.702587 -259.721871) (xy 22.743778 -259.757562) (xy 22.779469 -259.798753)
			(xy 22.808935 -259.844603) (xy 22.831577 -259.89418) (xy 22.846932 -259.946475) (xy 22.854688 -260.000423)
			(xy 22.855174 -260.027674) (xy 22.854672 -260.056319) (xy 22.85251 -260.0706) (xy 23.642826 -260.0706)
			(xy 23.646897 -260.014978) (xy 23.659023 -259.960541) (xy 23.678946 -259.90845) (xy 23.706242 -259.859815)
			(xy 23.740328 -259.815672) (xy 23.780477 -259.776963) (xy 23.825835 -259.744512) (xy 23.875435 -259.719011)
			(xy 23.928219 -259.701004) (xy 23.983062 -259.690874) (xy 24.038796 -259.688837) (xy 24.094233 -259.694937)
			(xy 24.14819 -259.709043) (xy 24.199519 -259.730855) (xy 24.247125 -259.759909) (xy 24.289993 -259.795584)
			(xy 24.32721 -259.837121) (xy 24.357983 -259.883634) (xy 24.381655 -259.934131) (xy 24.397723 -259.987538)
			(xy 24.405843 -260.042714) (xy 24.406352 -260.0706) (xy 24.405843 -260.098486) (xy 24.402695 -260.119876)
			(xy 27.661868 -260.119876) (xy 27.665939 -260.064254) (xy 27.678065 -260.009817) (xy 27.697988 -259.957726)
			(xy 27.725284 -259.909091) (xy 27.75937 -259.864948) (xy 27.799519 -259.826239) (xy 27.844877 -259.793788)
			(xy 27.894477 -259.768287) (xy 27.947261 -259.75028) (xy 28.002104 -259.74015) (xy 28.057838 -259.738113)
			(xy 28.113275 -259.744213) (xy 28.167232 -259.758319) (xy 28.218561 -259.780131) (xy 28.266167 -259.809185)
			(xy 28.309035 -259.84486) (xy 28.346252 -259.886397) (xy 28.377025 -259.93291) (xy 28.400697 -259.983407)
			(xy 28.416765 -260.036814) (xy 28.424885 -260.09199) (xy 28.425394 -260.119876) (xy 28.424885 -260.147762)
			(xy 28.416765 -260.202938) (xy 28.400697 -260.256345) (xy 28.377025 -260.306842) (xy 28.356202 -260.338316)
			(xy 34.296096 -260.338316) (xy 34.296647 -260.308934) (xy 34.305675 -260.250868) (xy 34.323505 -260.194874)
			(xy 34.349715 -260.142279) (xy 34.383683 -260.094327) (xy 34.424606 -260.052154) (xy 34.447734 -260.034024)
			(xy 34.456655 -260.026541) (xy 34.467116 -260.005769) (xy 34.4678 -259.994146) (xy 34.46907 -259.90804)
			(xy 34.46653 -259.896864) (xy 34.464244 -259.891784) (xy 34.46164 -259.8866) (xy 34.45445 -259.877497)
			(xy 34.45002 -259.87375) (xy 34.42817 -259.855546) (xy 34.389629 -259.813728) (xy 34.357722 -259.766652)
			(xy 34.333155 -259.715362) (xy 34.316472 -259.660993) (xy 34.308044 -259.604751) (xy 34.307526 -259.576316)
			(xy 34.308012 -259.549065) (xy 34.315768 -259.495117) (xy 34.331123 -259.442822) (xy 34.353765 -259.393245)
			(xy 34.383231 -259.347395) (xy 34.418922 -259.306204) (xy 34.460113 -259.270513) (xy 34.505963 -259.241047)
			(xy 34.55554 -259.218405) (xy 34.607835 -259.20305) (xy 34.661783 -259.195294) (xy 34.716285 -259.195294)
			(xy 34.770233 -259.20305) (xy 34.822528 -259.218405) (xy 34.872105 -259.241047) (xy 34.917955 -259.270513)
			(xy 34.959146 -259.306204) (xy 34.994837 -259.347395) (xy 35.024303 -259.393245) (xy 35.046945 -259.442822)
			(xy 35.0623 -259.495117) (xy 35.070056 -259.549065) (xy 35.070542 -259.576316) (xy 35.069999 -259.605698)
			(xy 35.060967 -259.663764) (xy 35.043134 -259.719757) (xy 35.016923 -259.772352) (xy 34.982954 -259.820304)
			(xy 34.942031 -259.862477) (xy 34.918904 -259.880608) (xy 34.909958 -259.888066) (xy 34.899513 -259.908857)
			(xy 34.898838 -259.920486) (xy 34.897568 -260.006592) (xy 34.900108 -260.017768) (xy 34.902394 -260.022848)
			(xy 34.905003 -260.028029) (xy 34.912191 -260.037133) (xy 34.916618 -260.040882) (xy 34.938443 -260.059114)
			(xy 34.976984 -260.100928) (xy 35.008893 -260.147998) (xy 35.033464 -260.199283) (xy 35.050153 -260.253645)
			(xy 35.058589 -260.309883) (xy 35.059112 -260.338316) (xy 35.692586 -260.338316) (xy 35.696657 -260.282694)
			(xy 35.708783 -260.228257) (xy 35.728706 -260.176166) (xy 35.756002 -260.127531) (xy 35.790088 -260.083388)
			(xy 35.830237 -260.044679) (xy 35.875595 -260.012228) (xy 35.925195 -259.986727) (xy 35.977979 -259.96872)
			(xy 36.032822 -259.95859) (xy 36.088556 -259.956553) (xy 36.143993 -259.962653) (xy 36.19795 -259.976759)
			(xy 36.249279 -259.998571) (xy 36.296885 -260.027625) (xy 36.339753 -260.0633) (xy 36.37697 -260.104837)
			(xy 36.407743 -260.15135) (xy 36.431415 -260.201847) (xy 36.447483 -260.255254) (xy 36.455603 -260.31043)
			(xy 36.456112 -260.338316) (xy 36.579046 -260.338316) (xy 36.583117 -260.282694) (xy 36.595243 -260.228257)
			(xy 36.615166 -260.176166) (xy 36.642462 -260.127531) (xy 36.676548 -260.083388) (xy 36.716697 -260.044679)
			(xy 36.762055 -260.012228) (xy 36.811655 -259.986727) (xy 36.864439 -259.96872) (xy 36.919282 -259.95859)
			(xy 36.975016 -259.956553) (xy 37.030453 -259.962653) (xy 37.08441 -259.976759) (xy 37.135739 -259.998571)
			(xy 37.183345 -260.027625) (xy 37.226213 -260.0633) (xy 37.26343 -260.104837) (xy 37.294203 -260.15135)
			(xy 37.317875 -260.201847) (xy 37.333943 -260.255254) (xy 37.342063 -260.31043) (xy 37.342572 -260.338316)
			(xy 37.342063 -260.366202) (xy 37.333943 -260.421378) (xy 37.317875 -260.474785) (xy 37.294203 -260.525282)
			(xy 37.26343 -260.571795) (xy 37.226213 -260.613332) (xy 37.183345 -260.649007) (xy 37.135739 -260.678061)
			(xy 37.08441 -260.699873) (xy 37.030453 -260.713979) (xy 36.975016 -260.720079) (xy 36.919282 -260.718042)
			(xy 36.864439 -260.707912) (xy 36.811655 -260.689905) (xy 36.762055 -260.664404) (xy 36.716697 -260.631953)
			(xy 36.676548 -260.593244) (xy 36.642462 -260.549101) (xy 36.615166 -260.500466) (xy 36.595243 -260.448375)
			(xy 36.583117 -260.393938) (xy 36.579046 -260.338316) (xy 36.456112 -260.338316) (xy 36.455603 -260.366202)
			(xy 36.447483 -260.421378) (xy 36.431415 -260.474785) (xy 36.407743 -260.525282) (xy 36.37697 -260.571795)
			(xy 36.339753 -260.613332) (xy 36.296885 -260.649007) (xy 36.249279 -260.678061) (xy 36.19795 -260.699873)
			(xy 36.143993 -260.713979) (xy 36.088556 -260.720079) (xy 36.032822 -260.718042) (xy 35.977979 -260.707912)
			(xy 35.925195 -260.689905) (xy 35.875595 -260.664404) (xy 35.830237 -260.631953) (xy 35.790088 -260.593244)
			(xy 35.756002 -260.549101) (xy 35.728706 -260.500466) (xy 35.708783 -260.448375) (xy 35.696657 -260.393938)
			(xy 35.692586 -260.338316) (xy 35.059112 -260.338316) (xy 35.058626 -260.365567) (xy 35.05087 -260.419515)
			(xy 35.035515 -260.47181) (xy 35.012873 -260.521387) (xy 34.983407 -260.567237) (xy 34.947716 -260.608428)
			(xy 34.906525 -260.644119) (xy 34.860675 -260.673585) (xy 34.811098 -260.696227) (xy 34.758803 -260.711582)
			(xy 34.704855 -260.719338) (xy 34.650353 -260.719338) (xy 34.596405 -260.711582) (xy 34.54411 -260.696227)
			(xy 34.494533 -260.673585) (xy 34.448683 -260.644119) (xy 34.407492 -260.608428) (xy 34.371801 -260.567237)
			(xy 34.342335 -260.521387) (xy 34.319693 -260.47181) (xy 34.304338 -260.419515) (xy 34.296582 -260.365567)
			(xy 34.296096 -260.338316) (xy 28.356202 -260.338316) (xy 28.346252 -260.353355) (xy 28.309035 -260.394892)
			(xy 28.266167 -260.430567) (xy 28.218561 -260.459621) (xy 28.167232 -260.481433) (xy 28.113275 -260.495539)
			(xy 28.057838 -260.501639) (xy 28.002104 -260.499602) (xy 27.947261 -260.489472) (xy 27.894477 -260.471465)
			(xy 27.844877 -260.445964) (xy 27.799519 -260.413513) (xy 27.75937 -260.374804) (xy 27.725284 -260.330661)
			(xy 27.697988 -260.282026) (xy 27.678065 -260.229935) (xy 27.665939 -260.175498) (xy 27.661868 -260.119876)
			(xy 24.402695 -260.119876) (xy 24.397723 -260.153662) (xy 24.381655 -260.207069) (xy 24.357983 -260.257566)
			(xy 24.32721 -260.304079) (xy 24.289993 -260.345616) (xy 24.247125 -260.381291) (xy 24.199519 -260.410345)
			(xy 24.14819 -260.432157) (xy 24.094233 -260.446263) (xy 24.038796 -260.452363) (xy 23.983062 -260.450326)
			(xy 23.928219 -260.440196) (xy 23.875435 -260.422189) (xy 23.825835 -260.396688) (xy 23.780477 -260.364237)
			(xy 23.740328 -260.325528) (xy 23.706242 -260.281385) (xy 23.678946 -260.23275) (xy 23.659023 -260.180659)
			(xy 23.646897 -260.126222) (xy 23.642826 -260.0706) (xy 22.85251 -260.0706) (xy 22.846097 -260.112963)
			(xy 22.82915 -260.167688) (xy 22.804213 -260.219265) (xy 22.771846 -260.266535) (xy 22.732776 -260.308435)
			(xy 22.710648 -260.326632) (xy 22.707511 -260.32929) (xy 22.702025 -260.335415) (xy 22.699726 -260.338824)
			(xy 22.696367 -260.344328) (xy 22.692245 -260.356539) (xy 22.691598 -260.362954) (xy 22.686518 -260.437884)
			(xy 22.686357 -260.448499) (xy 22.693571 -260.468439) (xy 22.700488 -260.476492) (xy 22.720239 -260.497943)
			(xy 22.749139 -260.53923) (xy 26.534616 -260.53923) (xy 26.538687 -260.483608) (xy 26.550813 -260.429171)
			(xy 26.570736 -260.37708) (xy 26.598032 -260.328445) (xy 26.632118 -260.284302) (xy 26.672267 -260.245593)
			(xy 26.717625 -260.213142) (xy 26.767225 -260.187641) (xy 26.820009 -260.169634) (xy 26.874852 -260.159504)
			(xy 26.930586 -260.157467) (xy 26.986023 -260.163567) (xy 27.03998 -260.177673) (xy 27.091309 -260.199485)
			(xy 27.138915 -260.228539) (xy 27.181783 -260.264214) (xy 27.219 -260.305751) (xy 27.249773 -260.352264)
			(xy 27.273445 -260.402761) (xy 27.289513 -260.456168) (xy 27.297633 -260.511344) (xy 27.298142 -260.53923)
			(xy 27.297633 -260.567116) (xy 27.289513 -260.622292) (xy 27.273445 -260.675699) (xy 27.249773 -260.726196)
			(xy 27.219 -260.772709) (xy 27.181783 -260.814246) (xy 27.138915 -260.849921) (xy 27.091309 -260.878975)
			(xy 27.03998 -260.900787) (xy 26.986023 -260.914893) (xy 26.930586 -260.920993) (xy 26.874852 -260.918956)
			(xy 26.820009 -260.908826) (xy 26.767225 -260.890819) (xy 26.717625 -260.865318) (xy 26.672267 -260.832867)
			(xy 26.632118 -260.794158) (xy 26.598032 -260.750015) (xy 26.570736 -260.70138) (xy 26.550813 -260.649289)
			(xy 26.538687 -260.594852) (xy 26.534616 -260.53923) (xy 22.749139 -260.53923) (xy 22.753675 -260.54571)
			(xy 22.779457 -260.598007) (xy 22.796986 -260.653616) (xy 22.805854 -260.711245) (xy 22.806406 -260.740398)
			(xy 22.80592 -260.767649) (xy 22.798164 -260.821597) (xy 22.782809 -260.873892) (xy 22.760167 -260.923469)
			(xy 22.730701 -260.969319) (xy 22.69501 -261.01051) (xy 22.653819 -261.046201) (xy 22.607969 -261.075667)
			(xy 22.558392 -261.098309) (xy 22.506097 -261.113664) (xy 22.452149 -261.12142) (xy 22.397647 -261.12142)
			(xy 22.343699 -261.113664) (xy 22.291404 -261.098309) (xy 22.241827 -261.075667) (xy 22.195977 -261.046201)
			(xy 22.154786 -261.01051) (xy 22.119095 -260.969319) (xy 22.089629 -260.923469) (xy 22.066987 -260.873892)
			(xy 22.051632 -260.821597) (xy 22.043876 -260.767649) (xy 22.04339 -260.740398) (xy 1.420114 -260.740398)
			(xy 1.420114 -261.764272) (xy 24.31872 -261.764272) (xy 24.322791 -261.70865) (xy 24.334917 -261.654213)
			(xy 24.35484 -261.602122) (xy 24.382136 -261.553487) (xy 24.416222 -261.509344) (xy 24.456371 -261.470635)
			(xy 24.501729 -261.438184) (xy 24.551329 -261.412683) (xy 24.604113 -261.394676) (xy 24.658956 -261.384546)
			(xy 24.71469 -261.382509) (xy 24.770127 -261.388609) (xy 24.824084 -261.402715) (xy 24.875413 -261.424527)
			(xy 24.923019 -261.453581) (xy 24.965887 -261.489256) (xy 25.003104 -261.530793) (xy 25.033877 -261.577306)
			(xy 25.057549 -261.627803) (xy 25.073617 -261.68121) (xy 25.081737 -261.736386) (xy 25.082246 -261.764272)
			(xy 25.081737 -261.792158) (xy 25.077941 -261.817951) (xy 25.519366 -261.817951) (xy 25.519366 -261.763449)
			(xy 25.527122 -261.709501) (xy 25.542477 -261.657206) (xy 25.565117 -261.607629) (xy 25.594582 -261.561778)
			(xy 25.630273 -261.520587) (xy 25.671462 -261.484894) (xy 25.717311 -261.455427) (xy 25.766888 -261.432784)
			(xy 25.819182 -261.417426) (xy 25.873129 -261.409667) (xy 25.90038 -261.40918) (xy 25.929298 -261.409682)
			(xy 25.986471 -261.41841) (xy 26.041672 -261.435669) (xy 26.093634 -261.461064) (xy 26.141167 -261.494012)
			(xy 26.183182 -261.533758) (xy 26.20137 -261.556246) (xy 26.208941 -261.564997) (xy 26.229693 -261.575185)
			(xy 26.241248 -261.575804) (xy 26.321512 -261.575804) (xy 26.33308 -261.575239) (xy 26.353851 -261.56504)
			(xy 26.36139 -261.556246) (xy 26.378143 -261.535463) (xy 26.416497 -261.498333) (xy 26.459651 -261.466911)
			(xy 26.506765 -261.441812) (xy 26.556917 -261.423526) (xy 26.609128 -261.412409) (xy 26.66238 -261.408679)
			(xy 26.715632 -261.412409) (xy 26.767843 -261.423526) (xy 26.817995 -261.441812) (xy 26.865109 -261.466911)
			(xy 26.908263 -261.498333) (xy 26.946617 -261.535463) (xy 26.96337 -261.556246) (xy 26.970941 -261.564997)
			(xy 26.991693 -261.575185) (xy 27.003248 -261.575804) (xy 27.083512 -261.575804) (xy 27.09508 -261.575239)
			(xy 27.115851 -261.56504) (xy 27.12339 -261.556246) (xy 27.140143 -261.535463) (xy 27.178497 -261.498333)
			(xy 27.221651 -261.466911) (xy 27.268765 -261.441812) (xy 27.318917 -261.423526) (xy 27.371128 -261.412409)
			(xy 27.42438 -261.408679) (xy 27.477632 -261.412409) (xy 27.529843 -261.423526) (xy 27.579995 -261.441812)
			(xy 27.627109 -261.466911) (xy 27.670263 -261.498333) (xy 27.708617 -261.535463) (xy 27.72537 -261.556246)
			(xy 27.732941 -261.564997) (xy 27.753693 -261.575185) (xy 27.765248 -261.575804) (xy 27.845512 -261.575804)
			(xy 27.85708 -261.575239) (xy 27.877851 -261.56504) (xy 27.88539 -261.556246) (xy 27.903573 -261.533756)
			(xy 27.945596 -261.494024) (xy 27.993133 -261.461087) (xy 28.045096 -261.4357) (xy 28.100294 -261.418445)
			(xy 28.157464 -261.409716) (xy 28.18638 -261.40918) (xy 28.213633 -261.409666) (xy 28.267584 -261.41742)
			(xy 28.319883 -261.432774) (xy 28.369464 -261.455415) (xy 28.399098 -261.474458) (xy 28.769562 -261.474458)
			(xy 28.773633 -261.418836) (xy 28.785759 -261.364399) (xy 28.805682 -261.312308) (xy 28.832978 -261.263673)
			(xy 28.867064 -261.21953) (xy 28.907213 -261.180821) (xy 28.952571 -261.14837) (xy 29.002171 -261.122869)
			(xy 29.054955 -261.104862) (xy 29.109798 -261.094732) (xy 29.165532 -261.092695) (xy 29.220969 -261.098795)
			(xy 29.274926 -261.112901) (xy 29.326255 -261.134713) (xy 29.373861 -261.163767) (xy 29.416729 -261.199442)
			(xy 29.453946 -261.240979) (xy 29.484719 -261.287492) (xy 29.508391 -261.337989) (xy 29.524459 -261.391396)
			(xy 29.532579 -261.446572) (xy 29.533088 -261.474458) (xy 30.2547 -261.474458) (xy 30.258771 -261.418836)
			(xy 30.270897 -261.364399) (xy 30.29082 -261.312308) (xy 30.318116 -261.263673) (xy 30.352202 -261.21953)
			(xy 30.392351 -261.180821) (xy 30.437709 -261.14837) (xy 30.487309 -261.122869) (xy 30.540093 -261.104862)
			(xy 30.594936 -261.094732) (xy 30.65067 -261.092695) (xy 30.706107 -261.098795) (xy 30.760064 -261.112901)
			(xy 30.811393 -261.134713) (xy 30.858999 -261.163767) (xy 30.901867 -261.199442) (xy 30.939084 -261.240979)
			(xy 30.969857 -261.287492) (xy 30.993529 -261.337989) (xy 31.009597 -261.391396) (xy 31.017717 -261.446572)
			(xy 31.018226 -261.474458) (xy 31.017717 -261.502344) (xy 31.009597 -261.55752) (xy 30.993529 -261.610927)
			(xy 30.969857 -261.661424) (xy 30.939084 -261.707937) (xy 30.901867 -261.749474) (xy 30.858999 -261.785149)
			(xy 30.811393 -261.814203) (xy 30.760064 -261.836015) (xy 30.706107 -261.850121) (xy 30.65067 -261.856221)
			(xy 30.594936 -261.854184) (xy 30.540093 -261.844054) (xy 30.487309 -261.826047) (xy 30.437709 -261.800546)
			(xy 30.392351 -261.768095) (xy 30.352202 -261.729386) (xy 30.318116 -261.685243) (xy 30.29082 -261.636608)
			(xy 30.270897 -261.584517) (xy 30.258771 -261.53008) (xy 30.2547 -261.474458) (xy 29.533088 -261.474458)
			(xy 29.532579 -261.502344) (xy 29.524459 -261.55752) (xy 29.508391 -261.610927) (xy 29.484719 -261.661424)
			(xy 29.453946 -261.707937) (xy 29.416729 -261.749474) (xy 29.373861 -261.785149) (xy 29.326255 -261.814203)
			(xy 29.274926 -261.836015) (xy 29.220969 -261.850121) (xy 29.165532 -261.856221) (xy 29.109798 -261.854184)
			(xy 29.054955 -261.844054) (xy 29.002171 -261.826047) (xy 28.952571 -261.800546) (xy 28.907213 -261.768095)
			(xy 28.867064 -261.729386) (xy 28.832978 -261.685243) (xy 28.805682 -261.636608) (xy 28.785759 -261.584517)
			(xy 28.773633 -261.53008) (xy 28.769562 -261.474458) (xy 28.399098 -261.474458) (xy 28.415318 -261.484881)
			(xy 28.456512 -261.520574) (xy 28.492207 -261.561766) (xy 28.521676 -261.607618) (xy 28.544319 -261.657198)
			(xy 28.559675 -261.709496) (xy 28.567433 -261.763447) (xy 28.567433 -261.817953) (xy 28.559675 -261.871904)
			(xy 28.544319 -261.924202) (xy 28.521676 -261.973782) (xy 28.492207 -262.019634) (xy 28.456512 -262.060826)
			(xy 28.415318 -262.096519) (xy 28.369464 -262.125985) (xy 28.319883 -262.148626) (xy 28.267584 -262.16398)
			(xy 28.213633 -262.171734) (xy 28.18638 -262.172196) (xy 28.157465 -262.171622) (xy 28.100296 -262.162905)
			(xy 28.045099 -262.145658) (xy 27.993137 -262.120277) (xy 27.945601 -262.087343) (xy 27.903582 -262.047611)
			(xy 27.88539 -262.02513) (xy 27.87784 -262.016356) (xy 27.857072 -262.006182) (xy 27.845512 -262.005572)
			(xy 27.765248 -262.005572) (xy 27.75368 -262.006145) (xy 27.732907 -262.016335) (xy 27.72537 -262.02513)
			(xy 27.708617 -262.045913) (xy 27.670263 -262.083043) (xy 27.627109 -262.114465) (xy 27.579995 -262.139564)
			(xy 27.529843 -262.15785) (xy 27.477632 -262.168967) (xy 27.42438 -262.172697) (xy 27.371128 -262.168967)
			(xy 27.318917 -262.15785) (xy 27.268765 -262.139564) (xy 27.221651 -262.114465) (xy 27.178497 -262.083043)
			(xy 27.140143 -262.045913) (xy 27.12339 -262.02513) (xy 27.11584 -262.016356) (xy 27.095072 -262.006182)
			(xy 27.083512 -262.005572) (xy 27.003248 -262.005572) (xy 26.99168 -262.006145) (xy 26.970907 -262.016335)
			(xy 26.96337 -262.02513) (xy 26.946617 -262.045913) (xy 26.908263 -262.083043) (xy 26.865109 -262.114465)
			(xy 26.817995 -262.139564) (xy 26.767843 -262.15785) (xy 26.715632 -262.168967) (xy 26.66238 -262.172697)
			(xy 26.609128 -262.168967) (xy 26.556917 -262.15785) (xy 26.506765 -262.139564) (xy 26.459651 -262.114465)
			(xy 26.416497 -262.083043) (xy 26.378143 -262.045913) (xy 26.36139 -262.02513) (xy 26.35384 -262.016356)
			(xy 26.333072 -262.006182) (xy 26.321512 -262.005572) (xy 26.241248 -262.005572) (xy 26.22968 -262.006145)
			(xy 26.208907 -262.016335) (xy 26.20137 -262.02513) (xy 26.183204 -262.047634) (xy 26.141178 -262.087367)
			(xy 26.093637 -262.120302) (xy 26.041672 -262.145687) (xy 25.98647 -262.162939) (xy 25.929297 -262.171663)
			(xy 25.90038 -262.172196) (xy 25.873129 -262.171733) (xy 25.819182 -262.163974) (xy 25.766888 -262.148616)
			(xy 25.717311 -262.125973) (xy 25.671462 -262.096506) (xy 25.630273 -262.060813) (xy 25.594582 -262.019622)
			(xy 25.565117 -261.973771) (xy 25.542477 -261.924194) (xy 25.527122 -261.871899) (xy 25.519366 -261.817951)
			(xy 25.077941 -261.817951) (xy 25.073617 -261.847334) (xy 25.057549 -261.900741) (xy 25.033877 -261.951238)
			(xy 25.003104 -261.997751) (xy 24.965887 -262.039288) (xy 24.923019 -262.074963) (xy 24.875413 -262.104017)
			(xy 24.824084 -262.125829) (xy 24.770127 -262.139935) (xy 24.71469 -262.146035) (xy 24.658956 -262.143998)
			(xy 24.604113 -262.133868) (xy 24.551329 -262.115861) (xy 24.501729 -262.09036) (xy 24.456371 -262.057909)
			(xy 24.416222 -262.0192) (xy 24.382136 -261.975057) (xy 24.35484 -261.926422) (xy 24.334917 -261.874331)
			(xy 24.322791 -261.819894) (xy 24.31872 -261.764272) (xy 1.420114 -261.764272) (xy 1.420114 -262.519668)
			(xy 22.592282 -262.519668) (xy 22.596353 -262.464046) (xy 22.608479 -262.409609) (xy 22.628402 -262.357518)
			(xy 22.655698 -262.308883) (xy 22.689784 -262.26474) (xy 22.729933 -262.226031) (xy 22.775291 -262.19358)
			(xy 22.824891 -262.168079) (xy 22.877675 -262.150072) (xy 22.932518 -262.139942) (xy 22.988252 -262.137905)
			(xy 23.043689 -262.144005) (xy 23.097646 -262.158111) (xy 23.148975 -262.179923) (xy 23.196581 -262.208977)
			(xy 23.239449 -262.244652) (xy 23.276666 -262.286189) (xy 23.307439 -262.332702) (xy 23.331111 -262.383199)
			(xy 23.347179 -262.436606) (xy 23.355299 -262.491782) (xy 23.355808 -262.519668) (xy 23.355299 -262.547554)
			(xy 23.347179 -262.60273) (xy 23.331111 -262.656137) (xy 23.307439 -262.706634) (xy 23.276666 -262.753147)
			(xy 23.239449 -262.794684) (xy 23.196581 -262.830359) (xy 23.148975 -262.859413) (xy 23.097646 -262.881225)
			(xy 23.043689 -262.895331) (xy 22.988252 -262.901431) (xy 22.932518 -262.899394) (xy 22.877675 -262.889264)
			(xy 22.824891 -262.871257) (xy 22.775291 -262.845756) (xy 22.729933 -262.813305) (xy 22.689784 -262.774596)
			(xy 22.655698 -262.730453) (xy 22.628402 -262.681818) (xy 22.608479 -262.629727) (xy 22.596353 -262.57529)
			(xy 22.592282 -262.519668) (xy 1.420114 -262.519668) (xy 1.420114 -262.912352) (xy 25.168858 -262.912352)
			(xy 25.172929 -262.85673) (xy 25.185055 -262.802293) (xy 25.204978 -262.750202) (xy 25.232274 -262.701567)
			(xy 25.26636 -262.657424) (xy 25.306509 -262.618715) (xy 25.351867 -262.586264) (xy 25.401467 -262.560763)
			(xy 25.454251 -262.542756) (xy 25.509094 -262.532626) (xy 25.564828 -262.530589) (xy 25.620265 -262.536689)
			(xy 25.674222 -262.550795) (xy 25.725551 -262.572607) (xy 25.773157 -262.601661) (xy 25.816025 -262.637336)
			(xy 25.853242 -262.678873) (xy 25.884015 -262.725386) (xy 25.907687 -262.775883) (xy 25.923755 -262.82929)
			(xy 25.931875 -262.884466) (xy 25.932384 -262.912352) (xy 25.931875 -262.940238) (xy 25.923755 -262.995414)
			(xy 25.907687 -263.048821) (xy 25.884015 -263.099318) (xy 25.853242 -263.145831) (xy 25.816025 -263.187368)
			(xy 25.773157 -263.223043) (xy 25.725551 -263.252097) (xy 25.674222 -263.273909) (xy 25.620265 -263.288015)
			(xy 25.564828 -263.294115) (xy 25.509094 -263.292078) (xy 25.454251 -263.281948) (xy 25.401467 -263.263941)
			(xy 25.351867 -263.23844) (xy 25.306509 -263.205989) (xy 25.26636 -263.16728) (xy 25.232274 -263.123137)
			(xy 25.204978 -263.074502) (xy 25.185055 -263.022411) (xy 25.172929 -262.967974) (xy 25.168858 -262.912352)
			(xy 1.420114 -262.912352) (xy 1.420114 -264.017506) (xy 36.356542 -264.017506) (xy 36.360613 -263.961884)
			(xy 36.372739 -263.907447) (xy 36.392662 -263.855356) (xy 36.419958 -263.806721) (xy 36.454044 -263.762578)
			(xy 36.494193 -263.723869) (xy 36.539551 -263.691418) (xy 36.589151 -263.665917) (xy 36.641935 -263.64791)
			(xy 36.696778 -263.63778) (xy 36.752512 -263.635743) (xy 36.807949 -263.641843) (xy 36.861906 -263.655949)
			(xy 36.913235 -263.677761) (xy 36.960841 -263.706815) (xy 37.003709 -263.74249) (xy 37.040926 -263.784027)
			(xy 37.071699 -263.83054) (xy 37.095371 -263.881037) (xy 37.111439 -263.934444) (xy 37.119559 -263.98962)
			(xy 37.120068 -264.017506) (xy 37.119559 -264.045392) (xy 37.111439 -264.100568) (xy 37.095371 -264.153975)
			(xy 37.078854 -264.18921) (xy 37.95979 -264.18921) (xy 37.963861 -264.133588) (xy 37.975987 -264.079151)
			(xy 37.99591 -264.02706) (xy 38.023206 -263.978425) (xy 38.057292 -263.934282) (xy 38.097441 -263.895573)
			(xy 38.142799 -263.863122) (xy 38.192399 -263.837621) (xy 38.245183 -263.819614) (xy 38.300026 -263.809484)
			(xy 38.35576 -263.807447) (xy 38.411197 -263.813547) (xy 38.465154 -263.827653) (xy 38.516483 -263.849465)
			(xy 38.564089 -263.878519) (xy 38.606957 -263.914194) (xy 38.644174 -263.955731) (xy 38.674947 -264.002244)
			(xy 38.698619 -264.052741) (xy 38.714687 -264.106148) (xy 38.722807 -264.161324) (xy 38.723316 -264.18921)
			(xy 38.722807 -264.217096) (xy 38.714687 -264.272272) (xy 38.698619 -264.325679) (xy 38.674947 -264.376176)
			(xy 38.644174 -264.422689) (xy 38.606957 -264.464226) (xy 38.564089 -264.499901) (xy 38.516483 -264.528955)
			(xy 38.465154 -264.550767) (xy 38.411197 -264.564873) (xy 38.35576 -264.570973) (xy 38.300026 -264.568936)
			(xy 38.245183 -264.558806) (xy 38.192399 -264.540799) (xy 38.142799 -264.515298) (xy 38.097441 -264.482847)
			(xy 38.057292 -264.444138) (xy 38.023206 -264.399995) (xy 37.99591 -264.35136) (xy 37.975987 -264.299269)
			(xy 37.963861 -264.244832) (xy 37.95979 -264.18921) (xy 37.078854 -264.18921) (xy 37.071699 -264.204472)
			(xy 37.040926 -264.250985) (xy 37.003709 -264.292522) (xy 36.960841 -264.328197) (xy 36.913235 -264.357251)
			(xy 36.861906 -264.379063) (xy 36.807949 -264.393169) (xy 36.752512 -264.399269) (xy 36.696778 -264.397232)
			(xy 36.641935 -264.387102) (xy 36.589151 -264.369095) (xy 36.539551 -264.343594) (xy 36.494193 -264.311143)
			(xy 36.454044 -264.272434) (xy 36.419958 -264.228291) (xy 36.392662 -264.179656) (xy 36.372739 -264.127565)
			(xy 36.360613 -264.073128) (xy 36.356542 -264.017506) (xy 1.420114 -264.017506) (xy 1.420114 -265.16457)
			(xy 40.46296 -265.16457) (xy 40.467031 -265.108948) (xy 40.479157 -265.054511) (xy 40.49908 -265.00242)
			(xy 40.526376 -264.953785) (xy 40.560462 -264.909642) (xy 40.600611 -264.870933) (xy 40.645969 -264.838482)
			(xy 40.695569 -264.812981) (xy 40.748353 -264.794974) (xy 40.803196 -264.784844) (xy 40.85893 -264.782807)
			(xy 40.914367 -264.788907) (xy 40.968324 -264.803013) (xy 41.019653 -264.824825) (xy 41.067259 -264.853879)
			(xy 41.110127 -264.889554) (xy 41.147344 -264.931091) (xy 41.178117 -264.977604) (xy 41.201789 -265.028101)
			(xy 41.217857 -265.081508) (xy 41.225977 -265.136684) (xy 41.226486 -265.16457) (xy 41.225977 -265.192456)
			(xy 41.217857 -265.247632) (xy 41.201789 -265.301039) (xy 41.178117 -265.351536) (xy 41.147344 -265.398049)
			(xy 41.110127 -265.439586) (xy 41.067259 -265.475261) (xy 41.019653 -265.504315) (xy 40.968324 -265.526127)
			(xy 40.914367 -265.540233) (xy 40.85893 -265.546333) (xy 40.803196 -265.544296) (xy 40.748353 -265.534166)
			(xy 40.695569 -265.516159) (xy 40.645969 -265.490658) (xy 40.600611 -265.458207) (xy 40.560462 -265.419498)
			(xy 40.526376 -265.375355) (xy 40.49908 -265.32672) (xy 40.479157 -265.274629) (xy 40.467031 -265.220192)
			(xy 40.46296 -265.16457) (xy 1.420114 -265.16457) (xy 1.420114 -265.804904) (xy 37.345618 -265.804904)
			(xy 37.349689 -265.749282) (xy 37.361815 -265.694845) (xy 37.381738 -265.642754) (xy 37.409034 -265.594119)
			(xy 37.44312 -265.549976) (xy 37.483269 -265.511267) (xy 37.528627 -265.478816) (xy 37.578227 -265.453315)
			(xy 37.631011 -265.435308) (xy 37.685854 -265.425178) (xy 37.741588 -265.423141) (xy 37.797025 -265.429241)
			(xy 37.850982 -265.443347) (xy 37.902311 -265.465159) (xy 37.949917 -265.494213) (xy 37.992785 -265.529888)
			(xy 38.030002 -265.571425) (xy 38.060775 -265.617938) (xy 38.084447 -265.668435) (xy 38.100515 -265.721842)
			(xy 38.108635 -265.777018) (xy 38.109144 -265.804904) (xy 38.108635 -265.83279) (xy 38.100515 -265.887966)
			(xy 38.084447 -265.941373) (xy 38.060775 -265.99187) (xy 38.030002 -266.038383) (xy 37.992785 -266.07992)
			(xy 37.949917 -266.115595) (xy 37.902311 -266.144649) (xy 37.850982 -266.166461) (xy 37.797025 -266.180567)
			(xy 37.741588 -266.186667) (xy 37.685854 -266.18463) (xy 37.631011 -266.1745) (xy 37.578227 -266.156493)
			(xy 37.528627 -266.130992) (xy 37.483269 -266.098541) (xy 37.44312 -266.059832) (xy 37.409034 -266.015689)
			(xy 37.381738 -265.967054) (xy 37.361815 -265.914963) (xy 37.349689 -265.860526) (xy 37.345618 -265.804904)
			(xy 1.420114 -265.804904) (xy 1.420114 -267.500608) (xy 17.210784 -267.500608) (xy 17.214855 -267.444986)
			(xy 17.226981 -267.390549) (xy 17.246904 -267.338458) (xy 17.2742 -267.289823) (xy 17.308286 -267.24568)
			(xy 17.348435 -267.206971) (xy 17.393793 -267.17452) (xy 17.443393 -267.149019) (xy 17.496177 -267.131012)
			(xy 17.55102 -267.120882) (xy 17.606754 -267.118845) (xy 17.662191 -267.124945) (xy 17.716148 -267.139051)
			(xy 17.767477 -267.160863) (xy 17.815083 -267.189917) (xy 17.857951 -267.225592) (xy 17.895168 -267.267129)
			(xy 17.925941 -267.313642) (xy 17.949613 -267.364139) (xy 17.965681 -267.417546) (xy 17.973801 -267.472722)
			(xy 17.97431 -267.500608) (xy 17.973801 -267.528494) (xy 17.965681 -267.58367) (xy 17.949613 -267.637077)
			(xy 17.925941 -267.687574) (xy 17.895168 -267.734087) (xy 17.857951 -267.775624) (xy 17.815083 -267.811299)
			(xy 17.767477 -267.840353) (xy 17.716148 -267.862165) (xy 17.662191 -267.876271) (xy 17.606754 -267.882371)
			(xy 17.55102 -267.880334) (xy 17.496177 -267.870204) (xy 17.443393 -267.852197) (xy 17.393793 -267.826696)
			(xy 17.348435 -267.794245) (xy 17.308286 -267.755536) (xy 17.2742 -267.711393) (xy 17.246904 -267.662758)
			(xy 17.226981 -267.610667) (xy 17.214855 -267.55623) (xy 17.210784 -267.500608) (xy 1.420114 -267.500608)
			(xy 1.420114 -270.10868) (xy 1.420651 -270.119041) (xy 1.428902 -270.138055) (xy 1.436116 -270.14551)
			(xy 1.489964 -270.19631) (xy 1.493266 -270.199104) (xy 1.50081 -270.204529) (xy 1.518517 -270.210114)
			(xy 1.52781 -270.210026) (xy 1.528064 -270.210026) (xy 1.551432 -270.209264) (xy 1.578683 -270.20975)
			(xy 1.63263 -270.217507) (xy 1.684924 -270.232862) (xy 1.734501 -270.255503) (xy 1.780351 -270.284969)
			(xy 1.821541 -270.320661) (xy 1.857232 -270.36185) (xy 1.886698 -270.407701) (xy 1.909339 -270.457277)
			(xy 1.924694 -270.509572) (xy 1.93245 -270.563519) (xy 1.93245 -270.618021) (xy 1.928662 -270.644366)
			(xy 5.002276 -270.644366) (xy 5.002704 -270.616994) (xy 5.010528 -270.562813) (xy 5.026025 -270.510308)
			(xy 5.048876 -270.460562) (xy 5.07861 -270.414598) (xy 5.096256 -270.393668) (xy 5.09651 -270.393414)
			(xy 5.102098 -270.386328) (xy 5.108344 -270.369411) (xy 5.108702 -270.360394) (xy 5.108702 -270.293338)
			(xy 5.108327 -270.284323) (xy 5.102092 -270.267406) (xy 5.09651 -270.260318) (xy 5.096256 -270.260318)
			(xy 5.096256 -270.260064) (xy 5.078626 -270.239125) (xy 5.048914 -270.193153) (xy 5.026077 -270.143407)
			(xy 5.010584 -270.090909) (xy 5.002752 -270.036735) (xy 5.002276 -270.009366) (xy 5.002746 -269.982115)
			(xy 5.010507 -269.928167) (xy 5.025865 -269.875873) (xy 5.048509 -269.826297) (xy 5.077978 -269.780447)
			(xy 5.113671 -269.739258) (xy 5.154862 -269.703567) (xy 5.200713 -269.674101) (xy 5.25029 -269.651459)
			(xy 5.302585 -269.636103) (xy 5.356533 -269.628345) (xy 5.383784 -269.627858) (xy 5.412522 -269.628403)
			(xy 5.469348 -269.637022) (xy 5.524238 -269.654068) (xy 5.57595 -269.679154) (xy 5.623314 -269.711714)
			(xy 5.644642 -269.730982) (xy 5.6515 -269.737586) (xy 5.660644 -269.741142) (xy 5.665111 -269.74276)
			(xy 5.674438 -269.744555) (xy 5.679186 -269.744698) (xy 5.748782 -269.744698) (xy 5.753535 -269.744595)
			(xy 5.762871 -269.742808) (xy 5.767324 -269.741142) (xy 5.776468 -269.737586) (xy 5.783326 -269.730982)
			(xy 5.804653 -269.711712) (xy 5.852016 -269.679147) (xy 5.903727 -269.654056) (xy 5.958618 -269.637006)
			(xy 6.015445 -269.628384) (xy 6.072923 -269.628384) (xy 6.12975 -269.637006) (xy 6.184641 -269.654056)
			(xy 6.236352 -269.679147) (xy 6.283715 -269.711712) (xy 6.305042 -269.730982) (xy 6.3119 -269.737586)
			(xy 6.321044 -269.741142) (xy 6.325511 -269.74276) (xy 6.334838 -269.744555) (xy 6.339586 -269.744698)
			(xy 6.409182 -269.744698) (xy 6.413935 -269.744595) (xy 6.423271 -269.742808) (xy 6.427724 -269.741142)
			(xy 6.436868 -269.737586) (xy 6.443726 -269.730982) (xy 6.465053 -269.711712) (xy 6.512416 -269.679147)
			(xy 6.564127 -269.654056) (xy 6.619018 -269.637006) (xy 6.675845 -269.628384) (xy 6.733323 -269.628384)
			(xy 6.79015 -269.637006) (xy 6.845041 -269.654056) (xy 6.896752 -269.679147) (xy 6.944115 -269.711712)
			(xy 6.965442 -269.730982) (xy 6.9723 -269.737586) (xy 6.981444 -269.741142) (xy 6.985911 -269.74276)
			(xy 6.995238 -269.744555) (xy 6.999986 -269.744698) (xy 7.069582 -269.744698) (xy 7.074335 -269.744595)
			(xy 7.083671 -269.742808) (xy 7.088124 -269.741142) (xy 7.097268 -269.737586) (xy 7.104126 -269.730982)
			(xy 7.125466 -269.711726) (xy 7.172824 -269.679156) (xy 7.224532 -269.65406) (xy 7.27942 -269.637006)
			(xy 7.336246 -269.62838) (xy 7.364984 -269.627858) (xy 7.392235 -269.628344) (xy 7.446183 -269.636101)
			(xy 7.498477 -269.651456) (xy 7.548054 -269.674098) (xy 7.593904 -269.703564) (xy 7.635094 -269.739256)
			(xy 7.670786 -269.780446) (xy 7.700252 -269.826296) (xy 7.722894 -269.875873) (xy 7.738249 -269.928167)
			(xy 7.746006 -269.982115) (xy 7.746492 -270.009366) (xy 7.746008 -270.036736) (xy 7.738195 -270.090914)
			(xy 7.72271 -270.143417) (xy 7.699872 -270.193164) (xy 7.670151 -270.239132) (xy 7.652512 -270.260064)
			(xy 7.652258 -270.260318) (xy 7.646653 -270.267392) (xy 7.640418 -270.284318) (xy 7.640066 -270.293338)
			(xy 7.640066 -270.360394) (xy 7.640433 -270.36941) (xy 7.646675 -270.386326) (xy 7.652258 -270.393414)
			(xy 7.652512 -270.393414) (xy 7.652512 -270.393668) (xy 7.670151 -270.4146) (xy 7.699863 -270.460573)
			(xy 7.722698 -270.51032) (xy 7.730174 -270.535654) (xy 8.785098 -270.535654) (xy 8.785596 -270.508285)
			(xy 8.793406 -270.454107) (xy 8.808888 -270.401605) (xy 8.831723 -270.351857) (xy 8.86144 -270.305889)
			(xy 8.879078 -270.284956) (xy 8.879332 -270.284702) (xy 8.884927 -270.277622) (xy 8.891168 -270.2607)
			(xy 8.891524 -270.251682) (xy 8.891524 -270.184626) (xy 8.891149 -270.175611) (xy 8.884913 -270.158694)
			(xy 8.879332 -270.151606) (xy 8.879078 -270.151606) (xy 8.879078 -270.151352) (xy 8.861446 -270.130414)
			(xy 8.831734 -270.084442) (xy 8.808897 -270.034696) (xy 8.793404 -269.982197) (xy 8.785574 -269.928023)
			(xy 8.785098 -269.900654) (xy 8.785535 -269.873401) (xy 8.793298 -269.819452) (xy 8.808659 -269.767156)
			(xy 8.831306 -269.717578) (xy 8.860778 -269.671727) (xy 8.896474 -269.630537) (xy 8.937669 -269.594847)
			(xy 8.983523 -269.565381) (xy 9.033104 -269.542741) (xy 9.085402 -269.527387) (xy 9.139353 -269.519631)
			(xy 9.166606 -269.519146) (xy 9.195344 -269.519681) (xy 9.252171 -269.528303) (xy 9.307061 -269.545351)
			(xy 9.358772 -269.57044) (xy 9.406136 -269.603001) (xy 9.427464 -269.62227) (xy 9.434322 -269.628874)
			(xy 9.443466 -269.63243) (xy 9.447931 -269.634054) (xy 9.457259 -269.635845) (xy 9.462008 -269.635986)
			(xy 9.531604 -269.635986) (xy 9.536357 -269.63589) (xy 9.545694 -269.634098) (xy 9.550146 -269.63243)
			(xy 9.55929 -269.628874) (xy 9.566148 -269.62227) (xy 9.587475 -269.603) (xy 9.634838 -269.570435)
			(xy 9.686549 -269.545344) (xy 9.74144 -269.528294) (xy 9.798267 -269.519672) (xy 9.855745 -269.519672)
			(xy 9.912572 -269.528294) (xy 9.967463 -269.545344) (xy 10.019174 -269.570435) (xy 10.066537 -269.603)
			(xy 10.087864 -269.62227) (xy 10.094722 -269.628874) (xy 10.103866 -269.63243) (xy 10.108331 -269.634054)
			(xy 10.117659 -269.635845) (xy 10.122408 -269.635986) (xy 10.192004 -269.635986) (xy 10.196757 -269.63589)
			(xy 10.206094 -269.634098) (xy 10.210546 -269.63243) (xy 10.21969 -269.628874) (xy 10.226548 -269.62227)
			(xy 10.247875 -269.603) (xy 10.295238 -269.570435) (xy 10.346949 -269.545344) (xy 10.40184 -269.528294)
			(xy 10.458667 -269.519672) (xy 10.516145 -269.519672) (xy 10.572972 -269.528294) (xy 10.627863 -269.545344)
			(xy 10.679574 -269.570435) (xy 10.726937 -269.603) (xy 10.748264 -269.62227) (xy 10.755122 -269.628874)
			(xy 10.764266 -269.63243) (xy 10.768731 -269.634054) (xy 10.778059 -269.635845) (xy 10.782808 -269.635986)
			(xy 10.852404 -269.635986) (xy 10.857157 -269.63589) (xy 10.866494 -269.634098) (xy 10.870946 -269.63243)
			(xy 10.88009 -269.628874) (xy 10.886948 -269.62227) (xy 10.908277 -269.603002) (xy 10.955638 -269.570434)
			(xy 11.007349 -269.54534) (xy 11.06224 -269.528289) (xy 11.119067 -269.519667) (xy 11.147806 -269.519146)
			(xy 11.175059 -269.519609) (xy 11.22901 -269.527366) (xy 11.281308 -269.542721) (xy 11.330889 -269.565364)
			(xy 11.376742 -269.594832) (xy 11.417935 -269.630525) (xy 11.453628 -269.671718) (xy 11.483096 -269.717571)
			(xy 11.505739 -269.767152) (xy 11.521094 -269.81945) (xy 11.528851 -269.873401) (xy 11.529314 -269.900654)
			(xy 11.528818 -269.928023) (xy 11.521007 -269.982201) (xy 11.505524 -270.034703) (xy 11.48269 -270.084451)
			(xy 11.472117 -270.100806) (xy 17.238724 -270.100806) (xy 17.242795 -270.045184) (xy 17.254921 -269.990747)
			(xy 17.274844 -269.938656) (xy 17.30214 -269.890021) (xy 17.336226 -269.845878) (xy 17.376375 -269.807169)
			(xy 17.421733 -269.774718) (xy 17.471333 -269.749217) (xy 17.524117 -269.73121) (xy 17.57896 -269.72108)
			(xy 17.634694 -269.719043) (xy 17.690131 -269.725143) (xy 17.744088 -269.739249) (xy 17.795417 -269.761061)
			(xy 17.843023 -269.790115) (xy 17.885891 -269.82579) (xy 17.923108 -269.867327) (xy 17.953881 -269.91384)
			(xy 17.977553 -269.964337) (xy 17.993621 -270.017744) (xy 18.001741 -270.07292) (xy 18.00225 -270.100806)
			(xy 18.001741 -270.128692) (xy 17.993621 -270.183868) (xy 17.977553 -270.237275) (xy 17.953881 -270.287772)
			(xy 17.923108 -270.334285) (xy 17.885891 -270.375822) (xy 17.843023 -270.411497) (xy 17.795417 -270.440551)
			(xy 17.744088 -270.462363) (xy 17.690131 -270.476469) (xy 17.634694 -270.482569) (xy 17.57896 -270.480532)
			(xy 17.524117 -270.470402) (xy 17.471333 -270.452395) (xy 17.421733 -270.426894) (xy 17.376375 -270.394443)
			(xy 17.336226 -270.355734) (xy 17.30214 -270.311591) (xy 17.274844 -270.262956) (xy 17.254921 -270.210865)
			(xy 17.242795 -270.156428) (xy 17.238724 -270.100806) (xy 11.472117 -270.100806) (xy 11.452972 -270.130419)
			(xy 11.435334 -270.151352) (xy 11.43508 -270.151606) (xy 11.429483 -270.158685) (xy 11.423243 -270.175608)
			(xy 11.422888 -270.184626) (xy 11.422888 -270.251682) (xy 11.423256 -270.260698) (xy 11.429496 -270.277615)
			(xy 11.43508 -270.284702) (xy 11.435334 -270.284702) (xy 11.435334 -270.284956) (xy 11.452971 -270.305889)
			(xy 11.482682 -270.351862) (xy 11.505518 -270.40161) (xy 11.52101 -270.45411) (xy 11.528839 -270.508285)
			(xy 11.529314 -270.535654) (xy 11.528802 -270.562905) (xy 11.521051 -270.616854) (xy 11.505701 -270.669151)
			(xy 11.483065 -270.71873) (xy 11.453602 -270.764584) (xy 11.417913 -270.805777) (xy 11.376725 -270.841471)
			(xy 11.330876 -270.87094) (xy 11.2813 -270.893583) (xy 11.229005 -270.90894) (xy 11.175057 -270.916698)
			(xy 11.147806 -270.917162) (xy 11.119068 -270.916618) (xy 11.062242 -270.907998) (xy 11.007352 -270.890952)
			(xy 10.95564 -270.865865) (xy 10.908276 -270.833306) (xy 10.886948 -270.814038) (xy 10.88009 -270.807434)
			(xy 10.870946 -270.803878) (xy 10.86648 -270.802258) (xy 10.857152 -270.800464) (xy 10.852404 -270.800322)
			(xy 10.782808 -270.800322) (xy 10.778055 -270.800421) (xy 10.768718 -270.802211) (xy 10.764266 -270.803878)
			(xy 10.755122 -270.807434) (xy 10.748264 -270.814038) (xy 10.726937 -270.833308) (xy 10.679574 -270.865873)
			(xy 10.627863 -270.890964) (xy 10.572972 -270.908014) (xy 10.516145 -270.916636) (xy 10.458667 -270.916636)
			(xy 10.40184 -270.908014) (xy 10.346949 -270.890964) (xy 10.295238 -270.865873) (xy 10.247875 -270.833308)
			(xy 10.226548 -270.814038) (xy 10.21969 -270.807434) (xy 10.210546 -270.803878) (xy 10.20608 -270.802258)
			(xy 10.196752 -270.800464) (xy 10.192004 -270.800322) (xy 10.122408 -270.800322) (xy 10.117655 -270.800421)
			(xy 10.108318 -270.802211) (xy 10.103866 -270.803878) (xy 10.094722 -270.807434) (xy 10.087864 -270.814038)
			(xy 10.066537 -270.833308) (xy 10.019174 -270.865873) (xy 9.967463 -270.890964) (xy 9.912572 -270.908014)
			(xy 9.855745 -270.916636) (xy 9.798267 -270.916636) (xy 9.74144 -270.908014) (xy 9.686549 -270.890964)
			(xy 9.634838 -270.865873) (xy 9.587475 -270.833308) (xy 9.566148 -270.814038) (xy 9.55929 -270.807434)
			(xy 9.550146 -270.803878) (xy 9.54568 -270.802258) (xy 9.536352 -270.800464) (xy 9.531604 -270.800322)
			(xy 9.462008 -270.800322) (xy 9.457255 -270.800421) (xy 9.447918 -270.802211) (xy 9.443466 -270.803878)
			(xy 9.434322 -270.807434) (xy 9.427464 -270.814038) (xy 9.406131 -270.833302) (xy 9.358771 -270.86587)
			(xy 9.307061 -270.890964) (xy 9.252171 -270.908016) (xy 9.195345 -270.916641) (xy 9.166606 -270.917162)
			(xy 9.139355 -270.916676) (xy 9.085407 -270.908919) (xy 9.033113 -270.893564) (xy 8.983536 -270.870922)
			(xy 8.937686 -270.841456) (xy 8.896496 -270.805764) (xy 8.860804 -270.764574) (xy 8.831338 -270.718724)
			(xy 8.808696 -270.669147) (xy 8.793341 -270.616853) (xy 8.785584 -270.562905) (xy 8.785098 -270.535654)
			(xy 7.730174 -270.535654) (xy 7.73819 -270.562821) (xy 7.746018 -270.616997) (xy 7.746492 -270.644366)
			(xy 7.746013 -270.671619) (xy 7.73826 -270.72557) (xy 7.722908 -270.777868) (xy 7.700268 -270.82745)
			(xy 7.670802 -270.873304) (xy 7.63511 -270.914497) (xy 7.593918 -270.950191) (xy 7.548065 -270.979659)
			(xy 7.498485 -271.002301) (xy 7.446188 -271.017656) (xy 7.392237 -271.025412) (xy 7.364984 -271.025874)
			(xy 7.336246 -271.02534) (xy 7.27942 -271.016717) (xy 7.22453 -270.999668) (xy 7.172818 -270.974579)
			(xy 7.125454 -270.942018) (xy 7.104126 -270.92275) (xy 7.097268 -270.916146) (xy 7.088124 -270.91259)
			(xy 7.083661 -270.910961) (xy 7.074331 -270.909174) (xy 7.069582 -270.909034) (xy 6.999986 -270.909034)
			(xy 6.995232 -270.909126) (xy 6.985896 -270.91092) (xy 6.981444 -270.91259) (xy 6.9723 -270.916146)
			(xy 6.965442 -270.92275) (xy 6.944115 -270.94202) (xy 6.896752 -270.974585) (xy 6.845041 -270.999676)
			(xy 6.79015 -271.016726) (xy 6.733323 -271.025348) (xy 6.675845 -271.025348) (xy 6.619018 -271.016726)
			(xy 6.564127 -270.999676) (xy 6.512416 -270.974585) (xy 6.465053 -270.94202) (xy 6.443726 -270.92275)
			(xy 6.436868 -270.916146) (xy 6.427724 -270.91259) (xy 6.423261 -270.910961) (xy 6.413931 -270.909174)
			(xy 6.409182 -270.909034) (xy 6.339586 -270.909034) (xy 6.334832 -270.909126) (xy 6.325496 -270.91092)
			(xy 6.321044 -270.91259) (xy 6.3119 -270.916146) (xy 6.305042 -270.92275) (xy 6.283715 -270.94202)
			(xy 6.236352 -270.974585) (xy 6.184641 -270.999676) (xy 6.12975 -271.016726) (xy 6.072923 -271.025348)
			(xy 6.015445 -271.025348) (xy 5.958618 -271.016726) (xy 5.903727 -270.999676) (xy 5.852016 -270.974585)
			(xy 5.804653 -270.94202) (xy 5.783326 -270.92275) (xy 5.776468 -270.916146) (xy 5.767324 -270.91259)
			(xy 5.762861 -270.910961) (xy 5.753531 -270.909174) (xy 5.748782 -270.909034) (xy 5.679186 -270.909034)
			(xy 5.674432 -270.909126) (xy 5.665096 -270.91092) (xy 5.660644 -270.91259) (xy 5.6515 -270.916146)
			(xy 5.644642 -270.92275) (xy 5.62332 -270.942026) (xy 5.575957 -270.974592) (xy 5.524244 -270.999684)
			(xy 5.469352 -271.016733) (xy 5.412523 -271.025354) (xy 5.383784 -271.025874) (xy 5.356531 -271.025411)
			(xy 5.30258 -271.017654) (xy 5.250282 -271.002299) (xy 5.200701 -270.979656) (xy 5.154848 -270.950188)
			(xy 5.113655 -270.914495) (xy 5.077962 -270.873302) (xy 5.048494 -270.827449) (xy 5.025851 -270.777868)
			(xy 5.010496 -270.72557) (xy 5.002739 -270.671619) (xy 5.002276 -270.644366) (xy 1.928662 -270.644366)
			(xy 1.924694 -270.671968) (xy 1.909339 -270.724263) (xy 1.886698 -270.773839) (xy 1.857232 -270.81969)
			(xy 1.821541 -270.860879) (xy 1.780351 -270.896571) (xy 1.734501 -270.926037) (xy 1.684924 -270.948678)
			(xy 1.63263 -270.964033) (xy 1.578683 -270.97179) (xy 1.551432 -270.97228) (xy 1.528318 -270.971518)
			(xy 1.52781 -270.971518) (xy 1.51851 -270.971365) (xy 1.500793 -270.976975) (xy 1.493266 -270.98244)
			(xy 1.489964 -270.985234) (xy 1.436116 -271.036034) (xy 1.428887 -271.043481) (xy 1.420627 -271.062498)
			(xy 1.420114 -271.072864) (xy 1.420114 -271.184624) (xy 17.47469 -271.184624) (xy 17.478761 -271.129002)
			(xy 17.490887 -271.074565) (xy 17.51081 -271.022474) (xy 17.538106 -270.973839) (xy 17.572192 -270.929696)
			(xy 17.612341 -270.890987) (xy 17.657699 -270.858536) (xy 17.707299 -270.833035) (xy 17.760083 -270.815028)
			(xy 17.814926 -270.804898) (xy 17.87066 -270.802861) (xy 17.926097 -270.808961) (xy 17.980054 -270.823067)
			(xy 18.031383 -270.844879) (xy 18.078989 -270.873933) (xy 18.11018 -270.89989) (xy 24.898611 -270.89989)
			(xy 24.902617 -270.704835) (xy 24.914627 -270.510109) (xy 24.934622 -270.31604) (xy 24.962567 -270.122956)
			(xy 24.998416 -269.931181) (xy 25.042108 -269.741041) (xy 25.093569 -269.552854) (xy 25.152713 -269.366939)
			(xy 25.21944 -269.183608) (xy 25.293637 -269.003172) (xy 25.375179 -268.825934) (xy 25.46393 -268.652193)
			(xy 25.559738 -268.482242) (xy 25.662443 -268.316368) (xy 25.771871 -268.15485) (xy 25.887838 -267.997961)
			(xy 26.010149 -267.845966) (xy 26.138596 -267.69912) (xy 26.272964 -267.557671) (xy 26.413026 -267.421858)
			(xy 26.558545 -267.291909) (xy 26.709277 -267.168045) (xy 26.864967 -267.050473) (xy 27.025353 -266.939393)
			(xy 27.190164 -266.83499) (xy 27.359122 -266.737442) (xy 27.531943 -266.646913) (xy 27.708335 -266.563555)
			(xy 27.888 -266.487509) (xy 28.070635 -266.418904) (xy 28.255934 -266.357854) (xy 28.443582 -266.304464)
			(xy 28.633264 -266.258822) (xy 28.824661 -266.221006) (xy 29.017448 -266.19108) (xy 29.211301 -266.169094)
			(xy 29.405894 -266.155085) (xy 29.600897 -266.149077) (xy 29.795983 -266.15108) (xy 29.990822 -266.161091)
			(xy 30.185086 -266.179092) (xy 30.378447 -266.205054) (xy 30.57058 -266.238932) (xy 30.761159 -266.280669)
			(xy 30.949864 -266.330196) (xy 31.136377 -266.387428) (xy 31.320383 -266.452269) (xy 31.48472 -266.517882)
			(xy 40.39692 -266.517882) (xy 40.400991 -266.46226) (xy 40.413117 -266.407823) (xy 40.43304 -266.355732)
			(xy 40.460336 -266.307097) (xy 40.494422 -266.262954) (xy 40.534571 -266.224245) (xy 40.579929 -266.191794)
			(xy 40.629529 -266.166293) (xy 40.682313 -266.148286) (xy 40.737156 -266.138156) (xy 40.79289 -266.136119)
			(xy 40.848327 -266.142219) (xy 40.902284 -266.156325) (xy 40.953613 -266.178137) (xy 41.001219 -266.207191)
			(xy 41.044087 -266.242866) (xy 41.081304 -266.284403) (xy 41.112077 -266.330916) (xy 41.135749 -266.381413)
			(xy 41.151817 -266.43482) (xy 41.159937 -266.489996) (xy 41.160446 -266.517882) (xy 41.159937 -266.545768)
			(xy 41.151817 -266.600944) (xy 41.135749 -266.654351) (xy 41.112077 -266.704848) (xy 41.081304 -266.751361)
			(xy 41.044087 -266.792898) (xy 41.001219 -266.828573) (xy 40.953613 -266.857627) (xy 40.902284 -266.879439)
			(xy 40.848327 -266.893545) (xy 40.79289 -266.899645) (xy 40.737156 -266.897608) (xy 40.682313 -266.887478)
			(xy 40.629529 -266.869471) (xy 40.579929 -266.84397) (xy 40.534571 -266.811519) (xy 40.494422 -266.77281)
			(xy 40.460336 -266.728667) (xy 40.43304 -266.680032) (xy 40.413117 -266.627941) (xy 40.400991 -266.573504)
			(xy 40.39692 -266.517882) (xy 31.48472 -266.517882) (xy 31.501571 -266.52461) (xy 31.679637 -266.604328)
			(xy 31.85428 -266.69129) (xy 32.025206 -266.785349) (xy 32.192125 -266.886345) (xy 32.308409 -266.963398)
			(xy 38.656004 -266.963398) (xy 38.660075 -266.907776) (xy 38.672201 -266.853339) (xy 38.692124 -266.801248)
			(xy 38.71942 -266.752613) (xy 38.753506 -266.70847) (xy 38.793655 -266.669761) (xy 38.839013 -266.63731)
			(xy 38.888613 -266.611809) (xy 38.941397 -266.593802) (xy 38.99624 -266.583672) (xy 39.051974 -266.581635)
			(xy 39.107411 -266.587735) (xy 39.161368 -266.601841) (xy 39.212697 -266.623653) (xy 39.260303 -266.652707)
			(xy 39.303171 -266.688382) (xy 39.340388 -266.729919) (xy 39.371161 -266.776432) (xy 39.394833 -266.826929)
			(xy 39.410901 -266.880336) (xy 39.419021 -266.935512) (xy 39.41953 -266.963398) (xy 39.419021 -266.991284)
			(xy 39.410901 -267.04646) (xy 39.394833 -267.099867) (xy 39.371161 -267.150364) (xy 39.340388 -267.196877)
			(xy 39.303171 -267.238414) (xy 39.260303 -267.274089) (xy 39.212697 -267.303143) (xy 39.161368 -267.324955)
			(xy 39.107411 -267.339061) (xy 39.051974 -267.345161) (xy 38.99624 -267.343124) (xy 38.941397 -267.332994)
			(xy 38.888613 -267.314987) (xy 38.839013 -267.289486) (xy 38.793655 -267.257035) (xy 38.753506 -267.218326)
			(xy 38.71942 -267.174183) (xy 38.692124 -267.125548) (xy 38.672201 -267.073457) (xy 38.660075 -267.01902)
			(xy 38.656004 -266.963398) (xy 32.308409 -266.963398) (xy 32.354758 -266.99411) (xy 32.512829 -267.10846)
			(xy 32.666072 -267.229203) (xy 32.814229 -267.356137) (xy 32.95705 -267.489045) (xy 33.045174 -267.578078)
			(xy 36.853112 -267.578078) (xy 36.857183 -267.522456) (xy 36.869309 -267.468019) (xy 36.889232 -267.415928)
			(xy 36.916528 -267.367293) (xy 36.950614 -267.32315) (xy 36.990763 -267.284441) (xy 37.036121 -267.25199)
			(xy 37.085721 -267.226489) (xy 37.138505 -267.208482) (xy 37.193348 -267.198352) (xy 37.249082 -267.196315)
			(xy 37.304519 -267.202415) (xy 37.358476 -267.216521) (xy 37.409805 -267.238333) (xy 37.457411 -267.267387)
			(xy 37.500279 -267.303062) (xy 37.537496 -267.344599) (xy 37.568269 -267.391112) (xy 37.591941 -267.441609)
			(xy 37.608009 -267.495016) (xy 37.616129 -267.550192) (xy 37.616638 -267.578078) (xy 37.616156 -267.604494)
			(xy 40.41775 -267.604494) (xy 40.418236 -267.577243) (xy 40.425992 -267.523295) (xy 40.441347 -267.471)
			(xy 40.463989 -267.421423) (xy 40.493455 -267.375573) (xy 40.529146 -267.334382) (xy 40.570337 -267.298691)
			(xy 40.616187 -267.269225) (xy 40.665764 -267.246583) (xy 40.718059 -267.231228) (xy 40.772007 -267.223472)
			(xy 40.826509 -267.223472) (xy 40.880457 -267.231228) (xy 40.932752 -267.246583) (xy 40.982329 -267.269225)
			(xy 41.028179 -267.298691) (xy 41.06937 -267.334382) (xy 41.105061 -267.375573) (xy 41.134527 -267.421423)
			(xy 41.157169 -267.471) (xy 41.172524 -267.523295) (xy 41.18028 -267.577243) (xy 41.180766 -267.604494)
			(xy 41.180261 -267.632763) (xy 41.17193 -267.688683) (xy 41.155434 -267.74276) (xy 41.131135 -267.79381)
			(xy 41.099566 -267.840712) (xy 41.061418 -267.88244) (xy 41.039796 -267.900658) (xy 41.029673 -267.909485)
			(xy 41.013976 -267.931265) (xy 41.004494 -267.956382) (xy 41.001881 -267.983101) (xy 41.006318 -268.009579)
			(xy 41.017498 -268.033987) (xy 41.034649 -268.05464) (xy 41.045384 -268.06271) (xy 41.066526 -268.078075)
			(xy 41.104806 -268.113657) (xy 41.13787 -268.154133) (xy 41.165096 -268.198745) (xy 41.185977 -268.246657)
			(xy 41.200119 -268.29697) (xy 41.207259 -268.348744) (xy 41.20769 -268.374876) (xy 41.207204 -268.402127)
			(xy 41.199448 -268.456075) (xy 41.184093 -268.50837) (xy 41.161451 -268.557947) (xy 41.131985 -268.603797)
			(xy 41.096294 -268.644988) (xy 41.055103 -268.680679) (xy 41.009253 -268.710145) (xy 40.959676 -268.732787)
			(xy 40.907381 -268.748142) (xy 40.853433 -268.755898) (xy 40.798931 -268.755898) (xy 40.744983 -268.748142)
			(xy 40.692688 -268.732787) (xy 40.643111 -268.710145) (xy 40.597261 -268.680679) (xy 40.55607 -268.644988)
			(xy 40.520379 -268.603797) (xy 40.490913 -268.557947) (xy 40.468271 -268.50837) (xy 40.452916 -268.456075)
			(xy 40.44516 -268.402127) (xy 40.444674 -268.374876) (xy 40.445179 -268.346607) (xy 40.453513 -268.290688)
			(xy 40.470011 -268.236612) (xy 40.49431 -268.185563) (xy 40.525878 -268.13866) (xy 40.564023 -268.096931)
			(xy 40.585644 -268.078712) (xy 40.595805 -268.069923) (xy 40.611512 -268.048137) (xy 40.620998 -268.02301)
			(xy 40.623608 -267.99628) (xy 40.619163 -267.969793) (xy 40.607969 -267.945379) (xy 40.5908 -267.924726)
			(xy 40.580056 -267.91666) (xy 40.558934 -267.90127) (xy 40.520655 -267.86569) (xy 40.487592 -267.825217)
			(xy 40.460364 -267.78061) (xy 40.439481 -267.732703) (xy 40.425333 -267.682394) (xy 40.418186 -267.630624)
			(xy 40.41775 -267.604494) (xy 37.616156 -267.604494) (xy 37.616129 -267.605964) (xy 37.608009 -267.66114)
			(xy 37.591941 -267.714547) (xy 37.568269 -267.765044) (xy 37.537496 -267.811557) (xy 37.500279 -267.853094)
			(xy 37.457411 -267.888769) (xy 37.409805 -267.917823) (xy 37.358476 -267.939635) (xy 37.304519 -267.953741)
			(xy 37.249082 -267.959841) (xy 37.193348 -267.957804) (xy 37.138505 -267.947674) (xy 37.085721 -267.929667)
			(xy 37.036121 -267.904166) (xy 36.990763 -267.871715) (xy 36.950614 -267.833006) (xy 36.916528 -267.788863)
			(xy 36.889232 -267.740228) (xy 36.869309 -267.688137) (xy 36.857183 -267.6337) (xy 36.853112 -267.578078)
			(xy 33.045174 -267.578078) (xy 33.094294 -267.627705) (xy 33.22573 -267.771883) (xy 33.351135 -267.921336)
			(xy 33.470299 -268.07581) (xy 33.58302 -268.235047) (xy 33.689109 -268.398778) (xy 33.788387 -268.566725)
			(xy 33.880685 -268.738608) (xy 33.96585 -268.914134) (xy 34.043736 -269.093009) (xy 34.114213 -269.274931)
			(xy 34.177161 -269.459593) (xy 34.232476 -269.646683) (xy 34.280062 -269.835887) (xy 34.319841 -270.026884)
			(xy 34.351745 -270.219354) (xy 34.37572 -270.412972) (xy 34.386802 -270.547592) (xy 39.118284 -270.547592)
			(xy 39.122355 -270.49197) (xy 39.134481 -270.437533) (xy 39.154404 -270.385442) (xy 39.1817 -270.336807)
			(xy 39.215786 -270.292664) (xy 39.255935 -270.253955) (xy 39.301293 -270.221504) (xy 39.350893 -270.196003)
			(xy 39.403677 -270.177996) (xy 39.45852 -270.167866) (xy 39.514254 -270.165829) (xy 39.569691 -270.171929)
			(xy 39.623648 -270.186035) (xy 39.674977 -270.207847) (xy 39.722583 -270.236901) (xy 39.765451 -270.272576)
			(xy 39.802668 -270.314113) (xy 39.833441 -270.360626) (xy 39.857113 -270.411123) (xy 39.873181 -270.46453)
			(xy 39.881301 -270.519706) (xy 39.88181 -270.547592) (xy 39.881301 -270.575478) (xy 39.873181 -270.630654)
			(xy 39.862636 -270.665702) (xy 40.061894 -270.665702) (xy 40.065965 -270.61008) (xy 40.078091 -270.555643)
			(xy 40.098014 -270.503552) (xy 40.12531 -270.454917) (xy 40.159396 -270.410774) (xy 40.199545 -270.372065)
			(xy 40.244903 -270.339614) (xy 40.294503 -270.314113) (xy 40.347287 -270.296106) (xy 40.40213 -270.285976)
			(xy 40.457864 -270.283939) (xy 40.513301 -270.290039) (xy 40.567258 -270.304145) (xy 40.618587 -270.325957)
			(xy 40.666193 -270.355011) (xy 40.709061 -270.390686) (xy 40.746278 -270.432223) (xy 40.777051 -270.478736)
			(xy 40.800723 -270.529233) (xy 40.816791 -270.58264) (xy 40.824911 -270.637816) (xy 40.82542 -270.665702)
			(xy 40.824911 -270.693588) (xy 40.816791 -270.748764) (xy 40.800723 -270.802171) (xy 40.777051 -270.852668)
			(xy 40.746278 -270.899181) (xy 40.709061 -270.940718) (xy 40.666193 -270.976393) (xy 40.618587 -271.005447)
			(xy 40.567258 -271.027259) (xy 40.513301 -271.041365) (xy 40.457864 -271.047465) (xy 40.40213 -271.045428)
			(xy 40.347287 -271.035298) (xy 40.294503 -271.017291) (xy 40.244903 -270.99179) (xy 40.199545 -270.959339)
			(xy 40.159396 -270.92063) (xy 40.12531 -270.876487) (xy 40.098014 -270.827852) (xy 40.078091 -270.775761)
			(xy 40.065965 -270.721324) (xy 40.061894 -270.665702) (xy 39.862636 -270.665702) (xy 39.857113 -270.684061)
			(xy 39.833441 -270.734558) (xy 39.802668 -270.781071) (xy 39.765451 -270.822608) (xy 39.722583 -270.858283)
			(xy 39.674977 -270.887337) (xy 39.623648 -270.909149) (xy 39.569691 -270.923255) (xy 39.514254 -270.929355)
			(xy 39.45852 -270.927318) (xy 39.403677 -270.917188) (xy 39.350893 -270.899181) (xy 39.301293 -270.87368)
			(xy 39.255935 -270.841229) (xy 39.215786 -270.80252) (xy 39.1817 -270.758377) (xy 39.154404 -270.709742)
			(xy 39.134481 -270.657651) (xy 39.122355 -270.603214) (xy 39.118284 -270.547592) (xy 34.386802 -270.547592)
			(xy 34.391726 -270.60741) (xy 34.399735 -270.802342) (xy 34.400236 -270.89989) (xy 34.399735 -270.997438)
			(xy 34.391726 -271.19237) (xy 34.37572 -271.386808) (xy 34.351745 -271.580426) (xy 34.319841 -271.772896)
			(xy 34.280062 -271.963893) (xy 34.232476 -272.153097) (xy 34.177161 -272.340187) (xy 34.114213 -272.524849)
			(xy 34.07549 -272.624804) (xy 37.969202 -272.624804) (xy 37.973162 -272.57575) (xy 37.984939 -272.527966)
			(xy 38.00423 -272.48269) (xy 38.030533 -272.441094) (xy 38.063168 -272.404257) (xy 38.101289 -272.373132)
			(xy 38.14391 -272.348525) (xy 38.189926 -272.331073) (xy 38.238145 -272.321229) (xy 38.28732 -272.319248)
			(xy 38.336175 -272.32518) (xy 38.383446 -272.338872) (xy 38.427908 -272.35997) (xy 38.468411 -272.387926)
			(xy 38.503904 -272.422018) (xy 38.533469 -272.461362) (xy 38.55634 -272.504939) (xy 38.571924 -272.55162)
			(xy 38.579819 -272.600197) (xy 38.580314 -272.624804) (xy 38.919162 -272.624804) (xy 38.923122 -272.57575)
			(xy 38.934899 -272.527966) (xy 38.95419 -272.48269) (xy 38.980493 -272.441094) (xy 39.013128 -272.404257)
			(xy 39.051249 -272.373132) (xy 39.09387 -272.348525) (xy 39.139886 -272.331073) (xy 39.188105 -272.321229)
			(xy 39.23728 -272.319248) (xy 39.286135 -272.32518) (xy 39.333406 -272.338872) (xy 39.377868 -272.35997)
			(xy 39.418371 -272.387926) (xy 39.453864 -272.422018) (xy 39.483429 -272.461362) (xy 39.5063 -272.504939)
			(xy 39.521884 -272.55162) (xy 39.529779 -272.600197) (xy 39.530274 -272.624804) (xy 39.869122 -272.624804)
			(xy 39.873082 -272.57575) (xy 39.884859 -272.527966) (xy 39.90415 -272.48269) (xy 39.930453 -272.441094)
			(xy 39.963088 -272.404257) (xy 40.001209 -272.373132) (xy 40.04383 -272.348525) (xy 40.089846 -272.331073)
			(xy 40.138065 -272.321229) (xy 40.18724 -272.319248) (xy 40.236095 -272.32518) (xy 40.283366 -272.338872)
			(xy 40.327828 -272.35997) (xy 40.368331 -272.387926) (xy 40.403824 -272.422018) (xy 40.433389 -272.461362)
			(xy 40.45626 -272.504939) (xy 40.471844 -272.55162) (xy 40.479739 -272.600197) (xy 40.480234 -272.624804)
			(xy 40.819082 -272.624804) (xy 40.823042 -272.57575) (xy 40.834819 -272.527966) (xy 40.85411 -272.48269)
			(xy 40.880413 -272.441094) (xy 40.913048 -272.404257) (xy 40.951169 -272.373132) (xy 40.99379 -272.348525)
			(xy 41.039806 -272.331073) (xy 41.088025 -272.321229) (xy 41.1372 -272.319248) (xy 41.186055 -272.32518)
			(xy 41.233326 -272.338872) (xy 41.277788 -272.35997) (xy 41.318291 -272.387926) (xy 41.353784 -272.422018)
			(xy 41.383349 -272.461362) (xy 41.40622 -272.504939) (xy 41.421804 -272.55162) (xy 41.429699 -272.600197)
			(xy 41.430194 -272.624804) (xy 41.429699 -272.649411) (xy 41.421804 -272.697988) (xy 41.40622 -272.744669)
			(xy 41.383349 -272.788246) (xy 41.353784 -272.82759) (xy 41.318291 -272.861682) (xy 41.277788 -272.889638)
			(xy 41.233326 -272.910736) (xy 41.186055 -272.924428) (xy 41.1372 -272.93036) (xy 41.088025 -272.928379)
			(xy 41.039806 -272.918535) (xy 40.99379 -272.901083) (xy 40.951169 -272.876476) (xy 40.913048 -272.845351)
			(xy 40.880413 -272.808514) (xy 40.85411 -272.766918) (xy 40.834819 -272.721642) (xy 40.823042 -272.673858)
			(xy 40.819082 -272.624804) (xy 40.480234 -272.624804) (xy 40.479739 -272.649411) (xy 40.471844 -272.697988)
			(xy 40.45626 -272.744669) (xy 40.433389 -272.788246) (xy 40.403824 -272.82759) (xy 40.368331 -272.861682)
			(xy 40.327828 -272.889638) (xy 40.283366 -272.910736) (xy 40.236095 -272.924428) (xy 40.18724 -272.93036)
			(xy 40.138065 -272.928379) (xy 40.089846 -272.918535) (xy 40.04383 -272.901083) (xy 40.001209 -272.876476)
			(xy 39.963088 -272.845351) (xy 39.930453 -272.808514) (xy 39.90415 -272.766918) (xy 39.884859 -272.721642)
			(xy 39.873082 -272.673858) (xy 39.869122 -272.624804) (xy 39.530274 -272.624804) (xy 39.529779 -272.649411)
			(xy 39.521884 -272.697988) (xy 39.5063 -272.744669) (xy 39.483429 -272.788246) (xy 39.453864 -272.82759)
			(xy 39.418371 -272.861682) (xy 39.377868 -272.889638) (xy 39.333406 -272.910736) (xy 39.286135 -272.924428)
			(xy 39.23728 -272.93036) (xy 39.188105 -272.928379) (xy 39.139886 -272.918535) (xy 39.09387 -272.901083)
			(xy 39.051249 -272.876476) (xy 39.013128 -272.845351) (xy 38.980493 -272.808514) (xy 38.95419 -272.766918)
			(xy 38.934899 -272.721642) (xy 38.923122 -272.673858) (xy 38.919162 -272.624804) (xy 38.580314 -272.624804)
			(xy 38.579819 -272.649411) (xy 38.571924 -272.697988) (xy 38.55634 -272.744669) (xy 38.533469 -272.788246)
			(xy 38.503904 -272.82759) (xy 38.468411 -272.861682) (xy 38.427908 -272.889638) (xy 38.383446 -272.910736)
			(xy 38.336175 -272.924428) (xy 38.28732 -272.93036) (xy 38.238145 -272.928379) (xy 38.189926 -272.918535)
			(xy 38.14391 -272.901083) (xy 38.101289 -272.876476) (xy 38.063168 -272.845351) (xy 38.030533 -272.808514)
			(xy 38.00423 -272.766918) (xy 37.984939 -272.721642) (xy 37.973162 -272.673858) (xy 37.969202 -272.624804)
			(xy 34.07549 -272.624804) (xy 34.043736 -272.706771) (xy 33.96585 -272.885646) (xy 33.880685 -273.061172)
			(xy 33.788387 -273.233055) (xy 33.689109 -273.401002) (xy 33.58302 -273.564733) (xy 33.575919 -273.574764)
			(xy 37.018988 -273.574764) (xy 37.022948 -273.52571) (xy 37.034725 -273.477926) (xy 37.054016 -273.43265)
			(xy 37.080319 -273.391054) (xy 37.112954 -273.354217) (xy 37.151075 -273.323092) (xy 37.193696 -273.298485)
			(xy 37.239712 -273.281033) (xy 37.287931 -273.271189) (xy 37.337106 -273.269208) (xy 37.385961 -273.27514)
			(xy 37.433232 -273.288832) (xy 37.477694 -273.30993) (xy 37.518197 -273.337886) (xy 37.55369 -273.371978)
			(xy 37.583255 -273.411322) (xy 37.606126 -273.454899) (xy 37.62171 -273.50158) (xy 37.629605 -273.550157)
			(xy 37.6301 -273.574764) (xy 37.968948 -273.574764) (xy 37.972908 -273.52571) (xy 37.984685 -273.477926)
			(xy 38.003976 -273.43265) (xy 38.030279 -273.391054) (xy 38.062914 -273.354217) (xy 38.101035 -273.323092)
			(xy 38.143656 -273.298485) (xy 38.189672 -273.281033) (xy 38.237891 -273.271189) (xy 38.287066 -273.269208)
			(xy 38.335921 -273.27514) (xy 38.383192 -273.288832) (xy 38.427654 -273.30993) (xy 38.468157 -273.337886)
			(xy 38.50365 -273.371978) (xy 38.533215 -273.411322) (xy 38.556086 -273.454899) (xy 38.57167 -273.50158)
			(xy 38.579565 -273.550157) (xy 38.58006 -273.574764) (xy 38.919162 -273.574764) (xy 38.923122 -273.52571)
			(xy 38.934899 -273.477926) (xy 38.95419 -273.43265) (xy 38.980493 -273.391054) (xy 39.013128 -273.354217)
			(xy 39.051249 -273.323092) (xy 39.09387 -273.298485) (xy 39.139886 -273.281033) (xy 39.188105 -273.271189)
			(xy 39.23728 -273.269208) (xy 39.286135 -273.27514) (xy 39.333406 -273.288832) (xy 39.377868 -273.30993)
			(xy 39.418371 -273.337886) (xy 39.453864 -273.371978) (xy 39.483429 -273.411322) (xy 39.5063 -273.454899)
			(xy 39.521884 -273.50158) (xy 39.529779 -273.550157) (xy 39.530274 -273.574764) (xy 39.869122 -273.574764)
			(xy 39.873082 -273.52571) (xy 39.884859 -273.477926) (xy 39.90415 -273.43265) (xy 39.930453 -273.391054)
			(xy 39.963088 -273.354217) (xy 40.001209 -273.323092) (xy 40.04383 -273.298485) (xy 40.089846 -273.281033)
			(xy 40.138065 -273.271189) (xy 40.18724 -273.269208) (xy 40.236095 -273.27514) (xy 40.283366 -273.288832)
			(xy 40.327828 -273.30993) (xy 40.368331 -273.337886) (xy 40.403824 -273.371978) (xy 40.433389 -273.411322)
			(xy 40.45626 -273.454899) (xy 40.471844 -273.50158) (xy 40.479739 -273.550157) (xy 40.480234 -273.574764)
			(xy 40.819082 -273.574764) (xy 40.823042 -273.52571) (xy 40.834819 -273.477926) (xy 40.85411 -273.43265)
			(xy 40.880413 -273.391054) (xy 40.913048 -273.354217) (xy 40.951169 -273.323092) (xy 40.99379 -273.298485)
			(xy 41.039806 -273.281033) (xy 41.088025 -273.271189) (xy 41.1372 -273.269208) (xy 41.186055 -273.27514)
			(xy 41.233326 -273.288832) (xy 41.277788 -273.30993) (xy 41.318291 -273.337886) (xy 41.353784 -273.371978)
			(xy 41.383349 -273.411322) (xy 41.40622 -273.454899) (xy 41.421804 -273.50158) (xy 41.429699 -273.550157)
			(xy 41.430194 -273.574764) (xy 41.429699 -273.599371) (xy 41.421804 -273.647948) (xy 41.40622 -273.694629)
			(xy 41.383349 -273.738206) (xy 41.353784 -273.77755) (xy 41.318291 -273.811642) (xy 41.277788 -273.839598)
			(xy 41.233326 -273.860696) (xy 41.186055 -273.874388) (xy 41.1372 -273.88032) (xy 41.088025 -273.878339)
			(xy 41.039806 -273.868495) (xy 40.99379 -273.851043) (xy 40.951169 -273.826436) (xy 40.913048 -273.795311)
			(xy 40.880413 -273.758474) (xy 40.85411 -273.716878) (xy 40.834819 -273.671602) (xy 40.823042 -273.623818)
			(xy 40.819082 -273.574764) (xy 40.480234 -273.574764) (xy 40.479739 -273.599371) (xy 40.471844 -273.647948)
			(xy 40.45626 -273.694629) (xy 40.433389 -273.738206) (xy 40.403824 -273.77755) (xy 40.368331 -273.811642)
			(xy 40.327828 -273.839598) (xy 40.283366 -273.860696) (xy 40.236095 -273.874388) (xy 40.18724 -273.88032)
			(xy 40.138065 -273.878339) (xy 40.089846 -273.868495) (xy 40.04383 -273.851043) (xy 40.001209 -273.826436)
			(xy 39.963088 -273.795311) (xy 39.930453 -273.758474) (xy 39.90415 -273.716878) (xy 39.884859 -273.671602)
			(xy 39.873082 -273.623818) (xy 39.869122 -273.574764) (xy 39.530274 -273.574764) (xy 39.529779 -273.599371)
			(xy 39.521884 -273.647948) (xy 39.5063 -273.694629) (xy 39.483429 -273.738206) (xy 39.453864 -273.77755)
			(xy 39.418371 -273.811642) (xy 39.377868 -273.839598) (xy 39.333406 -273.860696) (xy 39.286135 -273.874388)
			(xy 39.23728 -273.88032) (xy 39.188105 -273.878339) (xy 39.139886 -273.868495) (xy 39.09387 -273.851043)
			(xy 39.051249 -273.826436) (xy 39.013128 -273.795311) (xy 38.980493 -273.758474) (xy 38.95419 -273.716878)
			(xy 38.934899 -273.671602) (xy 38.923122 -273.623818) (xy 38.919162 -273.574764) (xy 38.58006 -273.574764)
			(xy 38.579565 -273.599371) (xy 38.57167 -273.647948) (xy 38.556086 -273.694629) (xy 38.533215 -273.738206)
			(xy 38.50365 -273.77755) (xy 38.468157 -273.811642) (xy 38.427654 -273.839598) (xy 38.383192 -273.860696)
			(xy 38.335921 -273.874388) (xy 38.287066 -273.88032) (xy 38.237891 -273.878339) (xy 38.189672 -273.868495)
			(xy 38.143656 -273.851043) (xy 38.101035 -273.826436) (xy 38.062914 -273.795311) (xy 38.030279 -273.758474)
			(xy 38.003976 -273.716878) (xy 37.984685 -273.671602) (xy 37.972908 -273.623818) (xy 37.968948 -273.574764)
			(xy 37.6301 -273.574764) (xy 37.629605 -273.599371) (xy 37.62171 -273.647948) (xy 37.606126 -273.694629)
			(xy 37.583255 -273.738206) (xy 37.55369 -273.77755) (xy 37.518197 -273.811642) (xy 37.477694 -273.839598)
			(xy 37.433232 -273.860696) (xy 37.385961 -273.874388) (xy 37.337106 -273.88032) (xy 37.287931 -273.878339)
			(xy 37.239712 -273.868495) (xy 37.193696 -273.851043) (xy 37.151075 -273.826436) (xy 37.112954 -273.795311)
			(xy 37.080319 -273.758474) (xy 37.054016 -273.716878) (xy 37.034725 -273.671602) (xy 37.022948 -273.623818)
			(xy 37.018988 -273.574764) (xy 33.575919 -273.574764) (xy 33.470299 -273.72397) (xy 33.351135 -273.878444)
			(xy 33.22573 -274.027897) (xy 33.094294 -274.172075) (xy 32.95705 -274.310735) (xy 32.814229 -274.443643)
			(xy 32.719591 -274.524724) (xy 37.018988 -274.524724) (xy 37.022948 -274.47567) (xy 37.034725 -274.427886)
			(xy 37.054016 -274.38261) (xy 37.080319 -274.341014) (xy 37.112954 -274.304177) (xy 37.151075 -274.273052)
			(xy 37.193696 -274.248445) (xy 37.239712 -274.230993) (xy 37.287931 -274.221149) (xy 37.337106 -274.219168)
			(xy 37.385961 -274.2251) (xy 37.433232 -274.238792) (xy 37.477694 -274.25989) (xy 37.518197 -274.287846)
			(xy 37.55369 -274.321938) (xy 37.583255 -274.361282) (xy 37.606126 -274.404859) (xy 37.62171 -274.45154)
			(xy 37.629605 -274.500117) (xy 37.6301 -274.524724) (xy 37.630095 -274.524978) (xy 37.969202 -274.524978)
			(xy 37.973162 -274.475924) (xy 37.984939 -274.42814) (xy 38.00423 -274.382864) (xy 38.030533 -274.341268)
			(xy 38.063168 -274.304431) (xy 38.101289 -274.273306) (xy 38.14391 -274.248699) (xy 38.189926 -274.231247)
			(xy 38.238145 -274.221403) (xy 38.28732 -274.219422) (xy 38.336175 -274.225354) (xy 38.383446 -274.239046)
			(xy 38.427908 -274.260144) (xy 38.468411 -274.2881) (xy 38.503904 -274.322192) (xy 38.533469 -274.361536)
			(xy 38.55634 -274.405113) (xy 38.571924 -274.451794) (xy 38.579819 -274.500371) (xy 38.580314 -274.524978)
			(xy 38.919162 -274.524978) (xy 38.923122 -274.475924) (xy 38.934899 -274.42814) (xy 38.95419 -274.382864)
			(xy 38.980493 -274.341268) (xy 39.013128 -274.304431) (xy 39.051249 -274.273306) (xy 39.09387 -274.248699)
			(xy 39.139886 -274.231247) (xy 39.188105 -274.221403) (xy 39.23728 -274.219422) (xy 39.286135 -274.225354)
			(xy 39.333406 -274.239046) (xy 39.377868 -274.260144) (xy 39.418371 -274.2881) (xy 39.453864 -274.322192)
			(xy 39.483429 -274.361536) (xy 39.5063 -274.405113) (xy 39.521884 -274.451794) (xy 39.529779 -274.500371)
			(xy 39.530274 -274.524978) (xy 39.869122 -274.524978) (xy 39.873082 -274.475924) (xy 39.884859 -274.42814)
			(xy 39.90415 -274.382864) (xy 39.930453 -274.341268) (xy 39.963088 -274.304431) (xy 40.001209 -274.273306)
			(xy 40.04383 -274.248699) (xy 40.089846 -274.231247) (xy 40.138065 -274.221403) (xy 40.18724 -274.219422)
			(xy 40.236095 -274.225354) (xy 40.283366 -274.239046) (xy 40.327828 -274.260144) (xy 40.368331 -274.2881)
			(xy 40.403824 -274.322192) (xy 40.433389 -274.361536) (xy 40.45626 -274.405113) (xy 40.471844 -274.451794)
			(xy 40.479739 -274.500371) (xy 40.480234 -274.524978) (xy 40.819082 -274.524978) (xy 40.823042 -274.475924)
			(xy 40.834819 -274.42814) (xy 40.85411 -274.382864) (xy 40.880413 -274.341268) (xy 40.913048 -274.304431)
			(xy 40.951169 -274.273306) (xy 40.99379 -274.248699) (xy 41.039806 -274.231247) (xy 41.088025 -274.221403)
			(xy 41.1372 -274.219422) (xy 41.186055 -274.225354) (xy 41.233326 -274.239046) (xy 41.277788 -274.260144)
			(xy 41.318291 -274.2881) (xy 41.353784 -274.322192) (xy 41.383349 -274.361536) (xy 41.40622 -274.405113)
			(xy 41.421804 -274.451794) (xy 41.429699 -274.500371) (xy 41.430194 -274.524978) (xy 41.429699 -274.549585)
			(xy 41.421804 -274.598162) (xy 41.40622 -274.644843) (xy 41.383349 -274.68842) (xy 41.353784 -274.727764)
			(xy 41.318291 -274.761856) (xy 41.277788 -274.789812) (xy 41.233326 -274.81091) (xy 41.186055 -274.824602)
			(xy 41.1372 -274.830534) (xy 41.088025 -274.828553) (xy 41.039806 -274.818709) (xy 40.99379 -274.801257)
			(xy 40.951169 -274.77665) (xy 40.913048 -274.745525) (xy 40.880413 -274.708688) (xy 40.85411 -274.667092)
			(xy 40.834819 -274.621816) (xy 40.823042 -274.574032) (xy 40.819082 -274.524978) (xy 40.480234 -274.524978)
			(xy 40.479739 -274.549585) (xy 40.471844 -274.598162) (xy 40.45626 -274.644843) (xy 40.433389 -274.68842)
			(xy 40.403824 -274.727764) (xy 40.368331 -274.761856) (xy 40.327828 -274.789812) (xy 40.283366 -274.81091)
			(xy 40.236095 -274.824602) (xy 40.18724 -274.830534) (xy 40.138065 -274.828553) (xy 40.089846 -274.818709)
			(xy 40.04383 -274.801257) (xy 40.001209 -274.77665) (xy 39.963088 -274.745525) (xy 39.930453 -274.708688)
			(xy 39.90415 -274.667092) (xy 39.884859 -274.621816) (xy 39.873082 -274.574032) (xy 39.869122 -274.524978)
			(xy 39.530274 -274.524978) (xy 39.529779 -274.549585) (xy 39.521884 -274.598162) (xy 39.5063 -274.644843)
			(xy 39.483429 -274.68842) (xy 39.453864 -274.727764) (xy 39.418371 -274.761856) (xy 39.377868 -274.789812)
			(xy 39.333406 -274.81091) (xy 39.286135 -274.824602) (xy 39.23728 -274.830534) (xy 39.188105 -274.828553)
			(xy 39.139886 -274.818709) (xy 39.09387 -274.801257) (xy 39.051249 -274.77665) (xy 39.013128 -274.745525)
			(xy 38.980493 -274.708688) (xy 38.95419 -274.667092) (xy 38.934899 -274.621816) (xy 38.923122 -274.574032)
			(xy 38.919162 -274.524978) (xy 38.580314 -274.524978) (xy 38.579819 -274.549585) (xy 38.571924 -274.598162)
			(xy 38.55634 -274.644843) (xy 38.533469 -274.68842) (xy 38.503904 -274.727764) (xy 38.468411 -274.761856)
			(xy 38.427908 -274.789812) (xy 38.383446 -274.81091) (xy 38.336175 -274.824602) (xy 38.28732 -274.830534)
			(xy 38.238145 -274.828553) (xy 38.189926 -274.818709) (xy 38.14391 -274.801257) (xy 38.101289 -274.77665)
			(xy 38.063168 -274.745525) (xy 38.030533 -274.708688) (xy 38.00423 -274.667092) (xy 37.984939 -274.621816)
			(xy 37.973162 -274.574032) (xy 37.969202 -274.524978) (xy 37.630095 -274.524978) (xy 37.629605 -274.549331)
			(xy 37.62171 -274.597908) (xy 37.606126 -274.644589) (xy 37.583255 -274.688166) (xy 37.55369 -274.72751)
			(xy 37.518197 -274.761602) (xy 37.477694 -274.789558) (xy 37.433232 -274.810656) (xy 37.385961 -274.824348)
			(xy 37.337106 -274.83028) (xy 37.287931 -274.828299) (xy 37.239712 -274.818455) (xy 37.193696 -274.801003)
			(xy 37.151075 -274.776396) (xy 37.112954 -274.745271) (xy 37.080319 -274.708434) (xy 37.054016 -274.666838)
			(xy 37.034725 -274.621562) (xy 37.022948 -274.573778) (xy 37.018988 -274.524724) (xy 32.719591 -274.524724)
			(xy 32.666072 -274.570577) (xy 32.512829 -274.69132) (xy 32.354758 -274.80567) (xy 32.192125 -274.913435)
			(xy 32.025206 -275.014431) (xy 31.85428 -275.10849) (xy 31.679637 -275.195452) (xy 31.501571 -275.27517)
			(xy 31.320383 -275.347511) (xy 31.136377 -275.412352) (xy 30.949864 -275.469584) (xy 30.929464 -275.474938)
			(xy 36.069028 -275.474938) (xy 36.072988 -275.425884) (xy 36.084765 -275.3781) (xy 36.104056 -275.332824)
			(xy 36.130359 -275.291228) (xy 36.162994 -275.254391) (xy 36.201115 -275.223266) (xy 36.243736 -275.198659)
			(xy 36.289752 -275.181207) (xy 36.337971 -275.171363) (xy 36.387146 -275.169382) (xy 36.436001 -275.175314)
			(xy 36.483272 -275.189006) (xy 36.527734 -275.210104) (xy 36.568237 -275.23806) (xy 36.60373 -275.272152)
			(xy 36.633295 -275.311496) (xy 36.656166 -275.355073) (xy 36.67175 -275.401754) (xy 36.679645 -275.450331)
			(xy 36.68014 -275.474938) (xy 37.018988 -275.474938) (xy 37.022948 -275.425884) (xy 37.034725 -275.3781)
			(xy 37.054016 -275.332824) (xy 37.080319 -275.291228) (xy 37.112954 -275.254391) (xy 37.151075 -275.223266)
			(xy 37.193696 -275.198659) (xy 37.239712 -275.181207) (xy 37.287931 -275.171363) (xy 37.337106 -275.169382)
			(xy 37.385961 -275.175314) (xy 37.433232 -275.189006) (xy 37.477694 -275.210104) (xy 37.518197 -275.23806)
			(xy 37.55369 -275.272152) (xy 37.583255 -275.311496) (xy 37.606126 -275.355073) (xy 37.62171 -275.401754)
			(xy 37.629605 -275.450331) (xy 37.6301 -275.474938) (xy 37.969202 -275.474938) (xy 37.973162 -275.425884)
			(xy 37.984939 -275.3781) (xy 38.00423 -275.332824) (xy 38.030533 -275.291228) (xy 38.063168 -275.254391)
			(xy 38.101289 -275.223266) (xy 38.14391 -275.198659) (xy 38.189926 -275.181207) (xy 38.238145 -275.171363)
			(xy 38.28732 -275.169382) (xy 38.336175 -275.175314) (xy 38.383446 -275.189006) (xy 38.427908 -275.210104)
			(xy 38.468411 -275.23806) (xy 38.503904 -275.272152) (xy 38.533469 -275.311496) (xy 38.55634 -275.355073)
			(xy 38.571924 -275.401754) (xy 38.579819 -275.450331) (xy 38.580314 -275.474938) (xy 38.919162 -275.474938)
			(xy 38.923122 -275.425884) (xy 38.934899 -275.3781) (xy 38.95419 -275.332824) (xy 38.980493 -275.291228)
			(xy 39.013128 -275.254391) (xy 39.051249 -275.223266) (xy 39.09387 -275.198659) (xy 39.139886 -275.181207)
			(xy 39.188105 -275.171363) (xy 39.23728 -275.169382) (xy 39.286135 -275.175314) (xy 39.333406 -275.189006)
			(xy 39.377868 -275.210104) (xy 39.418371 -275.23806) (xy 39.453864 -275.272152) (xy 39.483429 -275.311496)
			(xy 39.5063 -275.355073) (xy 39.521884 -275.401754) (xy 39.529779 -275.450331) (xy 39.530274 -275.474938)
			(xy 39.869122 -275.474938) (xy 39.873082 -275.425884) (xy 39.884859 -275.3781) (xy 39.90415 -275.332824)
			(xy 39.930453 -275.291228) (xy 39.963088 -275.254391) (xy 40.001209 -275.223266) (xy 40.04383 -275.198659)
			(xy 40.089846 -275.181207) (xy 40.138065 -275.171363) (xy 40.18724 -275.169382) (xy 40.236095 -275.175314)
			(xy 40.283366 -275.189006) (xy 40.327828 -275.210104) (xy 40.368331 -275.23806) (xy 40.403824 -275.272152)
			(xy 40.433389 -275.311496) (xy 40.45626 -275.355073) (xy 40.471844 -275.401754) (xy 40.479739 -275.450331)
			(xy 40.480234 -275.474938) (xy 40.819082 -275.474938) (xy 40.823042 -275.425884) (xy 40.834819 -275.3781)
			(xy 40.85411 -275.332824) (xy 40.880413 -275.291228) (xy 40.913048 -275.254391) (xy 40.951169 -275.223266)
			(xy 40.99379 -275.198659) (xy 41.039806 -275.181207) (xy 41.088025 -275.171363) (xy 41.1372 -275.169382)
			(xy 41.186055 -275.175314) (xy 41.233326 -275.189006) (xy 41.277788 -275.210104) (xy 41.318291 -275.23806)
			(xy 41.353784 -275.272152) (xy 41.383349 -275.311496) (xy 41.40622 -275.355073) (xy 41.421804 -275.401754)
			(xy 41.429699 -275.450331) (xy 41.430194 -275.474938) (xy 41.429699 -275.499545) (xy 41.421804 -275.548122)
			(xy 41.40622 -275.594803) (xy 41.383349 -275.63838) (xy 41.353784 -275.677724) (xy 41.318291 -275.711816)
			(xy 41.277788 -275.739772) (xy 41.233326 -275.76087) (xy 41.186055 -275.774562) (xy 41.1372 -275.780494)
			(xy 41.088025 -275.778513) (xy 41.039806 -275.768669) (xy 40.99379 -275.751217) (xy 40.951169 -275.72661)
			(xy 40.913048 -275.695485) (xy 40.880413 -275.658648) (xy 40.85411 -275.617052) (xy 40.834819 -275.571776)
			(xy 40.823042 -275.523992) (xy 40.819082 -275.474938) (xy 40.480234 -275.474938) (xy 40.479739 -275.499545)
			(xy 40.471844 -275.548122) (xy 40.45626 -275.594803) (xy 40.433389 -275.63838) (xy 40.403824 -275.677724)
			(xy 40.368331 -275.711816) (xy 40.327828 -275.739772) (xy 40.283366 -275.76087) (xy 40.236095 -275.774562)
			(xy 40.18724 -275.780494) (xy 40.138065 -275.778513) (xy 40.089846 -275.768669) (xy 40.04383 -275.751217)
			(xy 40.001209 -275.72661) (xy 39.963088 -275.695485) (xy 39.930453 -275.658648) (xy 39.90415 -275.617052)
			(xy 39.884859 -275.571776) (xy 39.873082 -275.523992) (xy 39.869122 -275.474938) (xy 39.530274 -275.474938)
			(xy 39.529779 -275.499545) (xy 39.521884 -275.548122) (xy 39.5063 -275.594803) (xy 39.483429 -275.63838)
			(xy 39.453864 -275.677724) (xy 39.418371 -275.711816) (xy 39.377868 -275.739772) (xy 39.333406 -275.76087)
			(xy 39.286135 -275.774562) (xy 39.23728 -275.780494) (xy 39.188105 -275.778513) (xy 39.139886 -275.768669)
			(xy 39.09387 -275.751217) (xy 39.051249 -275.72661) (xy 39.013128 -275.695485) (xy 38.980493 -275.658648)
			(xy 38.95419 -275.617052) (xy 38.934899 -275.571776) (xy 38.923122 -275.523992) (xy 38.919162 -275.474938)
			(xy 38.580314 -275.474938) (xy 38.579819 -275.499545) (xy 38.571924 -275.548122) (xy 38.55634 -275.594803)
			(xy 38.533469 -275.63838) (xy 38.503904 -275.677724) (xy 38.468411 -275.711816) (xy 38.427908 -275.739772)
			(xy 38.383446 -275.76087) (xy 38.336175 -275.774562) (xy 38.28732 -275.780494) (xy 38.238145 -275.778513)
			(xy 38.189926 -275.768669) (xy 38.14391 -275.751217) (xy 38.101289 -275.72661) (xy 38.063168 -275.695485)
			(xy 38.030533 -275.658648) (xy 38.00423 -275.617052) (xy 37.984939 -275.571776) (xy 37.973162 -275.523992)
			(xy 37.969202 -275.474938) (xy 37.6301 -275.474938) (xy 37.629605 -275.499545) (xy 37.62171 -275.548122)
			(xy 37.606126 -275.594803) (xy 37.583255 -275.63838) (xy 37.55369 -275.677724) (xy 37.518197 -275.711816)
			(xy 37.477694 -275.739772) (xy 37.433232 -275.76087) (xy 37.385961 -275.774562) (xy 37.337106 -275.780494)
			(xy 37.287931 -275.778513) (xy 37.239712 -275.768669) (xy 37.193696 -275.751217) (xy 37.151075 -275.72661)
			(xy 37.112954 -275.695485) (xy 37.080319 -275.658648) (xy 37.054016 -275.617052) (xy 37.034725 -275.571776)
			(xy 37.022948 -275.523992) (xy 37.018988 -275.474938) (xy 36.68014 -275.474938) (xy 36.679645 -275.499545)
			(xy 36.67175 -275.548122) (xy 36.656166 -275.594803) (xy 36.633295 -275.63838) (xy 36.60373 -275.677724)
			(xy 36.568237 -275.711816) (xy 36.527734 -275.739772) (xy 36.483272 -275.76087) (xy 36.436001 -275.774562)
			(xy 36.387146 -275.780494) (xy 36.337971 -275.778513) (xy 36.289752 -275.768669) (xy 36.243736 -275.751217)
			(xy 36.201115 -275.72661) (xy 36.162994 -275.695485) (xy 36.130359 -275.658648) (xy 36.104056 -275.617052)
			(xy 36.084765 -275.571776) (xy 36.072988 -275.523992) (xy 36.069028 -275.474938) (xy 30.929464 -275.474938)
			(xy 30.761159 -275.519111) (xy 30.57058 -275.560848) (xy 30.378447 -275.594726) (xy 30.185086 -275.620688)
			(xy 29.990822 -275.638689) (xy 29.795983 -275.6487) (xy 29.600897 -275.650703) (xy 29.405894 -275.644695)
			(xy 29.211301 -275.630686) (xy 29.017448 -275.6087) (xy 28.824661 -275.578774) (xy 28.633264 -275.540958)
			(xy 28.443582 -275.495316) (xy 28.255934 -275.441926) (xy 28.070635 -275.380876) (xy 27.888 -275.312271)
			(xy 27.708335 -275.236225) (xy 27.531943 -275.152867) (xy 27.359122 -275.062338) (xy 27.190164 -274.96479)
			(xy 27.025353 -274.860387) (xy 26.864967 -274.749307) (xy 26.709277 -274.631735) (xy 26.558545 -274.507871)
			(xy 26.413026 -274.377922) (xy 26.272964 -274.242109) (xy 26.138596 -274.10066) (xy 26.010149 -273.953814)
			(xy 25.887838 -273.801819) (xy 25.771871 -273.64493) (xy 25.662443 -273.483412) (xy 25.559738 -273.317538)
			(xy 25.46393 -273.147587) (xy 25.375179 -272.973846) (xy 25.293637 -272.796608) (xy 25.21944 -272.616172)
			(xy 25.152713 -272.432841) (xy 25.093569 -272.246926) (xy 25.042108 -272.058739) (xy 24.998416 -271.868599)
			(xy 24.962567 -271.676824) (xy 24.934622 -271.48374) (xy 24.914627 -271.289671) (xy 24.902617 -271.094945)
			(xy 24.898611 -270.89989) (xy 18.11018 -270.89989) (xy 18.121857 -270.909608) (xy 18.159074 -270.951145)
			(xy 18.189847 -270.997658) (xy 18.213519 -271.048155) (xy 18.229587 -271.101562) (xy 18.237707 -271.156738)
			(xy 18.238216 -271.184624) (xy 18.237707 -271.21251) (xy 18.229587 -271.267686) (xy 18.213519 -271.321093)
			(xy 18.189847 -271.37159) (xy 18.159074 -271.418103) (xy 18.121857 -271.45964) (xy 18.078989 -271.495315)
			(xy 18.031383 -271.524369) (xy 17.980054 -271.546181) (xy 17.926097 -271.560287) (xy 17.87066 -271.566387)
			(xy 17.814926 -271.56435) (xy 17.760083 -271.55422) (xy 17.707299 -271.536213) (xy 17.657699 -271.510712)
			(xy 17.612341 -271.478261) (xy 17.572192 -271.439552) (xy 17.538106 -271.395409) (xy 17.51081 -271.346774)
			(xy 17.490887 -271.294683) (xy 17.478761 -271.240246) (xy 17.47469 -271.184624) (xy 1.420114 -271.184624)
			(xy 1.420114 -271.453102) (xy 1.420655 -271.463461) (xy 1.428912 -271.482469) (xy 1.436116 -271.489932)
			(xy 1.489964 -271.540732) (xy 1.493266 -271.543526) (xy 1.500811 -271.548949) (xy 1.518518 -271.554532)
			(xy 1.52781 -271.554448) (xy 1.528064 -271.554448) (xy 1.551432 -271.553686) (xy 1.578683 -271.554172)
			(xy 1.632631 -271.561928) (xy 1.684926 -271.577283) (xy 1.734503 -271.599925) (xy 1.780353 -271.629391)
			(xy 1.821544 -271.665082) (xy 1.857235 -271.706273) (xy 1.886701 -271.752123) (xy 1.909343 -271.8017)
			(xy 1.924698 -271.853995) (xy 1.932454 -271.907943) (xy 1.932454 -271.962445) (xy 1.924698 -272.016393)
			(xy 1.909343 -272.068688) (xy 1.886701 -272.118265) (xy 1.857235 -272.164115) (xy 1.821544 -272.205306)
			(xy 1.780353 -272.240997) (xy 1.734503 -272.270463) (xy 1.684926 -272.293105) (xy 1.632631 -272.30846)
			(xy 1.578683 -272.316216) (xy 1.551432 -272.316702) (xy 1.528318 -272.31594) (xy 1.52781 -272.31594)
			(xy 1.518509 -272.315787) (xy 1.500788 -272.321389) (xy 1.493266 -272.326862) (xy 1.489964 -272.329656)
			(xy 1.472733 -272.345912) (xy 11.635738 -272.345912) (xy 11.639809 -272.29029) (xy 11.651935 -272.235853)
			(xy 11.671858 -272.183762) (xy 11.699154 -272.135127) (xy 11.73324 -272.090984) (xy 11.773389 -272.052275)
			(xy 11.818747 -272.019824) (xy 11.868347 -271.994323) (xy 11.921131 -271.976316) (xy 11.975974 -271.966186)
			(xy 12.031708 -271.964149) (xy 12.087145 -271.970249) (xy 12.141102 -271.984355) (xy 12.192431 -272.006167)
			(xy 12.240037 -272.035221) (xy 12.282905 -272.070896) (xy 12.320122 -272.112433) (xy 12.350895 -272.158946)
			(xy 12.374567 -272.209443) (xy 12.390635 -272.26285) (xy 12.398755 -272.318026) (xy 12.399264 -272.345912)
			(xy 12.398755 -272.373798) (xy 12.390635 -272.428974) (xy 12.374894 -272.481294) (xy 13.765528 -272.481294)
			(xy 13.769599 -272.425672) (xy 13.781725 -272.371235) (xy 13.801648 -272.319144) (xy 13.828944 -272.270509)
			(xy 13.86303 -272.226366) (xy 13.903179 -272.187657) (xy 13.948537 -272.155206) (xy 13.998137 -272.129705)
			(xy 14.050921 -272.111698) (xy 14.105764 -272.101568) (xy 14.161498 -272.099531) (xy 14.216935 -272.105631)
			(xy 14.270892 -272.119737) (xy 14.322221 -272.141549) (xy 14.369827 -272.170603) (xy 14.405901 -272.200624)
			(xy 17.412968 -272.200624) (xy 17.417039 -272.145002) (xy 17.429165 -272.090565) (xy 17.449088 -272.038474)
			(xy 17.476384 -271.989839) (xy 17.51047 -271.945696) (xy 17.550619 -271.906987) (xy 17.595977 -271.874536)
			(xy 17.645577 -271.849035) (xy 17.698361 -271.831028) (xy 17.753204 -271.820898) (xy 17.808938 -271.818861)
			(xy 17.864375 -271.824961) (xy 17.918332 -271.839067) (xy 17.969661 -271.860879) (xy 18.017267 -271.889933)
			(xy 18.060135 -271.925608) (xy 18.097352 -271.967145) (xy 18.128125 -272.013658) (xy 18.151797 -272.064155)
			(xy 18.167865 -272.117562) (xy 18.175985 -272.172738) (xy 18.176494 -272.200624) (xy 18.175985 -272.22851)
			(xy 18.167865 -272.283686) (xy 18.151797 -272.337093) (xy 18.128125 -272.38759) (xy 18.097352 -272.434103)
			(xy 18.060135 -272.47564) (xy 18.017267 -272.511315) (xy 17.969661 -272.540369) (xy 17.918332 -272.562181)
			(xy 17.864375 -272.576287) (xy 17.808938 -272.582387) (xy 17.753204 -272.58035) (xy 17.698361 -272.57022)
			(xy 17.645577 -272.552213) (xy 17.595977 -272.526712) (xy 17.550619 -272.494261) (xy 17.51047 -272.455552)
			(xy 17.476384 -272.411409) (xy 17.449088 -272.362774) (xy 17.429165 -272.310683) (xy 17.417039 -272.256246)
			(xy 17.412968 -272.200624) (xy 14.405901 -272.200624) (xy 14.412695 -272.206278) (xy 14.449912 -272.247815)
			(xy 14.480685 -272.294328) (xy 14.504357 -272.344825) (xy 14.520425 -272.398232) (xy 14.528545 -272.453408)
			(xy 14.529054 -272.481294) (xy 14.528545 -272.50918) (xy 14.520425 -272.564356) (xy 14.504357 -272.617763)
			(xy 14.480685 -272.66826) (xy 14.449912 -272.714773) (xy 14.412695 -272.75631) (xy 14.369827 -272.791985)
			(xy 14.322221 -272.821039) (xy 14.270892 -272.842851) (xy 14.216935 -272.856957) (xy 14.161498 -272.863057)
			(xy 14.105764 -272.86102) (xy 14.050921 -272.85089) (xy 13.998137 -272.832883) (xy 13.948537 -272.807382)
			(xy 13.903179 -272.774931) (xy 13.86303 -272.736222) (xy 13.828944 -272.692079) (xy 13.801648 -272.643444)
			(xy 13.781725 -272.591353) (xy 13.769599 -272.536916) (xy 13.765528 -272.481294) (xy 12.374894 -272.481294)
			(xy 12.374567 -272.482381) (xy 12.350895 -272.532878) (xy 12.320122 -272.579391) (xy 12.282905 -272.620928)
			(xy 12.240037 -272.656603) (xy 12.192431 -272.685657) (xy 12.141102 -272.707469) (xy 12.087145 -272.721575)
			(xy 12.031708 -272.727675) (xy 11.975974 -272.725638) (xy 11.921131 -272.715508) (xy 11.868347 -272.697501)
			(xy 11.818747 -272.672) (xy 11.773389 -272.639549) (xy 11.73324 -272.60084) (xy 11.699154 -272.556697)
			(xy 11.671858 -272.508062) (xy 11.651935 -272.455971) (xy 11.639809 -272.401534) (xy 11.635738 -272.345912)
			(xy 1.472733 -272.345912) (xy 1.436116 -272.380456) (xy 1.42889 -272.387904) (xy 1.420639 -272.406921)
			(xy 1.420114 -272.417286) (xy 1.420114 -272.820638) (xy 1.420693 -272.831176) (xy 1.429213 -272.850462)
			(xy 1.436624 -272.857976) (xy 1.491996 -272.908522) (xy 1.500171 -272.915299) (xy 1.520249 -272.922138)
			(xy 1.530858 -272.92173) (xy 1.564894 -272.920206) (xy 1.592145 -272.920692) (xy 1.646093 -272.928448)
			(xy 1.698388 -272.943803) (xy 1.747965 -272.966445) (xy 1.793815 -272.995911) (xy 1.835006 -273.031602)
			(xy 1.870697 -273.072793) (xy 1.900163 -273.118643) (xy 1.922805 -273.16822) (xy 1.93816 -273.220515)
			(xy 1.941774 -273.245651) (xy 8.10893 -273.245651) (xy 8.10893 -273.191149) (xy 8.116686 -273.137201)
			(xy 8.132041 -273.084907) (xy 8.154682 -273.03533) (xy 8.184148 -272.98948) (xy 8.21984 -272.94829)
			(xy 8.26103 -272.912598) (xy 8.30688 -272.883132) (xy 8.356457 -272.860491) (xy 8.408751 -272.845136)
			(xy 8.462699 -272.83738) (xy 8.48995 -272.836894) (xy 8.517319 -272.837391) (xy 8.571497 -272.845201)
			(xy 8.624 -272.860683) (xy 8.673747 -272.883518) (xy 8.719715 -272.913236) (xy 8.740648 -272.930874)
			(xy 8.740902 -272.931128) (xy 8.747982 -272.936725) (xy 8.764904 -272.942964) (xy 8.773922 -272.94332)
			(xy 8.840978 -272.94332) (xy 8.849993 -272.942948) (xy 8.86691 -272.93671) (xy 8.873998 -272.931128)
			(xy 8.873998 -272.930874) (xy 8.874252 -272.930874) (xy 8.895188 -272.91324) (xy 8.94116 -272.883528)
			(xy 8.990907 -272.860692) (xy 9.043406 -272.845199) (xy 9.097581 -272.837369) (xy 9.12495 -272.836894)
			(xy 9.152201 -272.837376) (xy 9.206149 -272.845132) (xy 9.258444 -272.860488) (xy 9.308022 -272.883129)
			(xy 9.353873 -272.912595) (xy 9.360311 -272.918174) (xy 15.261334 -272.918174) (xy 15.265405 -272.862552)
			(xy 15.277531 -272.808115) (xy 15.297454 -272.756024) (xy 15.32475 -272.707389) (xy 15.358836 -272.663246)
			(xy 15.398985 -272.624537) (xy 15.444343 -272.592086) (xy 15.493943 -272.566585) (xy 15.546727 -272.548578)
			(xy 15.60157 -272.538448) (xy 15.657304 -272.536411) (xy 15.712741 -272.542511) (xy 15.766698 -272.556617)
			(xy 15.818027 -272.578429) (xy 15.865633 -272.607483) (xy 15.908501 -272.643158) (xy 15.945718 -272.684695)
			(xy 15.976491 -272.731208) (xy 16.000163 -272.781705) (xy 16.016231 -272.835112) (xy 16.024351 -272.890288)
			(xy 16.02486 -272.918174) (xy 16.024351 -272.94606) (xy 16.016231 -273.001236) (xy 16.000163 -273.054643)
			(xy 15.976491 -273.10514) (xy 15.945718 -273.151653) (xy 15.908501 -273.19319) (xy 15.880342 -273.216624)
			(xy 17.412968 -273.216624) (xy 17.417039 -273.161002) (xy 17.429165 -273.106565) (xy 17.449088 -273.054474)
			(xy 17.476384 -273.005839) (xy 17.51047 -272.961696) (xy 17.550619 -272.922987) (xy 17.595977 -272.890536)
			(xy 17.645577 -272.865035) (xy 17.698361 -272.847028) (xy 17.753204 -272.836898) (xy 17.808938 -272.834861)
			(xy 17.864375 -272.840961) (xy 17.918332 -272.855067) (xy 17.969661 -272.876879) (xy 18.017267 -272.905933)
			(xy 18.060135 -272.941608) (xy 18.097352 -272.983145) (xy 18.128125 -273.029658) (xy 18.151797 -273.080155)
			(xy 18.167865 -273.133562) (xy 18.175985 -273.188738) (xy 18.176494 -273.216624) (xy 18.175985 -273.24451)
			(xy 18.167865 -273.299686) (xy 18.151797 -273.353093) (xy 18.128125 -273.40359) (xy 18.097352 -273.450103)
			(xy 18.060135 -273.49164) (xy 18.017267 -273.527315) (xy 17.969661 -273.556369) (xy 17.918332 -273.578181)
			(xy 17.864375 -273.592287) (xy 17.808938 -273.598387) (xy 17.753204 -273.59635) (xy 17.698361 -273.58622)
			(xy 17.645577 -273.568213) (xy 17.595977 -273.542712) (xy 17.550619 -273.510261) (xy 17.51047 -273.471552)
			(xy 17.476384 -273.427409) (xy 17.449088 -273.378774) (xy 17.429165 -273.326683) (xy 17.417039 -273.272246)
			(xy 17.412968 -273.216624) (xy 15.880342 -273.216624) (xy 15.865633 -273.228865) (xy 15.818027 -273.257919)
			(xy 15.766698 -273.279731) (xy 15.712741 -273.293837) (xy 15.657304 -273.299937) (xy 15.60157 -273.2979)
			(xy 15.546727 -273.28777) (xy 15.493943 -273.269763) (xy 15.444343 -273.244262) (xy 15.398985 -273.211811)
			(xy 15.358836 -273.173102) (xy 15.32475 -273.128959) (xy 15.297454 -273.080324) (xy 15.277531 -273.028233)
			(xy 15.265405 -272.973796) (xy 15.261334 -272.918174) (xy 9.360311 -272.918174) (xy 9.395063 -272.948287)
			(xy 9.430755 -272.989477) (xy 9.460221 -273.035328) (xy 9.482862 -273.084906) (xy 9.498218 -273.137201)
			(xy 9.505974 -273.191149) (xy 9.505974 -273.245651) (xy 9.498218 -273.299599) (xy 9.482862 -273.351894)
			(xy 9.460221 -273.401472) (xy 9.430755 -273.447323) (xy 9.395063 -273.488513) (xy 9.353873 -273.524205)
			(xy 9.308022 -273.553671) (xy 9.258444 -273.576312) (xy 9.206149 -273.591668) (xy 9.152201 -273.599424)
			(xy 9.12495 -273.59991) (xy 9.097581 -273.599412) (xy 9.043403 -273.591602) (xy 8.990901 -273.57612)
			(xy 8.941153 -273.553285) (xy 8.895185 -273.523568) (xy 8.874252 -273.50593) (xy 8.873998 -273.505676)
			(xy 8.866918 -273.50008) (xy 8.849996 -273.49384) (xy 8.840978 -273.493484) (xy 8.773922 -273.493484)
			(xy 8.764907 -273.493855) (xy 8.74799 -273.500093) (xy 8.740902 -273.505676) (xy 8.740902 -273.50593)
			(xy 8.740648 -273.50593) (xy 8.719713 -273.523565) (xy 8.67374 -273.553276) (xy 8.623993 -273.576112)
			(xy 8.571494 -273.591605) (xy 8.517319 -273.599435) (xy 8.48995 -273.59991) (xy 8.462699 -273.59942)
			(xy 8.408751 -273.591664) (xy 8.356457 -273.576309) (xy 8.30688 -273.553668) (xy 8.26103 -273.524202)
			(xy 8.21984 -273.48851) (xy 8.184148 -273.44732) (xy 8.154682 -273.40147) (xy 8.132041 -273.351893)
			(xy 8.116686 -273.299599) (xy 8.10893 -273.245651) (xy 1.941774 -273.245651) (xy 1.945916 -273.274463)
			(xy 1.945916 -273.328965) (xy 1.93816 -273.382913) (xy 1.922805 -273.435208) (xy 1.900163 -273.484785)
			(xy 1.870697 -273.530635) (xy 1.835006 -273.571826) (xy 1.793815 -273.607517) (xy 1.747965 -273.636983)
			(xy 1.698388 -273.659625) (xy 1.646093 -273.67498) (xy 1.592145 -273.682736) (xy 1.564894 -273.683222)
			(xy 1.530858 -273.681698) (xy 1.52023 -273.681184) (xy 1.500097 -273.68801) (xy 1.491996 -273.694906)
			(xy 1.436624 -273.745452) (xy 1.429171 -273.752942) (xy 1.42062 -273.772238) (xy 1.420114 -273.78279)
			(xy 1.420114 -274.168616) (xy 1.420576 -274.178863) (xy 1.428566 -274.197735) (xy 1.435608 -274.205192)
			(xy 1.487678 -274.255738) (xy 1.491455 -274.259292) (xy 1.500159 -274.264928) (xy 1.50495 -274.266914)
			(xy 1.514602 -274.27047) (xy 1.525016 -274.270216) (xy 1.537462 -274.269962) (xy 1.564713 -274.270448)
			(xy 1.618661 -274.278205) (xy 1.670955 -274.29356) (xy 1.720532 -274.316201) (xy 1.766382 -274.345668)
			(xy 1.807572 -274.381359) (xy 1.843264 -274.422549) (xy 1.87273 -274.4684) (xy 1.895371 -274.517977)
			(xy 1.910726 -274.570271) (xy 1.918482 -274.624219) (xy 1.918482 -274.678721) (xy 1.910726 -274.732669)
			(xy 1.895371 -274.784963) (xy 1.87273 -274.83454) (xy 1.843264 -274.880391) (xy 1.807572 -274.921581)
			(xy 1.766382 -274.957272) (xy 1.720532 -274.986739) (xy 1.69103 -275.000212) (xy 4.903216 -275.000212)
			(xy 4.903685 -274.972842) (xy 4.911502 -274.918663) (xy 4.92699 -274.866159) (xy 4.949831 -274.816413)
			(xy 4.979555 -274.770446) (xy 4.997196 -274.749514) (xy 4.99745 -274.74926) (xy 5.003024 -274.742165)
			(xy 5.009277 -274.725254) (xy 5.009642 -274.71624) (xy 5.009642 -274.649184) (xy 5.009305 -274.640165)
			(xy 5.003045 -274.623247) (xy 4.99745 -274.616164) (xy 4.997196 -274.616164) (xy 4.997196 -274.61591)
			(xy 4.979548 -274.594986) (xy 4.949837 -274.549011) (xy 4.927003 -274.499261) (xy 4.911514 -274.446759)
			(xy 4.903689 -274.392582) (xy 4.903216 -274.365212) (xy 4.903667 -274.337958) (xy 4.911423 -274.284006)
			(xy 4.926778 -274.231706) (xy 4.949421 -274.182124) (xy 4.97889 -274.13627) (xy 5.014585 -274.095077)
			(xy 5.05578 -274.059383) (xy 5.101635 -274.029915) (xy 5.151217 -274.007274) (xy 5.203517 -273.99192)
			(xy 5.25747 -273.984166) (xy 5.284724 -273.983704) (xy 5.313464 -273.984212) (xy 5.370292 -273.992838)
			(xy 5.425183 -274.009892) (xy 5.476894 -274.034987) (xy 5.524256 -274.067556) (xy 5.545582 -274.086828)
			(xy 5.55244 -274.093432) (xy 5.561584 -274.096988) (xy 5.566047 -274.098618) (xy 5.575377 -274.100405)
			(xy 5.580126 -274.100544) (xy 5.649722 -274.100544) (xy 5.654476 -274.100456) (xy 5.663812 -274.098659)
			(xy 5.668264 -274.096988) (xy 5.677408 -274.093432) (xy 5.684266 -274.086828) (xy 5.705593 -274.067558)
			(xy 5.752956 -274.034993) (xy 5.804667 -274.009902) (xy 5.859558 -273.992852) (xy 5.916385 -273.98423)
			(xy 5.973863 -273.98423) (xy 6.03069 -273.992852) (xy 6.085581 -274.009902) (xy 6.137292 -274.034993)
			(xy 6.184655 -274.067558) (xy 6.205982 -274.086828) (xy 6.21284 -274.093432) (xy 6.221984 -274.096988)
			(xy 6.226447 -274.098618) (xy 6.235777 -274.100405) (xy 6.240526 -274.100544) (xy 6.310122 -274.100544)
			(xy 6.314876 -274.100456) (xy 6.324212 -274.098659) (xy 6.328664 -274.096988) (xy 6.337808 -274.093432)
			(xy 6.344666 -274.086828) (xy 6.365993 -274.067558) (xy 6.413356 -274.034993) (xy 6.465067 -274.009902)
			(xy 6.519958 -273.992852) (xy 6.576785 -273.98423) (xy 6.634263 -273.98423) (xy 6.69109 -273.992852)
			(xy 6.745981 -274.009902) (xy 6.797692 -274.034993) (xy 6.845055 -274.067558) (xy 6.866382 -274.086828)
			(xy 6.87324 -274.093432) (xy 6.882384 -274.096988) (xy 6.886847 -274.098618) (xy 6.896177 -274.100405)
			(xy 6.900926 -274.100544) (xy 6.970522 -274.100544) (xy 6.975276 -274.100456) (xy 6.984612 -274.098659)
			(xy 6.989064 -274.096988) (xy 6.998208 -274.093432) (xy 7.005066 -274.086828) (xy 7.026382 -274.067544)
			(xy 7.073747 -274.03498) (xy 7.125462 -274.00989) (xy 7.180355 -273.992843) (xy 7.237184 -273.984223)
			(xy 7.265924 -273.983704) (xy 7.293176 -273.984156) (xy 7.347126 -273.991916) (xy 7.399422 -274.007274)
			(xy 7.449 -274.029919) (xy 7.494851 -274.059389) (xy 7.521238 -274.082256) (xy 10.07567 -274.082256)
			(xy 10.079741 -274.026634) (xy 10.091867 -273.972197) (xy 10.11179 -273.920106) (xy 10.139086 -273.871471)
			(xy 10.173172 -273.827328) (xy 10.213321 -273.788619) (xy 10.258679 -273.756168) (xy 10.308279 -273.730667)
			(xy 10.361063 -273.71266) (xy 10.415906 -273.70253) (xy 10.47164 -273.700493) (xy 10.527077 -273.706593)
			(xy 10.581034 -273.720699) (xy 10.632363 -273.742511) (xy 10.679969 -273.771565) (xy 10.722837 -273.80724)
			(xy 10.760054 -273.848777) (xy 10.790827 -273.89529) (xy 10.814499 -273.945787) (xy 10.830567 -273.999194)
			(xy 10.838687 -274.05437) (xy 10.839196 -274.082256) (xy 10.838687 -274.110142) (xy 10.830567 -274.165318)
			(xy 10.814499 -274.218725) (xy 10.807983 -274.232624) (xy 15.393668 -274.232624) (xy 15.397739 -274.177002)
			(xy 15.409865 -274.122565) (xy 15.429788 -274.070474) (xy 15.457084 -274.021839) (xy 15.49117 -273.977696)
			(xy 15.531319 -273.938987) (xy 15.576677 -273.906536) (xy 15.626277 -273.881035) (xy 15.679061 -273.863028)
			(xy 15.733904 -273.852898) (xy 15.789638 -273.850861) (xy 15.845075 -273.856961) (xy 15.899032 -273.871067)
			(xy 15.950361 -273.892879) (xy 15.997967 -273.921933) (xy 16.040835 -273.957608) (xy 16.078052 -273.999145)
			(xy 16.108825 -274.045658) (xy 16.132497 -274.096155) (xy 16.148565 -274.149562) (xy 16.156685 -274.204738)
			(xy 16.157194 -274.232624) (xy 17.412968 -274.232624) (xy 17.417039 -274.177002) (xy 17.429165 -274.122565)
			(xy 17.449088 -274.070474) (xy 17.476384 -274.021839) (xy 17.51047 -273.977696) (xy 17.550619 -273.938987)
			(xy 17.595977 -273.906536) (xy 17.645577 -273.881035) (xy 17.698361 -273.863028) (xy 17.753204 -273.852898)
			(xy 17.808938 -273.850861) (xy 17.864375 -273.856961) (xy 17.918332 -273.871067) (xy 17.969661 -273.892879)
			(xy 18.017267 -273.921933) (xy 18.060135 -273.957608) (xy 18.097352 -273.999145) (xy 18.128125 -274.045658)
			(xy 18.151797 -274.096155) (xy 18.167865 -274.149562) (xy 18.175985 -274.204738) (xy 18.176494 -274.232624)
			(xy 18.175985 -274.26051) (xy 18.167865 -274.315686) (xy 18.151797 -274.369093) (xy 18.128125 -274.41959)
			(xy 18.097352 -274.466103) (xy 18.060135 -274.50764) (xy 18.017267 -274.543315) (xy 17.969661 -274.572369)
			(xy 17.918332 -274.594181) (xy 17.864375 -274.608287) (xy 17.808938 -274.614387) (xy 17.753204 -274.61235)
			(xy 17.698361 -274.60222) (xy 17.645577 -274.584213) (xy 17.595977 -274.558712) (xy 17.550619 -274.526261)
			(xy 17.51047 -274.487552) (xy 17.476384 -274.443409) (xy 17.449088 -274.394774) (xy 17.429165 -274.342683)
			(xy 17.417039 -274.288246) (xy 17.412968 -274.232624) (xy 16.157194 -274.232624) (xy 16.156685 -274.26051)
			(xy 16.148565 -274.315686) (xy 16.132497 -274.369093) (xy 16.108825 -274.41959) (xy 16.078052 -274.466103)
			(xy 16.040835 -274.50764) (xy 15.997967 -274.543315) (xy 15.950361 -274.572369) (xy 15.899032 -274.594181)
			(xy 15.845075 -274.608287) (xy 15.789638 -274.614387) (xy 15.733904 -274.61235) (xy 15.679061 -274.60222)
			(xy 15.626277 -274.584213) (xy 15.576677 -274.558712) (xy 15.531319 -274.526261) (xy 15.49117 -274.487552)
			(xy 15.457084 -274.443409) (xy 15.429788 -274.394774) (xy 15.409865 -274.342683) (xy 15.397739 -274.288246)
			(xy 15.393668 -274.232624) (xy 10.807983 -274.232624) (xy 10.790827 -274.269222) (xy 10.760054 -274.315735)
			(xy 10.722837 -274.357272) (xy 10.679969 -274.392947) (xy 10.632363 -274.422001) (xy 10.581034 -274.443813)
			(xy 10.527077 -274.457919) (xy 10.47164 -274.464019) (xy 10.415906 -274.461982) (xy 10.361063 -274.451852)
			(xy 10.308279 -274.433845) (xy 10.258679 -274.408344) (xy 10.213321 -274.375893) (xy 10.173172 -274.337184)
			(xy 10.139086 -274.293041) (xy 10.11179 -274.244406) (xy 10.091867 -274.192315) (xy 10.079741 -274.137878)
			(xy 10.07567 -274.082256) (xy 7.521238 -274.082256) (xy 7.536041 -274.095084) (xy 7.571733 -274.136278)
			(xy 7.601198 -274.182131) (xy 7.623838 -274.231712) (xy 7.639192 -274.284009) (xy 7.646947 -274.33796)
			(xy 7.647432 -274.365212) (xy 7.64699 -274.392583) (xy 7.639169 -274.446764) (xy 7.623675 -274.499268)
			(xy 7.600827 -274.549015) (xy 7.571097 -274.59498) (xy 7.553452 -274.61591) (xy 7.553198 -274.616164)
			(xy 7.54762 -274.623257) (xy 7.541368 -274.640169) (xy 7.541006 -274.649184) (xy 7.541006 -274.71624)
			(xy 7.541343 -274.725259) (xy 7.547604 -274.742176) (xy 7.553198 -274.74926) (xy 7.553452 -274.74926)
			(xy 7.553452 -274.749514) (xy 7.571057 -274.770474) (xy 7.600775 -274.816438) (xy 7.623619 -274.866179)
			(xy 7.639118 -274.918673) (xy 7.640258 -274.926552) (xy 12.410946 -274.926552) (xy 12.415017 -274.87093)
			(xy 12.427143 -274.816493) (xy 12.447066 -274.764402) (xy 12.474362 -274.715767) (xy 12.508448 -274.671624)
			(xy 12.548597 -274.632915) (xy 12.593955 -274.600464) (xy 12.643555 -274.574963) (xy 12.696339 -274.556956)
			(xy 12.751182 -274.546826) (xy 12.806916 -274.544789) (xy 12.862353 -274.550889) (xy 12.91631 -274.564995)
			(xy 12.967639 -274.586807) (xy 13.015245 -274.615861) (xy 13.058113 -274.651536) (xy 13.09533 -274.693073)
			(xy 13.126103 -274.739586) (xy 13.149775 -274.790083) (xy 13.165843 -274.84349) (xy 13.173963 -274.898666)
			(xy 13.174263 -274.915122) (xy 13.600428 -274.915122) (xy 13.604499 -274.8595) (xy 13.616625 -274.805063)
			(xy 13.636548 -274.752972) (xy 13.663844 -274.704337) (xy 13.69793 -274.660194) (xy 13.738079 -274.621485)
			(xy 13.783437 -274.589034) (xy 13.833037 -274.563533) (xy 13.885821 -274.545526) (xy 13.940664 -274.535396)
			(xy 13.996398 -274.533359) (xy 14.051835 -274.539459) (xy 14.105792 -274.553565) (xy 14.157121 -274.575377)
			(xy 14.204727 -274.604431) (xy 14.247595 -274.640106) (xy 14.284812 -274.681643) (xy 14.315585 -274.728156)
			(xy 14.339257 -274.778653) (xy 14.355325 -274.83206) (xy 14.363445 -274.887236) (xy 14.363954 -274.915122)
			(xy 14.363445 -274.943008) (xy 14.355325 -274.998184) (xy 14.339257 -275.051591) (xy 14.315585 -275.102088)
			(xy 14.284812 -275.148601) (xy 14.247595 -275.190138) (xy 14.204727 -275.225813) (xy 14.157121 -275.254867)
			(xy 14.105792 -275.276679) (xy 14.051835 -275.290785) (xy 13.996398 -275.296885) (xy 13.940664 -275.294848)
			(xy 13.885821 -275.284718) (xy 13.833037 -275.266711) (xy 13.783437 -275.24121) (xy 13.738079 -275.208759)
			(xy 13.69793 -275.17005) (xy 13.663844 -275.125907) (xy 13.636548 -275.077272) (xy 13.616625 -275.025181)
			(xy 13.604499 -274.970744) (xy 13.600428 -274.915122) (xy 13.174263 -274.915122) (xy 13.174472 -274.926552)
			(xy 13.173963 -274.954438) (xy 13.165843 -275.009614) (xy 13.149775 -275.063021) (xy 13.126103 -275.113518)
			(xy 13.09533 -275.160031) (xy 13.058113 -275.201568) (xy 13.015245 -275.237243) (xy 12.967639 -275.266297)
			(xy 12.91631 -275.288109) (xy 12.862353 -275.302215) (xy 12.806916 -275.308315) (xy 12.751182 -275.306278)
			(xy 12.696339 -275.296148) (xy 12.643555 -275.278141) (xy 12.593955 -275.25264) (xy 12.548597 -275.220189)
			(xy 12.508448 -275.18148) (xy 12.474362 -275.137337) (xy 12.447066 -275.088702) (xy 12.427143 -275.036611)
			(xy 12.415017 -274.982174) (xy 12.410946 -274.926552) (xy 7.640258 -274.926552) (xy 7.646954 -274.972845)
			(xy 7.647432 -275.000212) (xy 7.646933 -275.027462) (xy 7.639176 -275.081408) (xy 7.62382 -275.133702)
			(xy 7.60118 -275.183277) (xy 7.571714 -275.229126) (xy 7.536024 -275.270316) (xy 7.494836 -275.306007)
			(xy 7.448988 -275.335474) (xy 7.399413 -275.358116) (xy 7.34712 -275.373473) (xy 7.293174 -275.381233)
			(xy 7.265924 -275.38172) (xy 7.237186 -275.381176) (xy 7.18036 -275.372558) (xy 7.125469 -275.355512)
			(xy 7.073757 -275.330425) (xy 7.026394 -275.297865) (xy 7.005066 -275.278596) (xy 6.998208 -275.271992)
			(xy 6.989064 -275.268436) (xy 6.984597 -275.266819) (xy 6.97527 -275.265023) (xy 6.970522 -275.26488)
			(xy 6.900926 -275.26488) (xy 6.896173 -275.264987) (xy 6.886837 -275.266772) (xy 6.882384 -275.268436)
			(xy 6.87324 -275.271992) (xy 6.866382 -275.278596) (xy 6.845055 -275.297866) (xy 6.797692 -275.330431)
			(xy 6.745981 -275.355522) (xy 6.69109 -275.372572) (xy 6.634263 -275.381194) (xy 6.576785 -275.381194)
			(xy 6.519958 -275.372572) (xy 6.465067 -275.355522) (xy 6.413356 -275.330431) (xy 6.365993 -275.297866)
			(xy 6.344666 -275.278596) (xy 6.337808 -275.271992) (xy 6.328664 -275.268436) (xy 6.324197 -275.266819)
			(xy 6.31487 -275.265023) (xy 6.310122 -275.26488) (xy 6.240526 -275.26488) (xy 6.235773 -275.264987)
			(xy 6.226437 -275.266772) (xy 6.221984 -275.268436) (xy 6.21284 -275.271992) (xy 6.205982 -275.278596)
			(xy 6.184655 -275.297866) (xy 6.137292 -275.330431) (xy 6.085581 -275.355522) (xy 6.03069 -275.372572)
			(xy 5.973863 -275.381194) (xy 5.916385 -275.381194) (xy 5.859558 -275.372572) (xy 5.804667 -275.355522)
			(xy 5.752956 -275.330431) (xy 5.705593 -275.297866) (xy 5.684266 -275.278596) (xy 5.677408 -275.271992)
			(xy 5.668264 -275.268436) (xy 5.663797 -275.266819) (xy 5.65447 -275.265023) (xy 5.649722 -275.26488)
			(xy 5.580126 -275.26488) (xy 5.575373 -275.264987) (xy 5.566037 -275.266772) (xy 5.561584 -275.268436)
			(xy 5.55244 -275.271992) (xy 5.545582 -275.278596) (xy 5.524235 -275.297844) (xy 5.47688 -275.330416)
			(xy 5.425173 -275.355514) (xy 5.370286 -275.372569) (xy 5.313462 -275.381197) (xy 5.284724 -275.38172)
			(xy 5.257472 -275.381222) (xy 5.203523 -275.373469) (xy 5.151227 -275.358117) (xy 5.101647 -275.335478)
			(xy 5.055795 -275.306013) (xy 5.014602 -275.270323) (xy 4.978908 -275.229134) (xy 4.949439 -275.183284)
			(xy 4.926796 -275.133707) (xy 4.911439 -275.081412) (xy 4.90368 -275.027464) (xy 4.903216 -275.000212)
			(xy 1.69103 -275.000212) (xy 1.670955 -275.00938) (xy 1.618661 -275.024735) (xy 1.564713 -275.032492)
			(xy 1.537462 -275.032978) (xy 1.525016 -275.032724) (xy 1.514602 -275.03247) (xy 1.50495 -275.036026)
			(xy 1.500169 -275.038032) (xy 1.491462 -275.043658) (xy 1.487678 -275.047202) (xy 1.435608 -275.097748)
			(xy 1.428551 -275.105197) (xy 1.420549 -275.124072) (xy 1.420114 -275.134324) (xy 1.420114 -275.49983)
			(xy 1.420622 -275.506942) (xy 1.422052 -275.514802) (xy 1.429041 -275.529156) (xy 1.434338 -275.535136)
			(xy 1.435608 -275.536406) (xy 1.488186 -275.587206) (xy 1.495877 -275.593998) (xy 1.515011 -275.601353)
			(xy 1.52527 -275.60143) (xy 1.53797 -275.601176) (xy 1.565221 -275.601662) (xy 1.619169 -275.609418)
			(xy 1.671464 -275.624773) (xy 1.721041 -275.647415) (xy 1.766891 -275.676881) (xy 1.808082 -275.712572)
			(xy 1.843773 -275.753763) (xy 1.873239 -275.799613) (xy 1.895881 -275.84919) (xy 1.911236 -275.901485)
			(xy 1.917724 -275.946616) (xy 10.886692 -275.946616) (xy 10.890763 -275.890994) (xy 10.902889 -275.836557)
			(xy 10.922812 -275.784466) (xy 10.950108 -275.735831) (xy 10.984194 -275.691688) (xy 11.024343 -275.652979)
			(xy 11.069701 -275.620528) (xy 11.119301 -275.595027) (xy 11.172085 -275.57702) (xy 11.226928 -275.56689)
			(xy 11.282662 -275.564853) (xy 11.338099 -275.570953) (xy 11.392056 -275.585059) (xy 11.443385 -275.606871)
			(xy 11.490991 -275.635925) (xy 11.533859 -275.6716) (xy 11.571076 -275.713137) (xy 11.601849 -275.75965)
			(xy 11.625521 -275.810147) (xy 11.641589 -275.863554) (xy 11.649709 -275.91873) (xy 11.650218 -275.946616)
			(xy 11.649709 -275.974502) (xy 11.641589 -276.029678) (xy 11.625521 -276.083085) (xy 11.620791 -276.093174)
			(xy 12.410946 -276.093174) (xy 12.415017 -276.037552) (xy 12.427143 -275.983115) (xy 12.447066 -275.931024)
			(xy 12.474362 -275.882389) (xy 12.508448 -275.838246) (xy 12.548597 -275.799537) (xy 12.593955 -275.767086)
			(xy 12.643555 -275.741585) (xy 12.696339 -275.723578) (xy 12.751182 -275.713448) (xy 12.806916 -275.711411)
			(xy 12.862353 -275.717511) (xy 12.91631 -275.731617) (xy 12.967639 -275.753429) (xy 13.015245 -275.782483)
			(xy 13.058113 -275.818158) (xy 13.09533 -275.859695) (xy 13.126103 -275.906208) (xy 13.149775 -275.956705)
			(xy 13.165843 -276.010112) (xy 13.173963 -276.065288) (xy 13.174268 -276.081998) (xy 13.588998 -276.081998)
			(xy 13.593069 -276.026376) (xy 13.605195 -275.971939) (xy 13.625118 -275.919848) (xy 13.652414 -275.871213)
			(xy 13.6865 -275.82707) (xy 13.726649 -275.788361) (xy 13.772007 -275.75591) (xy 13.821607 -275.730409)
			(xy 13.874391 -275.712402) (xy 13.929234 -275.702272) (xy 13.984968 -275.700235) (xy 14.040405 -275.706335)
			(xy 14.094362 -275.720441) (xy 14.145691 -275.742253) (xy 14.193297 -275.771307) (xy 14.236165 -275.806982)
			(xy 14.273382 -275.848519) (xy 14.304155 -275.895032) (xy 14.327827 -275.945529) (xy 14.343895 -275.998936)
			(xy 14.352015 -276.054112) (xy 14.352524 -276.081998) (xy 14.352015 -276.109884) (xy 14.343895 -276.16506)
			(xy 14.327827 -276.218467) (xy 14.30619 -276.264624) (xy 15.394178 -276.264624) (xy 15.394684 -276.235706)
			(xy 15.403411 -276.178533) (xy 15.42067 -276.123333) (xy 15.446064 -276.07137) (xy 15.479011 -276.023837)
			(xy 15.518756 -275.981822) (xy 15.541244 -275.963634) (xy 15.549993 -275.95606) (xy 15.560182 -275.93531)
			(xy 15.560802 -275.923756) (xy 15.560802 -275.843492) (xy 15.560235 -275.831924) (xy 15.550038 -275.811153)
			(xy 15.541244 -275.803614) (xy 15.518776 -275.785404) (xy 15.479038 -275.743389) (xy 15.446096 -275.695859)
			(xy 15.420705 -275.643901) (xy 15.403445 -275.588706) (xy 15.394714 -275.531539) (xy 15.394178 -275.502624)
			(xy 15.394664 -275.475373) (xy 15.40242 -275.421425) (xy 15.417775 -275.36913) (xy 15.440417 -275.319553)
			(xy 15.469883 -275.273703) (xy 15.505574 -275.232512) (xy 15.546765 -275.196821) (xy 15.592615 -275.167355)
			(xy 15.642192 -275.144713) (xy 15.694487 -275.129358) (xy 15.748435 -275.121602) (xy 15.802937 -275.121602)
			(xy 15.856885 -275.129358) (xy 15.90918 -275.144713) (xy 15.958757 -275.167355) (xy 16.004607 -275.196821)
			(xy 16.045798 -275.232512) (xy 16.081489 -275.273703) (xy 16.110955 -275.319553) (xy 16.133597 -275.36913)
			(xy 16.148952 -275.421425) (xy 16.156708 -275.475373) (xy 16.157194 -275.502624) (xy 16.156624 -275.531539)
			(xy 16.147906 -275.588708) (xy 16.130658 -275.643906) (xy 16.105276 -275.695868) (xy 16.072342 -275.743403)
			(xy 16.03261 -275.785422) (xy 16.010128 -275.803614) (xy 16.001352 -275.811162) (xy 15.991179 -275.831932)
			(xy 15.99057 -275.843492) (xy 15.99057 -275.923756) (xy 15.991142 -275.935324) (xy 16.001333 -275.956097)
			(xy 16.010128 -275.963634) (xy 16.032634 -275.981799) (xy 16.072366 -276.023825) (xy 16.105302 -276.071365)
			(xy 16.130686 -276.123332) (xy 16.147938 -276.178534) (xy 16.156662 -276.235707) (xy 16.157194 -276.264624)
			(xy 16.156708 -276.291875) (xy 16.148952 -276.345823) (xy 16.133597 -276.398118) (xy 16.121366 -276.424898)
			(xy 36.069028 -276.424898) (xy 36.072988 -276.375844) (xy 36.084765 -276.32806) (xy 36.104056 -276.282784)
			(xy 36.130359 -276.241188) (xy 36.162994 -276.204351) (xy 36.201115 -276.173226) (xy 36.243736 -276.148619)
			(xy 36.289752 -276.131167) (xy 36.337971 -276.121323) (xy 36.387146 -276.119342) (xy 36.436001 -276.125274)
			(xy 36.483272 -276.138966) (xy 36.527734 -276.160064) (xy 36.568237 -276.18802) (xy 36.60373 -276.222112)
			(xy 36.633295 -276.261456) (xy 36.656166 -276.305033) (xy 36.67175 -276.351714) (xy 36.679645 -276.400291)
			(xy 36.68014 -276.424898) (xy 37.018988 -276.424898) (xy 37.022948 -276.375844) (xy 37.034725 -276.32806)
			(xy 37.054016 -276.282784) (xy 37.080319 -276.241188) (xy 37.112954 -276.204351) (xy 37.151075 -276.173226)
			(xy 37.193696 -276.148619) (xy 37.239712 -276.131167) (xy 37.287931 -276.121323) (xy 37.337106 -276.119342)
			(xy 37.385961 -276.125274) (xy 37.433232 -276.138966) (xy 37.477694 -276.160064) (xy 37.518197 -276.18802)
			(xy 37.55369 -276.222112) (xy 37.583255 -276.261456) (xy 37.606126 -276.305033) (xy 37.62171 -276.351714)
			(xy 37.629605 -276.400291) (xy 37.6301 -276.424898) (xy 37.969202 -276.424898) (xy 37.973162 -276.375844)
			(xy 37.984939 -276.32806) (xy 38.00423 -276.282784) (xy 38.030533 -276.241188) (xy 38.063168 -276.204351)
			(xy 38.101289 -276.173226) (xy 38.14391 -276.148619) (xy 38.189926 -276.131167) (xy 38.238145 -276.121323)
			(xy 38.28732 -276.119342) (xy 38.336175 -276.125274) (xy 38.383446 -276.138966) (xy 38.427908 -276.160064)
			(xy 38.468411 -276.18802) (xy 38.503904 -276.222112) (xy 38.533469 -276.261456) (xy 38.55634 -276.305033)
			(xy 38.571924 -276.351714) (xy 38.579819 -276.400291) (xy 38.580314 -276.424898) (xy 38.919162 -276.424898)
			(xy 38.923122 -276.375844) (xy 38.934899 -276.32806) (xy 38.95419 -276.282784) (xy 38.980493 -276.241188)
			(xy 39.013128 -276.204351) (xy 39.051249 -276.173226) (xy 39.09387 -276.148619) (xy 39.139886 -276.131167)
			(xy 39.188105 -276.121323) (xy 39.23728 -276.119342) (xy 39.286135 -276.125274) (xy 39.333406 -276.138966)
			(xy 39.377868 -276.160064) (xy 39.418371 -276.18802) (xy 39.453864 -276.222112) (xy 39.483429 -276.261456)
			(xy 39.5063 -276.305033) (xy 39.521884 -276.351714) (xy 39.529779 -276.400291) (xy 39.530274 -276.424898)
			(xy 39.869122 -276.424898) (xy 39.873082 -276.375844) (xy 39.884859 -276.32806) (xy 39.90415 -276.282784)
			(xy 39.930453 -276.241188) (xy 39.963088 -276.204351) (xy 40.001209 -276.173226) (xy 40.04383 -276.148619)
			(xy 40.089846 -276.131167) (xy 40.138065 -276.121323) (xy 40.18724 -276.119342) (xy 40.236095 -276.125274)
			(xy 40.283366 -276.138966) (xy 40.327828 -276.160064) (xy 40.368331 -276.18802) (xy 40.403824 -276.222112)
			(xy 40.433389 -276.261456) (xy 40.45626 -276.305033) (xy 40.471844 -276.351714) (xy 40.479739 -276.400291)
			(xy 40.480234 -276.424898) (xy 40.819082 -276.424898) (xy 40.823042 -276.375844) (xy 40.834819 -276.32806)
			(xy 40.85411 -276.282784) (xy 40.880413 -276.241188) (xy 40.913048 -276.204351) (xy 40.951169 -276.173226)
			(xy 40.99379 -276.148619) (xy 41.039806 -276.131167) (xy 41.088025 -276.121323) (xy 41.1372 -276.119342)
			(xy 41.186055 -276.125274) (xy 41.233326 -276.138966) (xy 41.277788 -276.160064) (xy 41.318291 -276.18802)
			(xy 41.353784 -276.222112) (xy 41.383349 -276.261456) (xy 41.40622 -276.305033) (xy 41.421804 -276.351714)
			(xy 41.429699 -276.400291) (xy 41.430194 -276.424898) (xy 41.429699 -276.449505) (xy 41.421804 -276.498082)
			(xy 41.40622 -276.544763) (xy 41.383349 -276.58834) (xy 41.353784 -276.627684) (xy 41.318291 -276.661776)
			(xy 41.277788 -276.689732) (xy 41.233326 -276.71083) (xy 41.186055 -276.724522) (xy 41.1372 -276.730454)
			(xy 41.088025 -276.728473) (xy 41.039806 -276.718629) (xy 40.99379 -276.701177) (xy 40.951169 -276.67657)
			(xy 40.913048 -276.645445) (xy 40.880413 -276.608608) (xy 40.85411 -276.567012) (xy 40.834819 -276.521736)
			(xy 40.823042 -276.473952) (xy 40.819082 -276.424898) (xy 40.480234 -276.424898) (xy 40.479739 -276.449505)
			(xy 40.471844 -276.498082) (xy 40.45626 -276.544763) (xy 40.433389 -276.58834) (xy 40.403824 -276.627684)
			(xy 40.368331 -276.661776) (xy 40.327828 -276.689732) (xy 40.283366 -276.71083) (xy 40.236095 -276.724522)
			(xy 40.18724 -276.730454) (xy 40.138065 -276.728473) (xy 40.089846 -276.718629) (xy 40.04383 -276.701177)
			(xy 40.001209 -276.67657) (xy 39.963088 -276.645445) (xy 39.930453 -276.608608) (xy 39.90415 -276.567012)
			(xy 39.884859 -276.521736) (xy 39.873082 -276.473952) (xy 39.869122 -276.424898) (xy 39.530274 -276.424898)
			(xy 39.529779 -276.449505) (xy 39.521884 -276.498082) (xy 39.5063 -276.544763) (xy 39.483429 -276.58834)
			(xy 39.453864 -276.627684) (xy 39.418371 -276.661776) (xy 39.377868 -276.689732) (xy 39.333406 -276.71083)
			(xy 39.286135 -276.724522) (xy 39.23728 -276.730454) (xy 39.188105 -276.728473) (xy 39.139886 -276.718629)
			(xy 39.09387 -276.701177) (xy 39.051249 -276.67657) (xy 39.013128 -276.645445) (xy 38.980493 -276.608608)
			(xy 38.95419 -276.567012) (xy 38.934899 -276.521736) (xy 38.923122 -276.473952) (xy 38.919162 -276.424898)
			(xy 38.580314 -276.424898) (xy 38.579819 -276.449505) (xy 38.571924 -276.498082) (xy 38.55634 -276.544763)
			(xy 38.533469 -276.58834) (xy 38.503904 -276.627684) (xy 38.468411 -276.661776) (xy 38.427908 -276.689732)
			(xy 38.383446 -276.71083) (xy 38.336175 -276.724522) (xy 38.28732 -276.730454) (xy 38.238145 -276.728473)
			(xy 38.189926 -276.718629) (xy 38.14391 -276.701177) (xy 38.101289 -276.67657) (xy 38.063168 -276.645445)
			(xy 38.030533 -276.608608) (xy 38.00423 -276.567012) (xy 37.984939 -276.521736) (xy 37.973162 -276.473952)
			(xy 37.969202 -276.424898) (xy 37.6301 -276.424898) (xy 37.629605 -276.449505) (xy 37.62171 -276.498082)
			(xy 37.606126 -276.544763) (xy 37.583255 -276.58834) (xy 37.55369 -276.627684) (xy 37.518197 -276.661776)
			(xy 37.477694 -276.689732) (xy 37.433232 -276.71083) (xy 37.385961 -276.724522) (xy 37.337106 -276.730454)
			(xy 37.287931 -276.728473) (xy 37.239712 -276.718629) (xy 37.193696 -276.701177) (xy 37.151075 -276.67657)
			(xy 37.112954 -276.645445) (xy 37.080319 -276.608608) (xy 37.054016 -276.567012) (xy 37.034725 -276.521736)
			(xy 37.022948 -276.473952) (xy 37.018988 -276.424898) (xy 36.68014 -276.424898) (xy 36.679645 -276.449505)
			(xy 36.67175 -276.498082) (xy 36.656166 -276.544763) (xy 36.633295 -276.58834) (xy 36.60373 -276.627684)
			(xy 36.568237 -276.661776) (xy 36.527734 -276.689732) (xy 36.483272 -276.71083) (xy 36.436001 -276.724522)
			(xy 36.387146 -276.730454) (xy 36.337971 -276.728473) (xy 36.289752 -276.718629) (xy 36.243736 -276.701177)
			(xy 36.201115 -276.67657) (xy 36.162994 -276.645445) (xy 36.130359 -276.608608) (xy 36.104056 -276.567012)
			(xy 36.084765 -276.521736) (xy 36.072988 -276.473952) (xy 36.069028 -276.424898) (xy 16.121366 -276.424898)
			(xy 16.110955 -276.447695) (xy 16.081489 -276.493545) (xy 16.045798 -276.534736) (xy 16.004607 -276.570427)
			(xy 15.958757 -276.599893) (xy 15.90918 -276.622535) (xy 15.856885 -276.63789) (xy 15.802937 -276.645646)
			(xy 15.748435 -276.645646) (xy 15.694487 -276.63789) (xy 15.642192 -276.622535) (xy 15.592615 -276.599893)
			(xy 15.546765 -276.570427) (xy 15.505574 -276.534736) (xy 15.469883 -276.493545) (xy 15.440417 -276.447695)
			(xy 15.417775 -276.398118) (xy 15.40242 -276.345823) (xy 15.394664 -276.291875) (xy 15.394178 -276.264624)
			(xy 14.30619 -276.264624) (xy 14.304155 -276.268964) (xy 14.273382 -276.315477) (xy 14.236165 -276.357014)
			(xy 14.193297 -276.392689) (xy 14.145691 -276.421743) (xy 14.094362 -276.443555) (xy 14.040405 -276.457661)
			(xy 13.984968 -276.463761) (xy 13.929234 -276.461724) (xy 13.874391 -276.451594) (xy 13.821607 -276.433587)
			(xy 13.772007 -276.408086) (xy 13.726649 -276.375635) (xy 13.6865 -276.336926) (xy 13.652414 -276.292783)
			(xy 13.625118 -276.244148) (xy 13.605195 -276.192057) (xy 13.593069 -276.13762) (xy 13.588998 -276.081998)
			(xy 13.174268 -276.081998) (xy 13.174472 -276.093174) (xy 13.173963 -276.12106) (xy 13.165843 -276.176236)
			(xy 13.149775 -276.229643) (xy 13.126103 -276.28014) (xy 13.09533 -276.326653) (xy 13.058113 -276.36819)
			(xy 13.015245 -276.403865) (xy 12.967639 -276.432919) (xy 12.91631 -276.454731) (xy 12.862353 -276.468837)
			(xy 12.806916 -276.474937) (xy 12.751182 -276.4729) (xy 12.696339 -276.46277) (xy 12.643555 -276.444763)
			(xy 12.593955 -276.419262) (xy 12.548597 -276.386811) (xy 12.508448 -276.348102) (xy 12.474362 -276.303959)
			(xy 12.447066 -276.255324) (xy 12.427143 -276.203233) (xy 12.415017 -276.148796) (xy 12.410946 -276.093174)
			(xy 11.620791 -276.093174) (xy 11.601849 -276.133582) (xy 11.571076 -276.180095) (xy 11.533859 -276.221632)
			(xy 11.490991 -276.257307) (xy 11.443385 -276.286361) (xy 11.392056 -276.308173) (xy 11.338099 -276.322279)
			(xy 11.282662 -276.328379) (xy 11.226928 -276.326342) (xy 11.172085 -276.316212) (xy 11.119301 -276.298205)
			(xy 11.069701 -276.272704) (xy 11.024343 -276.240253) (xy 10.984194 -276.201544) (xy 10.950108 -276.157401)
			(xy 10.922812 -276.108766) (xy 10.902889 -276.056675) (xy 10.890763 -276.002238) (xy 10.886692 -275.946616)
			(xy 1.917724 -275.946616) (xy 1.918992 -275.955433) (xy 1.918992 -276.009935) (xy 1.911236 -276.063883)
			(xy 1.895881 -276.116178) (xy 1.873239 -276.165755) (xy 1.843773 -276.211605) (xy 1.808082 -276.252796)
			(xy 1.766891 -276.288487) (xy 1.721041 -276.317953) (xy 1.671464 -276.340595) (xy 1.619169 -276.35595)
			(xy 1.565221 -276.363706) (xy 1.53797 -276.364192) (xy 1.52527 -276.363938) (xy 1.515014 -276.364043)
			(xy 1.495879 -276.371379) (xy 1.488186 -276.378162) (xy 1.435608 -276.428962) (xy 1.434338 -276.430232)
			(xy 1.428978 -276.43617) (xy 1.421973 -276.450542) (xy 1.420622 -276.458426) (xy 1.420114 -276.465538)
			(xy 1.420114 -276.789134) (xy 9.320782 -276.789134) (xy 9.324853 -276.733512) (xy 9.336979 -276.679075)
			(xy 9.356902 -276.626984) (xy 9.384198 -276.578349) (xy 9.418284 -276.534206) (xy 9.458433 -276.495497)
			(xy 9.503791 -276.463046) (xy 9.553391 -276.437545) (xy 9.606175 -276.419538) (xy 9.661018 -276.409408)
			(xy 9.716752 -276.407371) (xy 9.772189 -276.413471) (xy 9.826146 -276.427577) (xy 9.877475 -276.449389)
			(xy 9.925081 -276.478443) (xy 9.967949 -276.514118) (xy 10.005166 -276.555655) (xy 10.035939 -276.602168)
			(xy 10.059611 -276.652665) (xy 10.075679 -276.706072) (xy 10.083799 -276.761248) (xy 10.084308 -276.789134)
			(xy 10.083799 -276.81702) (xy 10.075679 -276.872196) (xy 10.059611 -276.925603) (xy 10.035939 -276.9761)
			(xy 10.005166 -277.022613) (xy 9.967949 -277.06415) (xy 9.925081 -277.099825) (xy 9.877475 -277.128879)
			(xy 9.826146 -277.150691) (xy 9.772189 -277.164797) (xy 9.716752 -277.170897) (xy 9.661018 -277.16886)
			(xy 9.606175 -277.15873) (xy 9.553391 -277.140723) (xy 9.503791 -277.115222) (xy 9.458433 -277.082771)
			(xy 9.418284 -277.044062) (xy 9.384198 -276.999919) (xy 9.356902 -276.951284) (xy 9.336979 -276.899193)
			(xy 9.324853 -276.844756) (xy 9.320782 -276.789134) (xy 1.420114 -276.789134) (xy 1.420114 -276.876002)
			(xy 1.420622 -276.883114) (xy 1.422048 -276.890976) (xy 1.429031 -276.905335) (xy 1.434338 -276.911308)
			(xy 1.435608 -276.912578) (xy 1.488186 -276.963378) (xy 1.49588 -276.970162) (xy 1.515013 -276.977506)
			(xy 1.52527 -276.977602) (xy 1.538986 -276.977348) (xy 1.566237 -276.977834) (xy 1.620185 -276.98559)
			(xy 1.67248 -277.000945) (xy 1.722057 -277.023587) (xy 1.767907 -277.053053) (xy 1.809098 -277.088744)
			(xy 1.844789 -277.129935) (xy 1.874255 -277.175785) (xy 1.896897 -277.225362) (xy 1.912252 -277.277657)
			(xy 1.912679 -277.280624) (xy 15.393668 -277.280624) (xy 15.397739 -277.225002) (xy 15.409865 -277.170565)
			(xy 15.429788 -277.118474) (xy 15.457084 -277.069839) (xy 15.49117 -277.025696) (xy 15.531319 -276.986987)
			(xy 15.576677 -276.954536) (xy 15.626277 -276.929035) (xy 15.679061 -276.911028) (xy 15.733904 -276.900898)
			(xy 15.789638 -276.898861) (xy 15.845075 -276.904961) (xy 15.899032 -276.919067) (xy 15.950361 -276.940879)
			(xy 15.997967 -276.969933) (xy 16.040835 -277.005608) (xy 16.078052 -277.047145) (xy 16.108825 -277.093658)
			(xy 16.132497 -277.144155) (xy 16.148565 -277.197562) (xy 16.156685 -277.252738) (xy 16.157194 -277.280624)
			(xy 16.156685 -277.30851) (xy 16.148565 -277.363686) (xy 16.145204 -277.374858) (xy 36.069028 -277.374858)
			(xy 36.072988 -277.325804) (xy 36.084765 -277.27802) (xy 36.104056 -277.232744) (xy 36.130359 -277.191148)
			(xy 36.162994 -277.154311) (xy 36.201115 -277.123186) (xy 36.243736 -277.098579) (xy 36.289752 -277.081127)
			(xy 36.337971 -277.071283) (xy 36.387146 -277.069302) (xy 36.436001 -277.075234) (xy 36.483272 -277.088926)
			(xy 36.527734 -277.110024) (xy 36.568237 -277.13798) (xy 36.60373 -277.172072) (xy 36.633295 -277.211416)
			(xy 36.656166 -277.254993) (xy 36.67175 -277.301674) (xy 36.679645 -277.350251) (xy 36.68014 -277.374858)
			(xy 37.018988 -277.374858) (xy 37.022948 -277.325804) (xy 37.034725 -277.27802) (xy 37.054016 -277.232744)
			(xy 37.080319 -277.191148) (xy 37.112954 -277.154311) (xy 37.151075 -277.123186) (xy 37.193696 -277.098579)
			(xy 37.239712 -277.081127) (xy 37.287931 -277.071283) (xy 37.337106 -277.069302) (xy 37.385961 -277.075234)
			(xy 37.433232 -277.088926) (xy 37.477694 -277.110024) (xy 37.518197 -277.13798) (xy 37.55369 -277.172072)
			(xy 37.583255 -277.211416) (xy 37.606126 -277.254993) (xy 37.62171 -277.301674) (xy 37.629605 -277.350251)
			(xy 37.6301 -277.374858) (xy 37.969202 -277.374858) (xy 37.973162 -277.325804) (xy 37.984939 -277.27802)
			(xy 38.00423 -277.232744) (xy 38.030533 -277.191148) (xy 38.063168 -277.154311) (xy 38.101289 -277.123186)
			(xy 38.14391 -277.098579) (xy 38.189926 -277.081127) (xy 38.238145 -277.071283) (xy 38.28732 -277.069302)
			(xy 38.336175 -277.075234) (xy 38.383446 -277.088926) (xy 38.427908 -277.110024) (xy 38.468411 -277.13798)
			(xy 38.503904 -277.172072) (xy 38.533469 -277.211416) (xy 38.55634 -277.254993) (xy 38.571924 -277.301674)
			(xy 38.579819 -277.350251) (xy 38.580314 -277.374858) (xy 38.919162 -277.374858) (xy 38.923122 -277.325804)
			(xy 38.934899 -277.27802) (xy 38.95419 -277.232744) (xy 38.980493 -277.191148) (xy 39.013128 -277.154311)
			(xy 39.051249 -277.123186) (xy 39.09387 -277.098579) (xy 39.139886 -277.081127) (xy 39.188105 -277.071283)
			(xy 39.23728 -277.069302) (xy 39.286135 -277.075234) (xy 39.333406 -277.088926) (xy 39.377868 -277.110024)
			(xy 39.418371 -277.13798) (xy 39.453864 -277.172072) (xy 39.483429 -277.211416) (xy 39.5063 -277.254993)
			(xy 39.521884 -277.301674) (xy 39.529779 -277.350251) (xy 39.530274 -277.374858) (xy 39.869122 -277.374858)
			(xy 39.873082 -277.325804) (xy 39.884859 -277.27802) (xy 39.90415 -277.232744) (xy 39.930453 -277.191148)
			(xy 39.963088 -277.154311) (xy 40.001209 -277.123186) (xy 40.04383 -277.098579) (xy 40.089846 -277.081127)
			(xy 40.138065 -277.071283) (xy 40.18724 -277.069302) (xy 40.236095 -277.075234) (xy 40.283366 -277.088926)
			(xy 40.327828 -277.110024) (xy 40.368331 -277.13798) (xy 40.403824 -277.172072) (xy 40.433389 -277.211416)
			(xy 40.45626 -277.254993) (xy 40.471844 -277.301674) (xy 40.479739 -277.350251) (xy 40.480234 -277.374858)
			(xy 40.819082 -277.374858) (xy 40.823042 -277.325804) (xy 40.834819 -277.27802) (xy 40.85411 -277.232744)
			(xy 40.880413 -277.191148) (xy 40.913048 -277.154311) (xy 40.951169 -277.123186) (xy 40.99379 -277.098579)
			(xy 41.039806 -277.081127) (xy 41.088025 -277.071283) (xy 41.1372 -277.069302) (xy 41.186055 -277.075234)
			(xy 41.233326 -277.088926) (xy 41.277788 -277.110024) (xy 41.318291 -277.13798) (xy 41.353784 -277.172072)
			(xy 41.383349 -277.211416) (xy 41.40622 -277.254993) (xy 41.421804 -277.301674) (xy 41.429699 -277.350251)
			(xy 41.430194 -277.374858) (xy 41.429699 -277.399465) (xy 41.421804 -277.448042) (xy 41.40622 -277.494723)
			(xy 41.383349 -277.5383) (xy 41.353784 -277.577644) (xy 41.318291 -277.611736) (xy 41.277788 -277.639692)
			(xy 41.233326 -277.66079) (xy 41.186055 -277.674482) (xy 41.1372 -277.680414) (xy 41.088025 -277.678433)
			(xy 41.039806 -277.668589) (xy 40.99379 -277.651137) (xy 40.951169 -277.62653) (xy 40.913048 -277.595405)
			(xy 40.880413 -277.558568) (xy 40.85411 -277.516972) (xy 40.834819 -277.471696) (xy 40.823042 -277.423912)
			(xy 40.819082 -277.374858) (xy 40.480234 -277.374858) (xy 40.479739 -277.399465) (xy 40.471844 -277.448042)
			(xy 40.45626 -277.494723) (xy 40.433389 -277.5383) (xy 40.403824 -277.577644) (xy 40.368331 -277.611736)
			(xy 40.327828 -277.639692) (xy 40.283366 -277.66079) (xy 40.236095 -277.674482) (xy 40.18724 -277.680414)
			(xy 40.138065 -277.678433) (xy 40.089846 -277.668589) (xy 40.04383 -277.651137) (xy 40.001209 -277.62653)
			(xy 39.963088 -277.595405) (xy 39.930453 -277.558568) (xy 39.90415 -277.516972) (xy 39.884859 -277.471696)
			(xy 39.873082 -277.423912) (xy 39.869122 -277.374858) (xy 39.530274 -277.374858) (xy 39.529779 -277.399465)
			(xy 39.521884 -277.448042) (xy 39.5063 -277.494723) (xy 39.483429 -277.5383) (xy 39.453864 -277.577644)
			(xy 39.418371 -277.611736) (xy 39.377868 -277.639692) (xy 39.333406 -277.66079) (xy 39.286135 -277.674482)
			(xy 39.23728 -277.680414) (xy 39.188105 -277.678433) (xy 39.139886 -277.668589) (xy 39.09387 -277.651137)
			(xy 39.051249 -277.62653) (xy 39.013128 -277.595405) (xy 38.980493 -277.558568) (xy 38.95419 -277.516972)
			(xy 38.934899 -277.471696) (xy 38.923122 -277.423912) (xy 38.919162 -277.374858) (xy 38.580314 -277.374858)
			(xy 38.579819 -277.399465) (xy 38.571924 -277.448042) (xy 38.55634 -277.494723) (xy 38.533469 -277.5383)
			(xy 38.503904 -277.577644) (xy 38.468411 -277.611736) (xy 38.427908 -277.639692) (xy 38.383446 -277.66079)
			(xy 38.336175 -277.674482) (xy 38.28732 -277.680414) (xy 38.238145 -277.678433) (xy 38.189926 -277.668589)
			(xy 38.14391 -277.651137) (xy 38.101289 -277.62653) (xy 38.063168 -277.595405) (xy 38.030533 -277.558568)
			(xy 38.00423 -277.516972) (xy 37.984939 -277.471696) (xy 37.973162 -277.423912) (xy 37.969202 -277.374858)
			(xy 37.6301 -277.374858) (xy 37.629605 -277.399465) (xy 37.62171 -277.448042) (xy 37.606126 -277.494723)
			(xy 37.583255 -277.5383) (xy 37.55369 -277.577644) (xy 37.518197 -277.611736) (xy 37.477694 -277.639692)
			(xy 37.433232 -277.66079) (xy 37.385961 -277.674482) (xy 37.337106 -277.680414) (xy 37.287931 -277.678433)
			(xy 37.239712 -277.668589) (xy 37.193696 -277.651137) (xy 37.151075 -277.62653) (xy 37.112954 -277.595405)
			(xy 37.080319 -277.558568) (xy 37.054016 -277.516972) (xy 37.034725 -277.471696) (xy 37.022948 -277.423912)
			(xy 37.018988 -277.374858) (xy 36.68014 -277.374858) (xy 36.679645 -277.399465) (xy 36.67175 -277.448042)
			(xy 36.656166 -277.494723) (xy 36.633295 -277.5383) (xy 36.60373 -277.577644) (xy 36.568237 -277.611736)
			(xy 36.527734 -277.639692) (xy 36.483272 -277.66079) (xy 36.436001 -277.674482) (xy 36.387146 -277.680414)
			(xy 36.337971 -277.678433) (xy 36.289752 -277.668589) (xy 36.243736 -277.651137) (xy 36.201115 -277.62653)
			(xy 36.162994 -277.595405) (xy 36.130359 -277.558568) (xy 36.104056 -277.516972) (xy 36.084765 -277.471696)
			(xy 36.072988 -277.423912) (xy 36.069028 -277.374858) (xy 16.145204 -277.374858) (xy 16.132497 -277.417093)
			(xy 16.108825 -277.46759) (xy 16.078052 -277.514103) (xy 16.040835 -277.55564) (xy 15.997967 -277.591315)
			(xy 15.950361 -277.620369) (xy 15.899032 -277.642181) (xy 15.845075 -277.656287) (xy 15.789638 -277.662387)
			(xy 15.733904 -277.66035) (xy 15.679061 -277.65022) (xy 15.626277 -277.632213) (xy 15.576677 -277.606712)
			(xy 15.531319 -277.574261) (xy 15.49117 -277.535552) (xy 15.457084 -277.491409) (xy 15.429788 -277.442774)
			(xy 15.409865 -277.390683) (xy 15.397739 -277.336246) (xy 15.393668 -277.280624) (xy 1.912679 -277.280624)
			(xy 1.920008 -277.331605) (xy 1.920008 -277.386107) (xy 1.912252 -277.440055) (xy 1.896897 -277.49235)
			(xy 1.874255 -277.541927) (xy 1.844789 -277.587777) (xy 1.809098 -277.628968) (xy 1.767907 -277.664659)
			(xy 1.722057 -277.694125) (xy 1.67248 -277.716767) (xy 1.620185 -277.732122) (xy 1.566237 -277.739878)
			(xy 1.538986 -277.740364) (xy 1.52527 -277.74011) (xy 1.515015 -277.740217) (xy 1.495887 -277.747561)
			(xy 1.488186 -277.754334) (xy 1.435608 -277.805134) (xy 1.434338 -277.806404) (xy 1.428974 -277.81234)
			(xy 1.428028 -277.814278) (xy 9.324846 -277.814278) (xy 9.328917 -277.758656) (xy 9.341043 -277.704219)
			(xy 9.360966 -277.652128) (xy 9.388262 -277.603493) (xy 9.422348 -277.55935) (xy 9.462497 -277.520641)
			(xy 9.507855 -277.48819) (xy 9.557455 -277.462689) (xy 9.610239 -277.444682) (xy 9.665082 -277.434552)
			(xy 9.720816 -277.432515) (xy 9.776253 -277.438615) (xy 9.83021 -277.452721) (xy 9.881539 -277.474533)
			(xy 9.929145 -277.503587) (xy 9.972013 -277.539262) (xy 10.00923 -277.580799) (xy 10.040003 -277.627312)
			(xy 10.063675 -277.677809) (xy 10.079743 -277.731216) (xy 10.087863 -277.786392) (xy 10.088372 -277.814278)
			(xy 11.344146 -277.814278) (xy 11.348217 -277.758656) (xy 11.360343 -277.704219) (xy 11.380266 -277.652128)
			(xy 11.407562 -277.603493) (xy 11.441648 -277.55935) (xy 11.481797 -277.520641) (xy 11.527155 -277.48819)
			(xy 11.576755 -277.462689) (xy 11.629539 -277.444682) (xy 11.684382 -277.434552) (xy 11.740116 -277.432515)
			(xy 11.795553 -277.438615) (xy 11.84951 -277.452721) (xy 11.900839 -277.474533) (xy 11.948445 -277.503587)
			(xy 11.991313 -277.539262) (xy 12.02853 -277.580799) (xy 12.059303 -277.627312) (xy 12.082975 -277.677809)
			(xy 12.099043 -277.731216) (xy 12.107163 -277.786392) (xy 12.107672 -277.814278) (xy 12.107163 -277.842164)
			(xy 12.099043 -277.89734) (xy 12.082975 -277.950747) (xy 12.059303 -278.001244) (xy 12.02853 -278.047757)
			(xy 11.991313 -278.089294) (xy 11.948445 -278.124969) (xy 11.900839 -278.154023) (xy 11.84951 -278.175835)
			(xy 11.795553 -278.189941) (xy 11.740116 -278.196041) (xy 11.684382 -278.194004) (xy 11.629539 -278.183874)
			(xy 11.576755 -278.165867) (xy 11.527155 -278.140366) (xy 11.481797 -278.107915) (xy 11.441648 -278.069206)
			(xy 11.407562 -278.025063) (xy 11.380266 -277.976428) (xy 11.360343 -277.924337) (xy 11.348217 -277.8699)
			(xy 11.344146 -277.814278) (xy 10.088372 -277.814278) (xy 10.087863 -277.842164) (xy 10.079743 -277.89734)
			(xy 10.063675 -277.950747) (xy 10.040003 -278.001244) (xy 10.00923 -278.047757) (xy 9.972013 -278.089294)
			(xy 9.929145 -278.124969) (xy 9.881539 -278.154023) (xy 9.83021 -278.175835) (xy 9.776253 -278.189941)
			(xy 9.720816 -278.196041) (xy 9.665082 -278.194004) (xy 9.610239 -278.183874) (xy 9.557455 -278.165867)
			(xy 9.507855 -278.140366) (xy 9.462497 -278.107915) (xy 9.422348 -278.069206) (xy 9.388262 -278.025063)
			(xy 9.360966 -277.976428) (xy 9.341043 -277.924337) (xy 9.328917 -277.8699) (xy 9.324846 -277.814278)
			(xy 1.428028 -277.814278) (xy 1.421962 -277.826712) (xy 1.420622 -277.834598) (xy 1.420114 -277.84171)
			(xy 1.420114 -278.301704) (xy 19.362418 -278.301704) (xy 19.366489 -278.246082) (xy 19.378615 -278.191645)
			(xy 19.398538 -278.139554) (xy 19.425834 -278.090919) (xy 19.45992 -278.046776) (xy 19.500069 -278.008067)
			(xy 19.545427 -277.975616) (xy 19.595027 -277.950115) (xy 19.647811 -277.932108) (xy 19.702654 -277.921978)
			(xy 19.758388 -277.919941) (xy 19.813825 -277.926041) (xy 19.867782 -277.940147) (xy 19.919111 -277.961959)
			(xy 19.966717 -277.991013) (xy 20.009585 -278.026688) (xy 20.046802 -278.068225) (xy 20.077575 -278.114738)
			(xy 20.101247 -278.165235) (xy 20.117315 -278.218642) (xy 20.125435 -278.273818) (xy 20.125944 -278.301704)
			(xy 20.125435 -278.32959) (xy 20.117315 -278.384766) (xy 20.101247 -278.438173) (xy 20.098899 -278.443182)
			(xy 25.719276 -278.443182) (xy 25.723347 -278.38756) (xy 25.735473 -278.333123) (xy 25.755396 -278.281032)
			(xy 25.782692 -278.232397) (xy 25.816778 -278.188254) (xy 25.856927 -278.149545) (xy 25.902285 -278.117094)
			(xy 25.951885 -278.091593) (xy 26.004669 -278.073586) (xy 26.059512 -278.063456) (xy 26.115246 -278.061419)
			(xy 26.170683 -278.067519) (xy 26.22464 -278.081625) (xy 26.275969 -278.103437) (xy 26.323575 -278.132491)
			(xy 26.366443 -278.168166) (xy 26.40366 -278.209703) (xy 26.434433 -278.256216) (xy 26.458105 -278.306713)
			(xy 26.463552 -278.324818) (xy 36.069028 -278.324818) (xy 36.072988 -278.275764) (xy 36.084765 -278.22798)
			(xy 36.104056 -278.182704) (xy 36.130359 -278.141108) (xy 36.162994 -278.104271) (xy 36.201115 -278.073146)
			(xy 36.243736 -278.048539) (xy 36.289752 -278.031087) (xy 36.337971 -278.021243) (xy 36.387146 -278.019262)
			(xy 36.436001 -278.025194) (xy 36.483272 -278.038886) (xy 36.527734 -278.059984) (xy 36.568237 -278.08794)
			(xy 36.60373 -278.122032) (xy 36.633295 -278.161376) (xy 36.656166 -278.204953) (xy 36.67175 -278.251634)
			(xy 36.679645 -278.300211) (xy 36.68014 -278.324818) (xy 37.018988 -278.324818) (xy 37.022948 -278.275764)
			(xy 37.034725 -278.22798) (xy 37.054016 -278.182704) (xy 37.080319 -278.141108) (xy 37.112954 -278.104271)
			(xy 37.151075 -278.073146) (xy 37.193696 -278.048539) (xy 37.239712 -278.031087) (xy 37.287931 -278.021243)
			(xy 37.337106 -278.019262) (xy 37.385961 -278.025194) (xy 37.433232 -278.038886) (xy 37.477694 -278.059984)
			(xy 37.518197 -278.08794) (xy 37.55369 -278.122032) (xy 37.583255 -278.161376) (xy 37.606126 -278.204953)
			(xy 37.62171 -278.251634) (xy 37.629605 -278.300211) (xy 37.6301 -278.324818) (xy 37.969202 -278.324818)
			(xy 37.973162 -278.275764) (xy 37.984939 -278.22798) (xy 38.00423 -278.182704) (xy 38.030533 -278.141108)
			(xy 38.063168 -278.104271) (xy 38.101289 -278.073146) (xy 38.14391 -278.048539) (xy 38.189926 -278.031087)
			(xy 38.238145 -278.021243) (xy 38.28732 -278.019262) (xy 38.336175 -278.025194) (xy 38.383446 -278.038886)
			(xy 38.427908 -278.059984) (xy 38.468411 -278.08794) (xy 38.503904 -278.122032) (xy 38.533469 -278.161376)
			(xy 38.55634 -278.204953) (xy 38.571924 -278.251634) (xy 38.579819 -278.300211) (xy 38.580314 -278.324818)
			(xy 38.919162 -278.324818) (xy 38.923122 -278.275764) (xy 38.934899 -278.22798) (xy 38.95419 -278.182704)
			(xy 38.980493 -278.141108) (xy 39.013128 -278.104271) (xy 39.051249 -278.073146) (xy 39.09387 -278.048539)
			(xy 39.139886 -278.031087) (xy 39.188105 -278.021243) (xy 39.23728 -278.019262) (xy 39.286135 -278.025194)
			(xy 39.333406 -278.038886) (xy 39.377868 -278.059984) (xy 39.418371 -278.08794) (xy 39.453864 -278.122032)
			(xy 39.483429 -278.161376) (xy 39.5063 -278.204953) (xy 39.521884 -278.251634) (xy 39.529779 -278.300211)
			(xy 39.530274 -278.324818) (xy 39.869122 -278.324818) (xy 39.873082 -278.275764) (xy 39.884859 -278.22798)
			(xy 39.90415 -278.182704) (xy 39.930453 -278.141108) (xy 39.963088 -278.104271) (xy 40.001209 -278.073146)
			(xy 40.04383 -278.048539) (xy 40.089846 -278.031087) (xy 40.138065 -278.021243) (xy 40.18724 -278.019262)
			(xy 40.236095 -278.025194) (xy 40.283366 -278.038886) (xy 40.327828 -278.059984) (xy 40.368331 -278.08794)
			(xy 40.403824 -278.122032) (xy 40.433389 -278.161376) (xy 40.45626 -278.204953) (xy 40.471844 -278.251634)
			(xy 40.479739 -278.300211) (xy 40.480234 -278.324818) (xy 40.819082 -278.324818) (xy 40.823042 -278.275764)
			(xy 40.834819 -278.22798) (xy 40.85411 -278.182704) (xy 40.880413 -278.141108) (xy 40.913048 -278.104271)
			(xy 40.951169 -278.073146) (xy 40.99379 -278.048539) (xy 41.039806 -278.031087) (xy 41.088025 -278.021243)
			(xy 41.1372 -278.019262) (xy 41.186055 -278.025194) (xy 41.233326 -278.038886) (xy 41.277788 -278.059984)
			(xy 41.318291 -278.08794) (xy 41.353784 -278.122032) (xy 41.383349 -278.161376) (xy 41.40622 -278.204953)
			(xy 41.421804 -278.251634) (xy 41.429699 -278.300211) (xy 41.430194 -278.324818) (xy 41.429699 -278.349425)
			(xy 41.421804 -278.398002) (xy 41.40622 -278.444683) (xy 41.383349 -278.48826) (xy 41.353784 -278.527604)
			(xy 41.318291 -278.561696) (xy 41.277788 -278.589652) (xy 41.233326 -278.61075) (xy 41.186055 -278.624442)
			(xy 41.1372 -278.630374) (xy 41.088025 -278.628393) (xy 41.039806 -278.618549) (xy 40.99379 -278.601097)
			(xy 40.951169 -278.57649) (xy 40.913048 -278.545365) (xy 40.880413 -278.508528) (xy 40.85411 -278.466932)
			(xy 40.834819 -278.421656) (xy 40.823042 -278.373872) (xy 40.819082 -278.324818) (xy 40.480234 -278.324818)
			(xy 40.479739 -278.349425) (xy 40.471844 -278.398002) (xy 40.45626 -278.444683) (xy 40.433389 -278.48826)
			(xy 40.403824 -278.527604) (xy 40.368331 -278.561696) (xy 40.327828 -278.589652) (xy 40.283366 -278.61075)
			(xy 40.236095 -278.624442) (xy 40.18724 -278.630374) (xy 40.138065 -278.628393) (xy 40.089846 -278.618549)
			(xy 40.04383 -278.601097) (xy 40.001209 -278.57649) (xy 39.963088 -278.545365) (xy 39.930453 -278.508528)
			(xy 39.90415 -278.466932) (xy 39.884859 -278.421656) (xy 39.873082 -278.373872) (xy 39.869122 -278.324818)
			(xy 39.530274 -278.324818) (xy 39.529779 -278.349425) (xy 39.521884 -278.398002) (xy 39.5063 -278.444683)
			(xy 39.483429 -278.48826) (xy 39.453864 -278.527604) (xy 39.418371 -278.561696) (xy 39.377868 -278.589652)
			(xy 39.333406 -278.61075) (xy 39.286135 -278.624442) (xy 39.23728 -278.630374) (xy 39.188105 -278.628393)
			(xy 39.139886 -278.618549) (xy 39.09387 -278.601097) (xy 39.051249 -278.57649) (xy 39.013128 -278.545365)
			(xy 38.980493 -278.508528) (xy 38.95419 -278.466932) (xy 38.934899 -278.421656) (xy 38.923122 -278.373872)
			(xy 38.919162 -278.324818) (xy 38.580314 -278.324818) (xy 38.579819 -278.349425) (xy 38.571924 -278.398002)
			(xy 38.55634 -278.444683) (xy 38.533469 -278.48826) (xy 38.503904 -278.527604) (xy 38.468411 -278.561696)
			(xy 38.427908 -278.589652) (xy 38.383446 -278.61075) (xy 38.336175 -278.624442) (xy 38.28732 -278.630374)
			(xy 38.238145 -278.628393) (xy 38.189926 -278.618549) (xy 38.14391 -278.601097) (xy 38.101289 -278.57649)
			(xy 38.063168 -278.545365) (xy 38.030533 -278.508528) (xy 38.00423 -278.466932) (xy 37.984939 -278.421656)
			(xy 37.973162 -278.373872) (xy 37.969202 -278.324818) (xy 37.6301 -278.324818) (xy 37.629605 -278.349425)
			(xy 37.62171 -278.398002) (xy 37.606126 -278.444683) (xy 37.583255 -278.48826) (xy 37.55369 -278.527604)
			(xy 37.518197 -278.561696) (xy 37.477694 -278.589652) (xy 37.433232 -278.61075) (xy 37.385961 -278.624442)
			(xy 37.337106 -278.630374) (xy 37.287931 -278.628393) (xy 37.239712 -278.618549) (xy 37.193696 -278.601097)
			(xy 37.151075 -278.57649) (xy 37.112954 -278.545365) (xy 37.080319 -278.508528) (xy 37.054016 -278.466932)
			(xy 37.034725 -278.421656) (xy 37.022948 -278.373872) (xy 37.018988 -278.324818) (xy 36.68014 -278.324818)
			(xy 36.679645 -278.349425) (xy 36.67175 -278.398002) (xy 36.656166 -278.444683) (xy 36.633295 -278.48826)
			(xy 36.60373 -278.527604) (xy 36.568237 -278.561696) (xy 36.527734 -278.589652) (xy 36.483272 -278.61075)
			(xy 36.436001 -278.624442) (xy 36.387146 -278.630374) (xy 36.337971 -278.628393) (xy 36.289752 -278.618549)
			(xy 36.243736 -278.601097) (xy 36.201115 -278.57649) (xy 36.162994 -278.545365) (xy 36.130359 -278.508528)
			(xy 36.104056 -278.466932) (xy 36.084765 -278.421656) (xy 36.072988 -278.373872) (xy 36.069028 -278.324818)
			(xy 26.463552 -278.324818) (xy 26.474173 -278.36012) (xy 26.482293 -278.415296) (xy 26.482802 -278.443182)
			(xy 26.482293 -278.471068) (xy 26.474173 -278.526244) (xy 26.458105 -278.579651) (xy 26.434433 -278.630148)
			(xy 26.40366 -278.676661) (xy 26.366443 -278.718198) (xy 26.323575 -278.753873) (xy 26.318245 -278.757126)
			(xy 33.547048 -278.757126) (xy 33.551119 -278.701504) (xy 33.563245 -278.647067) (xy 33.583168 -278.594976)
			(xy 33.610464 -278.546341) (xy 33.64455 -278.502198) (xy 33.684699 -278.463489) (xy 33.730057 -278.431038)
			(xy 33.779657 -278.405537) (xy 33.832441 -278.38753) (xy 33.887284 -278.3774) (xy 33.943018 -278.375363)
			(xy 33.998455 -278.381463) (xy 34.052412 -278.395569) (xy 34.103741 -278.417381) (xy 34.151347 -278.446435)
			(xy 34.194215 -278.48211) (xy 34.231432 -278.523647) (xy 34.262205 -278.57016) (xy 34.285877 -278.620657)
			(xy 34.301945 -278.674064) (xy 34.310065 -278.72924) (xy 34.310574 -278.757126) (xy 34.310065 -278.785012)
			(xy 34.301945 -278.840188) (xy 34.285877 -278.893595) (xy 34.262205 -278.944092) (xy 34.231432 -278.990605)
			(xy 34.194215 -279.032142) (xy 34.151347 -279.067817) (xy 34.103741 -279.096871) (xy 34.052412 -279.118683)
			(xy 33.998455 -279.132789) (xy 33.943018 -279.138889) (xy 33.887284 -279.136852) (xy 33.832441 -279.126722)
			(xy 33.779657 -279.108715) (xy 33.730057 -279.083214) (xy 33.684699 -279.050763) (xy 33.64455 -279.012054)
			(xy 33.610464 -278.967911) (xy 33.583168 -278.919276) (xy 33.563245 -278.867185) (xy 33.551119 -278.812748)
			(xy 33.547048 -278.757126) (xy 26.318245 -278.757126) (xy 26.275969 -278.782927) (xy 26.22464 -278.804739)
			(xy 26.170683 -278.818845) (xy 26.115246 -278.824945) (xy 26.059512 -278.822908) (xy 26.004669 -278.812778)
			(xy 25.951885 -278.794771) (xy 25.902285 -278.76927) (xy 25.856927 -278.736819) (xy 25.816778 -278.69811)
			(xy 25.782692 -278.653967) (xy 25.755396 -278.605332) (xy 25.735473 -278.553241) (xy 25.723347 -278.498804)
			(xy 25.719276 -278.443182) (xy 20.098899 -278.443182) (xy 20.077575 -278.48867) (xy 20.046802 -278.535183)
			(xy 20.009585 -278.57672) (xy 19.966717 -278.612395) (xy 19.919111 -278.641449) (xy 19.867782 -278.663261)
			(xy 19.813825 -278.677367) (xy 19.758388 -278.683467) (xy 19.702654 -278.68143) (xy 19.647811 -278.6713)
			(xy 19.595027 -278.653293) (xy 19.545427 -278.627792) (xy 19.500069 -278.595341) (xy 19.45992 -278.556632)
			(xy 19.425834 -278.512489) (xy 19.398538 -278.463854) (xy 19.378615 -278.411763) (xy 19.366489 -278.357326)
			(xy 19.362418 -278.301704) (xy 1.420114 -278.301704) (xy 1.420114 -279.73909) (xy 5.034026 -279.73909)
			(xy 5.034518 -279.710836) (xy 5.042855 -279.654948) (xy 5.059345 -279.6009) (xy 5.083626 -279.549876)
			(xy 5.115169 -279.502992) (xy 5.133848 -279.481788) (xy 5.140452 -279.474676) (xy 5.143754 -279.46604)
			(xy 5.145419 -279.461587) (xy 5.147212 -279.452251) (xy 5.14731 -279.447498) (xy 5.14731 -279.378918)
			(xy 5.14717 -279.374169) (xy 5.145381 -279.36484) (xy 5.143754 -279.360376) (xy 5.140452 -279.35174)
			(xy 5.133848 -279.344628) (xy 5.115176 -279.32342) (xy 5.083639 -279.276534) (xy 5.059362 -279.22551)
			(xy 5.042875 -279.171465) (xy 5.034539 -279.115578) (xy 5.034026 -279.087326) (xy 5.03448 -279.060072)
			(xy 5.042234 -279.006119) (xy 5.057588 -278.953819) (xy 5.08023 -278.904237) (xy 5.109699 -278.858382)
			(xy 5.145394 -278.817188) (xy 5.186588 -278.781494) (xy 5.232444 -278.752026) (xy 5.282027 -278.729386)
			(xy 5.334327 -278.714032) (xy 5.38828 -278.706279) (xy 5.415534 -278.705818) (xy 5.444273 -278.706343)
			(xy 5.501099 -278.714969) (xy 5.555989 -278.73202) (xy 5.6077 -278.75711) (xy 5.655064 -278.789673)
			(xy 5.676392 -278.808942) (xy 5.68325 -278.815546) (xy 5.692394 -278.819102) (xy 5.696856 -278.820735)
			(xy 5.706187 -278.82252) (xy 5.710936 -278.822658) (xy 5.780532 -278.822658) (xy 5.785286 -278.822571)
			(xy 5.794622 -278.820773) (xy 5.799074 -278.819102) (xy 5.808218 -278.815546) (xy 5.815076 -278.808942)
			(xy 5.836403 -278.789672) (xy 5.883766 -278.757107) (xy 5.935477 -278.732016) (xy 5.990368 -278.714966)
			(xy 6.047195 -278.706344) (xy 6.104673 -278.706344) (xy 6.1615 -278.714966) (xy 6.216391 -278.732016)
			(xy 6.268102 -278.757107) (xy 6.315465 -278.789672) (xy 6.336792 -278.808942) (xy 6.34365 -278.815546)
			(xy 6.352794 -278.819102) (xy 6.357256 -278.820735) (xy 6.366587 -278.82252) (xy 6.371336 -278.822658)
			(xy 6.440932 -278.822658) (xy 6.445686 -278.822571) (xy 6.455022 -278.820773) (xy 6.459474 -278.819102)
			(xy 6.468618 -278.815546) (xy 6.475476 -278.808942) (xy 6.496803 -278.789672) (xy 6.544166 -278.757107)
			(xy 6.595877 -278.732016) (xy 6.650768 -278.714966) (xy 6.707595 -278.706344) (xy 6.765073 -278.706344)
			(xy 6.8219 -278.714966) (xy 6.876791 -278.732016) (xy 6.928502 -278.757107) (xy 6.975865 -278.789672)
			(xy 6.997192 -278.808942) (xy 7.00405 -278.815546) (xy 7.013194 -278.819102) (xy 7.017656 -278.820735)
			(xy 7.026987 -278.82252) (xy 7.031736 -278.822658) (xy 7.101332 -278.822658) (xy 7.106086 -278.822571)
			(xy 7.115422 -278.820773) (xy 7.119874 -278.819102) (xy 7.129018 -278.815546) (xy 7.135876 -278.808942)
			(xy 7.15719 -278.789656) (xy 7.204555 -278.757092) (xy 7.25627 -278.732002) (xy 7.311164 -278.714955)
			(xy 7.367994 -278.706336) (xy 7.396734 -278.705818) (xy 7.423987 -278.706246) (xy 7.477938 -278.714008)
			(xy 7.530236 -278.729369) (xy 7.579815 -278.752016) (xy 7.625666 -278.781488) (xy 7.666857 -278.817186)
			(xy 7.702548 -278.858382) (xy 7.732013 -278.904238) (xy 7.754652 -278.95382) (xy 7.770005 -279.00612)
			(xy 7.777758 -279.060073) (xy 7.778242 -279.087326) (xy 7.777767 -279.11558) (xy 7.769428 -279.17147)
			(xy 7.752934 -279.225518) (xy 7.729489 -279.274778) (xy 36.069028 -279.274778) (xy 36.072988 -279.225724)
			(xy 36.084765 -279.17794) (xy 36.104056 -279.132664) (xy 36.130359 -279.091068) (xy 36.162994 -279.054231)
			(xy 36.201115 -279.023106) (xy 36.243736 -278.998499) (xy 36.289752 -278.981047) (xy 36.337971 -278.971203)
			(xy 36.387146 -278.969222) (xy 36.436001 -278.975154) (xy 36.483272 -278.988846) (xy 36.527734 -279.009944)
			(xy 36.568237 -279.0379) (xy 36.60373 -279.071992) (xy 36.633295 -279.111336) (xy 36.656166 -279.154913)
			(xy 36.67175 -279.201594) (xy 36.679645 -279.250171) (xy 36.68014 -279.274778) (xy 37.018988 -279.274778)
			(xy 37.022948 -279.225724) (xy 37.034725 -279.17794) (xy 37.054016 -279.132664) (xy 37.080319 -279.091068)
			(xy 37.112954 -279.054231) (xy 37.151075 -279.023106) (xy 37.193696 -278.998499) (xy 37.239712 -278.981047)
			(xy 37.287931 -278.971203) (xy 37.337106 -278.969222) (xy 37.385961 -278.975154) (xy 37.433232 -278.988846)
			(xy 37.477694 -279.009944) (xy 37.518197 -279.0379) (xy 37.55369 -279.071992) (xy 37.583255 -279.111336)
			(xy 37.606126 -279.154913) (xy 37.62171 -279.201594) (xy 37.629605 -279.250171) (xy 37.6301 -279.274778)
			(xy 37.969202 -279.274778) (xy 37.973162 -279.225724) (xy 37.984939 -279.17794) (xy 38.00423 -279.132664)
			(xy 38.030533 -279.091068) (xy 38.063168 -279.054231) (xy 38.101289 -279.023106) (xy 38.14391 -278.998499)
			(xy 38.189926 -278.981047) (xy 38.238145 -278.971203) (xy 38.28732 -278.969222) (xy 38.336175 -278.975154)
			(xy 38.383446 -278.988846) (xy 38.427908 -279.009944) (xy 38.468411 -279.0379) (xy 38.503904 -279.071992)
			(xy 38.533469 -279.111336) (xy 38.55634 -279.154913) (xy 38.571924 -279.201594) (xy 38.579819 -279.250171)
			(xy 38.580314 -279.274778) (xy 38.919162 -279.274778) (xy 38.923122 -279.225724) (xy 38.934899 -279.17794)
			(xy 38.95419 -279.132664) (xy 38.980493 -279.091068) (xy 39.013128 -279.054231) (xy 39.051249 -279.023106)
			(xy 39.09387 -278.998499) (xy 39.139886 -278.981047) (xy 39.188105 -278.971203) (xy 39.23728 -278.969222)
			(xy 39.286135 -278.975154) (xy 39.333406 -278.988846) (xy 39.377868 -279.009944) (xy 39.418371 -279.0379)
			(xy 39.453864 -279.071992) (xy 39.483429 -279.111336) (xy 39.5063 -279.154913) (xy 39.521884 -279.201594)
			(xy 39.529779 -279.250171) (xy 39.530274 -279.274778) (xy 39.869122 -279.274778) (xy 39.873082 -279.225724)
			(xy 39.884859 -279.17794) (xy 39.90415 -279.132664) (xy 39.930453 -279.091068) (xy 39.963088 -279.054231)
			(xy 40.001209 -279.023106) (xy 40.04383 -278.998499) (xy 40.089846 -278.981047) (xy 40.138065 -278.971203)
			(xy 40.18724 -278.969222) (xy 40.236095 -278.975154) (xy 40.283366 -278.988846) (xy 40.327828 -279.009944)
			(xy 40.368331 -279.0379) (xy 40.403824 -279.071992) (xy 40.433389 -279.111336) (xy 40.45626 -279.154913)
			(xy 40.471844 -279.201594) (xy 40.479739 -279.250171) (xy 40.480234 -279.274778) (xy 40.819082 -279.274778)
			(xy 40.823042 -279.225724) (xy 40.834819 -279.17794) (xy 40.85411 -279.132664) (xy 40.880413 -279.091068)
			(xy 40.913048 -279.054231) (xy 40.951169 -279.023106) (xy 40.99379 -278.998499) (xy 41.039806 -278.981047)
			(xy 41.088025 -278.971203) (xy 41.1372 -278.969222) (xy 41.186055 -278.975154) (xy 41.233326 -278.988846)
			(xy 41.277788 -279.009944) (xy 41.318291 -279.0379) (xy 41.353784 -279.071992) (xy 41.383349 -279.111336)
			(xy 41.40622 -279.154913) (xy 41.421804 -279.201594) (xy 41.429699 -279.250171) (xy 41.430194 -279.274778)
			(xy 41.429699 -279.299385) (xy 41.421804 -279.347962) (xy 41.40622 -279.394643) (xy 41.383349 -279.43822)
			(xy 41.353784 -279.477564) (xy 41.318291 -279.511656) (xy 41.277788 -279.539612) (xy 41.233326 -279.56071)
			(xy 41.186055 -279.574402) (xy 41.1372 -279.580334) (xy 41.088025 -279.578353) (xy 41.039806 -279.568509)
			(xy 40.99379 -279.551057) (xy 40.951169 -279.52645) (xy 40.913048 -279.495325) (xy 40.880413 -279.458488)
			(xy 40.85411 -279.416892) (xy 40.834819 -279.371616) (xy 40.823042 -279.323832) (xy 40.819082 -279.274778)
			(xy 40.480234 -279.274778) (xy 40.479739 -279.299385) (xy 40.471844 -279.347962) (xy 40.45626 -279.394643)
			(xy 40.433389 -279.43822) (xy 40.403824 -279.477564) (xy 40.368331 -279.511656) (xy 40.327828 -279.539612)
			(xy 40.283366 -279.56071) (xy 40.236095 -279.574402) (xy 40.18724 -279.580334) (xy 40.138065 -279.578353)
			(xy 40.089846 -279.568509) (xy 40.04383 -279.551057) (xy 40.001209 -279.52645) (xy 39.963088 -279.495325)
			(xy 39.930453 -279.458488) (xy 39.90415 -279.416892) (xy 39.884859 -279.371616) (xy 39.873082 -279.323832)
			(xy 39.869122 -279.274778) (xy 39.530274 -279.274778) (xy 39.529779 -279.299385) (xy 39.521884 -279.347962)
			(xy 39.5063 -279.394643) (xy 39.483429 -279.43822) (xy 39.453864 -279.477564) (xy 39.418371 -279.511656)
			(xy 39.377868 -279.539612) (xy 39.333406 -279.56071) (xy 39.286135 -279.574402) (xy 39.23728 -279.580334)
			(xy 39.188105 -279.578353) (xy 39.139886 -279.568509) (xy 39.09387 -279.551057) (xy 39.051249 -279.52645)
			(xy 39.013128 -279.495325) (xy 38.980493 -279.458488) (xy 38.95419 -279.416892) (xy 38.934899 -279.371616)
			(xy 38.923122 -279.323832) (xy 38.919162 -279.274778) (xy 38.580314 -279.274778) (xy 38.579819 -279.299385)
			(xy 38.571924 -279.347962) (xy 38.55634 -279.394643) (xy 38.533469 -279.43822) (xy 38.503904 -279.477564)
			(xy 38.468411 -279.511656) (xy 38.427908 -279.539612) (xy 38.383446 -279.56071) (xy 38.336175 -279.574402)
			(xy 38.28732 -279.580334) (xy 38.238145 -279.578353) (xy 38.189926 -279.568509) (xy 38.14391 -279.551057)
			(xy 38.101289 -279.52645) (xy 38.063168 -279.495325) (xy 38.030533 -279.458488) (xy 38.00423 -279.416892)
			(xy 37.984939 -279.371616) (xy 37.973162 -279.323832) (xy 37.969202 -279.274778) (xy 37.6301 -279.274778)
			(xy 37.629605 -279.299385) (xy 37.62171 -279.347962) (xy 37.606126 -279.394643) (xy 37.583255 -279.43822)
			(xy 37.55369 -279.477564) (xy 37.518197 -279.511656) (xy 37.477694 -279.539612) (xy 37.433232 -279.56071)
			(xy 37.385961 -279.574402) (xy 37.337106 -279.580334) (xy 37.287931 -279.578353) (xy 37.239712 -279.568509)
			(xy 37.193696 -279.551057) (xy 37.151075 -279.52645) (xy 37.112954 -279.495325) (xy 37.080319 -279.458488)
			(xy 37.054016 -279.416892) (xy 37.034725 -279.371616) (xy 37.022948 -279.323832) (xy 37.018988 -279.274778)
			(xy 36.68014 -279.274778) (xy 36.679645 -279.299385) (xy 36.67175 -279.347962) (xy 36.656166 -279.394643)
			(xy 36.633295 -279.43822) (xy 36.60373 -279.477564) (xy 36.568237 -279.511656) (xy 36.527734 -279.539612)
			(xy 36.483272 -279.56071) (xy 36.436001 -279.574402) (xy 36.387146 -279.580334) (xy 36.337971 -279.578353)
			(xy 36.289752 -279.568509) (xy 36.243736 -279.551057) (xy 36.201115 -279.52645) (xy 36.162994 -279.495325)
			(xy 36.130359 -279.458488) (xy 36.104056 -279.416892) (xy 36.084765 -279.371616) (xy 36.072988 -279.323832)
			(xy 36.069028 -279.274778) (xy 7.729489 -279.274778) (xy 7.728649 -279.276542) (xy 7.697102 -279.323425)
			(xy 7.67842 -279.344628) (xy 7.671816 -279.35174) (xy 7.668514 -279.360376) (xy 7.666848 -279.364829)
			(xy 7.665056 -279.374165) (xy 7.664958 -279.378918) (xy 7.664958 -279.447498) (xy 7.665095 -279.452247)
			(xy 7.666886 -279.461576) (xy 7.668514 -279.46604) (xy 7.671816 -279.474676) (xy 7.67842 -279.481788)
			(xy 7.697095 -279.502995) (xy 7.728632 -279.54988) (xy 7.752909 -279.600904) (xy 7.769395 -279.654951)
			(xy 7.77773 -279.710837) (xy 7.778242 -279.73909) (xy 7.777713 -279.766339) (xy 7.769958 -279.820284)
			(xy 7.754606 -279.872576) (xy 7.731969 -279.92215) (xy 7.726209 -279.931114) (xy 25.811478 -279.931114)
			(xy 25.815549 -279.875492) (xy 25.827675 -279.821055) (xy 25.847598 -279.768964) (xy 25.874894 -279.720329)
			(xy 25.90898 -279.676186) (xy 25.949129 -279.637477) (xy 25.994487 -279.605026) (xy 26.044087 -279.579525)
			(xy 26.096871 -279.561518) (xy 26.151714 -279.551388) (xy 26.207448 -279.549351) (xy 26.262885 -279.555451)
			(xy 26.316842 -279.569557) (xy 26.368171 -279.591369) (xy 26.415777 -279.620423) (xy 26.458645 -279.656098)
			(xy 26.495862 -279.697635) (xy 26.526635 -279.744148) (xy 26.550307 -279.794645) (xy 26.566375 -279.848052)
			(xy 26.574495 -279.903228) (xy 26.575004 -279.931114) (xy 27.286964 -279.931114) (xy 27.291035 -279.875492)
			(xy 27.303161 -279.821055) (xy 27.323084 -279.768964) (xy 27.35038 -279.720329) (xy 27.384466 -279.676186)
			(xy 27.424615 -279.637477) (xy 27.469973 -279.605026) (xy 27.519573 -279.579525) (xy 27.572357 -279.561518)
			(xy 27.6272 -279.551388) (xy 27.682934 -279.549351) (xy 27.738371 -279.555451) (xy 27.792328 -279.569557)
			(xy 27.843657 -279.591369) (xy 27.891263 -279.620423) (xy 27.934131 -279.656098) (xy 27.971348 -279.697635)
			(xy 28.002121 -279.744148) (xy 28.025793 -279.794645) (xy 28.041861 -279.848052) (xy 28.049981 -279.903228)
			(xy 28.05049 -279.931114) (xy 28.175964 -279.931114) (xy 28.180035 -279.875492) (xy 28.192161 -279.821055)
			(xy 28.212084 -279.768964) (xy 28.23938 -279.720329) (xy 28.273466 -279.676186) (xy 28.313615 -279.637477)
			(xy 28.358973 -279.605026) (xy 28.408573 -279.579525) (xy 28.461357 -279.561518) (xy 28.5162 -279.551388)
			(xy 28.571934 -279.549351) (xy 28.627371 -279.555451) (xy 28.681328 -279.569557) (xy 28.732657 -279.591369)
			(xy 28.780263 -279.620423) (xy 28.823131 -279.656098) (xy 28.860348 -279.697635) (xy 28.891121 -279.744148)
			(xy 28.914793 -279.794645) (xy 28.930861 -279.848052) (xy 28.938981 -279.903228) (xy 28.93949 -279.931114)
			(xy 28.938981 -279.959) (xy 28.930861 -280.014176) (xy 28.914793 -280.067583) (xy 28.891121 -280.11808)
			(xy 28.860348 -280.164593) (xy 28.823131 -280.20613) (xy 28.780263 -280.241805) (xy 28.732657 -280.270859)
			(xy 28.681328 -280.292671) (xy 28.627371 -280.306777) (xy 28.571934 -280.312877) (xy 28.5162 -280.31084)
			(xy 28.461357 -280.30071) (xy 28.408573 -280.282703) (xy 28.358973 -280.257202) (xy 28.313615 -280.224751)
			(xy 28.273466 -280.186042) (xy 28.23938 -280.141899) (xy 28.212084 -280.093264) (xy 28.192161 -280.041173)
			(xy 28.180035 -279.986736) (xy 28.175964 -279.931114) (xy 28.05049 -279.931114) (xy 28.049981 -279.959)
			(xy 28.041861 -280.014176) (xy 28.025793 -280.067583) (xy 28.002121 -280.11808) (xy 27.971348 -280.164593)
			(xy 27.934131 -280.20613) (xy 27.891263 -280.241805) (xy 27.843657 -280.270859) (xy 27.792328 -280.292671)
			(xy 27.738371 -280.306777) (xy 27.682934 -280.312877) (xy 27.6272 -280.31084) (xy 27.572357 -280.30071)
			(xy 27.519573 -280.282703) (xy 27.469973 -280.257202) (xy 27.424615 -280.224751) (xy 27.384466 -280.186042)
			(xy 27.35038 -280.141899) (xy 27.323084 -280.093264) (xy 27.303161 -280.041173) (xy 27.291035 -279.986736)
			(xy 27.286964 -279.931114) (xy 26.575004 -279.931114) (xy 26.574495 -279.959) (xy 26.566375 -280.014176)
			(xy 26.550307 -280.067583) (xy 26.526635 -280.11808) (xy 26.495862 -280.164593) (xy 26.458645 -280.20613)
			(xy 26.415777 -280.241805) (xy 26.368171 -280.270859) (xy 26.316842 -280.292671) (xy 26.262885 -280.306777)
			(xy 26.207448 -280.312877) (xy 26.151714 -280.31084) (xy 26.096871 -280.30071) (xy 26.044087 -280.282703)
			(xy 25.994487 -280.257202) (xy 25.949129 -280.224751) (xy 25.90898 -280.186042) (xy 25.874894 -280.141899)
			(xy 25.847598 -280.093264) (xy 25.827675 -280.041173) (xy 25.815549 -279.986736) (xy 25.811478 -279.931114)
			(xy 7.726209 -279.931114) (xy 7.702507 -279.967999) (xy 7.66682 -280.009189) (xy 7.625634 -280.04488)
			(xy 7.579789 -280.074348) (xy 7.530217 -280.096991) (xy 7.477927 -280.112349) (xy 7.423983 -280.120109)
			(xy 7.396734 -280.120598) (xy 7.367994 -280.120115) (xy 7.311164 -280.111483) (xy 7.256273 -280.094423)
			(xy 7.204562 -280.069322) (xy 7.157201 -280.036749) (xy 7.135876 -280.017474) (xy 7.129018 -280.01087)
			(xy 7.119874 -280.007314) (xy 7.115407 -280.005699) (xy 7.10608 -280.003902) (xy 7.101332 -280.003758)
			(xy 7.031736 -280.003758) (xy 7.026983 -280.003862) (xy 7.017647 -280.005648) (xy 7.013194 -280.007314)
			(xy 7.00405 -280.01087) (xy 6.997192 -280.017474) (xy 6.975865 -280.036744) (xy 6.928502 -280.069309)
			(xy 6.876791 -280.0944) (xy 6.8219 -280.11145) (xy 6.765073 -280.120072) (xy 6.707595 -280.120072)
			(xy 6.650768 -280.11145) (xy 6.595877 -280.0944) (xy 6.544166 -280.069309) (xy 6.496803 -280.036744)
			(xy 6.475476 -280.017474) (xy 6.468618 -280.01087) (xy 6.459474 -280.007314) (xy 6.455007 -280.005699)
			(xy 6.44568 -280.003902) (xy 6.440932 -280.003758) (xy 6.371336 -280.003758) (xy 6.366583 -280.003862)
			(xy 6.357247 -280.005648) (xy 6.352794 -280.007314) (xy 6.34365 -280.01087) (xy 6.336792 -280.017474)
			(xy 6.315465 -280.036744) (xy 6.268102 -280.069309) (xy 6.216391 -280.0944) (xy 6.1615 -280.11145)
			(xy 6.104673 -280.120072) (xy 6.047195 -280.120072) (xy 5.990368 -280.11145) (xy 5.935477 -280.0944)
			(xy 5.883766 -280.069309) (xy 5.836403 -280.036744) (xy 5.815076 -280.017474) (xy 5.808218 -280.01087)
			(xy 5.799074 -280.007314) (xy 5.794607 -280.005699) (xy 5.78528 -280.003902) (xy 5.780532 -280.003758)
			(xy 5.710936 -280.003758) (xy 5.706183 -280.003862) (xy 5.696847 -280.005648) (xy 5.692394 -280.007314)
			(xy 5.68325 -280.01087) (xy 5.676392 -280.017474) (xy 5.655053 -280.036731) (xy 5.607694 -280.069298)
			(xy 5.555985 -280.094393) (xy 5.501097 -280.111447) (xy 5.444272 -280.120075) (xy 5.415534 -280.120598)
			(xy 5.388282 -280.120113) (xy 5.334331 -280.11236) (xy 5.282033 -280.097008) (xy 5.232452 -280.074369)
			(xy 5.186598 -280.044904) (xy 5.145405 -280.009212) (xy 5.109711 -279.968021) (xy 5.080243 -279.922169)
			(xy 5.0576 -279.87259) (xy 5.042245 -279.820293) (xy 5.034489 -279.766342) (xy 5.034026 -279.73909)
			(xy 1.420114 -279.73909) (xy 1.420114 -280.722651) (xy 9.692378 -280.722651) (xy 9.692378 -280.668149)
			(xy 9.700134 -280.614203) (xy 9.715488 -280.561909) (xy 9.738128 -280.512333) (xy 9.767593 -280.466483)
			(xy 9.803283 -280.425293) (xy 9.844472 -280.389602) (xy 9.890321 -280.360135) (xy 9.939896 -280.337493)
			(xy 9.992189 -280.322137) (xy 10.046135 -280.314379) (xy 10.073386 -280.313892) (xy 10.102124 -280.314426)
			(xy 10.158951 -280.323047) (xy 10.213842 -280.340094) (xy 10.265554 -280.365184) (xy 10.312917 -280.397746)
			(xy 10.334244 -280.417016) (xy 10.341102 -280.42362) (xy 10.350246 -280.427176) (xy 10.354712 -280.428796)
			(xy 10.36404 -280.43059) (xy 10.368788 -280.430732) (xy 10.438384 -280.430732) (xy 10.443137 -280.430627)
			(xy 10.452473 -280.428841) (xy 10.456926 -280.427176) (xy 10.46607 -280.42362) (xy 10.472928 -280.417016)
			(xy 10.494255 -280.397746) (xy 10.541618 -280.365181) (xy 10.593329 -280.34009) (xy 10.64822 -280.32304)
			(xy 10.705047 -280.314418) (xy 10.762525 -280.314418) (xy 10.819352 -280.32304) (xy 10.874243 -280.34009)
			(xy 10.925954 -280.365181) (xy 10.973317 -280.397746) (xy 10.994644 -280.417016) (xy 11.001502 -280.42362)
			(xy 11.010646 -280.427176) (xy 11.015112 -280.428796) (xy 11.02444 -280.43059) (xy 11.029188 -280.430732)
			(xy 11.098784 -280.430732) (xy 11.103537 -280.430627) (xy 11.112873 -280.428841) (xy 11.117326 -280.427176)
			(xy 11.12647 -280.42362) (xy 11.133328 -280.417016) (xy 11.154658 -280.397748) (xy 11.202019 -280.365182)
			(xy 11.25373 -280.34009) (xy 11.30862 -280.323038) (xy 11.365447 -280.314414) (xy 11.394186 -280.313892)
			(xy 11.42431 -280.31446) (xy 11.483807 -280.32394) (xy 11.541075 -280.342651) (xy 11.594692 -280.370128)
			(xy 11.643326 -280.405688) (xy 11.66495 -280.426668) (xy 11.670538 -280.431494) (xy 11.677271 -280.436175)
			(xy 11.692823 -280.441348) (xy 11.701018 -280.441654) (xy 11.773154 -280.441654) (xy 11.781345 -280.441315)
			(xy 11.79689 -280.436152) (xy 11.803634 -280.431494) (xy 11.809222 -280.426668) (xy 11.83087 -280.405712)
			(xy 11.879491 -280.370138) (xy 11.933102 -280.342652) (xy 11.990367 -280.323939) (xy 12.049863 -280.314463)
			(xy 12.079986 -280.313892) (xy 12.10724 -280.314354) (xy 12.161192 -280.32211) (xy 12.213491 -280.337465)
			(xy 12.263073 -280.360106) (xy 12.308928 -280.389574) (xy 12.350123 -280.425268) (xy 12.385818 -280.466461)
			(xy 12.415287 -280.512314) (xy 12.437931 -280.561895) (xy 12.453287 -280.614194) (xy 12.461045 -280.668147)
			(xy 12.461045 -280.72265) (xy 13.939778 -280.72265) (xy 13.939778 -280.66815) (xy 13.947534 -280.614204)
			(xy 13.962887 -280.561912) (xy 13.985527 -280.512336) (xy 14.01499 -280.466487) (xy 14.050679 -280.425298)
			(xy 14.091866 -280.389606) (xy 14.137713 -280.360139) (xy 14.187287 -280.337496) (xy 14.239579 -280.322139)
			(xy 14.293524 -280.31438) (xy 14.320774 -280.313892) (xy 14.349512 -280.314434) (xy 14.406339 -280.323052)
			(xy 14.461229 -280.340098) (xy 14.512941 -280.365186) (xy 14.560305 -280.397747) (xy 14.581632 -280.417016)
			(xy 14.58849 -280.42362) (xy 14.597634 -280.427176) (xy 14.602101 -280.428793) (xy 14.611428 -280.430589)
			(xy 14.616176 -280.430732) (xy 14.685772 -280.430732) (xy 14.690525 -280.430624) (xy 14.699861 -280.42884)
			(xy 14.704314 -280.427176) (xy 14.713458 -280.42362) (xy 14.720316 -280.417016) (xy 14.741643 -280.397746)
			(xy 14.789006 -280.365181) (xy 14.840717 -280.34009) (xy 14.895608 -280.32304) (xy 14.952435 -280.314418)
			(xy 15.009913 -280.314418) (xy 15.06674 -280.32304) (xy 15.121631 -280.34009) (xy 15.173342 -280.365181)
			(xy 15.220705 -280.397746) (xy 15.242032 -280.417016) (xy 15.24889 -280.42362) (xy 15.258034 -280.427176)
			(xy 15.262501 -280.428793) (xy 15.271828 -280.430589) (xy 15.276576 -280.430732) (xy 15.346172 -280.430732)
			(xy 15.350925 -280.430624) (xy 15.360261 -280.42884) (xy 15.364714 -280.427176) (xy 15.373858 -280.42362)
			(xy 15.380716 -280.417016) (xy 15.40205 -280.397754) (xy 15.449411 -280.365187) (xy 15.501121 -280.340094)
			(xy 15.55601 -280.323041) (xy 15.612836 -280.314415) (xy 15.641574 -280.313892) (xy 15.671697 -280.314467)
			(xy 15.731194 -280.323945) (xy 15.788462 -280.342655) (xy 15.84208 -280.37013) (xy 15.890713 -280.405689)
			(xy 15.912338 -280.426668) (xy 15.917926 -280.431494) (xy 15.924661 -280.436171) (xy 15.940212 -280.441347)
			(xy 15.948406 -280.441654) (xy 16.020542 -280.441654) (xy 16.028736 -280.441353) (xy 16.044282 -280.436164)
			(xy 16.051022 -280.431494) (xy 16.05661 -280.426668) (xy 16.078219 -280.40567) (xy 16.126851 -280.370101)
			(xy 16.180471 -280.342623) (xy 16.237745 -280.32392) (xy 16.297248 -280.314456) (xy 16.327374 -280.313892)
			(xy 16.354628 -280.314354) (xy 16.408582 -280.322108) (xy 16.460883 -280.337461) (xy 16.510466 -280.360102)
			(xy 16.556323 -280.38957) (xy 16.597518 -280.425263) (xy 16.633215 -280.466457) (xy 16.662685 -280.512311)
			(xy 16.68533 -280.561893) (xy 16.700687 -280.614193) (xy 16.708445 -280.668146) (xy 16.708445 -280.693114)
			(xy 31.338012 -280.693114) (xy 31.338555 -280.663732) (xy 31.347584 -280.605665) (xy 31.365415 -280.54967)
			(xy 31.391626 -280.497075) (xy 31.425597 -280.449124) (xy 31.466521 -280.406952) (xy 31.48965 -280.388822)
			(xy 31.498575 -280.381343) (xy 31.509034 -280.360568) (xy 31.509716 -280.348944) (xy 31.510986 -280.262838)
			(xy 31.508446 -280.251662) (xy 31.50616 -280.246582) (xy 31.503553 -280.241399) (xy 31.496365 -280.232296)
			(xy 31.491936 -280.228548) (xy 31.470088 -280.210342) (xy 31.431546 -280.168524) (xy 31.399638 -280.121449)
			(xy 31.375071 -280.070159) (xy 31.358388 -280.015791) (xy 31.34996 -279.959549) (xy 31.349442 -279.931114)
			(xy 31.349928 -279.903863) (xy 31.357684 -279.849915) (xy 31.373039 -279.79762) (xy 31.395681 -279.748043)
			(xy 31.425147 -279.702193) (xy 31.460838 -279.661002) (xy 31.502029 -279.625311) (xy 31.547879 -279.595845)
			(xy 31.597456 -279.573203) (xy 31.649751 -279.557848) (xy 31.703699 -279.550092) (xy 31.758201 -279.550092)
			(xy 31.812149 -279.557848) (xy 31.864444 -279.573203) (xy 31.914021 -279.595845) (xy 31.959871 -279.625311)
			(xy 32.001062 -279.661002) (xy 32.036753 -279.702193) (xy 32.066219 -279.748043) (xy 32.088861 -279.79762)
			(xy 32.104216 -279.849915) (xy 32.111972 -279.903863) (xy 32.112458 -279.931114) (xy 32.111907 -279.960496)
			(xy 32.102876 -280.018561) (xy 32.085044 -280.074554) (xy 32.058835 -280.127149) (xy 32.024867 -280.1751)
			(xy 31.983946 -280.217274) (xy 31.974426 -280.224738) (xy 36.069028 -280.224738) (xy 36.072988 -280.175684)
			(xy 36.084765 -280.1279) (xy 36.104056 -280.082624) (xy 36.130359 -280.041028) (xy 36.162994 -280.004191)
			(xy 36.201115 -279.973066) (xy 36.243736 -279.948459) (xy 36.289752 -279.931007) (xy 36.337971 -279.921163)
			(xy 36.387146 -279.919182) (xy 36.436001 -279.925114) (xy 36.483272 -279.938806) (xy 36.527734 -279.959904)
			(xy 36.568237 -279.98786) (xy 36.60373 -280.021952) (xy 36.633295 -280.061296) (xy 36.656166 -280.104873)
			(xy 36.67175 -280.151554) (xy 36.679645 -280.200131) (xy 36.68014 -280.224738) (xy 37.018988 -280.224738)
			(xy 37.022948 -280.175684) (xy 37.034725 -280.1279) (xy 37.054016 -280.082624) (xy 37.080319 -280.041028)
			(xy 37.112954 -280.004191) (xy 37.151075 -279.973066) (xy 37.193696 -279.948459) (xy 37.239712 -279.931007)
			(xy 37.287931 -279.921163) (xy 37.337106 -279.919182) (xy 37.385961 -279.925114) (xy 37.433232 -279.938806)
			(xy 37.477694 -279.959904) (xy 37.518197 -279.98786) (xy 37.55369 -280.021952) (xy 37.583255 -280.061296)
			(xy 37.606126 -280.104873) (xy 37.62171 -280.151554) (xy 37.629605 -280.200131) (xy 37.6301 -280.224738)
			(xy 37.969202 -280.224738) (xy 37.973162 -280.175684) (xy 37.984939 -280.1279) (xy 38.00423 -280.082624)
			(xy 38.030533 -280.041028) (xy 38.063168 -280.004191) (xy 38.101289 -279.973066) (xy 38.14391 -279.948459)
			(xy 38.189926 -279.931007) (xy 38.238145 -279.921163) (xy 38.28732 -279.919182) (xy 38.336175 -279.925114)
			(xy 38.383446 -279.938806) (xy 38.427908 -279.959904) (xy 38.468411 -279.98786) (xy 38.503904 -280.021952)
			(xy 38.533469 -280.061296) (xy 38.55634 -280.104873) (xy 38.571924 -280.151554) (xy 38.579819 -280.200131)
			(xy 38.580314 -280.224738) (xy 38.919162 -280.224738) (xy 38.923122 -280.175684) (xy 38.934899 -280.1279)
			(xy 38.95419 -280.082624) (xy 38.980493 -280.041028) (xy 39.013128 -280.004191) (xy 39.051249 -279.973066)
			(xy 39.09387 -279.948459) (xy 39.139886 -279.931007) (xy 39.188105 -279.921163) (xy 39.23728 -279.919182)
			(xy 39.286135 -279.925114) (xy 39.333406 -279.938806) (xy 39.377868 -279.959904) (xy 39.418371 -279.98786)
			(xy 39.453864 -280.021952) (xy 39.483429 -280.061296) (xy 39.5063 -280.104873) (xy 39.521884 -280.151554)
			(xy 39.529779 -280.200131) (xy 39.530274 -280.224738) (xy 39.869122 -280.224738) (xy 39.873082 -280.175684)
			(xy 39.884859 -280.1279) (xy 39.90415 -280.082624) (xy 39.930453 -280.041028) (xy 39.963088 -280.004191)
			(xy 40.001209 -279.973066) (xy 40.04383 -279.948459) (xy 40.089846 -279.931007) (xy 40.138065 -279.921163)
			(xy 40.18724 -279.919182) (xy 40.236095 -279.925114) (xy 40.283366 -279.938806) (xy 40.327828 -279.959904)
			(xy 40.368331 -279.98786) (xy 40.403824 -280.021952) (xy 40.433389 -280.061296) (xy 40.45626 -280.104873)
			(xy 40.471844 -280.151554) (xy 40.479739 -280.200131) (xy 40.480234 -280.224738) (xy 40.819082 -280.224738)
			(xy 40.823042 -280.175684) (xy 40.834819 -280.1279) (xy 40.85411 -280.082624) (xy 40.880413 -280.041028)
			(xy 40.913048 -280.004191) (xy 40.951169 -279.973066) (xy 40.99379 -279.948459) (xy 41.039806 -279.931007)
			(xy 41.088025 -279.921163) (xy 41.1372 -279.919182) (xy 41.186055 -279.925114) (xy 41.233326 -279.938806)
			(xy 41.277788 -279.959904) (xy 41.318291 -279.98786) (xy 41.353784 -280.021952) (xy 41.383349 -280.061296)
			(xy 41.40622 -280.104873) (xy 41.421804 -280.151554) (xy 41.429699 -280.200131) (xy 41.430194 -280.224738)
			(xy 41.769042 -280.224738) (xy 41.773002 -280.175684) (xy 41.784779 -280.1279) (xy 41.80407 -280.082624)
			(xy 41.830373 -280.041028) (xy 41.863008 -280.004191) (xy 41.901129 -279.973066) (xy 41.94375 -279.948459)
			(xy 41.989766 -279.931007) (xy 42.037985 -279.921163) (xy 42.08716 -279.919182) (xy 42.136015 -279.925114)
			(xy 42.183286 -279.938806) (xy 42.227748 -279.959904) (xy 42.268251 -279.98786) (xy 42.303744 -280.021952)
			(xy 42.333309 -280.061296) (xy 42.35618 -280.104873) (xy 42.371764 -280.151554) (xy 42.379659 -280.200131)
			(xy 42.380154 -280.224738) (xy 42.379659 -280.249345) (xy 42.371764 -280.297922) (xy 42.35618 -280.344603)
			(xy 42.333309 -280.38818) (xy 42.303744 -280.427524) (xy 42.268251 -280.461616) (xy 42.227748 -280.489572)
			(xy 42.183286 -280.51067) (xy 42.136015 -280.524362) (xy 42.08716 -280.530294) (xy 42.037985 -280.528313)
			(xy 41.989766 -280.518469) (xy 41.94375 -280.501017) (xy 41.901129 -280.47641) (xy 41.863008 -280.445285)
			(xy 41.830373 -280.408448) (xy 41.80407 -280.366852) (xy 41.784779 -280.321576) (xy 41.773002 -280.273792)
			(xy 41.769042 -280.224738) (xy 41.430194 -280.224738) (xy 41.429699 -280.249345) (xy 41.421804 -280.297922)
			(xy 41.40622 -280.344603) (xy 41.383349 -280.38818) (xy 41.353784 -280.427524) (xy 41.318291 -280.461616)
			(xy 41.277788 -280.489572) (xy 41.233326 -280.51067) (xy 41.186055 -280.524362) (xy 41.1372 -280.530294)
			(xy 41.088025 -280.528313) (xy 41.039806 -280.518469) (xy 40.99379 -280.501017) (xy 40.951169 -280.47641)
			(xy 40.913048 -280.445285) (xy 40.880413 -280.408448) (xy 40.85411 -280.366852) (xy 40.834819 -280.321576)
			(xy 40.823042 -280.273792) (xy 40.819082 -280.224738) (xy 40.480234 -280.224738) (xy 40.479739 -280.249345)
			(xy 40.471844 -280.297922) (xy 40.45626 -280.344603) (xy 40.433389 -280.38818) (xy 40.403824 -280.427524)
			(xy 40.368331 -280.461616) (xy 40.327828 -280.489572) (xy 40.283366 -280.51067) (xy 40.236095 -280.524362)
			(xy 40.18724 -280.530294) (xy 40.138065 -280.528313) (xy 40.089846 -280.518469) (xy 40.04383 -280.501017)
			(xy 40.001209 -280.47641) (xy 39.963088 -280.445285) (xy 39.930453 -280.408448) (xy 39.90415 -280.366852)
			(xy 39.884859 -280.321576) (xy 39.873082 -280.273792) (xy 39.869122 -280.224738) (xy 39.530274 -280.224738)
			(xy 39.529779 -280.249345) (xy 39.521884 -280.297922) (xy 39.5063 -280.344603) (xy 39.483429 -280.38818)
			(xy 39.453864 -280.427524) (xy 39.418371 -280.461616) (xy 39.377868 -280.489572) (xy 39.333406 -280.51067)
			(xy 39.286135 -280.524362) (xy 39.23728 -280.530294) (xy 39.188105 -280.528313) (xy 39.139886 -280.518469)
			(xy 39.09387 -280.501017) (xy 39.051249 -280.47641) (xy 39.013128 -280.445285) (xy 38.980493 -280.408448)
			(xy 38.95419 -280.366852) (xy 38.934899 -280.321576) (xy 38.923122 -280.273792) (xy 38.919162 -280.224738)
			(xy 38.580314 -280.224738) (xy 38.579819 -280.249345) (xy 38.571924 -280.297922) (xy 38.55634 -280.344603)
			(xy 38.533469 -280.38818) (xy 38.503904 -280.427524) (xy 38.468411 -280.461616) (xy 38.427908 -280.489572)
			(xy 38.383446 -280.51067) (xy 38.336175 -280.524362) (xy 38.28732 -280.530294) (xy 38.238145 -280.528313)
			(xy 38.189926 -280.518469) (xy 38.14391 -280.501017) (xy 38.101289 -280.47641) (xy 38.063168 -280.445285)
			(xy 38.030533 -280.408448) (xy 38.00423 -280.366852) (xy 37.984939 -280.321576) (xy 37.973162 -280.273792)
			(xy 37.969202 -280.224738) (xy 37.6301 -280.224738) (xy 37.629605 -280.249345) (xy 37.62171 -280.297922)
			(xy 37.606126 -280.344603) (xy 37.583255 -280.38818) (xy 37.55369 -280.427524) (xy 37.518197 -280.461616)
			(xy 37.477694 -280.489572) (xy 37.433232 -280.51067) (xy 37.385961 -280.524362) (xy 37.337106 -280.530294)
			(xy 37.287931 -280.528313) (xy 37.239712 -280.518469) (xy 37.193696 -280.501017) (xy 37.151075 -280.47641)
			(xy 37.112954 -280.445285) (xy 37.080319 -280.408448) (xy 37.054016 -280.366852) (xy 37.034725 -280.321576)
			(xy 37.022948 -280.273792) (xy 37.018988 -280.224738) (xy 36.68014 -280.224738) (xy 36.679645 -280.249345)
			(xy 36.67175 -280.297922) (xy 36.656166 -280.344603) (xy 36.633295 -280.38818) (xy 36.60373 -280.427524)
			(xy 36.568237 -280.461616) (xy 36.527734 -280.489572) (xy 36.483272 -280.51067) (xy 36.436001 -280.524362)
			(xy 36.387146 -280.530294) (xy 36.337971 -280.528313) (xy 36.289752 -280.518469) (xy 36.243736 -280.501017)
			(xy 36.201115 -280.47641) (xy 36.162994 -280.445285) (xy 36.130359 -280.408448) (xy 36.104056 -280.366852)
			(xy 36.084765 -280.321576) (xy 36.072988 -280.273792) (xy 36.069028 -280.224738) (xy 31.974426 -280.224738)
			(xy 31.96082 -280.235406) (xy 31.951877 -280.242867) (xy 31.94143 -280.263656) (xy 31.940754 -280.275284)
			(xy 31.939484 -280.36139) (xy 31.942024 -280.372566) (xy 31.94431 -280.377646) (xy 31.946917 -280.382829)
			(xy 31.954106 -280.391932) (xy 31.958534 -280.39568) (xy 31.980362 -280.413909) (xy 32.018902 -280.455724)
			(xy 32.05081 -280.502795) (xy 32.07538 -280.55408) (xy 32.092068 -280.608443) (xy 32.100505 -280.664681)
			(xy 32.101028 -280.693114) (xy 32.734502 -280.693114) (xy 32.738573 -280.637492) (xy 32.750699 -280.583055)
			(xy 32.770622 -280.530964) (xy 32.797918 -280.482329) (xy 32.832004 -280.438186) (xy 32.872153 -280.399477)
			(xy 32.917511 -280.367026) (xy 32.967111 -280.341525) (xy 33.019895 -280.323518) (xy 33.074738 -280.313388)
			(xy 33.130472 -280.311351) (xy 33.185909 -280.317451) (xy 33.239866 -280.331557) (xy 33.291195 -280.353369)
			(xy 33.338801 -280.382423) (xy 33.381669 -280.418098) (xy 33.418886 -280.459635) (xy 33.449659 -280.506148)
			(xy 33.473331 -280.556645) (xy 33.489399 -280.610052) (xy 33.497519 -280.665228) (xy 33.498028 -280.693114)
			(xy 33.620962 -280.693114) (xy 33.625033 -280.637492) (xy 33.637159 -280.583055) (xy 33.657082 -280.530964)
			(xy 33.684378 -280.482329) (xy 33.718464 -280.438186) (xy 33.758613 -280.399477) (xy 33.803971 -280.367026)
			(xy 33.853571 -280.341525) (xy 33.906355 -280.323518) (xy 33.961198 -280.313388) (xy 34.016932 -280.311351)
			(xy 34.072369 -280.317451) (xy 34.126326 -280.331557) (xy 34.177655 -280.353369) (xy 34.225261 -280.382423)
			(xy 34.268129 -280.418098) (xy 34.305346 -280.459635) (xy 34.336119 -280.506148) (xy 34.359791 -280.556645)
			(xy 34.375859 -280.610052) (xy 34.383979 -280.665228) (xy 34.384488 -280.693114) (xy 34.383979 -280.721)
			(xy 34.375859 -280.776176) (xy 34.359791 -280.829583) (xy 34.336119 -280.88008) (xy 34.305346 -280.926593)
			(xy 34.268129 -280.96813) (xy 34.225261 -281.003805) (xy 34.177655 -281.032859) (xy 34.126326 -281.054671)
			(xy 34.072369 -281.068777) (xy 34.016932 -281.074877) (xy 33.961198 -281.07284) (xy 33.906355 -281.06271)
			(xy 33.853571 -281.044703) (xy 33.803971 -281.019202) (xy 33.758613 -280.986751) (xy 33.718464 -280.948042)
			(xy 33.684378 -280.903899) (xy 33.657082 -280.855264) (xy 33.637159 -280.803173) (xy 33.625033 -280.748736)
			(xy 33.620962 -280.693114) (xy 33.498028 -280.693114) (xy 33.497519 -280.721) (xy 33.489399 -280.776176)
			(xy 33.473331 -280.829583) (xy 33.449659 -280.88008) (xy 33.418886 -280.926593) (xy 33.381669 -280.96813)
			(xy 33.338801 -281.003805) (xy 33.291195 -281.032859) (xy 33.239866 -281.054671) (xy 33.185909 -281.068777)
			(xy 33.130472 -281.074877) (xy 33.074738 -281.07284) (xy 33.019895 -281.06271) (xy 32.967111 -281.044703)
			(xy 32.917511 -281.019202) (xy 32.872153 -280.986751) (xy 32.832004 -280.948042) (xy 32.797918 -280.903899)
			(xy 32.770622 -280.855264) (xy 32.750699 -280.803173) (xy 32.738573 -280.748736) (xy 32.734502 -280.693114)
			(xy 32.101028 -280.693114) (xy 32.100542 -280.720365) (xy 32.092786 -280.774313) (xy 32.077431 -280.826608)
			(xy 32.054789 -280.876185) (xy 32.025323 -280.922035) (xy 31.989632 -280.963226) (xy 31.948441 -280.998917)
			(xy 31.902591 -281.028383) (xy 31.853014 -281.051025) (xy 31.800719 -281.06638) (xy 31.746771 -281.074136)
			(xy 31.692269 -281.074136) (xy 31.638321 -281.06638) (xy 31.586026 -281.051025) (xy 31.536449 -281.028383)
			(xy 31.490599 -280.998917) (xy 31.449408 -280.963226) (xy 31.413717 -280.922035) (xy 31.384251 -280.876185)
			(xy 31.361609 -280.826608) (xy 31.346254 -280.774313) (xy 31.338498 -280.720365) (xy 31.338012 -280.693114)
			(xy 16.708445 -280.693114) (xy 16.708445 -280.722654) (xy 16.700687 -280.776607) (xy 16.68533 -280.828907)
			(xy 16.662685 -280.878489) (xy 16.633215 -280.924343) (xy 16.597518 -280.965537) (xy 16.556323 -281.00123)
			(xy 16.510466 -281.030698) (xy 16.460883 -281.053339) (xy 16.408582 -281.068692) (xy 16.354628 -281.076446)
			(xy 16.327374 -281.076908) (xy 16.297249 -281.076366) (xy 16.237751 -281.06688) (xy 16.180482 -281.048163)
			(xy 16.126866 -281.02068) (xy 16.078233 -280.985115) (xy 16.05661 -280.964132) (xy 16.051022 -280.959306)
			(xy 16.044275 -280.954649) (xy 16.028734 -280.949461) (xy 16.020542 -280.949146) (xy 15.948406 -280.949146)
			(xy 15.940214 -280.949468) (xy 15.924668 -280.954642) (xy 15.917926 -280.959306) (xy 15.912338 -280.964132)
			(xy 15.890708 -280.985107) (xy 15.842082 -281.020678) (xy 15.788467 -281.048161) (xy 15.731197 -281.06687)
			(xy 15.671698 -281.07634) (xy 15.641574 -281.076908) (xy 15.612835 -281.076398) (xy 15.556007 -281.067772)
			(xy 15.501116 -281.050718) (xy 15.449404 -281.025624) (xy 15.402042 -280.993056) (xy 15.380716 -280.973784)
			(xy 15.373858 -280.96718) (xy 15.364714 -280.963624) (xy 15.360251 -280.961994) (xy 15.350921 -280.960207)
			(xy 15.346172 -280.960068) (xy 15.276576 -280.960068) (xy 15.271822 -280.960162) (xy 15.262486 -280.961956)
			(xy 15.258034 -280.963624) (xy 15.24889 -280.96718) (xy 15.242032 -280.973784) (xy 15.220705 -280.993054)
			(xy 15.173342 -281.025619) (xy 15.121631 -281.05071) (xy 15.06674 -281.06776) (xy 15.009913 -281.076382)
			(xy 14.952435 -281.076382) (xy 14.895608 -281.06776) (xy 14.840717 -281.05071) (xy 14.789006 -281.025619)
			(xy 14.741643 -280.993054) (xy 14.720316 -280.973784) (xy 14.713458 -280.96718) (xy 14.704314 -280.963624)
			(xy 14.699851 -280.961994) (xy 14.690521 -280.960207) (xy 14.685772 -280.960068) (xy 14.616176 -280.960068)
			(xy 14.611422 -280.960162) (xy 14.602086 -280.961956) (xy 14.597634 -280.963624) (xy 14.58849 -280.96718)
			(xy 14.581632 -280.973784) (xy 14.560319 -280.993071) (xy 14.512953 -281.025634) (xy 14.461237 -281.050723)
			(xy 14.406344 -281.06777) (xy 14.349514 -281.076389) (xy 14.320774 -281.076908) (xy 14.293524 -281.07642)
			(xy 14.239579 -281.068661) (xy 14.187287 -281.053304) (xy 14.137713 -281.030661) (xy 14.091866 -281.001194)
			(xy 14.050679 -280.965502) (xy 14.01499 -280.924313) (xy 13.985527 -280.878464) (xy 13.962887 -280.828888)
			(xy 13.947534 -280.776596) (xy 13.939778 -280.72265) (xy 12.461045 -280.72265) (xy 12.461045 -280.722653)
			(xy 12.453287 -280.776606) (xy 12.437931 -280.828905) (xy 12.415287 -280.878486) (xy 12.385818 -280.924339)
			(xy 12.350123 -280.965532) (xy 12.308928 -281.001226) (xy 12.263073 -281.030694) (xy 12.213491 -281.053335)
			(xy 12.161192 -281.06869) (xy 12.10724 -281.076446) (xy 12.079986 -281.076908) (xy 12.049862 -281.076358)
			(xy 11.990364 -281.066874) (xy 11.933095 -281.048159) (xy 11.879478 -281.020678) (xy 11.830845 -280.985114)
			(xy 11.809222 -280.964132) (xy 11.803634 -280.959306) (xy 11.796908 -280.954614) (xy 11.781351 -280.949447)
			(xy 11.773154 -280.949146) (xy 11.701018 -280.949146) (xy 11.692826 -280.949473) (xy 11.677281 -280.954644)
			(xy 11.670538 -280.959306) (xy 11.66495 -280.964132) (xy 11.643315 -280.985101) (xy 11.59469 -281.020673)
			(xy 11.541076 -281.048157) (xy 11.483808 -281.066867) (xy 11.42431 -281.076339) (xy 11.394186 -281.076908)
			(xy 11.365447 -281.076391) (xy 11.308619 -281.067766) (xy 11.253729 -281.050715) (xy 11.202017 -281.025622)
			(xy 11.154655 -280.993055) (xy 11.133328 -280.973784) (xy 11.12647 -280.96718) (xy 11.117326 -280.963624)
			(xy 11.112862 -280.961997) (xy 11.103533 -280.960208) (xy 11.098784 -280.960068) (xy 11.029188 -280.960068)
			(xy 11.024435 -280.960165) (xy 11.015098 -280.961957) (xy 11.010646 -280.963624) (xy 11.001502 -280.96718)
			(xy 10.994644 -280.973784) (xy 10.973317 -280.993054) (xy 10.925954 -281.025619) (xy 10.874243 -281.05071)
			(xy 10.819352 -281.06776) (xy 10.762525 -281.076382) (xy 10.705047 -281.076382) (xy 10.64822 -281.06776)
			(xy 10.593329 -281.05071) (xy 10.541618 -281.025619) (xy 10.494255 -280.993054) (xy 10.472928 -280.973784)
			(xy 10.46607 -280.96718) (xy 10.456926 -280.963624) (xy 10.452462 -280.961997) (xy 10.443133 -280.960208)
			(xy 10.438384 -280.960068) (xy 10.368788 -280.960068) (xy 10.364035 -280.960165) (xy 10.354698 -280.961957)
			(xy 10.350246 -280.963624) (xy 10.341102 -280.96718) (xy 10.334244 -280.973784) (xy 10.312926 -280.993065)
			(xy 10.265561 -281.025629) (xy 10.213847 -281.050719) (xy 10.158955 -281.067767) (xy 10.102126 -281.076388)
			(xy 10.073386 -281.076908) (xy 10.046135 -281.076421) (xy 9.992189 -281.068663) (xy 9.939896 -281.053307)
			(xy 9.890321 -281.030665) (xy 9.844472 -281.001198) (xy 9.803283 -280.965507) (xy 9.767593 -280.924317)
			(xy 9.738128 -280.878467) (xy 9.715488 -280.828891) (xy 9.700134 -280.776597) (xy 9.692378 -280.722651)
			(xy 1.420114 -280.722651) (xy 1.420114 -281.174952) (xy 36.069028 -281.174952) (xy 36.072988 -281.125898)
			(xy 36.084765 -281.078114) (xy 36.104056 -281.032838) (xy 36.130359 -280.991242) (xy 36.162994 -280.954405)
			(xy 36.201115 -280.92328) (xy 36.243736 -280.898673) (xy 36.289752 -280.881221) (xy 36.337971 -280.871377)
			(xy 36.387146 -280.869396) (xy 36.436001 -280.875328) (xy 36.483272 -280.88902) (xy 36.527734 -280.910118)
			(xy 36.568237 -280.938074) (xy 36.60373 -280.972166) (xy 36.633295 -281.01151) (xy 36.656166 -281.055087)
			(xy 36.67175 -281.101768) (xy 36.679645 -281.150345) (xy 36.68014 -281.174952) (xy 37.018988 -281.174952)
			(xy 37.022948 -281.125898) (xy 37.034725 -281.078114) (xy 37.054016 -281.032838) (xy 37.080319 -280.991242)
			(xy 37.112954 -280.954405) (xy 37.151075 -280.92328) (xy 37.193696 -280.898673) (xy 37.239712 -280.881221)
			(xy 37.287931 -280.871377) (xy 37.337106 -280.869396) (xy 37.385961 -280.875328) (xy 37.433232 -280.88902)
			(xy 37.477694 -280.910118) (xy 37.518197 -280.938074) (xy 37.55369 -280.972166) (xy 37.583255 -281.01151)
			(xy 37.606126 -281.055087) (xy 37.62171 -281.101768) (xy 37.629605 -281.150345) (xy 37.6301 -281.174952)
			(xy 37.969202 -281.174952) (xy 37.973162 -281.125898) (xy 37.984939 -281.078114) (xy 38.00423 -281.032838)
			(xy 38.030533 -280.991242) (xy 38.063168 -280.954405) (xy 38.101289 -280.92328) (xy 38.14391 -280.898673)
			(xy 38.189926 -280.881221) (xy 38.238145 -280.871377) (xy 38.28732 -280.869396) (xy 38.336175 -280.875328)
			(xy 38.383446 -280.88902) (xy 38.427908 -280.910118) (xy 38.468411 -280.938074) (xy 38.503904 -280.972166)
			(xy 38.533469 -281.01151) (xy 38.55634 -281.055087) (xy 38.571924 -281.101768) (xy 38.579819 -281.150345)
			(xy 38.580314 -281.174952) (xy 38.919162 -281.174952) (xy 38.923122 -281.125898) (xy 38.934899 -281.078114)
			(xy 38.95419 -281.032838) (xy 38.980493 -280.991242) (xy 39.013128 -280.954405) (xy 39.051249 -280.92328)
			(xy 39.09387 -280.898673) (xy 39.139886 -280.881221) (xy 39.188105 -280.871377) (xy 39.23728 -280.869396)
			(xy 39.286135 -280.875328) (xy 39.333406 -280.88902) (xy 39.377868 -280.910118) (xy 39.418371 -280.938074)
			(xy 39.453864 -280.972166) (xy 39.483429 -281.01151) (xy 39.5063 -281.055087) (xy 39.521884 -281.101768)
			(xy 39.529779 -281.150345) (xy 39.530274 -281.174952) (xy 39.869122 -281.174952) (xy 39.873082 -281.125898)
			(xy 39.884859 -281.078114) (xy 39.90415 -281.032838) (xy 39.930453 -280.991242) (xy 39.963088 -280.954405)
			(xy 40.001209 -280.92328) (xy 40.04383 -280.898673) (xy 40.089846 -280.881221) (xy 40.138065 -280.871377)
			(xy 40.18724 -280.869396) (xy 40.236095 -280.875328) (xy 40.283366 -280.88902) (xy 40.327828 -280.910118)
			(xy 40.368331 -280.938074) (xy 40.403824 -280.972166) (xy 40.433389 -281.01151) (xy 40.45626 -281.055087)
			(xy 40.471844 -281.101768) (xy 40.479739 -281.150345) (xy 40.480234 -281.174952) (xy 40.819082 -281.174952)
			(xy 40.823042 -281.125898) (xy 40.834819 -281.078114) (xy 40.85411 -281.032838) (xy 40.880413 -280.991242)
			(xy 40.913048 -280.954405) (xy 40.951169 -280.92328) (xy 40.99379 -280.898673) (xy 41.039806 -280.881221)
			(xy 41.088025 -280.871377) (xy 41.1372 -280.869396) (xy 41.186055 -280.875328) (xy 41.233326 -280.88902)
			(xy 41.277788 -280.910118) (xy 41.318291 -280.938074) (xy 41.353784 -280.972166) (xy 41.383349 -281.01151)
			(xy 41.40622 -281.055087) (xy 41.421804 -281.101768) (xy 41.429699 -281.150345) (xy 41.430194 -281.174952)
			(xy 41.769042 -281.174952) (xy 41.773002 -281.125898) (xy 41.784779 -281.078114) (xy 41.80407 -281.032838)
			(xy 41.830373 -280.991242) (xy 41.863008 -280.954405) (xy 41.901129 -280.92328) (xy 41.94375 -280.898673)
			(xy 41.989766 -280.881221) (xy 42.037985 -280.871377) (xy 42.08716 -280.869396) (xy 42.136015 -280.875328)
			(xy 42.183286 -280.88902) (xy 42.227748 -280.910118) (xy 42.268251 -280.938074) (xy 42.303744 -280.972166)
			(xy 42.333309 -281.01151) (xy 42.35618 -281.055087) (xy 42.371764 -281.101768) (xy 42.379659 -281.150345)
			(xy 42.380154 -281.174952) (xy 42.719002 -281.174952) (xy 42.722962 -281.125898) (xy 42.734739 -281.078114)
			(xy 42.75403 -281.032838) (xy 42.780333 -280.991242) (xy 42.812968 -280.954405) (xy 42.851089 -280.92328)
			(xy 42.89371 -280.898673) (xy 42.939726 -280.881221) (xy 42.987945 -280.871377) (xy 43.03712 -280.869396)
			(xy 43.085975 -280.875328) (xy 43.133246 -280.88902) (xy 43.177708 -280.910118) (xy 43.218211 -280.938074)
			(xy 43.253704 -280.972166) (xy 43.283269 -281.01151) (xy 43.30614 -281.055087) (xy 43.321724 -281.101768)
			(xy 43.329619 -281.150345) (xy 43.330114 -281.174952) (xy 43.329619 -281.199559) (xy 43.321724 -281.248136)
			(xy 43.30614 -281.294817) (xy 43.283269 -281.338394) (xy 43.253704 -281.377738) (xy 43.218211 -281.41183)
			(xy 43.177708 -281.439786) (xy 43.133246 -281.460884) (xy 43.085975 -281.474576) (xy 43.03712 -281.480508)
			(xy 42.987945 -281.478527) (xy 42.939726 -281.468683) (xy 42.89371 -281.451231) (xy 42.851089 -281.426624)
			(xy 42.812968 -281.395499) (xy 42.780333 -281.358662) (xy 42.75403 -281.317066) (xy 42.734739 -281.27179)
			(xy 42.722962 -281.224006) (xy 42.719002 -281.174952) (xy 42.380154 -281.174952) (xy 42.379659 -281.199559)
			(xy 42.371764 -281.248136) (xy 42.35618 -281.294817) (xy 42.333309 -281.338394) (xy 42.303744 -281.377738)
			(xy 42.268251 -281.41183) (xy 42.227748 -281.439786) (xy 42.183286 -281.460884) (xy 42.136015 -281.474576)
			(xy 42.08716 -281.480508) (xy 42.037985 -281.478527) (xy 41.989766 -281.468683) (xy 41.94375 -281.451231)
			(xy 41.901129 -281.426624) (xy 41.863008 -281.395499) (xy 41.830373 -281.358662) (xy 41.80407 -281.317066)
			(xy 41.784779 -281.27179) (xy 41.773002 -281.224006) (xy 41.769042 -281.174952) (xy 41.430194 -281.174952)
			(xy 41.429699 -281.199559) (xy 41.421804 -281.248136) (xy 41.40622 -281.294817) (xy 41.383349 -281.338394)
			(xy 41.353784 -281.377738) (xy 41.318291 -281.41183) (xy 41.277788 -281.439786) (xy 41.233326 -281.460884)
			(xy 41.186055 -281.474576) (xy 41.1372 -281.480508) (xy 41.088025 -281.478527) (xy 41.039806 -281.468683)
			(xy 40.99379 -281.451231) (xy 40.951169 -281.426624) (xy 40.913048 -281.395499) (xy 40.880413 -281.358662)
			(xy 40.85411 -281.317066) (xy 40.834819 -281.27179) (xy 40.823042 -281.224006) (xy 40.819082 -281.174952)
			(xy 40.480234 -281.174952) (xy 40.479739 -281.199559) (xy 40.471844 -281.248136) (xy 40.45626 -281.294817)
			(xy 40.433389 -281.338394) (xy 40.403824 -281.377738) (xy 40.368331 -281.41183) (xy 40.327828 -281.439786)
			(xy 40.283366 -281.460884) (xy 40.236095 -281.474576) (xy 40.18724 -281.480508) (xy 40.138065 -281.478527)
			(xy 40.089846 -281.468683) (xy 40.04383 -281.451231) (xy 40.001209 -281.426624) (xy 39.963088 -281.395499)
			(xy 39.930453 -281.358662) (xy 39.90415 -281.317066) (xy 39.884859 -281.27179) (xy 39.873082 -281.224006)
			(xy 39.869122 -281.174952) (xy 39.530274 -281.174952) (xy 39.529779 -281.199559) (xy 39.521884 -281.248136)
			(xy 39.5063 -281.294817) (xy 39.483429 -281.338394) (xy 39.453864 -281.377738) (xy 39.418371 -281.41183)
			(xy 39.377868 -281.439786) (xy 39.333406 -281.460884) (xy 39.286135 -281.474576) (xy 39.23728 -281.480508)
			(xy 39.188105 -281.478527) (xy 39.139886 -281.468683) (xy 39.09387 -281.451231) (xy 39.051249 -281.426624)
			(xy 39.013128 -281.395499) (xy 38.980493 -281.358662) (xy 38.95419 -281.317066) (xy 38.934899 -281.27179)
			(xy 38.923122 -281.224006) (xy 38.919162 -281.174952) (xy 38.580314 -281.174952) (xy 38.579819 -281.199559)
			(xy 38.571924 -281.248136) (xy 38.55634 -281.294817) (xy 38.533469 -281.338394) (xy 38.503904 -281.377738)
			(xy 38.468411 -281.41183) (xy 38.427908 -281.439786) (xy 38.383446 -281.460884) (xy 38.336175 -281.474576)
			(xy 38.28732 -281.480508) (xy 38.238145 -281.478527) (xy 38.189926 -281.468683) (xy 38.14391 -281.451231)
			(xy 38.101289 -281.426624) (xy 38.063168 -281.395499) (xy 38.030533 -281.358662) (xy 38.00423 -281.317066)
			(xy 37.984939 -281.27179) (xy 37.973162 -281.224006) (xy 37.969202 -281.174952) (xy 37.6301 -281.174952)
			(xy 37.629605 -281.199559) (xy 37.62171 -281.248136) (xy 37.606126 -281.294817) (xy 37.583255 -281.338394)
			(xy 37.55369 -281.377738) (xy 37.518197 -281.41183) (xy 37.477694 -281.439786) (xy 37.433232 -281.460884)
			(xy 37.385961 -281.474576) (xy 37.337106 -281.480508) (xy 37.287931 -281.478527) (xy 37.239712 -281.468683)
			(xy 37.193696 -281.451231) (xy 37.151075 -281.426624) (xy 37.112954 -281.395499) (xy 37.080319 -281.358662)
			(xy 37.054016 -281.317066) (xy 37.034725 -281.27179) (xy 37.022948 -281.224006) (xy 37.018988 -281.174952)
			(xy 36.68014 -281.174952) (xy 36.679645 -281.199559) (xy 36.67175 -281.248136) (xy 36.656166 -281.294817)
			(xy 36.633295 -281.338394) (xy 36.60373 -281.377738) (xy 36.568237 -281.41183) (xy 36.527734 -281.439786)
			(xy 36.483272 -281.460884) (xy 36.436001 -281.474576) (xy 36.387146 -281.480508) (xy 36.337971 -281.478527)
			(xy 36.289752 -281.468683) (xy 36.243736 -281.451231) (xy 36.201115 -281.426624) (xy 36.162994 -281.395499)
			(xy 36.130359 -281.358662) (xy 36.104056 -281.317066) (xy 36.084765 -281.27179) (xy 36.072988 -281.224006)
			(xy 36.069028 -281.174952) (xy 1.420114 -281.174952) (xy 1.420114 -281.829256) (xy 25.811478 -281.829256)
			(xy 25.815549 -281.773634) (xy 25.827675 -281.719197) (xy 25.847598 -281.667106) (xy 25.874894 -281.618471)
			(xy 25.90898 -281.574328) (xy 25.949129 -281.535619) (xy 25.994487 -281.503168) (xy 26.044087 -281.477667)
			(xy 26.096871 -281.45966) (xy 26.151714 -281.44953) (xy 26.207448 -281.447493) (xy 26.262885 -281.453593)
			(xy 26.316842 -281.467699) (xy 26.368171 -281.489511) (xy 26.415777 -281.518565) (xy 26.458645 -281.55424)
			(xy 26.495862 -281.595777) (xy 26.526635 -281.64229) (xy 26.550307 -281.692787) (xy 26.566375 -281.746194)
			(xy 26.574495 -281.80137) (xy 26.575004 -281.829256) (xy 27.296616 -281.829256) (xy 27.300687 -281.773634)
			(xy 27.312813 -281.719197) (xy 27.332736 -281.667106) (xy 27.360032 -281.618471) (xy 27.394118 -281.574328)
			(xy 27.434267 -281.535619) (xy 27.479625 -281.503168) (xy 27.529225 -281.477667) (xy 27.582009 -281.45966)
			(xy 27.636852 -281.44953) (xy 27.692586 -281.447493) (xy 27.748023 -281.453593) (xy 27.80198 -281.467699)
			(xy 27.853309 -281.489511) (xy 27.900915 -281.518565) (xy 27.943783 -281.55424) (xy 27.981 -281.595777)
			(xy 28.011773 -281.64229) (xy 28.035445 -281.692787) (xy 28.051513 -281.746194) (xy 28.059633 -281.80137)
			(xy 28.060142 -281.829256) (xy 28.059633 -281.857142) (xy 28.051513 -281.912318) (xy 28.035445 -281.965725)
			(xy 28.011773 -282.016222) (xy 27.981 -282.062735) (xy 27.943783 -282.104272) (xy 27.918981 -282.124912)
			(xy 36.069028 -282.124912) (xy 36.072988 -282.075858) (xy 36.084765 -282.028074) (xy 36.104056 -281.982798)
			(xy 36.130359 -281.941202) (xy 36.162994 -281.904365) (xy 36.201115 -281.87324) (xy 36.243736 -281.848633)
			(xy 36.289752 -281.831181) (xy 36.337971 -281.821337) (xy 36.387146 -281.819356) (xy 36.436001 -281.825288)
			(xy 36.483272 -281.83898) (xy 36.527734 -281.860078) (xy 36.568237 -281.888034) (xy 36.60373 -281.922126)
			(xy 36.633295 -281.96147) (xy 36.656166 -282.005047) (xy 36.67175 -282.051728) (xy 36.679645 -282.100305)
			(xy 36.68014 -282.124912) (xy 37.018988 -282.124912) (xy 37.022948 -282.075858) (xy 37.034725 -282.028074)
			(xy 37.054016 -281.982798) (xy 37.080319 -281.941202) (xy 37.112954 -281.904365) (xy 37.151075 -281.87324)
			(xy 37.193696 -281.848633) (xy 37.239712 -281.831181) (xy 37.287931 -281.821337) (xy 37.337106 -281.819356)
			(xy 37.385961 -281.825288) (xy 37.433232 -281.83898) (xy 37.477694 -281.860078) (xy 37.518197 -281.888034)
			(xy 37.55369 -281.922126) (xy 37.583255 -281.96147) (xy 37.606126 -282.005047) (xy 37.62171 -282.051728)
			(xy 37.629605 -282.100305) (xy 37.6301 -282.124912) (xy 37.969202 -282.124912) (xy 37.973162 -282.075858)
			(xy 37.984939 -282.028074) (xy 38.00423 -281.982798) (xy 38.030533 -281.941202) (xy 38.063168 -281.904365)
			(xy 38.101289 -281.87324) (xy 38.14391 -281.848633) (xy 38.189926 -281.831181) (xy 38.238145 -281.821337)
			(xy 38.28732 -281.819356) (xy 38.336175 -281.825288) (xy 38.383446 -281.83898) (xy 38.427908 -281.860078)
			(xy 38.468411 -281.888034) (xy 38.503904 -281.922126) (xy 38.533469 -281.96147) (xy 38.55634 -282.005047)
			(xy 38.571924 -282.051728) (xy 38.579819 -282.100305) (xy 38.580314 -282.124912) (xy 38.919162 -282.124912)
			(xy 38.923122 -282.075858) (xy 38.934899 -282.028074) (xy 38.95419 -281.982798) (xy 38.980493 -281.941202)
			(xy 39.013128 -281.904365) (xy 39.051249 -281.87324) (xy 39.09387 -281.848633) (xy 39.139886 -281.831181)
			(xy 39.188105 -281.821337) (xy 39.23728 -281.819356) (xy 39.286135 -281.825288) (xy 39.333406 -281.83898)
			(xy 39.377868 -281.860078) (xy 39.418371 -281.888034) (xy 39.453864 -281.922126) (xy 39.483429 -281.96147)
			(xy 39.5063 -282.005047) (xy 39.521884 -282.051728) (xy 39.529779 -282.100305) (xy 39.530274 -282.124912)
			(xy 39.869122 -282.124912) (xy 39.873082 -282.075858) (xy 39.884859 -282.028074) (xy 39.90415 -281.982798)
			(xy 39.930453 -281.941202) (xy 39.963088 -281.904365) (xy 40.001209 -281.87324) (xy 40.04383 -281.848633)
			(xy 40.089846 -281.831181) (xy 40.138065 -281.821337) (xy 40.18724 -281.819356) (xy 40.236095 -281.825288)
			(xy 40.283366 -281.83898) (xy 40.327828 -281.860078) (xy 40.368331 -281.888034) (xy 40.403824 -281.922126)
			(xy 40.433389 -281.96147) (xy 40.45626 -282.005047) (xy 40.471844 -282.051728) (xy 40.479739 -282.100305)
			(xy 40.480234 -282.124912) (xy 40.819082 -282.124912) (xy 40.823042 -282.075858) (xy 40.834819 -282.028074)
			(xy 40.85411 -281.982798) (xy 40.880413 -281.941202) (xy 40.913048 -281.904365) (xy 40.951169 -281.87324)
			(xy 40.99379 -281.848633) (xy 41.039806 -281.831181) (xy 41.088025 -281.821337) (xy 41.1372 -281.819356)
			(xy 41.186055 -281.825288) (xy 41.233326 -281.83898) (xy 41.277788 -281.860078) (xy 41.318291 -281.888034)
			(xy 41.353784 -281.922126) (xy 41.383349 -281.96147) (xy 41.40622 -282.005047) (xy 41.421804 -282.051728)
			(xy 41.429699 -282.100305) (xy 41.430194 -282.124912) (xy 41.769042 -282.124912) (xy 41.773002 -282.075858)
			(xy 41.784779 -282.028074) (xy 41.80407 -281.982798) (xy 41.830373 -281.941202) (xy 41.863008 -281.904365)
			(xy 41.901129 -281.87324) (xy 41.94375 -281.848633) (xy 41.989766 -281.831181) (xy 42.037985 -281.821337)
			(xy 42.08716 -281.819356) (xy 42.136015 -281.825288) (xy 42.183286 -281.83898) (xy 42.227748 -281.860078)
			(xy 42.268251 -281.888034) (xy 42.303744 -281.922126) (xy 42.333309 -281.96147) (xy 42.35618 -282.005047)
			(xy 42.371764 -282.051728) (xy 42.379659 -282.100305) (xy 42.380154 -282.124912) (xy 42.719002 -282.124912)
			(xy 42.722962 -282.075858) (xy 42.734739 -282.028074) (xy 42.75403 -281.982798) (xy 42.780333 -281.941202)
			(xy 42.812968 -281.904365) (xy 42.851089 -281.87324) (xy 42.89371 -281.848633) (xy 42.939726 -281.831181)
			(xy 42.987945 -281.821337) (xy 43.03712 -281.819356) (xy 43.085975 -281.825288) (xy 43.133246 -281.83898)
			(xy 43.177708 -281.860078) (xy 43.218211 -281.888034) (xy 43.253704 -281.922126) (xy 43.283269 -281.96147)
			(xy 43.30614 -282.005047) (xy 43.321724 -282.051728) (xy 43.329619 -282.100305) (xy 43.330114 -282.124912)
			(xy 43.329619 -282.149519) (xy 43.321724 -282.198096) (xy 43.30614 -282.244777) (xy 43.283269 -282.288354)
			(xy 43.253704 -282.327698) (xy 43.218211 -282.36179) (xy 43.177708 -282.389746) (xy 43.133246 -282.410844)
			(xy 43.085975 -282.424536) (xy 43.03712 -282.430468) (xy 42.987945 -282.428487) (xy 42.939726 -282.418643)
			(xy 42.89371 -282.401191) (xy 42.851089 -282.376584) (xy 42.812968 -282.345459) (xy 42.780333 -282.308622)
			(xy 42.75403 -282.267026) (xy 42.734739 -282.22175) (xy 42.722962 -282.173966) (xy 42.719002 -282.124912)
			(xy 42.380154 -282.124912) (xy 42.379659 -282.149519) (xy 42.371764 -282.198096) (xy 42.35618 -282.244777)
			(xy 42.333309 -282.288354) (xy 42.303744 -282.327698) (xy 42.268251 -282.36179) (xy 42.227748 -282.389746)
			(xy 42.183286 -282.410844) (xy 42.136015 -282.424536) (xy 42.08716 -282.430468) (xy 42.037985 -282.428487)
			(xy 41.989766 -282.418643) (xy 41.94375 -282.401191) (xy 41.901129 -282.376584) (xy 41.863008 -282.345459)
			(xy 41.830373 -282.308622) (xy 41.80407 -282.267026) (xy 41.784779 -282.22175) (xy 41.773002 -282.173966)
			(xy 41.769042 -282.124912) (xy 41.430194 -282.124912) (xy 41.429699 -282.149519) (xy 41.421804 -282.198096)
			(xy 41.40622 -282.244777) (xy 41.383349 -282.288354) (xy 41.353784 -282.327698) (xy 41.318291 -282.36179)
			(xy 41.277788 -282.389746) (xy 41.233326 -282.410844) (xy 41.186055 -282.424536) (xy 41.1372 -282.430468)
			(xy 41.088025 -282.428487) (xy 41.039806 -282.418643) (xy 40.99379 -282.401191) (xy 40.951169 -282.376584)
			(xy 40.913048 -282.345459) (xy 40.880413 -282.308622) (xy 40.85411 -282.267026) (xy 40.834819 -282.22175)
			(xy 40.823042 -282.173966) (xy 40.819082 -282.124912) (xy 40.480234 -282.124912) (xy 40.479739 -282.149519)
			(xy 40.471844 -282.198096) (xy 40.45626 -282.244777) (xy 40.433389 -282.288354) (xy 40.403824 -282.327698)
			(xy 40.368331 -282.36179) (xy 40.327828 -282.389746) (xy 40.283366 -282.410844) (xy 40.236095 -282.424536)
			(xy 40.18724 -282.430468) (xy 40.138065 -282.428487) (xy 40.089846 -282.418643) (xy 40.04383 -282.401191)
			(xy 40.001209 -282.376584) (xy 39.963088 -282.345459) (xy 39.930453 -282.308622) (xy 39.90415 -282.267026)
			(xy 39.884859 -282.22175) (xy 39.873082 -282.173966) (xy 39.869122 -282.124912) (xy 39.530274 -282.124912)
			(xy 39.529779 -282.149519) (xy 39.521884 -282.198096) (xy 39.5063 -282.244777) (xy 39.483429 -282.288354)
			(xy 39.453864 -282.327698) (xy 39.418371 -282.36179) (xy 39.377868 -282.389746) (xy 39.333406 -282.410844)
			(xy 39.286135 -282.424536) (xy 39.23728 -282.430468) (xy 39.188105 -282.428487) (xy 39.139886 -282.418643)
			(xy 39.09387 -282.401191) (xy 39.051249 -282.376584) (xy 39.013128 -282.345459) (xy 38.980493 -282.308622)
			(xy 38.95419 -282.267026) (xy 38.934899 -282.22175) (xy 38.923122 -282.173966) (xy 38.919162 -282.124912)
			(xy 38.580314 -282.124912) (xy 38.579819 -282.149519) (xy 38.571924 -282.198096) (xy 38.55634 -282.244777)
			(xy 38.533469 -282.288354) (xy 38.503904 -282.327698) (xy 38.468411 -282.36179) (xy 38.427908 -282.389746)
			(xy 38.383446 -282.410844) (xy 38.336175 -282.424536) (xy 38.28732 -282.430468) (xy 38.238145 -282.428487)
			(xy 38.189926 -282.418643) (xy 38.14391 -282.401191) (xy 38.101289 -282.376584) (xy 38.063168 -282.345459)
			(xy 38.030533 -282.308622) (xy 38.00423 -282.267026) (xy 37.984939 -282.22175) (xy 37.973162 -282.173966)
			(xy 37.969202 -282.124912) (xy 37.6301 -282.124912) (xy 37.629605 -282.149519) (xy 37.62171 -282.198096)
			(xy 37.606126 -282.244777) (xy 37.583255 -282.288354) (xy 37.55369 -282.327698) (xy 37.518197 -282.36179)
			(xy 37.477694 -282.389746) (xy 37.433232 -282.410844) (xy 37.385961 -282.424536) (xy 37.337106 -282.430468)
			(xy 37.287931 -282.428487) (xy 37.239712 -282.418643) (xy 37.193696 -282.401191) (xy 37.151075 -282.376584)
			(xy 37.112954 -282.345459) (xy 37.080319 -282.308622) (xy 37.054016 -282.267026) (xy 37.034725 -282.22175)
			(xy 37.022948 -282.173966) (xy 37.018988 -282.124912) (xy 36.68014 -282.124912) (xy 36.679645 -282.149519)
			(xy 36.67175 -282.198096) (xy 36.656166 -282.244777) (xy 36.633295 -282.288354) (xy 36.60373 -282.327698)
			(xy 36.568237 -282.36179) (xy 36.527734 -282.389746) (xy 36.483272 -282.410844) (xy 36.436001 -282.424536)
			(xy 36.387146 -282.430468) (xy 36.337971 -282.428487) (xy 36.289752 -282.418643) (xy 36.243736 -282.401191)
			(xy 36.201115 -282.376584) (xy 36.162994 -282.345459) (xy 36.130359 -282.308622) (xy 36.104056 -282.267026)
			(xy 36.084765 -282.22175) (xy 36.072988 -282.173966) (xy 36.069028 -282.124912) (xy 27.918981 -282.124912)
			(xy 27.900915 -282.139947) (xy 27.853309 -282.169001) (xy 27.80198 -282.190813) (xy 27.748023 -282.204919)
			(xy 27.692586 -282.211019) (xy 27.636852 -282.208982) (xy 27.582009 -282.198852) (xy 27.529225 -282.180845)
			(xy 27.479625 -282.155344) (xy 27.434267 -282.122893) (xy 27.394118 -282.084184) (xy 27.360032 -282.040041)
			(xy 27.332736 -281.991406) (xy 27.312813 -281.939315) (xy 27.300687 -281.884878) (xy 27.296616 -281.829256)
			(xy 26.575004 -281.829256) (xy 26.574495 -281.857142) (xy 26.566375 -281.912318) (xy 26.550307 -281.965725)
			(xy 26.526635 -282.016222) (xy 26.495862 -282.062735) (xy 26.458645 -282.104272) (xy 26.415777 -282.139947)
			(xy 26.368171 -282.169001) (xy 26.316842 -282.190813) (xy 26.262885 -282.204919) (xy 26.207448 -282.211019)
			(xy 26.151714 -282.208982) (xy 26.096871 -282.198852) (xy 26.044087 -282.180845) (xy 25.994487 -282.155344)
			(xy 25.949129 -282.122893) (xy 25.90898 -282.084184) (xy 25.874894 -282.040041) (xy 25.847598 -281.991406)
			(xy 25.827675 -281.939315) (xy 25.815549 -281.884878) (xy 25.811478 -281.829256) (xy 1.420114 -281.829256)
			(xy 1.420114 -282.382031) (xy 1.86739 -282.382031) (xy 1.86739 -282.327529) (xy 1.875146 -282.273582)
			(xy 1.890501 -282.221287) (xy 1.913142 -282.171711) (xy 1.942608 -282.12586) (xy 1.978299 -282.084671)
			(xy 2.019489 -282.048979) (xy 2.065339 -282.019513) (xy 2.114916 -281.996872) (xy 2.16721 -281.981517)
			(xy 2.221157 -281.97376) (xy 2.248408 -281.973274) (xy 2.277147 -281.9738) (xy 2.333974 -281.982423)
			(xy 2.388864 -281.999473) (xy 2.440576 -282.024564) (xy 2.487939 -282.057128) (xy 2.509266 -282.076398)
			(xy 2.516124 -282.083002) (xy 2.525268 -282.086558) (xy 2.529732 -282.088183) (xy 2.539061 -282.089974)
			(xy 2.54381 -282.090114) (xy 2.613406 -282.090114) (xy 2.618159 -282.090016) (xy 2.627496 -282.088225)
			(xy 2.631948 -282.086558) (xy 2.641092 -282.083002) (xy 2.64795 -282.076398) (xy 2.669283 -282.057134)
			(xy 2.716642 -282.024564) (xy 2.768352 -281.99947) (xy 2.823242 -281.982418) (xy 2.880069 -281.973795)
			(xy 2.908808 -281.973274) (xy 2.938932 -281.973833) (xy 2.998429 -281.983316) (xy 3.055698 -282.002029)
			(xy 3.109314 -282.029508) (xy 3.157948 -282.065069) (xy 3.179572 -282.08605) (xy 3.18516 -282.090876)
			(xy 3.191888 -282.095564) (xy 3.207444 -282.100734) (xy 3.21564 -282.101036) (xy 3.287776 -282.101036)
			(xy 3.295968 -282.10071) (xy 3.311514 -282.095539) (xy 3.318256 -282.090876) (xy 3.323844 -282.08605)
			(xy 3.345479 -282.06508) (xy 3.394104 -282.029509) (xy 3.447718 -282.002026) (xy 3.504986 -281.983315)
			(xy 3.564484 -281.973843) (xy 3.594608 -281.973274) (xy 3.621979 -281.973717) (xy 3.67616 -281.981538)
			(xy 3.728664 -281.997031) (xy 3.778411 -282.019879) (xy 3.824376 -282.049609) (xy 3.845306 -282.067254)
			(xy 3.84556 -282.067508) (xy 3.852653 -282.073085) (xy 3.869565 -282.079337) (xy 3.87858 -282.0797)
			(xy 3.945636 -282.0797) (xy 3.954655 -282.07936) (xy 3.971571 -282.073101) (xy 3.978656 -282.067508)
			(xy 3.978656 -282.067254) (xy 3.97891 -282.067254) (xy 3.999834 -282.049605) (xy 4.045808 -282.019893)
			(xy 4.095558 -281.997058) (xy 4.148061 -281.981569) (xy 4.202238 -281.973745) (xy 4.229608 -281.973274)
			(xy 4.256861 -281.973733) (xy 4.310813 -281.98149) (xy 4.363111 -281.996846) (xy 4.412691 -282.019488)
			(xy 4.458545 -282.048957) (xy 4.499738 -282.08465) (xy 4.535432 -282.125843) (xy 4.564901 -282.171697)
			(xy 4.587543 -282.221277) (xy 4.6029 -282.273576) (xy 4.610657 -282.327527) (xy 4.610657 -282.382031)
			(xy 5.88618 -282.382031) (xy 5.88618 -282.327529) (xy 5.893936 -282.273582) (xy 5.909291 -282.221288)
			(xy 5.931932 -282.171711) (xy 5.961397 -282.125861) (xy 5.997088 -282.084671) (xy 6.038278 -282.04898)
			(xy 6.084128 -282.019514) (xy 6.133704 -281.996872) (xy 6.185998 -281.981517) (xy 6.239945 -281.97376)
			(xy 6.267196 -281.973274) (xy 6.295934 -281.973807) (xy 6.352761 -281.982428) (xy 6.407651 -281.999477)
			(xy 6.459363 -282.024566) (xy 6.506727 -282.057129) (xy 6.528054 -282.076398) (xy 6.534912 -282.083002)
			(xy 6.544056 -282.086558) (xy 6.548521 -282.08818) (xy 6.55785 -282.089972) (xy 6.562598 -282.090114)
			(xy 6.632194 -282.090114) (xy 6.636947 -282.090013) (xy 6.646283 -282.088224) (xy 6.650736 -282.086558)
			(xy 6.65988 -282.083002) (xy 6.666738 -282.076398) (xy 6.688065 -282.057128) (xy 6.735428 -282.024563)
			(xy 6.787139 -281.999472) (xy 6.84203 -281.982422) (xy 6.898857 -281.9738) (xy 6.956335 -281.9738)
			(xy 7.013162 -281.982422) (xy 7.068053 -281.999472) (xy 7.119764 -282.024563) (xy 7.167127 -282.057128)
			(xy 7.188454 -282.076398) (xy 7.195312 -282.083002) (xy 7.204456 -282.086558) (xy 7.208921 -282.08818)
			(xy 7.21825 -282.089972) (xy 7.222998 -282.090114) (xy 7.292594 -282.090114) (xy 7.297347 -282.090013)
			(xy 7.306683 -282.088224) (xy 7.311136 -282.086558) (xy 7.32028 -282.083002) (xy 7.327138 -282.076398)
			(xy 7.348476 -282.05714) (xy 7.395834 -282.024569) (xy 7.447543 -281.999474) (xy 7.502431 -281.98242)
			(xy 7.559258 -281.973796) (xy 7.587996 -281.973274) (xy 7.61812 -281.97384) (xy 7.677617 -281.983321)
			(xy 7.734885 -282.002033) (xy 7.788502 -282.02951) (xy 7.837136 -282.06507) (xy 7.85876 -282.08605)
			(xy 7.864348 -282.090876) (xy 7.871079 -282.09556) (xy 7.886632 -282.100732) (xy 7.894828 -282.101036)
			(xy 7.966964 -282.101036) (xy 7.975155 -282.100705) (xy 7.990701 -282.095537) (xy 7.997444 -282.090876)
			(xy 8.003032 -282.08605) (xy 8.024672 -282.065086) (xy 8.073296 -282.029514) (xy 8.126908 -282.00203)
			(xy 8.184175 -281.983318) (xy 8.243673 -281.973844) (xy 8.273796 -281.973274) (xy 8.301049 -281.973733)
			(xy 8.355001 -281.98149) (xy 8.407299 -281.996845) (xy 8.45688 -282.019488) (xy 8.502734 -282.048956)
			(xy 8.543928 -282.08465) (xy 8.579622 -282.125843) (xy 8.60909 -282.171696) (xy 8.631733 -282.221277)
			(xy 8.64709 -282.273575) (xy 8.654847 -282.327527) (xy 8.654847 -282.382033) (xy 8.64709 -282.435985)
			(xy 8.631733 -282.488283) (xy 8.60909 -282.537864) (xy 8.579622 -282.583717) (xy 8.543928 -282.62491)
			(xy 8.502734 -282.660604) (xy 8.45688 -282.690072) (xy 8.407299 -282.712715) (xy 8.355001 -282.72807)
			(xy 8.301049 -282.735827) (xy 8.273796 -282.73629) (xy 8.243672 -282.735739) (xy 8.184174 -282.726256)
			(xy 8.126905 -282.707541) (xy 8.073288 -282.68006) (xy 8.024656 -282.644496) (xy 8.003032 -282.623514)
			(xy 7.997444 -282.618688) (xy 7.99071 -282.614008) (xy 7.975159 -282.608832) (xy 7.966964 -282.608528)
			(xy 7.894828 -282.608528) (xy 7.886635 -282.608845) (xy 7.871089 -282.614021) (xy 7.864348 -282.618688)
			(xy 7.85876 -282.623514) (xy 7.837134 -282.644493) (xy 7.788505 -282.680061) (xy 7.734889 -282.707541)
			(xy 7.677619 -282.726249) (xy 7.61812 -282.735721) (xy 7.587996 -282.73629) (xy 7.559257 -282.735771)
			(xy 7.502429 -282.727148) (xy 7.447538 -282.710097) (xy 7.395827 -282.685004) (xy 7.348464 -282.652437)
			(xy 7.327138 -282.633166) (xy 7.32028 -282.626562) (xy 7.311136 -282.623006) (xy 7.306672 -282.621381)
			(xy 7.297343 -282.619591) (xy 7.292594 -282.61945) (xy 7.222998 -282.61945) (xy 7.218244 -282.619544)
			(xy 7.208908 -282.621337) (xy 7.204456 -282.623006) (xy 7.195312 -282.626562) (xy 7.188454 -282.633166)
			(xy 7.167127 -282.652436) (xy 7.119764 -282.685001) (xy 7.068053 -282.710092) (xy 7.013162 -282.727142)
			(xy 6.956335 -282.735764) (xy 6.898857 -282.735764) (xy 6.84203 -282.727142) (xy 6.787139 -282.710092)
			(xy 6.735428 -282.685001) (xy 6.688065 -282.652436) (xy 6.666738 -282.633166) (xy 6.65988 -282.626562)
			(xy 6.650736 -282.623006) (xy 6.646272 -282.621381) (xy 6.636943 -282.619591) (xy 6.632194 -282.61945)
			(xy 6.562598 -282.61945) (xy 6.557844 -282.619544) (xy 6.548508 -282.621337) (xy 6.544056 -282.623006)
			(xy 6.534912 -282.626562) (xy 6.528054 -282.633166) (xy 6.506729 -282.652439) (xy 6.459366 -282.685005)
			(xy 6.407654 -282.710097) (xy 6.352763 -282.727147) (xy 6.295935 -282.735769) (xy 6.267196 -282.73629)
			(xy 6.239945 -282.7358) (xy 6.185998 -282.728043) (xy 6.133704 -282.712688) (xy 6.084128 -282.690046)
			(xy 6.038278 -282.66058) (xy 5.997088 -282.624889) (xy 5.961397 -282.583699) (xy 5.931932 -282.537849)
			(xy 5.909291 -282.488272) (xy 5.893936 -282.435978) (xy 5.88618 -282.382031) (xy 4.610657 -282.382031)
			(xy 4.610657 -282.382033) (xy 4.6029 -282.435984) (xy 4.587543 -282.488283) (xy 4.564901 -282.537863)
			(xy 4.535432 -282.583717) (xy 4.499738 -282.62491) (xy 4.458545 -282.660603) (xy 4.412691 -282.690072)
			(xy 4.363111 -282.712714) (xy 4.310813 -282.72807) (xy 4.256861 -282.735827) (xy 4.229608 -282.73629)
			(xy 4.202238 -282.735822) (xy 4.148059 -282.728005) (xy 4.095556 -282.712516) (xy 4.045809 -282.689675)
			(xy 3.999842 -282.659951) (xy 3.97891 -282.64231) (xy 3.978656 -282.642056) (xy 3.971561 -282.636481)
			(xy 3.954651 -282.630229) (xy 3.945636 -282.629864) (xy 3.87858 -282.629864) (xy 3.869563 -282.630219)
			(xy 3.852646 -282.636469) (xy 3.84556 -282.642056) (xy 3.84556 -282.64231) (xy 3.845306 -282.64231)
			(xy 3.824384 -282.659961) (xy 3.778408 -282.689671) (xy 3.728658 -282.712504) (xy 3.676155 -282.727993)
			(xy 3.621978 -282.735818) (xy 3.594608 -282.73629) (xy 3.564484 -282.735731) (xy 3.504986 -282.72625)
			(xy 3.447717 -282.707537) (xy 3.394101 -282.680058) (xy 3.345468 -282.644495) (xy 3.323844 -282.623514)
			(xy 3.318256 -282.618688) (xy 3.31152 -282.614013) (xy 3.295971 -282.608834) (xy 3.287776 -282.608528)
			(xy 3.21564 -282.608528) (xy 3.207448 -282.60885) (xy 3.191901 -282.614023) (xy 3.18516 -282.618688)
			(xy 3.179572 -282.623514) (xy 3.157941 -282.644487) (xy 3.109313 -282.680056) (xy 3.055699 -282.707537)
			(xy 2.99843 -282.726247) (xy 2.938932 -282.73572) (xy 2.908808 -282.73629) (xy 2.880069 -282.735764)
			(xy 2.823242 -282.727142) (xy 2.768351 -282.710093) (xy 2.716639 -282.685002) (xy 2.669277 -282.652437)
			(xy 2.64795 -282.633166) (xy 2.641092 -282.626562) (xy 2.631948 -282.623006) (xy 2.627483 -282.621384)
			(xy 2.618154 -282.619592) (xy 2.613406 -282.61945) (xy 2.54381 -282.61945) (xy 2.539057 -282.619548)
			(xy 2.52972 -282.621338) (xy 2.525268 -282.623006) (xy 2.516124 -282.626562) (xy 2.509266 -282.633166)
			(xy 2.487936 -282.652434) (xy 2.440575 -282.685) (xy 2.388864 -282.710093) (xy 2.333974 -282.727145)
			(xy 2.277147 -282.735768) (xy 2.248408 -282.73629) (xy 2.221157 -282.7358) (xy 2.16721 -282.728043)
			(xy 2.114916 -282.712688) (xy 2.065339 -282.690047) (xy 2.019489 -282.660581) (xy 1.978299 -282.624889)
			(xy 1.942608 -282.5837) (xy 1.913142 -282.537849) (xy 1.890501 -282.488273) (xy 1.875146 -282.435978)
			(xy 1.86739 -282.382031) (xy 1.420114 -282.382031) (xy 1.420114 -283.186451) (xy 9.692378 -283.186451)
			(xy 9.692378 -283.131949) (xy 9.700134 -283.078003) (xy 9.715488 -283.025709) (xy 9.738128 -282.976133)
			(xy 9.767593 -282.930283) (xy 9.803283 -282.889093) (xy 9.844472 -282.853402) (xy 9.890321 -282.823935)
			(xy 9.939896 -282.801293) (xy 9.992189 -282.785937) (xy 10.046135 -282.778179) (xy 10.073386 -282.777692)
			(xy 10.102124 -282.778226) (xy 10.158951 -282.786847) (xy 10.213842 -282.803894) (xy 10.265554 -282.828984)
			(xy 10.312917 -282.861546) (xy 10.334244 -282.880816) (xy 10.341102 -282.88742) (xy 10.350246 -282.890976)
			(xy 10.354712 -282.892596) (xy 10.36404 -282.89439) (xy 10.368788 -282.894532) (xy 10.438384 -282.894532)
			(xy 10.443137 -282.894427) (xy 10.452473 -282.892641) (xy 10.456926 -282.890976) (xy 10.46607 -282.88742)
			(xy 10.472928 -282.880816) (xy 10.494255 -282.861546) (xy 10.541618 -282.828981) (xy 10.593329 -282.80389)
			(xy 10.64822 -282.78684) (xy 10.705047 -282.778218) (xy 10.762525 -282.778218) (xy 10.819352 -282.78684)
			(xy 10.874243 -282.80389) (xy 10.925954 -282.828981) (xy 10.973317 -282.861546) (xy 10.994644 -282.880816)
			(xy 11.001502 -282.88742) (xy 11.010646 -282.890976) (xy 11.015112 -282.892596) (xy 11.02444 -282.89439)
			(xy 11.029188 -282.894532) (xy 11.098784 -282.894532) (xy 11.103537 -282.894427) (xy 11.112873 -282.892641)
			(xy 11.117326 -282.890976) (xy 11.12647 -282.88742) (xy 11.133328 -282.880816) (xy 11.154658 -282.861548)
			(xy 11.202019 -282.828982) (xy 11.25373 -282.80389) (xy 11.30862 -282.786838) (xy 11.365447 -282.778214)
			(xy 11.394186 -282.777692) (xy 11.42431 -282.77826) (xy 11.483807 -282.78774) (xy 11.541075 -282.806451)
			(xy 11.594692 -282.833928) (xy 11.643326 -282.869488) (xy 11.66495 -282.890468) (xy 11.670538 -282.895294)
			(xy 11.677271 -282.899975) (xy 11.692823 -282.905148) (xy 11.701018 -282.905454) (xy 11.773154 -282.905454)
			(xy 11.781345 -282.905115) (xy 11.79689 -282.899952) (xy 11.803634 -282.895294) (xy 11.809222 -282.890468)
			(xy 11.83087 -282.869512) (xy 11.879491 -282.833938) (xy 11.933102 -282.806452) (xy 11.990367 -282.787739)
			(xy 12.049863 -282.778263) (xy 12.079986 -282.777692) (xy 12.10724 -282.778154) (xy 12.161192 -282.78591)
			(xy 12.213491 -282.801265) (xy 12.263073 -282.823906) (xy 12.308928 -282.853374) (xy 12.350123 -282.889068)
			(xy 12.385818 -282.930261) (xy 12.415287 -282.976114) (xy 12.437931 -283.025695) (xy 12.453287 -283.077994)
			(xy 12.461045 -283.131947) (xy 12.461045 -283.18645) (xy 13.965178 -283.18645) (xy 13.965178 -283.13195)
			(xy 13.972934 -283.078004) (xy 13.988287 -283.025712) (xy 14.010927 -282.976136) (xy 14.04039 -282.930287)
			(xy 14.076079 -282.889098) (xy 14.117266 -282.853406) (xy 14.163113 -282.823939) (xy 14.212687 -282.801296)
			(xy 14.264979 -282.785939) (xy 14.318924 -282.77818) (xy 14.346174 -282.777692) (xy 14.374912 -282.778234)
			(xy 14.431739 -282.786852) (xy 14.486629 -282.803898) (xy 14.538341 -282.828986) (xy 14.585705 -282.861547)
			(xy 14.607032 -282.880816) (xy 14.61389 -282.88742) (xy 14.623034 -282.890976) (xy 14.627501 -282.892593)
			(xy 14.636828 -282.894389) (xy 14.641576 -282.894532) (xy 14.711172 -282.894532) (xy 14.715925 -282.894424)
			(xy 14.725261 -282.89264) (xy 14.729714 -282.890976) (xy 14.738858 -282.88742) (xy 14.745716 -282.880816)
			(xy 14.767043 -282.861546) (xy 14.814406 -282.828981) (xy 14.866117 -282.80389) (xy 14.921008 -282.78684)
			(xy 14.977835 -282.778218) (xy 15.035313 -282.778218) (xy 15.09214 -282.78684) (xy 15.147031 -282.80389)
			(xy 15.198742 -282.828981) (xy 15.246105 -282.861546) (xy 15.267432 -282.880816) (xy 15.27429 -282.88742)
			(xy 15.283434 -282.890976) (xy 15.287901 -282.892593) (xy 15.297228 -282.894389) (xy 15.301976 -282.894532)
			(xy 15.371572 -282.894532) (xy 15.376325 -282.894424) (xy 15.385661 -282.89264) (xy 15.390114 -282.890976)
			(xy 15.399258 -282.88742) (xy 15.406116 -282.880816) (xy 15.42745 -282.861554) (xy 15.474811 -282.828987)
			(xy 15.526521 -282.803894) (xy 15.58141 -282.786841) (xy 15.638236 -282.778215) (xy 15.666974 -282.777692)
			(xy 15.697097 -282.778267) (xy 15.756594 -282.787745) (xy 15.813862 -282.806455) (xy 15.86748 -282.83393)
			(xy 15.916113 -282.869489) (xy 15.937738 -282.890468) (xy 15.943326 -282.895294) (xy 15.950061 -282.899971)
			(xy 15.965612 -282.905147) (xy 15.973806 -282.905454) (xy 16.045942 -282.905454) (xy 16.054136 -282.905153)
			(xy 16.069682 -282.899964) (xy 16.076422 -282.895294) (xy 16.08201 -282.890468) (xy 16.103619 -282.86947)
			(xy 16.152251 -282.833901) (xy 16.205871 -282.806423) (xy 16.263145 -282.78772) (xy 16.322648 -282.778256)
			(xy 16.352774 -282.777692) (xy 16.380028 -282.778154) (xy 16.433982 -282.785908) (xy 16.486283 -282.801261)
			(xy 16.535866 -282.823902) (xy 16.581723 -282.85337) (xy 16.622918 -282.889063) (xy 16.658615 -282.930257)
			(xy 16.688085 -282.976111) (xy 16.71073 -283.025693) (xy 16.726087 -283.077993) (xy 16.733783 -283.131514)
			(xy 25.811478 -283.131514) (xy 25.815549 -283.075892) (xy 25.827675 -283.021455) (xy 25.847598 -282.969364)
			(xy 25.874894 -282.920729) (xy 25.90898 -282.876586) (xy 25.949129 -282.837877) (xy 25.994487 -282.805426)
			(xy 26.044087 -282.779925) (xy 26.096871 -282.761918) (xy 26.151714 -282.751788) (xy 26.207448 -282.749751)
			(xy 26.262885 -282.755851) (xy 26.316842 -282.769957) (xy 26.368171 -282.791769) (xy 26.415777 -282.820823)
			(xy 26.458645 -282.856498) (xy 26.495862 -282.898035) (xy 26.526635 -282.944548) (xy 26.550307 -282.995045)
			(xy 26.566375 -283.048452) (xy 26.574495 -283.103628) (xy 26.575004 -283.131514) (xy 27.286964 -283.131514)
			(xy 27.291035 -283.075892) (xy 27.303161 -283.021455) (xy 27.323084 -282.969364) (xy 27.35038 -282.920729)
			(xy 27.384466 -282.876586) (xy 27.424615 -282.837877) (xy 27.469973 -282.805426) (xy 27.519573 -282.779925)
			(xy 27.572357 -282.761918) (xy 27.6272 -282.751788) (xy 27.682934 -282.749751) (xy 27.738371 -282.755851)
			(xy 27.792328 -282.769957) (xy 27.843657 -282.791769) (xy 27.891263 -282.820823) (xy 27.934131 -282.856498)
			(xy 27.971348 -282.898035) (xy 28.002121 -282.944548) (xy 28.025793 -282.995045) (xy 28.041861 -283.048452)
			(xy 28.049981 -283.103628) (xy 28.05049 -283.131514) (xy 28.175964 -283.131514) (xy 28.180035 -283.075892)
			(xy 28.192161 -283.021455) (xy 28.212084 -282.969364) (xy 28.23938 -282.920729) (xy 28.273466 -282.876586)
			(xy 28.313615 -282.837877) (xy 28.358973 -282.805426) (xy 28.408573 -282.779925) (xy 28.461357 -282.761918)
			(xy 28.5162 -282.751788) (xy 28.571934 -282.749751) (xy 28.627371 -282.755851) (xy 28.681328 -282.769957)
			(xy 28.732657 -282.791769) (xy 28.780263 -282.820823) (xy 28.823131 -282.856498) (xy 28.860348 -282.898035)
			(xy 28.891121 -282.944548) (xy 28.914793 -282.995045) (xy 28.930861 -283.048452) (xy 28.938981 -283.103628)
			(xy 28.93949 -283.131514) (xy 28.938981 -283.1594) (xy 28.930861 -283.214576) (xy 28.914793 -283.267983)
			(xy 28.891121 -283.31848) (xy 28.860348 -283.364993) (xy 28.823131 -283.40653) (xy 28.780263 -283.442205)
			(xy 28.732657 -283.471259) (xy 28.681328 -283.493071) (xy 28.627371 -283.507177) (xy 28.571934 -283.513277)
			(xy 28.5162 -283.51124) (xy 28.461357 -283.50111) (xy 28.408573 -283.483103) (xy 28.358973 -283.457602)
			(xy 28.313615 -283.425151) (xy 28.273466 -283.386442) (xy 28.23938 -283.342299) (xy 28.212084 -283.293664)
			(xy 28.192161 -283.241573) (xy 28.180035 -283.187136) (xy 28.175964 -283.131514) (xy 28.05049 -283.131514)
			(xy 28.049981 -283.1594) (xy 28.041861 -283.214576) (xy 28.025793 -283.267983) (xy 28.002121 -283.31848)
			(xy 27.971348 -283.364993) (xy 27.934131 -283.40653) (xy 27.891263 -283.442205) (xy 27.843657 -283.471259)
			(xy 27.792328 -283.493071) (xy 27.738371 -283.507177) (xy 27.682934 -283.513277) (xy 27.6272 -283.51124)
			(xy 27.572357 -283.50111) (xy 27.519573 -283.483103) (xy 27.469973 -283.457602) (xy 27.424615 -283.425151)
			(xy 27.384466 -283.386442) (xy 27.35038 -283.342299) (xy 27.323084 -283.293664) (xy 27.303161 -283.241573)
			(xy 27.291035 -283.187136) (xy 27.286964 -283.131514) (xy 26.575004 -283.131514) (xy 26.574495 -283.1594)
			(xy 26.566375 -283.214576) (xy 26.550307 -283.267983) (xy 26.526635 -283.31848) (xy 26.495862 -283.364993)
			(xy 26.458645 -283.40653) (xy 26.415777 -283.442205) (xy 26.368171 -283.471259) (xy 26.316842 -283.493071)
			(xy 26.262885 -283.507177) (xy 26.207448 -283.513277) (xy 26.151714 -283.51124) (xy 26.096871 -283.50111)
			(xy 26.044087 -283.483103) (xy 25.994487 -283.457602) (xy 25.949129 -283.425151) (xy 25.90898 -283.386442)
			(xy 25.874894 -283.342299) (xy 25.847598 -283.293664) (xy 25.827675 -283.241573) (xy 25.815549 -283.187136)
			(xy 25.811478 -283.131514) (xy 16.733783 -283.131514) (xy 16.733845 -283.131946) (xy 16.733845 -283.186454)
			(xy 16.726087 -283.240407) (xy 16.71073 -283.292707) (xy 16.688085 -283.342289) (xy 16.658615 -283.388143)
			(xy 16.622918 -283.429337) (xy 16.581723 -283.46503) (xy 16.535866 -283.494498) (xy 16.486283 -283.517139)
			(xy 16.433982 -283.532492) (xy 16.380028 -283.540246) (xy 16.352774 -283.540708) (xy 16.322649 -283.540166)
			(xy 16.263151 -283.53068) (xy 16.205882 -283.511963) (xy 16.152266 -283.48448) (xy 16.103633 -283.448915)
			(xy 16.08201 -283.427932) (xy 16.076422 -283.423106) (xy 16.069675 -283.418449) (xy 16.054134 -283.413261)
			(xy 16.045942 -283.412946) (xy 15.973806 -283.412946) (xy 15.965614 -283.413268) (xy 15.950068 -283.418442)
			(xy 15.943326 -283.423106) (xy 15.937738 -283.427932) (xy 15.916108 -283.448907) (xy 15.867482 -283.484478)
			(xy 15.813867 -283.511961) (xy 15.756597 -283.53067) (xy 15.697098 -283.54014) (xy 15.666974 -283.540708)
			(xy 15.638235 -283.540198) (xy 15.581407 -283.531572) (xy 15.526516 -283.514518) (xy 15.474804 -283.489424)
			(xy 15.427442 -283.456856) (xy 15.406116 -283.437584) (xy 15.399258 -283.43098) (xy 15.390114 -283.427424)
			(xy 15.385651 -283.425794) (xy 15.376321 -283.424007) (xy 15.371572 -283.423868) (xy 15.301976 -283.423868)
			(xy 15.297222 -283.423962) (xy 15.287886 -283.425756) (xy 15.283434 -283.427424) (xy 15.27429 -283.43098)
			(xy 15.267432 -283.437584) (xy 15.246105 -283.456854) (xy 15.198742 -283.489419) (xy 15.147031 -283.51451)
			(xy 15.09214 -283.53156) (xy 15.035313 -283.540182) (xy 14.977835 -283.540182) (xy 14.921008 -283.53156)
			(xy 14.866117 -283.51451) (xy 14.814406 -283.489419) (xy 14.767043 -283.456854) (xy 14.745716 -283.437584)
			(xy 14.738858 -283.43098) (xy 14.729714 -283.427424) (xy 14.725251 -283.425794) (xy 14.715921 -283.424007)
			(xy 14.711172 -283.423868) (xy 14.641576 -283.423868) (xy 14.636822 -283.423962) (xy 14.627486 -283.425756)
			(xy 14.623034 -283.427424) (xy 14.61389 -283.43098) (xy 14.607032 -283.437584) (xy 14.585719 -283.456871)
			(xy 14.538353 -283.489434) (xy 14.486637 -283.514523) (xy 14.431744 -283.53157) (xy 14.374914 -283.540189)
			(xy 14.346174 -283.540708) (xy 14.318924 -283.54022) (xy 14.264979 -283.532461) (xy 14.212687 -283.517104)
			(xy 14.163113 -283.494461) (xy 14.117266 -283.464994) (xy 14.076079 -283.429302) (xy 14.04039 -283.388113)
			(xy 14.010927 -283.342264) (xy 13.988287 -283.292688) (xy 13.972934 -283.240396) (xy 13.965178 -283.18645)
			(xy 12.461045 -283.18645) (xy 12.461045 -283.186453) (xy 12.453287 -283.240406) (xy 12.437931 -283.292705)
			(xy 12.415287 -283.342286) (xy 12.385818 -283.388139) (xy 12.350123 -283.429332) (xy 12.308928 -283.465026)
			(xy 12.263073 -283.494494) (xy 12.213491 -283.517135) (xy 12.161192 -283.53249) (xy 12.10724 -283.540246)
			(xy 12.079986 -283.540708) (xy 12.049862 -283.540158) (xy 11.990364 -283.530674) (xy 11.933095 -283.511959)
			(xy 11.879478 -283.484478) (xy 11.830845 -283.448914) (xy 11.809222 -283.427932) (xy 11.803634 -283.423106)
			(xy 11.796908 -283.418414) (xy 11.781351 -283.413247) (xy 11.773154 -283.412946) (xy 11.701018 -283.412946)
			(xy 11.692826 -283.413273) (xy 11.677281 -283.418444) (xy 11.670538 -283.423106) (xy 11.66495 -283.427932)
			(xy 11.643315 -283.448901) (xy 11.59469 -283.484473) (xy 11.541076 -283.511957) (xy 11.483808 -283.530667)
			(xy 11.42431 -283.540139) (xy 11.394186 -283.540708) (xy 11.365447 -283.540191) (xy 11.308619 -283.531566)
			(xy 11.253729 -283.514515) (xy 11.202017 -283.489422) (xy 11.154655 -283.456855) (xy 11.133328 -283.437584)
			(xy 11.12647 -283.43098) (xy 11.117326 -283.427424) (xy 11.112862 -283.425797) (xy 11.103533 -283.424008)
			(xy 11.098784 -283.423868) (xy 11.029188 -283.423868) (xy 11.024435 -283.423965) (xy 11.015098 -283.425757)
			(xy 11.010646 -283.427424) (xy 11.001502 -283.43098) (xy 10.994644 -283.437584) (xy 10.973317 -283.456854)
			(xy 10.925954 -283.489419) (xy 10.874243 -283.51451) (xy 10.819352 -283.53156) (xy 10.762525 -283.540182)
			(xy 10.705047 -283.540182) (xy 10.64822 -283.53156) (xy 10.593329 -283.51451) (xy 10.541618 -283.489419)
			(xy 10.494255 -283.456854) (xy 10.472928 -283.437584) (xy 10.46607 -283.43098) (xy 10.456926 -283.427424)
			(xy 10.452462 -283.425797) (xy 10.443133 -283.424008) (xy 10.438384 -283.423868) (xy 10.368788 -283.423868)
			(xy 10.364035 -283.423965) (xy 10.354698 -283.425757) (xy 10.350246 -283.427424) (xy 10.341102 -283.43098)
			(xy 10.334244 -283.437584) (xy 10.312926 -283.456865) (xy 10.265561 -283.489429) (xy 10.213847 -283.514519)
			(xy 10.158955 -283.531567) (xy 10.102126 -283.540188) (xy 10.073386 -283.540708) (xy 10.046135 -283.540221)
			(xy 9.992189 -283.532463) (xy 9.939896 -283.517107) (xy 9.890321 -283.494465) (xy 9.844472 -283.464998)
			(xy 9.803283 -283.429307) (xy 9.767593 -283.388117) (xy 9.738128 -283.342267) (xy 9.715488 -283.292691)
			(xy 9.700134 -283.240397) (xy 9.692378 -283.186451) (xy 1.420114 -283.186451) (xy 1.420114 -283.893514)
			(xy 31.338012 -283.893514) (xy 31.338555 -283.864132) (xy 31.347584 -283.806065) (xy 31.365415 -283.75007)
			(xy 31.391626 -283.697475) (xy 31.425597 -283.649524) (xy 31.466521 -283.607352) (xy 31.48965 -283.589222)
			(xy 31.498575 -283.581743) (xy 31.509034 -283.560968) (xy 31.509716 -283.549344) (xy 31.510986 -283.463238)
			(xy 31.508446 -283.452062) (xy 31.50616 -283.446982) (xy 31.503553 -283.441799) (xy 31.496365 -283.432696)
			(xy 31.491936 -283.428948) (xy 31.470088 -283.410742) (xy 31.431546 -283.368924) (xy 31.399638 -283.321849)
			(xy 31.375071 -283.270559) (xy 31.358388 -283.216191) (xy 31.34996 -283.159949) (xy 31.349442 -283.131514)
			(xy 31.349928 -283.104263) (xy 31.357684 -283.050315) (xy 31.373039 -282.99802) (xy 31.395681 -282.948443)
			(xy 31.425147 -282.902593) (xy 31.460838 -282.861402) (xy 31.502029 -282.825711) (xy 31.547879 -282.796245)
			(xy 31.597456 -282.773603) (xy 31.649751 -282.758248) (xy 31.703699 -282.750492) (xy 31.758201 -282.750492)
			(xy 31.812149 -282.758248) (xy 31.864444 -282.773603) (xy 31.914021 -282.796245) (xy 31.959871 -282.825711)
			(xy 32.001062 -282.861402) (xy 32.036753 -282.902593) (xy 32.066219 -282.948443) (xy 32.088861 -282.99802)
			(xy 32.104216 -283.050315) (xy 32.107747 -283.074872) (xy 36.069028 -283.074872) (xy 36.072988 -283.025818)
			(xy 36.084765 -282.978034) (xy 36.104056 -282.932758) (xy 36.130359 -282.891162) (xy 36.162994 -282.854325)
			(xy 36.201115 -282.8232) (xy 36.243736 -282.798593) (xy 36.289752 -282.781141) (xy 36.337971 -282.771297)
			(xy 36.387146 -282.769316) (xy 36.436001 -282.775248) (xy 36.483272 -282.78894) (xy 36.527734 -282.810038)
			(xy 36.568237 -282.837994) (xy 36.60373 -282.872086) (xy 36.633295 -282.91143) (xy 36.656166 -282.955007)
			(xy 36.67175 -283.001688) (xy 36.679645 -283.050265) (xy 36.68014 -283.074872) (xy 37.018988 -283.074872)
			(xy 37.022948 -283.025818) (xy 37.034725 -282.978034) (xy 37.054016 -282.932758) (xy 37.080319 -282.891162)
			(xy 37.112954 -282.854325) (xy 37.151075 -282.8232) (xy 37.193696 -282.798593) (xy 37.239712 -282.781141)
			(xy 37.287931 -282.771297) (xy 37.337106 -282.769316) (xy 37.385961 -282.775248) (xy 37.433232 -282.78894)
			(xy 37.477694 -282.810038) (xy 37.518197 -282.837994) (xy 37.55369 -282.872086) (xy 37.583255 -282.91143)
			(xy 37.606126 -282.955007) (xy 37.62171 -283.001688) (xy 37.629605 -283.050265) (xy 37.6301 -283.074872)
			(xy 37.969202 -283.074872) (xy 37.973162 -283.025818) (xy 37.984939 -282.978034) (xy 38.00423 -282.932758)
			(xy 38.030533 -282.891162) (xy 38.063168 -282.854325) (xy 38.101289 -282.8232) (xy 38.14391 -282.798593)
			(xy 38.189926 -282.781141) (xy 38.238145 -282.771297) (xy 38.28732 -282.769316) (xy 38.336175 -282.775248)
			(xy 38.383446 -282.78894) (xy 38.427908 -282.810038) (xy 38.468411 -282.837994) (xy 38.503904 -282.872086)
			(xy 38.533469 -282.91143) (xy 38.55634 -282.955007) (xy 38.571924 -283.001688) (xy 38.579819 -283.050265)
			(xy 38.580314 -283.074872) (xy 38.919162 -283.074872) (xy 38.923122 -283.025818) (xy 38.934899 -282.978034)
			(xy 38.95419 -282.932758) (xy 38.980493 -282.891162) (xy 39.013128 -282.854325) (xy 39.051249 -282.8232)
			(xy 39.09387 -282.798593) (xy 39.139886 -282.781141) (xy 39.188105 -282.771297) (xy 39.23728 -282.769316)
			(xy 39.286135 -282.775248) (xy 39.333406 -282.78894) (xy 39.377868 -282.810038) (xy 39.418371 -282.837994)
			(xy 39.453864 -282.872086) (xy 39.483429 -282.91143) (xy 39.5063 -282.955007) (xy 39.521884 -283.001688)
			(xy 39.529779 -283.050265) (xy 39.530274 -283.074872) (xy 39.869122 -283.074872) (xy 39.873082 -283.025818)
			(xy 39.884859 -282.978034) (xy 39.90415 -282.932758) (xy 39.930453 -282.891162) (xy 39.963088 -282.854325)
			(xy 40.001209 -282.8232) (xy 40.04383 -282.798593) (xy 40.089846 -282.781141) (xy 40.138065 -282.771297)
			(xy 40.18724 -282.769316) (xy 40.236095 -282.775248) (xy 40.283366 -282.78894) (xy 40.327828 -282.810038)
			(xy 40.368331 -282.837994) (xy 40.403824 -282.872086) (xy 40.433389 -282.91143) (xy 40.45626 -282.955007)
			(xy 40.471844 -283.001688) (xy 40.479739 -283.050265) (xy 40.480234 -283.074872) (xy 40.819082 -283.074872)
			(xy 40.823042 -283.025818) (xy 40.834819 -282.978034) (xy 40.85411 -282.932758) (xy 40.880413 -282.891162)
			(xy 40.913048 -282.854325) (xy 40.951169 -282.8232) (xy 40.99379 -282.798593) (xy 41.039806 -282.781141)
			(xy 41.088025 -282.771297) (xy 41.1372 -282.769316) (xy 41.186055 -282.775248) (xy 41.233326 -282.78894)
			(xy 41.277788 -282.810038) (xy 41.318291 -282.837994) (xy 41.353784 -282.872086) (xy 41.383349 -282.91143)
			(xy 41.40622 -282.955007) (xy 41.421804 -283.001688) (xy 41.429699 -283.050265) (xy 41.430194 -283.074872)
			(xy 41.769042 -283.074872) (xy 41.773002 -283.025818) (xy 41.784779 -282.978034) (xy 41.80407 -282.932758)
			(xy 41.830373 -282.891162) (xy 41.863008 -282.854325) (xy 41.901129 -282.8232) (xy 41.94375 -282.798593)
			(xy 41.989766 -282.781141) (xy 42.037985 -282.771297) (xy 42.08716 -282.769316) (xy 42.136015 -282.775248)
			(xy 42.183286 -282.78894) (xy 42.227748 -282.810038) (xy 42.268251 -282.837994) (xy 42.303744 -282.872086)
			(xy 42.333309 -282.91143) (xy 42.35618 -282.955007) (xy 42.371764 -283.001688) (xy 42.379659 -283.050265)
			(xy 42.380154 -283.074872) (xy 42.379659 -283.099479) (xy 42.371764 -283.148056) (xy 42.35618 -283.194737)
			(xy 42.333309 -283.238314) (xy 42.303744 -283.277658) (xy 42.268251 -283.31175) (xy 42.227748 -283.339706)
			(xy 42.183286 -283.360804) (xy 42.136015 -283.374496) (xy 42.08716 -283.380428) (xy 42.037985 -283.378447)
			(xy 41.989766 -283.368603) (xy 41.94375 -283.351151) (xy 41.901129 -283.326544) (xy 41.863008 -283.295419)
			(xy 41.830373 -283.258582) (xy 41.80407 -283.216986) (xy 41.784779 -283.17171) (xy 41.773002 -283.123926)
			(xy 41.769042 -283.074872) (xy 41.430194 -283.074872) (xy 41.429699 -283.099479) (xy 41.421804 -283.148056)
			(xy 41.40622 -283.194737) (xy 41.383349 -283.238314) (xy 41.353784 -283.277658) (xy 41.318291 -283.31175)
			(xy 41.277788 -283.339706) (xy 41.233326 -283.360804) (xy 41.186055 -283.374496) (xy 41.1372 -283.380428)
			(xy 41.088025 -283.378447) (xy 41.039806 -283.368603) (xy 40.99379 -283.351151) (xy 40.951169 -283.326544)
			(xy 40.913048 -283.295419) (xy 40.880413 -283.258582) (xy 40.85411 -283.216986) (xy 40.834819 -283.17171)
			(xy 40.823042 -283.123926) (xy 40.819082 -283.074872) (xy 40.480234 -283.074872) (xy 40.479739 -283.099479)
			(xy 40.471844 -283.148056) (xy 40.45626 -283.194737) (xy 40.433389 -283.238314) (xy 40.403824 -283.277658)
			(xy 40.368331 -283.31175) (xy 40.327828 -283.339706) (xy 40.283366 -283.360804) (xy 40.236095 -283.374496)
			(xy 40.18724 -283.380428) (xy 40.138065 -283.378447) (xy 40.089846 -283.368603) (xy 40.04383 -283.351151)
			(xy 40.001209 -283.326544) (xy 39.963088 -283.295419) (xy 39.930453 -283.258582) (xy 39.90415 -283.216986)
			(xy 39.884859 -283.17171) (xy 39.873082 -283.123926) (xy 39.869122 -283.074872) (xy 39.530274 -283.074872)
			(xy 39.529779 -283.099479) (xy 39.521884 -283.148056) (xy 39.5063 -283.194737) (xy 39.483429 -283.238314)
			(xy 39.453864 -283.277658) (xy 39.418371 -283.31175) (xy 39.377868 -283.339706) (xy 39.333406 -283.360804)
			(xy 39.286135 -283.374496) (xy 39.23728 -283.380428) (xy 39.188105 -283.378447) (xy 39.139886 -283.368603)
			(xy 39.09387 -283.351151) (xy 39.051249 -283.326544) (xy 39.013128 -283.295419) (xy 38.980493 -283.258582)
			(xy 38.95419 -283.216986) (xy 38.934899 -283.17171) (xy 38.923122 -283.123926) (xy 38.919162 -283.074872)
			(xy 38.580314 -283.074872) (xy 38.579819 -283.099479) (xy 38.571924 -283.148056) (xy 38.55634 -283.194737)
			(xy 38.533469 -283.238314) (xy 38.503904 -283.277658) (xy 38.468411 -283.31175) (xy 38.427908 -283.339706)
			(xy 38.383446 -283.360804) (xy 38.336175 -283.374496) (xy 38.28732 -283.380428) (xy 38.238145 -283.378447)
			(xy 38.189926 -283.368603) (xy 38.14391 -283.351151) (xy 38.101289 -283.326544) (xy 38.063168 -283.295419)
			(xy 38.030533 -283.258582) (xy 38.00423 -283.216986) (xy 37.984939 -283.17171) (xy 37.973162 -283.123926)
			(xy 37.969202 -283.074872) (xy 37.6301 -283.074872) (xy 37.629605 -283.099479) (xy 37.62171 -283.148056)
			(xy 37.606126 -283.194737) (xy 37.583255 -283.238314) (xy 37.55369 -283.277658) (xy 37.518197 -283.31175)
			(xy 37.477694 -283.339706) (xy 37.433232 -283.360804) (xy 37.385961 -283.374496) (xy 37.337106 -283.380428)
			(xy 37.287931 -283.378447) (xy 37.239712 -283.368603) (xy 37.193696 -283.351151) (xy 37.151075 -283.326544)
			(xy 37.112954 -283.295419) (xy 37.080319 -283.258582) (xy 37.054016 -283.216986) (xy 37.034725 -283.17171)
			(xy 37.022948 -283.123926) (xy 37.018988 -283.074872) (xy 36.68014 -283.074872) (xy 36.679645 -283.099479)
			(xy 36.67175 -283.148056) (xy 36.656166 -283.194737) (xy 36.633295 -283.238314) (xy 36.60373 -283.277658)
			(xy 36.568237 -283.31175) (xy 36.527734 -283.339706) (xy 36.483272 -283.360804) (xy 36.436001 -283.374496)
			(xy 36.387146 -283.380428) (xy 36.337971 -283.378447) (xy 36.289752 -283.368603) (xy 36.243736 -283.351151)
			(xy 36.201115 -283.326544) (xy 36.162994 -283.295419) (xy 36.130359 -283.258582) (xy 36.104056 -283.216986)
			(xy 36.084765 -283.17171) (xy 36.072988 -283.123926) (xy 36.069028 -283.074872) (xy 32.107747 -283.074872)
			(xy 32.111972 -283.104263) (xy 32.112458 -283.131514) (xy 32.111907 -283.160896) (xy 32.102876 -283.218961)
			(xy 32.085044 -283.274954) (xy 32.058835 -283.327549) (xy 32.024867 -283.3755) (xy 31.983946 -283.417674)
			(xy 31.96082 -283.435806) (xy 31.951877 -283.443267) (xy 31.94143 -283.464056) (xy 31.940754 -283.475684)
			(xy 31.939484 -283.56179) (xy 31.942024 -283.572966) (xy 31.94431 -283.578046) (xy 31.946917 -283.583229)
			(xy 31.954106 -283.592332) (xy 31.958534 -283.59608) (xy 31.980362 -283.614309) (xy 32.018902 -283.656124)
			(xy 32.05081 -283.703195) (xy 32.07538 -283.75448) (xy 32.092068 -283.808843) (xy 32.100505 -283.865081)
			(xy 32.101028 -283.893514) (xy 32.734502 -283.893514) (xy 32.738573 -283.837892) (xy 32.750699 -283.783455)
			(xy 32.770622 -283.731364) (xy 32.797918 -283.682729) (xy 32.832004 -283.638586) (xy 32.872153 -283.599877)
			(xy 32.917511 -283.567426) (xy 32.967111 -283.541925) (xy 33.019895 -283.523918) (xy 33.074738 -283.513788)
			(xy 33.130472 -283.511751) (xy 33.185909 -283.517851) (xy 33.239866 -283.531957) (xy 33.291195 -283.553769)
			(xy 33.338801 -283.582823) (xy 33.381669 -283.618498) (xy 33.418886 -283.660035) (xy 33.449659 -283.706548)
			(xy 33.473331 -283.757045) (xy 33.489399 -283.810452) (xy 33.497519 -283.865628) (xy 33.498028 -283.893514)
			(xy 33.620962 -283.893514) (xy 33.625033 -283.837892) (xy 33.637159 -283.783455) (xy 33.657082 -283.731364)
			(xy 33.684378 -283.682729) (xy 33.718464 -283.638586) (xy 33.758613 -283.599877) (xy 33.803971 -283.567426)
			(xy 33.853571 -283.541925) (xy 33.906355 -283.523918) (xy 33.961198 -283.513788) (xy 34.016932 -283.511751)
			(xy 34.072369 -283.517851) (xy 34.126326 -283.531957) (xy 34.168437 -283.549852) (xy 73.593972 -283.549852)
			(xy 73.597932 -283.500798) (xy 73.609709 -283.453014) (xy 73.629 -283.407738) (xy 73.655303 -283.366142)
			(xy 73.687938 -283.329305) (xy 73.726059 -283.29818) (xy 73.76868 -283.273573) (xy 73.814696 -283.256121)
			(xy 73.862915 -283.246277) (xy 73.91209 -283.244296) (xy 73.960945 -283.250228) (xy 74.008216 -283.26392)
			(xy 74.052678 -283.285018) (xy 74.093181 -283.312974) (xy 74.128674 -283.347066) (xy 74.158239 -283.38641)
			(xy 74.18111 -283.429987) (xy 74.196694 -283.476668) (xy 74.204589 -283.525245) (xy 74.205084 -283.549852)
			(xy 74.204589 -283.574459) (xy 74.20441 -283.57556) (xy 74.523088 -283.57556) (xy 74.523088 -283.524144)
			(xy 74.531131 -283.473362) (xy 74.547019 -283.424463) (xy 74.570362 -283.378651) (xy 74.600583 -283.337055)
			(xy 74.636939 -283.300699) (xy 74.678535 -283.270478) (xy 74.724347 -283.247135) (xy 74.773246 -283.231247)
			(xy 74.824028 -283.223204) (xy 74.875444 -283.223204) (xy 74.926226 -283.231247) (xy 74.975125 -283.247135)
			(xy 75.020937 -283.270478) (xy 75.062533 -283.300699) (xy 75.098889 -283.337055) (xy 75.12911 -283.378651)
			(xy 75.152453 -283.424463) (xy 75.168341 -283.473362) (xy 75.176384 -283.524144) (xy 75.176888 -283.549852)
			(xy 75.176384 -283.57556) (xy 75.473302 -283.57556) (xy 75.473302 -283.524144) (xy 75.481345 -283.473362)
			(xy 75.497233 -283.424463) (xy 75.520576 -283.378651) (xy 75.550797 -283.337055) (xy 75.587153 -283.300699)
			(xy 75.628749 -283.270478) (xy 75.674561 -283.247135) (xy 75.72346 -283.231247) (xy 75.774242 -283.223204)
			(xy 75.825658 -283.223204) (xy 75.87644 -283.231247) (xy 75.925339 -283.247135) (xy 75.971151 -283.270478)
			(xy 76.012747 -283.300699) (xy 76.049103 -283.337055) (xy 76.079324 -283.378651) (xy 76.102667 -283.424463)
			(xy 76.118555 -283.473362) (xy 76.126598 -283.524144) (xy 76.127102 -283.549852) (xy 76.444106 -283.549852)
			(xy 76.448066 -283.500798) (xy 76.459843 -283.453014) (xy 76.479134 -283.407738) (xy 76.505437 -283.366142)
			(xy 76.538072 -283.329305) (xy 76.576193 -283.29818) (xy 76.618814 -283.273573) (xy 76.66483 -283.256121)
			(xy 76.713049 -283.246277) (xy 76.762224 -283.244296) (xy 76.811079 -283.250228) (xy 76.85835 -283.26392)
			(xy 76.902812 -283.285018) (xy 76.943315 -283.312974) (xy 76.978808 -283.347066) (xy 77.008373 -283.38641)
			(xy 77.031244 -283.429987) (xy 77.046828 -283.476668) (xy 77.054723 -283.525245) (xy 77.055218 -283.549852)
			(xy 77.394066 -283.549852) (xy 77.398026 -283.500798) (xy 77.409803 -283.453014) (xy 77.429094 -283.407738)
			(xy 77.455397 -283.366142) (xy 77.488032 -283.329305) (xy 77.526153 -283.29818) (xy 77.568774 -283.273573)
			(xy 77.61479 -283.256121) (xy 77.663009 -283.246277) (xy 77.712184 -283.244296) (xy 77.761039 -283.250228)
			(xy 77.80831 -283.26392) (xy 77.852772 -283.285018) (xy 77.893275 -283.312974) (xy 77.928768 -283.347066)
			(xy 77.958333 -283.38641) (xy 77.981204 -283.429987) (xy 77.996788 -283.476668) (xy 78.004683 -283.525245)
			(xy 78.005178 -283.549852) (xy 78.344026 -283.549852) (xy 78.347986 -283.500798) (xy 78.359763 -283.453014)
			(xy 78.379054 -283.407738) (xy 78.405357 -283.366142) (xy 78.437992 -283.329305) (xy 78.476113 -283.29818)
			(xy 78.518734 -283.273573) (xy 78.56475 -283.256121) (xy 78.612969 -283.246277) (xy 78.662144 -283.244296)
			(xy 78.710999 -283.250228) (xy 78.75827 -283.26392) (xy 78.802732 -283.285018) (xy 78.843235 -283.312974)
			(xy 78.878728 -283.347066) (xy 78.908293 -283.38641) (xy 78.931164 -283.429987) (xy 78.946748 -283.476668)
			(xy 78.954643 -283.525245) (xy 78.955138 -283.549852) (xy 79.293986 -283.549852) (xy 79.297946 -283.500798)
			(xy 79.309723 -283.453014) (xy 79.329014 -283.407738) (xy 79.355317 -283.366142) (xy 79.387952 -283.329305)
			(xy 79.426073 -283.29818) (xy 79.468694 -283.273573) (xy 79.51471 -283.256121) (xy 79.562929 -283.246277)
			(xy 79.612104 -283.244296) (xy 79.660959 -283.250228) (xy 79.70823 -283.26392) (xy 79.752692 -283.285018)
			(xy 79.793195 -283.312974) (xy 79.828688 -283.347066) (xy 79.858253 -283.38641) (xy 79.881124 -283.429987)
			(xy 79.896708 -283.476668) (xy 79.904603 -283.525245) (xy 79.905098 -283.549852) (xy 80.243946 -283.549852)
			(xy 80.247906 -283.500798) (xy 80.259683 -283.453014) (xy 80.278974 -283.407738) (xy 80.305277 -283.366142)
			(xy 80.337912 -283.329305) (xy 80.376033 -283.29818) (xy 80.418654 -283.273573) (xy 80.46467 -283.256121)
			(xy 80.512889 -283.246277) (xy 80.562064 -283.244296) (xy 80.610919 -283.250228) (xy 80.65819 -283.26392)
			(xy 80.702652 -283.285018) (xy 80.743155 -283.312974) (xy 80.778648 -283.347066) (xy 80.808213 -283.38641)
			(xy 80.831084 -283.429987) (xy 80.846668 -283.476668) (xy 80.854563 -283.525245) (xy 80.855058 -283.549852)
			(xy 80.854563 -283.574459) (xy 80.854384 -283.57556) (xy 81.173316 -283.57556) (xy 81.173316 -283.524144)
			(xy 81.181359 -283.473362) (xy 81.197247 -283.424463) (xy 81.22059 -283.378651) (xy 81.250811 -283.337055)
			(xy 81.287167 -283.300699) (xy 81.328763 -283.270478) (xy 81.374575 -283.247135) (xy 81.423474 -283.231247)
			(xy 81.474256 -283.223204) (xy 81.525672 -283.223204) (xy 81.576454 -283.231247) (xy 81.625353 -283.247135)
			(xy 81.671165 -283.270478) (xy 81.712761 -283.300699) (xy 81.749117 -283.337055) (xy 81.779338 -283.378651)
			(xy 81.802681 -283.424463) (xy 81.818569 -283.473362) (xy 81.826612 -283.524144) (xy 81.827116 -283.549852)
			(xy 81.826612 -283.57556) (xy 82.123276 -283.57556) (xy 82.123276 -283.524144) (xy 82.131319 -283.473362)
			(xy 82.147207 -283.424463) (xy 82.17055 -283.378651) (xy 82.200771 -283.337055) (xy 82.237127 -283.300699)
			(xy 82.278723 -283.270478) (xy 82.324535 -283.247135) (xy 82.373434 -283.231247) (xy 82.424216 -283.223204)
			(xy 82.475632 -283.223204) (xy 82.526414 -283.231247) (xy 82.575313 -283.247135) (xy 82.621125 -283.270478)
			(xy 82.662721 -283.300699) (xy 82.699077 -283.337055) (xy 82.729298 -283.378651) (xy 82.752641 -283.424463)
			(xy 82.768529 -283.473362) (xy 82.776572 -283.524144) (xy 82.777076 -283.549852) (xy 82.777071 -283.550106)
			(xy 83.094334 -283.550106) (xy 83.098294 -283.501052) (xy 83.110071 -283.453268) (xy 83.129362 -283.407992)
			(xy 83.155665 -283.366396) (xy 83.1883 -283.329559) (xy 83.226421 -283.298434) (xy 83.269042 -283.273827)
			(xy 83.315058 -283.256375) (xy 83.363277 -283.246531) (xy 83.412452 -283.24455) (xy 83.461307 -283.250482)
			(xy 83.508578 -283.264174) (xy 83.55304 -283.285272) (xy 83.593543 -283.313228) (xy 83.629036 -283.34732)
			(xy 83.658601 -283.386664) (xy 83.681472 -283.430241) (xy 83.697056 -283.476922) (xy 83.704951 -283.525499)
			(xy 83.705446 -283.550106) (xy 83.704951 -283.574713) (xy 83.697056 -283.62329) (xy 83.681472 -283.669971)
			(xy 83.658601 -283.713548) (xy 83.629036 -283.752892) (xy 83.593543 -283.786984) (xy 83.55304 -283.81494)
			(xy 83.508578 -283.836038) (xy 83.461307 -283.84973) (xy 83.412452 -283.855662) (xy 83.363277 -283.853681)
			(xy 83.315058 -283.843837) (xy 83.269042 -283.826385) (xy 83.226421 -283.801778) (xy 83.1883 -283.770653)
			(xy 83.155665 -283.733816) (xy 83.129362 -283.69222) (xy 83.110071 -283.646944) (xy 83.098294 -283.59916)
			(xy 83.094334 -283.550106) (xy 82.777071 -283.550106) (xy 82.776572 -283.57556) (xy 82.768529 -283.626342)
			(xy 82.752641 -283.675241) (xy 82.729298 -283.721053) (xy 82.699077 -283.762649) (xy 82.662721 -283.799005)
			(xy 82.621125 -283.829226) (xy 82.575313 -283.852569) (xy 82.526414 -283.868457) (xy 82.475632 -283.8765)
			(xy 82.424216 -283.8765) (xy 82.373434 -283.868457) (xy 82.324535 -283.852569) (xy 82.278723 -283.829226)
			(xy 82.237127 -283.799005) (xy 82.200771 -283.762649) (xy 82.17055 -283.721053) (xy 82.147207 -283.675241)
			(xy 82.131319 -283.626342) (xy 82.123276 -283.57556) (xy 81.826612 -283.57556) (xy 81.818569 -283.626342)
			(xy 81.802681 -283.675241) (xy 81.779338 -283.721053) (xy 81.749117 -283.762649) (xy 81.712761 -283.799005)
			(xy 81.671165 -283.829226) (xy 81.625353 -283.852569) (xy 81.576454 -283.868457) (xy 81.525672 -283.8765)
			(xy 81.474256 -283.8765) (xy 81.423474 -283.868457) (xy 81.374575 -283.852569) (xy 81.328763 -283.829226)
			(xy 81.287167 -283.799005) (xy 81.250811 -283.762649) (xy 81.22059 -283.721053) (xy 81.197247 -283.675241)
			(xy 81.181359 -283.626342) (xy 81.173316 -283.57556) (xy 80.854384 -283.57556) (xy 80.846668 -283.623036)
			(xy 80.831084 -283.669717) (xy 80.808213 -283.713294) (xy 80.778648 -283.752638) (xy 80.743155 -283.78673)
			(xy 80.702652 -283.814686) (xy 80.65819 -283.835784) (xy 80.610919 -283.849476) (xy 80.562064 -283.855408)
			(xy 80.512889 -283.853427) (xy 80.46467 -283.843583) (xy 80.418654 -283.826131) (xy 80.376033 -283.801524)
			(xy 80.337912 -283.770399) (xy 80.305277 -283.733562) (xy 80.278974 -283.691966) (xy 80.259683 -283.64669)
			(xy 80.247906 -283.598906) (xy 80.243946 -283.549852) (xy 79.905098 -283.549852) (xy 79.904603 -283.574459)
			(xy 79.896708 -283.623036) (xy 79.881124 -283.669717) (xy 79.858253 -283.713294) (xy 79.828688 -283.752638)
			(xy 79.793195 -283.78673) (xy 79.752692 -283.814686) (xy 79.70823 -283.835784) (xy 79.660959 -283.849476)
			(xy 79.612104 -283.855408) (xy 79.562929 -283.853427) (xy 79.51471 -283.843583) (xy 79.468694 -283.826131)
			(xy 79.426073 -283.801524) (xy 79.387952 -283.770399) (xy 79.355317 -283.733562) (xy 79.329014 -283.691966)
			(xy 79.309723 -283.64669) (xy 79.297946 -283.598906) (xy 79.293986 -283.549852) (xy 78.955138 -283.549852)
			(xy 78.954643 -283.574459) (xy 78.946748 -283.623036) (xy 78.931164 -283.669717) (xy 78.908293 -283.713294)
			(xy 78.878728 -283.752638) (xy 78.843235 -283.78673) (xy 78.802732 -283.814686) (xy 78.75827 -283.835784)
			(xy 78.710999 -283.849476) (xy 78.662144 -283.855408) (xy 78.612969 -283.853427) (xy 78.56475 -283.843583)
			(xy 78.518734 -283.826131) (xy 78.476113 -283.801524) (xy 78.437992 -283.770399) (xy 78.405357 -283.733562)
			(xy 78.379054 -283.691966) (xy 78.359763 -283.64669) (xy 78.347986 -283.598906) (xy 78.344026 -283.549852)
			(xy 78.005178 -283.549852) (xy 78.004683 -283.574459) (xy 77.996788 -283.623036) (xy 77.981204 -283.669717)
			(xy 77.958333 -283.713294) (xy 77.928768 -283.752638) (xy 77.893275 -283.78673) (xy 77.852772 -283.814686)
			(xy 77.80831 -283.835784) (xy 77.761039 -283.849476) (xy 77.712184 -283.855408) (xy 77.663009 -283.853427)
			(xy 77.61479 -283.843583) (xy 77.568774 -283.826131) (xy 77.526153 -283.801524) (xy 77.488032 -283.770399)
			(xy 77.455397 -283.733562) (xy 77.429094 -283.691966) (xy 77.409803 -283.64669) (xy 77.398026 -283.598906)
			(xy 77.394066 -283.549852) (xy 77.055218 -283.549852) (xy 77.054723 -283.574459) (xy 77.046828 -283.623036)
			(xy 77.031244 -283.669717) (xy 77.008373 -283.713294) (xy 76.978808 -283.752638) (xy 76.943315 -283.78673)
			(xy 76.902812 -283.814686) (xy 76.85835 -283.835784) (xy 76.811079 -283.849476) (xy 76.762224 -283.855408)
			(xy 76.713049 -283.853427) (xy 76.66483 -283.843583) (xy 76.618814 -283.826131) (xy 76.576193 -283.801524)
			(xy 76.538072 -283.770399) (xy 76.505437 -283.733562) (xy 76.479134 -283.691966) (xy 76.459843 -283.64669)
			(xy 76.448066 -283.598906) (xy 76.444106 -283.549852) (xy 76.127102 -283.549852) (xy 76.126598 -283.57556)
			(xy 76.118555 -283.626342) (xy 76.102667 -283.675241) (xy 76.079324 -283.721053) (xy 76.049103 -283.762649)
			(xy 76.012747 -283.799005) (xy 75.971151 -283.829226) (xy 75.925339 -283.852569) (xy 75.87644 -283.868457)
			(xy 75.825658 -283.8765) (xy 75.774242 -283.8765) (xy 75.72346 -283.868457) (xy 75.674561 -283.852569)
			(xy 75.628749 -283.829226) (xy 75.587153 -283.799005) (xy 75.550797 -283.762649) (xy 75.520576 -283.721053)
			(xy 75.497233 -283.675241) (xy 75.481345 -283.626342) (xy 75.473302 -283.57556) (xy 75.176384 -283.57556)
			(xy 75.168341 -283.626342) (xy 75.152453 -283.675241) (xy 75.12911 -283.721053) (xy 75.098889 -283.762649)
			(xy 75.062533 -283.799005) (xy 75.020937 -283.829226) (xy 74.975125 -283.852569) (xy 74.926226 -283.868457)
			(xy 74.875444 -283.8765) (xy 74.824028 -283.8765) (xy 74.773246 -283.868457) (xy 74.724347 -283.852569)
			(xy 74.678535 -283.829226) (xy 74.636939 -283.799005) (xy 74.600583 -283.762649) (xy 74.570362 -283.721053)
			(xy 74.547019 -283.675241) (xy 74.531131 -283.626342) (xy 74.523088 -283.57556) (xy 74.20441 -283.57556)
			(xy 74.196694 -283.623036) (xy 74.18111 -283.669717) (xy 74.158239 -283.713294) (xy 74.128674 -283.752638)
			(xy 74.093181 -283.78673) (xy 74.052678 -283.814686) (xy 74.008216 -283.835784) (xy 73.960945 -283.849476)
			(xy 73.91209 -283.855408) (xy 73.862915 -283.853427) (xy 73.814696 -283.843583) (xy 73.76868 -283.826131)
			(xy 73.726059 -283.801524) (xy 73.687938 -283.770399) (xy 73.655303 -283.733562) (xy 73.629 -283.691966)
			(xy 73.609709 -283.64669) (xy 73.597932 -283.598906) (xy 73.593972 -283.549852) (xy 34.168437 -283.549852)
			(xy 34.177655 -283.553769) (xy 34.225261 -283.582823) (xy 34.268129 -283.618498) (xy 34.305346 -283.660035)
			(xy 34.336119 -283.706548) (xy 34.359791 -283.757045) (xy 34.375859 -283.810452) (xy 34.383979 -283.865628)
			(xy 34.384488 -283.893514) (xy 34.383979 -283.9214) (xy 34.375859 -283.976576) (xy 34.361341 -284.024832)
			(xy 36.069028 -284.024832) (xy 36.072988 -283.975778) (xy 36.084765 -283.927994) (xy 36.104056 -283.882718)
			(xy 36.130359 -283.841122) (xy 36.162994 -283.804285) (xy 36.201115 -283.77316) (xy 36.243736 -283.748553)
			(xy 36.289752 -283.731101) (xy 36.337971 -283.721257) (xy 36.387146 -283.719276) (xy 36.436001 -283.725208)
			(xy 36.483272 -283.7389) (xy 36.527734 -283.759998) (xy 36.568237 -283.787954) (xy 36.60373 -283.822046)
			(xy 36.633295 -283.86139) (xy 36.656166 -283.904967) (xy 36.67175 -283.951648) (xy 36.679645 -284.000225)
			(xy 36.68014 -284.024832) (xy 37.018988 -284.024832) (xy 37.022948 -283.975778) (xy 37.034725 -283.927994)
			(xy 37.054016 -283.882718) (xy 37.080319 -283.841122) (xy 37.112954 -283.804285) (xy 37.151075 -283.77316)
			(xy 37.193696 -283.748553) (xy 37.239712 -283.731101) (xy 37.287931 -283.721257) (xy 37.337106 -283.719276)
			(xy 37.385961 -283.725208) (xy 37.433232 -283.7389) (xy 37.477694 -283.759998) (xy 37.518197 -283.787954)
			(xy 37.55369 -283.822046) (xy 37.583255 -283.86139) (xy 37.606126 -283.904967) (xy 37.62171 -283.951648)
			(xy 37.629605 -284.000225) (xy 37.6301 -284.024832) (xy 37.969202 -284.024832) (xy 37.973162 -283.975778)
			(xy 37.984939 -283.927994) (xy 38.00423 -283.882718) (xy 38.030533 -283.841122) (xy 38.063168 -283.804285)
			(xy 38.101289 -283.77316) (xy 38.14391 -283.748553) (xy 38.189926 -283.731101) (xy 38.238145 -283.721257)
			(xy 38.28732 -283.719276) (xy 38.336175 -283.725208) (xy 38.383446 -283.7389) (xy 38.427908 -283.759998)
			(xy 38.468411 -283.787954) (xy 38.503904 -283.822046) (xy 38.533469 -283.86139) (xy 38.55634 -283.904967)
			(xy 38.571924 -283.951648) (xy 38.579819 -284.000225) (xy 38.580314 -284.024832) (xy 38.919162 -284.024832)
			(xy 38.923122 -283.975778) (xy 38.934899 -283.927994) (xy 38.95419 -283.882718) (xy 38.980493 -283.841122)
			(xy 39.013128 -283.804285) (xy 39.051249 -283.77316) (xy 39.09387 -283.748553) (xy 39.139886 -283.731101)
			(xy 39.188105 -283.721257) (xy 39.23728 -283.719276) (xy 39.286135 -283.725208) (xy 39.333406 -283.7389)
			(xy 39.377868 -283.759998) (xy 39.418371 -283.787954) (xy 39.453864 -283.822046) (xy 39.483429 -283.86139)
			(xy 39.5063 -283.904967) (xy 39.521884 -283.951648) (xy 39.529779 -284.000225) (xy 39.530274 -284.024832)
			(xy 39.869122 -284.024832) (xy 39.873082 -283.975778) (xy 39.884859 -283.927994) (xy 39.90415 -283.882718)
			(xy 39.930453 -283.841122) (xy 39.963088 -283.804285) (xy 40.001209 -283.77316) (xy 40.04383 -283.748553)
			(xy 40.089846 -283.731101) (xy 40.138065 -283.721257) (xy 40.18724 -283.719276) (xy 40.236095 -283.725208)
			(xy 40.283366 -283.7389) (xy 40.327828 -283.759998) (xy 40.368331 -283.787954) (xy 40.403824 -283.822046)
			(xy 40.433389 -283.86139) (xy 40.45626 -283.904967) (xy 40.471844 -283.951648) (xy 40.479739 -284.000225)
			(xy 40.480234 -284.024832) (xy 40.819082 -284.024832) (xy 40.823042 -283.975778) (xy 40.834819 -283.927994)
			(xy 40.85411 -283.882718) (xy 40.880413 -283.841122) (xy 40.913048 -283.804285) (xy 40.951169 -283.77316)
			(xy 40.99379 -283.748553) (xy 41.039806 -283.731101) (xy 41.088025 -283.721257) (xy 41.1372 -283.719276)
			(xy 41.186055 -283.725208) (xy 41.233326 -283.7389) (xy 41.277788 -283.759998) (xy 41.318291 -283.787954)
			(xy 41.353784 -283.822046) (xy 41.383349 -283.86139) (xy 41.40622 -283.904967) (xy 41.421804 -283.951648)
			(xy 41.429699 -284.000225) (xy 41.430194 -284.024832) (xy 44.619176 -284.024832) (xy 44.623136 -283.975778)
			(xy 44.634913 -283.927994) (xy 44.654204 -283.882718) (xy 44.680507 -283.841122) (xy 44.713142 -283.804285)
			(xy 44.751263 -283.77316) (xy 44.793884 -283.748553) (xy 44.8399 -283.731101) (xy 44.888119 -283.721257)
			(xy 44.937294 -283.719276) (xy 44.986149 -283.725208) (xy 45.03342 -283.7389) (xy 45.077882 -283.759998)
			(xy 45.118385 -283.787954) (xy 45.153878 -283.822046) (xy 45.183443 -283.86139) (xy 45.206314 -283.904967)
			(xy 45.221898 -283.951648) (xy 45.229793 -284.000225) (xy 45.230288 -284.024832) (xy 45.569136 -284.024832)
			(xy 45.573096 -283.975778) (xy 45.584873 -283.927994) (xy 45.604164 -283.882718) (xy 45.630467 -283.841122)
			(xy 45.663102 -283.804285) (xy 45.701223 -283.77316) (xy 45.743844 -283.748553) (xy 45.78986 -283.731101)
			(xy 45.838079 -283.721257) (xy 45.887254 -283.719276) (xy 45.936109 -283.725208) (xy 45.98338 -283.7389)
			(xy 46.027842 -283.759998) (xy 46.068345 -283.787954) (xy 46.103838 -283.822046) (xy 46.133403 -283.86139)
			(xy 46.156274 -283.904967) (xy 46.171858 -283.951648) (xy 46.179753 -284.000225) (xy 46.180248 -284.024832)
			(xy 46.519096 -284.024832) (xy 46.523056 -283.975778) (xy 46.534833 -283.927994) (xy 46.554124 -283.882718)
			(xy 46.580427 -283.841122) (xy 46.613062 -283.804285) (xy 46.651183 -283.77316) (xy 46.693804 -283.748553)
			(xy 46.73982 -283.731101) (xy 46.788039 -283.721257) (xy 46.837214 -283.719276) (xy 46.886069 -283.725208)
			(xy 46.93334 -283.7389) (xy 46.977802 -283.759998) (xy 47.018305 -283.787954) (xy 47.053798 -283.822046)
			(xy 47.083363 -283.86139) (xy 47.106234 -283.904967) (xy 47.121818 -283.951648) (xy 47.129713 -284.000225)
			(xy 47.130208 -284.024832) (xy 47.469056 -284.024832) (xy 47.473016 -283.975778) (xy 47.484793 -283.927994)
			(xy 47.504084 -283.882718) (xy 47.530387 -283.841122) (xy 47.563022 -283.804285) (xy 47.601143 -283.77316)
			(xy 47.643764 -283.748553) (xy 47.68978 -283.731101) (xy 47.737999 -283.721257) (xy 47.787174 -283.719276)
			(xy 47.836029 -283.725208) (xy 47.8833 -283.7389) (xy 47.927762 -283.759998) (xy 47.968265 -283.787954)
			(xy 48.003758 -283.822046) (xy 48.033323 -283.86139) (xy 48.056194 -283.904967) (xy 48.071778 -283.951648)
			(xy 48.079673 -284.000225) (xy 48.080168 -284.024832) (xy 48.419016 -284.024832) (xy 48.422976 -283.975778)
			(xy 48.434753 -283.927994) (xy 48.454044 -283.882718) (xy 48.480347 -283.841122) (xy 48.512982 -283.804285)
			(xy 48.551103 -283.77316) (xy 48.593724 -283.748553) (xy 48.63974 -283.731101) (xy 48.687959 -283.721257)
			(xy 48.737134 -283.719276) (xy 48.785989 -283.725208) (xy 48.83326 -283.7389) (xy 48.877722 -283.759998)
			(xy 48.918225 -283.787954) (xy 48.953718 -283.822046) (xy 48.983283 -283.86139) (xy 49.006154 -283.904967)
			(xy 49.021738 -283.951648) (xy 49.029633 -284.000225) (xy 49.030128 -284.024832) (xy 49.368976 -284.024832)
			(xy 49.372936 -283.975778) (xy 49.384713 -283.927994) (xy 49.404004 -283.882718) (xy 49.430307 -283.841122)
			(xy 49.462942 -283.804285) (xy 49.501063 -283.77316) (xy 49.543684 -283.748553) (xy 49.5897 -283.731101)
			(xy 49.637919 -283.721257) (xy 49.687094 -283.719276) (xy 49.735949 -283.725208) (xy 49.78322 -283.7389)
			(xy 49.827682 -283.759998) (xy 49.868185 -283.787954) (xy 49.903678 -283.822046) (xy 49.933243 -283.86139)
			(xy 49.956114 -283.904967) (xy 49.971698 -283.951648) (xy 49.979593 -284.000225) (xy 49.980088 -284.024832)
			(xy 50.31919 -284.024832) (xy 50.32315 -283.975778) (xy 50.334927 -283.927994) (xy 50.354218 -283.882718)
			(xy 50.380521 -283.841122) (xy 50.413156 -283.804285) (xy 50.451277 -283.77316) (xy 50.493898 -283.748553)
			(xy 50.539914 -283.731101) (xy 50.588133 -283.721257) (xy 50.637308 -283.719276) (xy 50.686163 -283.725208)
			(xy 50.733434 -283.7389) (xy 50.777896 -283.759998) (xy 50.818399 -283.787954) (xy 50.853892 -283.822046)
			(xy 50.883457 -283.86139) (xy 50.906328 -283.904967) (xy 50.921912 -283.951648) (xy 50.929807 -284.000225)
			(xy 50.930302 -284.024832) (xy 51.26915 -284.024832) (xy 51.27311 -283.975778) (xy 51.284887 -283.927994)
			(xy 51.304178 -283.882718) (xy 51.330481 -283.841122) (xy 51.363116 -283.804285) (xy 51.401237 -283.77316)
			(xy 51.443858 -283.748553) (xy 51.489874 -283.731101) (xy 51.538093 -283.721257) (xy 51.587268 -283.719276)
			(xy 51.636123 -283.725208) (xy 51.683394 -283.7389) (xy 51.727856 -283.759998) (xy 51.768359 -283.787954)
			(xy 51.803852 -283.822046) (xy 51.833417 -283.86139) (xy 51.856288 -283.904967) (xy 51.871872 -283.951648)
			(xy 51.879767 -284.000225) (xy 51.880262 -284.024832) (xy 52.21911 -284.024832) (xy 52.22307 -283.975778)
			(xy 52.234847 -283.927994) (xy 52.254138 -283.882718) (xy 52.280441 -283.841122) (xy 52.313076 -283.804285)
			(xy 52.351197 -283.77316) (xy 52.393818 -283.748553) (xy 52.439834 -283.731101) (xy 52.488053 -283.721257)
			(xy 52.537228 -283.719276) (xy 52.586083 -283.725208) (xy 52.633354 -283.7389) (xy 52.677816 -283.759998)
			(xy 52.718319 -283.787954) (xy 52.753812 -283.822046) (xy 52.783377 -283.86139) (xy 52.806248 -283.904967)
			(xy 52.821832 -283.951648) (xy 52.829727 -284.000225) (xy 52.830222 -284.024832) (xy 53.16907 -284.024832)
			(xy 53.17303 -283.975778) (xy 53.184807 -283.927994) (xy 53.204098 -283.882718) (xy 53.230401 -283.841122)
			(xy 53.263036 -283.804285) (xy 53.301157 -283.77316) (xy 53.343778 -283.748553) (xy 53.389794 -283.731101)
			(xy 53.438013 -283.721257) (xy 53.487188 -283.719276) (xy 53.536043 -283.725208) (xy 53.583314 -283.7389)
			(xy 53.627776 -283.759998) (xy 53.668279 -283.787954) (xy 53.703772 -283.822046) (xy 53.733337 -283.86139)
			(xy 53.756208 -283.904967) (xy 53.771792 -283.951648) (xy 53.779687 -284.000225) (xy 53.780182 -284.024832)
			(xy 54.11903 -284.024832) (xy 54.12299 -283.975778) (xy 54.134767 -283.927994) (xy 54.154058 -283.882718)
			(xy 54.180361 -283.841122) (xy 54.212996 -283.804285) (xy 54.251117 -283.77316) (xy 54.293738 -283.748553)
			(xy 54.339754 -283.731101) (xy 54.387973 -283.721257) (xy 54.437148 -283.719276) (xy 54.486003 -283.725208)
			(xy 54.533274 -283.7389) (xy 54.577736 -283.759998) (xy 54.618239 -283.787954) (xy 54.653732 -283.822046)
			(xy 54.683297 -283.86139) (xy 54.706168 -283.904967) (xy 54.721752 -283.951648) (xy 54.729647 -284.000225)
			(xy 54.730142 -284.024832) (xy 55.06899 -284.024832) (xy 55.07295 -283.975778) (xy 55.084727 -283.927994)
			(xy 55.104018 -283.882718) (xy 55.130321 -283.841122) (xy 55.162956 -283.804285) (xy 55.201077 -283.77316)
			(xy 55.243698 -283.748553) (xy 55.289714 -283.731101) (xy 55.337933 -283.721257) (xy 55.387108 -283.719276)
			(xy 55.435963 -283.725208) (xy 55.483234 -283.7389) (xy 55.527696 -283.759998) (xy 55.568199 -283.787954)
			(xy 55.603692 -283.822046) (xy 55.633257 -283.86139) (xy 55.656128 -283.904967) (xy 55.671712 -283.951648)
			(xy 55.679607 -284.000225) (xy 55.680102 -284.024832) (xy 56.01895 -284.024832) (xy 56.02291 -283.975778)
			(xy 56.034687 -283.927994) (xy 56.053978 -283.882718) (xy 56.080281 -283.841122) (xy 56.112916 -283.804285)
			(xy 56.151037 -283.77316) (xy 56.193658 -283.748553) (xy 56.239674 -283.731101) (xy 56.287893 -283.721257)
			(xy 56.337068 -283.719276) (xy 56.385923 -283.725208) (xy 56.433194 -283.7389) (xy 56.477656 -283.759998)
			(xy 56.518159 -283.787954) (xy 56.553652 -283.822046) (xy 56.583217 -283.86139) (xy 56.606088 -283.904967)
			(xy 56.621672 -283.951648) (xy 56.629567 -284.000225) (xy 56.630062 -284.024832) (xy 56.969164 -284.024832)
			(xy 56.973124 -283.975778) (xy 56.984901 -283.927994) (xy 57.004192 -283.882718) (xy 57.030495 -283.841122)
			(xy 57.06313 -283.804285) (xy 57.101251 -283.77316) (xy 57.143872 -283.748553) (xy 57.189888 -283.731101)
			(xy 57.238107 -283.721257) (xy 57.287282 -283.719276) (xy 57.336137 -283.725208) (xy 57.383408 -283.7389)
			(xy 57.42787 -283.759998) (xy 57.468373 -283.787954) (xy 57.503866 -283.822046) (xy 57.533431 -283.86139)
			(xy 57.556302 -283.904967) (xy 57.571886 -283.951648) (xy 57.579781 -284.000225) (xy 57.580276 -284.024832)
			(xy 57.919124 -284.024832) (xy 57.923084 -283.975778) (xy 57.934861 -283.927994) (xy 57.954152 -283.882718)
			(xy 57.980455 -283.841122) (xy 58.01309 -283.804285) (xy 58.051211 -283.77316) (xy 58.093832 -283.748553)
			(xy 58.139848 -283.731101) (xy 58.188067 -283.721257) (xy 58.237242 -283.719276) (xy 58.286097 -283.725208)
			(xy 58.333368 -283.7389) (xy 58.37783 -283.759998) (xy 58.418333 -283.787954) (xy 58.453826 -283.822046)
			(xy 58.483391 -283.86139) (xy 58.506262 -283.904967) (xy 58.521846 -283.951648) (xy 58.529741 -284.000225)
			(xy 58.530236 -284.024832) (xy 59.819044 -284.024832) (xy 59.823004 -283.975778) (xy 59.834781 -283.927994)
			(xy 59.854072 -283.882718) (xy 59.880375 -283.841122) (xy 59.91301 -283.804285) (xy 59.951131 -283.77316)
			(xy 59.993752 -283.748553) (xy 60.039768 -283.731101) (xy 60.087987 -283.721257) (xy 60.137162 -283.719276)
			(xy 60.186017 -283.725208) (xy 60.233288 -283.7389) (xy 60.27775 -283.759998) (xy 60.318253 -283.787954)
			(xy 60.353746 -283.822046) (xy 60.383311 -283.86139) (xy 60.406182 -283.904967) (xy 60.421766 -283.951648)
			(xy 60.429661 -284.000225) (xy 60.430156 -284.024832) (xy 60.769004 -284.024832) (xy 60.772964 -283.975778)
			(xy 60.784741 -283.927994) (xy 60.804032 -283.882718) (xy 60.830335 -283.841122) (xy 60.86297 -283.804285)
			(xy 60.901091 -283.77316) (xy 60.943712 -283.748553) (xy 60.989728 -283.731101) (xy 61.037947 -283.721257)
			(xy 61.087122 -283.719276) (xy 61.135977 -283.725208) (xy 61.183248 -283.7389) (xy 61.22771 -283.759998)
			(xy 61.268213 -283.787954) (xy 61.303706 -283.822046) (xy 61.333271 -283.86139) (xy 61.356142 -283.904967)
			(xy 61.371726 -283.951648) (xy 61.379621 -284.000225) (xy 61.380116 -284.024832) (xy 61.718964 -284.024832)
			(xy 61.722924 -283.975778) (xy 61.734701 -283.927994) (xy 61.753992 -283.882718) (xy 61.780295 -283.841122)
			(xy 61.81293 -283.804285) (xy 61.851051 -283.77316) (xy 61.893672 -283.748553) (xy 61.939688 -283.731101)
			(xy 61.987907 -283.721257) (xy 62.037082 -283.719276) (xy 62.085937 -283.725208) (xy 62.133208 -283.7389)
			(xy 62.17767 -283.759998) (xy 62.218173 -283.787954) (xy 62.253666 -283.822046) (xy 62.283231 -283.86139)
			(xy 62.306102 -283.904967) (xy 62.321686 -283.951648) (xy 62.329581 -284.000225) (xy 62.330076 -284.024832)
			(xy 62.669178 -284.024832) (xy 62.673138 -283.975778) (xy 62.684915 -283.927994) (xy 62.704206 -283.882718)
			(xy 62.730509 -283.841122) (xy 62.763144 -283.804285) (xy 62.801265 -283.77316) (xy 62.843886 -283.748553)
			(xy 62.889902 -283.731101) (xy 62.938121 -283.721257) (xy 62.987296 -283.719276) (xy 63.036151 -283.725208)
			(xy 63.083422 -283.7389) (xy 63.127884 -283.759998) (xy 63.168387 -283.787954) (xy 63.20388 -283.822046)
			(xy 63.233445 -283.86139) (xy 63.256316 -283.904967) (xy 63.2719 -283.951648) (xy 63.279795 -284.000225)
			(xy 63.28029 -284.024832) (xy 63.619138 -284.024832) (xy 63.623098 -283.975778) (xy 63.634875 -283.927994)
			(xy 63.654166 -283.882718) (xy 63.680469 -283.841122) (xy 63.713104 -283.804285) (xy 63.751225 -283.77316)
			(xy 63.793846 -283.748553) (xy 63.839862 -283.731101) (xy 63.888081 -283.721257) (xy 63.937256 -283.719276)
			(xy 63.986111 -283.725208) (xy 64.033382 -283.7389) (xy 64.077844 -283.759998) (xy 64.118347 -283.787954)
			(xy 64.15384 -283.822046) (xy 64.183405 -283.86139) (xy 64.206276 -283.904967) (xy 64.22186 -283.951648)
			(xy 64.229755 -284.000225) (xy 64.23025 -284.024832) (xy 64.569098 -284.024832) (xy 64.573058 -283.975778)
			(xy 64.584835 -283.927994) (xy 64.604126 -283.882718) (xy 64.630429 -283.841122) (xy 64.663064 -283.804285)
			(xy 64.701185 -283.77316) (xy 64.743806 -283.748553) (xy 64.789822 -283.731101) (xy 64.838041 -283.721257)
			(xy 64.887216 -283.719276) (xy 64.936071 -283.725208) (xy 64.983342 -283.7389) (xy 65.027804 -283.759998)
			(xy 65.068307 -283.787954) (xy 65.1038 -283.822046) (xy 65.133365 -283.86139) (xy 65.156236 -283.904967)
			(xy 65.17182 -283.951648) (xy 65.179715 -284.000225) (xy 65.18021 -284.024832) (xy 65.519058 -284.024832)
			(xy 65.523018 -283.975778) (xy 65.534795 -283.927994) (xy 65.554086 -283.882718) (xy 65.580389 -283.841122)
			(xy 65.613024 -283.804285) (xy 65.651145 -283.77316) (xy 65.693766 -283.748553) (xy 65.739782 -283.731101)
			(xy 65.788001 -283.721257) (xy 65.837176 -283.719276) (xy 65.886031 -283.725208) (xy 65.933302 -283.7389)
			(xy 65.977764 -283.759998) (xy 66.018267 -283.787954) (xy 66.05376 -283.822046) (xy 66.083325 -283.86139)
			(xy 66.106196 -283.904967) (xy 66.12178 -283.951648) (xy 66.129675 -284.000225) (xy 66.13017 -284.024832)
			(xy 66.469018 -284.024832) (xy 66.472978 -283.975778) (xy 66.484755 -283.927994) (xy 66.504046 -283.882718)
			(xy 66.530349 -283.841122) (xy 66.562984 -283.804285) (xy 66.601105 -283.77316) (xy 66.643726 -283.748553)
			(xy 66.689742 -283.731101) (xy 66.737961 -283.721257) (xy 66.787136 -283.719276) (xy 66.835991 -283.725208)
			(xy 66.883262 -283.7389) (xy 66.927724 -283.759998) (xy 66.968227 -283.787954) (xy 67.00372 -283.822046)
			(xy 67.033285 -283.86139) (xy 67.056156 -283.904967) (xy 67.07174 -283.951648) (xy 67.079635 -284.000225)
			(xy 67.08013 -284.024832) (xy 68.368938 -284.024832) (xy 68.372898 -283.975778) (xy 68.384675 -283.927994)
			(xy 68.403966 -283.882718) (xy 68.430269 -283.841122) (xy 68.462904 -283.804285) (xy 68.501025 -283.77316)
			(xy 68.543646 -283.748553) (xy 68.589662 -283.731101) (xy 68.637881 -283.721257) (xy 68.687056 -283.719276)
			(xy 68.735911 -283.725208) (xy 68.783182 -283.7389) (xy 68.827644 -283.759998) (xy 68.868147 -283.787954)
			(xy 68.90364 -283.822046) (xy 68.933205 -283.86139) (xy 68.956076 -283.904967) (xy 68.97166 -283.951648)
			(xy 68.979555 -284.000225) (xy 68.98005 -284.024832) (xy 69.319152 -284.024832) (xy 69.323112 -283.975778)
			(xy 69.334889 -283.927994) (xy 69.35418 -283.882718) (xy 69.380483 -283.841122) (xy 69.413118 -283.804285)
			(xy 69.451239 -283.77316) (xy 69.49386 -283.748553) (xy 69.539876 -283.731101) (xy 69.588095 -283.721257)
			(xy 69.63727 -283.719276) (xy 69.686125 -283.725208) (xy 69.733396 -283.7389) (xy 69.777858 -283.759998)
			(xy 69.818361 -283.787954) (xy 69.853854 -283.822046) (xy 69.883419 -283.86139) (xy 69.90629 -283.904967)
			(xy 69.921874 -283.951648) (xy 69.929769 -284.000225) (xy 69.930264 -284.024832) (xy 70.269112 -284.024832)
			(xy 70.273072 -283.975778) (xy 70.284849 -283.927994) (xy 70.30414 -283.882718) (xy 70.330443 -283.841122)
			(xy 70.363078 -283.804285) (xy 70.401199 -283.77316) (xy 70.44382 -283.748553) (xy 70.489836 -283.731101)
			(xy 70.538055 -283.721257) (xy 70.58723 -283.719276) (xy 70.636085 -283.725208) (xy 70.683356 -283.7389)
			(xy 70.727818 -283.759998) (xy 70.768321 -283.787954) (xy 70.803814 -283.822046) (xy 70.833379 -283.86139)
			(xy 70.85625 -283.904967) (xy 70.871834 -283.951648) (xy 70.879729 -284.000225) (xy 70.880224 -284.024832)
			(xy 71.219072 -284.024832) (xy 71.223032 -283.975778) (xy 71.234809 -283.927994) (xy 71.2541 -283.882718)
			(xy 71.280403 -283.841122) (xy 71.313038 -283.804285) (xy 71.351159 -283.77316) (xy 71.39378 -283.748553)
			(xy 71.439796 -283.731101) (xy 71.488015 -283.721257) (xy 71.53719 -283.719276) (xy 71.586045 -283.725208)
			(xy 71.633316 -283.7389) (xy 71.677778 -283.759998) (xy 71.718281 -283.787954) (xy 71.753774 -283.822046)
			(xy 71.783339 -283.86139) (xy 71.80621 -283.904967) (xy 71.821794 -283.951648) (xy 71.829689 -284.000225)
			(xy 71.830184 -284.024832) (xy 72.169032 -284.024832) (xy 72.172992 -283.975778) (xy 72.184769 -283.927994)
			(xy 72.20406 -283.882718) (xy 72.230363 -283.841122) (xy 72.262998 -283.804285) (xy 72.301119 -283.77316)
			(xy 72.34374 -283.748553) (xy 72.389756 -283.731101) (xy 72.437975 -283.721257) (xy 72.48715 -283.719276)
			(xy 72.536005 -283.725208) (xy 72.583276 -283.7389) (xy 72.627738 -283.759998) (xy 72.668241 -283.787954)
			(xy 72.703734 -283.822046) (xy 72.733299 -283.86139) (xy 72.75617 -283.904967) (xy 72.771754 -283.951648)
			(xy 72.779649 -284.000225) (xy 72.780144 -284.024832) (xy 72.779649 -284.049439) (xy 72.771754 -284.098016)
			(xy 72.75617 -284.144697) (xy 72.733299 -284.188274) (xy 72.703734 -284.227618) (xy 72.668241 -284.26171)
			(xy 72.627738 -284.289666) (xy 72.583276 -284.310764) (xy 72.536005 -284.324456) (xy 72.48715 -284.330388)
			(xy 72.437975 -284.328407) (xy 72.389756 -284.318563) (xy 72.34374 -284.301111) (xy 72.301119 -284.276504)
			(xy 72.262998 -284.245379) (xy 72.230363 -284.208542) (xy 72.20406 -284.166946) (xy 72.184769 -284.12167)
			(xy 72.172992 -284.073886) (xy 72.169032 -284.024832) (xy 71.830184 -284.024832) (xy 71.829689 -284.049439)
			(xy 71.821794 -284.098016) (xy 71.80621 -284.144697) (xy 71.783339 -284.188274) (xy 71.753774 -284.227618)
			(xy 71.718281 -284.26171) (xy 71.677778 -284.289666) (xy 71.633316 -284.310764) (xy 71.586045 -284.324456)
			(xy 71.53719 -284.330388) (xy 71.488015 -284.328407) (xy 71.439796 -284.318563) (xy 71.39378 -284.301111)
			(xy 71.351159 -284.276504) (xy 71.313038 -284.245379) (xy 71.280403 -284.208542) (xy 71.2541 -284.166946)
			(xy 71.234809 -284.12167) (xy 71.223032 -284.073886) (xy 71.219072 -284.024832) (xy 70.880224 -284.024832)
			(xy 70.879729 -284.049439) (xy 70.871834 -284.098016) (xy 70.85625 -284.144697) (xy 70.833379 -284.188274)
			(xy 70.803814 -284.227618) (xy 70.768321 -284.26171) (xy 70.727818 -284.289666) (xy 70.683356 -284.310764)
			(xy 70.636085 -284.324456) (xy 70.58723 -284.330388) (xy 70.538055 -284.328407) (xy 70.489836 -284.318563)
			(xy 70.44382 -284.301111) (xy 70.401199 -284.276504) (xy 70.363078 -284.245379) (xy 70.330443 -284.208542)
			(xy 70.30414 -284.166946) (xy 70.284849 -284.12167) (xy 70.273072 -284.073886) (xy 70.269112 -284.024832)
			(xy 69.930264 -284.024832) (xy 69.929769 -284.049439) (xy 69.921874 -284.098016) (xy 69.90629 -284.144697)
			(xy 69.883419 -284.188274) (xy 69.853854 -284.227618) (xy 69.818361 -284.26171) (xy 69.777858 -284.289666)
			(xy 69.733396 -284.310764) (xy 69.686125 -284.324456) (xy 69.63727 -284.330388) (xy 69.588095 -284.328407)
			(xy 69.539876 -284.318563) (xy 69.49386 -284.301111) (xy 69.451239 -284.276504) (xy 69.413118 -284.245379)
			(xy 69.380483 -284.208542) (xy 69.35418 -284.166946) (xy 69.334889 -284.12167) (xy 69.323112 -284.073886)
			(xy 69.319152 -284.024832) (xy 68.98005 -284.024832) (xy 68.979555 -284.049439) (xy 68.97166 -284.098016)
			(xy 68.956076 -284.144697) (xy 68.933205 -284.188274) (xy 68.90364 -284.227618) (xy 68.868147 -284.26171)
			(xy 68.827644 -284.289666) (xy 68.783182 -284.310764) (xy 68.735911 -284.324456) (xy 68.687056 -284.330388)
			(xy 68.637881 -284.328407) (xy 68.589662 -284.318563) (xy 68.543646 -284.301111) (xy 68.501025 -284.276504)
			(xy 68.462904 -284.245379) (xy 68.430269 -284.208542) (xy 68.403966 -284.166946) (xy 68.384675 -284.12167)
			(xy 68.372898 -284.073886) (xy 68.368938 -284.024832) (xy 67.08013 -284.024832) (xy 67.079635 -284.049439)
			(xy 67.07174 -284.098016) (xy 67.056156 -284.144697) (xy 67.033285 -284.188274) (xy 67.00372 -284.227618)
			(xy 66.968227 -284.26171) (xy 66.927724 -284.289666) (xy 66.883262 -284.310764) (xy 66.835991 -284.324456)
			(xy 66.787136 -284.330388) (xy 66.737961 -284.328407) (xy 66.689742 -284.318563) (xy 66.643726 -284.301111)
			(xy 66.601105 -284.276504) (xy 66.562984 -284.245379) (xy 66.530349 -284.208542) (xy 66.504046 -284.166946)
			(xy 66.484755 -284.12167) (xy 66.472978 -284.073886) (xy 66.469018 -284.024832) (xy 66.13017 -284.024832)
			(xy 66.129675 -284.049439) (xy 66.12178 -284.098016) (xy 66.106196 -284.144697) (xy 66.083325 -284.188274)
			(xy 66.05376 -284.227618) (xy 66.018267 -284.26171) (xy 65.977764 -284.289666) (xy 65.933302 -284.310764)
			(xy 65.886031 -284.324456) (xy 65.837176 -284.330388) (xy 65.788001 -284.328407) (xy 65.739782 -284.318563)
			(xy 65.693766 -284.301111) (xy 65.651145 -284.276504) (xy 65.613024 -284.245379) (xy 65.580389 -284.208542)
			(xy 65.554086 -284.166946) (xy 65.534795 -284.12167) (xy 65.523018 -284.073886) (xy 65.519058 -284.024832)
			(xy 65.18021 -284.024832) (xy 65.179715 -284.049439) (xy 65.17182 -284.098016) (xy 65.156236 -284.144697)
			(xy 65.133365 -284.188274) (xy 65.1038 -284.227618) (xy 65.068307 -284.26171) (xy 65.027804 -284.289666)
			(xy 64.983342 -284.310764) (xy 64.936071 -284.324456) (xy 64.887216 -284.330388) (xy 64.838041 -284.328407)
			(xy 64.789822 -284.318563) (xy 64.743806 -284.301111) (xy 64.701185 -284.276504) (xy 64.663064 -284.245379)
			(xy 64.630429 -284.208542) (xy 64.604126 -284.166946) (xy 64.584835 -284.12167) (xy 64.573058 -284.073886)
			(xy 64.569098 -284.024832) (xy 64.23025 -284.024832) (xy 64.229755 -284.049439) (xy 64.22186 -284.098016)
			(xy 64.206276 -284.144697) (xy 64.183405 -284.188274) (xy 64.15384 -284.227618) (xy 64.118347 -284.26171)
			(xy 64.077844 -284.289666) (xy 64.033382 -284.310764) (xy 63.986111 -284.324456) (xy 63.937256 -284.330388)
			(xy 63.888081 -284.328407) (xy 63.839862 -284.318563) (xy 63.793846 -284.301111) (xy 63.751225 -284.276504)
			(xy 63.713104 -284.245379) (xy 63.680469 -284.208542) (xy 63.654166 -284.166946) (xy 63.634875 -284.12167)
			(xy 63.623098 -284.073886) (xy 63.619138 -284.024832) (xy 63.28029 -284.024832) (xy 63.279795 -284.049439)
			(xy 63.2719 -284.098016) (xy 63.256316 -284.144697) (xy 63.233445 -284.188274) (xy 63.20388 -284.227618)
			(xy 63.168387 -284.26171) (xy 63.127884 -284.289666) (xy 63.083422 -284.310764) (xy 63.036151 -284.324456)
			(xy 62.987296 -284.330388) (xy 62.938121 -284.328407) (xy 62.889902 -284.318563) (xy 62.843886 -284.301111)
			(xy 62.801265 -284.276504) (xy 62.763144 -284.245379) (xy 62.730509 -284.208542) (xy 62.704206 -284.166946)
			(xy 62.684915 -284.12167) (xy 62.673138 -284.073886) (xy 62.669178 -284.024832) (xy 62.330076 -284.024832)
			(xy 62.329581 -284.049439) (xy 62.321686 -284.098016) (xy 62.306102 -284.144697) (xy 62.283231 -284.188274)
			(xy 62.253666 -284.227618) (xy 62.218173 -284.26171) (xy 62.17767 -284.289666) (xy 62.133208 -284.310764)
			(xy 62.085937 -284.324456) (xy 62.037082 -284.330388) (xy 61.987907 -284.328407) (xy 61.939688 -284.318563)
			(xy 61.893672 -284.301111) (xy 61.851051 -284.276504) (xy 61.81293 -284.245379) (xy 61.780295 -284.208542)
			(xy 61.753992 -284.166946) (xy 61.734701 -284.12167) (xy 61.722924 -284.073886) (xy 61.718964 -284.024832)
			(xy 61.380116 -284.024832) (xy 61.379621 -284.049439) (xy 61.371726 -284.098016) (xy 61.356142 -284.144697)
			(xy 61.333271 -284.188274) (xy 61.303706 -284.227618) (xy 61.268213 -284.26171) (xy 61.22771 -284.289666)
			(xy 61.183248 -284.310764) (xy 61.135977 -284.324456) (xy 61.087122 -284.330388) (xy 61.037947 -284.328407)
			(xy 60.989728 -284.318563) (xy 60.943712 -284.301111) (xy 60.901091 -284.276504) (xy 60.86297 -284.245379)
			(xy 60.830335 -284.208542) (xy 60.804032 -284.166946) (xy 60.784741 -284.12167) (xy 60.772964 -284.073886)
			(xy 60.769004 -284.024832) (xy 60.430156 -284.024832) (xy 60.429661 -284.049439) (xy 60.421766 -284.098016)
			(xy 60.406182 -284.144697) (xy 60.383311 -284.188274) (xy 60.353746 -284.227618) (xy 60.318253 -284.26171)
			(xy 60.27775 -284.289666) (xy 60.233288 -284.310764) (xy 60.186017 -284.324456) (xy 60.137162 -284.330388)
			(xy 60.087987 -284.328407) (xy 60.039768 -284.318563) (xy 59.993752 -284.301111) (xy 59.951131 -284.276504)
			(xy 59.91301 -284.245379) (xy 59.880375 -284.208542) (xy 59.854072 -284.166946) (xy 59.834781 -284.12167)
			(xy 59.823004 -284.073886) (xy 59.819044 -284.024832) (xy 58.530236 -284.024832) (xy 58.529741 -284.049439)
			(xy 58.521846 -284.098016) (xy 58.506262 -284.144697) (xy 58.483391 -284.188274) (xy 58.453826 -284.227618)
			(xy 58.418333 -284.26171) (xy 58.37783 -284.289666) (xy 58.333368 -284.310764) (xy 58.286097 -284.324456)
			(xy 58.237242 -284.330388) (xy 58.188067 -284.328407) (xy 58.139848 -284.318563) (xy 58.093832 -284.301111)
			(xy 58.051211 -284.276504) (xy 58.01309 -284.245379) (xy 57.980455 -284.208542) (xy 57.954152 -284.166946)
			(xy 57.934861 -284.12167) (xy 57.923084 -284.073886) (xy 57.919124 -284.024832) (xy 57.580276 -284.024832)
			(xy 57.579781 -284.049439) (xy 57.571886 -284.098016) (xy 57.556302 -284.144697) (xy 57.533431 -284.188274)
			(xy 57.503866 -284.227618) (xy 57.468373 -284.26171) (xy 57.42787 -284.289666) (xy 57.383408 -284.310764)
			(xy 57.336137 -284.324456) (xy 57.287282 -284.330388) (xy 57.238107 -284.328407) (xy 57.189888 -284.318563)
			(xy 57.143872 -284.301111) (xy 57.101251 -284.276504) (xy 57.06313 -284.245379) (xy 57.030495 -284.208542)
			(xy 57.004192 -284.166946) (xy 56.984901 -284.12167) (xy 56.973124 -284.073886) (xy 56.969164 -284.024832)
			(xy 56.630062 -284.024832) (xy 56.629567 -284.049439) (xy 56.621672 -284.098016) (xy 56.606088 -284.144697)
			(xy 56.583217 -284.188274) (xy 56.553652 -284.227618) (xy 56.518159 -284.26171) (xy 56.477656 -284.289666)
			(xy 56.433194 -284.310764) (xy 56.385923 -284.324456) (xy 56.337068 -284.330388) (xy 56.287893 -284.328407)
			(xy 56.239674 -284.318563) (xy 56.193658 -284.301111) (xy 56.151037 -284.276504) (xy 56.112916 -284.245379)
			(xy 56.080281 -284.208542) (xy 56.053978 -284.166946) (xy 56.034687 -284.12167) (xy 56.02291 -284.073886)
			(xy 56.01895 -284.024832) (xy 55.680102 -284.024832) (xy 55.679607 -284.049439) (xy 55.671712 -284.098016)
			(xy 55.656128 -284.144697) (xy 55.633257 -284.188274) (xy 55.603692 -284.227618) (xy 55.568199 -284.26171)
			(xy 55.527696 -284.289666) (xy 55.483234 -284.310764) (xy 55.435963 -284.324456) (xy 55.387108 -284.330388)
			(xy 55.337933 -284.328407) (xy 55.289714 -284.318563) (xy 55.243698 -284.301111) (xy 55.201077 -284.276504)
			(xy 55.162956 -284.245379) (xy 55.130321 -284.208542) (xy 55.104018 -284.166946) (xy 55.084727 -284.12167)
			(xy 55.07295 -284.073886) (xy 55.06899 -284.024832) (xy 54.730142 -284.024832) (xy 54.729647 -284.049439)
			(xy 54.721752 -284.098016) (xy 54.706168 -284.144697) (xy 54.683297 -284.188274) (xy 54.653732 -284.227618)
			(xy 54.618239 -284.26171) (xy 54.577736 -284.289666) (xy 54.533274 -284.310764) (xy 54.486003 -284.324456)
			(xy 54.437148 -284.330388) (xy 54.387973 -284.328407) (xy 54.339754 -284.318563) (xy 54.293738 -284.301111)
			(xy 54.251117 -284.276504) (xy 54.212996 -284.245379) (xy 54.180361 -284.208542) (xy 54.154058 -284.166946)
			(xy 54.134767 -284.12167) (xy 54.12299 -284.073886) (xy 54.11903 -284.024832) (xy 53.780182 -284.024832)
			(xy 53.779687 -284.049439) (xy 53.771792 -284.098016) (xy 53.756208 -284.144697) (xy 53.733337 -284.188274)
			(xy 53.703772 -284.227618) (xy 53.668279 -284.26171) (xy 53.627776 -284.289666) (xy 53.583314 -284.310764)
			(xy 53.536043 -284.324456) (xy 53.487188 -284.330388) (xy 53.438013 -284.328407) (xy 53.389794 -284.318563)
			(xy 53.343778 -284.301111) (xy 53.301157 -284.276504) (xy 53.263036 -284.245379) (xy 53.230401 -284.208542)
			(xy 53.204098 -284.166946) (xy 53.184807 -284.12167) (xy 53.17303 -284.073886) (xy 53.16907 -284.024832)
			(xy 52.830222 -284.024832) (xy 52.829727 -284.049439) (xy 52.821832 -284.098016) (xy 52.806248 -284.144697)
			(xy 52.783377 -284.188274) (xy 52.753812 -284.227618) (xy 52.718319 -284.26171) (xy 52.677816 -284.289666)
			(xy 52.633354 -284.310764) (xy 52.586083 -284.324456) (xy 52.537228 -284.330388) (xy 52.488053 -284.328407)
			(xy 52.439834 -284.318563) (xy 52.393818 -284.301111) (xy 52.351197 -284.276504) (xy 52.313076 -284.245379)
			(xy 52.280441 -284.208542) (xy 52.254138 -284.166946) (xy 52.234847 -284.12167) (xy 52.22307 -284.073886)
			(xy 52.21911 -284.024832) (xy 51.880262 -284.024832) (xy 51.879767 -284.049439) (xy 51.871872 -284.098016)
			(xy 51.856288 -284.144697) (xy 51.833417 -284.188274) (xy 51.803852 -284.227618) (xy 51.768359 -284.26171)
			(xy 51.727856 -284.289666) (xy 51.683394 -284.310764) (xy 51.636123 -284.324456) (xy 51.587268 -284.330388)
			(xy 51.538093 -284.328407) (xy 51.489874 -284.318563) (xy 51.443858 -284.301111) (xy 51.401237 -284.276504)
			(xy 51.363116 -284.245379) (xy 51.330481 -284.208542) (xy 51.304178 -284.166946) (xy 51.284887 -284.12167)
			(xy 51.27311 -284.073886) (xy 51.26915 -284.024832) (xy 50.930302 -284.024832) (xy 50.929807 -284.049439)
			(xy 50.921912 -284.098016) (xy 50.906328 -284.144697) (xy 50.883457 -284.188274) (xy 50.853892 -284.227618)
			(xy 50.818399 -284.26171) (xy 50.777896 -284.289666) (xy 50.733434 -284.310764) (xy 50.686163 -284.324456)
			(xy 50.637308 -284.330388) (xy 50.588133 -284.328407) (xy 50.539914 -284.318563) (xy 50.493898 -284.301111)
			(xy 50.451277 -284.276504) (xy 50.413156 -284.245379) (xy 50.380521 -284.208542) (xy 50.354218 -284.166946)
			(xy 50.334927 -284.12167) (xy 50.32315 -284.073886) (xy 50.31919 -284.024832) (xy 49.980088 -284.024832)
			(xy 49.979593 -284.049439) (xy 49.971698 -284.098016) (xy 49.956114 -284.144697) (xy 49.933243 -284.188274)
			(xy 49.903678 -284.227618) (xy 49.868185 -284.26171) (xy 49.827682 -284.289666) (xy 49.78322 -284.310764)
			(xy 49.735949 -284.324456) (xy 49.687094 -284.330388) (xy 49.637919 -284.328407) (xy 49.5897 -284.318563)
			(xy 49.543684 -284.301111) (xy 49.501063 -284.276504) (xy 49.462942 -284.245379) (xy 49.430307 -284.208542)
			(xy 49.404004 -284.166946) (xy 49.384713 -284.12167) (xy 49.372936 -284.073886) (xy 49.368976 -284.024832)
			(xy 49.030128 -284.024832) (xy 49.029633 -284.049439) (xy 49.021738 -284.098016) (xy 49.006154 -284.144697)
			(xy 48.983283 -284.188274) (xy 48.953718 -284.227618) (xy 48.918225 -284.26171) (xy 48.877722 -284.289666)
			(xy 48.83326 -284.310764) (xy 48.785989 -284.324456) (xy 48.737134 -284.330388) (xy 48.687959 -284.328407)
			(xy 48.63974 -284.318563) (xy 48.593724 -284.301111) (xy 48.551103 -284.276504) (xy 48.512982 -284.245379)
			(xy 48.480347 -284.208542) (xy 48.454044 -284.166946) (xy 48.434753 -284.12167) (xy 48.422976 -284.073886)
			(xy 48.419016 -284.024832) (xy 48.080168 -284.024832) (xy 48.079673 -284.049439) (xy 48.071778 -284.098016)
			(xy 48.056194 -284.144697) (xy 48.033323 -284.188274) (xy 48.003758 -284.227618) (xy 47.968265 -284.26171)
			(xy 47.927762 -284.289666) (xy 47.8833 -284.310764) (xy 47.836029 -284.324456) (xy 47.787174 -284.330388)
			(xy 47.737999 -284.328407) (xy 47.68978 -284.318563) (xy 47.643764 -284.301111) (xy 47.601143 -284.276504)
			(xy 47.563022 -284.245379) (xy 47.530387 -284.208542) (xy 47.504084 -284.166946) (xy 47.484793 -284.12167)
			(xy 47.473016 -284.073886) (xy 47.469056 -284.024832) (xy 47.130208 -284.024832) (xy 47.129713 -284.049439)
			(xy 47.121818 -284.098016) (xy 47.106234 -284.144697) (xy 47.083363 -284.188274) (xy 47.053798 -284.227618)
			(xy 47.018305 -284.26171) (xy 46.977802 -284.289666) (xy 46.93334 -284.310764) (xy 46.886069 -284.324456)
			(xy 46.837214 -284.330388) (xy 46.788039 -284.328407) (xy 46.73982 -284.318563) (xy 46.693804 -284.301111)
			(xy 46.651183 -284.276504) (xy 46.613062 -284.245379) (xy 46.580427 -284.208542) (xy 46.554124 -284.166946)
			(xy 46.534833 -284.12167) (xy 46.523056 -284.073886) (xy 46.519096 -284.024832) (xy 46.180248 -284.024832)
			(xy 46.179753 -284.049439) (xy 46.171858 -284.098016) (xy 46.156274 -284.144697) (xy 46.133403 -284.188274)
			(xy 46.103838 -284.227618) (xy 46.068345 -284.26171) (xy 46.027842 -284.289666) (xy 45.98338 -284.310764)
			(xy 45.936109 -284.324456) (xy 45.887254 -284.330388) (xy 45.838079 -284.328407) (xy 45.78986 -284.318563)
			(xy 45.743844 -284.301111) (xy 45.701223 -284.276504) (xy 45.663102 -284.245379) (xy 45.630467 -284.208542)
			(xy 45.604164 -284.166946) (xy 45.584873 -284.12167) (xy 45.573096 -284.073886) (xy 45.569136 -284.024832)
			(xy 45.230288 -284.024832) (xy 45.229793 -284.049439) (xy 45.221898 -284.098016) (xy 45.206314 -284.144697)
			(xy 45.183443 -284.188274) (xy 45.153878 -284.227618) (xy 45.118385 -284.26171) (xy 45.077882 -284.289666)
			(xy 45.03342 -284.310764) (xy 44.986149 -284.324456) (xy 44.937294 -284.330388) (xy 44.888119 -284.328407)
			(xy 44.8399 -284.318563) (xy 44.793884 -284.301111) (xy 44.751263 -284.276504) (xy 44.713142 -284.245379)
			(xy 44.680507 -284.208542) (xy 44.654204 -284.166946) (xy 44.634913 -284.12167) (xy 44.623136 -284.073886)
			(xy 44.619176 -284.024832) (xy 41.430194 -284.024832) (xy 41.429699 -284.049439) (xy 41.421804 -284.098016)
			(xy 41.40622 -284.144697) (xy 41.383349 -284.188274) (xy 41.353784 -284.227618) (xy 41.318291 -284.26171)
			(xy 41.277788 -284.289666) (xy 41.233326 -284.310764) (xy 41.186055 -284.324456) (xy 41.1372 -284.330388)
			(xy 41.088025 -284.328407) (xy 41.039806 -284.318563) (xy 40.99379 -284.301111) (xy 40.951169 -284.276504)
			(xy 40.913048 -284.245379) (xy 40.880413 -284.208542) (xy 40.85411 -284.166946) (xy 40.834819 -284.12167)
			(xy 40.823042 -284.073886) (xy 40.819082 -284.024832) (xy 40.480234 -284.024832) (xy 40.479739 -284.049439)
			(xy 40.471844 -284.098016) (xy 40.45626 -284.144697) (xy 40.433389 -284.188274) (xy 40.403824 -284.227618)
			(xy 40.368331 -284.26171) (xy 40.327828 -284.289666) (xy 40.283366 -284.310764) (xy 40.236095 -284.324456)
			(xy 40.18724 -284.330388) (xy 40.138065 -284.328407) (xy 40.089846 -284.318563) (xy 40.04383 -284.301111)
			(xy 40.001209 -284.276504) (xy 39.963088 -284.245379) (xy 39.930453 -284.208542) (xy 39.90415 -284.166946)
			(xy 39.884859 -284.12167) (xy 39.873082 -284.073886) (xy 39.869122 -284.024832) (xy 39.530274 -284.024832)
			(xy 39.529779 -284.049439) (xy 39.521884 -284.098016) (xy 39.5063 -284.144697) (xy 39.483429 -284.188274)
			(xy 39.453864 -284.227618) (xy 39.418371 -284.26171) (xy 39.377868 -284.289666) (xy 39.333406 -284.310764)
			(xy 39.286135 -284.324456) (xy 39.23728 -284.330388) (xy 39.188105 -284.328407) (xy 39.139886 -284.318563)
			(xy 39.09387 -284.301111) (xy 39.051249 -284.276504) (xy 39.013128 -284.245379) (xy 38.980493 -284.208542)
			(xy 38.95419 -284.166946) (xy 38.934899 -284.12167) (xy 38.923122 -284.073886) (xy 38.919162 -284.024832)
			(xy 38.580314 -284.024832) (xy 38.579819 -284.049439) (xy 38.571924 -284.098016) (xy 38.55634 -284.144697)
			(xy 38.533469 -284.188274) (xy 38.503904 -284.227618) (xy 38.468411 -284.26171) (xy 38.427908 -284.289666)
			(xy 38.383446 -284.310764) (xy 38.336175 -284.324456) (xy 38.28732 -284.330388) (xy 38.238145 -284.328407)
			(xy 38.189926 -284.318563) (xy 38.14391 -284.301111) (xy 38.101289 -284.276504) (xy 38.063168 -284.245379)
			(xy 38.030533 -284.208542) (xy 38.00423 -284.166946) (xy 37.984939 -284.12167) (xy 37.973162 -284.073886)
			(xy 37.969202 -284.024832) (xy 37.6301 -284.024832) (xy 37.629605 -284.049439) (xy 37.62171 -284.098016)
			(xy 37.606126 -284.144697) (xy 37.583255 -284.188274) (xy 37.55369 -284.227618) (xy 37.518197 -284.26171)
			(xy 37.477694 -284.289666) (xy 37.433232 -284.310764) (xy 37.385961 -284.324456) (xy 37.337106 -284.330388)
			(xy 37.287931 -284.328407) (xy 37.239712 -284.318563) (xy 37.193696 -284.301111) (xy 37.151075 -284.276504)
			(xy 37.112954 -284.245379) (xy 37.080319 -284.208542) (xy 37.054016 -284.166946) (xy 37.034725 -284.12167)
			(xy 37.022948 -284.073886) (xy 37.018988 -284.024832) (xy 36.68014 -284.024832) (xy 36.679645 -284.049439)
			(xy 36.67175 -284.098016) (xy 36.656166 -284.144697) (xy 36.633295 -284.188274) (xy 36.60373 -284.227618)
			(xy 36.568237 -284.26171) (xy 36.527734 -284.289666) (xy 36.483272 -284.310764) (xy 36.436001 -284.324456)
			(xy 36.387146 -284.330388) (xy 36.337971 -284.328407) (xy 36.289752 -284.318563) (xy 36.243736 -284.301111)
			(xy 36.201115 -284.276504) (xy 36.162994 -284.245379) (xy 36.130359 -284.208542) (xy 36.104056 -284.166946)
			(xy 36.084765 -284.12167) (xy 36.072988 -284.073886) (xy 36.069028 -284.024832) (xy 34.361341 -284.024832)
			(xy 34.359791 -284.029983) (xy 34.336119 -284.08048) (xy 34.305346 -284.126993) (xy 34.268129 -284.16853)
			(xy 34.225261 -284.204205) (xy 34.177655 -284.233259) (xy 34.126326 -284.255071) (xy 34.072369 -284.269177)
			(xy 34.016932 -284.275277) (xy 33.961198 -284.27324) (xy 33.906355 -284.26311) (xy 33.853571 -284.245103)
			(xy 33.803971 -284.219602) (xy 33.758613 -284.187151) (xy 33.718464 -284.148442) (xy 33.684378 -284.104299)
			(xy 33.657082 -284.055664) (xy 33.637159 -284.003573) (xy 33.625033 -283.949136) (xy 33.620962 -283.893514)
			(xy 33.498028 -283.893514) (xy 33.497519 -283.9214) (xy 33.489399 -283.976576) (xy 33.473331 -284.029983)
			(xy 33.449659 -284.08048) (xy 33.418886 -284.126993) (xy 33.381669 -284.16853) (xy 33.338801 -284.204205)
			(xy 33.291195 -284.233259) (xy 33.239866 -284.255071) (xy 33.185909 -284.269177) (xy 33.130472 -284.275277)
			(xy 33.074738 -284.27324) (xy 33.019895 -284.26311) (xy 32.967111 -284.245103) (xy 32.917511 -284.219602)
			(xy 32.872153 -284.187151) (xy 32.832004 -284.148442) (xy 32.797918 -284.104299) (xy 32.770622 -284.055664)
			(xy 32.750699 -284.003573) (xy 32.738573 -283.949136) (xy 32.734502 -283.893514) (xy 32.101028 -283.893514)
			(xy 32.100542 -283.920765) (xy 32.092786 -283.974713) (xy 32.077431 -284.027008) (xy 32.054789 -284.076585)
			(xy 32.025323 -284.122435) (xy 31.989632 -284.163626) (xy 31.948441 -284.199317) (xy 31.902591 -284.228783)
			(xy 31.853014 -284.251425) (xy 31.800719 -284.26678) (xy 31.746771 -284.274536) (xy 31.692269 -284.274536)
			(xy 31.638321 -284.26678) (xy 31.586026 -284.251425) (xy 31.536449 -284.228783) (xy 31.490599 -284.199317)
			(xy 31.449408 -284.163626) (xy 31.413717 -284.122435) (xy 31.384251 -284.076585) (xy 31.361609 -284.027008)
			(xy 31.346254 -283.974713) (xy 31.338498 -283.920765) (xy 31.338012 -283.893514) (xy 1.420114 -283.893514)
			(xy 1.420114 -284.845831) (xy 1.89279 -284.845831) (xy 1.89279 -284.791329) (xy 1.900546 -284.737382)
			(xy 1.915901 -284.685087) (xy 1.938542 -284.635511) (xy 1.968008 -284.58966) (xy 2.003699 -284.548471)
			(xy 2.044889 -284.512779) (xy 2.090739 -284.483313) (xy 2.140316 -284.460672) (xy 2.19261 -284.445317)
			(xy 2.246557 -284.43756) (xy 2.273808 -284.437074) (xy 2.302547 -284.4376) (xy 2.359374 -284.446223)
			(xy 2.414264 -284.463273) (xy 2.465976 -284.488364) (xy 2.513339 -284.520928) (xy 2.534666 -284.540198)
			(xy 2.541524 -284.546802) (xy 2.559558 -284.553914) (xy 2.648458 -284.553914) (xy 2.666492 -284.546802)
			(xy 2.67335 -284.540198) (xy 2.694683 -284.520934) (xy 2.742042 -284.488364) (xy 2.793752 -284.46327)
			(xy 2.848642 -284.446218) (xy 2.905469 -284.437595) (xy 2.934208 -284.437074) (xy 2.964332 -284.437633)
			(xy 3.023829 -284.447116) (xy 3.081098 -284.465829) (xy 3.134714 -284.493308) (xy 3.183348 -284.528869)
			(xy 3.204972 -284.54985) (xy 3.212393 -284.556663) (xy 3.230976 -284.5644) (xy 3.24104 -284.564836)
			(xy 3.313176 -284.564836) (xy 3.323246 -284.564415) (xy 3.341845 -284.556693) (xy 3.349244 -284.54985)
			(xy 3.370879 -284.52888) (xy 3.419504 -284.493309) (xy 3.473118 -284.465826) (xy 3.530386 -284.447115)
			(xy 3.589884 -284.437643) (xy 3.620008 -284.437074) (xy 3.647379 -284.437517) (xy 3.70156 -284.445338)
			(xy 3.754064 -284.460831) (xy 3.803811 -284.483679) (xy 3.849776 -284.513409) (xy 3.870706 -284.531054)
			(xy 3.87096 -284.531308) (xy 3.878053 -284.536885) (xy 3.894965 -284.543137) (xy 3.90398 -284.5435)
			(xy 3.971036 -284.5435) (xy 3.980055 -284.54316) (xy 3.996971 -284.536901) (xy 4.004056 -284.531308)
			(xy 4.004056 -284.531054) (xy 4.00431 -284.531054) (xy 4.025234 -284.513405) (xy 4.071208 -284.483693)
			(xy 4.120958 -284.460858) (xy 4.173461 -284.445369) (xy 4.227638 -284.437545) (xy 4.255008 -284.437074)
			(xy 4.282261 -284.437533) (xy 4.336213 -284.44529) (xy 4.388511 -284.460646) (xy 4.438091 -284.483288)
			(xy 4.483945 -284.512757) (xy 4.525138 -284.54845) (xy 4.560832 -284.589643) (xy 4.590301 -284.635497)
			(xy 4.612943 -284.685077) (xy 4.6283 -284.737376) (xy 4.636057 -284.791327) (xy 4.636057 -284.845831)
			(xy 5.88618 -284.845831) (xy 5.88618 -284.791329) (xy 5.893936 -284.737382) (xy 5.909291 -284.685088)
			(xy 5.931932 -284.635511) (xy 5.961397 -284.589661) (xy 5.997088 -284.548471) (xy 6.038278 -284.51278)
			(xy 6.084128 -284.483314) (xy 6.133704 -284.460672) (xy 6.185998 -284.445317) (xy 6.239945 -284.43756)
			(xy 6.267196 -284.437074) (xy 6.295934 -284.437607) (xy 6.352761 -284.446228) (xy 6.407651 -284.463277)
			(xy 6.459363 -284.488366) (xy 6.506727 -284.520929) (xy 6.528054 -284.540198) (xy 6.534912 -284.546802)
			(xy 6.552946 -284.553914) (xy 6.641846 -284.553914) (xy 6.65988 -284.546802) (xy 6.666738 -284.540198)
			(xy 6.688065 -284.520928) (xy 6.735428 -284.488363) (xy 6.787139 -284.463272) (xy 6.84203 -284.446222)
			(xy 6.898857 -284.4376) (xy 6.956335 -284.4376) (xy 7.013162 -284.446222) (xy 7.068053 -284.463272)
			(xy 7.119764 -284.488363) (xy 7.167127 -284.520928) (xy 7.188454 -284.540198) (xy 7.195312 -284.546802)
			(xy 7.213346 -284.553914) (xy 7.302246 -284.553914) (xy 7.32028 -284.546802) (xy 7.327138 -284.540198)
			(xy 7.348476 -284.52094) (xy 7.395834 -284.488369) (xy 7.447543 -284.463274) (xy 7.502431 -284.44622)
			(xy 7.559258 -284.437596) (xy 7.587996 -284.437074) (xy 7.61812 -284.43764) (xy 7.677617 -284.447121)
			(xy 7.734885 -284.465833) (xy 7.788502 -284.49331) (xy 7.837136 -284.52887) (xy 7.85876 -284.54985)
			(xy 7.866186 -284.556658) (xy 7.884765 -284.564398) (xy 7.894828 -284.564836) (xy 7.966964 -284.564836)
			(xy 7.977033 -284.564409) (xy 7.995632 -284.556691) (xy 8.003032 -284.54985) (xy 8.024672 -284.528886)
			(xy 8.073296 -284.493314) (xy 8.126908 -284.46583) (xy 8.184175 -284.447118) (xy 8.243673 -284.437644)
			(xy 8.273796 -284.437074) (xy 8.301049 -284.437533) (xy 8.355001 -284.44529) (xy 8.407299 -284.460645)
			(xy 8.45688 -284.483288) (xy 8.482592 -284.499812) (xy 73.593972 -284.499812) (xy 73.597932 -284.450758)
			(xy 73.609709 -284.402974) (xy 73.629 -284.357698) (xy 73.655303 -284.316102) (xy 73.687938 -284.279265)
			(xy 73.726059 -284.24814) (xy 73.76868 -284.223533) (xy 73.814696 -284.206081) (xy 73.862915 -284.196237)
			(xy 73.91209 -284.194256) (xy 73.960945 -284.200188) (xy 74.008216 -284.21388) (xy 74.052678 -284.234978)
			(xy 74.093181 -284.262934) (xy 74.128674 -284.297026) (xy 74.158239 -284.33637) (xy 74.18111 -284.379947)
			(xy 74.196694 -284.426628) (xy 74.204589 -284.475205) (xy 74.205084 -284.499812) (xy 74.543932 -284.499812)
			(xy 74.547892 -284.450758) (xy 74.559669 -284.402974) (xy 74.57896 -284.357698) (xy 74.605263 -284.316102)
			(xy 74.637898 -284.279265) (xy 74.676019 -284.24814) (xy 74.71864 -284.223533) (xy 74.764656 -284.206081)
			(xy 74.812875 -284.196237) (xy 74.86205 -284.194256) (xy 74.910905 -284.200188) (xy 74.958176 -284.21388)
			(xy 75.002638 -284.234978) (xy 75.043141 -284.262934) (xy 75.078634 -284.297026) (xy 75.108199 -284.33637)
			(xy 75.13107 -284.379947) (xy 75.146654 -284.426628) (xy 75.154549 -284.475205) (xy 75.155044 -284.499812)
			(xy 75.494146 -284.499812) (xy 75.498106 -284.450758) (xy 75.509883 -284.402974) (xy 75.529174 -284.357698)
			(xy 75.555477 -284.316102) (xy 75.588112 -284.279265) (xy 75.626233 -284.24814) (xy 75.668854 -284.223533)
			(xy 75.71487 -284.206081) (xy 75.763089 -284.196237) (xy 75.812264 -284.194256) (xy 75.861119 -284.200188)
			(xy 75.90839 -284.21388) (xy 75.952852 -284.234978) (xy 75.993355 -284.262934) (xy 76.028848 -284.297026)
			(xy 76.058413 -284.33637) (xy 76.081284 -284.379947) (xy 76.096868 -284.426628) (xy 76.104763 -284.475205)
			(xy 76.105258 -284.499812) (xy 76.104763 -284.524419) (xy 76.104584 -284.52552) (xy 76.423262 -284.52552)
			(xy 76.423262 -284.474104) (xy 76.431305 -284.423322) (xy 76.447193 -284.374423) (xy 76.470536 -284.328611)
			(xy 76.500757 -284.287015) (xy 76.537113 -284.250659) (xy 76.578709 -284.220438) (xy 76.624521 -284.197095)
			(xy 76.67342 -284.181207) (xy 76.724202 -284.173164) (xy 76.775618 -284.173164) (xy 76.8264 -284.181207)
			(xy 76.875299 -284.197095) (xy 76.921111 -284.220438) (xy 76.962707 -284.250659) (xy 76.999063 -284.287015)
			(xy 77.029284 -284.328611) (xy 77.052627 -284.374423) (xy 77.068515 -284.423322) (xy 77.076558 -284.474104)
			(xy 77.077062 -284.499812) (xy 77.076558 -284.52552) (xy 77.373222 -284.52552) (xy 77.373222 -284.474104)
			(xy 77.381265 -284.423322) (xy 77.397153 -284.374423) (xy 77.420496 -284.328611) (xy 77.450717 -284.287015)
			(xy 77.487073 -284.250659) (xy 77.528669 -284.220438) (xy 77.574481 -284.197095) (xy 77.62338 -284.181207)
			(xy 77.674162 -284.173164) (xy 77.725578 -284.173164) (xy 77.77636 -284.181207) (xy 77.825259 -284.197095)
			(xy 77.871071 -284.220438) (xy 77.912667 -284.250659) (xy 77.949023 -284.287015) (xy 77.979244 -284.328611)
			(xy 78.002587 -284.374423) (xy 78.018475 -284.423322) (xy 78.026518 -284.474104) (xy 78.027022 -284.499812)
			(xy 78.344026 -284.499812) (xy 78.347986 -284.450758) (xy 78.359763 -284.402974) (xy 78.379054 -284.357698)
			(xy 78.405357 -284.316102) (xy 78.437992 -284.279265) (xy 78.476113 -284.24814) (xy 78.518734 -284.223533)
			(xy 78.56475 -284.206081) (xy 78.612969 -284.196237) (xy 78.662144 -284.194256) (xy 78.710999 -284.200188)
			(xy 78.75827 -284.21388) (xy 78.802732 -284.234978) (xy 78.843235 -284.262934) (xy 78.878728 -284.297026)
			(xy 78.908293 -284.33637) (xy 78.931164 -284.379947) (xy 78.946748 -284.426628) (xy 78.954643 -284.475205)
			(xy 78.955138 -284.499812) (xy 78.954643 -284.524419) (xy 78.954464 -284.52552) (xy 79.273142 -284.52552)
			(xy 79.273142 -284.474104) (xy 79.281185 -284.423322) (xy 79.297073 -284.374423) (xy 79.320416 -284.328611)
			(xy 79.350637 -284.287015) (xy 79.386993 -284.250659) (xy 79.428589 -284.220438) (xy 79.474401 -284.197095)
			(xy 79.5233 -284.181207) (xy 79.574082 -284.173164) (xy 79.625498 -284.173164) (xy 79.67628 -284.181207)
			(xy 79.725179 -284.197095) (xy 79.770991 -284.220438) (xy 79.812587 -284.250659) (xy 79.848943 -284.287015)
			(xy 79.879164 -284.328611) (xy 79.902507 -284.374423) (xy 79.918395 -284.423322) (xy 79.926438 -284.474104)
			(xy 79.926942 -284.499812) (xy 79.926438 -284.52552) (xy 80.223102 -284.52552) (xy 80.223102 -284.474104)
			(xy 80.231145 -284.423322) (xy 80.247033 -284.374423) (xy 80.270376 -284.328611) (xy 80.300597 -284.287015)
			(xy 80.336953 -284.250659) (xy 80.378549 -284.220438) (xy 80.424361 -284.197095) (xy 80.47326 -284.181207)
			(xy 80.524042 -284.173164) (xy 80.575458 -284.173164) (xy 80.62624 -284.181207) (xy 80.675139 -284.197095)
			(xy 80.720951 -284.220438) (xy 80.762547 -284.250659) (xy 80.798903 -284.287015) (xy 80.829124 -284.328611)
			(xy 80.852467 -284.374423) (xy 80.868355 -284.423322) (xy 80.876398 -284.474104) (xy 80.876902 -284.499812)
			(xy 81.19416 -284.499812) (xy 81.19812 -284.450758) (xy 81.209897 -284.402974) (xy 81.229188 -284.357698)
			(xy 81.255491 -284.316102) (xy 81.288126 -284.279265) (xy 81.326247 -284.24814) (xy 81.368868 -284.223533)
			(xy 81.414884 -284.206081) (xy 81.463103 -284.196237) (xy 81.512278 -284.194256) (xy 81.561133 -284.200188)
			(xy 81.608404 -284.21388) (xy 81.652866 -284.234978) (xy 81.693369 -284.262934) (xy 81.728862 -284.297026)
			(xy 81.758427 -284.33637) (xy 81.781298 -284.379947) (xy 81.796882 -284.426628) (xy 81.804777 -284.475205)
			(xy 81.805272 -284.499812) (xy 82.14412 -284.499812) (xy 82.14808 -284.450758) (xy 82.159857 -284.402974)
			(xy 82.179148 -284.357698) (xy 82.205451 -284.316102) (xy 82.238086 -284.279265) (xy 82.276207 -284.24814)
			(xy 82.318828 -284.223533) (xy 82.364844 -284.206081) (xy 82.413063 -284.196237) (xy 82.462238 -284.194256)
			(xy 82.511093 -284.200188) (xy 82.558364 -284.21388) (xy 82.602826 -284.234978) (xy 82.643329 -284.262934)
			(xy 82.678822 -284.297026) (xy 82.708387 -284.33637) (xy 82.731258 -284.379947) (xy 82.746842 -284.426628)
			(xy 82.754737 -284.475205) (xy 82.755232 -284.499812) (xy 82.754737 -284.524419) (xy 82.746842 -284.572996)
			(xy 82.731258 -284.619677) (xy 82.708387 -284.663254) (xy 82.678822 -284.702598) (xy 82.643329 -284.73669)
			(xy 82.602826 -284.764646) (xy 82.558364 -284.785744) (xy 82.511093 -284.799436) (xy 82.462238 -284.805368)
			(xy 82.413063 -284.803387) (xy 82.364844 -284.793543) (xy 82.318828 -284.776091) (xy 82.276207 -284.751484)
			(xy 82.238086 -284.720359) (xy 82.205451 -284.683522) (xy 82.179148 -284.641926) (xy 82.159857 -284.59665)
			(xy 82.14808 -284.548866) (xy 82.14412 -284.499812) (xy 81.805272 -284.499812) (xy 81.804777 -284.524419)
			(xy 81.796882 -284.572996) (xy 81.781298 -284.619677) (xy 81.758427 -284.663254) (xy 81.728862 -284.702598)
			(xy 81.693369 -284.73669) (xy 81.652866 -284.764646) (xy 81.608404 -284.785744) (xy 81.561133 -284.799436)
			(xy 81.512278 -284.805368) (xy 81.463103 -284.803387) (xy 81.414884 -284.793543) (xy 81.368868 -284.776091)
			(xy 81.326247 -284.751484) (xy 81.288126 -284.720359) (xy 81.255491 -284.683522) (xy 81.229188 -284.641926)
			(xy 81.209897 -284.59665) (xy 81.19812 -284.548866) (xy 81.19416 -284.499812) (xy 80.876902 -284.499812)
			(xy 80.876398 -284.52552) (xy 80.868355 -284.576302) (xy 80.852467 -284.625201) (xy 80.829124 -284.671013)
			(xy 80.798903 -284.712609) (xy 80.762547 -284.748965) (xy 80.720951 -284.779186) (xy 80.675139 -284.802529)
			(xy 80.62624 -284.818417) (xy 80.575458 -284.82646) (xy 80.524042 -284.82646) (xy 80.47326 -284.818417)
			(xy 80.424361 -284.802529) (xy 80.378549 -284.779186) (xy 80.336953 -284.748965) (xy 80.300597 -284.712609)
			(xy 80.270376 -284.671013) (xy 80.247033 -284.625201) (xy 80.231145 -284.576302) (xy 80.223102 -284.52552)
			(xy 79.926438 -284.52552) (xy 79.918395 -284.576302) (xy 79.902507 -284.625201) (xy 79.879164 -284.671013)
			(xy 79.848943 -284.712609) (xy 79.812587 -284.748965) (xy 79.770991 -284.779186) (xy 79.725179 -284.802529)
			(xy 79.67628 -284.818417) (xy 79.625498 -284.82646) (xy 79.574082 -284.82646) (xy 79.5233 -284.818417)
			(xy 79.474401 -284.802529) (xy 79.428589 -284.779186) (xy 79.386993 -284.748965) (xy 79.350637 -284.712609)
			(xy 79.320416 -284.671013) (xy 79.297073 -284.625201) (xy 79.281185 -284.576302) (xy 79.273142 -284.52552)
			(xy 78.954464 -284.52552) (xy 78.946748 -284.572996) (xy 78.931164 -284.619677) (xy 78.908293 -284.663254)
			(xy 78.878728 -284.702598) (xy 78.843235 -284.73669) (xy 78.802732 -284.764646) (xy 78.75827 -284.785744)
			(xy 78.710999 -284.799436) (xy 78.662144 -284.805368) (xy 78.612969 -284.803387) (xy 78.56475 -284.793543)
			(xy 78.518734 -284.776091) (xy 78.476113 -284.751484) (xy 78.437992 -284.720359) (xy 78.405357 -284.683522)
			(xy 78.379054 -284.641926) (xy 78.359763 -284.59665) (xy 78.347986 -284.548866) (xy 78.344026 -284.499812)
			(xy 78.027022 -284.499812) (xy 78.026518 -284.52552) (xy 78.018475 -284.576302) (xy 78.002587 -284.625201)
			(xy 77.979244 -284.671013) (xy 77.949023 -284.712609) (xy 77.912667 -284.748965) (xy 77.871071 -284.779186)
			(xy 77.825259 -284.802529) (xy 77.77636 -284.818417) (xy 77.725578 -284.82646) (xy 77.674162 -284.82646)
			(xy 77.62338 -284.818417) (xy 77.574481 -284.802529) (xy 77.528669 -284.779186) (xy 77.487073 -284.748965)
			(xy 77.450717 -284.712609) (xy 77.420496 -284.671013) (xy 77.397153 -284.625201) (xy 77.381265 -284.576302)
			(xy 77.373222 -284.52552) (xy 77.076558 -284.52552) (xy 77.068515 -284.576302) (xy 77.052627 -284.625201)
			(xy 77.029284 -284.671013) (xy 76.999063 -284.712609) (xy 76.962707 -284.748965) (xy 76.921111 -284.779186)
			(xy 76.875299 -284.802529) (xy 76.8264 -284.818417) (xy 76.775618 -284.82646) (xy 76.724202 -284.82646)
			(xy 76.67342 -284.818417) (xy 76.624521 -284.802529) (xy 76.578709 -284.779186) (xy 76.537113 -284.748965)
			(xy 76.500757 -284.712609) (xy 76.470536 -284.671013) (xy 76.447193 -284.625201) (xy 76.431305 -284.576302)
			(xy 76.423262 -284.52552) (xy 76.104584 -284.52552) (xy 76.096868 -284.572996) (xy 76.081284 -284.619677)
			(xy 76.058413 -284.663254) (xy 76.028848 -284.702598) (xy 75.993355 -284.73669) (xy 75.952852 -284.764646)
			(xy 75.90839 -284.785744) (xy 75.861119 -284.799436) (xy 75.812264 -284.805368) (xy 75.763089 -284.803387)
			(xy 75.71487 -284.793543) (xy 75.668854 -284.776091) (xy 75.626233 -284.751484) (xy 75.588112 -284.720359)
			(xy 75.555477 -284.683522) (xy 75.529174 -284.641926) (xy 75.509883 -284.59665) (xy 75.498106 -284.548866)
			(xy 75.494146 -284.499812) (xy 75.155044 -284.499812) (xy 75.154549 -284.524419) (xy 75.146654 -284.572996)
			(xy 75.13107 -284.619677) (xy 75.108199 -284.663254) (xy 75.078634 -284.702598) (xy 75.043141 -284.73669)
			(xy 75.002638 -284.764646) (xy 74.958176 -284.785744) (xy 74.910905 -284.799436) (xy 74.86205 -284.805368)
			(xy 74.812875 -284.803387) (xy 74.764656 -284.793543) (xy 74.71864 -284.776091) (xy 74.676019 -284.751484)
			(xy 74.637898 -284.720359) (xy 74.605263 -284.683522) (xy 74.57896 -284.641926) (xy 74.559669 -284.59665)
			(xy 74.547892 -284.548866) (xy 74.543932 -284.499812) (xy 74.205084 -284.499812) (xy 74.204589 -284.524419)
			(xy 74.196694 -284.572996) (xy 74.18111 -284.619677) (xy 74.158239 -284.663254) (xy 74.128674 -284.702598)
			(xy 74.093181 -284.73669) (xy 74.052678 -284.764646) (xy 74.008216 -284.785744) (xy 73.960945 -284.799436)
			(xy 73.91209 -284.805368) (xy 73.862915 -284.803387) (xy 73.814696 -284.793543) (xy 73.76868 -284.776091)
			(xy 73.726059 -284.751484) (xy 73.687938 -284.720359) (xy 73.655303 -284.683522) (xy 73.629 -284.641926)
			(xy 73.609709 -284.59665) (xy 73.597932 -284.548866) (xy 73.593972 -284.499812) (xy 8.482592 -284.499812)
			(xy 8.502734 -284.512756) (xy 8.543928 -284.54845) (xy 8.579622 -284.589643) (xy 8.60909 -284.635496)
			(xy 8.631733 -284.685077) (xy 8.64709 -284.737375) (xy 8.654847 -284.791327) (xy 8.654847 -284.845833)
			(xy 8.64709 -284.899785) (xy 8.631733 -284.952083) (xy 8.60909 -285.001664) (xy 8.591101 -285.029656)
			(xy 25.811478 -285.029656) (xy 25.815549 -284.974034) (xy 25.827675 -284.919597) (xy 25.847598 -284.867506)
			(xy 25.874894 -284.818871) (xy 25.90898 -284.774728) (xy 25.949129 -284.736019) (xy 25.994487 -284.703568)
			(xy 26.044087 -284.678067) (xy 26.096871 -284.66006) (xy 26.151714 -284.64993) (xy 26.207448 -284.647893)
			(xy 26.262885 -284.653993) (xy 26.316842 -284.668099) (xy 26.368171 -284.689911) (xy 26.415777 -284.718965)
			(xy 26.458645 -284.75464) (xy 26.495862 -284.796177) (xy 26.526635 -284.84269) (xy 26.550307 -284.893187)
			(xy 26.566375 -284.946594) (xy 26.574495 -285.00177) (xy 26.575004 -285.029656) (xy 27.296616 -285.029656)
			(xy 27.300687 -284.974034) (xy 27.312813 -284.919597) (xy 27.332736 -284.867506) (xy 27.360032 -284.818871)
			(xy 27.394118 -284.774728) (xy 27.434267 -284.736019) (xy 27.479625 -284.703568) (xy 27.529225 -284.678067)
			(xy 27.582009 -284.66006) (xy 27.636852 -284.64993) (xy 27.692586 -284.647893) (xy 27.748023 -284.653993)
			(xy 27.80198 -284.668099) (xy 27.853309 -284.689911) (xy 27.900915 -284.718965) (xy 27.943783 -284.75464)
			(xy 27.981 -284.796177) (xy 28.011773 -284.84269) (xy 28.035445 -284.893187) (xy 28.051513 -284.946594)
			(xy 28.055663 -284.974792) (xy 36.069028 -284.974792) (xy 36.072988 -284.925738) (xy 36.084765 -284.877954)
			(xy 36.104056 -284.832678) (xy 36.130359 -284.791082) (xy 36.162994 -284.754245) (xy 36.201115 -284.72312)
			(xy 36.243736 -284.698513) (xy 36.289752 -284.681061) (xy 36.337971 -284.671217) (xy 36.387146 -284.669236)
			(xy 36.436001 -284.675168) (xy 36.483272 -284.68886) (xy 36.527734 -284.709958) (xy 36.568237 -284.737914)
			(xy 36.60373 -284.772006) (xy 36.633295 -284.81135) (xy 36.656166 -284.854927) (xy 36.67175 -284.901608)
			(xy 36.679645 -284.950185) (xy 36.68014 -284.974792) (xy 37.018988 -284.974792) (xy 37.022948 -284.925738)
			(xy 37.034725 -284.877954) (xy 37.054016 -284.832678) (xy 37.080319 -284.791082) (xy 37.112954 -284.754245)
			(xy 37.151075 -284.72312) (xy 37.193696 -284.698513) (xy 37.239712 -284.681061) (xy 37.287931 -284.671217)
			(xy 37.337106 -284.669236) (xy 37.385961 -284.675168) (xy 37.433232 -284.68886) (xy 37.477694 -284.709958)
			(xy 37.518197 -284.737914) (xy 37.55369 -284.772006) (xy 37.583255 -284.81135) (xy 37.606126 -284.854927)
			(xy 37.62171 -284.901608) (xy 37.629605 -284.950185) (xy 37.6301 -284.974792) (xy 37.969202 -284.974792)
			(xy 37.973162 -284.925738) (xy 37.984939 -284.877954) (xy 38.00423 -284.832678) (xy 38.030533 -284.791082)
			(xy 38.063168 -284.754245) (xy 38.101289 -284.72312) (xy 38.14391 -284.698513) (xy 38.189926 -284.681061)
			(xy 38.238145 -284.671217) (xy 38.28732 -284.669236) (xy 38.336175 -284.675168) (xy 38.383446 -284.68886)
			(xy 38.427908 -284.709958) (xy 38.468411 -284.737914) (xy 38.503904 -284.772006) (xy 38.533469 -284.81135)
			(xy 38.55634 -284.854927) (xy 38.571924 -284.901608) (xy 38.579819 -284.950185) (xy 38.580314 -284.974792)
			(xy 38.919162 -284.974792) (xy 38.923122 -284.925738) (xy 38.934899 -284.877954) (xy 38.95419 -284.832678)
			(xy 38.980493 -284.791082) (xy 39.013128 -284.754245) (xy 39.051249 -284.72312) (xy 39.09387 -284.698513)
			(xy 39.139886 -284.681061) (xy 39.188105 -284.671217) (xy 39.23728 -284.669236) (xy 39.286135 -284.675168)
			(xy 39.333406 -284.68886) (xy 39.377868 -284.709958) (xy 39.418371 -284.737914) (xy 39.453864 -284.772006)
			(xy 39.483429 -284.81135) (xy 39.5063 -284.854927) (xy 39.521884 -284.901608) (xy 39.529779 -284.950185)
			(xy 39.530274 -284.974792) (xy 39.869122 -284.974792) (xy 39.873082 -284.925738) (xy 39.884859 -284.877954)
			(xy 39.90415 -284.832678) (xy 39.930453 -284.791082) (xy 39.963088 -284.754245) (xy 40.001209 -284.72312)
			(xy 40.04383 -284.698513) (xy 40.089846 -284.681061) (xy 40.138065 -284.671217) (xy 40.18724 -284.669236)
			(xy 40.236095 -284.675168) (xy 40.283366 -284.68886) (xy 40.327828 -284.709958) (xy 40.368331 -284.737914)
			(xy 40.403824 -284.772006) (xy 40.433389 -284.81135) (xy 40.45626 -284.854927) (xy 40.471844 -284.901608)
			(xy 40.479739 -284.950185) (xy 40.480234 -284.974792) (xy 40.819082 -284.974792) (xy 40.823042 -284.925738)
			(xy 40.834819 -284.877954) (xy 40.85411 -284.832678) (xy 40.880413 -284.791082) (xy 40.913048 -284.754245)
			(xy 40.951169 -284.72312) (xy 40.99379 -284.698513) (xy 41.039806 -284.681061) (xy 41.088025 -284.671217)
			(xy 41.1372 -284.669236) (xy 41.186055 -284.675168) (xy 41.233326 -284.68886) (xy 41.277788 -284.709958)
			(xy 41.318291 -284.737914) (xy 41.353784 -284.772006) (xy 41.383349 -284.81135) (xy 41.40622 -284.854927)
			(xy 41.421804 -284.901608) (xy 41.429699 -284.950185) (xy 41.430194 -284.974792) (xy 42.719002 -284.974792)
			(xy 42.722962 -284.925738) (xy 42.734739 -284.877954) (xy 42.75403 -284.832678) (xy 42.780333 -284.791082)
			(xy 42.812968 -284.754245) (xy 42.851089 -284.72312) (xy 42.89371 -284.698513) (xy 42.939726 -284.681061)
			(xy 42.987945 -284.671217) (xy 43.03712 -284.669236) (xy 43.085975 -284.675168) (xy 43.133246 -284.68886)
			(xy 43.177708 -284.709958) (xy 43.218211 -284.737914) (xy 43.253704 -284.772006) (xy 43.283269 -284.81135)
			(xy 43.30614 -284.854927) (xy 43.321724 -284.901608) (xy 43.329619 -284.950185) (xy 43.330114 -284.974792)
			(xy 44.619176 -284.974792) (xy 44.623136 -284.925738) (xy 44.634913 -284.877954) (xy 44.654204 -284.832678)
			(xy 44.680507 -284.791082) (xy 44.713142 -284.754245) (xy 44.751263 -284.72312) (xy 44.793884 -284.698513)
			(xy 44.8399 -284.681061) (xy 44.888119 -284.671217) (xy 44.937294 -284.669236) (xy 44.986149 -284.675168)
			(xy 45.03342 -284.68886) (xy 45.077882 -284.709958) (xy 45.118385 -284.737914) (xy 45.153878 -284.772006)
			(xy 45.183443 -284.81135) (xy 45.206314 -284.854927) (xy 45.221898 -284.901608) (xy 45.229793 -284.950185)
			(xy 45.230288 -284.974792) (xy 45.569136 -284.974792) (xy 45.573096 -284.925738) (xy 45.584873 -284.877954)
			(xy 45.604164 -284.832678) (xy 45.630467 -284.791082) (xy 45.663102 -284.754245) (xy 45.701223 -284.72312)
			(xy 45.743844 -284.698513) (xy 45.78986 -284.681061) (xy 45.838079 -284.671217) (xy 45.887254 -284.669236)
			(xy 45.936109 -284.675168) (xy 45.98338 -284.68886) (xy 46.027842 -284.709958) (xy 46.068345 -284.737914)
			(xy 46.103838 -284.772006) (xy 46.133403 -284.81135) (xy 46.156274 -284.854927) (xy 46.171858 -284.901608)
			(xy 46.179753 -284.950185) (xy 46.180248 -284.974792) (xy 46.519096 -284.974792) (xy 46.523056 -284.925738)
			(xy 46.534833 -284.877954) (xy 46.554124 -284.832678) (xy 46.580427 -284.791082) (xy 46.613062 -284.754245)
			(xy 46.651183 -284.72312) (xy 46.693804 -284.698513) (xy 46.73982 -284.681061) (xy 46.788039 -284.671217)
			(xy 46.837214 -284.669236) (xy 46.886069 -284.675168) (xy 46.93334 -284.68886) (xy 46.977802 -284.709958)
			(xy 47.018305 -284.737914) (xy 47.053798 -284.772006) (xy 47.083363 -284.81135) (xy 47.106234 -284.854927)
			(xy 47.121818 -284.901608) (xy 47.129713 -284.950185) (xy 47.130208 -284.974792) (xy 47.469056 -284.974792)
			(xy 47.473016 -284.925738) (xy 47.484793 -284.877954) (xy 47.504084 -284.832678) (xy 47.530387 -284.791082)
			(xy 47.563022 -284.754245) (xy 47.601143 -284.72312) (xy 47.643764 -284.698513) (xy 47.68978 -284.681061)
			(xy 47.737999 -284.671217) (xy 47.787174 -284.669236) (xy 47.836029 -284.675168) (xy 47.8833 -284.68886)
			(xy 47.927762 -284.709958) (xy 47.968265 -284.737914) (xy 48.003758 -284.772006) (xy 48.033323 -284.81135)
			(xy 48.056194 -284.854927) (xy 48.071778 -284.901608) (xy 48.079673 -284.950185) (xy 48.080168 -284.974792)
			(xy 48.419016 -284.974792) (xy 48.422976 -284.925738) (xy 48.434753 -284.877954) (xy 48.454044 -284.832678)
			(xy 48.480347 -284.791082) (xy 48.512982 -284.754245) (xy 48.551103 -284.72312) (xy 48.593724 -284.698513)
			(xy 48.63974 -284.681061) (xy 48.687959 -284.671217) (xy 48.737134 -284.669236) (xy 48.785989 -284.675168)
			(xy 48.83326 -284.68886) (xy 48.877722 -284.709958) (xy 48.918225 -284.737914) (xy 48.953718 -284.772006)
			(xy 48.983283 -284.81135) (xy 49.006154 -284.854927) (xy 49.021738 -284.901608) (xy 49.029633 -284.950185)
			(xy 49.030128 -284.974792) (xy 49.368976 -284.974792) (xy 49.372936 -284.925738) (xy 49.384713 -284.877954)
			(xy 49.404004 -284.832678) (xy 49.430307 -284.791082) (xy 49.462942 -284.754245) (xy 49.501063 -284.72312)
			(xy 49.543684 -284.698513) (xy 49.5897 -284.681061) (xy 49.637919 -284.671217) (xy 49.687094 -284.669236)
			(xy 49.735949 -284.675168) (xy 49.78322 -284.68886) (xy 49.827682 -284.709958) (xy 49.868185 -284.737914)
			(xy 49.903678 -284.772006) (xy 49.933243 -284.81135) (xy 49.956114 -284.854927) (xy 49.971698 -284.901608)
			(xy 49.979593 -284.950185) (xy 49.980088 -284.974792) (xy 50.31919 -284.974792) (xy 50.32315 -284.925738)
			(xy 50.334927 -284.877954) (xy 50.354218 -284.832678) (xy 50.380521 -284.791082) (xy 50.413156 -284.754245)
			(xy 50.451277 -284.72312) (xy 50.493898 -284.698513) (xy 50.539914 -284.681061) (xy 50.588133 -284.671217)
			(xy 50.637308 -284.669236) (xy 50.686163 -284.675168) (xy 50.733434 -284.68886) (xy 50.777896 -284.709958)
			(xy 50.818399 -284.737914) (xy 50.853892 -284.772006) (xy 50.883457 -284.81135) (xy 50.906328 -284.854927)
			(xy 50.921912 -284.901608) (xy 50.929807 -284.950185) (xy 50.930302 -284.974792) (xy 51.26915 -284.974792)
			(xy 51.27311 -284.925738) (xy 51.284887 -284.877954) (xy 51.304178 -284.832678) (xy 51.330481 -284.791082)
			(xy 51.363116 -284.754245) (xy 51.401237 -284.72312) (xy 51.443858 -284.698513) (xy 51.489874 -284.681061)
			(xy 51.538093 -284.671217) (xy 51.587268 -284.669236) (xy 51.636123 -284.675168) (xy 51.683394 -284.68886)
			(xy 51.727856 -284.709958) (xy 51.768359 -284.737914) (xy 51.803852 -284.772006) (xy 51.833417 -284.81135)
			(xy 51.856288 -284.854927) (xy 51.871872 -284.901608) (xy 51.879767 -284.950185) (xy 51.880262 -284.974792)
			(xy 52.21911 -284.974792) (xy 52.22307 -284.925738) (xy 52.234847 -284.877954) (xy 52.254138 -284.832678)
			(xy 52.280441 -284.791082) (xy 52.313076 -284.754245) (xy 52.351197 -284.72312) (xy 52.393818 -284.698513)
			(xy 52.439834 -284.681061) (xy 52.488053 -284.671217) (xy 52.537228 -284.669236) (xy 52.586083 -284.675168)
			(xy 52.633354 -284.68886) (xy 52.677816 -284.709958) (xy 52.718319 -284.737914) (xy 52.753812 -284.772006)
			(xy 52.783377 -284.81135) (xy 52.806248 -284.854927) (xy 52.821832 -284.901608) (xy 52.829727 -284.950185)
			(xy 52.830222 -284.974792) (xy 53.16907 -284.974792) (xy 53.17303 -284.925738) (xy 53.184807 -284.877954)
			(xy 53.204098 -284.832678) (xy 53.230401 -284.791082) (xy 53.263036 -284.754245) (xy 53.301157 -284.72312)
			(xy 53.343778 -284.698513) (xy 53.389794 -284.681061) (xy 53.438013 -284.671217) (xy 53.487188 -284.669236)
			(xy 53.536043 -284.675168) (xy 53.583314 -284.68886) (xy 53.627776 -284.709958) (xy 53.668279 -284.737914)
			(xy 53.703772 -284.772006) (xy 53.733337 -284.81135) (xy 53.756208 -284.854927) (xy 53.771792 -284.901608)
			(xy 53.779687 -284.950185) (xy 53.780182 -284.974792) (xy 54.11903 -284.974792) (xy 54.12299 -284.925738)
			(xy 54.134767 -284.877954) (xy 54.154058 -284.832678) (xy 54.180361 -284.791082) (xy 54.212996 -284.754245)
			(xy 54.251117 -284.72312) (xy 54.293738 -284.698513) (xy 54.339754 -284.681061) (xy 54.387973 -284.671217)
			(xy 54.437148 -284.669236) (xy 54.486003 -284.675168) (xy 54.533274 -284.68886) (xy 54.577736 -284.709958)
			(xy 54.618239 -284.737914) (xy 54.653732 -284.772006) (xy 54.683297 -284.81135) (xy 54.706168 -284.854927)
			(xy 54.721752 -284.901608) (xy 54.729647 -284.950185) (xy 54.730142 -284.974792) (xy 55.06899 -284.974792)
			(xy 55.07295 -284.925738) (xy 55.084727 -284.877954) (xy 55.104018 -284.832678) (xy 55.130321 -284.791082)
			(xy 55.162956 -284.754245) (xy 55.201077 -284.72312) (xy 55.243698 -284.698513) (xy 55.289714 -284.681061)
			(xy 55.337933 -284.671217) (xy 55.387108 -284.669236) (xy 55.435963 -284.675168) (xy 55.483234 -284.68886)
			(xy 55.527696 -284.709958) (xy 55.568199 -284.737914) (xy 55.603692 -284.772006) (xy 55.633257 -284.81135)
			(xy 55.656128 -284.854927) (xy 55.671712 -284.901608) (xy 55.679607 -284.950185) (xy 55.680102 -284.974792)
			(xy 56.01895 -284.974792) (xy 56.02291 -284.925738) (xy 56.034687 -284.877954) (xy 56.053978 -284.832678)
			(xy 56.080281 -284.791082) (xy 56.112916 -284.754245) (xy 56.151037 -284.72312) (xy 56.193658 -284.698513)
			(xy 56.239674 -284.681061) (xy 56.287893 -284.671217) (xy 56.337068 -284.669236) (xy 56.385923 -284.675168)
			(xy 56.433194 -284.68886) (xy 56.477656 -284.709958) (xy 56.518159 -284.737914) (xy 56.553652 -284.772006)
			(xy 56.583217 -284.81135) (xy 56.606088 -284.854927) (xy 56.621672 -284.901608) (xy 56.629567 -284.950185)
			(xy 56.630062 -284.974792) (xy 56.969164 -284.974792) (xy 56.973124 -284.925738) (xy 56.984901 -284.877954)
			(xy 57.004192 -284.832678) (xy 57.030495 -284.791082) (xy 57.06313 -284.754245) (xy 57.101251 -284.72312)
			(xy 57.143872 -284.698513) (xy 57.189888 -284.681061) (xy 57.238107 -284.671217) (xy 57.287282 -284.669236)
			(xy 57.336137 -284.675168) (xy 57.383408 -284.68886) (xy 57.42787 -284.709958) (xy 57.468373 -284.737914)
			(xy 57.503866 -284.772006) (xy 57.533431 -284.81135) (xy 57.556302 -284.854927) (xy 57.571886 -284.901608)
			(xy 57.579781 -284.950185) (xy 57.580276 -284.974792) (xy 57.919124 -284.974792) (xy 57.923084 -284.925738)
			(xy 57.934861 -284.877954) (xy 57.954152 -284.832678) (xy 57.980455 -284.791082) (xy 58.01309 -284.754245)
			(xy 58.051211 -284.72312) (xy 58.093832 -284.698513) (xy 58.139848 -284.681061) (xy 58.188067 -284.671217)
			(xy 58.237242 -284.669236) (xy 58.286097 -284.675168) (xy 58.333368 -284.68886) (xy 58.37783 -284.709958)
			(xy 58.418333 -284.737914) (xy 58.453826 -284.772006) (xy 58.483391 -284.81135) (xy 58.506262 -284.854927)
			(xy 58.521846 -284.901608) (xy 58.529741 -284.950185) (xy 58.530236 -284.974792) (xy 59.819044 -284.974792)
			(xy 59.823004 -284.925738) (xy 59.834781 -284.877954) (xy 59.854072 -284.832678) (xy 59.880375 -284.791082)
			(xy 59.91301 -284.754245) (xy 59.951131 -284.72312) (xy 59.993752 -284.698513) (xy 60.039768 -284.681061)
			(xy 60.087987 -284.671217) (xy 60.137162 -284.669236) (xy 60.186017 -284.675168) (xy 60.233288 -284.68886)
			(xy 60.27775 -284.709958) (xy 60.318253 -284.737914) (xy 60.353746 -284.772006) (xy 60.383311 -284.81135)
			(xy 60.406182 -284.854927) (xy 60.421766 -284.901608) (xy 60.429661 -284.950185) (xy 60.430156 -284.974792)
			(xy 60.769004 -284.974792) (xy 60.772964 -284.925738) (xy 60.784741 -284.877954) (xy 60.804032 -284.832678)
			(xy 60.830335 -284.791082) (xy 60.86297 -284.754245) (xy 60.901091 -284.72312) (xy 60.943712 -284.698513)
			(xy 60.989728 -284.681061) (xy 61.037947 -284.671217) (xy 61.087122 -284.669236) (xy 61.135977 -284.675168)
			(xy 61.183248 -284.68886) (xy 61.22771 -284.709958) (xy 61.268213 -284.737914) (xy 61.303706 -284.772006)
			(xy 61.333271 -284.81135) (xy 61.356142 -284.854927) (xy 61.371726 -284.901608) (xy 61.379621 -284.950185)
			(xy 61.380116 -284.974792) (xy 61.718964 -284.974792) (xy 61.722924 -284.925738) (xy 61.734701 -284.877954)
			(xy 61.753992 -284.832678) (xy 61.780295 -284.791082) (xy 61.81293 -284.754245) (xy 61.851051 -284.72312)
			(xy 61.893672 -284.698513) (xy 61.939688 -284.681061) (xy 61.987907 -284.671217) (xy 62.037082 -284.669236)
			(xy 62.085937 -284.675168) (xy 62.133208 -284.68886) (xy 62.17767 -284.709958) (xy 62.218173 -284.737914)
			(xy 62.253666 -284.772006) (xy 62.283231 -284.81135) (xy 62.306102 -284.854927) (xy 62.321686 -284.901608)
			(xy 62.329581 -284.950185) (xy 62.330076 -284.974792) (xy 62.669178 -284.974792) (xy 62.673138 -284.925738)
			(xy 62.684915 -284.877954) (xy 62.704206 -284.832678) (xy 62.730509 -284.791082) (xy 62.763144 -284.754245)
			(xy 62.801265 -284.72312) (xy 62.843886 -284.698513) (xy 62.889902 -284.681061) (xy 62.938121 -284.671217)
			(xy 62.987296 -284.669236) (xy 63.036151 -284.675168) (xy 63.083422 -284.68886) (xy 63.127884 -284.709958)
			(xy 63.168387 -284.737914) (xy 63.20388 -284.772006) (xy 63.233445 -284.81135) (xy 63.256316 -284.854927)
			(xy 63.2719 -284.901608) (xy 63.279795 -284.950185) (xy 63.28029 -284.974792) (xy 63.619138 -284.974792)
			(xy 63.623098 -284.925738) (xy 63.634875 -284.877954) (xy 63.654166 -284.832678) (xy 63.680469 -284.791082)
			(xy 63.713104 -284.754245) (xy 63.751225 -284.72312) (xy 63.793846 -284.698513) (xy 63.839862 -284.681061)
			(xy 63.888081 -284.671217) (xy 63.937256 -284.669236) (xy 63.986111 -284.675168) (xy 64.033382 -284.68886)
			(xy 64.077844 -284.709958) (xy 64.118347 -284.737914) (xy 64.15384 -284.772006) (xy 64.183405 -284.81135)
			(xy 64.206276 -284.854927) (xy 64.22186 -284.901608) (xy 64.229755 -284.950185) (xy 64.23025 -284.974792)
			(xy 64.569098 -284.974792) (xy 64.573058 -284.925738) (xy 64.584835 -284.877954) (xy 64.604126 -284.832678)
			(xy 64.630429 -284.791082) (xy 64.663064 -284.754245) (xy 64.701185 -284.72312) (xy 64.743806 -284.698513)
			(xy 64.789822 -284.681061) (xy 64.838041 -284.671217) (xy 64.887216 -284.669236) (xy 64.936071 -284.675168)
			(xy 64.983342 -284.68886) (xy 65.027804 -284.709958) (xy 65.068307 -284.737914) (xy 65.1038 -284.772006)
			(xy 65.133365 -284.81135) (xy 65.156236 -284.854927) (xy 65.17182 -284.901608) (xy 65.179715 -284.950185)
			(xy 65.18021 -284.974792) (xy 65.519058 -284.974792) (xy 65.523018 -284.925738) (xy 65.534795 -284.877954)
			(xy 65.554086 -284.832678) (xy 65.580389 -284.791082) (xy 65.613024 -284.754245) (xy 65.651145 -284.72312)
			(xy 65.693766 -284.698513) (xy 65.739782 -284.681061) (xy 65.788001 -284.671217) (xy 65.837176 -284.669236)
			(xy 65.886031 -284.675168) (xy 65.933302 -284.68886) (xy 65.977764 -284.709958) (xy 66.018267 -284.737914)
			(xy 66.05376 -284.772006) (xy 66.083325 -284.81135) (xy 66.106196 -284.854927) (xy 66.12178 -284.901608)
			(xy 66.129675 -284.950185) (xy 66.13017 -284.974792) (xy 66.469018 -284.974792) (xy 66.472978 -284.925738)
			(xy 66.484755 -284.877954) (xy 66.504046 -284.832678) (xy 66.530349 -284.791082) (xy 66.562984 -284.754245)
			(xy 66.601105 -284.72312) (xy 66.643726 -284.698513) (xy 66.689742 -284.681061) (xy 66.737961 -284.671217)
			(xy 66.787136 -284.669236) (xy 66.835991 -284.675168) (xy 66.883262 -284.68886) (xy 66.927724 -284.709958)
			(xy 66.968227 -284.737914) (xy 67.00372 -284.772006) (xy 67.033285 -284.81135) (xy 67.056156 -284.854927)
			(xy 67.07174 -284.901608) (xy 67.079635 -284.950185) (xy 67.08013 -284.974792) (xy 67.418978 -284.974792)
			(xy 67.422938 -284.925738) (xy 67.434715 -284.877954) (xy 67.454006 -284.832678) (xy 67.480309 -284.791082)
			(xy 67.512944 -284.754245) (xy 67.551065 -284.72312) (xy 67.593686 -284.698513) (xy 67.639702 -284.681061)
			(xy 67.687921 -284.671217) (xy 67.737096 -284.669236) (xy 67.785951 -284.675168) (xy 67.833222 -284.68886)
			(xy 67.877684 -284.709958) (xy 67.918187 -284.737914) (xy 67.95368 -284.772006) (xy 67.983245 -284.81135)
			(xy 68.006116 -284.854927) (xy 68.0217 -284.901608) (xy 68.029595 -284.950185) (xy 68.03009 -284.974792)
			(xy 68.368938 -284.974792) (xy 68.372898 -284.925738) (xy 68.384675 -284.877954) (xy 68.403966 -284.832678)
			(xy 68.430269 -284.791082) (xy 68.462904 -284.754245) (xy 68.501025 -284.72312) (xy 68.543646 -284.698513)
			(xy 68.589662 -284.681061) (xy 68.637881 -284.671217) (xy 68.687056 -284.669236) (xy 68.735911 -284.675168)
			(xy 68.783182 -284.68886) (xy 68.827644 -284.709958) (xy 68.868147 -284.737914) (xy 68.90364 -284.772006)
			(xy 68.933205 -284.81135) (xy 68.956076 -284.854927) (xy 68.97166 -284.901608) (xy 68.979555 -284.950185)
			(xy 68.98005 -284.974792) (xy 69.319152 -284.974792) (xy 69.323112 -284.925738) (xy 69.334889 -284.877954)
			(xy 69.35418 -284.832678) (xy 69.380483 -284.791082) (xy 69.413118 -284.754245) (xy 69.451239 -284.72312)
			(xy 69.49386 -284.698513) (xy 69.539876 -284.681061) (xy 69.588095 -284.671217) (xy 69.63727 -284.669236)
			(xy 69.686125 -284.675168) (xy 69.733396 -284.68886) (xy 69.777858 -284.709958) (xy 69.818361 -284.737914)
			(xy 69.853854 -284.772006) (xy 69.883419 -284.81135) (xy 69.90629 -284.854927) (xy 69.921874 -284.901608)
			(xy 69.929769 -284.950185) (xy 69.930264 -284.974792) (xy 70.269112 -284.974792) (xy 70.273072 -284.925738)
			(xy 70.284849 -284.877954) (xy 70.30414 -284.832678) (xy 70.330443 -284.791082) (xy 70.363078 -284.754245)
			(xy 70.401199 -284.72312) (xy 70.44382 -284.698513) (xy 70.489836 -284.681061) (xy 70.538055 -284.671217)
			(xy 70.58723 -284.669236) (xy 70.636085 -284.675168) (xy 70.683356 -284.68886) (xy 70.727818 -284.709958)
			(xy 70.768321 -284.737914) (xy 70.803814 -284.772006) (xy 70.833379 -284.81135) (xy 70.85625 -284.854927)
			(xy 70.871834 -284.901608) (xy 70.879729 -284.950185) (xy 70.880224 -284.974792) (xy 70.879729 -284.999399)
			(xy 70.871834 -285.047976) (xy 70.85625 -285.094657) (xy 70.833379 -285.138234) (xy 70.803814 -285.177578)
			(xy 70.768321 -285.21167) (xy 70.727818 -285.239626) (xy 70.683356 -285.260724) (xy 70.636085 -285.274416)
			(xy 70.58723 -285.280348) (xy 70.538055 -285.278367) (xy 70.489836 -285.268523) (xy 70.44382 -285.251071)
			(xy 70.401199 -285.226464) (xy 70.363078 -285.195339) (xy 70.330443 -285.158502) (xy 70.30414 -285.116906)
			(xy 70.284849 -285.07163) (xy 70.273072 -285.023846) (xy 70.269112 -284.974792) (xy 69.930264 -284.974792)
			(xy 69.929769 -284.999399) (xy 69.921874 -285.047976) (xy 69.90629 -285.094657) (xy 69.883419 -285.138234)
			(xy 69.853854 -285.177578) (xy 69.818361 -285.21167) (xy 69.777858 -285.239626) (xy 69.733396 -285.260724)
			(xy 69.686125 -285.274416) (xy 69.63727 -285.280348) (xy 69.588095 -285.278367) (xy 69.539876 -285.268523)
			(xy 69.49386 -285.251071) (xy 69.451239 -285.226464) (xy 69.413118 -285.195339) (xy 69.380483 -285.158502)
			(xy 69.35418 -285.116906) (xy 69.334889 -285.07163) (xy 69.323112 -285.023846) (xy 69.319152 -284.974792)
			(xy 68.98005 -284.974792) (xy 68.979555 -284.999399) (xy 68.97166 -285.047976) (xy 68.956076 -285.094657)
			(xy 68.933205 -285.138234) (xy 68.90364 -285.177578) (xy 68.868147 -285.21167) (xy 68.827644 -285.239626)
			(xy 68.783182 -285.260724) (xy 68.735911 -285.274416) (xy 68.687056 -285.280348) (xy 68.637881 -285.278367)
			(xy 68.589662 -285.268523) (xy 68.543646 -285.251071) (xy 68.501025 -285.226464) (xy 68.462904 -285.195339)
			(xy 68.430269 -285.158502) (xy 68.403966 -285.116906) (xy 68.384675 -285.07163) (xy 68.372898 -285.023846)
			(xy 68.368938 -284.974792) (xy 68.03009 -284.974792) (xy 68.029595 -284.999399) (xy 68.0217 -285.047976)
			(xy 68.006116 -285.094657) (xy 67.983245 -285.138234) (xy 67.95368 -285.177578) (xy 67.918187 -285.21167)
			(xy 67.877684 -285.239626) (xy 67.833222 -285.260724) (xy 67.785951 -285.274416) (xy 67.737096 -285.280348)
			(xy 67.687921 -285.278367) (xy 67.639702 -285.268523) (xy 67.593686 -285.251071) (xy 67.551065 -285.226464)
			(xy 67.512944 -285.195339) (xy 67.480309 -285.158502) (xy 67.454006 -285.116906) (xy 67.434715 -285.07163)
			(xy 67.422938 -285.023846) (xy 67.418978 -284.974792) (xy 67.08013 -284.974792) (xy 67.079635 -284.999399)
			(xy 67.07174 -285.047976) (xy 67.056156 -285.094657) (xy 67.033285 -285.138234) (xy 67.00372 -285.177578)
			(xy 66.968227 -285.21167) (xy 66.927724 -285.239626) (xy 66.883262 -285.260724) (xy 66.835991 -285.274416)
			(xy 66.787136 -285.280348) (xy 66.737961 -285.278367) (xy 66.689742 -285.268523) (xy 66.643726 -285.251071)
			(xy 66.601105 -285.226464) (xy 66.562984 -285.195339) (xy 66.530349 -285.158502) (xy 66.504046 -285.116906)
			(xy 66.484755 -285.07163) (xy 66.472978 -285.023846) (xy 66.469018 -284.974792) (xy 66.13017 -284.974792)
			(xy 66.129675 -284.999399) (xy 66.12178 -285.047976) (xy 66.106196 -285.094657) (xy 66.083325 -285.138234)
			(xy 66.05376 -285.177578) (xy 66.018267 -285.21167) (xy 65.977764 -285.239626) (xy 65.933302 -285.260724)
			(xy 65.886031 -285.274416) (xy 65.837176 -285.280348) (xy 65.788001 -285.278367) (xy 65.739782 -285.268523)
			(xy 65.693766 -285.251071) (xy 65.651145 -285.226464) (xy 65.613024 -285.195339) (xy 65.580389 -285.158502)
			(xy 65.554086 -285.116906) (xy 65.534795 -285.07163) (xy 65.523018 -285.023846) (xy 65.519058 -284.974792)
			(xy 65.18021 -284.974792) (xy 65.179715 -284.999399) (xy 65.17182 -285.047976) (xy 65.156236 -285.094657)
			(xy 65.133365 -285.138234) (xy 65.1038 -285.177578) (xy 65.068307 -285.21167) (xy 65.027804 -285.239626)
			(xy 64.983342 -285.260724) (xy 64.936071 -285.274416) (xy 64.887216 -285.280348) (xy 64.838041 -285.278367)
			(xy 64.789822 -285.268523) (xy 64.743806 -285.251071) (xy 64.701185 -285.226464) (xy 64.663064 -285.195339)
			(xy 64.630429 -285.158502) (xy 64.604126 -285.116906) (xy 64.584835 -285.07163) (xy 64.573058 -285.023846)
			(xy 64.569098 -284.974792) (xy 64.23025 -284.974792) (xy 64.229755 -284.999399) (xy 64.22186 -285.047976)
			(xy 64.206276 -285.094657) (xy 64.183405 -285.138234) (xy 64.15384 -285.177578) (xy 64.118347 -285.21167)
			(xy 64.077844 -285.239626) (xy 64.033382 -285.260724) (xy 63.986111 -285.274416) (xy 63.937256 -285.280348)
			(xy 63.888081 -285.278367) (xy 63.839862 -285.268523) (xy 63.793846 -285.251071) (xy 63.751225 -285.226464)
			(xy 63.713104 -285.195339) (xy 63.680469 -285.158502) (xy 63.654166 -285.116906) (xy 63.634875 -285.07163)
			(xy 63.623098 -285.023846) (xy 63.619138 -284.974792) (xy 63.28029 -284.974792) (xy 63.279795 -284.999399)
			(xy 63.2719 -285.047976) (xy 63.256316 -285.094657) (xy 63.233445 -285.138234) (xy 63.20388 -285.177578)
			(xy 63.168387 -285.21167) (xy 63.127884 -285.239626) (xy 63.083422 -285.260724) (xy 63.036151 -285.274416)
			(xy 62.987296 -285.280348) (xy 62.938121 -285.278367) (xy 62.889902 -285.268523) (xy 62.843886 -285.251071)
			(xy 62.801265 -285.226464) (xy 62.763144 -285.195339) (xy 62.730509 -285.158502) (xy 62.704206 -285.116906)
			(xy 62.684915 -285.07163) (xy 62.673138 -285.023846) (xy 62.669178 -284.974792) (xy 62.330076 -284.974792)
			(xy 62.329581 -284.999399) (xy 62.321686 -285.047976) (xy 62.306102 -285.094657) (xy 62.283231 -285.138234)
			(xy 62.253666 -285.177578) (xy 62.218173 -285.21167) (xy 62.17767 -285.239626) (xy 62.133208 -285.260724)
			(xy 62.085937 -285.274416) (xy 62.037082 -285.280348) (xy 61.987907 -285.278367) (xy 61.939688 -285.268523)
			(xy 61.893672 -285.251071) (xy 61.851051 -285.226464) (xy 61.81293 -285.195339) (xy 61.780295 -285.158502)
			(xy 61.753992 -285.116906) (xy 61.734701 -285.07163) (xy 61.722924 -285.023846) (xy 61.718964 -284.974792)
			(xy 61.380116 -284.974792) (xy 61.379621 -284.999399) (xy 61.371726 -285.047976) (xy 61.356142 -285.094657)
			(xy 61.333271 -285.138234) (xy 61.303706 -285.177578) (xy 61.268213 -285.21167) (xy 61.22771 -285.239626)
			(xy 61.183248 -285.260724) (xy 61.135977 -285.274416) (xy 61.087122 -285.280348) (xy 61.037947 -285.278367)
			(xy 60.989728 -285.268523) (xy 60.943712 -285.251071) (xy 60.901091 -285.226464) (xy 60.86297 -285.195339)
			(xy 60.830335 -285.158502) (xy 60.804032 -285.116906) (xy 60.784741 -285.07163) (xy 60.772964 -285.023846)
			(xy 60.769004 -284.974792) (xy 60.430156 -284.974792) (xy 60.429661 -284.999399) (xy 60.421766 -285.047976)
			(xy 60.406182 -285.094657) (xy 60.383311 -285.138234) (xy 60.353746 -285.177578) (xy 60.318253 -285.21167)
			(xy 60.27775 -285.239626) (xy 60.233288 -285.260724) (xy 60.186017 -285.274416) (xy 60.137162 -285.280348)
			(xy 60.087987 -285.278367) (xy 60.039768 -285.268523) (xy 59.993752 -285.251071) (xy 59.951131 -285.226464)
			(xy 59.91301 -285.195339) (xy 59.880375 -285.158502) (xy 59.854072 -285.116906) (xy 59.834781 -285.07163)
			(xy 59.823004 -285.023846) (xy 59.819044 -284.974792) (xy 58.530236 -284.974792) (xy 58.529741 -284.999399)
			(xy 58.521846 -285.047976) (xy 58.506262 -285.094657) (xy 58.483391 -285.138234) (xy 58.453826 -285.177578)
			(xy 58.418333 -285.21167) (xy 58.37783 -285.239626) (xy 58.333368 -285.260724) (xy 58.286097 -285.274416)
			(xy 58.237242 -285.280348) (xy 58.188067 -285.278367) (xy 58.139848 -285.268523) (xy 58.093832 -285.251071)
			(xy 58.051211 -285.226464) (xy 58.01309 -285.195339) (xy 57.980455 -285.158502) (xy 57.954152 -285.116906)
			(xy 57.934861 -285.07163) (xy 57.923084 -285.023846) (xy 57.919124 -284.974792) (xy 57.580276 -284.974792)
			(xy 57.579781 -284.999399) (xy 57.571886 -285.047976) (xy 57.556302 -285.094657) (xy 57.533431 -285.138234)
			(xy 57.503866 -285.177578) (xy 57.468373 -285.21167) (xy 57.42787 -285.239626) (xy 57.383408 -285.260724)
			(xy 57.336137 -285.274416) (xy 57.287282 -285.280348) (xy 57.238107 -285.278367) (xy 57.189888 -285.268523)
			(xy 57.143872 -285.251071) (xy 57.101251 -285.226464) (xy 57.06313 -285.195339) (xy 57.030495 -285.158502)
			(xy 57.004192 -285.116906) (xy 56.984901 -285.07163) (xy 56.973124 -285.023846) (xy 56.969164 -284.974792)
			(xy 56.630062 -284.974792) (xy 56.629567 -284.999399) (xy 56.621672 -285.047976) (xy 56.606088 -285.094657)
			(xy 56.583217 -285.138234) (xy 56.553652 -285.177578) (xy 56.518159 -285.21167) (xy 56.477656 -285.239626)
			(xy 56.433194 -285.260724) (xy 56.385923 -285.274416) (xy 56.337068 -285.280348) (xy 56.287893 -285.278367)
			(xy 56.239674 -285.268523) (xy 56.193658 -285.251071) (xy 56.151037 -285.226464) (xy 56.112916 -285.195339)
			(xy 56.080281 -285.158502) (xy 56.053978 -285.116906) (xy 56.034687 -285.07163) (xy 56.02291 -285.023846)
			(xy 56.01895 -284.974792) (xy 55.680102 -284.974792) (xy 55.679607 -284.999399) (xy 55.671712 -285.047976)
			(xy 55.656128 -285.094657) (xy 55.633257 -285.138234) (xy 55.603692 -285.177578) (xy 55.568199 -285.21167)
			(xy 55.527696 -285.239626) (xy 55.483234 -285.260724) (xy 55.435963 -285.274416) (xy 55.387108 -285.280348)
			(xy 55.337933 -285.278367) (xy 55.289714 -285.268523) (xy 55.243698 -285.251071) (xy 55.201077 -285.226464)
			(xy 55.162956 -285.195339) (xy 55.130321 -285.158502) (xy 55.104018 -285.116906) (xy 55.084727 -285.07163)
			(xy 55.07295 -285.023846) (xy 55.06899 -284.974792) (xy 54.730142 -284.974792) (xy 54.729647 -284.999399)
			(xy 54.721752 -285.047976) (xy 54.706168 -285.094657) (xy 54.683297 -285.138234) (xy 54.653732 -285.177578)
			(xy 54.618239 -285.21167) (xy 54.577736 -285.239626) (xy 54.533274 -285.260724) (xy 54.486003 -285.274416)
			(xy 54.437148 -285.280348) (xy 54.387973 -285.278367) (xy 54.339754 -285.268523) (xy 54.293738 -285.251071)
			(xy 54.251117 -285.226464) (xy 54.212996 -285.195339) (xy 54.180361 -285.158502) (xy 54.154058 -285.116906)
			(xy 54.134767 -285.07163) (xy 54.12299 -285.023846) (xy 54.11903 -284.974792) (xy 53.780182 -284.974792)
			(xy 53.779687 -284.999399) (xy 53.771792 -285.047976) (xy 53.756208 -285.094657) (xy 53.733337 -285.138234)
			(xy 53.703772 -285.177578) (xy 53.668279 -285.21167) (xy 53.627776 -285.239626) (xy 53.583314 -285.260724)
			(xy 53.536043 -285.274416) (xy 53.487188 -285.280348) (xy 53.438013 -285.278367) (xy 53.389794 -285.268523)
			(xy 53.343778 -285.251071) (xy 53.301157 -285.226464) (xy 53.263036 -285.195339) (xy 53.230401 -285.158502)
			(xy 53.204098 -285.116906) (xy 53.184807 -285.07163) (xy 53.17303 -285.023846) (xy 53.16907 -284.974792)
			(xy 52.830222 -284.974792) (xy 52.829727 -284.999399) (xy 52.821832 -285.047976) (xy 52.806248 -285.094657)
			(xy 52.783377 -285.138234) (xy 52.753812 -285.177578) (xy 52.718319 -285.21167) (xy 52.677816 -285.239626)
			(xy 52.633354 -285.260724) (xy 52.586083 -285.274416) (xy 52.537228 -285.280348) (xy 52.488053 -285.278367)
			(xy 52.439834 -285.268523) (xy 52.393818 -285.251071) (xy 52.351197 -285.226464) (xy 52.313076 -285.195339)
			(xy 52.280441 -285.158502) (xy 52.254138 -285.116906) (xy 52.234847 -285.07163) (xy 52.22307 -285.023846)
			(xy 52.21911 -284.974792) (xy 51.880262 -284.974792) (xy 51.879767 -284.999399) (xy 51.871872 -285.047976)
			(xy 51.856288 -285.094657) (xy 51.833417 -285.138234) (xy 51.803852 -285.177578) (xy 51.768359 -285.21167)
			(xy 51.727856 -285.239626) (xy 51.683394 -285.260724) (xy 51.636123 -285.274416) (xy 51.587268 -285.280348)
			(xy 51.538093 -285.278367) (xy 51.489874 -285.268523) (xy 51.443858 -285.251071) (xy 51.401237 -285.226464)
			(xy 51.363116 -285.195339) (xy 51.330481 -285.158502) (xy 51.304178 -285.116906) (xy 51.284887 -285.07163)
			(xy 51.27311 -285.023846) (xy 51.26915 -284.974792) (xy 50.930302 -284.974792) (xy 50.929807 -284.999399)
			(xy 50.921912 -285.047976) (xy 50.906328 -285.094657) (xy 50.883457 -285.138234) (xy 50.853892 -285.177578)
			(xy 50.818399 -285.21167) (xy 50.777896 -285.239626) (xy 50.733434 -285.260724) (xy 50.686163 -285.274416)
			(xy 50.637308 -285.280348) (xy 50.588133 -285.278367) (xy 50.539914 -285.268523) (xy 50.493898 -285.251071)
			(xy 50.451277 -285.226464) (xy 50.413156 -285.195339) (xy 50.380521 -285.158502) (xy 50.354218 -285.116906)
			(xy 50.334927 -285.07163) (xy 50.32315 -285.023846) (xy 50.31919 -284.974792) (xy 49.980088 -284.974792)
			(xy 49.979593 -284.999399) (xy 49.971698 -285.047976) (xy 49.956114 -285.094657) (xy 49.933243 -285.138234)
			(xy 49.903678 -285.177578) (xy 49.868185 -285.21167) (xy 49.827682 -285.239626) (xy 49.78322 -285.260724)
			(xy 49.735949 -285.274416) (xy 49.687094 -285.280348) (xy 49.637919 -285.278367) (xy 49.5897 -285.268523)
			(xy 49.543684 -285.251071) (xy 49.501063 -285.226464) (xy 49.462942 -285.195339) (xy 49.430307 -285.158502)
			(xy 49.404004 -285.116906) (xy 49.384713 -285.07163) (xy 49.372936 -285.023846) (xy 49.368976 -284.974792)
			(xy 49.030128 -284.974792) (xy 49.029633 -284.999399) (xy 49.021738 -285.047976) (xy 49.006154 -285.094657)
			(xy 48.983283 -285.138234) (xy 48.953718 -285.177578) (xy 48.918225 -285.21167) (xy 48.877722 -285.239626)
			(xy 48.83326 -285.260724) (xy 48.785989 -285.274416) (xy 48.737134 -285.280348) (xy 48.687959 -285.278367)
			(xy 48.63974 -285.268523) (xy 48.593724 -285.251071) (xy 48.551103 -285.226464) (xy 48.512982 -285.195339)
			(xy 48.480347 -285.158502) (xy 48.454044 -285.116906) (xy 48.434753 -285.07163) (xy 48.422976 -285.023846)
			(xy 48.419016 -284.974792) (xy 48.080168 -284.974792) (xy 48.079673 -284.999399) (xy 48.071778 -285.047976)
			(xy 48.056194 -285.094657) (xy 48.033323 -285.138234) (xy 48.003758 -285.177578) (xy 47.968265 -285.21167)
			(xy 47.927762 -285.239626) (xy 47.8833 -285.260724) (xy 47.836029 -285.274416) (xy 47.787174 -285.280348)
			(xy 47.737999 -285.278367) (xy 47.68978 -285.268523) (xy 47.643764 -285.251071) (xy 47.601143 -285.226464)
			(xy 47.563022 -285.195339) (xy 47.530387 -285.158502) (xy 47.504084 -285.116906) (xy 47.484793 -285.07163)
			(xy 47.473016 -285.023846) (xy 47.469056 -284.974792) (xy 47.130208 -284.974792) (xy 47.129713 -284.999399)
			(xy 47.121818 -285.047976) (xy 47.106234 -285.094657) (xy 47.083363 -285.138234) (xy 47.053798 -285.177578)
			(xy 47.018305 -285.21167) (xy 46.977802 -285.239626) (xy 46.93334 -285.260724) (xy 46.886069 -285.274416)
			(xy 46.837214 -285.280348) (xy 46.788039 -285.278367) (xy 46.73982 -285.268523) (xy 46.693804 -285.251071)
			(xy 46.651183 -285.226464) (xy 46.613062 -285.195339) (xy 46.580427 -285.158502) (xy 46.554124 -285.116906)
			(xy 46.534833 -285.07163) (xy 46.523056 -285.023846) (xy 46.519096 -284.974792) (xy 46.180248 -284.974792)
			(xy 46.179753 -284.999399) (xy 46.171858 -285.047976) (xy 46.156274 -285.094657) (xy 46.133403 -285.138234)
			(xy 46.103838 -285.177578) (xy 46.068345 -285.21167) (xy 46.027842 -285.239626) (xy 45.98338 -285.260724)
			(xy 45.936109 -285.274416) (xy 45.887254 -285.280348) (xy 45.838079 -285.278367) (xy 45.78986 -285.268523)
			(xy 45.743844 -285.251071) (xy 45.701223 -285.226464) (xy 45.663102 -285.195339) (xy 45.630467 -285.158502)
			(xy 45.604164 -285.116906) (xy 45.584873 -285.07163) (xy 45.573096 -285.023846) (xy 45.569136 -284.974792)
			(xy 45.230288 -284.974792) (xy 45.229793 -284.999399) (xy 45.221898 -285.047976) (xy 45.206314 -285.094657)
			(xy 45.183443 -285.138234) (xy 45.153878 -285.177578) (xy 45.118385 -285.21167) (xy 45.077882 -285.239626)
			(xy 45.03342 -285.260724) (xy 44.986149 -285.274416) (xy 44.937294 -285.280348) (xy 44.888119 -285.278367)
			(xy 44.8399 -285.268523) (xy 44.793884 -285.251071) (xy 44.751263 -285.226464) (xy 44.713142 -285.195339)
			(xy 44.680507 -285.158502) (xy 44.654204 -285.116906) (xy 44.634913 -285.07163) (xy 44.623136 -285.023846)
			(xy 44.619176 -284.974792) (xy 43.330114 -284.974792) (xy 43.329619 -284.999399) (xy 43.321724 -285.047976)
			(xy 43.30614 -285.094657) (xy 43.283269 -285.138234) (xy 43.253704 -285.177578) (xy 43.218211 -285.21167)
			(xy 43.177708 -285.239626) (xy 43.133246 -285.260724) (xy 43.085975 -285.274416) (xy 43.03712 -285.280348)
			(xy 42.987945 -285.278367) (xy 42.939726 -285.268523) (xy 42.89371 -285.251071) (xy 42.851089 -285.226464)
			(xy 42.812968 -285.195339) (xy 42.780333 -285.158502) (xy 42.75403 -285.116906) (xy 42.734739 -285.07163)
			(xy 42.722962 -285.023846) (xy 42.719002 -284.974792) (xy 41.430194 -284.974792) (xy 41.429699 -284.999399)
			(xy 41.421804 -285.047976) (xy 41.40622 -285.094657) (xy 41.383349 -285.138234) (xy 41.353784 -285.177578)
			(xy 41.318291 -285.21167) (xy 41.277788 -285.239626) (xy 41.233326 -285.260724) (xy 41.186055 -285.274416)
			(xy 41.1372 -285.280348) (xy 41.088025 -285.278367) (xy 41.039806 -285.268523) (xy 40.99379 -285.251071)
			(xy 40.951169 -285.226464) (xy 40.913048 -285.195339) (xy 40.880413 -285.158502) (xy 40.85411 -285.116906)
			(xy 40.834819 -285.07163) (xy 40.823042 -285.023846) (xy 40.819082 -284.974792) (xy 40.480234 -284.974792)
			(xy 40.479739 -284.999399) (xy 40.471844 -285.047976) (xy 40.45626 -285.094657) (xy 40.433389 -285.138234)
			(xy 40.403824 -285.177578) (xy 40.368331 -285.21167) (xy 40.327828 -285.239626) (xy 40.283366 -285.260724)
			(xy 40.236095 -285.274416) (xy 40.18724 -285.280348) (xy 40.138065 -285.278367) (xy 40.089846 -285.268523)
			(xy 40.04383 -285.251071) (xy 40.001209 -285.226464) (xy 39.963088 -285.195339) (xy 39.930453 -285.158502)
			(xy 39.90415 -285.116906) (xy 39.884859 -285.07163) (xy 39.873082 -285.023846) (xy 39.869122 -284.974792)
			(xy 39.530274 -284.974792) (xy 39.529779 -284.999399) (xy 39.521884 -285.047976) (xy 39.5063 -285.094657)
			(xy 39.483429 -285.138234) (xy 39.453864 -285.177578) (xy 39.418371 -285.21167) (xy 39.377868 -285.239626)
			(xy 39.333406 -285.260724) (xy 39.286135 -285.274416) (xy 39.23728 -285.280348) (xy 39.188105 -285.278367)
			(xy 39.139886 -285.268523) (xy 39.09387 -285.251071) (xy 39.051249 -285.226464) (xy 39.013128 -285.195339)
			(xy 38.980493 -285.158502) (xy 38.95419 -285.116906) (xy 38.934899 -285.07163) (xy 38.923122 -285.023846)
			(xy 38.919162 -284.974792) (xy 38.580314 -284.974792) (xy 38.579819 -284.999399) (xy 38.571924 -285.047976)
			(xy 38.55634 -285.094657) (xy 38.533469 -285.138234) (xy 38.503904 -285.177578) (xy 38.468411 -285.21167)
			(xy 38.427908 -285.239626) (xy 38.383446 -285.260724) (xy 38.336175 -285.274416) (xy 38.28732 -285.280348)
			(xy 38.238145 -285.278367) (xy 38.189926 -285.268523) (xy 38.14391 -285.251071) (xy 38.101289 -285.226464)
			(xy 38.063168 -285.195339) (xy 38.030533 -285.158502) (xy 38.00423 -285.116906) (xy 37.984939 -285.07163)
			(xy 37.973162 -285.023846) (xy 37.969202 -284.974792) (xy 37.6301 -284.974792) (xy 37.629605 -284.999399)
			(xy 37.62171 -285.047976) (xy 37.606126 -285.094657) (xy 37.583255 -285.138234) (xy 37.55369 -285.177578)
			(xy 37.518197 -285.21167) (xy 37.477694 -285.239626) (xy 37.433232 -285.260724) (xy 37.385961 -285.274416)
			(xy 37.337106 -285.280348) (xy 37.287931 -285.278367) (xy 37.239712 -285.268523) (xy 37.193696 -285.251071)
			(xy 37.151075 -285.226464) (xy 37.112954 -285.195339) (xy 37.080319 -285.158502) (xy 37.054016 -285.116906)
			(xy 37.034725 -285.07163) (xy 37.022948 -285.023846) (xy 37.018988 -284.974792) (xy 36.68014 -284.974792)
			(xy 36.679645 -284.999399) (xy 36.67175 -285.047976) (xy 36.656166 -285.094657) (xy 36.633295 -285.138234)
			(xy 36.60373 -285.177578) (xy 36.568237 -285.21167) (xy 36.527734 -285.239626) (xy 36.483272 -285.260724)
			(xy 36.436001 -285.274416) (xy 36.387146 -285.280348) (xy 36.337971 -285.278367) (xy 36.289752 -285.268523)
			(xy 36.243736 -285.251071) (xy 36.201115 -285.226464) (xy 36.162994 -285.195339) (xy 36.130359 -285.158502)
			(xy 36.104056 -285.116906) (xy 36.084765 -285.07163) (xy 36.072988 -285.023846) (xy 36.069028 -284.974792)
			(xy 28.055663 -284.974792) (xy 28.059633 -285.00177) (xy 28.060142 -285.029656) (xy 28.059633 -285.057542)
			(xy 28.051513 -285.112718) (xy 28.035445 -285.166125) (xy 28.011773 -285.216622) (xy 27.981 -285.263135)
			(xy 27.943783 -285.304672) (xy 27.900915 -285.340347) (xy 27.853309 -285.369401) (xy 27.80198 -285.391213)
			(xy 27.748023 -285.405319) (xy 27.692586 -285.411419) (xy 27.636852 -285.409382) (xy 27.582009 -285.399252)
			(xy 27.529225 -285.381245) (xy 27.479625 -285.355744) (xy 27.434267 -285.323293) (xy 27.394118 -285.284584)
			(xy 27.360032 -285.240441) (xy 27.332736 -285.191806) (xy 27.312813 -285.139715) (xy 27.300687 -285.085278)
			(xy 27.296616 -285.029656) (xy 26.575004 -285.029656) (xy 26.574495 -285.057542) (xy 26.566375 -285.112718)
			(xy 26.550307 -285.166125) (xy 26.526635 -285.216622) (xy 26.495862 -285.263135) (xy 26.458645 -285.304672)
			(xy 26.415777 -285.340347) (xy 26.368171 -285.369401) (xy 26.316842 -285.391213) (xy 26.262885 -285.405319)
			(xy 26.207448 -285.411419) (xy 26.151714 -285.409382) (xy 26.096871 -285.399252) (xy 26.044087 -285.381245)
			(xy 25.994487 -285.355744) (xy 25.949129 -285.323293) (xy 25.90898 -285.284584) (xy 25.874894 -285.240441)
			(xy 25.847598 -285.191806) (xy 25.827675 -285.139715) (xy 25.815549 -285.085278) (xy 25.811478 -285.029656)
			(xy 8.591101 -285.029656) (xy 8.579622 -285.047517) (xy 8.543928 -285.08871) (xy 8.502734 -285.124404)
			(xy 8.45688 -285.153872) (xy 8.407299 -285.176515) (xy 8.355001 -285.19187) (xy 8.301049 -285.199627)
			(xy 8.273796 -285.20009) (xy 8.243672 -285.199539) (xy 8.184174 -285.190056) (xy 8.126905 -285.171341)
			(xy 8.073288 -285.14386) (xy 8.024656 -285.108296) (xy 8.003032 -285.087314) (xy 7.995613 -285.080497)
			(xy 7.977028 -285.072763) (xy 7.966964 -285.072328) (xy 7.894828 -285.072328) (xy 7.884759 -285.072761)
			(xy 7.866161 -285.080476) (xy 7.85876 -285.087314) (xy 7.837134 -285.108293) (xy 7.788505 -285.143861)
			(xy 7.734889 -285.171341) (xy 7.677619 -285.190049) (xy 7.61812 -285.199521) (xy 7.587996 -285.20009)
			(xy 7.559257 -285.199571) (xy 7.502429 -285.190948) (xy 7.447538 -285.173897) (xy 7.395827 -285.148804)
			(xy 7.348464 -285.116237) (xy 7.327138 -285.096966) (xy 7.32028 -285.090362) (xy 7.302246 -285.08325)
			(xy 7.213346 -285.08325) (xy 7.195312 -285.090362) (xy 7.188454 -285.096966) (xy 7.167127 -285.116236)
			(xy 7.119764 -285.148801) (xy 7.068053 -285.173892) (xy 7.013162 -285.190942) (xy 6.956335 -285.199564)
			(xy 6.898857 -285.199564) (xy 6.84203 -285.190942) (xy 6.787139 -285.173892) (xy 6.735428 -285.148801)
			(xy 6.688065 -285.116236) (xy 6.666738 -285.096966) (xy 6.65988 -285.090362) (xy 6.641846 -285.08325)
			(xy 6.552946 -285.08325) (xy 6.534912 -285.090362) (xy 6.528054 -285.096966) (xy 6.506729 -285.116239)
			(xy 6.459366 -285.148805) (xy 6.407654 -285.173897) (xy 6.352763 -285.190947) (xy 6.295935 -285.199569)
			(xy 6.267196 -285.20009) (xy 6.239945 -285.1996) (xy 6.185998 -285.191843) (xy 6.133704 -285.176488)
			(xy 6.084128 -285.153846) (xy 6.038278 -285.12438) (xy 5.997088 -285.088689) (xy 5.961397 -285.047499)
			(xy 5.931932 -285.001649) (xy 5.909291 -284.952072) (xy 5.893936 -284.899778) (xy 5.88618 -284.845831)
			(xy 4.636057 -284.845831) (xy 4.636057 -284.845833) (xy 4.6283 -284.899784) (xy 4.612943 -284.952083)
			(xy 4.590301 -285.001663) (xy 4.560832 -285.047517) (xy 4.525138 -285.08871) (xy 4.483945 -285.124403)
			(xy 4.438091 -285.153872) (xy 4.388511 -285.176514) (xy 4.336213 -285.19187) (xy 4.282261 -285.199627)
			(xy 4.255008 -285.20009) (xy 4.227638 -285.199622) (xy 4.173459 -285.191805) (xy 4.120956 -285.176316)
			(xy 4.071209 -285.153475) (xy 4.025242 -285.123751) (xy 4.00431 -285.10611) (xy 4.004056 -285.105856)
			(xy 3.996961 -285.100281) (xy 3.980051 -285.094029) (xy 3.971036 -285.093664) (xy 3.90398 -285.093664)
			(xy 3.894963 -285.094019) (xy 3.878046 -285.100269) (xy 3.87096 -285.105856) (xy 3.87096 -285.10611)
			(xy 3.870706 -285.10611) (xy 3.849784 -285.123761) (xy 3.803808 -285.153471) (xy 3.754058 -285.176304)
			(xy 3.701555 -285.191793) (xy 3.647378 -285.199618) (xy 3.620008 -285.20009) (xy 3.589884 -285.199531)
			(xy 3.530386 -285.19005) (xy 3.473117 -285.171337) (xy 3.419501 -285.143858) (xy 3.370868 -285.108295)
			(xy 3.349244 -285.087314) (xy 3.341821 -285.080503) (xy 3.323239 -285.072766) (xy 3.313176 -285.072328)
			(xy 3.24104 -285.072328) (xy 3.230972 -285.072767) (xy 3.212374 -285.080478) (xy 3.204972 -285.087314)
			(xy 3.183341 -285.108287) (xy 3.134713 -285.143856) (xy 3.081099 -285.171337) (xy 3.02383 -285.190047)
			(xy 2.964332 -285.19952) (xy 2.934208 -285.20009) (xy 2.905469 -285.199564) (xy 2.848642 -285.190942)
			(xy 2.793751 -285.173893) (xy 2.742039 -285.148802) (xy 2.694677 -285.116237) (xy 2.67335 -285.096966)
			(xy 2.666492 -285.090362) (xy 2.648458 -285.08325) (xy 2.559558 -285.08325) (xy 2.541524 -285.090362)
			(xy 2.534666 -285.096966) (xy 2.513336 -285.116234) (xy 2.465975 -285.1488) (xy 2.414264 -285.173893)
			(xy 2.359374 -285.190945) (xy 2.302547 -285.199568) (xy 2.273808 -285.20009) (xy 2.246557 -285.1996)
			(xy 2.19261 -285.191843) (xy 2.140316 -285.176488) (xy 2.090739 -285.153847) (xy 2.044889 -285.124381)
			(xy 2.003699 -285.088689) (xy 1.968008 -285.0475) (xy 1.938542 -285.001649) (xy 1.915901 -284.952073)
			(xy 1.900546 -284.899778) (xy 1.89279 -284.845831) (xy 1.420114 -284.845831) (xy 1.420114 -285.462218)
			(xy 11.958572 -285.462218) (xy 11.962643 -285.406596) (xy 11.974769 -285.352159) (xy 11.994692 -285.300068)
			(xy 12.021988 -285.251433) (xy 12.056074 -285.20729) (xy 12.096223 -285.168581) (xy 12.141581 -285.13613)
			(xy 12.191181 -285.110629) (xy 12.243965 -285.092622) (xy 12.298808 -285.082492) (xy 12.354542 -285.080455)
			(xy 12.409979 -285.086555) (xy 12.463936 -285.100661) (xy 12.515265 -285.122473) (xy 12.562871 -285.151527)
			(xy 12.605739 -285.187202) (xy 12.642956 -285.228739) (xy 12.673729 -285.275252) (xy 12.697401 -285.325749)
			(xy 12.713469 -285.379156) (xy 12.721589 -285.434332) (xy 12.722098 -285.462218) (xy 14.151354 -285.462218)
			(xy 14.155425 -285.406596) (xy 14.167551 -285.352159) (xy 14.187474 -285.300068) (xy 14.21477 -285.251433)
			(xy 14.248856 -285.20729) (xy 14.289005 -285.168581) (xy 14.334363 -285.13613) (xy 14.383963 -285.110629)
			(xy 14.436747 -285.092622) (xy 14.49159 -285.082492) (xy 14.547324 -285.080455) (xy 14.602761 -285.086555)
			(xy 14.656718 -285.100661) (xy 14.708047 -285.122473) (xy 14.755653 -285.151527) (xy 14.798521 -285.187202)
			(xy 14.835738 -285.228739) (xy 14.866511 -285.275252) (xy 14.890183 -285.325749) (xy 14.906251 -285.379156)
			(xy 14.914371 -285.434332) (xy 14.914653 -285.449772) (xy 73.593972 -285.449772) (xy 73.597932 -285.400718)
			(xy 73.609709 -285.352934) (xy 73.629 -285.307658) (xy 73.655303 -285.266062) (xy 73.687938 -285.229225)
			(xy 73.726059 -285.1981) (xy 73.76868 -285.173493) (xy 73.814696 -285.156041) (xy 73.862915 -285.146197)
			(xy 73.91209 -285.144216) (xy 73.960945 -285.150148) (xy 74.008216 -285.16384) (xy 74.052678 -285.184938)
			(xy 74.093181 -285.212894) (xy 74.128674 -285.246986) (xy 74.158239 -285.28633) (xy 74.18111 -285.329907)
			(xy 74.196694 -285.376588) (xy 74.204589 -285.425165) (xy 74.205084 -285.449772) (xy 74.204589 -285.474379)
			(xy 74.20441 -285.47548) (xy 74.523088 -285.47548) (xy 74.523088 -285.424064) (xy 74.531131 -285.373282)
			(xy 74.547019 -285.324383) (xy 74.570362 -285.278571) (xy 74.600583 -285.236975) (xy 74.636939 -285.200619)
			(xy 74.678535 -285.170398) (xy 74.724347 -285.147055) (xy 74.773246 -285.131167) (xy 74.824028 -285.123124)
			(xy 74.875444 -285.123124) (xy 74.926226 -285.131167) (xy 74.975125 -285.147055) (xy 75.020937 -285.170398)
			(xy 75.062533 -285.200619) (xy 75.098889 -285.236975) (xy 75.12911 -285.278571) (xy 75.152453 -285.324383)
			(xy 75.168341 -285.373282) (xy 75.176384 -285.424064) (xy 75.176888 -285.449772) (xy 75.176384 -285.47548)
			(xy 75.473302 -285.47548) (xy 75.473302 -285.424064) (xy 75.481345 -285.373282) (xy 75.497233 -285.324383)
			(xy 75.520576 -285.278571) (xy 75.550797 -285.236975) (xy 75.587153 -285.200619) (xy 75.628749 -285.170398)
			(xy 75.674561 -285.147055) (xy 75.72346 -285.131167) (xy 75.774242 -285.123124) (xy 75.825658 -285.123124)
			(xy 75.87644 -285.131167) (xy 75.925339 -285.147055) (xy 75.971151 -285.170398) (xy 76.012747 -285.200619)
			(xy 76.049103 -285.236975) (xy 76.079324 -285.278571) (xy 76.102667 -285.324383) (xy 76.118555 -285.373282)
			(xy 76.126598 -285.424064) (xy 76.127102 -285.449772) (xy 76.444106 -285.449772) (xy 76.448066 -285.400718)
			(xy 76.459843 -285.352934) (xy 76.479134 -285.307658) (xy 76.505437 -285.266062) (xy 76.538072 -285.229225)
			(xy 76.576193 -285.1981) (xy 76.618814 -285.173493) (xy 76.66483 -285.156041) (xy 76.713049 -285.146197)
			(xy 76.762224 -285.144216) (xy 76.811079 -285.150148) (xy 76.85835 -285.16384) (xy 76.902812 -285.184938)
			(xy 76.943315 -285.212894) (xy 76.978808 -285.246986) (xy 77.008373 -285.28633) (xy 77.031244 -285.329907)
			(xy 77.046828 -285.376588) (xy 77.054723 -285.425165) (xy 77.055218 -285.449772) (xy 77.394066 -285.449772)
			(xy 77.398026 -285.400718) (xy 77.409803 -285.352934) (xy 77.429094 -285.307658) (xy 77.455397 -285.266062)
			(xy 77.488032 -285.229225) (xy 77.526153 -285.1981) (xy 77.568774 -285.173493) (xy 77.61479 -285.156041)
			(xy 77.663009 -285.146197) (xy 77.712184 -285.144216) (xy 77.761039 -285.150148) (xy 77.80831 -285.16384)
			(xy 77.852772 -285.184938) (xy 77.893275 -285.212894) (xy 77.928768 -285.246986) (xy 77.958333 -285.28633)
			(xy 77.981204 -285.329907) (xy 77.996788 -285.376588) (xy 78.004683 -285.425165) (xy 78.005178 -285.449772)
			(xy 78.344026 -285.449772) (xy 78.347986 -285.400718) (xy 78.359763 -285.352934) (xy 78.379054 -285.307658)
			(xy 78.405357 -285.266062) (xy 78.437992 -285.229225) (xy 78.476113 -285.1981) (xy 78.518734 -285.173493)
			(xy 78.56475 -285.156041) (xy 78.612969 -285.146197) (xy 78.662144 -285.144216) (xy 78.710999 -285.150148)
			(xy 78.75827 -285.16384) (xy 78.802732 -285.184938) (xy 78.843235 -285.212894) (xy 78.878728 -285.246986)
			(xy 78.908293 -285.28633) (xy 78.931164 -285.329907) (xy 78.946748 -285.376588) (xy 78.954643 -285.425165)
			(xy 78.955138 -285.449772) (xy 79.293986 -285.449772) (xy 79.297946 -285.400718) (xy 79.309723 -285.352934)
			(xy 79.329014 -285.307658) (xy 79.355317 -285.266062) (xy 79.387952 -285.229225) (xy 79.426073 -285.1981)
			(xy 79.468694 -285.173493) (xy 79.51471 -285.156041) (xy 79.562929 -285.146197) (xy 79.612104 -285.144216)
			(xy 79.660959 -285.150148) (xy 79.70823 -285.16384) (xy 79.752692 -285.184938) (xy 79.793195 -285.212894)
			(xy 79.828688 -285.246986) (xy 79.858253 -285.28633) (xy 79.881124 -285.329907) (xy 79.896708 -285.376588)
			(xy 79.904603 -285.425165) (xy 79.905098 -285.449772) (xy 80.243946 -285.449772) (xy 80.247906 -285.400718)
			(xy 80.259683 -285.352934) (xy 80.278974 -285.307658) (xy 80.305277 -285.266062) (xy 80.337912 -285.229225)
			(xy 80.376033 -285.1981) (xy 80.418654 -285.173493) (xy 80.46467 -285.156041) (xy 80.512889 -285.146197)
			(xy 80.562064 -285.144216) (xy 80.610919 -285.150148) (xy 80.65819 -285.16384) (xy 80.702652 -285.184938)
			(xy 80.743155 -285.212894) (xy 80.778648 -285.246986) (xy 80.808213 -285.28633) (xy 80.831084 -285.329907)
			(xy 80.846668 -285.376588) (xy 80.854563 -285.425165) (xy 80.855058 -285.449772) (xy 80.854563 -285.474379)
			(xy 80.854384 -285.47548) (xy 81.173316 -285.47548) (xy 81.173316 -285.424064) (xy 81.181359 -285.373282)
			(xy 81.197247 -285.324383) (xy 81.22059 -285.278571) (xy 81.250811 -285.236975) (xy 81.287167 -285.200619)
			(xy 81.328763 -285.170398) (xy 81.374575 -285.147055) (xy 81.423474 -285.131167) (xy 81.474256 -285.123124)
			(xy 81.525672 -285.123124) (xy 81.576454 -285.131167) (xy 81.625353 -285.147055) (xy 81.671165 -285.170398)
			(xy 81.712761 -285.200619) (xy 81.749117 -285.236975) (xy 81.779338 -285.278571) (xy 81.802681 -285.324383)
			(xy 81.818569 -285.373282) (xy 81.826612 -285.424064) (xy 81.827116 -285.449772) (xy 81.826612 -285.47548)
			(xy 82.123276 -285.47548) (xy 82.123276 -285.424064) (xy 82.131319 -285.373282) (xy 82.147207 -285.324383)
			(xy 82.17055 -285.278571) (xy 82.200771 -285.236975) (xy 82.237127 -285.200619) (xy 82.278723 -285.170398)
			(xy 82.324535 -285.147055) (xy 82.373434 -285.131167) (xy 82.424216 -285.123124) (xy 82.475632 -285.123124)
			(xy 82.526414 -285.131167) (xy 82.575313 -285.147055) (xy 82.621125 -285.170398) (xy 82.662721 -285.200619)
			(xy 82.699077 -285.236975) (xy 82.729298 -285.278571) (xy 82.752641 -285.324383) (xy 82.768529 -285.373282)
			(xy 82.776572 -285.424064) (xy 82.777076 -285.449772) (xy 82.777071 -285.450026) (xy 83.094334 -285.450026)
			(xy 83.098294 -285.400972) (xy 83.110071 -285.353188) (xy 83.129362 -285.307912) (xy 83.155665 -285.266316)
			(xy 83.1883 -285.229479) (xy 83.226421 -285.198354) (xy 83.269042 -285.173747) (xy 83.315058 -285.156295)
			(xy 83.363277 -285.146451) (xy 83.412452 -285.14447) (xy 83.461307 -285.150402) (xy 83.508578 -285.164094)
			(xy 83.55304 -285.185192) (xy 83.593543 -285.213148) (xy 83.629036 -285.24724) (xy 83.658601 -285.286584)
			(xy 83.681472 -285.330161) (xy 83.697056 -285.376842) (xy 83.704951 -285.425419) (xy 83.705446 -285.450026)
			(xy 83.704951 -285.474633) (xy 83.697056 -285.52321) (xy 83.681472 -285.569891) (xy 83.658601 -285.613468)
			(xy 83.629036 -285.652812) (xy 83.593543 -285.686904) (xy 83.55304 -285.71486) (xy 83.508578 -285.735958)
			(xy 83.461307 -285.74965) (xy 83.412452 -285.755582) (xy 83.363277 -285.753601) (xy 83.315058 -285.743757)
			(xy 83.269042 -285.726305) (xy 83.226421 -285.701698) (xy 83.1883 -285.670573) (xy 83.155665 -285.633736)
			(xy 83.129362 -285.59214) (xy 83.110071 -285.546864) (xy 83.098294 -285.49908) (xy 83.094334 -285.450026)
			(xy 82.777071 -285.450026) (xy 82.776572 -285.47548) (xy 82.768529 -285.526262) (xy 82.752641 -285.575161)
			(xy 82.729298 -285.620973) (xy 82.699077 -285.662569) (xy 82.662721 -285.698925) (xy 82.621125 -285.729146)
			(xy 82.575313 -285.752489) (xy 82.526414 -285.768377) (xy 82.475632 -285.77642) (xy 82.424216 -285.77642)
			(xy 82.373434 -285.768377) (xy 82.324535 -285.752489) (xy 82.278723 -285.729146) (xy 82.237127 -285.698925)
			(xy 82.200771 -285.662569) (xy 82.17055 -285.620973) (xy 82.147207 -285.575161) (xy 82.131319 -285.526262)
			(xy 82.123276 -285.47548) (xy 81.826612 -285.47548) (xy 81.818569 -285.526262) (xy 81.802681 -285.575161)
			(xy 81.779338 -285.620973) (xy 81.749117 -285.662569) (xy 81.712761 -285.698925) (xy 81.671165 -285.729146)
			(xy 81.625353 -285.752489) (xy 81.576454 -285.768377) (xy 81.525672 -285.77642) (xy 81.474256 -285.77642)
			(xy 81.423474 -285.768377) (xy 81.374575 -285.752489) (xy 81.328763 -285.729146) (xy 81.287167 -285.698925)
			(xy 81.250811 -285.662569) (xy 81.22059 -285.620973) (xy 81.197247 -285.575161) (xy 81.181359 -285.526262)
			(xy 81.173316 -285.47548) (xy 80.854384 -285.47548) (xy 80.846668 -285.522956) (xy 80.831084 -285.569637)
			(xy 80.808213 -285.613214) (xy 80.778648 -285.652558) (xy 80.743155 -285.68665) (xy 80.702652 -285.714606)
			(xy 80.65819 -285.735704) (xy 80.610919 -285.749396) (xy 80.562064 -285.755328) (xy 80.512889 -285.753347)
			(xy 80.46467 -285.743503) (xy 80.418654 -285.726051) (xy 80.376033 -285.701444) (xy 80.337912 -285.670319)
			(xy 80.305277 -285.633482) (xy 80.278974 -285.591886) (xy 80.259683 -285.54661) (xy 80.247906 -285.498826)
			(xy 80.243946 -285.449772) (xy 79.905098 -285.449772) (xy 79.904603 -285.474379) (xy 79.896708 -285.522956)
			(xy 79.881124 -285.569637) (xy 79.858253 -285.613214) (xy 79.828688 -285.652558) (xy 79.793195 -285.68665)
			(xy 79.752692 -285.714606) (xy 79.70823 -285.735704) (xy 79.660959 -285.749396) (xy 79.612104 -285.755328)
			(xy 79.562929 -285.753347) (xy 79.51471 -285.743503) (xy 79.468694 -285.726051) (xy 79.426073 -285.701444)
			(xy 79.387952 -285.670319) (xy 79.355317 -285.633482) (xy 79.329014 -285.591886) (xy 79.309723 -285.54661)
			(xy 79.297946 -285.498826) (xy 79.293986 -285.449772) (xy 78.955138 -285.449772) (xy 78.954643 -285.474379)
			(xy 78.946748 -285.522956) (xy 78.931164 -285.569637) (xy 78.908293 -285.613214) (xy 78.878728 -285.652558)
			(xy 78.843235 -285.68665) (xy 78.802732 -285.714606) (xy 78.75827 -285.735704) (xy 78.710999 -285.749396)
			(xy 78.662144 -285.755328) (xy 78.612969 -285.753347) (xy 78.56475 -285.743503) (xy 78.518734 -285.726051)
			(xy 78.476113 -285.701444) (xy 78.437992 -285.670319) (xy 78.405357 -285.633482) (xy 78.379054 -285.591886)
			(xy 78.359763 -285.54661) (xy 78.347986 -285.498826) (xy 78.344026 -285.449772) (xy 78.005178 -285.449772)
			(xy 78.004683 -285.474379) (xy 77.996788 -285.522956) (xy 77.981204 -285.569637) (xy 77.958333 -285.613214)
			(xy 77.928768 -285.652558) (xy 77.893275 -285.68665) (xy 77.852772 -285.714606) (xy 77.80831 -285.735704)
			(xy 77.761039 -285.749396) (xy 77.712184 -285.755328) (xy 77.663009 -285.753347) (xy 77.61479 -285.743503)
			(xy 77.568774 -285.726051) (xy 77.526153 -285.701444) (xy 77.488032 -285.670319) (xy 77.455397 -285.633482)
			(xy 77.429094 -285.591886) (xy 77.409803 -285.54661) (xy 77.398026 -285.498826) (xy 77.394066 -285.449772)
			(xy 77.055218 -285.449772) (xy 77.054723 -285.474379) (xy 77.046828 -285.522956) (xy 77.031244 -285.569637)
			(xy 77.008373 -285.613214) (xy 76.978808 -285.652558) (xy 76.943315 -285.68665) (xy 76.902812 -285.714606)
			(xy 76.85835 -285.735704) (xy 76.811079 -285.749396) (xy 76.762224 -285.755328) (xy 76.713049 -285.753347)
			(xy 76.66483 -285.743503) (xy 76.618814 -285.726051) (xy 76.576193 -285.701444) (xy 76.538072 -285.670319)
			(xy 76.505437 -285.633482) (xy 76.479134 -285.591886) (xy 76.459843 -285.54661) (xy 76.448066 -285.498826)
			(xy 76.444106 -285.449772) (xy 76.127102 -285.449772) (xy 76.126598 -285.47548) (xy 76.118555 -285.526262)
			(xy 76.102667 -285.575161) (xy 76.079324 -285.620973) (xy 76.049103 -285.662569) (xy 76.012747 -285.698925)
			(xy 75.971151 -285.729146) (xy 75.925339 -285.752489) (xy 75.87644 -285.768377) (xy 75.825658 -285.77642)
			(xy 75.774242 -285.77642) (xy 75.72346 -285.768377) (xy 75.674561 -285.752489) (xy 75.628749 -285.729146)
			(xy 75.587153 -285.698925) (xy 75.550797 -285.662569) (xy 75.520576 -285.620973) (xy 75.497233 -285.575161)
			(xy 75.481345 -285.526262) (xy 75.473302 -285.47548) (xy 75.176384 -285.47548) (xy 75.168341 -285.526262)
			(xy 75.152453 -285.575161) (xy 75.12911 -285.620973) (xy 75.098889 -285.662569) (xy 75.062533 -285.698925)
			(xy 75.020937 -285.729146) (xy 74.975125 -285.752489) (xy 74.926226 -285.768377) (xy 74.875444 -285.77642)
			(xy 74.824028 -285.77642) (xy 74.773246 -285.768377) (xy 74.724347 -285.752489) (xy 74.678535 -285.729146)
			(xy 74.636939 -285.698925) (xy 74.600583 -285.662569) (xy 74.570362 -285.620973) (xy 74.547019 -285.575161)
			(xy 74.531131 -285.526262) (xy 74.523088 -285.47548) (xy 74.20441 -285.47548) (xy 74.196694 -285.522956)
			(xy 74.18111 -285.569637) (xy 74.158239 -285.613214) (xy 74.128674 -285.652558) (xy 74.093181 -285.68665)
			(xy 74.052678 -285.714606) (xy 74.008216 -285.735704) (xy 73.960945 -285.749396) (xy 73.91209 -285.755328)
			(xy 73.862915 -285.753347) (xy 73.814696 -285.743503) (xy 73.76868 -285.726051) (xy 73.726059 -285.701444)
			(xy 73.687938 -285.670319) (xy 73.655303 -285.633482) (xy 73.629 -285.591886) (xy 73.609709 -285.54661)
			(xy 73.597932 -285.498826) (xy 73.593972 -285.449772) (xy 14.914653 -285.449772) (xy 14.91488 -285.462218)
			(xy 14.914371 -285.490104) (xy 14.906251 -285.54528) (xy 14.890183 -285.598687) (xy 14.866511 -285.649184)
			(xy 14.835738 -285.695697) (xy 14.798521 -285.737234) (xy 14.755653 -285.772909) (xy 14.708047 -285.801963)
			(xy 14.656718 -285.823775) (xy 14.602761 -285.837881) (xy 14.547324 -285.843981) (xy 14.49159 -285.841944)
			(xy 14.436747 -285.831814) (xy 14.383963 -285.813807) (xy 14.334363 -285.788306) (xy 14.289005 -285.755855)
			(xy 14.248856 -285.717146) (xy 14.21477 -285.673003) (xy 14.187474 -285.624368) (xy 14.167551 -285.572277)
			(xy 14.155425 -285.51784) (xy 14.151354 -285.462218) (xy 12.722098 -285.462218) (xy 12.721589 -285.490104)
			(xy 12.713469 -285.54528) (xy 12.697401 -285.598687) (xy 12.673729 -285.649184) (xy 12.642956 -285.695697)
			(xy 12.605739 -285.737234) (xy 12.562871 -285.772909) (xy 12.515265 -285.801963) (xy 12.463936 -285.823775)
			(xy 12.409979 -285.837881) (xy 12.354542 -285.843981) (xy 12.298808 -285.841944) (xy 12.243965 -285.831814)
			(xy 12.191181 -285.813807) (xy 12.141581 -285.788306) (xy 12.096223 -285.755855) (xy 12.056074 -285.717146)
			(xy 12.021988 -285.673003) (xy 11.994692 -285.624368) (xy 11.974769 -285.572277) (xy 11.962643 -285.51784)
			(xy 11.958572 -285.462218) (xy 1.420114 -285.462218) (xy 1.420114 -285.924752) (xy 36.069028 -285.924752)
			(xy 36.072988 -285.875698) (xy 36.084765 -285.827914) (xy 36.104056 -285.782638) (xy 36.130359 -285.741042)
			(xy 36.162994 -285.704205) (xy 36.201115 -285.67308) (xy 36.243736 -285.648473) (xy 36.289752 -285.631021)
			(xy 36.337971 -285.621177) (xy 36.387146 -285.619196) (xy 36.436001 -285.625128) (xy 36.483272 -285.63882)
			(xy 36.527734 -285.659918) (xy 36.568237 -285.687874) (xy 36.60373 -285.721966) (xy 36.633295 -285.76131)
			(xy 36.656166 -285.804887) (xy 36.67175 -285.851568) (xy 36.679645 -285.900145) (xy 36.68014 -285.924752)
			(xy 37.018988 -285.924752) (xy 37.022948 -285.875698) (xy 37.034725 -285.827914) (xy 37.054016 -285.782638)
			(xy 37.080319 -285.741042) (xy 37.112954 -285.704205) (xy 37.151075 -285.67308) (xy 37.193696 -285.648473)
			(xy 37.239712 -285.631021) (xy 37.287931 -285.621177) (xy 37.337106 -285.619196) (xy 37.385961 -285.625128)
			(xy 37.433232 -285.63882) (xy 37.477694 -285.659918) (xy 37.518197 -285.687874) (xy 37.55369 -285.721966)
			(xy 37.583255 -285.76131) (xy 37.606126 -285.804887) (xy 37.62171 -285.851568) (xy 37.629605 -285.900145)
			(xy 37.6301 -285.924752) (xy 37.969202 -285.924752) (xy 37.973162 -285.875698) (xy 37.984939 -285.827914)
			(xy 38.00423 -285.782638) (xy 38.030533 -285.741042) (xy 38.063168 -285.704205) (xy 38.101289 -285.67308)
			(xy 38.14391 -285.648473) (xy 38.189926 -285.631021) (xy 38.238145 -285.621177) (xy 38.28732 -285.619196)
			(xy 38.336175 -285.625128) (xy 38.383446 -285.63882) (xy 38.427908 -285.659918) (xy 38.468411 -285.687874)
			(xy 38.503904 -285.721966) (xy 38.533469 -285.76131) (xy 38.55634 -285.804887) (xy 38.571924 -285.851568)
			(xy 38.579819 -285.900145) (xy 38.580314 -285.924752) (xy 38.919162 -285.924752) (xy 38.923122 -285.875698)
			(xy 38.934899 -285.827914) (xy 38.95419 -285.782638) (xy 38.980493 -285.741042) (xy 39.013128 -285.704205)
			(xy 39.051249 -285.67308) (xy 39.09387 -285.648473) (xy 39.139886 -285.631021) (xy 39.188105 -285.621177)
			(xy 39.23728 -285.619196) (xy 39.286135 -285.625128) (xy 39.333406 -285.63882) (xy 39.377868 -285.659918)
			(xy 39.418371 -285.687874) (xy 39.453864 -285.721966) (xy 39.483429 -285.76131) (xy 39.5063 -285.804887)
			(xy 39.521884 -285.851568) (xy 39.529779 -285.900145) (xy 39.530274 -285.924752) (xy 39.869122 -285.924752)
			(xy 39.873082 -285.875698) (xy 39.884859 -285.827914) (xy 39.90415 -285.782638) (xy 39.930453 -285.741042)
			(xy 39.963088 -285.704205) (xy 40.001209 -285.67308) (xy 40.04383 -285.648473) (xy 40.089846 -285.631021)
			(xy 40.138065 -285.621177) (xy 40.18724 -285.619196) (xy 40.236095 -285.625128) (xy 40.283366 -285.63882)
			(xy 40.327828 -285.659918) (xy 40.368331 -285.687874) (xy 40.403824 -285.721966) (xy 40.433389 -285.76131)
			(xy 40.45626 -285.804887) (xy 40.471844 -285.851568) (xy 40.479739 -285.900145) (xy 40.480234 -285.924752)
			(xy 40.819082 -285.924752) (xy 40.823042 -285.875698) (xy 40.834819 -285.827914) (xy 40.85411 -285.782638)
			(xy 40.880413 -285.741042) (xy 40.913048 -285.704205) (xy 40.951169 -285.67308) (xy 40.99379 -285.648473)
			(xy 41.039806 -285.631021) (xy 41.088025 -285.621177) (xy 41.1372 -285.619196) (xy 41.186055 -285.625128)
			(xy 41.233326 -285.63882) (xy 41.277788 -285.659918) (xy 41.318291 -285.687874) (xy 41.353784 -285.721966)
			(xy 41.383349 -285.76131) (xy 41.40622 -285.804887) (xy 41.421804 -285.851568) (xy 41.429699 -285.900145)
			(xy 41.430194 -285.924752) (xy 44.619176 -285.924752) (xy 44.623136 -285.875698) (xy 44.634913 -285.827914)
			(xy 44.654204 -285.782638) (xy 44.680507 -285.741042) (xy 44.713142 -285.704205) (xy 44.751263 -285.67308)
			(xy 44.793884 -285.648473) (xy 44.8399 -285.631021) (xy 44.888119 -285.621177) (xy 44.937294 -285.619196)
			(xy 44.986149 -285.625128) (xy 45.03342 -285.63882) (xy 45.077882 -285.659918) (xy 45.118385 -285.687874)
			(xy 45.153878 -285.721966) (xy 45.183443 -285.76131) (xy 45.206314 -285.804887) (xy 45.221898 -285.851568)
			(xy 45.229793 -285.900145) (xy 45.230288 -285.924752) (xy 45.569136 -285.924752) (xy 45.573096 -285.875698)
			(xy 45.584873 -285.827914) (xy 45.604164 -285.782638) (xy 45.630467 -285.741042) (xy 45.663102 -285.704205)
			(xy 45.701223 -285.67308) (xy 45.743844 -285.648473) (xy 45.78986 -285.631021) (xy 45.838079 -285.621177)
			(xy 45.887254 -285.619196) (xy 45.936109 -285.625128) (xy 45.98338 -285.63882) (xy 46.027842 -285.659918)
			(xy 46.068345 -285.687874) (xy 46.103838 -285.721966) (xy 46.133403 -285.76131) (xy 46.156274 -285.804887)
			(xy 46.171858 -285.851568) (xy 46.179753 -285.900145) (xy 46.180248 -285.924752) (xy 46.519096 -285.924752)
			(xy 46.523056 -285.875698) (xy 46.534833 -285.827914) (xy 46.554124 -285.782638) (xy 46.580427 -285.741042)
			(xy 46.613062 -285.704205) (xy 46.651183 -285.67308) (xy 46.693804 -285.648473) (xy 46.73982 -285.631021)
			(xy 46.788039 -285.621177) (xy 46.837214 -285.619196) (xy 46.886069 -285.625128) (xy 46.93334 -285.63882)
			(xy 46.977802 -285.659918) (xy 47.018305 -285.687874) (xy 47.053798 -285.721966) (xy 47.083363 -285.76131)
			(xy 47.106234 -285.804887) (xy 47.121818 -285.851568) (xy 47.129713 -285.900145) (xy 47.130208 -285.924752)
			(xy 47.469056 -285.924752) (xy 47.473016 -285.875698) (xy 47.484793 -285.827914) (xy 47.504084 -285.782638)
			(xy 47.530387 -285.741042) (xy 47.563022 -285.704205) (xy 47.601143 -285.67308) (xy 47.643764 -285.648473)
			(xy 47.68978 -285.631021) (xy 47.737999 -285.621177) (xy 47.787174 -285.619196) (xy 47.836029 -285.625128)
			(xy 47.8833 -285.63882) (xy 47.927762 -285.659918) (xy 47.968265 -285.687874) (xy 48.003758 -285.721966)
			(xy 48.033323 -285.76131) (xy 48.056194 -285.804887) (xy 48.071778 -285.851568) (xy 48.079673 -285.900145)
			(xy 48.080168 -285.924752) (xy 48.419016 -285.924752) (xy 48.422976 -285.875698) (xy 48.434753 -285.827914)
			(xy 48.454044 -285.782638) (xy 48.480347 -285.741042) (xy 48.512982 -285.704205) (xy 48.551103 -285.67308)
			(xy 48.593724 -285.648473) (xy 48.63974 -285.631021) (xy 48.687959 -285.621177) (xy 48.737134 -285.619196)
			(xy 48.785989 -285.625128) (xy 48.83326 -285.63882) (xy 48.877722 -285.659918) (xy 48.918225 -285.687874)
			(xy 48.953718 -285.721966) (xy 48.983283 -285.76131) (xy 49.006154 -285.804887) (xy 49.021738 -285.851568)
			(xy 49.029633 -285.900145) (xy 49.030128 -285.924752) (xy 49.368976 -285.924752) (xy 49.372936 -285.875698)
			(xy 49.384713 -285.827914) (xy 49.404004 -285.782638) (xy 49.430307 -285.741042) (xy 49.462942 -285.704205)
			(xy 49.501063 -285.67308) (xy 49.543684 -285.648473) (xy 49.5897 -285.631021) (xy 49.637919 -285.621177)
			(xy 49.687094 -285.619196) (xy 49.735949 -285.625128) (xy 49.78322 -285.63882) (xy 49.827682 -285.659918)
			(xy 49.868185 -285.687874) (xy 49.903678 -285.721966) (xy 49.933243 -285.76131) (xy 49.956114 -285.804887)
			(xy 49.971698 -285.851568) (xy 49.979593 -285.900145) (xy 49.980088 -285.924752) (xy 50.31919 -285.924752)
			(xy 50.32315 -285.875698) (xy 50.334927 -285.827914) (xy 50.354218 -285.782638) (xy 50.380521 -285.741042)
			(xy 50.413156 -285.704205) (xy 50.451277 -285.67308) (xy 50.493898 -285.648473) (xy 50.539914 -285.631021)
			(xy 50.588133 -285.621177) (xy 50.637308 -285.619196) (xy 50.686163 -285.625128) (xy 50.733434 -285.63882)
			(xy 50.777896 -285.659918) (xy 50.818399 -285.687874) (xy 50.853892 -285.721966) (xy 50.883457 -285.76131)
			(xy 50.906328 -285.804887) (xy 50.921912 -285.851568) (xy 50.929807 -285.900145) (xy 50.930302 -285.924752)
			(xy 51.26915 -285.924752) (xy 51.27311 -285.875698) (xy 51.284887 -285.827914) (xy 51.304178 -285.782638)
			(xy 51.330481 -285.741042) (xy 51.363116 -285.704205) (xy 51.401237 -285.67308) (xy 51.443858 -285.648473)
			(xy 51.489874 -285.631021) (xy 51.538093 -285.621177) (xy 51.587268 -285.619196) (xy 51.636123 -285.625128)
			(xy 51.683394 -285.63882) (xy 51.727856 -285.659918) (xy 51.768359 -285.687874) (xy 51.803852 -285.721966)
			(xy 51.833417 -285.76131) (xy 51.856288 -285.804887) (xy 51.871872 -285.851568) (xy 51.879767 -285.900145)
			(xy 51.880262 -285.924752) (xy 52.21911 -285.924752) (xy 52.22307 -285.875698) (xy 52.234847 -285.827914)
			(xy 52.254138 -285.782638) (xy 52.280441 -285.741042) (xy 52.313076 -285.704205) (xy 52.351197 -285.67308)
			(xy 52.393818 -285.648473) (xy 52.439834 -285.631021) (xy 52.488053 -285.621177) (xy 52.537228 -285.619196)
			(xy 52.586083 -285.625128) (xy 52.633354 -285.63882) (xy 52.677816 -285.659918) (xy 52.718319 -285.687874)
			(xy 52.753812 -285.721966) (xy 52.783377 -285.76131) (xy 52.806248 -285.804887) (xy 52.821832 -285.851568)
			(xy 52.829727 -285.900145) (xy 52.830222 -285.924752) (xy 53.16907 -285.924752) (xy 53.17303 -285.875698)
			(xy 53.184807 -285.827914) (xy 53.204098 -285.782638) (xy 53.230401 -285.741042) (xy 53.263036 -285.704205)
			(xy 53.301157 -285.67308) (xy 53.343778 -285.648473) (xy 53.389794 -285.631021) (xy 53.438013 -285.621177)
			(xy 53.487188 -285.619196) (xy 53.536043 -285.625128) (xy 53.583314 -285.63882) (xy 53.627776 -285.659918)
			(xy 53.668279 -285.687874) (xy 53.703772 -285.721966) (xy 53.733337 -285.76131) (xy 53.756208 -285.804887)
			(xy 53.771792 -285.851568) (xy 53.779687 -285.900145) (xy 53.780182 -285.924752) (xy 54.11903 -285.924752)
			(xy 54.12299 -285.875698) (xy 54.134767 -285.827914) (xy 54.154058 -285.782638) (xy 54.180361 -285.741042)
			(xy 54.212996 -285.704205) (xy 54.251117 -285.67308) (xy 54.293738 -285.648473) (xy 54.339754 -285.631021)
			(xy 54.387973 -285.621177) (xy 54.437148 -285.619196) (xy 54.486003 -285.625128) (xy 54.533274 -285.63882)
			(xy 54.577736 -285.659918) (xy 54.618239 -285.687874) (xy 54.653732 -285.721966) (xy 54.683297 -285.76131)
			(xy 54.706168 -285.804887) (xy 54.721752 -285.851568) (xy 54.729647 -285.900145) (xy 54.730142 -285.924752)
			(xy 55.06899 -285.924752) (xy 55.07295 -285.875698) (xy 55.084727 -285.827914) (xy 55.104018 -285.782638)
			(xy 55.130321 -285.741042) (xy 55.162956 -285.704205) (xy 55.201077 -285.67308) (xy 55.243698 -285.648473)
			(xy 55.289714 -285.631021) (xy 55.337933 -285.621177) (xy 55.387108 -285.619196) (xy 55.435963 -285.625128)
			(xy 55.483234 -285.63882) (xy 55.527696 -285.659918) (xy 55.568199 -285.687874) (xy 55.603692 -285.721966)
			(xy 55.633257 -285.76131) (xy 55.656128 -285.804887) (xy 55.671712 -285.851568) (xy 55.679607 -285.900145)
			(xy 55.680102 -285.924752) (xy 56.01895 -285.924752) (xy 56.02291 -285.875698) (xy 56.034687 -285.827914)
			(xy 56.053978 -285.782638) (xy 56.080281 -285.741042) (xy 56.112916 -285.704205) (xy 56.151037 -285.67308)
			(xy 56.193658 -285.648473) (xy 56.239674 -285.631021) (xy 56.287893 -285.621177) (xy 56.337068 -285.619196)
			(xy 56.385923 -285.625128) (xy 56.433194 -285.63882) (xy 56.477656 -285.659918) (xy 56.518159 -285.687874)
			(xy 56.553652 -285.721966) (xy 56.583217 -285.76131) (xy 56.606088 -285.804887) (xy 56.621672 -285.851568)
			(xy 56.629567 -285.900145) (xy 56.630062 -285.924752) (xy 56.969164 -285.924752) (xy 56.973124 -285.875698)
			(xy 56.984901 -285.827914) (xy 57.004192 -285.782638) (xy 57.030495 -285.741042) (xy 57.06313 -285.704205)
			(xy 57.101251 -285.67308) (xy 57.143872 -285.648473) (xy 57.189888 -285.631021) (xy 57.238107 -285.621177)
			(xy 57.287282 -285.619196) (xy 57.336137 -285.625128) (xy 57.383408 -285.63882) (xy 57.42787 -285.659918)
			(xy 57.468373 -285.687874) (xy 57.503866 -285.721966) (xy 57.533431 -285.76131) (xy 57.556302 -285.804887)
			(xy 57.571886 -285.851568) (xy 57.579781 -285.900145) (xy 57.580276 -285.924752) (xy 57.919124 -285.924752)
			(xy 57.923084 -285.875698) (xy 57.934861 -285.827914) (xy 57.954152 -285.782638) (xy 57.980455 -285.741042)
			(xy 58.01309 -285.704205) (xy 58.051211 -285.67308) (xy 58.093832 -285.648473) (xy 58.139848 -285.631021)
			(xy 58.188067 -285.621177) (xy 58.237242 -285.619196) (xy 58.286097 -285.625128) (xy 58.333368 -285.63882)
			(xy 58.37783 -285.659918) (xy 58.418333 -285.687874) (xy 58.453826 -285.721966) (xy 58.483391 -285.76131)
			(xy 58.506262 -285.804887) (xy 58.521846 -285.851568) (xy 58.529741 -285.900145) (xy 58.530236 -285.924752)
			(xy 59.819044 -285.924752) (xy 59.823004 -285.875698) (xy 59.834781 -285.827914) (xy 59.854072 -285.782638)
			(xy 59.880375 -285.741042) (xy 59.91301 -285.704205) (xy 59.951131 -285.67308) (xy 59.993752 -285.648473)
			(xy 60.039768 -285.631021) (xy 60.087987 -285.621177) (xy 60.137162 -285.619196) (xy 60.186017 -285.625128)
			(xy 60.233288 -285.63882) (xy 60.27775 -285.659918) (xy 60.318253 -285.687874) (xy 60.353746 -285.721966)
			(xy 60.383311 -285.76131) (xy 60.406182 -285.804887) (xy 60.421766 -285.851568) (xy 60.429661 -285.900145)
			(xy 60.430156 -285.924752) (xy 60.769004 -285.924752) (xy 60.772964 -285.875698) (xy 60.784741 -285.827914)
			(xy 60.804032 -285.782638) (xy 60.830335 -285.741042) (xy 60.86297 -285.704205) (xy 60.901091 -285.67308)
			(xy 60.943712 -285.648473) (xy 60.989728 -285.631021) (xy 61.037947 -285.621177) (xy 61.087122 -285.619196)
			(xy 61.135977 -285.625128) (xy 61.183248 -285.63882) (xy 61.22771 -285.659918) (xy 61.268213 -285.687874)
			(xy 61.303706 -285.721966) (xy 61.333271 -285.76131) (xy 61.356142 -285.804887) (xy 61.371726 -285.851568)
			(xy 61.379621 -285.900145) (xy 61.380116 -285.924752) (xy 61.718964 -285.924752) (xy 61.722924 -285.875698)
			(xy 61.734701 -285.827914) (xy 61.753992 -285.782638) (xy 61.780295 -285.741042) (xy 61.81293 -285.704205)
			(xy 61.851051 -285.67308) (xy 61.893672 -285.648473) (xy 61.939688 -285.631021) (xy 61.987907 -285.621177)
			(xy 62.037082 -285.619196) (xy 62.085937 -285.625128) (xy 62.133208 -285.63882) (xy 62.17767 -285.659918)
			(xy 62.218173 -285.687874) (xy 62.253666 -285.721966) (xy 62.283231 -285.76131) (xy 62.306102 -285.804887)
			(xy 62.321686 -285.851568) (xy 62.329581 -285.900145) (xy 62.330076 -285.924752) (xy 62.669178 -285.924752)
			(xy 62.673138 -285.875698) (xy 62.684915 -285.827914) (xy 62.704206 -285.782638) (xy 62.730509 -285.741042)
			(xy 62.763144 -285.704205) (xy 62.801265 -285.67308) (xy 62.843886 -285.648473) (xy 62.889902 -285.631021)
			(xy 62.938121 -285.621177) (xy 62.987296 -285.619196) (xy 63.036151 -285.625128) (xy 63.083422 -285.63882)
			(xy 63.127884 -285.659918) (xy 63.168387 -285.687874) (xy 63.20388 -285.721966) (xy 63.233445 -285.76131)
			(xy 63.256316 -285.804887) (xy 63.2719 -285.851568) (xy 63.279795 -285.900145) (xy 63.28029 -285.924752)
			(xy 63.619138 -285.924752) (xy 63.623098 -285.875698) (xy 63.634875 -285.827914) (xy 63.654166 -285.782638)
			(xy 63.680469 -285.741042) (xy 63.713104 -285.704205) (xy 63.751225 -285.67308) (xy 63.793846 -285.648473)
			(xy 63.839862 -285.631021) (xy 63.888081 -285.621177) (xy 63.937256 -285.619196) (xy 63.986111 -285.625128)
			(xy 64.033382 -285.63882) (xy 64.077844 -285.659918) (xy 64.118347 -285.687874) (xy 64.15384 -285.721966)
			(xy 64.183405 -285.76131) (xy 64.206276 -285.804887) (xy 64.22186 -285.851568) (xy 64.229755 -285.900145)
			(xy 64.23025 -285.924752) (xy 64.569098 -285.924752) (xy 64.573058 -285.875698) (xy 64.584835 -285.827914)
			(xy 64.604126 -285.782638) (xy 64.630429 -285.741042) (xy 64.663064 -285.704205) (xy 64.701185 -285.67308)
			(xy 64.743806 -285.648473) (xy 64.789822 -285.631021) (xy 64.838041 -285.621177) (xy 64.887216 -285.619196)
			(xy 64.936071 -285.625128) (xy 64.983342 -285.63882) (xy 65.027804 -285.659918) (xy 65.068307 -285.687874)
			(xy 65.1038 -285.721966) (xy 65.133365 -285.76131) (xy 65.156236 -285.804887) (xy 65.17182 -285.851568)
			(xy 65.179715 -285.900145) (xy 65.18021 -285.924752) (xy 65.519058 -285.924752) (xy 65.523018 -285.875698)
			(xy 65.534795 -285.827914) (xy 65.554086 -285.782638) (xy 65.580389 -285.741042) (xy 65.613024 -285.704205)
			(xy 65.651145 -285.67308) (xy 65.693766 -285.648473) (xy 65.739782 -285.631021) (xy 65.788001 -285.621177)
			(xy 65.837176 -285.619196) (xy 65.886031 -285.625128) (xy 65.933302 -285.63882) (xy 65.977764 -285.659918)
			(xy 66.018267 -285.687874) (xy 66.05376 -285.721966) (xy 66.083325 -285.76131) (xy 66.106196 -285.804887)
			(xy 66.12178 -285.851568) (xy 66.129675 -285.900145) (xy 66.13017 -285.924752) (xy 66.469018 -285.924752)
			(xy 66.472978 -285.875698) (xy 66.484755 -285.827914) (xy 66.504046 -285.782638) (xy 66.530349 -285.741042)
			(xy 66.562984 -285.704205) (xy 66.601105 -285.67308) (xy 66.643726 -285.648473) (xy 66.689742 -285.631021)
			(xy 66.737961 -285.621177) (xy 66.787136 -285.619196) (xy 66.835991 -285.625128) (xy 66.883262 -285.63882)
			(xy 66.927724 -285.659918) (xy 66.968227 -285.687874) (xy 67.00372 -285.721966) (xy 67.033285 -285.76131)
			(xy 67.056156 -285.804887) (xy 67.07174 -285.851568) (xy 67.079635 -285.900145) (xy 67.08013 -285.924752)
			(xy 67.418978 -285.924752) (xy 67.422938 -285.875698) (xy 67.434715 -285.827914) (xy 67.454006 -285.782638)
			(xy 67.480309 -285.741042) (xy 67.512944 -285.704205) (xy 67.551065 -285.67308) (xy 67.593686 -285.648473)
			(xy 67.639702 -285.631021) (xy 67.687921 -285.621177) (xy 67.737096 -285.619196) (xy 67.785951 -285.625128)
			(xy 67.833222 -285.63882) (xy 67.877684 -285.659918) (xy 67.918187 -285.687874) (xy 67.95368 -285.721966)
			(xy 67.983245 -285.76131) (xy 68.006116 -285.804887) (xy 68.0217 -285.851568) (xy 68.029595 -285.900145)
			(xy 68.03009 -285.924752) (xy 68.368938 -285.924752) (xy 68.372898 -285.875698) (xy 68.384675 -285.827914)
			(xy 68.403966 -285.782638) (xy 68.430269 -285.741042) (xy 68.462904 -285.704205) (xy 68.501025 -285.67308)
			(xy 68.543646 -285.648473) (xy 68.589662 -285.631021) (xy 68.637881 -285.621177) (xy 68.687056 -285.619196)
			(xy 68.735911 -285.625128) (xy 68.783182 -285.63882) (xy 68.827644 -285.659918) (xy 68.868147 -285.687874)
			(xy 68.90364 -285.721966) (xy 68.933205 -285.76131) (xy 68.956076 -285.804887) (xy 68.97166 -285.851568)
			(xy 68.979555 -285.900145) (xy 68.98005 -285.924752) (xy 69.319152 -285.924752) (xy 69.323112 -285.875698)
			(xy 69.334889 -285.827914) (xy 69.35418 -285.782638) (xy 69.380483 -285.741042) (xy 69.413118 -285.704205)
			(xy 69.451239 -285.67308) (xy 69.49386 -285.648473) (xy 69.539876 -285.631021) (xy 69.588095 -285.621177)
			(xy 69.63727 -285.619196) (xy 69.686125 -285.625128) (xy 69.733396 -285.63882) (xy 69.777858 -285.659918)
			(xy 69.818361 -285.687874) (xy 69.853854 -285.721966) (xy 69.883419 -285.76131) (xy 69.90629 -285.804887)
			(xy 69.921874 -285.851568) (xy 69.929769 -285.900145) (xy 69.930264 -285.924752) (xy 70.269112 -285.924752)
			(xy 70.273072 -285.875698) (xy 70.284849 -285.827914) (xy 70.30414 -285.782638) (xy 70.330443 -285.741042)
			(xy 70.363078 -285.704205) (xy 70.401199 -285.67308) (xy 70.44382 -285.648473) (xy 70.489836 -285.631021)
			(xy 70.538055 -285.621177) (xy 70.58723 -285.619196) (xy 70.636085 -285.625128) (xy 70.683356 -285.63882)
			(xy 70.727818 -285.659918) (xy 70.768321 -285.687874) (xy 70.803814 -285.721966) (xy 70.833379 -285.76131)
			(xy 70.85625 -285.804887) (xy 70.871834 -285.851568) (xy 70.879729 -285.900145) (xy 70.880224 -285.924752)
			(xy 70.879729 -285.949359) (xy 70.871834 -285.997936) (xy 70.85625 -286.044617) (xy 70.833379 -286.088194)
			(xy 70.803814 -286.127538) (xy 70.768321 -286.16163) (xy 70.727818 -286.189586) (xy 70.683356 -286.210684)
			(xy 70.636085 -286.224376) (xy 70.58723 -286.230308) (xy 70.538055 -286.228327) (xy 70.489836 -286.218483)
			(xy 70.44382 -286.201031) (xy 70.401199 -286.176424) (xy 70.363078 -286.145299) (xy 70.330443 -286.108462)
			(xy 70.30414 -286.066866) (xy 70.284849 -286.02159) (xy 70.273072 -285.973806) (xy 70.269112 -285.924752)
			(xy 69.930264 -285.924752) (xy 69.929769 -285.949359) (xy 69.921874 -285.997936) (xy 69.90629 -286.044617)
			(xy 69.883419 -286.088194) (xy 69.853854 -286.127538) (xy 69.818361 -286.16163) (xy 69.777858 -286.189586)
			(xy 69.733396 -286.210684) (xy 69.686125 -286.224376) (xy 69.63727 -286.230308) (xy 69.588095 -286.228327)
			(xy 69.539876 -286.218483) (xy 69.49386 -286.201031) (xy 69.451239 -286.176424) (xy 69.413118 -286.145299)
			(xy 69.380483 -286.108462) (xy 69.35418 -286.066866) (xy 69.334889 -286.02159) (xy 69.323112 -285.973806)
			(xy 69.319152 -285.924752) (xy 68.98005 -285.924752) (xy 68.979555 -285.949359) (xy 68.97166 -285.997936)
			(xy 68.956076 -286.044617) (xy 68.933205 -286.088194) (xy 68.90364 -286.127538) (xy 68.868147 -286.16163)
			(xy 68.827644 -286.189586) (xy 68.783182 -286.210684) (xy 68.735911 -286.224376) (xy 68.687056 -286.230308)
			(xy 68.637881 -286.228327) (xy 68.589662 -286.218483) (xy 68.543646 -286.201031) (xy 68.501025 -286.176424)
			(xy 68.462904 -286.145299) (xy 68.430269 -286.108462) (xy 68.403966 -286.066866) (xy 68.384675 -286.02159)
			(xy 68.372898 -285.973806) (xy 68.368938 -285.924752) (xy 68.03009 -285.924752) (xy 68.029595 -285.949359)
			(xy 68.0217 -285.997936) (xy 68.006116 -286.044617) (xy 67.983245 -286.088194) (xy 67.95368 -286.127538)
			(xy 67.918187 -286.16163) (xy 67.877684 -286.189586) (xy 67.833222 -286.210684) (xy 67.785951 -286.224376)
			(xy 67.737096 -286.230308) (xy 67.687921 -286.228327) (xy 67.639702 -286.218483) (xy 67.593686 -286.201031)
			(xy 67.551065 -286.176424) (xy 67.512944 -286.145299) (xy 67.480309 -286.108462) (xy 67.454006 -286.066866)
			(xy 67.434715 -286.02159) (xy 67.422938 -285.973806) (xy 67.418978 -285.924752) (xy 67.08013 -285.924752)
			(xy 67.079635 -285.949359) (xy 67.07174 -285.997936) (xy 67.056156 -286.044617) (xy 67.033285 -286.088194)
			(xy 67.00372 -286.127538) (xy 66.968227 -286.16163) (xy 66.927724 -286.189586) (xy 66.883262 -286.210684)
			(xy 66.835991 -286.224376) (xy 66.787136 -286.230308) (xy 66.737961 -286.228327) (xy 66.689742 -286.218483)
			(xy 66.643726 -286.201031) (xy 66.601105 -286.176424) (xy 66.562984 -286.145299) (xy 66.530349 -286.108462)
			(xy 66.504046 -286.066866) (xy 66.484755 -286.02159) (xy 66.472978 -285.973806) (xy 66.469018 -285.924752)
			(xy 66.13017 -285.924752) (xy 66.129675 -285.949359) (xy 66.12178 -285.997936) (xy 66.106196 -286.044617)
			(xy 66.083325 -286.088194) (xy 66.05376 -286.127538) (xy 66.018267 -286.16163) (xy 65.977764 -286.189586)
			(xy 65.933302 -286.210684) (xy 65.886031 -286.224376) (xy 65.837176 -286.230308) (xy 65.788001 -286.228327)
			(xy 65.739782 -286.218483) (xy 65.693766 -286.201031) (xy 65.651145 -286.176424) (xy 65.613024 -286.145299)
			(xy 65.580389 -286.108462) (xy 65.554086 -286.066866) (xy 65.534795 -286.02159) (xy 65.523018 -285.973806)
			(xy 65.519058 -285.924752) (xy 65.18021 -285.924752) (xy 65.179715 -285.949359) (xy 65.17182 -285.997936)
			(xy 65.156236 -286.044617) (xy 65.133365 -286.088194) (xy 65.1038 -286.127538) (xy 65.068307 -286.16163)
			(xy 65.027804 -286.189586) (xy 64.983342 -286.210684) (xy 64.936071 -286.224376) (xy 64.887216 -286.230308)
			(xy 64.838041 -286.228327) (xy 64.789822 -286.218483) (xy 64.743806 -286.201031) (xy 64.701185 -286.176424)
			(xy 64.663064 -286.145299) (xy 64.630429 -286.108462) (xy 64.604126 -286.066866) (xy 64.584835 -286.02159)
			(xy 64.573058 -285.973806) (xy 64.569098 -285.924752) (xy 64.23025 -285.924752) (xy 64.229755 -285.949359)
			(xy 64.22186 -285.997936) (xy 64.206276 -286.044617) (xy 64.183405 -286.088194) (xy 64.15384 -286.127538)
			(xy 64.118347 -286.16163) (xy 64.077844 -286.189586) (xy 64.033382 -286.210684) (xy 63.986111 -286.224376)
			(xy 63.937256 -286.230308) (xy 63.888081 -286.228327) (xy 63.839862 -286.218483) (xy 63.793846 -286.201031)
			(xy 63.751225 -286.176424) (xy 63.713104 -286.145299) (xy 63.680469 -286.108462) (xy 63.654166 -286.066866)
			(xy 63.634875 -286.02159) (xy 63.623098 -285.973806) (xy 63.619138 -285.924752) (xy 63.28029 -285.924752)
			(xy 63.279795 -285.949359) (xy 63.2719 -285.997936) (xy 63.256316 -286.044617) (xy 63.233445 -286.088194)
			(xy 63.20388 -286.127538) (xy 63.168387 -286.16163) (xy 63.127884 -286.189586) (xy 63.083422 -286.210684)
			(xy 63.036151 -286.224376) (xy 62.987296 -286.230308) (xy 62.938121 -286.228327) (xy 62.889902 -286.218483)
			(xy 62.843886 -286.201031) (xy 62.801265 -286.176424) (xy 62.763144 -286.145299) (xy 62.730509 -286.108462)
			(xy 62.704206 -286.066866) (xy 62.684915 -286.02159) (xy 62.673138 -285.973806) (xy 62.669178 -285.924752)
			(xy 62.330076 -285.924752) (xy 62.329581 -285.949359) (xy 62.321686 -285.997936) (xy 62.306102 -286.044617)
			(xy 62.283231 -286.088194) (xy 62.253666 -286.127538) (xy 62.218173 -286.16163) (xy 62.17767 -286.189586)
			(xy 62.133208 -286.210684) (xy 62.085937 -286.224376) (xy 62.037082 -286.230308) (xy 61.987907 -286.228327)
			(xy 61.939688 -286.218483) (xy 61.893672 -286.201031) (xy 61.851051 -286.176424) (xy 61.81293 -286.145299)
			(xy 61.780295 -286.108462) (xy 61.753992 -286.066866) (xy 61.734701 -286.02159) (xy 61.722924 -285.973806)
			(xy 61.718964 -285.924752) (xy 61.380116 -285.924752) (xy 61.379621 -285.949359) (xy 61.371726 -285.997936)
			(xy 61.356142 -286.044617) (xy 61.333271 -286.088194) (xy 61.303706 -286.127538) (xy 61.268213 -286.16163)
			(xy 61.22771 -286.189586) (xy 61.183248 -286.210684) (xy 61.135977 -286.224376) (xy 61.087122 -286.230308)
			(xy 61.037947 -286.228327) (xy 60.989728 -286.218483) (xy 60.943712 -286.201031) (xy 60.901091 -286.176424)
			(xy 60.86297 -286.145299) (xy 60.830335 -286.108462) (xy 60.804032 -286.066866) (xy 60.784741 -286.02159)
			(xy 60.772964 -285.973806) (xy 60.769004 -285.924752) (xy 60.430156 -285.924752) (xy 60.429661 -285.949359)
			(xy 60.421766 -285.997936) (xy 60.406182 -286.044617) (xy 60.383311 -286.088194) (xy 60.353746 -286.127538)
			(xy 60.318253 -286.16163) (xy 60.27775 -286.189586) (xy 60.233288 -286.210684) (xy 60.186017 -286.224376)
			(xy 60.137162 -286.230308) (xy 60.087987 -286.228327) (xy 60.039768 -286.218483) (xy 59.993752 -286.201031)
			(xy 59.951131 -286.176424) (xy 59.91301 -286.145299) (xy 59.880375 -286.108462) (xy 59.854072 -286.066866)
			(xy 59.834781 -286.02159) (xy 59.823004 -285.973806) (xy 59.819044 -285.924752) (xy 58.530236 -285.924752)
			(xy 58.529741 -285.949359) (xy 58.521846 -285.997936) (xy 58.506262 -286.044617) (xy 58.483391 -286.088194)
			(xy 58.453826 -286.127538) (xy 58.418333 -286.16163) (xy 58.37783 -286.189586) (xy 58.333368 -286.210684)
			(xy 58.286097 -286.224376) (xy 58.237242 -286.230308) (xy 58.188067 -286.228327) (xy 58.139848 -286.218483)
			(xy 58.093832 -286.201031) (xy 58.051211 -286.176424) (xy 58.01309 -286.145299) (xy 57.980455 -286.108462)
			(xy 57.954152 -286.066866) (xy 57.934861 -286.02159) (xy 57.923084 -285.973806) (xy 57.919124 -285.924752)
			(xy 57.580276 -285.924752) (xy 57.579781 -285.949359) (xy 57.571886 -285.997936) (xy 57.556302 -286.044617)
			(xy 57.533431 -286.088194) (xy 57.503866 -286.127538) (xy 57.468373 -286.16163) (xy 57.42787 -286.189586)
			(xy 57.383408 -286.210684) (xy 57.336137 -286.224376) (xy 57.287282 -286.230308) (xy 57.238107 -286.228327)
			(xy 57.189888 -286.218483) (xy 57.143872 -286.201031) (xy 57.101251 -286.176424) (xy 57.06313 -286.145299)
			(xy 57.030495 -286.108462) (xy 57.004192 -286.066866) (xy 56.984901 -286.02159) (xy 56.973124 -285.973806)
			(xy 56.969164 -285.924752) (xy 56.630062 -285.924752) (xy 56.629567 -285.949359) (xy 56.621672 -285.997936)
			(xy 56.606088 -286.044617) (xy 56.583217 -286.088194) (xy 56.553652 -286.127538) (xy 56.518159 -286.16163)
			(xy 56.477656 -286.189586) (xy 56.433194 -286.210684) (xy 56.385923 -286.224376) (xy 56.337068 -286.230308)
			(xy 56.287893 -286.228327) (xy 56.239674 -286.218483) (xy 56.193658 -286.201031) (xy 56.151037 -286.176424)
			(xy 56.112916 -286.145299) (xy 56.080281 -286.108462) (xy 56.053978 -286.066866) (xy 56.034687 -286.02159)
			(xy 56.02291 -285.973806) (xy 56.01895 -285.924752) (xy 55.680102 -285.924752) (xy 55.679607 -285.949359)
			(xy 55.671712 -285.997936) (xy 55.656128 -286.044617) (xy 55.633257 -286.088194) (xy 55.603692 -286.127538)
			(xy 55.568199 -286.16163) (xy 55.527696 -286.189586) (xy 55.483234 -286.210684) (xy 55.435963 -286.224376)
			(xy 55.387108 -286.230308) (xy 55.337933 -286.228327) (xy 55.289714 -286.218483) (xy 55.243698 -286.201031)
			(xy 55.201077 -286.176424) (xy 55.162956 -286.145299) (xy 55.130321 -286.108462) (xy 55.104018 -286.066866)
			(xy 55.084727 -286.02159) (xy 55.07295 -285.973806) (xy 55.06899 -285.924752) (xy 54.730142 -285.924752)
			(xy 54.729647 -285.949359) (xy 54.721752 -285.997936) (xy 54.706168 -286.044617) (xy 54.683297 -286.088194)
			(xy 54.653732 -286.127538) (xy 54.618239 -286.16163) (xy 54.577736 -286.189586) (xy 54.533274 -286.210684)
			(xy 54.486003 -286.224376) (xy 54.437148 -286.230308) (xy 54.387973 -286.228327) (xy 54.339754 -286.218483)
			(xy 54.293738 -286.201031) (xy 54.251117 -286.176424) (xy 54.212996 -286.145299) (xy 54.180361 -286.108462)
			(xy 54.154058 -286.066866) (xy 54.134767 -286.02159) (xy 54.12299 -285.973806) (xy 54.11903 -285.924752)
			(xy 53.780182 -285.924752) (xy 53.779687 -285.949359) (xy 53.771792 -285.997936) (xy 53.756208 -286.044617)
			(xy 53.733337 -286.088194) (xy 53.703772 -286.127538) (xy 53.668279 -286.16163) (xy 53.627776 -286.189586)
			(xy 53.583314 -286.210684) (xy 53.536043 -286.224376) (xy 53.487188 -286.230308) (xy 53.438013 -286.228327)
			(xy 53.389794 -286.218483) (xy 53.343778 -286.201031) (xy 53.301157 -286.176424) (xy 53.263036 -286.145299)
			(xy 53.230401 -286.108462) (xy 53.204098 -286.066866) (xy 53.184807 -286.02159) (xy 53.17303 -285.973806)
			(xy 53.16907 -285.924752) (xy 52.830222 -285.924752) (xy 52.829727 -285.949359) (xy 52.821832 -285.997936)
			(xy 52.806248 -286.044617) (xy 52.783377 -286.088194) (xy 52.753812 -286.127538) (xy 52.718319 -286.16163)
			(xy 52.677816 -286.189586) (xy 52.633354 -286.210684) (xy 52.586083 -286.224376) (xy 52.537228 -286.230308)
			(xy 52.488053 -286.228327) (xy 52.439834 -286.218483) (xy 52.393818 -286.201031) (xy 52.351197 -286.176424)
			(xy 52.313076 -286.145299) (xy 52.280441 -286.108462) (xy 52.254138 -286.066866) (xy 52.234847 -286.02159)
			(xy 52.22307 -285.973806) (xy 52.21911 -285.924752) (xy 51.880262 -285.924752) (xy 51.879767 -285.949359)
			(xy 51.871872 -285.997936) (xy 51.856288 -286.044617) (xy 51.833417 -286.088194) (xy 51.803852 -286.127538)
			(xy 51.768359 -286.16163) (xy 51.727856 -286.189586) (xy 51.683394 -286.210684) (xy 51.636123 -286.224376)
			(xy 51.587268 -286.230308) (xy 51.538093 -286.228327) (xy 51.489874 -286.218483) (xy 51.443858 -286.201031)
			(xy 51.401237 -286.176424) (xy 51.363116 -286.145299) (xy 51.330481 -286.108462) (xy 51.304178 -286.066866)
			(xy 51.284887 -286.02159) (xy 51.27311 -285.973806) (xy 51.26915 -285.924752) (xy 50.930302 -285.924752)
			(xy 50.929807 -285.949359) (xy 50.921912 -285.997936) (xy 50.906328 -286.044617) (xy 50.883457 -286.088194)
			(xy 50.853892 -286.127538) (xy 50.818399 -286.16163) (xy 50.777896 -286.189586) (xy 50.733434 -286.210684)
			(xy 50.686163 -286.224376) (xy 50.637308 -286.230308) (xy 50.588133 -286.228327) (xy 50.539914 -286.218483)
			(xy 50.493898 -286.201031) (xy 50.451277 -286.176424) (xy 50.413156 -286.145299) (xy 50.380521 -286.108462)
			(xy 50.354218 -286.066866) (xy 50.334927 -286.02159) (xy 50.32315 -285.973806) (xy 50.31919 -285.924752)
			(xy 49.980088 -285.924752) (xy 49.979593 -285.949359) (xy 49.971698 -285.997936) (xy 49.956114 -286.044617)
			(xy 49.933243 -286.088194) (xy 49.903678 -286.127538) (xy 49.868185 -286.16163) (xy 49.827682 -286.189586)
			(xy 49.78322 -286.210684) (xy 49.735949 -286.224376) (xy 49.687094 -286.230308) (xy 49.637919 -286.228327)
			(xy 49.5897 -286.218483) (xy 49.543684 -286.201031) (xy 49.501063 -286.176424) (xy 49.462942 -286.145299)
			(xy 49.430307 -286.108462) (xy 49.404004 -286.066866) (xy 49.384713 -286.02159) (xy 49.372936 -285.973806)
			(xy 49.368976 -285.924752) (xy 49.030128 -285.924752) (xy 49.029633 -285.949359) (xy 49.021738 -285.997936)
			(xy 49.006154 -286.044617) (xy 48.983283 -286.088194) (xy 48.953718 -286.127538) (xy 48.918225 -286.16163)
			(xy 48.877722 -286.189586) (xy 48.83326 -286.210684) (xy 48.785989 -286.224376) (xy 48.737134 -286.230308)
			(xy 48.687959 -286.228327) (xy 48.63974 -286.218483) (xy 48.593724 -286.201031) (xy 48.551103 -286.176424)
			(xy 48.512982 -286.145299) (xy 48.480347 -286.108462) (xy 48.454044 -286.066866) (xy 48.434753 -286.02159)
			(xy 48.422976 -285.973806) (xy 48.419016 -285.924752) (xy 48.080168 -285.924752) (xy 48.079673 -285.949359)
			(xy 48.071778 -285.997936) (xy 48.056194 -286.044617) (xy 48.033323 -286.088194) (xy 48.003758 -286.127538)
			(xy 47.968265 -286.16163) (xy 47.927762 -286.189586) (xy 47.8833 -286.210684) (xy 47.836029 -286.224376)
			(xy 47.787174 -286.230308) (xy 47.737999 -286.228327) (xy 47.68978 -286.218483) (xy 47.643764 -286.201031)
			(xy 47.601143 -286.176424) (xy 47.563022 -286.145299) (xy 47.530387 -286.108462) (xy 47.504084 -286.066866)
			(xy 47.484793 -286.02159) (xy 47.473016 -285.973806) (xy 47.469056 -285.924752) (xy 47.130208 -285.924752)
			(xy 47.129713 -285.949359) (xy 47.121818 -285.997936) (xy 47.106234 -286.044617) (xy 47.083363 -286.088194)
			(xy 47.053798 -286.127538) (xy 47.018305 -286.16163) (xy 46.977802 -286.189586) (xy 46.93334 -286.210684)
			(xy 46.886069 -286.224376) (xy 46.837214 -286.230308) (xy 46.788039 -286.228327) (xy 46.73982 -286.218483)
			(xy 46.693804 -286.201031) (xy 46.651183 -286.176424) (xy 46.613062 -286.145299) (xy 46.580427 -286.108462)
			(xy 46.554124 -286.066866) (xy 46.534833 -286.02159) (xy 46.523056 -285.973806) (xy 46.519096 -285.924752)
			(xy 46.180248 -285.924752) (xy 46.179753 -285.949359) (xy 46.171858 -285.997936) (xy 46.156274 -286.044617)
			(xy 46.133403 -286.088194) (xy 46.103838 -286.127538) (xy 46.068345 -286.16163) (xy 46.027842 -286.189586)
			(xy 45.98338 -286.210684) (xy 45.936109 -286.224376) (xy 45.887254 -286.230308) (xy 45.838079 -286.228327)
			(xy 45.78986 -286.218483) (xy 45.743844 -286.201031) (xy 45.701223 -286.176424) (xy 45.663102 -286.145299)
			(xy 45.630467 -286.108462) (xy 45.604164 -286.066866) (xy 45.584873 -286.02159) (xy 45.573096 -285.973806)
			(xy 45.569136 -285.924752) (xy 45.230288 -285.924752) (xy 45.229793 -285.949359) (xy 45.221898 -285.997936)
			(xy 45.206314 -286.044617) (xy 45.183443 -286.088194) (xy 45.153878 -286.127538) (xy 45.118385 -286.16163)
			(xy 45.077882 -286.189586) (xy 45.03342 -286.210684) (xy 44.986149 -286.224376) (xy 44.937294 -286.230308)
			(xy 44.888119 -286.228327) (xy 44.8399 -286.218483) (xy 44.793884 -286.201031) (xy 44.751263 -286.176424)
			(xy 44.713142 -286.145299) (xy 44.680507 -286.108462) (xy 44.654204 -286.066866) (xy 44.634913 -286.02159)
			(xy 44.623136 -285.973806) (xy 44.619176 -285.924752) (xy 41.430194 -285.924752) (xy 41.429699 -285.949359)
			(xy 41.421804 -285.997936) (xy 41.40622 -286.044617) (xy 41.383349 -286.088194) (xy 41.353784 -286.127538)
			(xy 41.318291 -286.16163) (xy 41.277788 -286.189586) (xy 41.233326 -286.210684) (xy 41.186055 -286.224376)
			(xy 41.1372 -286.230308) (xy 41.088025 -286.228327) (xy 41.039806 -286.218483) (xy 40.99379 -286.201031)
			(xy 40.951169 -286.176424) (xy 40.913048 -286.145299) (xy 40.880413 -286.108462) (xy 40.85411 -286.066866)
			(xy 40.834819 -286.02159) (xy 40.823042 -285.973806) (xy 40.819082 -285.924752) (xy 40.480234 -285.924752)
			(xy 40.479739 -285.949359) (xy 40.471844 -285.997936) (xy 40.45626 -286.044617) (xy 40.433389 -286.088194)
			(xy 40.403824 -286.127538) (xy 40.368331 -286.16163) (xy 40.327828 -286.189586) (xy 40.283366 -286.210684)
			(xy 40.236095 -286.224376) (xy 40.18724 -286.230308) (xy 40.138065 -286.228327) (xy 40.089846 -286.218483)
			(xy 40.04383 -286.201031) (xy 40.001209 -286.176424) (xy 39.963088 -286.145299) (xy 39.930453 -286.108462)
			(xy 39.90415 -286.066866) (xy 39.884859 -286.02159) (xy 39.873082 -285.973806) (xy 39.869122 -285.924752)
			(xy 39.530274 -285.924752) (xy 39.529779 -285.949359) (xy 39.521884 -285.997936) (xy 39.5063 -286.044617)
			(xy 39.483429 -286.088194) (xy 39.453864 -286.127538) (xy 39.418371 -286.16163) (xy 39.377868 -286.189586)
			(xy 39.333406 -286.210684) (xy 39.286135 -286.224376) (xy 39.23728 -286.230308) (xy 39.188105 -286.228327)
			(xy 39.139886 -286.218483) (xy 39.09387 -286.201031) (xy 39.051249 -286.176424) (xy 39.013128 -286.145299)
			(xy 38.980493 -286.108462) (xy 38.95419 -286.066866) (xy 38.934899 -286.02159) (xy 38.923122 -285.973806)
			(xy 38.919162 -285.924752) (xy 38.580314 -285.924752) (xy 38.579819 -285.949359) (xy 38.571924 -285.997936)
			(xy 38.55634 -286.044617) (xy 38.533469 -286.088194) (xy 38.503904 -286.127538) (xy 38.468411 -286.16163)
			(xy 38.427908 -286.189586) (xy 38.383446 -286.210684) (xy 38.336175 -286.224376) (xy 38.28732 -286.230308)
			(xy 38.238145 -286.228327) (xy 38.189926 -286.218483) (xy 38.14391 -286.201031) (xy 38.101289 -286.176424)
			(xy 38.063168 -286.145299) (xy 38.030533 -286.108462) (xy 38.00423 -286.066866) (xy 37.984939 -286.02159)
			(xy 37.973162 -285.973806) (xy 37.969202 -285.924752) (xy 37.6301 -285.924752) (xy 37.629605 -285.949359)
			(xy 37.62171 -285.997936) (xy 37.606126 -286.044617) (xy 37.583255 -286.088194) (xy 37.55369 -286.127538)
			(xy 37.518197 -286.16163) (xy 37.477694 -286.189586) (xy 37.433232 -286.210684) (xy 37.385961 -286.224376)
			(xy 37.337106 -286.230308) (xy 37.287931 -286.228327) (xy 37.239712 -286.218483) (xy 37.193696 -286.201031)
			(xy 37.151075 -286.176424) (xy 37.112954 -286.145299) (xy 37.080319 -286.108462) (xy 37.054016 -286.066866)
			(xy 37.034725 -286.02159) (xy 37.022948 -285.973806) (xy 37.018988 -285.924752) (xy 36.68014 -285.924752)
			(xy 36.679645 -285.949359) (xy 36.67175 -285.997936) (xy 36.656166 -286.044617) (xy 36.633295 -286.088194)
			(xy 36.60373 -286.127538) (xy 36.568237 -286.16163) (xy 36.527734 -286.189586) (xy 36.483272 -286.210684)
			(xy 36.436001 -286.224376) (xy 36.387146 -286.230308) (xy 36.337971 -286.228327) (xy 36.289752 -286.218483)
			(xy 36.243736 -286.201031) (xy 36.201115 -286.176424) (xy 36.162994 -286.145299) (xy 36.130359 -286.108462)
			(xy 36.104056 -286.066866) (xy 36.084765 -286.02159) (xy 36.072988 -285.973806) (xy 36.069028 -285.924752)
			(xy 1.420114 -285.924752) (xy 1.420114 -286.331914) (xy 25.811478 -286.331914) (xy 25.815549 -286.276292)
			(xy 25.827675 -286.221855) (xy 25.847598 -286.169764) (xy 25.874894 -286.121129) (xy 25.90898 -286.076986)
			(xy 25.949129 -286.038277) (xy 25.994487 -286.005826) (xy 26.044087 -285.980325) (xy 26.096871 -285.962318)
			(xy 26.151714 -285.952188) (xy 26.207448 -285.950151) (xy 26.262885 -285.956251) (xy 26.316842 -285.970357)
			(xy 26.368171 -285.992169) (xy 26.415777 -286.021223) (xy 26.458645 -286.056898) (xy 26.495862 -286.098435)
			(xy 26.526635 -286.144948) (xy 26.550307 -286.195445) (xy 26.566375 -286.248852) (xy 26.574495 -286.304028)
			(xy 26.575004 -286.331914) (xy 27.286964 -286.331914) (xy 27.291035 -286.276292) (xy 27.303161 -286.221855)
			(xy 27.323084 -286.169764) (xy 27.35038 -286.121129) (xy 27.384466 -286.076986) (xy 27.424615 -286.038277)
			(xy 27.469973 -286.005826) (xy 27.519573 -285.980325) (xy 27.572357 -285.962318) (xy 27.6272 -285.952188)
			(xy 27.682934 -285.950151) (xy 27.738371 -285.956251) (xy 27.792328 -285.970357) (xy 27.843657 -285.992169)
			(xy 27.891263 -286.021223) (xy 27.934131 -286.056898) (xy 27.971348 -286.098435) (xy 28.002121 -286.144948)
			(xy 28.025793 -286.195445) (xy 28.041861 -286.248852) (xy 28.049981 -286.304028) (xy 28.05049 -286.331914)
			(xy 28.175964 -286.331914) (xy 28.180035 -286.276292) (xy 28.192161 -286.221855) (xy 28.212084 -286.169764)
			(xy 28.23938 -286.121129) (xy 28.273466 -286.076986) (xy 28.313615 -286.038277) (xy 28.358973 -286.005826)
			(xy 28.408573 -285.980325) (xy 28.461357 -285.962318) (xy 28.5162 -285.952188) (xy 28.571934 -285.950151)
			(xy 28.627371 -285.956251) (xy 28.681328 -285.970357) (xy 28.732657 -285.992169) (xy 28.780263 -286.021223)
			(xy 28.823131 -286.056898) (xy 28.860348 -286.098435) (xy 28.891121 -286.144948) (xy 28.914793 -286.195445)
			(xy 28.930861 -286.248852) (xy 28.938981 -286.304028) (xy 28.93949 -286.331914) (xy 28.938981 -286.3598)
			(xy 28.930861 -286.414976) (xy 28.914793 -286.468383) (xy 28.891121 -286.51888) (xy 28.860348 -286.565393)
			(xy 28.823131 -286.60693) (xy 28.780263 -286.642605) (xy 28.732657 -286.671659) (xy 28.681328 -286.693471)
			(xy 28.627371 -286.707577) (xy 28.571934 -286.713677) (xy 28.5162 -286.71164) (xy 28.461357 -286.70151)
			(xy 28.408573 -286.683503) (xy 28.358973 -286.658002) (xy 28.313615 -286.625551) (xy 28.273466 -286.586842)
			(xy 28.23938 -286.542699) (xy 28.212084 -286.494064) (xy 28.192161 -286.441973) (xy 28.180035 -286.387536)
			(xy 28.175964 -286.331914) (xy 28.05049 -286.331914) (xy 28.049981 -286.3598) (xy 28.041861 -286.414976)
			(xy 28.025793 -286.468383) (xy 28.002121 -286.51888) (xy 27.971348 -286.565393) (xy 27.934131 -286.60693)
			(xy 27.891263 -286.642605) (xy 27.843657 -286.671659) (xy 27.792328 -286.693471) (xy 27.738371 -286.707577)
			(xy 27.682934 -286.713677) (xy 27.6272 -286.71164) (xy 27.572357 -286.70151) (xy 27.519573 -286.683503)
			(xy 27.469973 -286.658002) (xy 27.424615 -286.625551) (xy 27.384466 -286.586842) (xy 27.35038 -286.542699)
			(xy 27.323084 -286.494064) (xy 27.303161 -286.441973) (xy 27.291035 -286.387536) (xy 27.286964 -286.331914)
			(xy 26.575004 -286.331914) (xy 26.574495 -286.3598) (xy 26.566375 -286.414976) (xy 26.550307 -286.468383)
			(xy 26.526635 -286.51888) (xy 26.495862 -286.565393) (xy 26.458645 -286.60693) (xy 26.415777 -286.642605)
			(xy 26.368171 -286.671659) (xy 26.316842 -286.693471) (xy 26.262885 -286.707577) (xy 26.207448 -286.713677)
			(xy 26.151714 -286.71164) (xy 26.096871 -286.70151) (xy 26.044087 -286.683503) (xy 25.994487 -286.658002)
			(xy 25.949129 -286.625551) (xy 25.90898 -286.586842) (xy 25.874894 -286.542699) (xy 25.847598 -286.494064)
			(xy 25.827675 -286.441973) (xy 25.815549 -286.387536) (xy 25.811478 -286.331914) (xy 1.420114 -286.331914)
			(xy 1.420114 -287.131831) (xy 3.23899 -287.131831) (xy 3.23899 -287.077329) (xy 3.246746 -287.023382)
			(xy 3.262101 -286.971087) (xy 3.284742 -286.921511) (xy 3.314208 -286.87566) (xy 3.349899 -286.834471)
			(xy 3.391089 -286.798779) (xy 3.436939 -286.769313) (xy 3.486516 -286.746672) (xy 3.53881 -286.731317)
			(xy 3.592757 -286.72356) (xy 3.620008 -286.723074) (xy 3.647379 -286.723517) (xy 3.70156 -286.731338)
			(xy 3.754064 -286.746831) (xy 3.803811 -286.769679) (xy 3.849776 -286.799409) (xy 3.870706 -286.817054)
			(xy 3.87096 -286.817308) (xy 3.878053 -286.822885) (xy 3.894965 -286.829137) (xy 3.90398 -286.8295)
			(xy 3.971036 -286.8295) (xy 3.980055 -286.82916) (xy 3.996971 -286.822901) (xy 4.004056 -286.817308)
			(xy 4.004056 -286.817054) (xy 4.00431 -286.817054) (xy 4.025234 -286.799405) (xy 4.071208 -286.769693)
			(xy 4.120958 -286.746858) (xy 4.173461 -286.731369) (xy 4.227638 -286.723545) (xy 4.255008 -286.723074)
			(xy 4.282261 -286.723533) (xy 4.336213 -286.73129) (xy 4.388511 -286.746646) (xy 4.438091 -286.769288)
			(xy 4.483945 -286.798757) (xy 4.525138 -286.83445) (xy 4.560832 -286.875643) (xy 4.590301 -286.921497)
			(xy 4.612943 -286.971077) (xy 4.6283 -287.023376) (xy 4.636057 -287.077327) (xy 4.636057 -287.131831)
			(xy 5.20038 -287.131831) (xy 5.20038 -287.077329) (xy 5.208136 -287.023382) (xy 5.223491 -286.971088)
			(xy 5.246132 -286.921511) (xy 5.275597 -286.875661) (xy 5.311288 -286.834471) (xy 5.352478 -286.79878)
			(xy 5.398328 -286.769314) (xy 5.447904 -286.746672) (xy 5.500198 -286.731317) (xy 5.554145 -286.72356)
			(xy 5.581396 -286.723074) (xy 5.61152 -286.72364) (xy 5.671017 -286.733121) (xy 5.728285 -286.751833)
			(xy 5.781902 -286.77931) (xy 5.830536 -286.81487) (xy 5.85216 -286.83585) (xy 5.859586 -286.842658)
			(xy 5.878165 -286.850398) (xy 5.888228 -286.850836) (xy 5.960364 -286.850836) (xy 5.970433 -286.850409)
			(xy 5.989032 -286.842691) (xy 5.996432 -286.83585) (xy 6.018072 -286.814886) (xy 6.066696 -286.779314)
			(xy 6.120308 -286.75183) (xy 6.177575 -286.733118) (xy 6.237073 -286.723644) (xy 6.267196 -286.723074)
			(xy 6.294449 -286.723533) (xy 6.348401 -286.73129) (xy 6.400699 -286.746645) (xy 6.45028 -286.769288)
			(xy 6.496134 -286.798756) (xy 6.537328 -286.83445) (xy 6.573022 -286.875643) (xy 6.60249 -286.921496)
			(xy 6.625133 -286.971077) (xy 6.64049 -287.023375) (xy 6.648247 -287.077327) (xy 6.648247 -287.093914)
			(xy 31.338012 -287.093914) (xy 31.338555 -287.064532) (xy 31.347584 -287.006465) (xy 31.365415 -286.95047)
			(xy 31.391626 -286.897875) (xy 31.425597 -286.849924) (xy 31.466521 -286.807752) (xy 31.48965 -286.789622)
			(xy 31.498575 -286.782143) (xy 31.509034 -286.761368) (xy 31.509716 -286.749744) (xy 31.510986 -286.657796)
			(xy 31.50108 -286.636714) (xy 31.491936 -286.629348) (xy 31.470088 -286.611142) (xy 31.431546 -286.569324)
			(xy 31.399638 -286.522249) (xy 31.375071 -286.470959) (xy 31.358388 -286.416591) (xy 31.34996 -286.360349)
			(xy 31.349442 -286.331914) (xy 31.349928 -286.304663) (xy 31.357684 -286.250715) (xy 31.373039 -286.19842)
			(xy 31.395681 -286.148843) (xy 31.425147 -286.102993) (xy 31.460838 -286.061802) (xy 31.502029 -286.026111)
			(xy 31.547879 -285.996645) (xy 31.597456 -285.974003) (xy 31.649751 -285.958648) (xy 31.703699 -285.950892)
			(xy 31.758201 -285.950892) (xy 31.812149 -285.958648) (xy 31.864444 -285.974003) (xy 31.914021 -285.996645)
			(xy 31.959871 -286.026111) (xy 32.001062 -286.061802) (xy 32.036753 -286.102993) (xy 32.066219 -286.148843)
			(xy 32.088861 -286.19842) (xy 32.104216 -286.250715) (xy 32.111972 -286.304663) (xy 32.112458 -286.331914)
			(xy 32.111907 -286.361296) (xy 32.105929 -286.399732) (xy 73.593972 -286.399732) (xy 73.597932 -286.350678)
			(xy 73.609709 -286.302894) (xy 73.629 -286.257618) (xy 73.655303 -286.216022) (xy 73.687938 -286.179185)
			(xy 73.726059 -286.14806) (xy 73.76868 -286.123453) (xy 73.814696 -286.106001) (xy 73.862915 -286.096157)
			(xy 73.91209 -286.094176) (xy 73.960945 -286.100108) (xy 74.008216 -286.1138) (xy 74.052678 -286.134898)
			(xy 74.093181 -286.162854) (xy 74.128674 -286.196946) (xy 74.158239 -286.23629) (xy 74.18111 -286.279867)
			(xy 74.196694 -286.326548) (xy 74.204589 -286.375125) (xy 74.205084 -286.399732) (xy 74.544186 -286.399732)
			(xy 74.548146 -286.350678) (xy 74.559923 -286.302894) (xy 74.579214 -286.257618) (xy 74.605517 -286.216022)
			(xy 74.638152 -286.179185) (xy 74.676273 -286.14806) (xy 74.718894 -286.123453) (xy 74.76491 -286.106001)
			(xy 74.813129 -286.096157) (xy 74.862304 -286.094176) (xy 74.911159 -286.100108) (xy 74.95843 -286.1138)
			(xy 75.002892 -286.134898) (xy 75.043395 -286.162854) (xy 75.078888 -286.196946) (xy 75.108453 -286.23629)
			(xy 75.131324 -286.279867) (xy 75.146908 -286.326548) (xy 75.154803 -286.375125) (xy 75.155298 -286.399732)
			(xy 75.494146 -286.399732) (xy 75.498106 -286.350678) (xy 75.509883 -286.302894) (xy 75.529174 -286.257618)
			(xy 75.555477 -286.216022) (xy 75.588112 -286.179185) (xy 75.626233 -286.14806) (xy 75.668854 -286.123453)
			(xy 75.71487 -286.106001) (xy 75.763089 -286.096157) (xy 75.812264 -286.094176) (xy 75.861119 -286.100108)
			(xy 75.90839 -286.1138) (xy 75.952852 -286.134898) (xy 75.993355 -286.162854) (xy 76.028848 -286.196946)
			(xy 76.058413 -286.23629) (xy 76.081284 -286.279867) (xy 76.096868 -286.326548) (xy 76.104763 -286.375125)
			(xy 76.105258 -286.399732) (xy 76.104763 -286.424339) (xy 76.104543 -286.425694) (xy 76.423262 -286.425694)
			(xy 76.423262 -286.374278) (xy 76.431305 -286.323496) (xy 76.447193 -286.274597) (xy 76.470536 -286.228785)
			(xy 76.500757 -286.187189) (xy 76.537113 -286.150833) (xy 76.578709 -286.120612) (xy 76.624521 -286.097269)
			(xy 76.67342 -286.081381) (xy 76.724202 -286.073338) (xy 76.775618 -286.073338) (xy 76.8264 -286.081381)
			(xy 76.875299 -286.097269) (xy 76.921111 -286.120612) (xy 76.962707 -286.150833) (xy 76.999063 -286.187189)
			(xy 77.029284 -286.228785) (xy 77.052627 -286.274597) (xy 77.068515 -286.323496) (xy 77.076558 -286.374278)
			(xy 77.077062 -286.399986) (xy 77.076558 -286.425694) (xy 77.373222 -286.425694) (xy 77.373222 -286.374278)
			(xy 77.381265 -286.323496) (xy 77.397153 -286.274597) (xy 77.420496 -286.228785) (xy 77.450717 -286.187189)
			(xy 77.487073 -286.150833) (xy 77.528669 -286.120612) (xy 77.574481 -286.097269) (xy 77.62338 -286.081381)
			(xy 77.674162 -286.073338) (xy 77.725578 -286.073338) (xy 77.77636 -286.081381) (xy 77.825259 -286.097269)
			(xy 77.871071 -286.120612) (xy 77.912667 -286.150833) (xy 77.949023 -286.187189) (xy 77.979244 -286.228785)
			(xy 78.002587 -286.274597) (xy 78.018475 -286.323496) (xy 78.026518 -286.374278) (xy 78.027017 -286.399732)
			(xy 78.344026 -286.399732) (xy 78.347986 -286.350678) (xy 78.359763 -286.302894) (xy 78.379054 -286.257618)
			(xy 78.405357 -286.216022) (xy 78.437992 -286.179185) (xy 78.476113 -286.14806) (xy 78.518734 -286.123453)
			(xy 78.56475 -286.106001) (xy 78.612969 -286.096157) (xy 78.662144 -286.094176) (xy 78.710999 -286.100108)
			(xy 78.75827 -286.1138) (xy 78.802732 -286.134898) (xy 78.843235 -286.162854) (xy 78.878728 -286.196946)
			(xy 78.908293 -286.23629) (xy 78.931164 -286.279867) (xy 78.946748 -286.326548) (xy 78.954643 -286.375125)
			(xy 78.955138 -286.399732) (xy 78.954643 -286.424339) (xy 78.954464 -286.42544) (xy 79.273142 -286.42544)
			(xy 79.273142 -286.374024) (xy 79.281185 -286.323242) (xy 79.297073 -286.274343) (xy 79.320416 -286.228531)
			(xy 79.350637 -286.186935) (xy 79.386993 -286.150579) (xy 79.428589 -286.120358) (xy 79.474401 -286.097015)
			(xy 79.5233 -286.081127) (xy 79.574082 -286.073084) (xy 79.625498 -286.073084) (xy 79.67628 -286.081127)
			(xy 79.725179 -286.097015) (xy 79.770991 -286.120358) (xy 79.812587 -286.150579) (xy 79.848943 -286.186935)
			(xy 79.879164 -286.228531) (xy 79.902507 -286.274343) (xy 79.918395 -286.323242) (xy 79.926438 -286.374024)
			(xy 79.926942 -286.399732) (xy 79.926438 -286.42544) (xy 80.223102 -286.42544) (xy 80.223102 -286.374024)
			(xy 80.231145 -286.323242) (xy 80.247033 -286.274343) (xy 80.270376 -286.228531) (xy 80.300597 -286.186935)
			(xy 80.336953 -286.150579) (xy 80.378549 -286.120358) (xy 80.424361 -286.097015) (xy 80.47326 -286.081127)
			(xy 80.524042 -286.073084) (xy 80.575458 -286.073084) (xy 80.62624 -286.081127) (xy 80.675139 -286.097015)
			(xy 80.720951 -286.120358) (xy 80.762547 -286.150579) (xy 80.798903 -286.186935) (xy 80.829124 -286.228531)
			(xy 80.852467 -286.274343) (xy 80.868355 -286.323242) (xy 80.876398 -286.374024) (xy 80.876902 -286.399732)
			(xy 81.19416 -286.399732) (xy 81.19812 -286.350678) (xy 81.209897 -286.302894) (xy 81.229188 -286.257618)
			(xy 81.255491 -286.216022) (xy 81.288126 -286.179185) (xy 81.326247 -286.14806) (xy 81.368868 -286.123453)
			(xy 81.414884 -286.106001) (xy 81.463103 -286.096157) (xy 81.512278 -286.094176) (xy 81.561133 -286.100108)
			(xy 81.608404 -286.1138) (xy 81.652866 -286.134898) (xy 81.693369 -286.162854) (xy 81.728862 -286.196946)
			(xy 81.758427 -286.23629) (xy 81.781298 -286.279867) (xy 81.796882 -286.326548) (xy 81.804777 -286.375125)
			(xy 81.805272 -286.399732) (xy 82.14412 -286.399732) (xy 82.14808 -286.350678) (xy 82.159857 -286.302894)
			(xy 82.179148 -286.257618) (xy 82.205451 -286.216022) (xy 82.238086 -286.179185) (xy 82.276207 -286.14806)
			(xy 82.318828 -286.123453) (xy 82.364844 -286.106001) (xy 82.413063 -286.096157) (xy 82.462238 -286.094176)
			(xy 82.511093 -286.100108) (xy 82.558364 -286.1138) (xy 82.602826 -286.134898) (xy 82.643329 -286.162854)
			(xy 82.678822 -286.196946) (xy 82.708387 -286.23629) (xy 82.731258 -286.279867) (xy 82.746842 -286.326548)
			(xy 82.754737 -286.375125) (xy 82.755232 -286.399732) (xy 82.754737 -286.424339) (xy 82.746842 -286.472916)
			(xy 82.731258 -286.519597) (xy 82.708387 -286.563174) (xy 82.678822 -286.602518) (xy 82.643329 -286.63661)
			(xy 82.602826 -286.664566) (xy 82.558364 -286.685664) (xy 82.511093 -286.699356) (xy 82.462238 -286.705288)
			(xy 82.413063 -286.703307) (xy 82.364844 -286.693463) (xy 82.318828 -286.676011) (xy 82.276207 -286.651404)
			(xy 82.238086 -286.620279) (xy 82.205451 -286.583442) (xy 82.179148 -286.541846) (xy 82.159857 -286.49657)
			(xy 82.14808 -286.448786) (xy 82.14412 -286.399732) (xy 81.805272 -286.399732) (xy 81.804777 -286.424339)
			(xy 81.796882 -286.472916) (xy 81.781298 -286.519597) (xy 81.758427 -286.563174) (xy 81.728862 -286.602518)
			(xy 81.693369 -286.63661) (xy 81.652866 -286.664566) (xy 81.608404 -286.685664) (xy 81.561133 -286.699356)
			(xy 81.512278 -286.705288) (xy 81.463103 -286.703307) (xy 81.414884 -286.693463) (xy 81.368868 -286.676011)
			(xy 81.326247 -286.651404) (xy 81.288126 -286.620279) (xy 81.255491 -286.583442) (xy 81.229188 -286.541846)
			(xy 81.209897 -286.49657) (xy 81.19812 -286.448786) (xy 81.19416 -286.399732) (xy 80.876902 -286.399732)
			(xy 80.876398 -286.42544) (xy 80.868355 -286.476222) (xy 80.852467 -286.525121) (xy 80.829124 -286.570933)
			(xy 80.798903 -286.612529) (xy 80.762547 -286.648885) (xy 80.720951 -286.679106) (xy 80.675139 -286.702449)
			(xy 80.62624 -286.718337) (xy 80.575458 -286.72638) (xy 80.524042 -286.72638) (xy 80.47326 -286.718337)
			(xy 80.424361 -286.702449) (xy 80.378549 -286.679106) (xy 80.336953 -286.648885) (xy 80.300597 -286.612529)
			(xy 80.270376 -286.570933) (xy 80.247033 -286.525121) (xy 80.231145 -286.476222) (xy 80.223102 -286.42544)
			(xy 79.926438 -286.42544) (xy 79.918395 -286.476222) (xy 79.902507 -286.525121) (xy 79.879164 -286.570933)
			(xy 79.848943 -286.612529) (xy 79.812587 -286.648885) (xy 79.770991 -286.679106) (xy 79.725179 -286.702449)
			(xy 79.67628 -286.718337) (xy 79.625498 -286.72638) (xy 79.574082 -286.72638) (xy 79.5233 -286.718337)
			(xy 79.474401 -286.702449) (xy 79.428589 -286.679106) (xy 79.386993 -286.648885) (xy 79.350637 -286.612529)
			(xy 79.320416 -286.570933) (xy 79.297073 -286.525121) (xy 79.281185 -286.476222) (xy 79.273142 -286.42544)
			(xy 78.954464 -286.42544) (xy 78.946748 -286.472916) (xy 78.931164 -286.519597) (xy 78.908293 -286.563174)
			(xy 78.878728 -286.602518) (xy 78.843235 -286.63661) (xy 78.802732 -286.664566) (xy 78.75827 -286.685664)
			(xy 78.710999 -286.699356) (xy 78.662144 -286.705288) (xy 78.612969 -286.703307) (xy 78.56475 -286.693463)
			(xy 78.518734 -286.676011) (xy 78.476113 -286.651404) (xy 78.437992 -286.620279) (xy 78.405357 -286.583442)
			(xy 78.379054 -286.541846) (xy 78.359763 -286.49657) (xy 78.347986 -286.448786) (xy 78.344026 -286.399732)
			(xy 78.027017 -286.399732) (xy 78.027022 -286.399986) (xy 78.026518 -286.425694) (xy 78.018475 -286.476476)
			(xy 78.002587 -286.525375) (xy 77.979244 -286.571187) (xy 77.949023 -286.612783) (xy 77.912667 -286.649139)
			(xy 77.871071 -286.67936) (xy 77.825259 -286.702703) (xy 77.77636 -286.718591) (xy 77.725578 -286.726634)
			(xy 77.674162 -286.726634) (xy 77.62338 -286.718591) (xy 77.574481 -286.702703) (xy 77.528669 -286.67936)
			(xy 77.487073 -286.649139) (xy 77.450717 -286.612783) (xy 77.420496 -286.571187) (xy 77.397153 -286.525375)
			(xy 77.381265 -286.476476) (xy 77.373222 -286.425694) (xy 77.076558 -286.425694) (xy 77.068515 -286.476476)
			(xy 77.052627 -286.525375) (xy 77.029284 -286.571187) (xy 76.999063 -286.612783) (xy 76.962707 -286.649139)
			(xy 76.921111 -286.67936) (xy 76.875299 -286.702703) (xy 76.8264 -286.718591) (xy 76.775618 -286.726634)
			(xy 76.724202 -286.726634) (xy 76.67342 -286.718591) (xy 76.624521 -286.702703) (xy 76.578709 -286.67936)
			(xy 76.537113 -286.649139) (xy 76.500757 -286.612783) (xy 76.470536 -286.571187) (xy 76.447193 -286.525375)
			(xy 76.431305 -286.476476) (xy 76.423262 -286.425694) (xy 76.104543 -286.425694) (xy 76.096868 -286.472916)
			(xy 76.081284 -286.519597) (xy 76.058413 -286.563174) (xy 76.028848 -286.602518) (xy 75.993355 -286.63661)
			(xy 75.952852 -286.664566) (xy 75.90839 -286.685664) (xy 75.861119 -286.699356) (xy 75.812264 -286.705288)
			(xy 75.763089 -286.703307) (xy 75.71487 -286.693463) (xy 75.668854 -286.676011) (xy 75.626233 -286.651404)
			(xy 75.588112 -286.620279) (xy 75.555477 -286.583442) (xy 75.529174 -286.541846) (xy 75.509883 -286.49657)
			(xy 75.498106 -286.448786) (xy 75.494146 -286.399732) (xy 75.155298 -286.399732) (xy 75.154803 -286.424339)
			(xy 75.146908 -286.472916) (xy 75.131324 -286.519597) (xy 75.108453 -286.563174) (xy 75.078888 -286.602518)
			(xy 75.043395 -286.63661) (xy 75.002892 -286.664566) (xy 74.95843 -286.685664) (xy 74.911159 -286.699356)
			(xy 74.862304 -286.705288) (xy 74.813129 -286.703307) (xy 74.76491 -286.693463) (xy 74.718894 -286.676011)
			(xy 74.676273 -286.651404) (xy 74.638152 -286.620279) (xy 74.605517 -286.583442) (xy 74.579214 -286.541846)
			(xy 74.559923 -286.49657) (xy 74.548146 -286.448786) (xy 74.544186 -286.399732) (xy 74.205084 -286.399732)
			(xy 74.204589 -286.424339) (xy 74.196694 -286.472916) (xy 74.18111 -286.519597) (xy 74.158239 -286.563174)
			(xy 74.128674 -286.602518) (xy 74.093181 -286.63661) (xy 74.052678 -286.664566) (xy 74.008216 -286.685664)
			(xy 73.960945 -286.699356) (xy 73.91209 -286.705288) (xy 73.862915 -286.703307) (xy 73.814696 -286.693463)
			(xy 73.76868 -286.676011) (xy 73.726059 -286.651404) (xy 73.687938 -286.620279) (xy 73.655303 -286.583442)
			(xy 73.629 -286.541846) (xy 73.609709 -286.49657) (xy 73.597932 -286.448786) (xy 73.593972 -286.399732)
			(xy 32.105929 -286.399732) (xy 32.102876 -286.419361) (xy 32.085044 -286.475354) (xy 32.058835 -286.527949)
			(xy 32.024867 -286.5759) (xy 31.983946 -286.618074) (xy 31.96082 -286.636206) (xy 31.951877 -286.643667)
			(xy 31.94143 -286.664456) (xy 31.940754 -286.676084) (xy 31.939484 -286.768032) (xy 31.94939 -286.789114)
			(xy 31.958534 -286.79648) (xy 31.980362 -286.814709) (xy 32.018902 -286.856524) (xy 32.05081 -286.903595)
			(xy 32.07538 -286.95488) (xy 32.092068 -287.009243) (xy 32.100505 -287.065481) (xy 32.101028 -287.093914)
			(xy 32.734502 -287.093914) (xy 32.738573 -287.038292) (xy 32.750699 -286.983855) (xy 32.770622 -286.931764)
			(xy 32.797918 -286.883129) (xy 32.832004 -286.838986) (xy 32.872153 -286.800277) (xy 32.917511 -286.767826)
			(xy 32.967111 -286.742325) (xy 33.019895 -286.724318) (xy 33.074738 -286.714188) (xy 33.130472 -286.712151)
			(xy 33.185909 -286.718251) (xy 33.239866 -286.732357) (xy 33.291195 -286.754169) (xy 33.338801 -286.783223)
			(xy 33.381669 -286.818898) (xy 33.418886 -286.860435) (xy 33.449659 -286.906948) (xy 33.473331 -286.957445)
			(xy 33.489399 -287.010852) (xy 33.497519 -287.066028) (xy 33.498028 -287.093914) (xy 33.620962 -287.093914)
			(xy 33.625033 -287.038292) (xy 33.637159 -286.983855) (xy 33.657082 -286.931764) (xy 33.684378 -286.883129)
			(xy 33.718464 -286.838986) (xy 33.758613 -286.800277) (xy 33.803971 -286.767826) (xy 33.853571 -286.742325)
			(xy 33.906355 -286.724318) (xy 33.961198 -286.714188) (xy 34.016932 -286.712151) (xy 34.072369 -286.718251)
			(xy 34.126326 -286.732357) (xy 34.177655 -286.754169) (xy 34.225261 -286.783223) (xy 34.268129 -286.818898)
			(xy 34.305346 -286.860435) (xy 34.31496 -286.874966) (xy 36.069028 -286.874966) (xy 36.072988 -286.825912)
			(xy 36.084765 -286.778128) (xy 36.104056 -286.732852) (xy 36.130359 -286.691256) (xy 36.162994 -286.654419)
			(xy 36.201115 -286.623294) (xy 36.243736 -286.598687) (xy 36.289752 -286.581235) (xy 36.337971 -286.571391)
			(xy 36.387146 -286.56941) (xy 36.436001 -286.575342) (xy 36.483272 -286.589034) (xy 36.527734 -286.610132)
			(xy 36.568237 -286.638088) (xy 36.60373 -286.67218) (xy 36.633295 -286.711524) (xy 36.656166 -286.755101)
			(xy 36.67175 -286.801782) (xy 36.679645 -286.850359) (xy 36.68014 -286.874966) (xy 37.018988 -286.874966)
			(xy 37.022948 -286.825912) (xy 37.034725 -286.778128) (xy 37.054016 -286.732852) (xy 37.080319 -286.691256)
			(xy 37.112954 -286.654419) (xy 37.151075 -286.623294) (xy 37.193696 -286.598687) (xy 37.239712 -286.581235)
			(xy 37.287931 -286.571391) (xy 37.337106 -286.56941) (xy 37.385961 -286.575342) (xy 37.433232 -286.589034)
			(xy 37.477694 -286.610132) (xy 37.518197 -286.638088) (xy 37.55369 -286.67218) (xy 37.583255 -286.711524)
			(xy 37.606126 -286.755101) (xy 37.62171 -286.801782) (xy 37.629605 -286.850359) (xy 37.6301 -286.874966)
			(xy 37.969202 -286.874966) (xy 37.973162 -286.825912) (xy 37.984939 -286.778128) (xy 38.00423 -286.732852)
			(xy 38.030533 -286.691256) (xy 38.063168 -286.654419) (xy 38.101289 -286.623294) (xy 38.14391 -286.598687)
			(xy 38.189926 -286.581235) (xy 38.238145 -286.571391) (xy 38.28732 -286.56941) (xy 38.336175 -286.575342)
			(xy 38.383446 -286.589034) (xy 38.427908 -286.610132) (xy 38.468411 -286.638088) (xy 38.503904 -286.67218)
			(xy 38.533469 -286.711524) (xy 38.55634 -286.755101) (xy 38.571924 -286.801782) (xy 38.579819 -286.850359)
			(xy 38.580314 -286.874966) (xy 38.919162 -286.874966) (xy 38.923122 -286.825912) (xy 38.934899 -286.778128)
			(xy 38.95419 -286.732852) (xy 38.980493 -286.691256) (xy 39.013128 -286.654419) (xy 39.051249 -286.623294)
			(xy 39.09387 -286.598687) (xy 39.139886 -286.581235) (xy 39.188105 -286.571391) (xy 39.23728 -286.56941)
			(xy 39.286135 -286.575342) (xy 39.333406 -286.589034) (xy 39.377868 -286.610132) (xy 39.418371 -286.638088)
			(xy 39.453864 -286.67218) (xy 39.483429 -286.711524) (xy 39.5063 -286.755101) (xy 39.521884 -286.801782)
			(xy 39.529779 -286.850359) (xy 39.530274 -286.874966) (xy 39.869122 -286.874966) (xy 39.873082 -286.825912)
			(xy 39.884859 -286.778128) (xy 39.90415 -286.732852) (xy 39.930453 -286.691256) (xy 39.963088 -286.654419)
			(xy 40.001209 -286.623294) (xy 40.04383 -286.598687) (xy 40.089846 -286.581235) (xy 40.138065 -286.571391)
			(xy 40.18724 -286.56941) (xy 40.236095 -286.575342) (xy 40.283366 -286.589034) (xy 40.327828 -286.610132)
			(xy 40.368331 -286.638088) (xy 40.403824 -286.67218) (xy 40.433389 -286.711524) (xy 40.45626 -286.755101)
			(xy 40.471844 -286.801782) (xy 40.479739 -286.850359) (xy 40.480234 -286.874966) (xy 40.819082 -286.874966)
			(xy 40.823042 -286.825912) (xy 40.834819 -286.778128) (xy 40.85411 -286.732852) (xy 40.880413 -286.691256)
			(xy 40.913048 -286.654419) (xy 40.951169 -286.623294) (xy 40.99379 -286.598687) (xy 41.039806 -286.581235)
			(xy 41.088025 -286.571391) (xy 41.1372 -286.56941) (xy 41.186055 -286.575342) (xy 41.233326 -286.589034)
			(xy 41.277788 -286.610132) (xy 41.318291 -286.638088) (xy 41.353784 -286.67218) (xy 41.383349 -286.711524)
			(xy 41.40622 -286.755101) (xy 41.421804 -286.801782) (xy 41.429699 -286.850359) (xy 41.430194 -286.874966)
			(xy 41.769042 -286.874966) (xy 41.773002 -286.825912) (xy 41.784779 -286.778128) (xy 41.80407 -286.732852)
			(xy 41.830373 -286.691256) (xy 41.863008 -286.654419) (xy 41.901129 -286.623294) (xy 41.94375 -286.598687)
			(xy 41.989766 -286.581235) (xy 42.037985 -286.571391) (xy 42.08716 -286.56941) (xy 42.136015 -286.575342)
			(xy 42.183286 -286.589034) (xy 42.227748 -286.610132) (xy 42.268251 -286.638088) (xy 42.303744 -286.67218)
			(xy 42.333309 -286.711524) (xy 42.35618 -286.755101) (xy 42.371764 -286.801782) (xy 42.379659 -286.850359)
			(xy 42.380149 -286.874712) (xy 42.719002 -286.874712) (xy 42.722962 -286.825658) (xy 42.734739 -286.777874)
			(xy 42.75403 -286.732598) (xy 42.780333 -286.691002) (xy 42.812968 -286.654165) (xy 42.851089 -286.62304)
			(xy 42.89371 -286.598433) (xy 42.939726 -286.580981) (xy 42.987945 -286.571137) (xy 43.03712 -286.569156)
			(xy 43.085975 -286.575088) (xy 43.133246 -286.58878) (xy 43.177708 -286.609878) (xy 43.218211 -286.637834)
			(xy 43.253704 -286.671926) (xy 43.283269 -286.71127) (xy 43.30614 -286.754847) (xy 43.321724 -286.801528)
			(xy 43.329619 -286.850105) (xy 43.330114 -286.874712) (xy 43.668962 -286.874712) (xy 43.672922 -286.825658)
			(xy 43.684699 -286.777874) (xy 43.70399 -286.732598) (xy 43.730293 -286.691002) (xy 43.762928 -286.654165)
			(xy 43.801049 -286.62304) (xy 43.84367 -286.598433) (xy 43.889686 -286.580981) (xy 43.937905 -286.571137)
			(xy 43.98708 -286.569156) (xy 44.035935 -286.575088) (xy 44.083206 -286.58878) (xy 44.127668 -286.609878)
			(xy 44.168171 -286.637834) (xy 44.203664 -286.671926) (xy 44.233229 -286.71127) (xy 44.2561 -286.754847)
			(xy 44.271684 -286.801528) (xy 44.279579 -286.850105) (xy 44.280074 -286.874712) (xy 44.280069 -286.874966)
			(xy 44.619176 -286.874966) (xy 44.623136 -286.825912) (xy 44.634913 -286.778128) (xy 44.654204 -286.732852)
			(xy 44.680507 -286.691256) (xy 44.713142 -286.654419) (xy 44.751263 -286.623294) (xy 44.793884 -286.598687)
			(xy 44.8399 -286.581235) (xy 44.888119 -286.571391) (xy 44.937294 -286.56941) (xy 44.986149 -286.575342)
			(xy 45.03342 -286.589034) (xy 45.077882 -286.610132) (xy 45.118385 -286.638088) (xy 45.153878 -286.67218)
			(xy 45.183443 -286.711524) (xy 45.206314 -286.755101) (xy 45.221898 -286.801782) (xy 45.229793 -286.850359)
			(xy 45.230288 -286.874966) (xy 45.569136 -286.874966) (xy 45.573096 -286.825912) (xy 45.584873 -286.778128)
			(xy 45.604164 -286.732852) (xy 45.630467 -286.691256) (xy 45.663102 -286.654419) (xy 45.701223 -286.623294)
			(xy 45.743844 -286.598687) (xy 45.78986 -286.581235) (xy 45.838079 -286.571391) (xy 45.887254 -286.56941)
			(xy 45.936109 -286.575342) (xy 45.98338 -286.589034) (xy 46.027842 -286.610132) (xy 46.068345 -286.638088)
			(xy 46.103838 -286.67218) (xy 46.133403 -286.711524) (xy 46.156274 -286.755101) (xy 46.171858 -286.801782)
			(xy 46.179753 -286.850359) (xy 46.180248 -286.874966) (xy 46.519096 -286.874966) (xy 46.523056 -286.825912)
			(xy 46.534833 -286.778128) (xy 46.554124 -286.732852) (xy 46.580427 -286.691256) (xy 46.613062 -286.654419)
			(xy 46.651183 -286.623294) (xy 46.693804 -286.598687) (xy 46.73982 -286.581235) (xy 46.788039 -286.571391)
			(xy 46.837214 -286.56941) (xy 46.886069 -286.575342) (xy 46.93334 -286.589034) (xy 46.977802 -286.610132)
			(xy 47.018305 -286.638088) (xy 47.053798 -286.67218) (xy 47.083363 -286.711524) (xy 47.106234 -286.755101)
			(xy 47.121818 -286.801782) (xy 47.129713 -286.850359) (xy 47.130208 -286.874966) (xy 47.469056 -286.874966)
			(xy 47.473016 -286.825912) (xy 47.484793 -286.778128) (xy 47.504084 -286.732852) (xy 47.530387 -286.691256)
			(xy 47.563022 -286.654419) (xy 47.601143 -286.623294) (xy 47.643764 -286.598687) (xy 47.68978 -286.581235)
			(xy 47.737999 -286.571391) (xy 47.787174 -286.56941) (xy 47.836029 -286.575342) (xy 47.8833 -286.589034)
			(xy 47.927762 -286.610132) (xy 47.968265 -286.638088) (xy 48.003758 -286.67218) (xy 48.033323 -286.711524)
			(xy 48.056194 -286.755101) (xy 48.071778 -286.801782) (xy 48.079673 -286.850359) (xy 48.080168 -286.874966)
			(xy 48.419016 -286.874966) (xy 48.422976 -286.825912) (xy 48.434753 -286.778128) (xy 48.454044 -286.732852)
			(xy 48.480347 -286.691256) (xy 48.512982 -286.654419) (xy 48.551103 -286.623294) (xy 48.593724 -286.598687)
			(xy 48.63974 -286.581235) (xy 48.687959 -286.571391) (xy 48.737134 -286.56941) (xy 48.785989 -286.575342)
			(xy 48.83326 -286.589034) (xy 48.877722 -286.610132) (xy 48.918225 -286.638088) (xy 48.953718 -286.67218)
			(xy 48.983283 -286.711524) (xy 49.006154 -286.755101) (xy 49.021738 -286.801782) (xy 49.029633 -286.850359)
			(xy 49.030128 -286.874966) (xy 49.368976 -286.874966) (xy 49.372936 -286.825912) (xy 49.384713 -286.778128)
			(xy 49.404004 -286.732852) (xy 49.430307 -286.691256) (xy 49.462942 -286.654419) (xy 49.501063 -286.623294)
			(xy 49.543684 -286.598687) (xy 49.5897 -286.581235) (xy 49.637919 -286.571391) (xy 49.687094 -286.56941)
			(xy 49.735949 -286.575342) (xy 49.78322 -286.589034) (xy 49.827682 -286.610132) (xy 49.868185 -286.638088)
			(xy 49.903678 -286.67218) (xy 49.933243 -286.711524) (xy 49.956114 -286.755101) (xy 49.971698 -286.801782)
			(xy 49.979593 -286.850359) (xy 49.980088 -286.874966) (xy 68.368938 -286.874966) (xy 68.372898 -286.825912)
			(xy 68.384675 -286.778128) (xy 68.403966 -286.732852) (xy 68.430269 -286.691256) (xy 68.462904 -286.654419)
			(xy 68.501025 -286.623294) (xy 68.543646 -286.598687) (xy 68.589662 -286.581235) (xy 68.637881 -286.571391)
			(xy 68.687056 -286.56941) (xy 68.735911 -286.575342) (xy 68.783182 -286.589034) (xy 68.827644 -286.610132)
			(xy 68.868147 -286.638088) (xy 68.90364 -286.67218) (xy 68.933205 -286.711524) (xy 68.956076 -286.755101)
			(xy 68.97166 -286.801782) (xy 68.979555 -286.850359) (xy 68.98005 -286.874966) (xy 69.319152 -286.874966)
			(xy 69.323112 -286.825912) (xy 69.334889 -286.778128) (xy 69.35418 -286.732852) (xy 69.380483 -286.691256)
			(xy 69.413118 -286.654419) (xy 69.451239 -286.623294) (xy 69.49386 -286.598687) (xy 69.539876 -286.581235)
			(xy 69.588095 -286.571391) (xy 69.63727 -286.56941) (xy 69.686125 -286.575342) (xy 69.733396 -286.589034)
			(xy 69.777858 -286.610132) (xy 69.818361 -286.638088) (xy 69.853854 -286.67218) (xy 69.883419 -286.711524)
			(xy 69.90629 -286.755101) (xy 69.921874 -286.801782) (xy 69.929769 -286.850359) (xy 69.930264 -286.874966)
			(xy 70.269112 -286.874966) (xy 70.273072 -286.825912) (xy 70.284849 -286.778128) (xy 70.30414 -286.732852)
			(xy 70.330443 -286.691256) (xy 70.363078 -286.654419) (xy 70.401199 -286.623294) (xy 70.44382 -286.598687)
			(xy 70.489836 -286.581235) (xy 70.538055 -286.571391) (xy 70.58723 -286.56941) (xy 70.636085 -286.575342)
			(xy 70.683356 -286.589034) (xy 70.727818 -286.610132) (xy 70.768321 -286.638088) (xy 70.803814 -286.67218)
			(xy 70.833379 -286.711524) (xy 70.85625 -286.755101) (xy 70.871834 -286.801782) (xy 70.879729 -286.850359)
			(xy 70.880224 -286.874966) (xy 70.879729 -286.899573) (xy 70.871834 -286.94815) (xy 70.85625 -286.994831)
			(xy 70.833379 -287.038408) (xy 70.803814 -287.077752) (xy 70.768321 -287.111844) (xy 70.727818 -287.1398)
			(xy 70.683356 -287.160898) (xy 70.636085 -287.17459) (xy 70.58723 -287.180522) (xy 70.538055 -287.178541)
			(xy 70.489836 -287.168697) (xy 70.44382 -287.151245) (xy 70.401199 -287.126638) (xy 70.363078 -287.095513)
			(xy 70.330443 -287.058676) (xy 70.30414 -287.01708) (xy 70.284849 -286.971804) (xy 70.273072 -286.92402)
			(xy 70.269112 -286.874966) (xy 69.930264 -286.874966) (xy 69.929769 -286.899573) (xy 69.921874 -286.94815)
			(xy 69.90629 -286.994831) (xy 69.883419 -287.038408) (xy 69.853854 -287.077752) (xy 69.818361 -287.111844)
			(xy 69.777858 -287.1398) (xy 69.733396 -287.160898) (xy 69.686125 -287.17459) (xy 69.63727 -287.180522)
			(xy 69.588095 -287.178541) (xy 69.539876 -287.168697) (xy 69.49386 -287.151245) (xy 69.451239 -287.126638)
			(xy 69.413118 -287.095513) (xy 69.380483 -287.058676) (xy 69.35418 -287.01708) (xy 69.334889 -286.971804)
			(xy 69.323112 -286.92402) (xy 69.319152 -286.874966) (xy 68.98005 -286.874966) (xy 68.979555 -286.899573)
			(xy 68.97166 -286.94815) (xy 68.956076 -286.994831) (xy 68.933205 -287.038408) (xy 68.90364 -287.077752)
			(xy 68.868147 -287.111844) (xy 68.827644 -287.1398) (xy 68.783182 -287.160898) (xy 68.735911 -287.17459)
			(xy 68.687056 -287.180522) (xy 68.637881 -287.178541) (xy 68.589662 -287.168697) (xy 68.543646 -287.151245)
			(xy 68.501025 -287.126638) (xy 68.462904 -287.095513) (xy 68.430269 -287.058676) (xy 68.403966 -287.01708)
			(xy 68.384675 -286.971804) (xy 68.372898 -286.92402) (xy 68.368938 -286.874966) (xy 49.980088 -286.874966)
			(xy 49.979593 -286.899573) (xy 49.971698 -286.94815) (xy 49.956114 -286.994831) (xy 49.933243 -287.038408)
			(xy 49.903678 -287.077752) (xy 49.868185 -287.111844) (xy 49.827682 -287.1398) (xy 49.78322 -287.160898)
			(xy 49.735949 -287.17459) (xy 49.687094 -287.180522) (xy 49.637919 -287.178541) (xy 49.5897 -287.168697)
			(xy 49.543684 -287.151245) (xy 49.501063 -287.126638) (xy 49.462942 -287.095513) (xy 49.430307 -287.058676)
			(xy 49.404004 -287.01708) (xy 49.384713 -286.971804) (xy 49.372936 -286.92402) (xy 49.368976 -286.874966)
			(xy 49.030128 -286.874966) (xy 49.029633 -286.899573) (xy 49.021738 -286.94815) (xy 49.006154 -286.994831)
			(xy 48.983283 -287.038408) (xy 48.953718 -287.077752) (xy 48.918225 -287.111844) (xy 48.877722 -287.1398)
			(xy 48.83326 -287.160898) (xy 48.785989 -287.17459) (xy 48.737134 -287.180522) (xy 48.687959 -287.178541)
			(xy 48.63974 -287.168697) (xy 48.593724 -287.151245) (xy 48.551103 -287.126638) (xy 48.512982 -287.095513)
			(xy 48.480347 -287.058676) (xy 48.454044 -287.01708) (xy 48.434753 -286.971804) (xy 48.422976 -286.92402)
			(xy 48.419016 -286.874966) (xy 48.080168 -286.874966) (xy 48.079673 -286.899573) (xy 48.071778 -286.94815)
			(xy 48.056194 -286.994831) (xy 48.033323 -287.038408) (xy 48.003758 -287.077752) (xy 47.968265 -287.111844)
			(xy 47.927762 -287.1398) (xy 47.8833 -287.160898) (xy 47.836029 -287.17459) (xy 47.787174 -287.180522)
			(xy 47.737999 -287.178541) (xy 47.68978 -287.168697) (xy 47.643764 -287.151245) (xy 47.601143 -287.126638)
			(xy 47.563022 -287.095513) (xy 47.530387 -287.058676) (xy 47.504084 -287.01708) (xy 47.484793 -286.971804)
			(xy 47.473016 -286.92402) (xy 47.469056 -286.874966) (xy 47.130208 -286.874966) (xy 47.129713 -286.899573)
			(xy 47.121818 -286.94815) (xy 47.106234 -286.994831) (xy 47.083363 -287.038408) (xy 47.053798 -287.077752)
			(xy 47.018305 -287.111844) (xy 46.977802 -287.1398) (xy 46.93334 -287.160898) (xy 46.886069 -287.17459)
			(xy 46.837214 -287.180522) (xy 46.788039 -287.178541) (xy 46.73982 -287.168697) (xy 46.693804 -287.151245)
			(xy 46.651183 -287.126638) (xy 46.613062 -287.095513) (xy 46.580427 -287.058676) (xy 46.554124 -287.01708)
			(xy 46.534833 -286.971804) (xy 46.523056 -286.92402) (xy 46.519096 -286.874966) (xy 46.180248 -286.874966)
			(xy 46.179753 -286.899573) (xy 46.171858 -286.94815) (xy 46.156274 -286.994831) (xy 46.133403 -287.038408)
			(xy 46.103838 -287.077752) (xy 46.068345 -287.111844) (xy 46.027842 -287.1398) (xy 45.98338 -287.160898)
			(xy 45.936109 -287.17459) (xy 45.887254 -287.180522) (xy 45.838079 -287.178541) (xy 45.78986 -287.168697)
			(xy 45.743844 -287.151245) (xy 45.701223 -287.126638) (xy 45.663102 -287.095513) (xy 45.630467 -287.058676)
			(xy 45.604164 -287.01708) (xy 45.584873 -286.971804) (xy 45.573096 -286.92402) (xy 45.569136 -286.874966)
			(xy 45.230288 -286.874966) (xy 45.229793 -286.899573) (xy 45.221898 -286.94815) (xy 45.206314 -286.994831)
			(xy 45.183443 -287.038408) (xy 45.153878 -287.077752) (xy 45.118385 -287.111844) (xy 45.077882 -287.1398)
			(xy 45.03342 -287.160898) (xy 44.986149 -287.17459) (xy 44.937294 -287.180522) (xy 44.888119 -287.178541)
			(xy 44.8399 -287.168697) (xy 44.793884 -287.151245) (xy 44.751263 -287.126638) (xy 44.713142 -287.095513)
			(xy 44.680507 -287.058676) (xy 44.654204 -287.01708) (xy 44.634913 -286.971804) (xy 44.623136 -286.92402)
			(xy 44.619176 -286.874966) (xy 44.280069 -286.874966) (xy 44.279579 -286.899319) (xy 44.271684 -286.947896)
			(xy 44.2561 -286.994577) (xy 44.233229 -287.038154) (xy 44.203664 -287.077498) (xy 44.168171 -287.11159)
			(xy 44.127668 -287.139546) (xy 44.083206 -287.160644) (xy 44.035935 -287.174336) (xy 43.98708 -287.180268)
			(xy 43.937905 -287.178287) (xy 43.889686 -287.168443) (xy 43.84367 -287.150991) (xy 43.801049 -287.126384)
			(xy 43.762928 -287.095259) (xy 43.730293 -287.058422) (xy 43.70399 -287.016826) (xy 43.684699 -286.97155)
			(xy 43.672922 -286.923766) (xy 43.668962 -286.874712) (xy 43.330114 -286.874712) (xy 43.329619 -286.899319)
			(xy 43.321724 -286.947896) (xy 43.30614 -286.994577) (xy 43.283269 -287.038154) (xy 43.253704 -287.077498)
			(xy 43.218211 -287.11159) (xy 43.177708 -287.139546) (xy 43.133246 -287.160644) (xy 43.085975 -287.174336)
			(xy 43.03712 -287.180268) (xy 42.987945 -287.178287) (xy 42.939726 -287.168443) (xy 42.89371 -287.150991)
			(xy 42.851089 -287.126384) (xy 42.812968 -287.095259) (xy 42.780333 -287.058422) (xy 42.75403 -287.016826)
			(xy 42.734739 -286.97155) (xy 42.722962 -286.923766) (xy 42.719002 -286.874712) (xy 42.380149 -286.874712)
			(xy 42.380154 -286.874966) (xy 42.379659 -286.899573) (xy 42.371764 -286.94815) (xy 42.35618 -286.994831)
			(xy 42.333309 -287.038408) (xy 42.303744 -287.077752) (xy 42.268251 -287.111844) (xy 42.227748 -287.1398)
			(xy 42.183286 -287.160898) (xy 42.136015 -287.17459) (xy 42.08716 -287.180522) (xy 42.037985 -287.178541)
			(xy 41.989766 -287.168697) (xy 41.94375 -287.151245) (xy 41.901129 -287.126638) (xy 41.863008 -287.095513)
			(xy 41.830373 -287.058676) (xy 41.80407 -287.01708) (xy 41.784779 -286.971804) (xy 41.773002 -286.92402)
			(xy 41.769042 -286.874966) (xy 41.430194 -286.874966) (xy 41.429699 -286.899573) (xy 41.421804 -286.94815)
			(xy 41.40622 -286.994831) (xy 41.383349 -287.038408) (xy 41.353784 -287.077752) (xy 41.318291 -287.111844)
			(xy 41.277788 -287.1398) (xy 41.233326 -287.160898) (xy 41.186055 -287.17459) (xy 41.1372 -287.180522)
			(xy 41.088025 -287.178541) (xy 41.039806 -287.168697) (xy 40.99379 -287.151245) (xy 40.951169 -287.126638)
			(xy 40.913048 -287.095513) (xy 40.880413 -287.058676) (xy 40.85411 -287.01708) (xy 40.834819 -286.971804)
			(xy 40.823042 -286.92402) (xy 40.819082 -286.874966) (xy 40.480234 -286.874966) (xy 40.479739 -286.899573)
			(xy 40.471844 -286.94815) (xy 40.45626 -286.994831) (xy 40.433389 -287.038408) (xy 40.403824 -287.077752)
			(xy 40.368331 -287.111844) (xy 40.327828 -287.1398) (xy 40.283366 -287.160898) (xy 40.236095 -287.17459)
			(xy 40.18724 -287.180522) (xy 40.138065 -287.178541) (xy 40.089846 -287.168697) (xy 40.04383 -287.151245)
			(xy 40.001209 -287.126638) (xy 39.963088 -287.095513) (xy 39.930453 -287.058676) (xy 39.90415 -287.01708)
			(xy 39.884859 -286.971804) (xy 39.873082 -286.92402) (xy 39.869122 -286.874966) (xy 39.530274 -286.874966)
			(xy 39.529779 -286.899573) (xy 39.521884 -286.94815) (xy 39.5063 -286.994831) (xy 39.483429 -287.038408)
			(xy 39.453864 -287.077752) (xy 39.418371 -287.111844) (xy 39.377868 -287.1398) (xy 39.333406 -287.160898)
			(xy 39.286135 -287.17459) (xy 39.23728 -287.180522) (xy 39.188105 -287.178541) (xy 39.139886 -287.168697)
			(xy 39.09387 -287.151245) (xy 39.051249 -287.126638) (xy 39.013128 -287.095513) (xy 38.980493 -287.058676)
			(xy 38.95419 -287.01708) (xy 38.934899 -286.971804) (xy 38.923122 -286.92402) (xy 38.919162 -286.874966)
			(xy 38.580314 -286.874966) (xy 38.579819 -286.899573) (xy 38.571924 -286.94815) (xy 38.55634 -286.994831)
			(xy 38.533469 -287.038408) (xy 38.503904 -287.077752) (xy 38.468411 -287.111844) (xy 38.427908 -287.1398)
			(xy 38.383446 -287.160898) (xy 38.336175 -287.17459) (xy 38.28732 -287.180522) (xy 38.238145 -287.178541)
			(xy 38.189926 -287.168697) (xy 38.14391 -287.151245) (xy 38.101289 -287.126638) (xy 38.063168 -287.095513)
			(xy 38.030533 -287.058676) (xy 38.00423 -287.01708) (xy 37.984939 -286.971804) (xy 37.973162 -286.92402)
			(xy 37.969202 -286.874966) (xy 37.6301 -286.874966) (xy 37.629605 -286.899573) (xy 37.62171 -286.94815)
			(xy 37.606126 -286.994831) (xy 37.583255 -287.038408) (xy 37.55369 -287.077752) (xy 37.518197 -287.111844)
			(xy 37.477694 -287.1398) (xy 37.433232 -287.160898) (xy 37.385961 -287.17459) (xy 37.337106 -287.180522)
			(xy 37.287931 -287.178541) (xy 37.239712 -287.168697) (xy 37.193696 -287.151245) (xy 37.151075 -287.126638)
			(xy 37.112954 -287.095513) (xy 37.080319 -287.058676) (xy 37.054016 -287.01708) (xy 37.034725 -286.971804)
			(xy 37.022948 -286.92402) (xy 37.018988 -286.874966) (xy 36.68014 -286.874966) (xy 36.679645 -286.899573)
			(xy 36.67175 -286.94815) (xy 36.656166 -286.994831) (xy 36.633295 -287.038408) (xy 36.60373 -287.077752)
			(xy 36.568237 -287.111844) (xy 36.527734 -287.1398) (xy 36.483272 -287.160898) (xy 36.436001 -287.17459)
			(xy 36.387146 -287.180522) (xy 36.337971 -287.178541) (xy 36.289752 -287.168697) (xy 36.243736 -287.151245)
			(xy 36.201115 -287.126638) (xy 36.162994 -287.095513) (xy 36.130359 -287.058676) (xy 36.104056 -287.01708)
			(xy 36.084765 -286.971804) (xy 36.072988 -286.92402) (xy 36.069028 -286.874966) (xy 34.31496 -286.874966)
			(xy 34.336119 -286.906948) (xy 34.359791 -286.957445) (xy 34.375859 -287.010852) (xy 34.383979 -287.066028)
			(xy 34.384488 -287.093914) (xy 34.383979 -287.1218) (xy 34.375859 -287.176976) (xy 34.359791 -287.230383)
			(xy 34.336119 -287.28088) (xy 34.305346 -287.327393) (xy 34.285139 -287.349946) (xy 73.593972 -287.349946)
			(xy 73.597932 -287.300892) (xy 73.609709 -287.253108) (xy 73.629 -287.207832) (xy 73.655303 -287.166236)
			(xy 73.687938 -287.129399) (xy 73.726059 -287.098274) (xy 73.76868 -287.073667) (xy 73.814696 -287.056215)
			(xy 73.862915 -287.046371) (xy 73.91209 -287.04439) (xy 73.960945 -287.050322) (xy 74.008216 -287.064014)
			(xy 74.052678 -287.085112) (xy 74.093181 -287.113068) (xy 74.128674 -287.14716) (xy 74.158239 -287.186504)
			(xy 74.18111 -287.230081) (xy 74.196694 -287.276762) (xy 74.204589 -287.325339) (xy 74.205084 -287.349946)
			(xy 74.204589 -287.374553) (xy 74.20441 -287.375654) (xy 74.523088 -287.375654) (xy 74.523088 -287.324238)
			(xy 74.531131 -287.273456) (xy 74.547019 -287.224557) (xy 74.570362 -287.178745) (xy 74.600583 -287.137149)
			(xy 74.636939 -287.100793) (xy 74.678535 -287.070572) (xy 74.724347 -287.047229) (xy 74.773246 -287.031341)
			(xy 74.824028 -287.023298) (xy 74.875444 -287.023298) (xy 74.926226 -287.031341) (xy 74.975125 -287.047229)
			(xy 75.020937 -287.070572) (xy 75.062533 -287.100793) (xy 75.098889 -287.137149) (xy 75.12911 -287.178745)
			(xy 75.152453 -287.224557) (xy 75.168341 -287.273456) (xy 75.176384 -287.324238) (xy 75.176888 -287.349946)
			(xy 75.176384 -287.375654) (xy 75.473302 -287.375654) (xy 75.473302 -287.324238) (xy 75.481345 -287.273456)
			(xy 75.497233 -287.224557) (xy 75.520576 -287.178745) (xy 75.550797 -287.137149) (xy 75.587153 -287.100793)
			(xy 75.628749 -287.070572) (xy 75.674561 -287.047229) (xy 75.72346 -287.031341) (xy 75.774242 -287.023298)
			(xy 75.825658 -287.023298) (xy 75.87644 -287.031341) (xy 75.925339 -287.047229) (xy 75.971151 -287.070572)
			(xy 76.012747 -287.100793) (xy 76.049103 -287.137149) (xy 76.079324 -287.178745) (xy 76.102667 -287.224557)
			(xy 76.118555 -287.273456) (xy 76.126598 -287.324238) (xy 76.127102 -287.349946) (xy 76.444106 -287.349946)
			(xy 76.448066 -287.300892) (xy 76.459843 -287.253108) (xy 76.479134 -287.207832) (xy 76.505437 -287.166236)
			(xy 76.538072 -287.129399) (xy 76.576193 -287.098274) (xy 76.618814 -287.073667) (xy 76.66483 -287.056215)
			(xy 76.713049 -287.046371) (xy 76.762224 -287.04439) (xy 76.811079 -287.050322) (xy 76.85835 -287.064014)
			(xy 76.902812 -287.085112) (xy 76.943315 -287.113068) (xy 76.978808 -287.14716) (xy 77.008373 -287.186504)
			(xy 77.031244 -287.230081) (xy 77.046828 -287.276762) (xy 77.054723 -287.325339) (xy 77.055218 -287.349946)
			(xy 77.394066 -287.349946) (xy 77.398026 -287.300892) (xy 77.409803 -287.253108) (xy 77.429094 -287.207832)
			(xy 77.455397 -287.166236) (xy 77.488032 -287.129399) (xy 77.526153 -287.098274) (xy 77.568774 -287.073667)
			(xy 77.61479 -287.056215) (xy 77.663009 -287.046371) (xy 77.712184 -287.04439) (xy 77.761039 -287.050322)
			(xy 77.80831 -287.064014) (xy 77.852772 -287.085112) (xy 77.893275 -287.113068) (xy 77.928768 -287.14716)
			(xy 77.958333 -287.186504) (xy 77.981204 -287.230081) (xy 77.996788 -287.276762) (xy 78.004683 -287.325339)
			(xy 78.005178 -287.349946) (xy 78.344026 -287.349946) (xy 78.347986 -287.300892) (xy 78.359763 -287.253108)
			(xy 78.379054 -287.207832) (xy 78.405357 -287.166236) (xy 78.437992 -287.129399) (xy 78.476113 -287.098274)
			(xy 78.518734 -287.073667) (xy 78.56475 -287.056215) (xy 78.612969 -287.046371) (xy 78.662144 -287.04439)
			(xy 78.710999 -287.050322) (xy 78.75827 -287.064014) (xy 78.802732 -287.085112) (xy 78.843235 -287.113068)
			(xy 78.878728 -287.14716) (xy 78.908293 -287.186504) (xy 78.931164 -287.230081) (xy 78.946748 -287.276762)
			(xy 78.954643 -287.325339) (xy 78.955138 -287.349946) (xy 79.293732 -287.349946) (xy 79.297692 -287.300892)
			(xy 79.309469 -287.253108) (xy 79.32876 -287.207832) (xy 79.355063 -287.166236) (xy 79.387698 -287.129399)
			(xy 79.425819 -287.098274) (xy 79.46844 -287.073667) (xy 79.514456 -287.056215) (xy 79.562675 -287.046371)
			(xy 79.61185 -287.04439) (xy 79.660705 -287.050322) (xy 79.707976 -287.064014) (xy 79.752438 -287.085112)
			(xy 79.792941 -287.113068) (xy 79.828434 -287.14716) (xy 79.857999 -287.186504) (xy 79.88087 -287.230081)
			(xy 79.896454 -287.276762) (xy 79.904349 -287.325339) (xy 79.904844 -287.349946) (xy 80.243946 -287.349946)
			(xy 80.247906 -287.300892) (xy 80.259683 -287.253108) (xy 80.278974 -287.207832) (xy 80.305277 -287.166236)
			(xy 80.337912 -287.129399) (xy 80.376033 -287.098274) (xy 80.418654 -287.073667) (xy 80.46467 -287.056215)
			(xy 80.512889 -287.046371) (xy 80.562064 -287.04439) (xy 80.610919 -287.050322) (xy 80.65819 -287.064014)
			(xy 80.702652 -287.085112) (xy 80.743155 -287.113068) (xy 80.778648 -287.14716) (xy 80.808213 -287.186504)
			(xy 80.831084 -287.230081) (xy 80.846668 -287.276762) (xy 80.854563 -287.325339) (xy 80.855058 -287.349946)
			(xy 80.854563 -287.374553) (xy 80.854384 -287.375654) (xy 81.173316 -287.375654) (xy 81.173316 -287.324238)
			(xy 81.181359 -287.273456) (xy 81.197247 -287.224557) (xy 81.22059 -287.178745) (xy 81.250811 -287.137149)
			(xy 81.287167 -287.100793) (xy 81.328763 -287.070572) (xy 81.374575 -287.047229) (xy 81.423474 -287.031341)
			(xy 81.474256 -287.023298) (xy 81.525672 -287.023298) (xy 81.576454 -287.031341) (xy 81.625353 -287.047229)
			(xy 81.671165 -287.070572) (xy 81.712761 -287.100793) (xy 81.749117 -287.137149) (xy 81.779338 -287.178745)
			(xy 81.802681 -287.224557) (xy 81.818569 -287.273456) (xy 81.826612 -287.324238) (xy 81.827116 -287.349946)
			(xy 81.826612 -287.375654) (xy 82.123276 -287.375654) (xy 82.123276 -287.324238) (xy 82.131319 -287.273456)
			(xy 82.147207 -287.224557) (xy 82.17055 -287.178745) (xy 82.200771 -287.137149) (xy 82.237127 -287.100793)
			(xy 82.278723 -287.070572) (xy 82.324535 -287.047229) (xy 82.373434 -287.031341) (xy 82.424216 -287.023298)
			(xy 82.475632 -287.023298) (xy 82.526414 -287.031341) (xy 82.575313 -287.047229) (xy 82.621125 -287.070572)
			(xy 82.662721 -287.100793) (xy 82.699077 -287.137149) (xy 82.729298 -287.178745) (xy 82.752641 -287.224557)
			(xy 82.768529 -287.273456) (xy 82.776572 -287.324238) (xy 82.777076 -287.349946) (xy 82.777071 -287.3502)
			(xy 83.094334 -287.3502) (xy 83.098294 -287.301146) (xy 83.110071 -287.253362) (xy 83.129362 -287.208086)
			(xy 83.155665 -287.16649) (xy 83.1883 -287.129653) (xy 83.226421 -287.098528) (xy 83.269042 -287.073921)
			(xy 83.315058 -287.056469) (xy 83.363277 -287.046625) (xy 83.412452 -287.044644) (xy 83.461307 -287.050576)
			(xy 83.508578 -287.064268) (xy 83.55304 -287.085366) (xy 83.593543 -287.113322) (xy 83.629036 -287.147414)
			(xy 83.658601 -287.186758) (xy 83.681472 -287.230335) (xy 83.697056 -287.277016) (xy 83.704951 -287.325593)
			(xy 83.705446 -287.3502) (xy 83.704951 -287.374807) (xy 83.697056 -287.423384) (xy 83.681472 -287.470065)
			(xy 83.658601 -287.513642) (xy 83.629036 -287.552986) (xy 83.593543 -287.587078) (xy 83.55304 -287.615034)
			(xy 83.508578 -287.636132) (xy 83.461307 -287.649824) (xy 83.412452 -287.655756) (xy 83.363277 -287.653775)
			(xy 83.315058 -287.643931) (xy 83.269042 -287.626479) (xy 83.226421 -287.601872) (xy 83.1883 -287.570747)
			(xy 83.155665 -287.53391) (xy 83.129362 -287.492314) (xy 83.110071 -287.447038) (xy 83.098294 -287.399254)
			(xy 83.094334 -287.3502) (xy 82.777071 -287.3502) (xy 82.776572 -287.375654) (xy 82.768529 -287.426436)
			(xy 82.752641 -287.475335) (xy 82.729298 -287.521147) (xy 82.699077 -287.562743) (xy 82.662721 -287.599099)
			(xy 82.621125 -287.62932) (xy 82.575313 -287.652663) (xy 82.526414 -287.668551) (xy 82.475632 -287.676594)
			(xy 82.424216 -287.676594) (xy 82.373434 -287.668551) (xy 82.324535 -287.652663) (xy 82.278723 -287.62932)
			(xy 82.237127 -287.599099) (xy 82.200771 -287.562743) (xy 82.17055 -287.521147) (xy 82.147207 -287.475335)
			(xy 82.131319 -287.426436) (xy 82.123276 -287.375654) (xy 81.826612 -287.375654) (xy 81.818569 -287.426436)
			(xy 81.802681 -287.475335) (xy 81.779338 -287.521147) (xy 81.749117 -287.562743) (xy 81.712761 -287.599099)
			(xy 81.671165 -287.62932) (xy 81.625353 -287.652663) (xy 81.576454 -287.668551) (xy 81.525672 -287.676594)
			(xy 81.474256 -287.676594) (xy 81.423474 -287.668551) (xy 81.374575 -287.652663) (xy 81.328763 -287.62932)
			(xy 81.287167 -287.599099) (xy 81.250811 -287.562743) (xy 81.22059 -287.521147) (xy 81.197247 -287.475335)
			(xy 81.181359 -287.426436) (xy 81.173316 -287.375654) (xy 80.854384 -287.375654) (xy 80.846668 -287.42313)
			(xy 80.831084 -287.469811) (xy 80.808213 -287.513388) (xy 80.778648 -287.552732) (xy 80.743155 -287.586824)
			(xy 80.702652 -287.61478) (xy 80.65819 -287.635878) (xy 80.610919 -287.64957) (xy 80.562064 -287.655502)
			(xy 80.512889 -287.653521) (xy 80.46467 -287.643677) (xy 80.418654 -287.626225) (xy 80.376033 -287.601618)
			(xy 80.337912 -287.570493) (xy 80.305277 -287.533656) (xy 80.278974 -287.49206) (xy 80.259683 -287.446784)
			(xy 80.247906 -287.399) (xy 80.243946 -287.349946) (xy 79.904844 -287.349946) (xy 79.904349 -287.374553)
			(xy 79.896454 -287.42313) (xy 79.88087 -287.469811) (xy 79.857999 -287.513388) (xy 79.828434 -287.552732)
			(xy 79.792941 -287.586824) (xy 79.752438 -287.61478) (xy 79.707976 -287.635878) (xy 79.660705 -287.64957)
			(xy 79.61185 -287.655502) (xy 79.562675 -287.653521) (xy 79.514456 -287.643677) (xy 79.46844 -287.626225)
			(xy 79.425819 -287.601618) (xy 79.387698 -287.570493) (xy 79.355063 -287.533656) (xy 79.32876 -287.49206)
			(xy 79.309469 -287.446784) (xy 79.297692 -287.399) (xy 79.293732 -287.349946) (xy 78.955138 -287.349946)
			(xy 78.954643 -287.374553) (xy 78.946748 -287.42313) (xy 78.931164 -287.469811) (xy 78.908293 -287.513388)
			(xy 78.878728 -287.552732) (xy 78.843235 -287.586824) (xy 78.802732 -287.61478) (xy 78.75827 -287.635878)
			(xy 78.710999 -287.64957) (xy 78.662144 -287.655502) (xy 78.612969 -287.653521) (xy 78.56475 -287.643677)
			(xy 78.518734 -287.626225) (xy 78.476113 -287.601618) (xy 78.437992 -287.570493) (xy 78.405357 -287.533656)
			(xy 78.379054 -287.49206) (xy 78.359763 -287.446784) (xy 78.347986 -287.399) (xy 78.344026 -287.349946)
			(xy 78.005178 -287.349946) (xy 78.004683 -287.374553) (xy 77.996788 -287.42313) (xy 77.981204 -287.469811)
			(xy 77.958333 -287.513388) (xy 77.928768 -287.552732) (xy 77.893275 -287.586824) (xy 77.852772 -287.61478)
			(xy 77.80831 -287.635878) (xy 77.761039 -287.64957) (xy 77.712184 -287.655502) (xy 77.663009 -287.653521)
			(xy 77.61479 -287.643677) (xy 77.568774 -287.626225) (xy 77.526153 -287.601618) (xy 77.488032 -287.570493)
			(xy 77.455397 -287.533656) (xy 77.429094 -287.49206) (xy 77.409803 -287.446784) (xy 77.398026 -287.399)
			(xy 77.394066 -287.349946) (xy 77.055218 -287.349946) (xy 77.054723 -287.374553) (xy 77.046828 -287.42313)
			(xy 77.031244 -287.469811) (xy 77.008373 -287.513388) (xy 76.978808 -287.552732) (xy 76.943315 -287.586824)
			(xy 76.902812 -287.61478) (xy 76.85835 -287.635878) (xy 76.811079 -287.64957) (xy 76.762224 -287.655502)
			(xy 76.713049 -287.653521) (xy 76.66483 -287.643677) (xy 76.618814 -287.626225) (xy 76.576193 -287.601618)
			(xy 76.538072 -287.570493) (xy 76.505437 -287.533656) (xy 76.479134 -287.49206) (xy 76.459843 -287.446784)
			(xy 76.448066 -287.399) (xy 76.444106 -287.349946) (xy 76.127102 -287.349946) (xy 76.126598 -287.375654)
			(xy 76.118555 -287.426436) (xy 76.102667 -287.475335) (xy 76.079324 -287.521147) (xy 76.049103 -287.562743)
			(xy 76.012747 -287.599099) (xy 75.971151 -287.62932) (xy 75.925339 -287.652663) (xy 75.87644 -287.668551)
			(xy 75.825658 -287.676594) (xy 75.774242 -287.676594) (xy 75.72346 -287.668551) (xy 75.674561 -287.652663)
			(xy 75.628749 -287.62932) (xy 75.587153 -287.599099) (xy 75.550797 -287.562743) (xy 75.520576 -287.521147)
			(xy 75.497233 -287.475335) (xy 75.481345 -287.426436) (xy 75.473302 -287.375654) (xy 75.176384 -287.375654)
			(xy 75.168341 -287.426436) (xy 75.152453 -287.475335) (xy 75.12911 -287.521147) (xy 75.098889 -287.562743)
			(xy 75.062533 -287.599099) (xy 75.020937 -287.62932) (xy 74.975125 -287.652663) (xy 74.926226 -287.668551)
			(xy 74.875444 -287.676594) (xy 74.824028 -287.676594) (xy 74.773246 -287.668551) (xy 74.724347 -287.652663)
			(xy 74.678535 -287.62932) (xy 74.636939 -287.599099) (xy 74.600583 -287.562743) (xy 74.570362 -287.521147)
			(xy 74.547019 -287.475335) (xy 74.531131 -287.426436) (xy 74.523088 -287.375654) (xy 74.20441 -287.375654)
			(xy 74.196694 -287.42313) (xy 74.18111 -287.469811) (xy 74.158239 -287.513388) (xy 74.128674 -287.552732)
			(xy 74.093181 -287.586824) (xy 74.052678 -287.61478) (xy 74.008216 -287.635878) (xy 73.960945 -287.64957)
			(xy 73.91209 -287.655502) (xy 73.862915 -287.653521) (xy 73.814696 -287.643677) (xy 73.76868 -287.626225)
			(xy 73.726059 -287.601618) (xy 73.687938 -287.570493) (xy 73.655303 -287.533656) (xy 73.629 -287.49206)
			(xy 73.609709 -287.446784) (xy 73.597932 -287.399) (xy 73.593972 -287.349946) (xy 34.285139 -287.349946)
			(xy 34.268129 -287.36893) (xy 34.225261 -287.404605) (xy 34.177655 -287.433659) (xy 34.126326 -287.455471)
			(xy 34.072369 -287.469577) (xy 34.016932 -287.475677) (xy 33.961198 -287.47364) (xy 33.906355 -287.46351)
			(xy 33.853571 -287.445503) (xy 33.803971 -287.420002) (xy 33.758613 -287.387551) (xy 33.718464 -287.348842)
			(xy 33.684378 -287.304699) (xy 33.657082 -287.256064) (xy 33.637159 -287.203973) (xy 33.625033 -287.149536)
			(xy 33.620962 -287.093914) (xy 33.498028 -287.093914) (xy 33.497519 -287.1218) (xy 33.489399 -287.176976)
			(xy 33.473331 -287.230383) (xy 33.449659 -287.28088) (xy 33.418886 -287.327393) (xy 33.381669 -287.36893)
			(xy 33.338801 -287.404605) (xy 33.291195 -287.433659) (xy 33.239866 -287.455471) (xy 33.185909 -287.469577)
			(xy 33.130472 -287.475677) (xy 33.074738 -287.47364) (xy 33.019895 -287.46351) (xy 32.967111 -287.445503)
			(xy 32.917511 -287.420002) (xy 32.872153 -287.387551) (xy 32.832004 -287.348842) (xy 32.797918 -287.304699)
			(xy 32.770622 -287.256064) (xy 32.750699 -287.203973) (xy 32.738573 -287.149536) (xy 32.734502 -287.093914)
			(xy 32.101028 -287.093914) (xy 32.100542 -287.121165) (xy 32.092786 -287.175113) (xy 32.077431 -287.227408)
			(xy 32.054789 -287.276985) (xy 32.025323 -287.322835) (xy 31.989632 -287.364026) (xy 31.948441 -287.399717)
			(xy 31.902591 -287.429183) (xy 31.853014 -287.451825) (xy 31.800719 -287.46718) (xy 31.746771 -287.474936)
			(xy 31.692269 -287.474936) (xy 31.638321 -287.46718) (xy 31.586026 -287.451825) (xy 31.536449 -287.429183)
			(xy 31.490599 -287.399717) (xy 31.449408 -287.364026) (xy 31.413717 -287.322835) (xy 31.384251 -287.276985)
			(xy 31.361609 -287.227408) (xy 31.346254 -287.175113) (xy 31.338498 -287.121165) (xy 31.338012 -287.093914)
			(xy 6.648247 -287.093914) (xy 6.648247 -287.131833) (xy 6.64049 -287.185785) (xy 6.625133 -287.238083)
			(xy 6.60249 -287.287664) (xy 6.573022 -287.333517) (xy 6.537328 -287.37471) (xy 6.496134 -287.410404)
			(xy 6.45028 -287.439872) (xy 6.400699 -287.462515) (xy 6.348401 -287.47787) (xy 6.294449 -287.485627)
			(xy 6.267196 -287.48609) (xy 6.237072 -287.485539) (xy 6.177574 -287.476056) (xy 6.120305 -287.457341)
			(xy 6.066688 -287.42986) (xy 6.018056 -287.394296) (xy 5.996432 -287.373314) (xy 5.989013 -287.366497)
			(xy 5.970428 -287.358763) (xy 5.960364 -287.358328) (xy 5.888228 -287.358328) (xy 5.878159 -287.358761)
			(xy 5.859561 -287.366476) (xy 5.85216 -287.373314) (xy 5.830534 -287.394293) (xy 5.781905 -287.429861)
			(xy 5.728289 -287.457341) (xy 5.671019 -287.476049) (xy 5.61152 -287.485521) (xy 5.581396 -287.48609)
			(xy 5.554145 -287.4856) (xy 5.500198 -287.477843) (xy 5.447904 -287.462488) (xy 5.398328 -287.439846)
			(xy 5.352478 -287.41038) (xy 5.311288 -287.374689) (xy 5.275597 -287.333499) (xy 5.246132 -287.287649)
			(xy 5.223491 -287.238072) (xy 5.208136 -287.185778) (xy 5.20038 -287.131831) (xy 4.636057 -287.131831)
			(xy 4.636057 -287.131833) (xy 4.6283 -287.185784) (xy 4.612943 -287.238083) (xy 4.590301 -287.287663)
			(xy 4.560832 -287.333517) (xy 4.525138 -287.37471) (xy 4.483945 -287.410403) (xy 4.438091 -287.439872)
			(xy 4.388511 -287.462514) (xy 4.336213 -287.47787) (xy 4.282261 -287.485627) (xy 4.255008 -287.48609)
			(xy 4.227638 -287.485622) (xy 4.173459 -287.477805) (xy 4.120956 -287.462316) (xy 4.071209 -287.439475)
			(xy 4.025242 -287.409751) (xy 4.00431 -287.39211) (xy 4.004056 -287.391856) (xy 3.996961 -287.386281)
			(xy 3.980051 -287.380029) (xy 3.971036 -287.379664) (xy 3.90398 -287.379664) (xy 3.894963 -287.380019)
			(xy 3.878046 -287.386269) (xy 3.87096 -287.391856) (xy 3.87096 -287.39211) (xy 3.870706 -287.39211)
			(xy 3.849784 -287.409761) (xy 3.803808 -287.439471) (xy 3.754058 -287.462304) (xy 3.701555 -287.477793)
			(xy 3.647378 -287.485618) (xy 3.620008 -287.48609) (xy 3.592757 -287.4856) (xy 3.53881 -287.477843)
			(xy 3.486516 -287.462488) (xy 3.436939 -287.439847) (xy 3.391089 -287.410381) (xy 3.349899 -287.374689)
			(xy 3.314208 -287.3335) (xy 3.284742 -287.287649) (xy 3.262101 -287.238073) (xy 3.246746 -287.185778)
			(xy 3.23899 -287.131831) (xy 1.420114 -287.131831) (xy 1.420114 -287.984001) (xy 11.94992 -287.984001)
			(xy 11.94992 -287.929499) (xy 11.957676 -287.875552) (xy 11.973031 -287.823257) (xy 11.995672 -287.773681)
			(xy 12.025138 -287.72783) (xy 12.060829 -287.686641) (xy 12.102019 -287.650949) (xy 12.147869 -287.621483)
			(xy 12.197446 -287.598842) (xy 12.24974 -287.583487) (xy 12.303687 -287.57573) (xy 12.330938 -287.575244)
			(xy 12.358307 -287.575736) (xy 12.412486 -287.583546) (xy 12.464989 -287.599028) (xy 12.514736 -287.621865)
			(xy 12.560704 -287.651585) (xy 12.581636 -287.669224) (xy 12.58189 -287.669478) (xy 12.588969 -287.675076)
			(xy 12.605892 -287.681314) (xy 12.61491 -287.68167) (xy 12.681966 -287.68167) (xy 12.690982 -287.681303)
			(xy 12.707899 -287.675063) (xy 12.714986 -287.669478) (xy 12.714986 -287.669224) (xy 12.71524 -287.669224)
			(xy 12.736187 -287.651603) (xy 12.782155 -287.621888) (xy 12.831899 -287.599048) (xy 12.884396 -287.583553)
			(xy 12.93857 -287.57572) (xy 12.965938 -287.575244) (xy 12.993191 -287.575703) (xy 13.047143 -287.58346)
			(xy 13.099441 -287.598816) (xy 13.149021 -287.621458) (xy 13.194875 -287.650927) (xy 13.236068 -287.68662)
			(xy 13.271762 -287.727813) (xy 13.301231 -287.773667) (xy 13.323873 -287.823247) (xy 13.33923 -287.875546)
			(xy 13.346987 -287.929497) (xy 13.346987 -287.984001) (xy 13.68982 -287.984001) (xy 13.68982 -287.929499)
			(xy 13.697576 -287.875552) (xy 13.712931 -287.823257) (xy 13.735572 -287.773681) (xy 13.765038 -287.72783)
			(xy 13.800729 -287.686641) (xy 13.841919 -287.650949) (xy 13.887769 -287.621483) (xy 13.937346 -287.598842)
			(xy 13.98964 -287.583487) (xy 14.043587 -287.57573) (xy 14.070838 -287.575244) (xy 14.098207 -287.575736)
			(xy 14.152386 -287.583546) (xy 14.204889 -287.599028) (xy 14.254636 -287.621865) (xy 14.300604 -287.651585)
			(xy 14.321536 -287.669224) (xy 14.32179 -287.669478) (xy 14.328869 -287.675076) (xy 14.345792 -287.681314)
			(xy 14.35481 -287.68167) (xy 14.421866 -287.68167) (xy 14.430882 -287.681303) (xy 14.447799 -287.675063)
			(xy 14.454886 -287.669478) (xy 14.454886 -287.669224) (xy 14.45514 -287.669224) (xy 14.476087 -287.651603)
			(xy 14.522055 -287.621888) (xy 14.571799 -287.599048) (xy 14.624296 -287.583553) (xy 14.67847 -287.57572)
			(xy 14.705838 -287.575244) (xy 14.733091 -287.575703) (xy 14.787043 -287.58346) (xy 14.839341 -287.598816)
			(xy 14.888921 -287.621458) (xy 14.934775 -287.650927) (xy 14.975968 -287.68662) (xy 15.011662 -287.727813)
			(xy 15.041131 -287.773667) (xy 15.063773 -287.823247) (xy 15.064266 -287.824926) (xy 36.069028 -287.824926)
			(xy 36.072988 -287.775872) (xy 36.084765 -287.728088) (xy 36.104056 -287.682812) (xy 36.130359 -287.641216)
			(xy 36.162994 -287.604379) (xy 36.201115 -287.573254) (xy 36.243736 -287.548647) (xy 36.289752 -287.531195)
			(xy 36.337971 -287.521351) (xy 36.387146 -287.51937) (xy 36.436001 -287.525302) (xy 36.483272 -287.538994)
			(xy 36.527734 -287.560092) (xy 36.568237 -287.588048) (xy 36.60373 -287.62214) (xy 36.633295 -287.661484)
			(xy 36.656166 -287.705061) (xy 36.67175 -287.751742) (xy 36.679645 -287.800319) (xy 36.68014 -287.824926)
			(xy 37.018988 -287.824926) (xy 37.022948 -287.775872) (xy 37.034725 -287.728088) (xy 37.054016 -287.682812)
			(xy 37.080319 -287.641216) (xy 37.112954 -287.604379) (xy 37.151075 -287.573254) (xy 37.193696 -287.548647)
			(xy 37.239712 -287.531195) (xy 37.287931 -287.521351) (xy 37.337106 -287.51937) (xy 37.385961 -287.525302)
			(xy 37.433232 -287.538994) (xy 37.477694 -287.560092) (xy 37.518197 -287.588048) (xy 37.55369 -287.62214)
			(xy 37.583255 -287.661484) (xy 37.606126 -287.705061) (xy 37.62171 -287.751742) (xy 37.629605 -287.800319)
			(xy 37.6301 -287.824926) (xy 37.629605 -287.849533) (xy 37.629463 -287.850408) (xy 37.944539 -287.850408)
			(xy 37.944539 -287.798392) (xy 37.952677 -287.747016) (xy 37.968751 -287.697546) (xy 37.992366 -287.651199)
			(xy 38.02294 -287.609117) (xy 38.059722 -287.572337) (xy 38.101804 -287.541763) (xy 38.148151 -287.518148)
			(xy 38.197622 -287.502075) (xy 38.248998 -287.493939) (xy 38.275006 -287.493456) (xy 39.224966 -287.493456)
			(xy 39.250978 -287.493901) (xy 39.302363 -287.502035) (xy 39.351843 -287.518107) (xy 39.398199 -287.541722)
			(xy 39.44029 -287.572299) (xy 39.477079 -287.609084) (xy 39.50766 -287.651172) (xy 39.53128 -287.697525)
			(xy 39.547357 -287.747004) (xy 39.555496 -287.798388) (xy 39.555496 -287.824926) (xy 39.869122 -287.824926)
			(xy 39.873082 -287.775872) (xy 39.884859 -287.728088) (xy 39.90415 -287.682812) (xy 39.930453 -287.641216)
			(xy 39.963088 -287.604379) (xy 40.001209 -287.573254) (xy 40.04383 -287.548647) (xy 40.089846 -287.531195)
			(xy 40.138065 -287.521351) (xy 40.18724 -287.51937) (xy 40.236095 -287.525302) (xy 40.283366 -287.538994)
			(xy 40.327828 -287.560092) (xy 40.368331 -287.588048) (xy 40.403824 -287.62214) (xy 40.433389 -287.661484)
			(xy 40.45626 -287.705061) (xy 40.471844 -287.751742) (xy 40.479739 -287.800319) (xy 40.480234 -287.824926)
			(xy 40.479739 -287.849533) (xy 40.479597 -287.850405) (xy 40.794466 -287.850405) (xy 40.794466 -287.798395)
			(xy 40.802602 -287.747025) (xy 40.818674 -287.697561) (xy 40.842285 -287.651219) (xy 40.872855 -287.609142)
			(xy 40.909631 -287.572364) (xy 40.951707 -287.541792) (xy 40.998048 -287.518179) (xy 41.047512 -287.502105)
			(xy 41.098881 -287.493967) (xy 41.124886 -287.493456) (xy 42.074846 -287.493456) (xy 42.100852 -287.493934)
			(xy 42.152223 -287.502077) (xy 42.201688 -287.518155) (xy 42.248029 -287.541773) (xy 42.290106 -287.572348)
			(xy 42.326882 -287.609129) (xy 42.357451 -287.65121) (xy 42.381063 -287.697554) (xy 42.397134 -287.747022)
			(xy 42.40527 -287.798394) (xy 42.40527 -287.824926) (xy 42.719002 -287.824926) (xy 42.722962 -287.775872)
			(xy 42.734739 -287.728088) (xy 42.75403 -287.682812) (xy 42.780333 -287.641216) (xy 42.812968 -287.604379)
			(xy 42.851089 -287.573254) (xy 42.89371 -287.548647) (xy 42.939726 -287.531195) (xy 42.987945 -287.521351)
			(xy 43.03712 -287.51937) (xy 43.085975 -287.525302) (xy 43.133246 -287.538994) (xy 43.177708 -287.560092)
			(xy 43.218211 -287.588048) (xy 43.253704 -287.62214) (xy 43.283269 -287.661484) (xy 43.30614 -287.705061)
			(xy 43.321724 -287.751742) (xy 43.329619 -287.800319) (xy 43.330114 -287.824926) (xy 43.668962 -287.824926)
			(xy 43.672922 -287.775872) (xy 43.684699 -287.728088) (xy 43.70399 -287.682812) (xy 43.730293 -287.641216)
			(xy 43.762928 -287.604379) (xy 43.801049 -287.573254) (xy 43.84367 -287.548647) (xy 43.889686 -287.531195)
			(xy 43.937905 -287.521351) (xy 43.98708 -287.51937) (xy 44.035935 -287.525302) (xy 44.083206 -287.538994)
			(xy 44.127668 -287.560092) (xy 44.168171 -287.588048) (xy 44.203664 -287.62214) (xy 44.233229 -287.661484)
			(xy 44.2561 -287.705061) (xy 44.271684 -287.751742) (xy 44.279579 -287.800319) (xy 44.280074 -287.824926)
			(xy 44.619176 -287.824926) (xy 44.623136 -287.775872) (xy 44.634913 -287.728088) (xy 44.654204 -287.682812)
			(xy 44.680507 -287.641216) (xy 44.713142 -287.604379) (xy 44.751263 -287.573254) (xy 44.793884 -287.548647)
			(xy 44.8399 -287.531195) (xy 44.888119 -287.521351) (xy 44.937294 -287.51937) (xy 44.986149 -287.525302)
			(xy 45.03342 -287.538994) (xy 45.077882 -287.560092) (xy 45.118385 -287.588048) (xy 45.153878 -287.62214)
			(xy 45.183443 -287.661484) (xy 45.206314 -287.705061) (xy 45.221898 -287.751742) (xy 45.229793 -287.800319)
			(xy 45.230288 -287.824926) (xy 45.569136 -287.824926) (xy 45.573096 -287.775872) (xy 45.584873 -287.728088)
			(xy 45.604164 -287.682812) (xy 45.630467 -287.641216) (xy 45.663102 -287.604379) (xy 45.701223 -287.573254)
			(xy 45.743844 -287.548647) (xy 45.78986 -287.531195) (xy 45.838079 -287.521351) (xy 45.887254 -287.51937)
			(xy 45.936109 -287.525302) (xy 45.98338 -287.538994) (xy 46.027842 -287.560092) (xy 46.068345 -287.588048)
			(xy 46.103838 -287.62214) (xy 46.133403 -287.661484) (xy 46.156274 -287.705061) (xy 46.171858 -287.751742)
			(xy 46.179753 -287.800319) (xy 46.180248 -287.824926) (xy 46.519096 -287.824926) (xy 46.523056 -287.775872)
			(xy 46.534833 -287.728088) (xy 46.554124 -287.682812) (xy 46.580427 -287.641216) (xy 46.613062 -287.604379)
			(xy 46.651183 -287.573254) (xy 46.693804 -287.548647) (xy 46.73982 -287.531195) (xy 46.788039 -287.521351)
			(xy 46.837214 -287.51937) (xy 46.886069 -287.525302) (xy 46.93334 -287.538994) (xy 46.977802 -287.560092)
			(xy 47.018305 -287.588048) (xy 47.053798 -287.62214) (xy 47.083363 -287.661484) (xy 47.106234 -287.705061)
			(xy 47.121818 -287.751742) (xy 47.129713 -287.800319) (xy 47.130208 -287.824926) (xy 47.469056 -287.824926)
			(xy 47.473016 -287.775872) (xy 47.484793 -287.728088) (xy 47.504084 -287.682812) (xy 47.530387 -287.641216)
			(xy 47.563022 -287.604379) (xy 47.601143 -287.573254) (xy 47.643764 -287.548647) (xy 47.68978 -287.531195)
			(xy 47.737999 -287.521351) (xy 47.787174 -287.51937) (xy 47.836029 -287.525302) (xy 47.8833 -287.538994)
			(xy 47.927762 -287.560092) (xy 47.968265 -287.588048) (xy 48.003758 -287.62214) (xy 48.033323 -287.661484)
			(xy 48.056194 -287.705061) (xy 48.071778 -287.751742) (xy 48.079673 -287.800319) (xy 48.080168 -287.824926)
			(xy 48.419016 -287.824926) (xy 48.422976 -287.775872) (xy 48.434753 -287.728088) (xy 48.454044 -287.682812)
			(xy 48.480347 -287.641216) (xy 48.512982 -287.604379) (xy 48.551103 -287.573254) (xy 48.593724 -287.548647)
			(xy 48.63974 -287.531195) (xy 48.687959 -287.521351) (xy 48.737134 -287.51937) (xy 48.785989 -287.525302)
			(xy 48.83326 -287.538994) (xy 48.877722 -287.560092) (xy 48.918225 -287.588048) (xy 48.953718 -287.62214)
			(xy 48.983283 -287.661484) (xy 49.006154 -287.705061) (xy 49.021738 -287.751742) (xy 49.029633 -287.800319)
			(xy 49.030128 -287.824926) (xy 49.368976 -287.824926) (xy 49.372936 -287.775872) (xy 49.384713 -287.728088)
			(xy 49.404004 -287.682812) (xy 49.430307 -287.641216) (xy 49.462942 -287.604379) (xy 49.501063 -287.573254)
			(xy 49.543684 -287.548647) (xy 49.5897 -287.531195) (xy 49.637919 -287.521351) (xy 49.687094 -287.51937)
			(xy 49.735949 -287.525302) (xy 49.78322 -287.538994) (xy 49.827682 -287.560092) (xy 49.868185 -287.588048)
			(xy 49.903678 -287.62214) (xy 49.933243 -287.661484) (xy 49.956114 -287.705061) (xy 49.971698 -287.751742)
			(xy 49.979593 -287.800319) (xy 49.980088 -287.824926) (xy 50.31919 -287.824926) (xy 50.32315 -287.775872)
			(xy 50.334927 -287.728088) (xy 50.354218 -287.682812) (xy 50.380521 -287.641216) (xy 50.413156 -287.604379)
			(xy 50.451277 -287.573254) (xy 50.493898 -287.548647) (xy 50.539914 -287.531195) (xy 50.588133 -287.521351)
			(xy 50.637308 -287.51937) (xy 50.686163 -287.525302) (xy 50.733434 -287.538994) (xy 50.777896 -287.560092)
			(xy 50.818399 -287.588048) (xy 50.853892 -287.62214) (xy 50.883457 -287.661484) (xy 50.906328 -287.705061)
			(xy 50.921912 -287.751742) (xy 50.929807 -287.800319) (xy 50.930302 -287.824926) (xy 51.26915 -287.824926)
			(xy 51.27311 -287.775872) (xy 51.284887 -287.728088) (xy 51.304178 -287.682812) (xy 51.330481 -287.641216)
			(xy 51.363116 -287.604379) (xy 51.401237 -287.573254) (xy 51.443858 -287.548647) (xy 51.489874 -287.531195)
			(xy 51.538093 -287.521351) (xy 51.587268 -287.51937) (xy 51.636123 -287.525302) (xy 51.683394 -287.538994)
			(xy 51.727856 -287.560092) (xy 51.768359 -287.588048) (xy 51.803852 -287.62214) (xy 51.833417 -287.661484)
			(xy 51.856288 -287.705061) (xy 51.871872 -287.751742) (xy 51.879767 -287.800319) (xy 51.880262 -287.824926)
			(xy 52.21911 -287.824926) (xy 52.22307 -287.775872) (xy 52.234847 -287.728088) (xy 52.254138 -287.682812)
			(xy 52.280441 -287.641216) (xy 52.313076 -287.604379) (xy 52.351197 -287.573254) (xy 52.393818 -287.548647)
			(xy 52.439834 -287.531195) (xy 52.488053 -287.521351) (xy 52.537228 -287.51937) (xy 52.586083 -287.525302)
			(xy 52.633354 -287.538994) (xy 52.677816 -287.560092) (xy 52.718319 -287.588048) (xy 52.753812 -287.62214)
			(xy 52.783377 -287.661484) (xy 52.806248 -287.705061) (xy 52.821832 -287.751742) (xy 52.829727 -287.800319)
			(xy 52.830222 -287.824926) (xy 53.16907 -287.824926) (xy 53.17303 -287.775872) (xy 53.184807 -287.728088)
			(xy 53.204098 -287.682812) (xy 53.230401 -287.641216) (xy 53.263036 -287.604379) (xy 53.301157 -287.573254)
			(xy 53.343778 -287.548647) (xy 53.389794 -287.531195) (xy 53.438013 -287.521351) (xy 53.487188 -287.51937)
			(xy 53.536043 -287.525302) (xy 53.583314 -287.538994) (xy 53.627776 -287.560092) (xy 53.668279 -287.588048)
			(xy 53.703772 -287.62214) (xy 53.733337 -287.661484) (xy 53.756208 -287.705061) (xy 53.771792 -287.751742)
			(xy 53.779687 -287.800319) (xy 53.780182 -287.824926) (xy 54.11903 -287.824926) (xy 54.12299 -287.775872)
			(xy 54.134767 -287.728088) (xy 54.154058 -287.682812) (xy 54.180361 -287.641216) (xy 54.212996 -287.604379)
			(xy 54.251117 -287.573254) (xy 54.293738 -287.548647) (xy 54.339754 -287.531195) (xy 54.387973 -287.521351)
			(xy 54.437148 -287.51937) (xy 54.486003 -287.525302) (xy 54.533274 -287.538994) (xy 54.577736 -287.560092)
			(xy 54.618239 -287.588048) (xy 54.653732 -287.62214) (xy 54.683297 -287.661484) (xy 54.706168 -287.705061)
			(xy 54.721752 -287.751742) (xy 54.729647 -287.800319) (xy 54.730142 -287.824926) (xy 55.06899 -287.824926)
			(xy 55.07295 -287.775872) (xy 55.084727 -287.728088) (xy 55.104018 -287.682812) (xy 55.130321 -287.641216)
			(xy 55.162956 -287.604379) (xy 55.201077 -287.573254) (xy 55.243698 -287.548647) (xy 55.289714 -287.531195)
			(xy 55.337933 -287.521351) (xy 55.387108 -287.51937) (xy 55.435963 -287.525302) (xy 55.483234 -287.538994)
			(xy 55.527696 -287.560092) (xy 55.568199 -287.588048) (xy 55.603692 -287.62214) (xy 55.633257 -287.661484)
			(xy 55.656128 -287.705061) (xy 55.671712 -287.751742) (xy 55.679607 -287.800319) (xy 55.680102 -287.824926)
			(xy 56.01895 -287.824926) (xy 56.02291 -287.775872) (xy 56.034687 -287.728088) (xy 56.053978 -287.682812)
			(xy 56.080281 -287.641216) (xy 56.112916 -287.604379) (xy 56.151037 -287.573254) (xy 56.193658 -287.548647)
			(xy 56.239674 -287.531195) (xy 56.287893 -287.521351) (xy 56.337068 -287.51937) (xy 56.385923 -287.525302)
			(xy 56.433194 -287.538994) (xy 56.477656 -287.560092) (xy 56.518159 -287.588048) (xy 56.553652 -287.62214)
			(xy 56.583217 -287.661484) (xy 56.606088 -287.705061) (xy 56.621672 -287.751742) (xy 56.629567 -287.800319)
			(xy 56.630062 -287.824926) (xy 56.969164 -287.824926) (xy 56.973124 -287.775872) (xy 56.984901 -287.728088)
			(xy 57.004192 -287.682812) (xy 57.030495 -287.641216) (xy 57.06313 -287.604379) (xy 57.101251 -287.573254)
			(xy 57.143872 -287.548647) (xy 57.189888 -287.531195) (xy 57.238107 -287.521351) (xy 57.287282 -287.51937)
			(xy 57.336137 -287.525302) (xy 57.383408 -287.538994) (xy 57.42787 -287.560092) (xy 57.468373 -287.588048)
			(xy 57.503866 -287.62214) (xy 57.533431 -287.661484) (xy 57.553624 -287.699958) (xy 57.944016 -287.699958)
			(xy 57.947976 -287.650904) (xy 57.959753 -287.60312) (xy 57.979044 -287.557844) (xy 58.005347 -287.516248)
			(xy 58.037982 -287.479411) (xy 58.076103 -287.448286) (xy 58.118724 -287.423679) (xy 58.16474 -287.406227)
			(xy 58.212959 -287.396383) (xy 58.262134 -287.394402) (xy 58.310989 -287.400334) (xy 58.35826 -287.414026)
			(xy 58.402722 -287.435124) (xy 58.443225 -287.46308) (xy 58.478718 -287.497172) (xy 58.508283 -287.536516)
			(xy 58.531154 -287.580093) (xy 58.546738 -287.626774) (xy 58.554633 -287.675351) (xy 58.555128 -287.699958)
			(xy 58.554633 -287.724565) (xy 58.546738 -287.773142) (xy 58.531154 -287.819823) (xy 58.508283 -287.8634)
			(xy 58.480888 -287.899856) (xy 59.819044 -287.899856) (xy 59.823004 -287.850802) (xy 59.834781 -287.803018)
			(xy 59.854072 -287.757742) (xy 59.880375 -287.716146) (xy 59.91301 -287.679309) (xy 59.951131 -287.648184)
			(xy 59.993752 -287.623577) (xy 60.039768 -287.606125) (xy 60.087987 -287.596281) (xy 60.137162 -287.5943)
			(xy 60.186017 -287.600232) (xy 60.233288 -287.613924) (xy 60.27775 -287.635022) (xy 60.318253 -287.662978)
			(xy 60.353746 -287.69707) (xy 60.383311 -287.736414) (xy 60.406182 -287.779991) (xy 60.421183 -287.824926)
			(xy 60.769004 -287.824926) (xy 60.772964 -287.775872) (xy 60.784741 -287.728088) (xy 60.804032 -287.682812)
			(xy 60.830335 -287.641216) (xy 60.86297 -287.604379) (xy 60.901091 -287.573254) (xy 60.943712 -287.548647)
			(xy 60.989728 -287.531195) (xy 61.037947 -287.521351) (xy 61.087122 -287.51937) (xy 61.135977 -287.525302)
			(xy 61.183248 -287.538994) (xy 61.22771 -287.560092) (xy 61.268213 -287.588048) (xy 61.303706 -287.62214)
			(xy 61.333271 -287.661484) (xy 61.356142 -287.705061) (xy 61.371726 -287.751742) (xy 61.379621 -287.800319)
			(xy 61.380116 -287.824926) (xy 61.718964 -287.824926) (xy 61.722924 -287.775872) (xy 61.734701 -287.728088)
			(xy 61.753992 -287.682812) (xy 61.780295 -287.641216) (xy 61.81293 -287.604379) (xy 61.851051 -287.573254)
			(xy 61.893672 -287.548647) (xy 61.939688 -287.531195) (xy 61.987907 -287.521351) (xy 62.037082 -287.51937)
			(xy 62.085937 -287.525302) (xy 62.133208 -287.538994) (xy 62.17767 -287.560092) (xy 62.218173 -287.588048)
			(xy 62.253666 -287.62214) (xy 62.283231 -287.661484) (xy 62.306102 -287.705061) (xy 62.321686 -287.751742)
			(xy 62.329581 -287.800319) (xy 62.330076 -287.824926) (xy 62.669178 -287.824926) (xy 62.673138 -287.775872)
			(xy 62.684915 -287.728088) (xy 62.704206 -287.682812) (xy 62.730509 -287.641216) (xy 62.763144 -287.604379)
			(xy 62.801265 -287.573254) (xy 62.843886 -287.548647) (xy 62.889902 -287.531195) (xy 62.938121 -287.521351)
			(xy 62.987296 -287.51937) (xy 63.036151 -287.525302) (xy 63.083422 -287.538994) (xy 63.127884 -287.560092)
			(xy 63.168387 -287.588048) (xy 63.20388 -287.62214) (xy 63.233445 -287.661484) (xy 63.256316 -287.705061)
			(xy 63.2719 -287.751742) (xy 63.279795 -287.800319) (xy 63.28029 -287.824926) (xy 63.619138 -287.824926)
			(xy 63.623098 -287.775872) (xy 63.634875 -287.728088) (xy 63.654166 -287.682812) (xy 63.680469 -287.641216)
			(xy 63.713104 -287.604379) (xy 63.751225 -287.573254) (xy 63.793846 -287.548647) (xy 63.839862 -287.531195)
			(xy 63.888081 -287.521351) (xy 63.937256 -287.51937) (xy 63.986111 -287.525302) (xy 64.033382 -287.538994)
			(xy 64.077844 -287.560092) (xy 64.118347 -287.588048) (xy 64.15384 -287.62214) (xy 64.183405 -287.661484)
			(xy 64.206276 -287.705061) (xy 64.22186 -287.751742) (xy 64.229755 -287.800319) (xy 64.23025 -287.824926)
			(xy 64.569098 -287.824926) (xy 64.573058 -287.775872) (xy 64.584835 -287.728088) (xy 64.604126 -287.682812)
			(xy 64.630429 -287.641216) (xy 64.663064 -287.604379) (xy 64.701185 -287.573254) (xy 64.743806 -287.548647)
			(xy 64.789822 -287.531195) (xy 64.838041 -287.521351) (xy 64.887216 -287.51937) (xy 64.936071 -287.525302)
			(xy 64.983342 -287.538994) (xy 65.027804 -287.560092) (xy 65.068307 -287.588048) (xy 65.1038 -287.62214)
			(xy 65.133365 -287.661484) (xy 65.156236 -287.705061) (xy 65.17182 -287.751742) (xy 65.179715 -287.800319)
			(xy 65.18021 -287.824926) (xy 65.519058 -287.824926) (xy 65.523018 -287.775872) (xy 65.534795 -287.728088)
			(xy 65.554086 -287.682812) (xy 65.580389 -287.641216) (xy 65.613024 -287.604379) (xy 65.651145 -287.573254)
			(xy 65.693766 -287.548647) (xy 65.739782 -287.531195) (xy 65.788001 -287.521351) (xy 65.837176 -287.51937)
			(xy 65.886031 -287.525302) (xy 65.933302 -287.538994) (xy 65.977764 -287.560092) (xy 66.018267 -287.588048)
			(xy 66.05376 -287.62214) (xy 66.083325 -287.661484) (xy 66.106196 -287.705061) (xy 66.12178 -287.751742)
			(xy 66.129675 -287.800319) (xy 66.13017 -287.824926) (xy 66.469018 -287.824926) (xy 66.472978 -287.775872)
			(xy 66.484755 -287.728088) (xy 66.504046 -287.682812) (xy 66.530349 -287.641216) (xy 66.562984 -287.604379)
			(xy 66.601105 -287.573254) (xy 66.643726 -287.548647) (xy 66.689742 -287.531195) (xy 66.737961 -287.521351)
			(xy 66.787136 -287.51937) (xy 66.835991 -287.525302) (xy 66.883262 -287.538994) (xy 66.927724 -287.560092)
			(xy 66.968227 -287.588048) (xy 67.00372 -287.62214) (xy 67.033285 -287.661484) (xy 67.056156 -287.705061)
			(xy 67.07174 -287.751742) (xy 67.079635 -287.800319) (xy 67.08013 -287.824926) (xy 67.418978 -287.824926)
			(xy 67.422938 -287.775872) (xy 67.434715 -287.728088) (xy 67.454006 -287.682812) (xy 67.480309 -287.641216)
			(xy 67.512944 -287.604379) (xy 67.551065 -287.573254) (xy 67.593686 -287.548647) (xy 67.639702 -287.531195)
			(xy 67.687921 -287.521351) (xy 67.737096 -287.51937) (xy 67.785951 -287.525302) (xy 67.833222 -287.538994)
			(xy 67.877684 -287.560092) (xy 67.918187 -287.588048) (xy 67.95368 -287.62214) (xy 67.983245 -287.661484)
			(xy 68.006116 -287.705061) (xy 68.0217 -287.751742) (xy 68.029595 -287.800319) (xy 68.03009 -287.824926)
			(xy 68.368938 -287.824926) (xy 68.372898 -287.775872) (xy 68.384675 -287.728088) (xy 68.403966 -287.682812)
			(xy 68.430269 -287.641216) (xy 68.462904 -287.604379) (xy 68.501025 -287.573254) (xy 68.543646 -287.548647)
			(xy 68.589662 -287.531195) (xy 68.637881 -287.521351) (xy 68.687056 -287.51937) (xy 68.735911 -287.525302)
			(xy 68.783182 -287.538994) (xy 68.827644 -287.560092) (xy 68.868147 -287.588048) (xy 68.90364 -287.62214)
			(xy 68.933205 -287.661484) (xy 68.956076 -287.705061) (xy 68.97166 -287.751742) (xy 68.979555 -287.800319)
			(xy 68.98005 -287.824926) (xy 70.269112 -287.824926) (xy 70.273072 -287.775872) (xy 70.284849 -287.728088)
			(xy 70.30414 -287.682812) (xy 70.330443 -287.641216) (xy 70.363078 -287.604379) (xy 70.401199 -287.573254)
			(xy 70.44382 -287.548647) (xy 70.489836 -287.531195) (xy 70.538055 -287.521351) (xy 70.58723 -287.51937)
			(xy 70.636085 -287.525302) (xy 70.683356 -287.538994) (xy 70.727818 -287.560092) (xy 70.768321 -287.588048)
			(xy 70.803814 -287.62214) (xy 70.833379 -287.661484) (xy 70.85625 -287.705061) (xy 70.871834 -287.751742)
			(xy 70.879729 -287.800319) (xy 70.880224 -287.824926) (xy 70.879729 -287.849533) (xy 70.871834 -287.89811)
			(xy 70.85625 -287.944791) (xy 70.833379 -287.988368) (xy 70.803814 -288.027712) (xy 70.768321 -288.061804)
			(xy 70.727818 -288.08976) (xy 70.683356 -288.110858) (xy 70.636085 -288.12455) (xy 70.58723 -288.130482)
			(xy 70.538055 -288.128501) (xy 70.489836 -288.118657) (xy 70.44382 -288.101205) (xy 70.401199 -288.076598)
			(xy 70.363078 -288.045473) (xy 70.330443 -288.008636) (xy 70.30414 -287.96704) (xy 70.284849 -287.921764)
			(xy 70.273072 -287.87398) (xy 70.269112 -287.824926) (xy 68.98005 -287.824926) (xy 68.979555 -287.849533)
			(xy 68.97166 -287.89811) (xy 68.956076 -287.944791) (xy 68.933205 -287.988368) (xy 68.90364 -288.027712)
			(xy 68.868147 -288.061804) (xy 68.827644 -288.08976) (xy 68.783182 -288.110858) (xy 68.735911 -288.12455)
			(xy 68.687056 -288.130482) (xy 68.637881 -288.128501) (xy 68.589662 -288.118657) (xy 68.543646 -288.101205)
			(xy 68.501025 -288.076598) (xy 68.462904 -288.045473) (xy 68.430269 -288.008636) (xy 68.403966 -287.96704)
			(xy 68.384675 -287.921764) (xy 68.372898 -287.87398) (xy 68.368938 -287.824926) (xy 68.03009 -287.824926)
			(xy 68.029595 -287.849533) (xy 68.0217 -287.89811) (xy 68.006116 -287.944791) (xy 67.983245 -287.988368)
			(xy 67.95368 -288.027712) (xy 67.918187 -288.061804) (xy 67.877684 -288.08976) (xy 67.833222 -288.110858)
			(xy 67.785951 -288.12455) (xy 67.737096 -288.130482) (xy 67.687921 -288.128501) (xy 67.639702 -288.118657)
			(xy 67.593686 -288.101205) (xy 67.551065 -288.076598) (xy 67.512944 -288.045473) (xy 67.480309 -288.008636)
			(xy 67.454006 -287.96704) (xy 67.434715 -287.921764) (xy 67.422938 -287.87398) (xy 67.418978 -287.824926)
			(xy 67.08013 -287.824926) (xy 67.079635 -287.849533) (xy 67.07174 -287.89811) (xy 67.056156 -287.944791)
			(xy 67.033285 -287.988368) (xy 67.00372 -288.027712) (xy 66.968227 -288.061804) (xy 66.927724 -288.08976)
			(xy 66.883262 -288.110858) (xy 66.835991 -288.12455) (xy 66.787136 -288.130482) (xy 66.737961 -288.128501)
			(xy 66.689742 -288.118657) (xy 66.643726 -288.101205) (xy 66.601105 -288.076598) (xy 66.562984 -288.045473)
			(xy 66.530349 -288.008636) (xy 66.504046 -287.96704) (xy 66.484755 -287.921764) (xy 66.472978 -287.87398)
			(xy 66.469018 -287.824926) (xy 66.13017 -287.824926) (xy 66.129675 -287.849533) (xy 66.12178 -287.89811)
			(xy 66.106196 -287.944791) (xy 66.083325 -287.988368) (xy 66.05376 -288.027712) (xy 66.018267 -288.061804)
			(xy 65.977764 -288.08976) (xy 65.933302 -288.110858) (xy 65.886031 -288.12455) (xy 65.837176 -288.130482)
			(xy 65.788001 -288.128501) (xy 65.739782 -288.118657) (xy 65.693766 -288.101205) (xy 65.651145 -288.076598)
			(xy 65.613024 -288.045473) (xy 65.580389 -288.008636) (xy 65.554086 -287.96704) (xy 65.534795 -287.921764)
			(xy 65.523018 -287.87398) (xy 65.519058 -287.824926) (xy 65.18021 -287.824926) (xy 65.179715 -287.849533)
			(xy 65.17182 -287.89811) (xy 65.156236 -287.944791) (xy 65.133365 -287.988368) (xy 65.1038 -288.027712)
			(xy 65.068307 -288.061804) (xy 65.027804 -288.08976) (xy 64.983342 -288.110858) (xy 64.936071 -288.12455)
			(xy 64.887216 -288.130482) (xy 64.838041 -288.128501) (xy 64.789822 -288.118657) (xy 64.743806 -288.101205)
			(xy 64.701185 -288.076598) (xy 64.663064 -288.045473) (xy 64.630429 -288.008636) (xy 64.604126 -287.96704)
			(xy 64.584835 -287.921764) (xy 64.573058 -287.87398) (xy 64.569098 -287.824926) (xy 64.23025 -287.824926)
			(xy 64.229755 -287.849533) (xy 64.22186 -287.89811) (xy 64.206276 -287.944791) (xy 64.183405 -287.988368)
			(xy 64.15384 -288.027712) (xy 64.118347 -288.061804) (xy 64.077844 -288.08976) (xy 64.033382 -288.110858)
			(xy 63.986111 -288.12455) (xy 63.937256 -288.130482) (xy 63.888081 -288.128501) (xy 63.839862 -288.118657)
			(xy 63.793846 -288.101205) (xy 63.751225 -288.076598) (xy 63.713104 -288.045473) (xy 63.680469 -288.008636)
			(xy 63.654166 -287.96704) (xy 63.634875 -287.921764) (xy 63.623098 -287.87398) (xy 63.619138 -287.824926)
			(xy 63.28029 -287.824926) (xy 63.279795 -287.849533) (xy 63.2719 -287.89811) (xy 63.256316 -287.944791)
			(xy 63.233445 -287.988368) (xy 63.20388 -288.027712) (xy 63.168387 -288.061804) (xy 63.127884 -288.08976)
			(xy 63.083422 -288.110858) (xy 63.036151 -288.12455) (xy 62.987296 -288.130482) (xy 62.938121 -288.128501)
			(xy 62.889902 -288.118657) (xy 62.843886 -288.101205) (xy 62.801265 -288.076598) (xy 62.763144 -288.045473)
			(xy 62.730509 -288.008636) (xy 62.704206 -287.96704) (xy 62.684915 -287.921764) (xy 62.673138 -287.87398)
			(xy 62.669178 -287.824926) (xy 62.330076 -287.824926) (xy 62.329581 -287.849533) (xy 62.321686 -287.89811)
			(xy 62.306102 -287.944791) (xy 62.283231 -287.988368) (xy 62.253666 -288.027712) (xy 62.218173 -288.061804)
			(xy 62.17767 -288.08976) (xy 62.133208 -288.110858) (xy 62.085937 -288.12455) (xy 62.037082 -288.130482)
			(xy 61.987907 -288.128501) (xy 61.939688 -288.118657) (xy 61.893672 -288.101205) (xy 61.851051 -288.076598)
			(xy 61.81293 -288.045473) (xy 61.780295 -288.008636) (xy 61.753992 -287.96704) (xy 61.734701 -287.921764)
			(xy 61.722924 -287.87398) (xy 61.718964 -287.824926) (xy 61.380116 -287.824926) (xy 61.379621 -287.849533)
			(xy 61.371726 -287.89811) (xy 61.356142 -287.944791) (xy 61.333271 -287.988368) (xy 61.303706 -288.027712)
			(xy 61.268213 -288.061804) (xy 61.22771 -288.08976) (xy 61.183248 -288.110858) (xy 61.135977 -288.12455)
			(xy 61.087122 -288.130482) (xy 61.037947 -288.128501) (xy 60.989728 -288.118657) (xy 60.943712 -288.101205)
			(xy 60.901091 -288.076598) (xy 60.86297 -288.045473) (xy 60.830335 -288.008636) (xy 60.804032 -287.96704)
			(xy 60.784741 -287.921764) (xy 60.772964 -287.87398) (xy 60.769004 -287.824926) (xy 60.421183 -287.824926)
			(xy 60.421766 -287.826672) (xy 60.429661 -287.875249) (xy 60.430156 -287.899856) (xy 60.429661 -287.924463)
			(xy 60.421766 -287.97304) (xy 60.406182 -288.019721) (xy 60.383311 -288.063298) (xy 60.353746 -288.102642)
			(xy 60.318253 -288.136734) (xy 60.27775 -288.16469) (xy 60.233288 -288.185788) (xy 60.186017 -288.19948)
			(xy 60.137162 -288.205412) (xy 60.087987 -288.203431) (xy 60.039768 -288.193587) (xy 59.993752 -288.176135)
			(xy 59.951131 -288.151528) (xy 59.91301 -288.120403) (xy 59.880375 -288.083566) (xy 59.854072 -288.04197)
			(xy 59.834781 -287.996694) (xy 59.823004 -287.94891) (xy 59.819044 -287.899856) (xy 58.480888 -287.899856)
			(xy 58.478718 -287.902744) (xy 58.443225 -287.936836) (xy 58.402722 -287.964792) (xy 58.35826 -287.98589)
			(xy 58.310989 -287.999582) (xy 58.262134 -288.005514) (xy 58.212959 -288.003533) (xy 58.16474 -287.993689)
			(xy 58.118724 -287.976237) (xy 58.076103 -287.95163) (xy 58.037982 -287.920505) (xy 58.005347 -287.883668)
			(xy 57.979044 -287.842072) (xy 57.959753 -287.796796) (xy 57.947976 -287.749012) (xy 57.944016 -287.699958)
			(xy 57.553624 -287.699958) (xy 57.556302 -287.705061) (xy 57.571886 -287.751742) (xy 57.579781 -287.800319)
			(xy 57.580276 -287.824926) (xy 57.579781 -287.849533) (xy 57.571886 -287.89811) (xy 57.556302 -287.944791)
			(xy 57.533431 -287.988368) (xy 57.503866 -288.027712) (xy 57.468373 -288.061804) (xy 57.42787 -288.08976)
			(xy 57.383408 -288.110858) (xy 57.336137 -288.12455) (xy 57.287282 -288.130482) (xy 57.238107 -288.128501)
			(xy 57.189888 -288.118657) (xy 57.143872 -288.101205) (xy 57.101251 -288.076598) (xy 57.06313 -288.045473)
			(xy 57.030495 -288.008636) (xy 57.004192 -287.96704) (xy 56.984901 -287.921764) (xy 56.973124 -287.87398)
			(xy 56.969164 -287.824926) (xy 56.630062 -287.824926) (xy 56.629567 -287.849533) (xy 56.621672 -287.89811)
			(xy 56.606088 -287.944791) (xy 56.583217 -287.988368) (xy 56.553652 -288.027712) (xy 56.518159 -288.061804)
			(xy 56.477656 -288.08976) (xy 56.433194 -288.110858) (xy 56.385923 -288.12455) (xy 56.337068 -288.130482)
			(xy 56.287893 -288.128501) (xy 56.239674 -288.118657) (xy 56.193658 -288.101205) (xy 56.151037 -288.076598)
			(xy 56.112916 -288.045473) (xy 56.080281 -288.008636) (xy 56.053978 -287.96704) (xy 56.034687 -287.921764)
			(xy 56.02291 -287.87398) (xy 56.01895 -287.824926) (xy 55.680102 -287.824926) (xy 55.679607 -287.849533)
			(xy 55.671712 -287.89811) (xy 55.656128 -287.944791) (xy 55.633257 -287.988368) (xy 55.603692 -288.027712)
			(xy 55.568199 -288.061804) (xy 55.527696 -288.08976) (xy 55.483234 -288.110858) (xy 55.435963 -288.12455)
			(xy 55.387108 -288.130482) (xy 55.337933 -288.128501) (xy 55.289714 -288.118657) (xy 55.243698 -288.101205)
			(xy 55.201077 -288.076598) (xy 55.162956 -288.045473) (xy 55.130321 -288.008636) (xy 55.104018 -287.96704)
			(xy 55.084727 -287.921764) (xy 55.07295 -287.87398) (xy 55.06899 -287.824926) (xy 54.730142 -287.824926)
			(xy 54.729647 -287.849533) (xy 54.721752 -287.89811) (xy 54.706168 -287.944791) (xy 54.683297 -287.988368)
			(xy 54.653732 -288.027712) (xy 54.618239 -288.061804) (xy 54.577736 -288.08976) (xy 54.533274 -288.110858)
			(xy 54.486003 -288.12455) (xy 54.437148 -288.130482) (xy 54.387973 -288.128501) (xy 54.339754 -288.118657)
			(xy 54.293738 -288.101205) (xy 54.251117 -288.076598) (xy 54.212996 -288.045473) (xy 54.180361 -288.008636)
			(xy 54.154058 -287.96704) (xy 54.134767 -287.921764) (xy 54.12299 -287.87398) (xy 54.11903 -287.824926)
			(xy 53.780182 -287.824926) (xy 53.779687 -287.849533) (xy 53.771792 -287.89811) (xy 53.756208 -287.944791)
			(xy 53.733337 -287.988368) (xy 53.703772 -288.027712) (xy 53.668279 -288.061804) (xy 53.627776 -288.08976)
			(xy 53.583314 -288.110858) (xy 53.536043 -288.12455) (xy 53.487188 -288.130482) (xy 53.438013 -288.128501)
			(xy 53.389794 -288.118657) (xy 53.343778 -288.101205) (xy 53.301157 -288.076598) (xy 53.263036 -288.045473)
			(xy 53.230401 -288.008636) (xy 53.204098 -287.96704) (xy 53.184807 -287.921764) (xy 53.17303 -287.87398)
			(xy 53.16907 -287.824926) (xy 52.830222 -287.824926) (xy 52.829727 -287.849533) (xy 52.821832 -287.89811)
			(xy 52.806248 -287.944791) (xy 52.783377 -287.988368) (xy 52.753812 -288.027712) (xy 52.718319 -288.061804)
			(xy 52.677816 -288.08976) (xy 52.633354 -288.110858) (xy 52.586083 -288.12455) (xy 52.537228 -288.130482)
			(xy 52.488053 -288.128501) (xy 52.439834 -288.118657) (xy 52.393818 -288.101205) (xy 52.351197 -288.076598)
			(xy 52.313076 -288.045473) (xy 52.280441 -288.008636) (xy 52.254138 -287.96704) (xy 52.234847 -287.921764)
			(xy 52.22307 -287.87398) (xy 52.21911 -287.824926) (xy 51.880262 -287.824926) (xy 51.879767 -287.849533)
			(xy 51.871872 -287.89811) (xy 51.856288 -287.944791) (xy 51.833417 -287.988368) (xy 51.803852 -288.027712)
			(xy 51.768359 -288.061804) (xy 51.727856 -288.08976) (xy 51.683394 -288.110858) (xy 51.636123 -288.12455)
			(xy 51.587268 -288.130482) (xy 51.538093 -288.128501) (xy 51.489874 -288.118657) (xy 51.443858 -288.101205)
			(xy 51.401237 -288.076598) (xy 51.363116 -288.045473) (xy 51.330481 -288.008636) (xy 51.304178 -287.96704)
			(xy 51.284887 -287.921764) (xy 51.27311 -287.87398) (xy 51.26915 -287.824926) (xy 50.930302 -287.824926)
			(xy 50.929807 -287.849533) (xy 50.921912 -287.89811) (xy 50.906328 -287.944791) (xy 50.883457 -287.988368)
			(xy 50.853892 -288.027712) (xy 50.818399 -288.061804) (xy 50.777896 -288.08976) (xy 50.733434 -288.110858)
			(xy 50.686163 -288.12455) (xy 50.637308 -288.130482) (xy 50.588133 -288.128501) (xy 50.539914 -288.118657)
			(xy 50.493898 -288.101205) (xy 50.451277 -288.076598) (xy 50.413156 -288.045473) (xy 50.380521 -288.008636)
			(xy 50.354218 -287.96704) (xy 50.334927 -287.921764) (xy 50.32315 -287.87398) (xy 50.31919 -287.824926)
			(xy 49.980088 -287.824926) (xy 49.979593 -287.849533) (xy 49.971698 -287.89811) (xy 49.956114 -287.944791)
			(xy 49.933243 -287.988368) (xy 49.903678 -288.027712) (xy 49.868185 -288.061804) (xy 49.827682 -288.08976)
			(xy 49.78322 -288.110858) (xy 49.735949 -288.12455) (xy 49.687094 -288.130482) (xy 49.637919 -288.128501)
			(xy 49.5897 -288.118657) (xy 49.543684 -288.101205) (xy 49.501063 -288.076598) (xy 49.462942 -288.045473)
			(xy 49.430307 -288.008636) (xy 49.404004 -287.96704) (xy 49.384713 -287.921764) (xy 49.372936 -287.87398)
			(xy 49.368976 -287.824926) (xy 49.030128 -287.824926) (xy 49.029633 -287.849533) (xy 49.021738 -287.89811)
			(xy 49.006154 -287.944791) (xy 48.983283 -287.988368) (xy 48.953718 -288.027712) (xy 48.918225 -288.061804)
			(xy 48.877722 -288.08976) (xy 48.83326 -288.110858) (xy 48.785989 -288.12455) (xy 48.737134 -288.130482)
			(xy 48.687959 -288.128501) (xy 48.63974 -288.118657) (xy 48.593724 -288.101205) (xy 48.551103 -288.076598)
			(xy 48.512982 -288.045473) (xy 48.480347 -288.008636) (xy 48.454044 -287.96704) (xy 48.434753 -287.921764)
			(xy 48.422976 -287.87398) (xy 48.419016 -287.824926) (xy 48.080168 -287.824926) (xy 48.079673 -287.849533)
			(xy 48.071778 -287.89811) (xy 48.056194 -287.944791) (xy 48.033323 -287.988368) (xy 48.003758 -288.027712)
			(xy 47.968265 -288.061804) (xy 47.927762 -288.08976) (xy 47.8833 -288.110858) (xy 47.836029 -288.12455)
			(xy 47.787174 -288.130482) (xy 47.737999 -288.128501) (xy 47.68978 -288.118657) (xy 47.643764 -288.101205)
			(xy 47.601143 -288.076598) (xy 47.563022 -288.045473) (xy 47.530387 -288.008636) (xy 47.504084 -287.96704)
			(xy 47.484793 -287.921764) (xy 47.473016 -287.87398) (xy 47.469056 -287.824926) (xy 47.130208 -287.824926)
			(xy 47.129713 -287.849533) (xy 47.121818 -287.89811) (xy 47.106234 -287.944791) (xy 47.083363 -287.988368)
			(xy 47.053798 -288.027712) (xy 47.018305 -288.061804) (xy 46.977802 -288.08976) (xy 46.93334 -288.110858)
			(xy 46.886069 -288.12455) (xy 46.837214 -288.130482) (xy 46.788039 -288.128501) (xy 46.73982 -288.118657)
			(xy 46.693804 -288.101205) (xy 46.651183 -288.076598) (xy 46.613062 -288.045473) (xy 46.580427 -288.008636)
			(xy 46.554124 -287.96704) (xy 46.534833 -287.921764) (xy 46.523056 -287.87398) (xy 46.519096 -287.824926)
			(xy 46.180248 -287.824926) (xy 46.179753 -287.849533) (xy 46.171858 -287.89811) (xy 46.156274 -287.944791)
			(xy 46.133403 -287.988368) (xy 46.103838 -288.027712) (xy 46.068345 -288.061804) (xy 46.027842 -288.08976)
			(xy 45.98338 -288.110858) (xy 45.936109 -288.12455) (xy 45.887254 -288.130482) (xy 45.838079 -288.128501)
			(xy 45.78986 -288.118657) (xy 45.743844 -288.101205) (xy 45.701223 -288.076598) (xy 45.663102 -288.045473)
			(xy 45.630467 -288.008636) (xy 45.604164 -287.96704) (xy 45.584873 -287.921764) (xy 45.573096 -287.87398)
			(xy 45.569136 -287.824926) (xy 45.230288 -287.824926) (xy 45.229793 -287.849533) (xy 45.221898 -287.89811)
			(xy 45.206314 -287.944791) (xy 45.183443 -287.988368) (xy 45.153878 -288.027712) (xy 45.118385 -288.061804)
			(xy 45.077882 -288.08976) (xy 45.03342 -288.110858) (xy 44.986149 -288.12455) (xy 44.937294 -288.130482)
			(xy 44.888119 -288.128501) (xy 44.8399 -288.118657) (xy 44.793884 -288.101205) (xy 44.751263 -288.076598)
			(xy 44.713142 -288.045473) (xy 44.680507 -288.008636) (xy 44.654204 -287.96704) (xy 44.634913 -287.921764)
			(xy 44.623136 -287.87398) (xy 44.619176 -287.824926) (xy 44.280074 -287.824926) (xy 44.279579 -287.849533)
			(xy 44.271684 -287.89811) (xy 44.2561 -287.944791) (xy 44.233229 -287.988368) (xy 44.203664 -288.027712)
			(xy 44.168171 -288.061804) (xy 44.127668 -288.08976) (xy 44.083206 -288.110858) (xy 44.035935 -288.12455)
			(xy 43.98708 -288.130482) (xy 43.937905 -288.128501) (xy 43.889686 -288.118657) (xy 43.84367 -288.101205)
			(xy 43.801049 -288.076598) (xy 43.762928 -288.045473) (xy 43.730293 -288.008636) (xy 43.70399 -287.96704)
			(xy 43.684699 -287.921764) (xy 43.672922 -287.87398) (xy 43.668962 -287.824926) (xy 43.330114 -287.824926)
			(xy 43.329619 -287.849533) (xy 43.321724 -287.89811) (xy 43.30614 -287.944791) (xy 43.283269 -287.988368)
			(xy 43.253704 -288.027712) (xy 43.218211 -288.061804) (xy 43.177708 -288.08976) (xy 43.133246 -288.110858)
			(xy 43.085975 -288.12455) (xy 43.03712 -288.130482) (xy 42.987945 -288.128501) (xy 42.939726 -288.118657)
			(xy 42.89371 -288.101205) (xy 42.851089 -288.076598) (xy 42.812968 -288.045473) (xy 42.780333 -288.008636)
			(xy 42.75403 -287.96704) (xy 42.734739 -287.921764) (xy 42.722962 -287.87398) (xy 42.719002 -287.824926)
			(xy 42.40527 -287.824926) (xy 42.40527 -287.850406) (xy 42.397134 -287.901778) (xy 42.381063 -287.951246)
			(xy 42.357451 -287.99759) (xy 42.326882 -288.039671) (xy 42.290106 -288.076452) (xy 42.248029 -288.107027)
			(xy 42.201688 -288.130645) (xy 42.152223 -288.146723) (xy 42.100852 -288.154866) (xy 42.074846 -288.15538)
			(xy 41.124886 -288.15538) (xy 41.098881 -288.154833) (xy 41.047512 -288.146695) (xy 40.998048 -288.130621)
			(xy 40.951707 -288.107008) (xy 40.909631 -288.076436) (xy 40.872855 -288.039658) (xy 40.842285 -287.997581)
			(xy 40.818674 -287.951239) (xy 40.802602 -287.901775) (xy 40.794466 -287.850405) (xy 40.479597 -287.850405)
			(xy 40.471844 -287.89811) (xy 40.45626 -287.944791) (xy 40.433389 -287.988368) (xy 40.403824 -288.027712)
			(xy 40.368331 -288.061804) (xy 40.327828 -288.08976) (xy 40.283366 -288.110858) (xy 40.236095 -288.12455)
			(xy 40.18724 -288.130482) (xy 40.138065 -288.128501) (xy 40.089846 -288.118657) (xy 40.04383 -288.101205)
			(xy 40.001209 -288.076598) (xy 39.963088 -288.045473) (xy 39.930453 -288.008636) (xy 39.90415 -287.96704)
			(xy 39.884859 -287.921764) (xy 39.873082 -287.87398) (xy 39.869122 -287.824926) (xy 39.555496 -287.824926)
			(xy 39.555496 -287.850412) (xy 39.547357 -287.901796) (xy 39.53128 -287.951275) (xy 39.50766 -287.997628)
			(xy 39.477079 -288.039716) (xy 39.44029 -288.076501) (xy 39.398199 -288.107078) (xy 39.351843 -288.130693)
			(xy 39.302363 -288.146765) (xy 39.250978 -288.154899) (xy 39.224966 -288.15538) (xy 38.275006 -288.15538)
			(xy 38.248998 -288.154861) (xy 38.197622 -288.146725) (xy 38.148151 -288.130652) (xy 38.101804 -288.107037)
			(xy 38.059722 -288.076463) (xy 38.02294 -288.039683) (xy 37.992366 -287.997601) (xy 37.968751 -287.951254)
			(xy 37.952677 -287.901784) (xy 37.944539 -287.850408) (xy 37.629463 -287.850408) (xy 37.62171 -287.89811)
			(xy 37.606126 -287.944791) (xy 37.583255 -287.988368) (xy 37.55369 -288.027712) (xy 37.518197 -288.061804)
			(xy 37.477694 -288.08976) (xy 37.433232 -288.110858) (xy 37.385961 -288.12455) (xy 37.337106 -288.130482)
			(xy 37.287931 -288.128501) (xy 37.239712 -288.118657) (xy 37.193696 -288.101205) (xy 37.151075 -288.076598)
			(xy 37.112954 -288.045473) (xy 37.080319 -288.008636) (xy 37.054016 -287.96704) (xy 37.034725 -287.921764)
			(xy 37.022948 -287.87398) (xy 37.018988 -287.824926) (xy 36.68014 -287.824926) (xy 36.679645 -287.849533)
			(xy 36.67175 -287.89811) (xy 36.656166 -287.944791) (xy 36.633295 -287.988368) (xy 36.60373 -288.027712)
			(xy 36.568237 -288.061804) (xy 36.527734 -288.08976) (xy 36.483272 -288.110858) (xy 36.436001 -288.12455)
			(xy 36.387146 -288.130482) (xy 36.337971 -288.128501) (xy 36.289752 -288.118657) (xy 36.243736 -288.101205)
			(xy 36.201115 -288.076598) (xy 36.162994 -288.045473) (xy 36.130359 -288.008636) (xy 36.104056 -287.96704)
			(xy 36.084765 -287.921764) (xy 36.072988 -287.87398) (xy 36.069028 -287.824926) (xy 15.064266 -287.824926)
			(xy 15.07913 -287.875546) (xy 15.086887 -287.929497) (xy 15.086887 -287.984003) (xy 15.07913 -288.037954)
			(xy 15.063773 -288.090253) (xy 15.041131 -288.139833) (xy 15.011662 -288.185687) (xy 14.975968 -288.22688)
			(xy 14.972303 -288.230056) (xy 25.811478 -288.230056) (xy 25.815549 -288.174434) (xy 25.827675 -288.119997)
			(xy 25.847598 -288.067906) (xy 25.874894 -288.019271) (xy 25.90898 -287.975128) (xy 25.949129 -287.936419)
			(xy 25.994487 -287.903968) (xy 26.044087 -287.878467) (xy 26.096871 -287.86046) (xy 26.151714 -287.85033)
			(xy 26.207448 -287.848293) (xy 26.262885 -287.854393) (xy 26.316842 -287.868499) (xy 26.368171 -287.890311)
			(xy 26.415777 -287.919365) (xy 26.458645 -287.95504) (xy 26.495862 -287.996577) (xy 26.526635 -288.04309)
			(xy 26.550307 -288.093587) (xy 26.566375 -288.146994) (xy 26.574495 -288.20217) (xy 26.575004 -288.230056)
			(xy 27.296616 -288.230056) (xy 27.300687 -288.174434) (xy 27.312813 -288.119997) (xy 27.332736 -288.067906)
			(xy 27.360032 -288.019271) (xy 27.394118 -287.975128) (xy 27.434267 -287.936419) (xy 27.479625 -287.903968)
			(xy 27.529225 -287.878467) (xy 27.582009 -287.86046) (xy 27.636852 -287.85033) (xy 27.692586 -287.848293)
			(xy 27.748023 -287.854393) (xy 27.80198 -287.868499) (xy 27.853309 -287.890311) (xy 27.900915 -287.919365)
			(xy 27.943783 -287.95504) (xy 27.981 -287.996577) (xy 28.011773 -288.04309) (xy 28.035445 -288.093587)
			(xy 28.051513 -288.146994) (xy 28.059633 -288.20217) (xy 28.060142 -288.230056) (xy 28.059633 -288.257942)
			(xy 28.053457 -288.299906) (xy 73.593972 -288.299906) (xy 73.597932 -288.250852) (xy 73.609709 -288.203068)
			(xy 73.629 -288.157792) (xy 73.655303 -288.116196) (xy 73.687938 -288.079359) (xy 73.726059 -288.048234)
			(xy 73.76868 -288.023627) (xy 73.814696 -288.006175) (xy 73.862915 -287.996331) (xy 73.91209 -287.99435)
			(xy 73.960945 -288.000282) (xy 74.008216 -288.013974) (xy 74.052678 -288.035072) (xy 74.093181 -288.063028)
			(xy 74.128674 -288.09712) (xy 74.158239 -288.136464) (xy 74.18111 -288.180041) (xy 74.196694 -288.226722)
			(xy 74.204589 -288.275299) (xy 74.205084 -288.299906) (xy 74.544186 -288.299906) (xy 74.548146 -288.250852)
			(xy 74.559923 -288.203068) (xy 74.579214 -288.157792) (xy 74.605517 -288.116196) (xy 74.638152 -288.079359)
			(xy 74.676273 -288.048234) (xy 74.718894 -288.023627) (xy 74.76491 -288.006175) (xy 74.813129 -287.996331)
			(xy 74.862304 -287.99435) (xy 74.911159 -288.000282) (xy 74.95843 -288.013974) (xy 75.002892 -288.035072)
			(xy 75.043395 -288.063028) (xy 75.078888 -288.09712) (xy 75.108453 -288.136464) (xy 75.131324 -288.180041)
			(xy 75.146908 -288.226722) (xy 75.154803 -288.275299) (xy 75.155298 -288.299906) (xy 75.494146 -288.299906)
			(xy 75.498106 -288.250852) (xy 75.509883 -288.203068) (xy 75.529174 -288.157792) (xy 75.555477 -288.116196)
			(xy 75.588112 -288.079359) (xy 75.626233 -288.048234) (xy 75.668854 -288.023627) (xy 75.71487 -288.006175)
			(xy 75.763089 -287.996331) (xy 75.812264 -287.99435) (xy 75.861119 -288.000282) (xy 75.90839 -288.013974)
			(xy 75.952852 -288.035072) (xy 75.993355 -288.063028) (xy 76.028848 -288.09712) (xy 76.058413 -288.136464)
			(xy 76.081284 -288.180041) (xy 76.096868 -288.226722) (xy 76.104763 -288.275299) (xy 76.105258 -288.299906)
			(xy 76.104763 -288.324513) (xy 76.104584 -288.325614) (xy 76.423262 -288.325614) (xy 76.423262 -288.274198)
			(xy 76.431305 -288.223416) (xy 76.447193 -288.174517) (xy 76.470536 -288.128705) (xy 76.500757 -288.087109)
			(xy 76.537113 -288.050753) (xy 76.578709 -288.020532) (xy 76.624521 -287.997189) (xy 76.67342 -287.981301)
			(xy 76.724202 -287.973258) (xy 76.775618 -287.973258) (xy 76.8264 -287.981301) (xy 76.875299 -287.997189)
			(xy 76.921111 -288.020532) (xy 76.962707 -288.050753) (xy 76.999063 -288.087109) (xy 77.029284 -288.128705)
			(xy 77.052627 -288.174517) (xy 77.068515 -288.223416) (xy 77.076558 -288.274198) (xy 77.077062 -288.299906)
			(xy 77.076558 -288.325614) (xy 77.373222 -288.325614) (xy 77.373222 -288.274198) (xy 77.381265 -288.223416)
			(xy 77.397153 -288.174517) (xy 77.420496 -288.128705) (xy 77.450717 -288.087109) (xy 77.487073 -288.050753)
			(xy 77.528669 -288.020532) (xy 77.574481 -287.997189) (xy 77.62338 -287.981301) (xy 77.674162 -287.973258)
			(xy 77.725578 -287.973258) (xy 77.77636 -287.981301) (xy 77.825259 -287.997189) (xy 77.871071 -288.020532)
			(xy 77.912667 -288.050753) (xy 77.949023 -288.087109) (xy 77.979244 -288.128705) (xy 78.002587 -288.174517)
			(xy 78.018475 -288.223416) (xy 78.026518 -288.274198) (xy 78.027022 -288.299906) (xy 78.026859 -288.308201)
			(xy 78.344052 -288.308201) (xy 78.346737 -288.258626) (xy 78.357407 -288.210138) (xy 78.375781 -288.164015)
			(xy 78.401375 -288.121473) (xy 78.433515 -288.083632) (xy 78.471354 -288.051489) (xy 78.513894 -288.025892)
			(xy 78.560015 -288.007514) (xy 78.608502 -287.99684) (xy 78.658077 -287.994151) (xy 78.707434 -287.999518)
			(xy 78.755272 -288.0128) (xy 78.800331 -288.033646) (xy 78.841424 -288.061507) (xy 78.877468 -288.09565)
			(xy 78.907514 -288.135174) (xy 78.930769 -288.179039) (xy 78.946621 -288.226088) (xy 78.954652 -288.275082)
			(xy 78.955138 -288.299906) (xy 78.954962 -288.314089) (xy 78.952289 -288.342329) (xy 78.949804 -288.356294)
			(xy 78.947518 -288.36874) (xy 78.954884 -288.392362) (xy 79.032354 -288.469832) (xy 79.055976 -288.477198)
			(xy 79.068422 -288.474912) (xy 79.082388 -288.472437) (xy 79.110628 -288.469764) (xy 79.12481 -288.469578)
			(xy 79.125064 -288.469578) (xy 79.134871 -288.469656) (xy 79.154445 -288.470929) (xy 79.16418 -288.472118)
			(xy 79.176118 -288.473642) (xy 79.198978 -288.465768) (xy 79.272384 -288.389314) (xy 79.279496 -288.366708)
			(xy 79.277464 -288.35477) (xy 79.277464 -288.354262) (xy 79.27533 -288.340838) (xy 79.273038 -288.313752)
			(xy 79.272892 -288.30016) (xy 79.272892 -288.299906) (xy 79.273396 -288.274218) (xy 79.281433 -288.223475)
			(xy 79.297309 -288.174614) (xy 79.320633 -288.128838) (xy 79.35083 -288.087274) (xy 79.387158 -288.050946)
			(xy 79.428722 -288.020749) (xy 79.474498 -287.997425) (xy 79.523359 -287.981549) (xy 79.574102 -287.973512)
			(xy 79.625478 -287.973512) (xy 79.676221 -287.981549) (xy 79.725082 -287.997425) (xy 79.770858 -288.020749)
			(xy 79.812422 -288.050946) (xy 79.84875 -288.087274) (xy 79.878947 -288.128838) (xy 79.902271 -288.174614)
			(xy 79.918147 -288.223475) (xy 79.926184 -288.274218) (xy 79.926688 -288.299906) (xy 79.926688 -288.30016)
			(xy 79.926531 -288.313814) (xy 79.924245 -288.341028) (xy 79.922116 -288.354516) (xy 79.922116 -288.35477)
			(xy 79.920839 -288.366506) (xy 79.927862 -288.389015) (xy 79.935578 -288.39795) (xy 80.000602 -288.465768)
			(xy 80.023462 -288.473642) (xy 80.0354 -288.472118) (xy 80.045199 -288.470925) (xy 80.064899 -288.469657)
			(xy 80.07477 -288.469578) (xy 80.084641 -288.469654) (xy 80.104342 -288.470923) (xy 80.11414 -288.472118)
			(xy 80.126078 -288.473642) (xy 80.148938 -288.465768) (xy 80.222344 -288.389314) (xy 80.229456 -288.366708)
			(xy 80.227424 -288.35477) (xy 80.227424 -288.354262) (xy 80.225291 -288.340838) (xy 80.222998 -288.313752)
			(xy 80.222852 -288.30016) (xy 80.222852 -288.299906) (xy 80.223356 -288.274218) (xy 80.231393 -288.223475)
			(xy 80.247269 -288.174614) (xy 80.270593 -288.128838) (xy 80.30079 -288.087274) (xy 80.337118 -288.050946)
			(xy 80.378682 -288.020749) (xy 80.424458 -287.997425) (xy 80.473319 -287.981549) (xy 80.524062 -287.973512)
			(xy 80.575438 -287.973512) (xy 80.626181 -287.981549) (xy 80.675042 -287.997425) (xy 80.720818 -288.020749)
			(xy 80.762382 -288.050946) (xy 80.79871 -288.087274) (xy 80.828907 -288.128838) (xy 80.852231 -288.174614)
			(xy 80.868107 -288.223475) (xy 80.876144 -288.274218) (xy 80.876648 -288.299906) (xy 80.876648 -288.30016)
			(xy 80.876491 -288.313814) (xy 80.874204 -288.341028) (xy 80.872076 -288.354516) (xy 80.87076 -288.366313)
			(xy 80.877787 -288.388958) (xy 80.885538 -288.39795) (xy 80.942434 -288.456878) (xy 80.951152 -288.465074)
			(xy 80.973683 -288.473032) (xy 80.985614 -288.472118) (xy 80.99535 -288.470941) (xy 81.014923 -288.469667)
			(xy 81.02473 -288.469578) (xy 81.024984 -288.469578) (xy 81.039167 -288.469757) (xy 81.067407 -288.472428)
			(xy 81.081372 -288.474912) (xy 81.093818 -288.477198) (xy 81.11744 -288.469832) (xy 81.19491 -288.392362)
			(xy 81.202276 -288.36874) (xy 81.19999 -288.356294) (xy 81.197516 -288.342328) (xy 81.194843 -288.314088)
			(xy 81.194656 -288.299906) (xy 81.195178 -288.274651) (xy 81.203491 -288.224829) (xy 81.219892 -288.177055)
			(xy 81.243933 -288.132632) (xy 81.274957 -288.092772) (xy 81.312119 -288.058562) (xy 81.354405 -288.030936)
			(xy 81.400661 -288.010646) (xy 81.449626 -287.998246) (xy 81.499964 -287.994075) (xy 81.550302 -287.998246)
			(xy 81.599267 -288.010646) (xy 81.645523 -288.030936) (xy 81.687809 -288.058562) (xy 81.724971 -288.092772)
			(xy 81.755995 -288.132632) (xy 81.780036 -288.177055) (xy 81.796437 -288.224829) (xy 81.80475 -288.274651)
			(xy 81.805272 -288.299906) (xy 81.805097 -288.314089) (xy 81.802424 -288.342329) (xy 81.799938 -288.356294)
			(xy 81.797652 -288.36874) (xy 81.805018 -288.392362) (xy 81.882488 -288.469832) (xy 81.90611 -288.477198)
			(xy 81.918556 -288.474912) (xy 81.932521 -288.472432) (xy 81.960761 -288.469763) (xy 81.974944 -288.469578)
			(xy 81.989127 -288.469763) (xy 82.017367 -288.472429) (xy 82.031332 -288.474912) (xy 82.043778 -288.477198)
			(xy 82.0674 -288.469832) (xy 82.14487 -288.392362) (xy 82.152236 -288.36874) (xy 82.14995 -288.356294)
			(xy 82.147477 -288.342328) (xy 82.144803 -288.314088) (xy 82.144616 -288.299906) (xy 82.145138 -288.274651)
			(xy 82.153451 -288.224829) (xy 82.169852 -288.177055) (xy 82.193893 -288.132632) (xy 82.224917 -288.092772)
			(xy 82.262079 -288.058562) (xy 82.304365 -288.030936) (xy 82.350621 -288.010646) (xy 82.399586 -287.998246)
			(xy 82.449924 -287.994075) (xy 82.500262 -287.998246) (xy 82.549227 -288.010646) (xy 82.595483 -288.030936)
			(xy 82.637769 -288.058562) (xy 82.674931 -288.092772) (xy 82.705955 -288.132632) (xy 82.729996 -288.177055)
			(xy 82.746397 -288.224829) (xy 82.75471 -288.274651) (xy 82.755232 -288.299906) (xy 82.755056 -288.314089)
			(xy 82.752383 -288.342329) (xy 82.749898 -288.356294) (xy 82.747612 -288.36874) (xy 82.754978 -288.392362)
			(xy 82.832448 -288.469832) (xy 82.85607 -288.477198) (xy 82.868516 -288.474912) (xy 82.882482 -288.472437)
			(xy 82.910722 -288.469764) (xy 82.924904 -288.469578) (xy 82.949725 -288.470082) (xy 82.998712 -288.478114)
			(xy 83.045755 -288.493965) (xy 83.089613 -288.517218) (xy 83.129132 -288.547261) (xy 83.163269 -288.583301)
			(xy 83.191127 -288.624389) (xy 83.21197 -288.669443) (xy 83.225249 -288.717275) (xy 83.230615 -288.766626)
			(xy 83.227926 -288.816194) (xy 83.217254 -288.864675) (xy 83.198878 -288.91079) (xy 83.173284 -288.953325)
			(xy 83.141146 -288.991159) (xy 83.10331 -289.023295) (xy 83.060774 -289.048886) (xy 83.014658 -289.067259)
			(xy 82.966176 -289.077929) (xy 82.916608 -289.080615) (xy 82.867257 -289.075246) (xy 82.819426 -289.061963)
			(xy 82.774373 -289.041118) (xy 82.733287 -289.013258) (xy 82.697249 -288.979118) (xy 82.667209 -288.939598)
			(xy 82.643958 -288.895738) (xy 82.62811 -288.848695) (xy 82.620081 -288.799707) (xy 82.619596 -288.774886)
			(xy 82.619771 -288.760703) (xy 82.622444 -288.732463) (xy 82.62493 -288.718498) (xy 82.627216 -288.706052)
			(xy 82.61985 -288.68243) (xy 82.54238 -288.60496) (xy 82.518758 -288.597594) (xy 82.506312 -288.59988)
			(xy 82.492345 -288.602351) (xy 82.464106 -288.605026) (xy 82.449924 -288.605214) (xy 82.435741 -288.605034)
			(xy 82.407501 -288.602364) (xy 82.393536 -288.59988) (xy 82.38109 -288.597594) (xy 82.357468 -288.60496)
			(xy 82.279998 -288.68243) (xy 82.272632 -288.706052) (xy 82.274918 -288.718498) (xy 82.27739 -288.732465)
			(xy 82.280065 -288.760704) (xy 82.280252 -288.774886) (xy 82.27973 -288.800141) (xy 82.271417 -288.849963)
			(xy 82.255016 -288.897737) (xy 82.230975 -288.94216) (xy 82.199951 -288.98202) (xy 82.162789 -289.01623)
			(xy 82.120503 -289.043856) (xy 82.074247 -289.064146) (xy 82.025282 -289.076546) (xy 81.974944 -289.080717)
			(xy 81.924606 -289.076546) (xy 81.875641 -289.064146) (xy 81.829385 -289.043856) (xy 81.787099 -289.01623)
			(xy 81.749937 -288.98202) (xy 81.718913 -288.94216) (xy 81.694872 -288.897737) (xy 81.678471 -288.849963)
			(xy 81.670158 -288.800141) (xy 81.669636 -288.774886) (xy 81.66981 -288.760703) (xy 81.672484 -288.732463)
			(xy 81.67497 -288.718498) (xy 81.677256 -288.706052) (xy 81.66989 -288.68243) (xy 81.59242 -288.60496)
			(xy 81.568798 -288.597594) (xy 81.556352 -288.59988) (xy 81.542387 -288.602359) (xy 81.514147 -288.605029)
			(xy 81.499964 -288.605214) (xy 81.485781 -288.605042) (xy 81.457541 -288.602367) (xy 81.443576 -288.59988)
			(xy 81.43113 -288.597594) (xy 81.407508 -288.60496) (xy 81.330038 -288.68243) (xy 81.322672 -288.706052)
			(xy 81.324958 -288.718498) (xy 81.32743 -288.732465) (xy 81.330105 -288.760704) (xy 81.330292 -288.774886)
			(xy 81.32977 -288.800141) (xy 81.321457 -288.849963) (xy 81.305056 -288.897737) (xy 81.281015 -288.94216)
			(xy 81.249991 -288.98202) (xy 81.212829 -289.01623) (xy 81.170543 -289.043856) (xy 81.124287 -289.064146)
			(xy 81.075322 -289.076546) (xy 81.024984 -289.080717) (xy 80.974646 -289.076546) (xy 80.925681 -289.064146)
			(xy 80.879425 -289.043856) (xy 80.837139 -289.01623) (xy 80.799977 -288.98202) (xy 80.768953 -288.94216)
			(xy 80.744912 -288.897737) (xy 80.728511 -288.849963) (xy 80.720198 -288.800141) (xy 80.719676 -288.774886)
			(xy 80.719676 -288.774632) (xy 80.719754 -288.764825) (xy 80.721027 -288.745251) (xy 80.722216 -288.735516)
			(xy 80.723119 -288.723589) (xy 80.715155 -288.701065) (xy 80.706976 -288.692336) (xy 80.648302 -288.635694)
			(xy 80.639209 -288.627856) (xy 80.616284 -288.620836) (xy 80.60436 -288.622232) (xy 80.590873 -288.624375)
			(xy 80.563659 -288.626666) (xy 80.550004 -288.626804) (xy 80.549496 -288.626804) (xy 80.535841 -288.626653)
			(xy 80.508628 -288.624362) (xy 80.49514 -288.622232) (xy 80.494886 -288.622232) (xy 80.483149 -288.620986)
			(xy 80.460643 -288.627987) (xy 80.451706 -288.635694) (xy 80.383888 -288.700718) (xy 80.376014 -288.723578)
			(xy 80.377538 -288.735516) (xy 80.378715 -288.745252) (xy 80.379989 -288.764825) (xy 80.380078 -288.774632)
			(xy 80.380078 -288.774886) (xy 80.379556 -288.800141) (xy 80.371243 -288.849963) (xy 80.354842 -288.897737)
			(xy 80.330801 -288.94216) (xy 80.299777 -288.98202) (xy 80.262615 -289.01623) (xy 80.220329 -289.043856)
			(xy 80.174073 -289.064146) (xy 80.125108 -289.076546) (xy 80.07477 -289.080717) (xy 80.024432 -289.076546)
			(xy 79.975467 -289.064146) (xy 79.929211 -289.043856) (xy 79.886925 -289.01623) (xy 79.849763 -288.98202)
			(xy 79.818739 -288.94216) (xy 79.794698 -288.897737) (xy 79.778297 -288.849963) (xy 79.769984 -288.800141)
			(xy 79.769462 -288.774886) (xy 79.769462 -288.774632) (xy 79.76954 -288.764825) (xy 79.770813 -288.745251)
			(xy 79.772002 -288.735516) (xy 79.773526 -288.723578) (xy 79.765652 -288.700718) (xy 79.689198 -288.627312)
			(xy 79.666592 -288.6202) (xy 79.654654 -288.622232) (xy 79.654146 -288.622232) (xy 79.640722 -288.624368)
			(xy 79.613636 -288.626659) (xy 79.600044 -288.626804) (xy 79.599536 -288.626804) (xy 79.585882 -288.626648)
			(xy 79.558668 -288.624361) (xy 79.54518 -288.622232) (xy 79.544926 -288.622232) (xy 79.533191 -288.620949)
			(xy 79.51068 -288.627976) (xy 79.501746 -288.635694) (xy 79.433928 -288.700718) (xy 79.426054 -288.723578)
			(xy 79.427578 -288.735516) (xy 79.428755 -288.745252) (xy 79.430029 -288.764825) (xy 79.430118 -288.774632)
			(xy 79.430118 -288.774886) (xy 79.429596 -288.800141) (xy 79.421283 -288.849963) (xy 79.404882 -288.897737)
			(xy 79.380841 -288.94216) (xy 79.349817 -288.98202) (xy 79.312655 -289.01623) (xy 79.270369 -289.043856)
			(xy 79.224113 -289.064146) (xy 79.175148 -289.076546) (xy 79.12481 -289.080717) (xy 79.074472 -289.076546)
			(xy 79.025507 -289.064146) (xy 78.979251 -289.043856) (xy 78.936965 -289.01623) (xy 78.899803 -288.98202)
			(xy 78.868779 -288.94216) (xy 78.844738 -288.897737) (xy 78.828337 -288.849963) (xy 78.820024 -288.800141)
			(xy 78.819502 -288.774886) (xy 78.819677 -288.760703) (xy 78.82235 -288.732463) (xy 78.824836 -288.718498)
			(xy 78.827122 -288.706052) (xy 78.819756 -288.68243) (xy 78.742286 -288.60496) (xy 78.718664 -288.597594)
			(xy 78.706218 -288.59988) (xy 78.692253 -288.602364) (xy 78.664013 -288.605031) (xy 78.64983 -288.605214)
			(xy 78.625006 -288.604754) (xy 78.576012 -288.596727) (xy 78.528961 -288.580879) (xy 78.485095 -288.557627)
			(xy 78.445568 -288.527584) (xy 78.411422 -288.491543) (xy 78.383558 -288.450452) (xy 78.362708 -288.405394)
			(xy 78.349423 -288.357557) (xy 78.344052 -288.308201) (xy 78.026859 -288.308201) (xy 78.026518 -288.325614)
			(xy 78.018475 -288.376396) (xy 78.002587 -288.425295) (xy 77.979244 -288.471107) (xy 77.949023 -288.512703)
			(xy 77.912667 -288.549059) (xy 77.871071 -288.57928) (xy 77.825259 -288.602623) (xy 77.77636 -288.618511)
			(xy 77.725578 -288.626554) (xy 77.674162 -288.626554) (xy 77.62338 -288.618511) (xy 77.574481 -288.602623)
			(xy 77.528669 -288.57928) (xy 77.487073 -288.549059) (xy 77.450717 -288.512703) (xy 77.420496 -288.471107)
			(xy 77.397153 -288.425295) (xy 77.381265 -288.376396) (xy 77.373222 -288.325614) (xy 77.076558 -288.325614)
			(xy 77.068515 -288.376396) (xy 77.052627 -288.425295) (xy 77.029284 -288.471107) (xy 76.999063 -288.512703)
			(xy 76.962707 -288.549059) (xy 76.921111 -288.57928) (xy 76.875299 -288.602623) (xy 76.8264 -288.618511)
			(xy 76.775618 -288.626554) (xy 76.724202 -288.626554) (xy 76.67342 -288.618511) (xy 76.624521 -288.602623)
			(xy 76.578709 -288.57928) (xy 76.537113 -288.549059) (xy 76.500757 -288.512703) (xy 76.470536 -288.471107)
			(xy 76.447193 -288.425295) (xy 76.431305 -288.376396) (xy 76.423262 -288.325614) (xy 76.104584 -288.325614)
			(xy 76.096868 -288.37309) (xy 76.081284 -288.419771) (xy 76.058413 -288.463348) (xy 76.028848 -288.502692)
			(xy 75.993355 -288.536784) (xy 75.952852 -288.56474) (xy 75.90839 -288.585838) (xy 75.861119 -288.59953)
			(xy 75.812264 -288.605462) (xy 75.763089 -288.603481) (xy 75.71487 -288.593637) (xy 75.668854 -288.576185)
			(xy 75.626233 -288.551578) (xy 75.588112 -288.520453) (xy 75.555477 -288.483616) (xy 75.529174 -288.44202)
			(xy 75.509883 -288.396744) (xy 75.498106 -288.34896) (xy 75.494146 -288.299906) (xy 75.155298 -288.299906)
			(xy 75.154803 -288.324513) (xy 75.146908 -288.37309) (xy 75.131324 -288.419771) (xy 75.108453 -288.463348)
			(xy 75.078888 -288.502692) (xy 75.043395 -288.536784) (xy 75.002892 -288.56474) (xy 74.95843 -288.585838)
			(xy 74.911159 -288.59953) (xy 74.862304 -288.605462) (xy 74.813129 -288.603481) (xy 74.76491 -288.593637)
			(xy 74.718894 -288.576185) (xy 74.676273 -288.551578) (xy 74.638152 -288.520453) (xy 74.605517 -288.483616)
			(xy 74.579214 -288.44202) (xy 74.559923 -288.396744) (xy 74.548146 -288.34896) (xy 74.544186 -288.299906)
			(xy 74.205084 -288.299906) (xy 74.204589 -288.324513) (xy 74.196694 -288.37309) (xy 74.18111 -288.419771)
			(xy 74.158239 -288.463348) (xy 74.128674 -288.502692) (xy 74.093181 -288.536784) (xy 74.052678 -288.56474)
			(xy 74.008216 -288.585838) (xy 73.960945 -288.59953) (xy 73.91209 -288.605462) (xy 73.862915 -288.603481)
			(xy 73.814696 -288.593637) (xy 73.76868 -288.576185) (xy 73.726059 -288.551578) (xy 73.687938 -288.520453)
			(xy 73.655303 -288.483616) (xy 73.629 -288.44202) (xy 73.609709 -288.396744) (xy 73.597932 -288.34896)
			(xy 73.593972 -288.299906) (xy 28.053457 -288.299906) (xy 28.051513 -288.313118) (xy 28.035445 -288.366525)
			(xy 28.011773 -288.417022) (xy 27.981 -288.463535) (xy 27.943783 -288.505072) (xy 27.900915 -288.540747)
			(xy 27.853309 -288.569801) (xy 27.80198 -288.591613) (xy 27.748023 -288.605719) (xy 27.692586 -288.611819)
			(xy 27.636852 -288.609782) (xy 27.582009 -288.599652) (xy 27.529225 -288.581645) (xy 27.479625 -288.556144)
			(xy 27.434267 -288.523693) (xy 27.394118 -288.484984) (xy 27.360032 -288.440841) (xy 27.332736 -288.392206)
			(xy 27.312813 -288.340115) (xy 27.300687 -288.285678) (xy 27.296616 -288.230056) (xy 26.575004 -288.230056)
			(xy 26.574495 -288.257942) (xy 26.566375 -288.313118) (xy 26.550307 -288.366525) (xy 26.526635 -288.417022)
			(xy 26.495862 -288.463535) (xy 26.458645 -288.505072) (xy 26.415777 -288.540747) (xy 26.368171 -288.569801)
			(xy 26.316842 -288.591613) (xy 26.262885 -288.605719) (xy 26.207448 -288.611819) (xy 26.151714 -288.609782)
			(xy 26.096871 -288.599652) (xy 26.044087 -288.581645) (xy 25.994487 -288.556144) (xy 25.949129 -288.523693)
			(xy 25.90898 -288.484984) (xy 25.874894 -288.440841) (xy 25.847598 -288.392206) (xy 25.827675 -288.340115)
			(xy 25.815549 -288.285678) (xy 25.811478 -288.230056) (xy 14.972303 -288.230056) (xy 14.934775 -288.262573)
			(xy 14.888921 -288.292042) (xy 14.839341 -288.314684) (xy 14.787043 -288.33004) (xy 14.733091 -288.337797)
			(xy 14.705838 -288.33826) (xy 14.678468 -288.337781) (xy 14.624289 -288.329968) (xy 14.571786 -288.314482)
			(xy 14.522039 -288.291643) (xy 14.476072 -288.261921) (xy 14.45514 -288.24428) (xy 14.454886 -288.244026)
			(xy 14.447814 -288.238419) (xy 14.430886 -288.232186) (xy 14.421866 -288.231834) (xy 14.35481 -288.231834)
			(xy 14.345793 -288.232189) (xy 14.328876 -288.238437) (xy 14.32179 -288.244026) (xy 14.32179 -288.24428)
			(xy 14.321536 -288.24428) (xy 14.300599 -288.261913) (xy 14.254628 -288.291626) (xy 14.204881 -288.314464)
			(xy 14.152382 -288.329956) (xy 14.098207 -288.337785) (xy 14.070838 -288.33826) (xy 14.043587 -288.33777)
			(xy 13.98964 -288.330013) (xy 13.937346 -288.314658) (xy 13.887769 -288.292017) (xy 13.841919 -288.262551)
			(xy 13.800729 -288.226859) (xy 13.765038 -288.18567) (xy 13.735572 -288.139819) (xy 13.712931 -288.090243)
			(xy 13.697576 -288.037948) (xy 13.68982 -287.984001) (xy 13.346987 -287.984001) (xy 13.346987 -287.984003)
			(xy 13.33923 -288.037954) (xy 13.323873 -288.090253) (xy 13.301231 -288.139833) (xy 13.271762 -288.185687)
			(xy 13.236068 -288.22688) (xy 13.194875 -288.262573) (xy 13.149021 -288.292042) (xy 13.099441 -288.314684)
			(xy 13.047143 -288.33004) (xy 12.993191 -288.337797) (xy 12.965938 -288.33826) (xy 12.938568 -288.337781)
			(xy 12.884389 -288.329968) (xy 12.831886 -288.314482) (xy 12.782139 -288.291643) (xy 12.736172 -288.261921)
			(xy 12.71524 -288.24428) (xy 12.714986 -288.244026) (xy 12.707914 -288.238419) (xy 12.690986 -288.232186)
			(xy 12.681966 -288.231834) (xy 12.61491 -288.231834) (xy 12.605893 -288.232189) (xy 12.588976 -288.238437)
			(xy 12.58189 -288.244026) (xy 12.58189 -288.24428) (xy 12.581636 -288.24428) (xy 12.560699 -288.261913)
			(xy 12.514728 -288.291626) (xy 12.464981 -288.314464) (xy 12.412482 -288.329956) (xy 12.358307 -288.337785)
			(xy 12.330938 -288.33826) (xy 12.303687 -288.33777) (xy 12.24974 -288.330013) (xy 12.197446 -288.314658)
			(xy 12.147869 -288.292017) (xy 12.102019 -288.262551) (xy 12.060829 -288.226859) (xy 12.025138 -288.18567)
			(xy 11.995672 -288.139819) (xy 11.973031 -288.090243) (xy 11.957676 -288.037948) (xy 11.94992 -287.984001)
			(xy 1.420114 -287.984001) (xy 1.420114 -289.258323) (xy 3.252675 -289.258323) (xy 3.252675 -289.203817)
			(xy 3.260432 -289.149866) (xy 3.275789 -289.097568) (xy 3.298431 -289.047987) (xy 3.3279 -289.002134)
			(xy 3.363594 -288.960941) (xy 3.404787 -288.925247) (xy 3.450641 -288.89578) (xy 3.500221 -288.873137)
			(xy 3.55252 -288.857782) (xy 3.606471 -288.850025) (xy 3.633724 -288.849562) (xy 3.661095 -288.849999)
			(xy 3.715276 -288.857821) (xy 3.76778 -288.873316) (xy 3.817527 -288.896165) (xy 3.863492 -288.925897)
			(xy 3.884422 -288.943542) (xy 3.884676 -288.943796) (xy 3.891766 -288.949378) (xy 3.90868 -288.955628)
			(xy 3.917696 -288.955988) (xy 3.984752 -288.955988) (xy 3.993767 -288.95561) (xy 4.010684 -288.949377)
			(xy 4.017772 -288.943796) (xy 4.017772 -288.943542) (xy 4.018026 -288.943542) (xy 4.038981 -288.925931)
			(xy 4.084947 -288.896213) (xy 4.134688 -288.873371) (xy 4.187184 -288.857874) (xy 4.241356 -288.850039)
			(xy 4.268724 -288.849562) (xy 4.295975 -288.850048) (xy 4.349922 -288.857805) (xy 4.402217 -288.873161)
			(xy 4.451793 -288.895802) (xy 4.497643 -288.925268) (xy 4.538833 -288.96096) (xy 4.574524 -289.00215)
			(xy 4.60399 -289.048) (xy 4.626631 -289.097577) (xy 4.641986 -289.149872) (xy 4.649742 -289.203819)
			(xy 4.649742 -289.258321) (xy 5.006068 -289.258321) (xy 5.006068 -289.203819) (xy 5.013824 -289.149872)
			(xy 5.029179 -289.097577) (xy 5.05182 -289.048) (xy 5.081286 -289.00215) (xy 5.116977 -288.96096)
			(xy 5.158167 -288.925268) (xy 5.204017 -288.895802) (xy 5.253593 -288.873161) (xy 5.305888 -288.857805)
			(xy 5.359835 -288.850048) (xy 5.387086 -288.849562) (xy 5.414457 -288.850021) (xy 5.468637 -288.857838)
			(xy 5.52114 -288.873328) (xy 5.570887 -288.896172) (xy 5.616853 -288.925899) (xy 5.637784 -288.943542)
			(xy 5.638038 -288.943796) (xy 5.645139 -288.949362) (xy 5.662045 -288.955621) (xy 5.671058 -288.955988)
			(xy 5.738114 -288.955988) (xy 5.747132 -288.95564) (xy 5.764049 -288.949387) (xy 5.771134 -288.943796)
			(xy 5.771134 -288.943542) (xy 5.771388 -288.943542) (xy 5.792319 -288.925902) (xy 5.838292 -288.896189)
			(xy 5.888039 -288.873352) (xy 5.94054 -288.857862) (xy 5.994717 -288.850035) (xy 6.022086 -288.849562)
			(xy 6.049339 -288.850025) (xy 6.10329 -288.857782) (xy 6.155589 -288.873137) (xy 6.205169 -288.89578)
			(xy 6.251023 -288.925247) (xy 6.292216 -288.960941) (xy 6.32791 -289.002134) (xy 6.357379 -289.047987)
			(xy 6.380021 -289.097568) (xy 6.395378 -289.149866) (xy 6.403135 -289.203817) (xy 6.403135 -289.258323)
			(xy 6.395378 -289.312274) (xy 6.380021 -289.364572) (xy 6.357379 -289.414153) (xy 6.32791 -289.460006)
			(xy 6.292216 -289.501199) (xy 6.256307 -289.532314) (xy 28.175964 -289.532314) (xy 28.180035 -289.476692)
			(xy 28.192161 -289.422255) (xy 28.212084 -289.370164) (xy 28.23938 -289.321529) (xy 28.273466 -289.277386)
			(xy 28.313615 -289.238677) (xy 28.358973 -289.206226) (xy 28.408573 -289.180725) (xy 28.461357 -289.162718)
			(xy 28.5162 -289.152588) (xy 28.571934 -289.150551) (xy 28.627371 -289.156651) (xy 28.681328 -289.170757)
			(xy 28.732657 -289.192569) (xy 28.780263 -289.221623) (xy 28.823131 -289.257298) (xy 28.860348 -289.298835)
			(xy 28.891121 -289.345348) (xy 28.914793 -289.395845) (xy 28.930861 -289.449252) (xy 28.938981 -289.504428)
			(xy 28.93949 -289.532314) (xy 28.938981 -289.5602) (xy 28.930861 -289.615376) (xy 28.914793 -289.668783)
			(xy 28.891121 -289.71928) (xy 28.860348 -289.765793) (xy 28.823131 -289.80733) (xy 28.780263 -289.843005)
			(xy 28.732657 -289.872059) (xy 28.681328 -289.893871) (xy 28.627371 -289.907977) (xy 28.571934 -289.914077)
			(xy 28.5162 -289.91204) (xy 28.461357 -289.90191) (xy 28.408573 -289.883903) (xy 28.358973 -289.858402)
			(xy 28.313615 -289.825951) (xy 28.273466 -289.787242) (xy 28.23938 -289.743099) (xy 28.212084 -289.694464)
			(xy 28.192161 -289.642373) (xy 28.180035 -289.587936) (xy 28.175964 -289.532314) (xy 6.256307 -289.532314)
			(xy 6.251023 -289.536893) (xy 6.205169 -289.56636) (xy 6.155589 -289.589003) (xy 6.10329 -289.604358)
			(xy 6.049339 -289.612115) (xy 6.022086 -289.612578) (xy 5.994715 -289.612125) (xy 5.940535 -289.604305)
			(xy 5.888032 -289.588813) (xy 5.838285 -289.565968) (xy 5.792319 -289.536241) (xy 5.771388 -289.518598)
			(xy 5.771134 -289.518344) (xy 5.764047 -289.512759) (xy 5.74713 -289.506513) (xy 5.738114 -289.506152)
			(xy 5.671058 -289.506152) (xy 5.662043 -289.506525) (xy 5.645125 -289.51276) (xy 5.638038 -289.518344)
			(xy 5.638038 -289.518598) (xy 5.637784 -289.518598) (xy 5.616831 -289.536211) (xy 5.570864 -289.565927)
			(xy 5.521122 -289.588768) (xy 5.468626 -289.604265) (xy 5.414454 -289.6121) (xy 5.387086 -289.612578)
			(xy 5.359835 -289.612092) (xy 5.305888 -289.604335) (xy 5.253593 -289.588979) (xy 5.204017 -289.566338)
			(xy 5.158167 -289.536872) (xy 5.116977 -289.50118) (xy 5.081286 -289.45999) (xy 5.05182 -289.41414)
			(xy 5.029179 -289.364563) (xy 5.013824 -289.312268) (xy 5.006068 -289.258321) (xy 4.649742 -289.258321)
			(xy 4.641986 -289.312268) (xy 4.626631 -289.364563) (xy 4.60399 -289.41414) (xy 4.574524 -289.45999)
			(xy 4.538833 -289.50118) (xy 4.497643 -289.536872) (xy 4.451793 -289.566338) (xy 4.402217 -289.588979)
			(xy 4.349922 -289.604335) (xy 4.295975 -289.612092) (xy 4.268724 -289.612578) (xy 4.241354 -289.612103)
			(xy 4.187175 -289.604288) (xy 4.134672 -289.588802) (xy 4.084925 -289.565962) (xy 4.038958 -289.536239)
			(xy 4.018026 -289.518598) (xy 4.017772 -289.518344) (xy 4.010674 -289.512775) (xy 3.993766 -289.506519)
			(xy 3.984752 -289.506152) (xy 3.917696 -289.506152) (xy 3.908678 -289.506496) (xy 3.89176 -289.512751)
			(xy 3.884676 -289.518344) (xy 3.884676 -289.518598) (xy 3.884422 -289.518598) (xy 3.863492 -289.53624)
			(xy 3.817519 -289.565951) (xy 3.767771 -289.588787) (xy 3.71527 -289.604277) (xy 3.661093 -289.612105)
			(xy 3.633724 -289.612578) (xy 3.606471 -289.612115) (xy 3.55252 -289.604358) (xy 3.500221 -289.589003)
			(xy 3.450641 -289.56636) (xy 3.404787 -289.536893) (xy 3.363594 -289.501199) (xy 3.3279 -289.460006)
			(xy 3.298431 -289.414153) (xy 3.275789 -289.364572) (xy 3.260432 -289.312274) (xy 3.252675 -289.258323)
			(xy 1.420114 -289.258323) (xy 1.420114 -291.430456) (xy 25.811478 -291.430456) (xy 25.815549 -291.374834)
			(xy 25.827675 -291.320397) (xy 25.847598 -291.268306) (xy 25.874894 -291.219671) (xy 25.90898 -291.175528)
			(xy 25.949129 -291.136819) (xy 25.994487 -291.104368) (xy 26.044087 -291.078867) (xy 26.096871 -291.06086)
			(xy 26.151714 -291.05073) (xy 26.207448 -291.048693) (xy 26.262885 -291.054793) (xy 26.316842 -291.068899)
			(xy 26.368171 -291.090711) (xy 26.415777 -291.119765) (xy 26.458645 -291.15544) (xy 26.495862 -291.196977)
			(xy 26.526635 -291.24349) (xy 26.550307 -291.293987) (xy 26.566375 -291.347394) (xy 26.574495 -291.40257)
			(xy 26.575004 -291.430456) (xy 27.296616 -291.430456) (xy 27.300687 -291.374834) (xy 27.312813 -291.320397)
			(xy 27.332736 -291.268306) (xy 27.360032 -291.219671) (xy 27.394118 -291.175528) (xy 27.434267 -291.136819)
			(xy 27.479625 -291.104368) (xy 27.529225 -291.078867) (xy 27.582009 -291.06086) (xy 27.636852 -291.05073)
			(xy 27.692586 -291.048693) (xy 27.748023 -291.054793) (xy 27.80198 -291.068899) (xy 27.853309 -291.090711)
			(xy 27.900915 -291.119765) (xy 27.943783 -291.15544) (xy 27.981 -291.196977) (xy 28.011773 -291.24349)
			(xy 28.035445 -291.293987) (xy 28.051513 -291.347394) (xy 28.059633 -291.40257) (xy 28.060142 -291.430456)
			(xy 28.059633 -291.458342) (xy 28.051513 -291.513518) (xy 28.035445 -291.566925) (xy 28.011773 -291.617422)
			(xy 27.981 -291.663935) (xy 27.943783 -291.705472) (xy 27.900915 -291.741147) (xy 27.853309 -291.770201)
			(xy 27.80198 -291.792013) (xy 27.748023 -291.806119) (xy 27.692586 -291.812219) (xy 27.636852 -291.810182)
			(xy 27.582009 -291.800052) (xy 27.529225 -291.782045) (xy 27.479625 -291.756544) (xy 27.434267 -291.724093)
			(xy 27.394118 -291.685384) (xy 27.360032 -291.641241) (xy 27.332736 -291.592606) (xy 27.312813 -291.540515)
			(xy 27.300687 -291.486078) (xy 27.296616 -291.430456) (xy 26.575004 -291.430456) (xy 26.574495 -291.458342)
			(xy 26.566375 -291.513518) (xy 26.550307 -291.566925) (xy 26.526635 -291.617422) (xy 26.495862 -291.663935)
			(xy 26.458645 -291.705472) (xy 26.415777 -291.741147) (xy 26.368171 -291.770201) (xy 26.316842 -291.792013)
			(xy 26.262885 -291.806119) (xy 26.207448 -291.812219) (xy 26.151714 -291.810182) (xy 26.096871 -291.800052)
			(xy 26.044087 -291.782045) (xy 25.994487 -291.756544) (xy 25.949129 -291.724093) (xy 25.90898 -291.685384)
			(xy 25.874894 -291.641241) (xy 25.847598 -291.592606) (xy 25.827675 -291.540515) (xy 25.815549 -291.486078)
			(xy 25.811478 -291.430456) (xy 1.420114 -291.430456) (xy 1.420114 -292.169342) (xy 30.994604 -292.169342)
			(xy 30.994604 -289.830256) (xy 30.995093 -289.806606) (xy 31.002434 -289.759879) (xy 31.016888 -289.71484)
			(xy 31.038109 -289.672567) (xy 31.065591 -289.634069) (xy 31.098677 -289.600265) (xy 31.136576 -289.571963)
			(xy 31.178384 -289.549839) (xy 31.200598 -289.541712) (xy 31.322772 -289.499802) (xy 31.331106 -289.49657)
			(xy 31.344951 -289.485277) (xy 31.354067 -289.469912) (xy 31.356046 -289.461194) (xy 31.361398 -289.435338)
			(xy 31.378318 -289.385322) (xy 31.40197 -289.338115) (xy 31.431903 -289.294619) (xy 31.467546 -289.255664)
			(xy 31.508217 -289.221994) (xy 31.553142 -289.19425) (xy 31.601462 -289.172964) (xy 31.652254 -289.158541)
			(xy 31.70455 -289.151256) (xy 31.73095 -289.150806) (xy 31.731204 -289.150806) (xy 31.761043 -289.151387)
			(xy 31.819989 -289.160699) (xy 31.848552 -289.169348) (xy 31.864808 -289.174682) (xy 31.897066 -289.163506)
			(xy 31.921958 -289.125914) (xy 31.93622 -289.105254) (xy 31.970405 -289.068493) (xy 32.010137 -289.037811)
			(xy 32.054349 -289.014033) (xy 32.10185 -288.997798) (xy 32.151367 -288.989542) (xy 32.176466 -288.989008)
			(xy 35.033712 -288.989008) (xy 35.045525 -288.988427) (xy 35.066708 -288.977968) (xy 35.074352 -288.968942)
			(xy 35.130486 -288.89452) (xy 35.134804 -288.870898) (xy 35.131502 -288.859468) (xy 35.125913 -288.838771)
			(xy 35.119924 -288.796321) (xy 35.119564 -288.774886) (xy 35.120086 -288.749631) (xy 35.128399 -288.699809)
			(xy 35.1448 -288.652035) (xy 35.168841 -288.607612) (xy 35.199865 -288.567752) (xy 35.237027 -288.533542)
			(xy 35.279313 -288.505916) (xy 35.325569 -288.485626) (xy 35.374534 -288.473226) (xy 35.424872 -288.469055)
			(xy 35.47521 -288.473226) (xy 35.524175 -288.485626) (xy 35.570431 -288.505916) (xy 35.612717 -288.533542)
			(xy 35.649879 -288.567752) (xy 35.680903 -288.607612) (xy 35.704944 -288.652035) (xy 35.721345 -288.699809)
			(xy 35.729658 -288.749631) (xy 35.73018 -288.774886) (xy 35.729736 -288.79834) (xy 35.729416 -288.800413)
			(xy 36.0443 -288.800413) (xy 36.0443 -288.748387) (xy 36.052439 -288.697003) (xy 36.068516 -288.647524)
			(xy 36.092136 -288.60117) (xy 36.122718 -288.559082) (xy 36.159507 -288.522297) (xy 36.201598 -288.49172)
			(xy 36.247954 -288.468104) (xy 36.297434 -288.452031) (xy 36.348819 -288.443897) (xy 36.374832 -288.443416)
			(xy 37.324792 -288.443416) (xy 37.3508 -288.443943) (xy 37.402175 -288.452079) (xy 37.451646 -288.468151)
			(xy 37.497993 -288.491765) (xy 37.540075 -288.522339) (xy 37.576856 -288.559119) (xy 37.60743 -288.601201)
			(xy 37.631045 -288.647547) (xy 37.647119 -288.697017) (xy 37.655257 -288.748392) (xy 37.655257 -288.774886)
			(xy 37.969202 -288.774886) (xy 37.973162 -288.725832) (xy 37.984939 -288.678048) (xy 38.00423 -288.632772)
			(xy 38.030533 -288.591176) (xy 38.063168 -288.554339) (xy 38.101289 -288.523214) (xy 38.14391 -288.498607)
			(xy 38.189926 -288.481155) (xy 38.238145 -288.471311) (xy 38.28732 -288.46933) (xy 38.336175 -288.475262)
			(xy 38.383446 -288.488954) (xy 38.427908 -288.510052) (xy 38.468411 -288.538008) (xy 38.503904 -288.5721)
			(xy 38.533469 -288.611444) (xy 38.55634 -288.655021) (xy 38.571924 -288.701702) (xy 38.579819 -288.750279)
			(xy 38.580314 -288.774886) (xy 41.769042 -288.774886) (xy 41.773002 -288.725832) (xy 41.784779 -288.678048)
			(xy 41.80407 -288.632772) (xy 41.830373 -288.591176) (xy 41.863008 -288.554339) (xy 41.901129 -288.523214)
			(xy 41.94375 -288.498607) (xy 41.989766 -288.481155) (xy 42.037985 -288.471311) (xy 42.08716 -288.46933)
			(xy 42.136015 -288.475262) (xy 42.183286 -288.488954) (xy 42.227748 -288.510052) (xy 42.268251 -288.538008)
			(xy 42.303744 -288.5721) (xy 42.333309 -288.611444) (xy 42.35618 -288.655021) (xy 42.371764 -288.701702)
			(xy 42.379659 -288.750279) (xy 42.380154 -288.774886) (xy 42.379659 -288.799493) (xy 42.37951 -288.800411)
			(xy 42.694299 -288.800411) (xy 42.694299 -288.748389) (xy 42.702438 -288.697007) (xy 42.718514 -288.64753)
			(xy 42.742132 -288.601178) (xy 42.77271 -288.559091) (xy 42.809496 -288.522306) (xy 42.851583 -288.491729)
			(xy 42.897936 -288.468111) (xy 42.947413 -288.452036) (xy 42.998795 -288.443899) (xy 43.024806 -288.443416)
			(xy 43.974766 -288.443416) (xy 44.000775 -288.443941) (xy 44.052154 -288.452074) (xy 44.101628 -288.468144)
			(xy 44.147978 -288.491757) (xy 44.190064 -288.52233) (xy 44.226848 -288.55911) (xy 44.257426 -288.601193)
			(xy 44.281043 -288.647541) (xy 44.297119 -288.697013) (xy 44.305257 -288.748391) (xy 44.305257 -288.774886)
			(xy 44.619176 -288.774886) (xy 44.623136 -288.725832) (xy 44.634913 -288.678048) (xy 44.654204 -288.632772)
			(xy 44.680507 -288.591176) (xy 44.713142 -288.554339) (xy 44.751263 -288.523214) (xy 44.793884 -288.498607)
			(xy 44.8399 -288.481155) (xy 44.888119 -288.471311) (xy 44.937294 -288.46933) (xy 44.986149 -288.475262)
			(xy 45.03342 -288.488954) (xy 45.077882 -288.510052) (xy 45.118385 -288.538008) (xy 45.153878 -288.5721)
			(xy 45.183443 -288.611444) (xy 45.206314 -288.655021) (xy 45.221898 -288.701702) (xy 45.229793 -288.750279)
			(xy 45.230288 -288.774886) (xy 45.569136 -288.774886) (xy 45.573096 -288.725832) (xy 45.584873 -288.678048)
			(xy 45.604164 -288.632772) (xy 45.630467 -288.591176) (xy 45.663102 -288.554339) (xy 45.701223 -288.523214)
			(xy 45.743844 -288.498607) (xy 45.78986 -288.481155) (xy 45.838079 -288.471311) (xy 45.887254 -288.46933)
			(xy 45.936109 -288.475262) (xy 45.98338 -288.488954) (xy 46.027842 -288.510052) (xy 46.068345 -288.538008)
			(xy 46.103838 -288.5721) (xy 46.133403 -288.611444) (xy 46.156274 -288.655021) (xy 46.171858 -288.701702)
			(xy 46.179753 -288.750279) (xy 46.180248 -288.774886) (xy 46.519096 -288.774886) (xy 46.523056 -288.725832)
			(xy 46.534833 -288.678048) (xy 46.554124 -288.632772) (xy 46.580427 -288.591176) (xy 46.613062 -288.554339)
			(xy 46.651183 -288.523214) (xy 46.693804 -288.498607) (xy 46.73982 -288.481155) (xy 46.788039 -288.471311)
			(xy 46.837214 -288.46933) (xy 46.886069 -288.475262) (xy 46.93334 -288.488954) (xy 46.977802 -288.510052)
			(xy 47.018305 -288.538008) (xy 47.053798 -288.5721) (xy 47.083363 -288.611444) (xy 47.106234 -288.655021)
			(xy 47.121818 -288.701702) (xy 47.129713 -288.750279) (xy 47.130208 -288.774886) (xy 47.469056 -288.774886)
			(xy 47.473016 -288.725832) (xy 47.484793 -288.678048) (xy 47.504084 -288.632772) (xy 47.530387 -288.591176)
			(xy 47.563022 -288.554339) (xy 47.601143 -288.523214) (xy 47.643764 -288.498607) (xy 47.68978 -288.481155)
			(xy 47.737999 -288.471311) (xy 47.787174 -288.46933) (xy 47.836029 -288.475262) (xy 47.8833 -288.488954)
			(xy 47.927762 -288.510052) (xy 47.968265 -288.538008) (xy 48.003758 -288.5721) (xy 48.033323 -288.611444)
			(xy 48.056194 -288.655021) (xy 48.071778 -288.701702) (xy 48.079673 -288.750279) (xy 48.080168 -288.774886)
			(xy 48.419016 -288.774886) (xy 48.422976 -288.725832) (xy 48.434753 -288.678048) (xy 48.454044 -288.632772)
			(xy 48.480347 -288.591176) (xy 48.512982 -288.554339) (xy 48.551103 -288.523214) (xy 48.593724 -288.498607)
			(xy 48.63974 -288.481155) (xy 48.687959 -288.471311) (xy 48.737134 -288.46933) (xy 48.785989 -288.475262)
			(xy 48.83326 -288.488954) (xy 48.877722 -288.510052) (xy 48.918225 -288.538008) (xy 48.953718 -288.5721)
			(xy 48.983283 -288.611444) (xy 49.006154 -288.655021) (xy 49.021738 -288.701702) (xy 49.029633 -288.750279)
			(xy 49.030128 -288.774886) (xy 49.368976 -288.774886) (xy 49.372936 -288.725832) (xy 49.384713 -288.678048)
			(xy 49.404004 -288.632772) (xy 49.430307 -288.591176) (xy 49.462942 -288.554339) (xy 49.501063 -288.523214)
			(xy 49.543684 -288.498607) (xy 49.5897 -288.481155) (xy 49.637919 -288.471311) (xy 49.687094 -288.46933)
			(xy 49.735949 -288.475262) (xy 49.78322 -288.488954) (xy 49.827682 -288.510052) (xy 49.868185 -288.538008)
			(xy 49.903678 -288.5721) (xy 49.933243 -288.611444) (xy 49.956114 -288.655021) (xy 49.971698 -288.701702)
			(xy 49.979593 -288.750279) (xy 49.980088 -288.774886) (xy 50.31919 -288.774886) (xy 50.32315 -288.725832)
			(xy 50.334927 -288.678048) (xy 50.354218 -288.632772) (xy 50.380521 -288.591176) (xy 50.413156 -288.554339)
			(xy 50.451277 -288.523214) (xy 50.493898 -288.498607) (xy 50.539914 -288.481155) (xy 50.588133 -288.471311)
			(xy 50.637308 -288.46933) (xy 50.686163 -288.475262) (xy 50.733434 -288.488954) (xy 50.777896 -288.510052)
			(xy 50.818399 -288.538008) (xy 50.853892 -288.5721) (xy 50.883457 -288.611444) (xy 50.906328 -288.655021)
			(xy 50.921912 -288.701702) (xy 50.929807 -288.750279) (xy 50.930302 -288.774886) (xy 51.26915 -288.774886)
			(xy 51.27311 -288.725832) (xy 51.284887 -288.678048) (xy 51.304178 -288.632772) (xy 51.330481 -288.591176)
			(xy 51.363116 -288.554339) (xy 51.401237 -288.523214) (xy 51.443858 -288.498607) (xy 51.489874 -288.481155)
			(xy 51.538093 -288.471311) (xy 51.587268 -288.46933) (xy 51.636123 -288.475262) (xy 51.683394 -288.488954)
			(xy 51.727856 -288.510052) (xy 51.768359 -288.538008) (xy 51.803852 -288.5721) (xy 51.833417 -288.611444)
			(xy 51.856288 -288.655021) (xy 51.871872 -288.701702) (xy 51.879767 -288.750279) (xy 51.880262 -288.774886)
			(xy 52.21911 -288.774886) (xy 52.22307 -288.725832) (xy 52.234847 -288.678048) (xy 52.254138 -288.632772)
			(xy 52.280441 -288.591176) (xy 52.313076 -288.554339) (xy 52.351197 -288.523214) (xy 52.393818 -288.498607)
			(xy 52.439834 -288.481155) (xy 52.488053 -288.471311) (xy 52.537228 -288.46933) (xy 52.586083 -288.475262)
			(xy 52.633354 -288.488954) (xy 52.677816 -288.510052) (xy 52.718319 -288.538008) (xy 52.753812 -288.5721)
			(xy 52.783377 -288.611444) (xy 52.806248 -288.655021) (xy 52.821832 -288.701702) (xy 52.829727 -288.750279)
			(xy 52.830222 -288.774886) (xy 53.16907 -288.774886) (xy 53.17303 -288.725832) (xy 53.184807 -288.678048)
			(xy 53.204098 -288.632772) (xy 53.230401 -288.591176) (xy 53.263036 -288.554339) (xy 53.301157 -288.523214)
			(xy 53.343778 -288.498607) (xy 53.389794 -288.481155) (xy 53.438013 -288.471311) (xy 53.487188 -288.46933)
			(xy 53.536043 -288.475262) (xy 53.583314 -288.488954) (xy 53.627776 -288.510052) (xy 53.668279 -288.538008)
			(xy 53.703772 -288.5721) (xy 53.733337 -288.611444) (xy 53.756208 -288.655021) (xy 53.771792 -288.701702)
			(xy 53.779687 -288.750279) (xy 53.780182 -288.774886) (xy 54.11903 -288.774886) (xy 54.12299 -288.725832)
			(xy 54.134767 -288.678048) (xy 54.154058 -288.632772) (xy 54.180361 -288.591176) (xy 54.212996 -288.554339)
			(xy 54.251117 -288.523214) (xy 54.293738 -288.498607) (xy 54.339754 -288.481155) (xy 54.387973 -288.471311)
			(xy 54.437148 -288.46933) (xy 54.486003 -288.475262) (xy 54.533274 -288.488954) (xy 54.577736 -288.510052)
			(xy 54.618239 -288.538008) (xy 54.653732 -288.5721) (xy 54.683297 -288.611444) (xy 54.706168 -288.655021)
			(xy 54.721752 -288.701702) (xy 54.729647 -288.750279) (xy 54.730142 -288.774886) (xy 55.06899 -288.774886)
			(xy 55.07295 -288.725832) (xy 55.084727 -288.678048) (xy 55.104018 -288.632772) (xy 55.130321 -288.591176)
			(xy 55.162956 -288.554339) (xy 55.201077 -288.523214) (xy 55.243698 -288.498607) (xy 55.289714 -288.481155)
			(xy 55.337933 -288.471311) (xy 55.387108 -288.46933) (xy 55.435963 -288.475262) (xy 55.483234 -288.488954)
			(xy 55.527696 -288.510052) (xy 55.568199 -288.538008) (xy 55.603692 -288.5721) (xy 55.633257 -288.611444)
			(xy 55.656128 -288.655021) (xy 55.671712 -288.701702) (xy 55.679607 -288.750279) (xy 55.680102 -288.774886)
			(xy 56.01895 -288.774886) (xy 56.02291 -288.725832) (xy 56.034687 -288.678048) (xy 56.053978 -288.632772)
			(xy 56.080281 -288.591176) (xy 56.112916 -288.554339) (xy 56.151037 -288.523214) (xy 56.193658 -288.498607)
			(xy 56.239674 -288.481155) (xy 56.287893 -288.471311) (xy 56.337068 -288.46933) (xy 56.385923 -288.475262)
			(xy 56.433194 -288.488954) (xy 56.477656 -288.510052) (xy 56.518159 -288.538008) (xy 56.553652 -288.5721)
			(xy 56.583217 -288.611444) (xy 56.606088 -288.655021) (xy 56.621672 -288.701702) (xy 56.629567 -288.750279)
			(xy 56.630062 -288.774886) (xy 56.969164 -288.774886) (xy 56.973124 -288.725832) (xy 56.984901 -288.678048)
			(xy 57.004192 -288.632772) (xy 57.030495 -288.591176) (xy 57.06313 -288.554339) (xy 57.101251 -288.523214)
			(xy 57.143872 -288.498607) (xy 57.189888 -288.481155) (xy 57.238107 -288.471311) (xy 57.287282 -288.46933)
			(xy 57.336137 -288.475262) (xy 57.383408 -288.488954) (xy 57.42787 -288.510052) (xy 57.468373 -288.538008)
			(xy 57.503866 -288.5721) (xy 57.533431 -288.611444) (xy 57.556302 -288.655021) (xy 57.571886 -288.701702)
			(xy 57.579781 -288.750279) (xy 57.580276 -288.774886) (xy 57.919124 -288.774886) (xy 57.923084 -288.725832)
			(xy 57.934861 -288.678048) (xy 57.954152 -288.632772) (xy 57.980455 -288.591176) (xy 58.01309 -288.554339)
			(xy 58.051211 -288.523214) (xy 58.093832 -288.498607) (xy 58.139848 -288.481155) (xy 58.188067 -288.471311)
			(xy 58.237242 -288.46933) (xy 58.286097 -288.475262) (xy 58.333368 -288.488954) (xy 58.37783 -288.510052)
			(xy 58.418333 -288.538008) (xy 58.453826 -288.5721) (xy 58.483391 -288.611444) (xy 58.506262 -288.655021)
			(xy 58.521846 -288.701702) (xy 58.529741 -288.750279) (xy 58.530236 -288.774886) (xy 59.819044 -288.774886)
			(xy 59.823004 -288.725832) (xy 59.834781 -288.678048) (xy 59.854072 -288.632772) (xy 59.880375 -288.591176)
			(xy 59.91301 -288.554339) (xy 59.951131 -288.523214) (xy 59.993752 -288.498607) (xy 60.039768 -288.481155)
			(xy 60.087987 -288.471311) (xy 60.137162 -288.46933) (xy 60.186017 -288.475262) (xy 60.233288 -288.488954)
			(xy 60.27775 -288.510052) (xy 60.318253 -288.538008) (xy 60.353746 -288.5721) (xy 60.383311 -288.611444)
			(xy 60.406182 -288.655021) (xy 60.421766 -288.701702) (xy 60.429661 -288.750279) (xy 60.430156 -288.774886)
			(xy 60.769004 -288.774886) (xy 60.772964 -288.725832) (xy 60.784741 -288.678048) (xy 60.804032 -288.632772)
			(xy 60.830335 -288.591176) (xy 60.86297 -288.554339) (xy 60.901091 -288.523214) (xy 60.943712 -288.498607)
			(xy 60.989728 -288.481155) (xy 61.037947 -288.471311) (xy 61.087122 -288.46933) (xy 61.135977 -288.475262)
			(xy 61.183248 -288.488954) (xy 61.22771 -288.510052) (xy 61.268213 -288.538008) (xy 61.303706 -288.5721)
			(xy 61.333271 -288.611444) (xy 61.356142 -288.655021) (xy 61.371726 -288.701702) (xy 61.379621 -288.750279)
			(xy 61.380116 -288.774886) (xy 61.718964 -288.774886) (xy 61.722924 -288.725832) (xy 61.734701 -288.678048)
			(xy 61.753992 -288.632772) (xy 61.780295 -288.591176) (xy 61.81293 -288.554339) (xy 61.851051 -288.523214)
			(xy 61.893672 -288.498607) (xy 61.939688 -288.481155) (xy 61.987907 -288.471311) (xy 62.037082 -288.46933)
			(xy 62.085937 -288.475262) (xy 62.133208 -288.488954) (xy 62.17767 -288.510052) (xy 62.218173 -288.538008)
			(xy 62.253666 -288.5721) (xy 62.283231 -288.611444) (xy 62.306102 -288.655021) (xy 62.321686 -288.701702)
			(xy 62.329581 -288.750279) (xy 62.330076 -288.774886) (xy 62.669178 -288.774886) (xy 62.673138 -288.725832)
			(xy 62.684915 -288.678048) (xy 62.704206 -288.632772) (xy 62.730509 -288.591176) (xy 62.763144 -288.554339)
			(xy 62.801265 -288.523214) (xy 62.843886 -288.498607) (xy 62.889902 -288.481155) (xy 62.938121 -288.471311)
			(xy 62.987296 -288.46933) (xy 63.036151 -288.475262) (xy 63.083422 -288.488954) (xy 63.127884 -288.510052)
			(xy 63.168387 -288.538008) (xy 63.20388 -288.5721) (xy 63.233445 -288.611444) (xy 63.256316 -288.655021)
			(xy 63.2719 -288.701702) (xy 63.279795 -288.750279) (xy 63.28029 -288.774886) (xy 63.619138 -288.774886)
			(xy 63.623098 -288.725832) (xy 63.634875 -288.678048) (xy 63.654166 -288.632772) (xy 63.680469 -288.591176)
			(xy 63.713104 -288.554339) (xy 63.751225 -288.523214) (xy 63.793846 -288.498607) (xy 63.839862 -288.481155)
			(xy 63.888081 -288.471311) (xy 63.937256 -288.46933) (xy 63.986111 -288.475262) (xy 64.033382 -288.488954)
			(xy 64.077844 -288.510052) (xy 64.118347 -288.538008) (xy 64.15384 -288.5721) (xy 64.183405 -288.611444)
			(xy 64.206276 -288.655021) (xy 64.22186 -288.701702) (xy 64.229755 -288.750279) (xy 64.23025 -288.774886)
			(xy 64.569098 -288.774886) (xy 64.573058 -288.725832) (xy 64.584835 -288.678048) (xy 64.604126 -288.632772)
			(xy 64.630429 -288.591176) (xy 64.663064 -288.554339) (xy 64.701185 -288.523214) (xy 64.743806 -288.498607)
			(xy 64.789822 -288.481155) (xy 64.838041 -288.471311) (xy 64.887216 -288.46933) (xy 64.936071 -288.475262)
			(xy 64.983342 -288.488954) (xy 65.027804 -288.510052) (xy 65.068307 -288.538008) (xy 65.1038 -288.5721)
			(xy 65.133365 -288.611444) (xy 65.156236 -288.655021) (xy 65.17182 -288.701702) (xy 65.179715 -288.750279)
			(xy 65.18021 -288.774886) (xy 65.519058 -288.774886) (xy 65.523018 -288.725832) (xy 65.534795 -288.678048)
			(xy 65.554086 -288.632772) (xy 65.580389 -288.591176) (xy 65.613024 -288.554339) (xy 65.651145 -288.523214)
			(xy 65.693766 -288.498607) (xy 65.739782 -288.481155) (xy 65.788001 -288.471311) (xy 65.837176 -288.46933)
			(xy 65.886031 -288.475262) (xy 65.933302 -288.488954) (xy 65.977764 -288.510052) (xy 66.018267 -288.538008)
			(xy 66.05376 -288.5721) (xy 66.083325 -288.611444) (xy 66.106196 -288.655021) (xy 66.12178 -288.701702)
			(xy 66.129675 -288.750279) (xy 66.13017 -288.774886) (xy 66.469018 -288.774886) (xy 66.472978 -288.725832)
			(xy 66.484755 -288.678048) (xy 66.504046 -288.632772) (xy 66.530349 -288.591176) (xy 66.562984 -288.554339)
			(xy 66.601105 -288.523214) (xy 66.643726 -288.498607) (xy 66.689742 -288.481155) (xy 66.737961 -288.471311)
			(xy 66.787136 -288.46933) (xy 66.835991 -288.475262) (xy 66.883262 -288.488954) (xy 66.927724 -288.510052)
			(xy 66.968227 -288.538008) (xy 67.00372 -288.5721) (xy 67.033285 -288.611444) (xy 67.056156 -288.655021)
			(xy 67.07174 -288.701702) (xy 67.079635 -288.750279) (xy 67.08013 -288.774886) (xy 67.418978 -288.774886)
			(xy 67.422938 -288.725832) (xy 67.434715 -288.678048) (xy 67.454006 -288.632772) (xy 67.480309 -288.591176)
			(xy 67.512944 -288.554339) (xy 67.551065 -288.523214) (xy 67.593686 -288.498607) (xy 67.639702 -288.481155)
			(xy 67.687921 -288.471311) (xy 67.737096 -288.46933) (xy 67.785951 -288.475262) (xy 67.833222 -288.488954)
			(xy 67.877684 -288.510052) (xy 67.918187 -288.538008) (xy 67.95368 -288.5721) (xy 67.983245 -288.611444)
			(xy 68.006116 -288.655021) (xy 68.0217 -288.701702) (xy 68.029595 -288.750279) (xy 68.03009 -288.774886)
			(xy 68.368938 -288.774886) (xy 68.372898 -288.725832) (xy 68.384675 -288.678048) (xy 68.403966 -288.632772)
			(xy 68.430269 -288.591176) (xy 68.462904 -288.554339) (xy 68.501025 -288.523214) (xy 68.543646 -288.498607)
			(xy 68.589662 -288.481155) (xy 68.637881 -288.471311) (xy 68.687056 -288.46933) (xy 68.735911 -288.475262)
			(xy 68.783182 -288.488954) (xy 68.827644 -288.510052) (xy 68.868147 -288.538008) (xy 68.90364 -288.5721)
			(xy 68.933205 -288.611444) (xy 68.956076 -288.655021) (xy 68.97166 -288.701702) (xy 68.979555 -288.750279)
			(xy 68.98005 -288.774886) (xy 69.319152 -288.774886) (xy 69.323112 -288.725832) (xy 69.334889 -288.678048)
			(xy 69.35418 -288.632772) (xy 69.380483 -288.591176) (xy 69.413118 -288.554339) (xy 69.451239 -288.523214)
			(xy 69.49386 -288.498607) (xy 69.539876 -288.481155) (xy 69.588095 -288.471311) (xy 69.63727 -288.46933)
			(xy 69.686125 -288.475262) (xy 69.733396 -288.488954) (xy 69.777858 -288.510052) (xy 69.818361 -288.538008)
			(xy 69.853854 -288.5721) (xy 69.883419 -288.611444) (xy 69.90629 -288.655021) (xy 69.921874 -288.701702)
			(xy 69.929769 -288.750279) (xy 69.930264 -288.774886) (xy 70.269112 -288.774886) (xy 70.273072 -288.725832)
			(xy 70.284849 -288.678048) (xy 70.30414 -288.632772) (xy 70.330443 -288.591176) (xy 70.363078 -288.554339)
			(xy 70.401199 -288.523214) (xy 70.44382 -288.498607) (xy 70.489836 -288.481155) (xy 70.538055 -288.471311)
			(xy 70.58723 -288.46933) (xy 70.636085 -288.475262) (xy 70.683356 -288.488954) (xy 70.727818 -288.510052)
			(xy 70.768321 -288.538008) (xy 70.803814 -288.5721) (xy 70.833379 -288.611444) (xy 70.85625 -288.655021)
			(xy 70.871834 -288.701702) (xy 70.879729 -288.750279) (xy 70.880224 -288.774886) (xy 71.219072 -288.774886)
			(xy 71.223032 -288.725832) (xy 71.234809 -288.678048) (xy 71.2541 -288.632772) (xy 71.280403 -288.591176)
			(xy 71.313038 -288.554339) (xy 71.351159 -288.523214) (xy 71.39378 -288.498607) (xy 71.439796 -288.481155)
			(xy 71.488015 -288.471311) (xy 71.53719 -288.46933) (xy 71.586045 -288.475262) (xy 71.633316 -288.488954)
			(xy 71.677778 -288.510052) (xy 71.718281 -288.538008) (xy 71.753774 -288.5721) (xy 71.783339 -288.611444)
			(xy 71.80621 -288.655021) (xy 71.821794 -288.701702) (xy 71.829689 -288.750279) (xy 71.830184 -288.774886)
			(xy 72.169032 -288.774886) (xy 72.172992 -288.725832) (xy 72.184769 -288.678048) (xy 72.20406 -288.632772)
			(xy 72.230363 -288.591176) (xy 72.262998 -288.554339) (xy 72.301119 -288.523214) (xy 72.34374 -288.498607)
			(xy 72.389756 -288.481155) (xy 72.437975 -288.471311) (xy 72.48715 -288.46933) (xy 72.536005 -288.475262)
			(xy 72.583276 -288.488954) (xy 72.627738 -288.510052) (xy 72.668241 -288.538008) (xy 72.703734 -288.5721)
			(xy 72.733299 -288.611444) (xy 72.75617 -288.655021) (xy 72.771754 -288.701702) (xy 72.779649 -288.750279)
			(xy 72.780144 -288.774886) (xy 72.779649 -288.799493) (xy 72.771754 -288.84807) (xy 72.75617 -288.894751)
			(xy 72.733299 -288.938328) (xy 72.703734 -288.977672) (xy 72.668241 -289.011764) (xy 72.627738 -289.03972)
			(xy 72.583276 -289.060818) (xy 72.536005 -289.07451) (xy 72.48715 -289.080442) (xy 72.437975 -289.078461)
			(xy 72.389756 -289.068617) (xy 72.34374 -289.051165) (xy 72.301119 -289.026558) (xy 72.262998 -288.995433)
			(xy 72.230363 -288.958596) (xy 72.20406 -288.917) (xy 72.184769 -288.871724) (xy 72.172992 -288.82394)
			(xy 72.169032 -288.774886) (xy 71.830184 -288.774886) (xy 71.829689 -288.799493) (xy 71.821794 -288.84807)
			(xy 71.80621 -288.894751) (xy 71.783339 -288.938328) (xy 71.753774 -288.977672) (xy 71.718281 -289.011764)
			(xy 71.677778 -289.03972) (xy 71.633316 -289.060818) (xy 71.586045 -289.07451) (xy 71.53719 -289.080442)
			(xy 71.488015 -289.078461) (xy 71.439796 -289.068617) (xy 71.39378 -289.051165) (xy 71.351159 -289.026558)
			(xy 71.313038 -288.995433) (xy 71.280403 -288.958596) (xy 71.2541 -288.917) (xy 71.234809 -288.871724)
			(xy 71.223032 -288.82394) (xy 71.219072 -288.774886) (xy 70.880224 -288.774886) (xy 70.879729 -288.799493)
			(xy 70.871834 -288.84807) (xy 70.85625 -288.894751) (xy 70.833379 -288.938328) (xy 70.803814 -288.977672)
			(xy 70.768321 -289.011764) (xy 70.727818 -289.03972) (xy 70.683356 -289.060818) (xy 70.636085 -289.07451)
			(xy 70.58723 -289.080442) (xy 70.538055 -289.078461) (xy 70.489836 -289.068617) (xy 70.44382 -289.051165)
			(xy 70.401199 -289.026558) (xy 70.363078 -288.995433) (xy 70.330443 -288.958596) (xy 70.30414 -288.917)
			(xy 70.284849 -288.871724) (xy 70.273072 -288.82394) (xy 70.269112 -288.774886) (xy 69.930264 -288.774886)
			(xy 69.929769 -288.799493) (xy 69.921874 -288.84807) (xy 69.90629 -288.894751) (xy 69.883419 -288.938328)
			(xy 69.853854 -288.977672) (xy 69.818361 -289.011764) (xy 69.777858 -289.03972) (xy 69.733396 -289.060818)
			(xy 69.686125 -289.07451) (xy 69.63727 -289.080442) (xy 69.588095 -289.078461) (xy 69.539876 -289.068617)
			(xy 69.49386 -289.051165) (xy 69.451239 -289.026558) (xy 69.413118 -288.995433) (xy 69.380483 -288.958596)
			(xy 69.35418 -288.917) (xy 69.334889 -288.871724) (xy 69.323112 -288.82394) (xy 69.319152 -288.774886)
			(xy 68.98005 -288.774886) (xy 68.979555 -288.799493) (xy 68.97166 -288.84807) (xy 68.956076 -288.894751)
			(xy 68.933205 -288.938328) (xy 68.90364 -288.977672) (xy 68.868147 -289.011764) (xy 68.827644 -289.03972)
			(xy 68.783182 -289.060818) (xy 68.735911 -289.07451) (xy 68.687056 -289.080442) (xy 68.637881 -289.078461)
			(xy 68.589662 -289.068617) (xy 68.543646 -289.051165) (xy 68.501025 -289.026558) (xy 68.462904 -288.995433)
			(xy 68.430269 -288.958596) (xy 68.403966 -288.917) (xy 68.384675 -288.871724) (xy 68.372898 -288.82394)
			(xy 68.368938 -288.774886) (xy 68.03009 -288.774886) (xy 68.029595 -288.799493) (xy 68.0217 -288.84807)
			(xy 68.006116 -288.894751) (xy 67.983245 -288.938328) (xy 67.95368 -288.977672) (xy 67.918187 -289.011764)
			(xy 67.877684 -289.03972) (xy 67.833222 -289.060818) (xy 67.785951 -289.07451) (xy 67.737096 -289.080442)
			(xy 67.687921 -289.078461) (xy 67.639702 -289.068617) (xy 67.593686 -289.051165) (xy 67.551065 -289.026558)
			(xy 67.512944 -288.995433) (xy 67.480309 -288.958596) (xy 67.454006 -288.917) (xy 67.434715 -288.871724)
			(xy 67.422938 -288.82394) (xy 67.418978 -288.774886) (xy 67.08013 -288.774886) (xy 67.079635 -288.799493)
			(xy 67.07174 -288.84807) (xy 67.056156 -288.894751) (xy 67.033285 -288.938328) (xy 67.00372 -288.977672)
			(xy 66.968227 -289.011764) (xy 66.927724 -289.03972) (xy 66.883262 -289.060818) (xy 66.835991 -289.07451)
			(xy 66.787136 -289.080442) (xy 66.737961 -289.078461) (xy 66.689742 -289.068617) (xy 66.643726 -289.051165)
			(xy 66.601105 -289.026558) (xy 66.562984 -288.995433) (xy 66.530349 -288.958596) (xy 66.504046 -288.917)
			(xy 66.484755 -288.871724) (xy 66.472978 -288.82394) (xy 66.469018 -288.774886) (xy 66.13017 -288.774886)
			(xy 66.129675 -288.799493) (xy 66.12178 -288.84807) (xy 66.106196 -288.894751) (xy 66.083325 -288.938328)
			(xy 66.05376 -288.977672) (xy 66.018267 -289.011764) (xy 65.977764 -289.03972) (xy 65.933302 -289.060818)
			(xy 65.886031 -289.07451) (xy 65.837176 -289.080442) (xy 65.788001 -289.078461) (xy 65.739782 -289.068617)
			(xy 65.693766 -289.051165) (xy 65.651145 -289.026558) (xy 65.613024 -288.995433) (xy 65.580389 -288.958596)
			(xy 65.554086 -288.917) (xy 65.534795 -288.871724) (xy 65.523018 -288.82394) (xy 65.519058 -288.774886)
			(xy 65.18021 -288.774886) (xy 65.179715 -288.799493) (xy 65.17182 -288.84807) (xy 65.156236 -288.894751)
			(xy 65.133365 -288.938328) (xy 65.1038 -288.977672) (xy 65.068307 -289.011764) (xy 65.027804 -289.03972)
			(xy 64.983342 -289.060818) (xy 64.936071 -289.07451) (xy 64.887216 -289.080442) (xy 64.838041 -289.078461)
			(xy 64.789822 -289.068617) (xy 64.743806 -289.051165) (xy 64.701185 -289.026558) (xy 64.663064 -288.995433)
			(xy 64.630429 -288.958596) (xy 64.604126 -288.917) (xy 64.584835 -288.871724) (xy 64.573058 -288.82394)
			(xy 64.569098 -288.774886) (xy 64.23025 -288.774886) (xy 64.229755 -288.799493) (xy 64.22186 -288.84807)
			(xy 64.206276 -288.894751) (xy 64.183405 -288.938328) (xy 64.15384 -288.977672) (xy 64.118347 -289.011764)
			(xy 64.077844 -289.03972) (xy 64.033382 -289.060818) (xy 63.986111 -289.07451) (xy 63.937256 -289.080442)
			(xy 63.888081 -289.078461) (xy 63.839862 -289.068617) (xy 63.793846 -289.051165) (xy 63.751225 -289.026558)
			(xy 63.713104 -288.995433) (xy 63.680469 -288.958596) (xy 63.654166 -288.917) (xy 63.634875 -288.871724)
			(xy 63.623098 -288.82394) (xy 63.619138 -288.774886) (xy 63.28029 -288.774886) (xy 63.279795 -288.799493)
			(xy 63.2719 -288.84807) (xy 63.256316 -288.894751) (xy 63.233445 -288.938328) (xy 63.20388 -288.977672)
			(xy 63.168387 -289.011764) (xy 63.127884 -289.03972) (xy 63.083422 -289.060818) (xy 63.036151 -289.07451)
			(xy 62.987296 -289.080442) (xy 62.938121 -289.078461) (xy 62.889902 -289.068617) (xy 62.843886 -289.051165)
			(xy 62.801265 -289.026558) (xy 62.763144 -288.995433) (xy 62.730509 -288.958596) (xy 62.704206 -288.917)
			(xy 62.684915 -288.871724) (xy 62.673138 -288.82394) (xy 62.669178 -288.774886) (xy 62.330076 -288.774886)
			(xy 62.329581 -288.799493) (xy 62.321686 -288.84807) (xy 62.306102 -288.894751) (xy 62.283231 -288.938328)
			(xy 62.253666 -288.977672) (xy 62.218173 -289.011764) (xy 62.17767 -289.03972) (xy 62.133208 -289.060818)
			(xy 62.085937 -289.07451) (xy 62.037082 -289.080442) (xy 61.987907 -289.078461) (xy 61.939688 -289.068617)
			(xy 61.893672 -289.051165) (xy 61.851051 -289.026558) (xy 61.81293 -288.995433) (xy 61.780295 -288.958596)
			(xy 61.753992 -288.917) (xy 61.734701 -288.871724) (xy 61.722924 -288.82394) (xy 61.718964 -288.774886)
			(xy 61.380116 -288.774886) (xy 61.379621 -288.799493) (xy 61.371726 -288.84807) (xy 61.356142 -288.894751)
			(xy 61.333271 -288.938328) (xy 61.303706 -288.977672) (xy 61.268213 -289.011764) (xy 61.22771 -289.03972)
			(xy 61.183248 -289.060818) (xy 61.135977 -289.07451) (xy 61.087122 -289.080442) (xy 61.037947 -289.078461)
			(xy 60.989728 -289.068617) (xy 60.943712 -289.051165) (xy 60.901091 -289.026558) (xy 60.86297 -288.995433)
			(xy 60.830335 -288.958596) (xy 60.804032 -288.917) (xy 60.784741 -288.871724) (xy 60.772964 -288.82394)
			(xy 60.769004 -288.774886) (xy 60.430156 -288.774886) (xy 60.429661 -288.799493) (xy 60.421766 -288.84807)
			(xy 60.406182 -288.894751) (xy 60.383311 -288.938328) (xy 60.353746 -288.977672) (xy 60.318253 -289.011764)
			(xy 60.27775 -289.03972) (xy 60.233288 -289.060818) (xy 60.186017 -289.07451) (xy 60.137162 -289.080442)
			(xy 60.087987 -289.078461) (xy 60.039768 -289.068617) (xy 59.993752 -289.051165) (xy 59.951131 -289.026558)
			(xy 59.91301 -288.995433) (xy 59.880375 -288.958596) (xy 59.854072 -288.917) (xy 59.834781 -288.871724)
			(xy 59.823004 -288.82394) (xy 59.819044 -288.774886) (xy 58.530236 -288.774886) (xy 58.529741 -288.799493)
			(xy 58.521846 -288.84807) (xy 58.506262 -288.894751) (xy 58.483391 -288.938328) (xy 58.453826 -288.977672)
			(xy 58.418333 -289.011764) (xy 58.37783 -289.03972) (xy 58.333368 -289.060818) (xy 58.286097 -289.07451)
			(xy 58.237242 -289.080442) (xy 58.188067 -289.078461) (xy 58.139848 -289.068617) (xy 58.093832 -289.051165)
			(xy 58.051211 -289.026558) (xy 58.01309 -288.995433) (xy 57.980455 -288.958596) (xy 57.954152 -288.917)
			(xy 57.934861 -288.871724) (xy 57.923084 -288.82394) (xy 57.919124 -288.774886) (xy 57.580276 -288.774886)
			(xy 57.579781 -288.799493) (xy 57.571886 -288.84807) (xy 57.556302 -288.894751) (xy 57.533431 -288.938328)
			(xy 57.503866 -288.977672) (xy 57.468373 -289.011764) (xy 57.42787 -289.03972) (xy 57.383408 -289.060818)
			(xy 57.336137 -289.07451) (xy 57.287282 -289.080442) (xy 57.238107 -289.078461) (xy 57.189888 -289.068617)
			(xy 57.143872 -289.051165) (xy 57.101251 -289.026558) (xy 57.06313 -288.995433) (xy 57.030495 -288.958596)
			(xy 57.004192 -288.917) (xy 56.984901 -288.871724) (xy 56.973124 -288.82394) (xy 56.969164 -288.774886)
			(xy 56.630062 -288.774886) (xy 56.629567 -288.799493) (xy 56.621672 -288.84807) (xy 56.606088 -288.894751)
			(xy 56.583217 -288.938328) (xy 56.553652 -288.977672) (xy 56.518159 -289.011764) (xy 56.477656 -289.03972)
			(xy 56.433194 -289.060818) (xy 56.385923 -289.07451) (xy 56.337068 -289.080442) (xy 56.287893 -289.078461)
			(xy 56.239674 -289.068617) (xy 56.193658 -289.051165) (xy 56.151037 -289.026558) (xy 56.112916 -288.995433)
			(xy 56.080281 -288.958596) (xy 56.053978 -288.917) (xy 56.034687 -288.871724) (xy 56.02291 -288.82394)
			(xy 56.01895 -288.774886) (xy 55.680102 -288.774886) (xy 55.679607 -288.799493) (xy 55.671712 -288.84807)
			(xy 55.656128 -288.894751) (xy 55.633257 -288.938328) (xy 55.603692 -288.977672) (xy 55.568199 -289.011764)
			(xy 55.527696 -289.03972) (xy 55.483234 -289.060818) (xy 55.435963 -289.07451) (xy 55.387108 -289.080442)
			(xy 55.337933 -289.078461) (xy 55.289714 -289.068617) (xy 55.243698 -289.051165) (xy 55.201077 -289.026558)
			(xy 55.162956 -288.995433) (xy 55.130321 -288.958596) (xy 55.104018 -288.917) (xy 55.084727 -288.871724)
			(xy 55.07295 -288.82394) (xy 55.06899 -288.774886) (xy 54.730142 -288.774886) (xy 54.729647 -288.799493)
			(xy 54.721752 -288.84807) (xy 54.706168 -288.894751) (xy 54.683297 -288.938328) (xy 54.653732 -288.977672)
			(xy 54.618239 -289.011764) (xy 54.577736 -289.03972) (xy 54.533274 -289.060818) (xy 54.486003 -289.07451)
			(xy 54.437148 -289.080442) (xy 54.387973 -289.078461) (xy 54.339754 -289.068617) (xy 54.293738 -289.051165)
			(xy 54.251117 -289.026558) (xy 54.212996 -288.995433) (xy 54.180361 -288.958596) (xy 54.154058 -288.917)
			(xy 54.134767 -288.871724) (xy 54.12299 -288.82394) (xy 54.11903 -288.774886) (xy 53.780182 -288.774886)
			(xy 53.779687 -288.799493) (xy 53.771792 -288.84807) (xy 53.756208 -288.894751) (xy 53.733337 -288.938328)
			(xy 53.703772 -288.977672) (xy 53.668279 -289.011764) (xy 53.627776 -289.03972) (xy 53.583314 -289.060818)
			(xy 53.536043 -289.07451) (xy 53.487188 -289.080442) (xy 53.438013 -289.078461) (xy 53.389794 -289.068617)
			(xy 53.343778 -289.051165) (xy 53.301157 -289.026558) (xy 53.263036 -288.995433) (xy 53.230401 -288.958596)
			(xy 53.204098 -288.917) (xy 53.184807 -288.871724) (xy 53.17303 -288.82394) (xy 53.16907 -288.774886)
			(xy 52.830222 -288.774886) (xy 52.829727 -288.799493) (xy 52.821832 -288.84807) (xy 52.806248 -288.894751)
			(xy 52.783377 -288.938328) (xy 52.753812 -288.977672) (xy 52.718319 -289.011764) (xy 52.677816 -289.03972)
			(xy 52.633354 -289.060818) (xy 52.586083 -289.07451) (xy 52.537228 -289.080442) (xy 52.488053 -289.078461)
			(xy 52.439834 -289.068617) (xy 52.393818 -289.051165) (xy 52.351197 -289.026558) (xy 52.313076 -288.995433)
			(xy 52.280441 -288.958596) (xy 52.254138 -288.917) (xy 52.234847 -288.871724) (xy 52.22307 -288.82394)
			(xy 52.21911 -288.774886) (xy 51.880262 -288.774886) (xy 51.879767 -288.799493) (xy 51.871872 -288.84807)
			(xy 51.856288 -288.894751) (xy 51.833417 -288.938328) (xy 51.803852 -288.977672) (xy 51.768359 -289.011764)
			(xy 51.727856 -289.03972) (xy 51.683394 -289.060818) (xy 51.636123 -289.07451) (xy 51.587268 -289.080442)
			(xy 51.538093 -289.078461) (xy 51.489874 -289.068617) (xy 51.443858 -289.051165) (xy 51.401237 -289.026558)
			(xy 51.363116 -288.995433) (xy 51.330481 -288.958596) (xy 51.304178 -288.917) (xy 51.284887 -288.871724)
			(xy 51.27311 -288.82394) (xy 51.26915 -288.774886) (xy 50.930302 -288.774886) (xy 50.929807 -288.799493)
			(xy 50.921912 -288.84807) (xy 50.906328 -288.894751) (xy 50.883457 -288.938328) (xy 50.853892 -288.977672)
			(xy 50.818399 -289.011764) (xy 50.777896 -289.03972) (xy 50.733434 -289.060818) (xy 50.686163 -289.07451)
			(xy 50.637308 -289.080442) (xy 50.588133 -289.078461) (xy 50.539914 -289.068617) (xy 50.493898 -289.051165)
			(xy 50.451277 -289.026558) (xy 50.413156 -288.995433) (xy 50.380521 -288.958596) (xy 50.354218 -288.917)
			(xy 50.334927 -288.871724) (xy 50.32315 -288.82394) (xy 50.31919 -288.774886) (xy 49.980088 -288.774886)
			(xy 49.979593 -288.799493) (xy 49.971698 -288.84807) (xy 49.956114 -288.894751) (xy 49.933243 -288.938328)
			(xy 49.903678 -288.977672) (xy 49.868185 -289.011764) (xy 49.827682 -289.03972) (xy 49.78322 -289.060818)
			(xy 49.735949 -289.07451) (xy 49.687094 -289.080442) (xy 49.637919 -289.078461) (xy 49.5897 -289.068617)
			(xy 49.543684 -289.051165) (xy 49.501063 -289.026558) (xy 49.462942 -288.995433) (xy 49.430307 -288.958596)
			(xy 49.404004 -288.917) (xy 49.384713 -288.871724) (xy 49.372936 -288.82394) (xy 49.368976 -288.774886)
			(xy 49.030128 -288.774886) (xy 49.029633 -288.799493) (xy 49.021738 -288.84807) (xy 49.006154 -288.894751)
			(xy 48.983283 -288.938328) (xy 48.953718 -288.977672) (xy 48.918225 -289.011764) (xy 48.877722 -289.03972)
			(xy 48.83326 -289.060818) (xy 48.785989 -289.07451) (xy 48.737134 -289.080442) (xy 48.687959 -289.078461)
			(xy 48.63974 -289.068617) (xy 48.593724 -289.051165) (xy 48.551103 -289.026558) (xy 48.512982 -288.995433)
			(xy 48.480347 -288.958596) (xy 48.454044 -288.917) (xy 48.434753 -288.871724) (xy 48.422976 -288.82394)
			(xy 48.419016 -288.774886) (xy 48.080168 -288.774886) (xy 48.079673 -288.799493) (xy 48.071778 -288.84807)
			(xy 48.056194 -288.894751) (xy 48.033323 -288.938328) (xy 48.003758 -288.977672) (xy 47.968265 -289.011764)
			(xy 47.927762 -289.03972) (xy 47.8833 -289.060818) (xy 47.836029 -289.07451) (xy 47.787174 -289.080442)
			(xy 47.737999 -289.078461) (xy 47.68978 -289.068617) (xy 47.643764 -289.051165) (xy 47.601143 -289.026558)
			(xy 47.563022 -288.995433) (xy 47.530387 -288.958596) (xy 47.504084 -288.917) (xy 47.484793 -288.871724)
			(xy 47.473016 -288.82394) (xy 47.469056 -288.774886) (xy 47.130208 -288.774886) (xy 47.129713 -288.799493)
			(xy 47.121818 -288.84807) (xy 47.106234 -288.894751) (xy 47.083363 -288.938328) (xy 47.053798 -288.977672)
			(xy 47.018305 -289.011764) (xy 46.977802 -289.03972) (xy 46.93334 -289.060818) (xy 46.886069 -289.07451)
			(xy 46.837214 -289.080442) (xy 46.788039 -289.078461) (xy 46.73982 -289.068617) (xy 46.693804 -289.051165)
			(xy 46.651183 -289.026558) (xy 46.613062 -288.995433) (xy 46.580427 -288.958596) (xy 46.554124 -288.917)
			(xy 46.534833 -288.871724) (xy 46.523056 -288.82394) (xy 46.519096 -288.774886) (xy 46.180248 -288.774886)
			(xy 46.179753 -288.799493) (xy 46.171858 -288.84807) (xy 46.156274 -288.894751) (xy 46.133403 -288.938328)
			(xy 46.103838 -288.977672) (xy 46.068345 -289.011764) (xy 46.027842 -289.03972) (xy 45.98338 -289.060818)
			(xy 45.936109 -289.07451) (xy 45.887254 -289.080442) (xy 45.838079 -289.078461) (xy 45.78986 -289.068617)
			(xy 45.743844 -289.051165) (xy 45.701223 -289.026558) (xy 45.663102 -288.995433) (xy 45.630467 -288.958596)
			(xy 45.604164 -288.917) (xy 45.584873 -288.871724) (xy 45.573096 -288.82394) (xy 45.569136 -288.774886)
			(xy 45.230288 -288.774886) (xy 45.229793 -288.799493) (xy 45.221898 -288.84807) (xy 45.206314 -288.894751)
			(xy 45.183443 -288.938328) (xy 45.153878 -288.977672) (xy 45.118385 -289.011764) (xy 45.077882 -289.03972)
			(xy 45.03342 -289.060818) (xy 44.986149 -289.07451) (xy 44.937294 -289.080442) (xy 44.888119 -289.078461)
			(xy 44.8399 -289.068617) (xy 44.793884 -289.051165) (xy 44.751263 -289.026558) (xy 44.713142 -288.995433)
			(xy 44.680507 -288.958596) (xy 44.654204 -288.917) (xy 44.634913 -288.871724) (xy 44.623136 -288.82394)
			(xy 44.619176 -288.774886) (xy 44.305257 -288.774886) (xy 44.305257 -288.800409) (xy 44.297119 -288.851787)
			(xy 44.281043 -288.901259) (xy 44.257426 -288.947607) (xy 44.226848 -288.98969) (xy 44.190064 -289.02647)
			(xy 44.147978 -289.057043) (xy 44.101628 -289.080656) (xy 44.052154 -289.096726) (xy 44.000775 -289.104859)
			(xy 43.974766 -289.10534) (xy 43.024806 -289.10534) (xy 42.998795 -289.104901) (xy 42.947413 -289.096764)
			(xy 42.897936 -289.080689) (xy 42.851583 -289.057071) (xy 42.809496 -289.026494) (xy 42.77271 -288.989709)
			(xy 42.742132 -288.947622) (xy 42.718514 -288.90127) (xy 42.702438 -288.851793) (xy 42.694299 -288.800411)
			(xy 42.37951 -288.800411) (xy 42.371764 -288.84807) (xy 42.35618 -288.894751) (xy 42.333309 -288.938328)
			(xy 42.303744 -288.977672) (xy 42.268251 -289.011764) (xy 42.227748 -289.03972) (xy 42.183286 -289.060818)
			(xy 42.136015 -289.07451) (xy 42.08716 -289.080442) (xy 42.037985 -289.078461) (xy 41.989766 -289.068617)
			(xy 41.94375 -289.051165) (xy 41.901129 -289.026558) (xy 41.863008 -288.995433) (xy 41.830373 -288.958596)
			(xy 41.80407 -288.917) (xy 41.784779 -288.871724) (xy 41.773002 -288.82394) (xy 41.769042 -288.774886)
			(xy 38.580314 -288.774886) (xy 38.579819 -288.799493) (xy 38.571924 -288.84807) (xy 38.55634 -288.894751)
			(xy 38.533469 -288.938328) (xy 38.503904 -288.977672) (xy 38.468411 -289.011764) (xy 38.427908 -289.03972)
			(xy 38.383446 -289.060818) (xy 38.336175 -289.07451) (xy 38.28732 -289.080442) (xy 38.238145 -289.078461)
			(xy 38.189926 -289.068617) (xy 38.14391 -289.051165) (xy 38.101289 -289.026558) (xy 38.063168 -288.995433)
			(xy 38.030533 -288.958596) (xy 38.00423 -288.917) (xy 37.984939 -288.871724) (xy 37.973162 -288.82394)
			(xy 37.969202 -288.774886) (xy 37.655257 -288.774886) (xy 37.655257 -288.800408) (xy 37.647119 -288.851783)
			(xy 37.631045 -288.901253) (xy 37.60743 -288.947599) (xy 37.576856 -288.989681) (xy 37.540075 -289.026461)
			(xy 37.497993 -289.057035) (xy 37.451646 -289.080649) (xy 37.402175 -289.096721) (xy 37.3508 -289.104857)
			(xy 37.324792 -289.10534) (xy 36.374832 -289.10534) (xy 36.348819 -289.104903) (xy 36.297434 -289.096769)
			(xy 36.247954 -289.080696) (xy 36.201598 -289.05708) (xy 36.159507 -289.026503) (xy 36.122718 -288.989718)
			(xy 36.092136 -288.94763) (xy 36.068516 -288.901276) (xy 36.052439 -288.851797) (xy 36.0443 -288.800413)
			(xy 35.729416 -288.800413) (xy 35.722569 -288.844698) (xy 35.708401 -288.889417) (xy 35.687566 -288.931444)
			(xy 35.660553 -288.969794) (xy 35.644582 -288.986976) (xy 35.638207 -288.994165) (xy 35.630907 -289.011926)
			(xy 35.630358 -289.02152) (xy 35.62985 -289.053016) (xy 35.630176 -289.063218) (xy 35.637915 -289.082088)
			(xy 35.644836 -289.089592) (xy 36.040822 -289.485578) (xy 36.0478 -289.491988) (xy 36.065159 -289.499553)
			(xy 36.074604 -289.50031) (xy 36.152836 -289.503612) (xy 36.17087 -289.497516) (xy 36.177982 -289.49142)
			(xy 36.198803 -289.474604) (xy 36.245105 -289.447768) (xy 36.295375 -289.429409) (xy 36.348074 -289.42009)
			(xy 36.374832 -289.419538) (xy 36.398828 -289.419909) (xy 36.446229 -289.427422) (xy 36.491871 -289.442258)
			(xy 36.534631 -289.464051) (xy 36.573454 -289.492265) (xy 36.607386 -289.526205) (xy 36.63559 -289.565036)
			(xy 36.657372 -289.607801) (xy 36.672196 -289.653447) (xy 36.679697 -289.70085) (xy 36.68014 -289.724846)
			(xy 37.018988 -289.724846) (xy 37.022948 -289.675792) (xy 37.034725 -289.628008) (xy 37.054016 -289.582732)
			(xy 37.080319 -289.541136) (xy 37.112954 -289.504299) (xy 37.151075 -289.473174) (xy 37.193696 -289.448567)
			(xy 37.239712 -289.431115) (xy 37.287931 -289.421271) (xy 37.337106 -289.41929) (xy 37.385961 -289.425222)
			(xy 37.433232 -289.438914) (xy 37.477694 -289.460012) (xy 37.518197 -289.487968) (xy 37.55369 -289.52206)
			(xy 37.583255 -289.561404) (xy 37.606126 -289.604981) (xy 37.62171 -289.651662) (xy 37.629605 -289.700239)
			(xy 37.6301 -289.724846) (xy 37.969202 -289.724846) (xy 37.973162 -289.675792) (xy 37.984939 -289.628008)
			(xy 38.00423 -289.582732) (xy 38.030533 -289.541136) (xy 38.063168 -289.504299) (xy 38.101289 -289.473174)
			(xy 38.14391 -289.448567) (xy 38.189926 -289.431115) (xy 38.238145 -289.421271) (xy 38.28732 -289.41929)
			(xy 38.336175 -289.425222) (xy 38.383446 -289.438914) (xy 38.427908 -289.460012) (xy 38.468411 -289.487968)
			(xy 38.503904 -289.52206) (xy 38.533469 -289.561404) (xy 38.55634 -289.604981) (xy 38.571924 -289.651662)
			(xy 38.579819 -289.700239) (xy 38.580314 -289.724846) (xy 38.919162 -289.724846) (xy 38.923122 -289.675792)
			(xy 38.934899 -289.628008) (xy 38.95419 -289.582732) (xy 38.980493 -289.541136) (xy 39.013128 -289.504299)
			(xy 39.051249 -289.473174) (xy 39.09387 -289.448567) (xy 39.139886 -289.431115) (xy 39.188105 -289.421271)
			(xy 39.23728 -289.41929) (xy 39.286135 -289.425222) (xy 39.333406 -289.438914) (xy 39.377868 -289.460012)
			(xy 39.418371 -289.487968) (xy 39.453864 -289.52206) (xy 39.483429 -289.561404) (xy 39.5063 -289.604981)
			(xy 39.521884 -289.651662) (xy 39.529779 -289.700239) (xy 39.530274 -289.724846) (xy 39.869122 -289.724846)
			(xy 39.873082 -289.675792) (xy 39.884859 -289.628008) (xy 39.90415 -289.582732) (xy 39.930453 -289.541136)
			(xy 39.963088 -289.504299) (xy 40.001209 -289.473174) (xy 40.04383 -289.448567) (xy 40.089846 -289.431115)
			(xy 40.138065 -289.421271) (xy 40.18724 -289.41929) (xy 40.236095 -289.425222) (xy 40.283366 -289.438914)
			(xy 40.327828 -289.460012) (xy 40.368331 -289.487968) (xy 40.403824 -289.52206) (xy 40.433389 -289.561404)
			(xy 40.45626 -289.604981) (xy 40.471844 -289.651662) (xy 40.479739 -289.700239) (xy 40.480234 -289.724846)
			(xy 40.819082 -289.724846) (xy 40.823042 -289.675792) (xy 40.834819 -289.628008) (xy 40.85411 -289.582732)
			(xy 40.880413 -289.541136) (xy 40.913048 -289.504299) (xy 40.951169 -289.473174) (xy 40.99379 -289.448567)
			(xy 41.039806 -289.431115) (xy 41.088025 -289.421271) (xy 41.1372 -289.41929) (xy 41.186055 -289.425222)
			(xy 41.233326 -289.438914) (xy 41.277788 -289.460012) (xy 41.318291 -289.487968) (xy 41.353784 -289.52206)
			(xy 41.383349 -289.561404) (xy 41.40622 -289.604981) (xy 41.421804 -289.651662) (xy 41.429699 -289.700239)
			(xy 41.430194 -289.724846) (xy 41.769042 -289.724846) (xy 41.773002 -289.675792) (xy 41.784779 -289.628008)
			(xy 41.80407 -289.582732) (xy 41.830373 -289.541136) (xy 41.863008 -289.504299) (xy 41.901129 -289.473174)
			(xy 41.94375 -289.448567) (xy 41.989766 -289.431115) (xy 42.037985 -289.421271) (xy 42.08716 -289.41929)
			(xy 42.136015 -289.425222) (xy 42.183286 -289.438914) (xy 42.227748 -289.460012) (xy 42.268251 -289.487968)
			(xy 42.303744 -289.52206) (xy 42.333309 -289.561404) (xy 42.35618 -289.604981) (xy 42.371764 -289.651662)
			(xy 42.379659 -289.700239) (xy 42.380154 -289.724846) (xy 42.719002 -289.724846) (xy 42.722962 -289.675792)
			(xy 42.734739 -289.628008) (xy 42.75403 -289.582732) (xy 42.780333 -289.541136) (xy 42.812968 -289.504299)
			(xy 42.851089 -289.473174) (xy 42.89371 -289.448567) (xy 42.939726 -289.431115) (xy 42.987945 -289.421271)
			(xy 43.03712 -289.41929) (xy 43.085975 -289.425222) (xy 43.133246 -289.438914) (xy 43.177708 -289.460012)
			(xy 43.218211 -289.487968) (xy 43.253704 -289.52206) (xy 43.283269 -289.561404) (xy 43.30614 -289.604981)
			(xy 43.321724 -289.651662) (xy 43.329619 -289.700239) (xy 43.330114 -289.724846) (xy 43.668962 -289.724846)
			(xy 43.672922 -289.675792) (xy 43.684699 -289.628008) (xy 43.70399 -289.582732) (xy 43.730293 -289.541136)
			(xy 43.762928 -289.504299) (xy 43.801049 -289.473174) (xy 43.84367 -289.448567) (xy 43.889686 -289.431115)
			(xy 43.937905 -289.421271) (xy 43.98708 -289.41929) (xy 44.035935 -289.425222) (xy 44.083206 -289.438914)
			(xy 44.127668 -289.460012) (xy 44.168171 -289.487968) (xy 44.203664 -289.52206) (xy 44.233229 -289.561404)
			(xy 44.2561 -289.604981) (xy 44.271684 -289.651662) (xy 44.279579 -289.700239) (xy 44.280074 -289.724846)
			(xy 44.619176 -289.724846) (xy 44.623136 -289.675792) (xy 44.634913 -289.628008) (xy 44.654204 -289.582732)
			(xy 44.680507 -289.541136) (xy 44.713142 -289.504299) (xy 44.751263 -289.473174) (xy 44.793884 -289.448567)
			(xy 44.8399 -289.431115) (xy 44.888119 -289.421271) (xy 44.937294 -289.41929) (xy 44.986149 -289.425222)
			(xy 45.03342 -289.438914) (xy 45.077882 -289.460012) (xy 45.118385 -289.487968) (xy 45.153878 -289.52206)
			(xy 45.183443 -289.561404) (xy 45.206314 -289.604981) (xy 45.221898 -289.651662) (xy 45.229793 -289.700239)
			(xy 45.230288 -289.724846) (xy 45.569136 -289.724846) (xy 45.573096 -289.675792) (xy 45.584873 -289.628008)
			(xy 45.604164 -289.582732) (xy 45.630467 -289.541136) (xy 45.663102 -289.504299) (xy 45.701223 -289.473174)
			(xy 45.743844 -289.448567) (xy 45.78986 -289.431115) (xy 45.838079 -289.421271) (xy 45.887254 -289.41929)
			(xy 45.936109 -289.425222) (xy 45.98338 -289.438914) (xy 46.027842 -289.460012) (xy 46.068345 -289.487968)
			(xy 46.103838 -289.52206) (xy 46.133403 -289.561404) (xy 46.156274 -289.604981) (xy 46.171858 -289.651662)
			(xy 46.179753 -289.700239) (xy 46.180248 -289.724846) (xy 46.519096 -289.724846) (xy 46.523056 -289.675792)
			(xy 46.534833 -289.628008) (xy 46.554124 -289.582732) (xy 46.580427 -289.541136) (xy 46.613062 -289.504299)
			(xy 46.651183 -289.473174) (xy 46.693804 -289.448567) (xy 46.73982 -289.431115) (xy 46.788039 -289.421271)
			(xy 46.837214 -289.41929) (xy 46.886069 -289.425222) (xy 46.93334 -289.438914) (xy 46.977802 -289.460012)
			(xy 47.018305 -289.487968) (xy 47.053798 -289.52206) (xy 47.083363 -289.561404) (xy 47.106234 -289.604981)
			(xy 47.121818 -289.651662) (xy 47.129713 -289.700239) (xy 47.130208 -289.724846) (xy 47.469056 -289.724846)
			(xy 47.473016 -289.675792) (xy 47.484793 -289.628008) (xy 47.504084 -289.582732) (xy 47.530387 -289.541136)
			(xy 47.563022 -289.504299) (xy 47.601143 -289.473174) (xy 47.643764 -289.448567) (xy 47.68978 -289.431115)
			(xy 47.737999 -289.421271) (xy 47.787174 -289.41929) (xy 47.836029 -289.425222) (xy 47.8833 -289.438914)
			(xy 47.927762 -289.460012) (xy 47.968265 -289.487968) (xy 48.003758 -289.52206) (xy 48.033323 -289.561404)
			(xy 48.056194 -289.604981) (xy 48.071778 -289.651662) (xy 48.079673 -289.700239) (xy 48.080168 -289.724846)
			(xy 48.419016 -289.724846) (xy 48.422976 -289.675792) (xy 48.434753 -289.628008) (xy 48.454044 -289.582732)
			(xy 48.480347 -289.541136) (xy 48.512982 -289.504299) (xy 48.551103 -289.473174) (xy 48.593724 -289.448567)
			(xy 48.63974 -289.431115) (xy 48.687959 -289.421271) (xy 48.737134 -289.41929) (xy 48.785989 -289.425222)
			(xy 48.83326 -289.438914) (xy 48.877722 -289.460012) (xy 48.918225 -289.487968) (xy 48.953718 -289.52206)
			(xy 48.983283 -289.561404) (xy 49.006154 -289.604981) (xy 49.021738 -289.651662) (xy 49.029633 -289.700239)
			(xy 49.030128 -289.724846) (xy 49.368976 -289.724846) (xy 49.372936 -289.675792) (xy 49.384713 -289.628008)
			(xy 49.404004 -289.582732) (xy 49.430307 -289.541136) (xy 49.462942 -289.504299) (xy 49.501063 -289.473174)
			(xy 49.543684 -289.448567) (xy 49.5897 -289.431115) (xy 49.637919 -289.421271) (xy 49.687094 -289.41929)
			(xy 49.735949 -289.425222) (xy 49.78322 -289.438914) (xy 49.827682 -289.460012) (xy 49.868185 -289.487968)
			(xy 49.903678 -289.52206) (xy 49.933243 -289.561404) (xy 49.956114 -289.604981) (xy 49.971698 -289.651662)
			(xy 49.979593 -289.700239) (xy 49.980088 -289.724846) (xy 50.31919 -289.724846) (xy 50.32315 -289.675792)
			(xy 50.334927 -289.628008) (xy 50.354218 -289.582732) (xy 50.380521 -289.541136) (xy 50.413156 -289.504299)
			(xy 50.451277 -289.473174) (xy 50.493898 -289.448567) (xy 50.539914 -289.431115) (xy 50.588133 -289.421271)
			(xy 50.637308 -289.41929) (xy 50.686163 -289.425222) (xy 50.733434 -289.438914) (xy 50.777896 -289.460012)
			(xy 50.818399 -289.487968) (xy 50.853892 -289.52206) (xy 50.883457 -289.561404) (xy 50.906328 -289.604981)
			(xy 50.921912 -289.651662) (xy 50.929807 -289.700239) (xy 50.930302 -289.724846) (xy 51.26915 -289.724846)
			(xy 51.27311 -289.675792) (xy 51.284887 -289.628008) (xy 51.304178 -289.582732) (xy 51.330481 -289.541136)
			(xy 51.363116 -289.504299) (xy 51.401237 -289.473174) (xy 51.443858 -289.448567) (xy 51.489874 -289.431115)
			(xy 51.538093 -289.421271) (xy 51.587268 -289.41929) (xy 51.636123 -289.425222) (xy 51.683394 -289.438914)
			(xy 51.727856 -289.460012) (xy 51.768359 -289.487968) (xy 51.803852 -289.52206) (xy 51.833417 -289.561404)
			(xy 51.856288 -289.604981) (xy 51.871872 -289.651662) (xy 51.879767 -289.700239) (xy 51.880262 -289.724846)
			(xy 52.21911 -289.724846) (xy 52.22307 -289.675792) (xy 52.234847 -289.628008) (xy 52.254138 -289.582732)
			(xy 52.280441 -289.541136) (xy 52.313076 -289.504299) (xy 52.351197 -289.473174) (xy 52.393818 -289.448567)
			(xy 52.439834 -289.431115) (xy 52.488053 -289.421271) (xy 52.537228 -289.41929) (xy 52.586083 -289.425222)
			(xy 52.633354 -289.438914) (xy 52.677816 -289.460012) (xy 52.718319 -289.487968) (xy 52.753812 -289.52206)
			(xy 52.783377 -289.561404) (xy 52.806248 -289.604981) (xy 52.821832 -289.651662) (xy 52.829727 -289.700239)
			(xy 52.830222 -289.724846) (xy 53.16907 -289.724846) (xy 53.17303 -289.675792) (xy 53.184807 -289.628008)
			(xy 53.204098 -289.582732) (xy 53.230401 -289.541136) (xy 53.263036 -289.504299) (xy 53.301157 -289.473174)
			(xy 53.343778 -289.448567) (xy 53.389794 -289.431115) (xy 53.438013 -289.421271) (xy 53.487188 -289.41929)
			(xy 53.536043 -289.425222) (xy 53.583314 -289.438914) (xy 53.627776 -289.460012) (xy 53.668279 -289.487968)
			(xy 53.703772 -289.52206) (xy 53.733337 -289.561404) (xy 53.756208 -289.604981) (xy 53.771792 -289.651662)
			(xy 53.779687 -289.700239) (xy 53.780182 -289.724846) (xy 54.11903 -289.724846) (xy 54.12299 -289.675792)
			(xy 54.134767 -289.628008) (xy 54.154058 -289.582732) (xy 54.180361 -289.541136) (xy 54.212996 -289.504299)
			(xy 54.251117 -289.473174) (xy 54.293738 -289.448567) (xy 54.339754 -289.431115) (xy 54.387973 -289.421271)
			(xy 54.437148 -289.41929) (xy 54.486003 -289.425222) (xy 54.533274 -289.438914) (xy 54.577736 -289.460012)
			(xy 54.618239 -289.487968) (xy 54.653732 -289.52206) (xy 54.683297 -289.561404) (xy 54.706168 -289.604981)
			(xy 54.721752 -289.651662) (xy 54.729647 -289.700239) (xy 54.730142 -289.724846) (xy 55.06899 -289.724846)
			(xy 55.07295 -289.675792) (xy 55.084727 -289.628008) (xy 55.104018 -289.582732) (xy 55.130321 -289.541136)
			(xy 55.162956 -289.504299) (xy 55.201077 -289.473174) (xy 55.243698 -289.448567) (xy 55.289714 -289.431115)
			(xy 55.337933 -289.421271) (xy 55.387108 -289.41929) (xy 55.435963 -289.425222) (xy 55.483234 -289.438914)
			(xy 55.527696 -289.460012) (xy 55.568199 -289.487968) (xy 55.603692 -289.52206) (xy 55.633257 -289.561404)
			(xy 55.656128 -289.604981) (xy 55.671712 -289.651662) (xy 55.679607 -289.700239) (xy 55.680102 -289.724846)
			(xy 56.01895 -289.724846) (xy 56.02291 -289.675792) (xy 56.034687 -289.628008) (xy 56.053978 -289.582732)
			(xy 56.080281 -289.541136) (xy 56.112916 -289.504299) (xy 56.151037 -289.473174) (xy 56.193658 -289.448567)
			(xy 56.239674 -289.431115) (xy 56.287893 -289.421271) (xy 56.337068 -289.41929) (xy 56.385923 -289.425222)
			(xy 56.433194 -289.438914) (xy 56.477656 -289.460012) (xy 56.518159 -289.487968) (xy 56.553652 -289.52206)
			(xy 56.583217 -289.561404) (xy 56.606088 -289.604981) (xy 56.621672 -289.651662) (xy 56.629567 -289.700239)
			(xy 56.630062 -289.724846) (xy 56.969164 -289.724846) (xy 56.973124 -289.675792) (xy 56.984901 -289.628008)
			(xy 57.004192 -289.582732) (xy 57.030495 -289.541136) (xy 57.06313 -289.504299) (xy 57.101251 -289.473174)
			(xy 57.143872 -289.448567) (xy 57.189888 -289.431115) (xy 57.238107 -289.421271) (xy 57.287282 -289.41929)
			(xy 57.336137 -289.425222) (xy 57.383408 -289.438914) (xy 57.42787 -289.460012) (xy 57.468373 -289.487968)
			(xy 57.503866 -289.52206) (xy 57.533431 -289.561404) (xy 57.556302 -289.604981) (xy 57.571886 -289.651662)
			(xy 57.579781 -289.700239) (xy 57.580276 -289.724846) (xy 57.919124 -289.724846) (xy 57.923084 -289.675792)
			(xy 57.934861 -289.628008) (xy 57.954152 -289.582732) (xy 57.980455 -289.541136) (xy 58.01309 -289.504299)
			(xy 58.051211 -289.473174) (xy 58.093832 -289.448567) (xy 58.139848 -289.431115) (xy 58.188067 -289.421271)
			(xy 58.237242 -289.41929) (xy 58.286097 -289.425222) (xy 58.333368 -289.438914) (xy 58.37783 -289.460012)
			(xy 58.418333 -289.487968) (xy 58.453826 -289.52206) (xy 58.483391 -289.561404) (xy 58.506262 -289.604981)
			(xy 58.521846 -289.651662) (xy 58.529741 -289.700239) (xy 58.530236 -289.724846) (xy 59.819044 -289.724846)
			(xy 59.823004 -289.675792) (xy 59.834781 -289.628008) (xy 59.854072 -289.582732) (xy 59.880375 -289.541136)
			(xy 59.91301 -289.504299) (xy 59.951131 -289.473174) (xy 59.993752 -289.448567) (xy 60.039768 -289.431115)
			(xy 60.087987 -289.421271) (xy 60.137162 -289.41929) (xy 60.186017 -289.425222) (xy 60.233288 -289.438914)
			(xy 60.27775 -289.460012) (xy 60.318253 -289.487968) (xy 60.353746 -289.52206) (xy 60.383311 -289.561404)
			(xy 60.406182 -289.604981) (xy 60.421766 -289.651662) (xy 60.429661 -289.700239) (xy 60.430156 -289.724846)
			(xy 60.769004 -289.724846) (xy 60.772964 -289.675792) (xy 60.784741 -289.628008) (xy 60.804032 -289.582732)
			(xy 60.830335 -289.541136) (xy 60.86297 -289.504299) (xy 60.901091 -289.473174) (xy 60.943712 -289.448567)
			(xy 60.989728 -289.431115) (xy 61.037947 -289.421271) (xy 61.087122 -289.41929) (xy 61.135977 -289.425222)
			(xy 61.183248 -289.438914) (xy 61.22771 -289.460012) (xy 61.268213 -289.487968) (xy 61.303706 -289.52206)
			(xy 61.333271 -289.561404) (xy 61.356142 -289.604981) (xy 61.371726 -289.651662) (xy 61.379621 -289.700239)
			(xy 61.380116 -289.724846) (xy 61.718964 -289.724846) (xy 61.722924 -289.675792) (xy 61.734701 -289.628008)
			(xy 61.753992 -289.582732) (xy 61.780295 -289.541136) (xy 61.81293 -289.504299) (xy 61.851051 -289.473174)
			(xy 61.893672 -289.448567) (xy 61.939688 -289.431115) (xy 61.987907 -289.421271) (xy 62.037082 -289.41929)
			(xy 62.085937 -289.425222) (xy 62.133208 -289.438914) (xy 62.17767 -289.460012) (xy 62.218173 -289.487968)
			(xy 62.253666 -289.52206) (xy 62.283231 -289.561404) (xy 62.306102 -289.604981) (xy 62.321686 -289.651662)
			(xy 62.329581 -289.700239) (xy 62.330076 -289.724846) (xy 62.669178 -289.724846) (xy 62.673138 -289.675792)
			(xy 62.684915 -289.628008) (xy 62.704206 -289.582732) (xy 62.730509 -289.541136) (xy 62.763144 -289.504299)
			(xy 62.801265 -289.473174) (xy 62.843886 -289.448567) (xy 62.889902 -289.431115) (xy 62.938121 -289.421271)
			(xy 62.987296 -289.41929) (xy 63.036151 -289.425222) (xy 63.083422 -289.438914) (xy 63.127884 -289.460012)
			(xy 63.168387 -289.487968) (xy 63.20388 -289.52206) (xy 63.233445 -289.561404) (xy 63.256316 -289.604981)
			(xy 63.2719 -289.651662) (xy 63.279795 -289.700239) (xy 63.28029 -289.724846) (xy 63.619138 -289.724846)
			(xy 63.623098 -289.675792) (xy 63.634875 -289.628008) (xy 63.654166 -289.582732) (xy 63.680469 -289.541136)
			(xy 63.713104 -289.504299) (xy 63.751225 -289.473174) (xy 63.793846 -289.448567) (xy 63.839862 -289.431115)
			(xy 63.888081 -289.421271) (xy 63.937256 -289.41929) (xy 63.986111 -289.425222) (xy 64.033382 -289.438914)
			(xy 64.077844 -289.460012) (xy 64.118347 -289.487968) (xy 64.15384 -289.52206) (xy 64.183405 -289.561404)
			(xy 64.206276 -289.604981) (xy 64.22186 -289.651662) (xy 64.229755 -289.700239) (xy 64.23025 -289.724846)
			(xy 64.569098 -289.724846) (xy 64.573058 -289.675792) (xy 64.584835 -289.628008) (xy 64.604126 -289.582732)
			(xy 64.630429 -289.541136) (xy 64.663064 -289.504299) (xy 64.701185 -289.473174) (xy 64.743806 -289.448567)
			(xy 64.789822 -289.431115) (xy 64.838041 -289.421271) (xy 64.887216 -289.41929) (xy 64.936071 -289.425222)
			(xy 64.983342 -289.438914) (xy 65.027804 -289.460012) (xy 65.068307 -289.487968) (xy 65.1038 -289.52206)
			(xy 65.133365 -289.561404) (xy 65.156236 -289.604981) (xy 65.17182 -289.651662) (xy 65.179715 -289.700239)
			(xy 65.18021 -289.724846) (xy 65.519058 -289.724846) (xy 65.523018 -289.675792) (xy 65.534795 -289.628008)
			(xy 65.554086 -289.582732) (xy 65.580389 -289.541136) (xy 65.613024 -289.504299) (xy 65.651145 -289.473174)
			(xy 65.693766 -289.448567) (xy 65.739782 -289.431115) (xy 65.788001 -289.421271) (xy 65.837176 -289.41929)
			(xy 65.886031 -289.425222) (xy 65.933302 -289.438914) (xy 65.977764 -289.460012) (xy 66.018267 -289.487968)
			(xy 66.05376 -289.52206) (xy 66.083325 -289.561404) (xy 66.106196 -289.604981) (xy 66.12178 -289.651662)
			(xy 66.129675 -289.700239) (xy 66.13017 -289.724846) (xy 66.469018 -289.724846) (xy 66.472978 -289.675792)
			(xy 66.484755 -289.628008) (xy 66.504046 -289.582732) (xy 66.530349 -289.541136) (xy 66.562984 -289.504299)
			(xy 66.601105 -289.473174) (xy 66.643726 -289.448567) (xy 66.689742 -289.431115) (xy 66.737961 -289.421271)
			(xy 66.787136 -289.41929) (xy 66.835991 -289.425222) (xy 66.883262 -289.438914) (xy 66.927724 -289.460012)
			(xy 66.968227 -289.487968) (xy 67.00372 -289.52206) (xy 67.033285 -289.561404) (xy 67.056156 -289.604981)
			(xy 67.07174 -289.651662) (xy 67.079635 -289.700239) (xy 67.08013 -289.724846) (xy 67.418978 -289.724846)
			(xy 67.422938 -289.675792) (xy 67.434715 -289.628008) (xy 67.454006 -289.582732) (xy 67.480309 -289.541136)
			(xy 67.512944 -289.504299) (xy 67.551065 -289.473174) (xy 67.593686 -289.448567) (xy 67.639702 -289.431115)
			(xy 67.687921 -289.421271) (xy 67.737096 -289.41929) (xy 67.785951 -289.425222) (xy 67.833222 -289.438914)
			(xy 67.877684 -289.460012) (xy 67.918187 -289.487968) (xy 67.95368 -289.52206) (xy 67.983245 -289.561404)
			(xy 68.006116 -289.604981) (xy 68.0217 -289.651662) (xy 68.029595 -289.700239) (xy 68.03009 -289.724846)
			(xy 68.368938 -289.724846) (xy 68.372898 -289.675792) (xy 68.384675 -289.628008) (xy 68.403966 -289.582732)
			(xy 68.430269 -289.541136) (xy 68.462904 -289.504299) (xy 68.501025 -289.473174) (xy 68.543646 -289.448567)
			(xy 68.589662 -289.431115) (xy 68.637881 -289.421271) (xy 68.687056 -289.41929) (xy 68.735911 -289.425222)
			(xy 68.783182 -289.438914) (xy 68.827644 -289.460012) (xy 68.868147 -289.487968) (xy 68.90364 -289.52206)
			(xy 68.933205 -289.561404) (xy 68.956076 -289.604981) (xy 68.97166 -289.651662) (xy 68.979555 -289.700239)
			(xy 68.98005 -289.724846) (xy 69.319152 -289.724846) (xy 69.323112 -289.675792) (xy 69.334889 -289.628008)
			(xy 69.35418 -289.582732) (xy 69.380483 -289.541136) (xy 69.413118 -289.504299) (xy 69.451239 -289.473174)
			(xy 69.49386 -289.448567) (xy 69.539876 -289.431115) (xy 69.588095 -289.421271) (xy 69.63727 -289.41929)
			(xy 69.686125 -289.425222) (xy 69.733396 -289.438914) (xy 69.777858 -289.460012) (xy 69.818361 -289.487968)
			(xy 69.853854 -289.52206) (xy 69.883419 -289.561404) (xy 69.90629 -289.604981) (xy 69.921874 -289.651662)
			(xy 69.929769 -289.700239) (xy 69.930264 -289.724846) (xy 70.269112 -289.724846) (xy 70.273072 -289.675792)
			(xy 70.284849 -289.628008) (xy 70.30414 -289.582732) (xy 70.330443 -289.541136) (xy 70.363078 -289.504299)
			(xy 70.401199 -289.473174) (xy 70.44382 -289.448567) (xy 70.489836 -289.431115) (xy 70.538055 -289.421271)
			(xy 70.58723 -289.41929) (xy 70.636085 -289.425222) (xy 70.683356 -289.438914) (xy 70.727818 -289.460012)
			(xy 70.768321 -289.487968) (xy 70.803814 -289.52206) (xy 70.833379 -289.561404) (xy 70.85625 -289.604981)
			(xy 70.871834 -289.651662) (xy 70.879729 -289.700239) (xy 70.880224 -289.724846) (xy 71.219072 -289.724846)
			(xy 71.223032 -289.675792) (xy 71.234809 -289.628008) (xy 71.2541 -289.582732) (xy 71.280403 -289.541136)
			(xy 71.313038 -289.504299) (xy 71.351159 -289.473174) (xy 71.39378 -289.448567) (xy 71.439796 -289.431115)
			(xy 71.488015 -289.421271) (xy 71.53719 -289.41929) (xy 71.586045 -289.425222) (xy 71.633316 -289.438914)
			(xy 71.677778 -289.460012) (xy 71.718281 -289.487968) (xy 71.753774 -289.52206) (xy 71.783339 -289.561404)
			(xy 71.80621 -289.604981) (xy 71.821794 -289.651662) (xy 71.829689 -289.700239) (xy 71.830184 -289.724846)
			(xy 72.169032 -289.724846) (xy 72.172992 -289.675792) (xy 72.184769 -289.628008) (xy 72.20406 -289.582732)
			(xy 72.230363 -289.541136) (xy 72.262998 -289.504299) (xy 72.301119 -289.473174) (xy 72.34374 -289.448567)
			(xy 72.389756 -289.431115) (xy 72.437975 -289.421271) (xy 72.48715 -289.41929) (xy 72.536005 -289.425222)
			(xy 72.583276 -289.438914) (xy 72.627738 -289.460012) (xy 72.668241 -289.487968) (xy 72.703734 -289.52206)
			(xy 72.733299 -289.561404) (xy 72.75617 -289.604981) (xy 72.771754 -289.651662) (xy 72.779649 -289.700239)
			(xy 72.779976 -289.716507) (xy 73.119127 -289.716507) (xy 73.124496 -289.667166) (xy 73.137775 -289.619343)
			(xy 73.158617 -289.574298) (xy 73.186471 -289.533218) (xy 73.220603 -289.497186) (xy 73.260116 -289.46715)
			(xy 73.303967 -289.443902) (xy 73.351001 -289.428054) (xy 73.39998 -289.420024) (xy 73.424796 -289.419538)
			(xy 73.438979 -289.419714) (xy 73.467219 -289.422387) (xy 73.481184 -289.424872) (xy 73.49363 -289.427158)
			(xy 73.517252 -289.419792) (xy 73.594722 -289.342322) (xy 73.602088 -289.3187) (xy 73.599802 -289.306254)
			(xy 73.597323 -289.292289) (xy 73.594653 -289.264049) (xy 73.594468 -289.249866) (xy 73.59499 -289.224611)
			(xy 73.603303 -289.174789) (xy 73.619704 -289.127015) (xy 73.643745 -289.082592) (xy 73.674769 -289.042732)
			(xy 73.711931 -289.008522) (xy 73.754217 -288.980896) (xy 73.800473 -288.960606) (xy 73.849438 -288.948206)
			(xy 73.899776 -288.944035) (xy 73.950114 -288.948206) (xy 73.999079 -288.960606) (xy 74.045335 -288.980896)
			(xy 74.087621 -289.008522) (xy 74.124783 -289.042732) (xy 74.155807 -289.082592) (xy 74.179848 -289.127015)
			(xy 74.196249 -289.174789) (xy 74.204562 -289.224611) (xy 74.205084 -289.249866) (xy 74.204903 -289.264049)
			(xy 74.202234 -289.292289) (xy 74.19975 -289.306254) (xy 74.19975 -289.306508) (xy 74.198288 -289.318739)
			(xy 74.205575 -289.342226) (xy 74.21372 -289.351466) (xy 74.2823 -289.419792) (xy 74.305922 -289.427158)
			(xy 74.318368 -289.424872) (xy 74.332396 -289.42238) (xy 74.360764 -289.419713) (xy 74.37501 -289.419538)
			(xy 74.399829 -289.419989) (xy 74.448813 -289.42802) (xy 74.495853 -289.443871) (xy 74.539708 -289.467122)
			(xy 74.579225 -289.497162) (xy 74.613361 -289.5332) (xy 74.641217 -289.574284) (xy 74.66206 -289.619335)
			(xy 74.675341 -289.667163) (xy 74.680709 -289.71651) (xy 74.680257 -289.724846) (xy 75.969126 -289.724846)
			(xy 75.973086 -289.675792) (xy 75.984863 -289.628008) (xy 76.004154 -289.582732) (xy 76.030457 -289.541136)
			(xy 76.063092 -289.504299) (xy 76.101213 -289.473174) (xy 76.143834 -289.448567) (xy 76.18985 -289.431115)
			(xy 76.238069 -289.421271) (xy 76.287244 -289.41929) (xy 76.336099 -289.425222) (xy 76.38337 -289.438914)
			(xy 76.427832 -289.460012) (xy 76.468335 -289.487968) (xy 76.503828 -289.52206) (xy 76.533393 -289.561404)
			(xy 76.556264 -289.604981) (xy 76.571848 -289.651662) (xy 76.579743 -289.700239) (xy 76.580238 -289.724846)
			(xy 76.919086 -289.724846) (xy 76.923046 -289.675792) (xy 76.934823 -289.628008) (xy 76.954114 -289.582732)
			(xy 76.980417 -289.541136) (xy 77.013052 -289.504299) (xy 77.051173 -289.473174) (xy 77.093794 -289.448567)
			(xy 77.13981 -289.431115) (xy 77.188029 -289.421271) (xy 77.237204 -289.41929) (xy 77.286059 -289.425222)
			(xy 77.33333 -289.438914) (xy 77.377792 -289.460012) (xy 77.418295 -289.487968) (xy 77.453788 -289.52206)
			(xy 77.483353 -289.561404) (xy 77.506224 -289.604981) (xy 77.521808 -289.651662) (xy 77.529703 -289.700239)
			(xy 77.530198 -289.724846) (xy 77.869046 -289.724846) (xy 77.873006 -289.675792) (xy 77.884783 -289.628008)
			(xy 77.904074 -289.582732) (xy 77.930377 -289.541136) (xy 77.963012 -289.504299) (xy 78.001133 -289.473174)
			(xy 78.043754 -289.448567) (xy 78.08977 -289.431115) (xy 78.137989 -289.421271) (xy 78.187164 -289.41929)
			(xy 78.236019 -289.425222) (xy 78.28329 -289.438914) (xy 78.327752 -289.460012) (xy 78.368255 -289.487968)
			(xy 78.403748 -289.52206) (xy 78.433313 -289.561404) (xy 78.456184 -289.604981) (xy 78.471768 -289.651662)
			(xy 78.479663 -289.700239) (xy 78.480158 -289.724846) (xy 78.819006 -289.724846) (xy 78.822966 -289.675792)
			(xy 78.834743 -289.628008) (xy 78.854034 -289.582732) (xy 78.880337 -289.541136) (xy 78.912972 -289.504299)
			(xy 78.951093 -289.473174) (xy 78.993714 -289.448567) (xy 79.03973 -289.431115) (xy 79.087949 -289.421271)
			(xy 79.137124 -289.41929) (xy 79.185979 -289.425222) (xy 79.23325 -289.438914) (xy 79.277712 -289.460012)
			(xy 79.318215 -289.487968) (xy 79.353708 -289.52206) (xy 79.383273 -289.561404) (xy 79.406144 -289.604981)
			(xy 79.421728 -289.651662) (xy 79.429623 -289.700239) (xy 79.430118 -289.724846) (xy 79.768966 -289.724846)
			(xy 79.772926 -289.675792) (xy 79.784703 -289.628008) (xy 79.803994 -289.582732) (xy 79.830297 -289.541136)
			(xy 79.862932 -289.504299) (xy 79.901053 -289.473174) (xy 79.943674 -289.448567) (xy 79.98969 -289.431115)
			(xy 80.037909 -289.421271) (xy 80.087084 -289.41929) (xy 80.135939 -289.425222) (xy 80.18321 -289.438914)
			(xy 80.227672 -289.460012) (xy 80.268175 -289.487968) (xy 80.303668 -289.52206) (xy 80.333233 -289.561404)
			(xy 80.356104 -289.604981) (xy 80.371688 -289.651662) (xy 80.379583 -289.700239) (xy 80.380078 -289.724846)
			(xy 80.71918 -289.724846) (xy 80.72314 -289.675792) (xy 80.734917 -289.628008) (xy 80.754208 -289.582732)
			(xy 80.780511 -289.541136) (xy 80.813146 -289.504299) (xy 80.851267 -289.473174) (xy 80.893888 -289.448567)
			(xy 80.939904 -289.431115) (xy 80.988123 -289.421271) (xy 81.037298 -289.41929) (xy 81.086153 -289.425222)
			(xy 81.133424 -289.438914) (xy 81.177886 -289.460012) (xy 81.218389 -289.487968) (xy 81.253882 -289.52206)
			(xy 81.283447 -289.561404) (xy 81.306318 -289.604981) (xy 81.321902 -289.651662) (xy 81.329797 -289.700239)
			(xy 81.330292 -289.724846) (xy 81.66914 -289.724846) (xy 81.6731 -289.675792) (xy 81.684877 -289.628008)
			(xy 81.704168 -289.582732) (xy 81.730471 -289.541136) (xy 81.763106 -289.504299) (xy 81.801227 -289.473174)
			(xy 81.843848 -289.448567) (xy 81.889864 -289.431115) (xy 81.938083 -289.421271) (xy 81.987258 -289.41929)
			(xy 82.036113 -289.425222) (xy 82.083384 -289.438914) (xy 82.127846 -289.460012) (xy 82.168349 -289.487968)
			(xy 82.203842 -289.52206) (xy 82.233407 -289.561404) (xy 82.256278 -289.604981) (xy 82.271862 -289.651662)
			(xy 82.279757 -289.700239) (xy 82.280252 -289.724846) (xy 82.6191 -289.724846) (xy 82.62306 -289.675792)
			(xy 82.634837 -289.628008) (xy 82.654128 -289.582732) (xy 82.680431 -289.541136) (xy 82.713066 -289.504299)
			(xy 82.751187 -289.473174) (xy 82.793808 -289.448567) (xy 82.839824 -289.431115) (xy 82.888043 -289.421271)
			(xy 82.937218 -289.41929) (xy 82.986073 -289.425222) (xy 83.033344 -289.438914) (xy 83.077806 -289.460012)
			(xy 83.118309 -289.487968) (xy 83.153802 -289.52206) (xy 83.183367 -289.561404) (xy 83.206238 -289.604981)
			(xy 83.221822 -289.651662) (xy 83.229717 -289.700239) (xy 83.230212 -289.724846) (xy 83.229717 -289.749453)
			(xy 83.221822 -289.79803) (xy 83.206238 -289.844711) (xy 83.183367 -289.888288) (xy 83.153802 -289.927632)
			(xy 83.118309 -289.961724) (xy 83.077806 -289.98968) (xy 83.033344 -290.010778) (xy 82.986073 -290.02447)
			(xy 82.937218 -290.030402) (xy 82.888043 -290.028421) (xy 82.839824 -290.018577) (xy 82.793808 -290.001125)
			(xy 82.751187 -289.976518) (xy 82.713066 -289.945393) (xy 82.680431 -289.908556) (xy 82.654128 -289.86696)
			(xy 82.634837 -289.821684) (xy 82.62306 -289.7739) (xy 82.6191 -289.724846) (xy 82.280252 -289.724846)
			(xy 82.279757 -289.749453) (xy 82.271862 -289.79803) (xy 82.256278 -289.844711) (xy 82.233407 -289.888288)
			(xy 82.203842 -289.927632) (xy 82.168349 -289.961724) (xy 82.127846 -289.98968) (xy 82.083384 -290.010778)
			(xy 82.036113 -290.02447) (xy 81.987258 -290.030402) (xy 81.938083 -290.028421) (xy 81.889864 -290.018577)
			(xy 81.843848 -290.001125) (xy 81.801227 -289.976518) (xy 81.763106 -289.945393) (xy 81.730471 -289.908556)
			(xy 81.704168 -289.86696) (xy 81.684877 -289.821684) (xy 81.6731 -289.7739) (xy 81.66914 -289.724846)
			(xy 81.330292 -289.724846) (xy 81.329797 -289.749453) (xy 81.321902 -289.79803) (xy 81.306318 -289.844711)
			(xy 81.283447 -289.888288) (xy 81.253882 -289.927632) (xy 81.218389 -289.961724) (xy 81.177886 -289.98968)
			(xy 81.133424 -290.010778) (xy 81.086153 -290.02447) (xy 81.037298 -290.030402) (xy 80.988123 -290.028421)
			(xy 80.939904 -290.018577) (xy 80.893888 -290.001125) (xy 80.851267 -289.976518) (xy 80.813146 -289.945393)
			(xy 80.780511 -289.908556) (xy 80.754208 -289.86696) (xy 80.734917 -289.821684) (xy 80.72314 -289.7739)
			(xy 80.71918 -289.724846) (xy 80.380078 -289.724846) (xy 80.379583 -289.749453) (xy 80.371688 -289.79803)
			(xy 80.356104 -289.844711) (xy 80.333233 -289.888288) (xy 80.303668 -289.927632) (xy 80.268175 -289.961724)
			(xy 80.227672 -289.98968) (xy 80.18321 -290.010778) (xy 80.135939 -290.02447) (xy 80.087084 -290.030402)
			(xy 80.037909 -290.028421) (xy 79.98969 -290.018577) (xy 79.943674 -290.001125) (xy 79.901053 -289.976518)
			(xy 79.862932 -289.945393) (xy 79.830297 -289.908556) (xy 79.803994 -289.86696) (xy 79.784703 -289.821684)
			(xy 79.772926 -289.7739) (xy 79.768966 -289.724846) (xy 79.430118 -289.724846) (xy 79.429623 -289.749453)
			(xy 79.421728 -289.79803) (xy 79.406144 -289.844711) (xy 79.383273 -289.888288) (xy 79.353708 -289.927632)
			(xy 79.318215 -289.961724) (xy 79.277712 -289.98968) (xy 79.23325 -290.010778) (xy 79.185979 -290.02447)
			(xy 79.137124 -290.030402) (xy 79.087949 -290.028421) (xy 79.03973 -290.018577) (xy 78.993714 -290.001125)
			(xy 78.951093 -289.976518) (xy 78.912972 -289.945393) (xy 78.880337 -289.908556) (xy 78.854034 -289.86696)
			(xy 78.834743 -289.821684) (xy 78.822966 -289.7739) (xy 78.819006 -289.724846) (xy 78.480158 -289.724846)
			(xy 78.479663 -289.749453) (xy 78.471768 -289.79803) (xy 78.456184 -289.844711) (xy 78.433313 -289.888288)
			(xy 78.403748 -289.927632) (xy 78.368255 -289.961724) (xy 78.327752 -289.98968) (xy 78.28329 -290.010778)
			(xy 78.236019 -290.02447) (xy 78.187164 -290.030402) (xy 78.137989 -290.028421) (xy 78.08977 -290.018577)
			(xy 78.043754 -290.001125) (xy 78.001133 -289.976518) (xy 77.963012 -289.945393) (xy 77.930377 -289.908556)
			(xy 77.904074 -289.86696) (xy 77.884783 -289.821684) (xy 77.873006 -289.7739) (xy 77.869046 -289.724846)
			(xy 77.530198 -289.724846) (xy 77.529703 -289.749453) (xy 77.521808 -289.79803) (xy 77.506224 -289.844711)
			(xy 77.483353 -289.888288) (xy 77.453788 -289.927632) (xy 77.418295 -289.961724) (xy 77.377792 -289.98968)
			(xy 77.33333 -290.010778) (xy 77.286059 -290.02447) (xy 77.237204 -290.030402) (xy 77.188029 -290.028421)
			(xy 77.13981 -290.018577) (xy 77.093794 -290.001125) (xy 77.051173 -289.976518) (xy 77.013052 -289.945393)
			(xy 76.980417 -289.908556) (xy 76.954114 -289.86696) (xy 76.934823 -289.821684) (xy 76.923046 -289.7739)
			(xy 76.919086 -289.724846) (xy 76.580238 -289.724846) (xy 76.579743 -289.749453) (xy 76.571848 -289.79803)
			(xy 76.556264 -289.844711) (xy 76.533393 -289.888288) (xy 76.503828 -289.927632) (xy 76.468335 -289.961724)
			(xy 76.427832 -289.98968) (xy 76.38337 -290.010778) (xy 76.336099 -290.02447) (xy 76.287244 -290.030402)
			(xy 76.238069 -290.028421) (xy 76.18985 -290.018577) (xy 76.143834 -290.001125) (xy 76.101213 -289.976518)
			(xy 76.063092 -289.945393) (xy 76.030457 -289.908556) (xy 76.004154 -289.86696) (xy 75.984863 -289.821684)
			(xy 75.973086 -289.7739) (xy 75.969126 -289.724846) (xy 74.680257 -289.724846) (xy 74.678023 -289.766076)
			(xy 74.667354 -289.814554) (xy 74.648983 -289.860667) (xy 74.623394 -289.903201) (xy 74.591261 -289.941035)
			(xy 74.553431 -289.973173) (xy 74.510899 -289.998767) (xy 74.464788 -290.017143) (xy 74.416311 -290.027818)
			(xy 74.366746 -290.03051) (xy 74.317399 -290.025147) (xy 74.269568 -290.011873) (xy 74.224516 -289.991035)
			(xy 74.183428 -289.963183) (xy 74.147387 -289.929051) (xy 74.117342 -289.889539) (xy 74.094085 -289.845686)
			(xy 74.078229 -289.798648) (xy 74.070192 -289.749665) (xy 74.069702 -289.724846) (xy 74.069885 -289.710663)
			(xy 74.072553 -289.682423) (xy 74.075036 -289.668458) (xy 74.075036 -289.668204) (xy 74.076466 -289.655972)
			(xy 74.069197 -289.632491) (xy 74.061066 -289.623246) (xy 73.992486 -289.55492) (xy 73.968864 -289.547554)
			(xy 73.956418 -289.54984) (xy 73.942388 -289.55232) (xy 73.914022 -289.554995) (xy 73.899776 -289.555174)
			(xy 73.885593 -289.555001) (xy 73.857353 -289.552327) (xy 73.843388 -289.54984) (xy 73.830942 -289.547554)
			(xy 73.80732 -289.55492) (xy 73.72985 -289.63239) (xy 73.722484 -289.656012) (xy 73.72477 -289.668458)
			(xy 73.72725 -289.682423) (xy 73.72992 -289.710663) (xy 73.730104 -289.724846) (xy 73.729573 -289.749662)
			(xy 73.721536 -289.79864) (xy 73.705682 -289.845672) (xy 73.682427 -289.88952) (xy 73.652386 -289.929028)
			(xy 73.616349 -289.963156) (xy 73.575265 -289.991004) (xy 73.530218 -290.011839) (xy 73.482393 -290.025112)
			(xy 73.433051 -290.030474) (xy 73.383491 -290.027782) (xy 73.33502 -290.017108) (xy 73.288914 -289.998733)
			(xy 73.246388 -289.973142) (xy 73.208562 -289.941008) (xy 73.176434 -289.903178) (xy 73.150848 -289.860648)
			(xy 73.13248 -289.81454) (xy 73.121812 -289.766067) (xy 73.119127 -289.716507) (xy 72.779976 -289.716507)
			(xy 72.780144 -289.724846) (xy 72.779649 -289.749453) (xy 72.771754 -289.79803) (xy 72.75617 -289.844711)
			(xy 72.733299 -289.888288) (xy 72.703734 -289.927632) (xy 72.668241 -289.961724) (xy 72.627738 -289.98968)
			(xy 72.583276 -290.010778) (xy 72.536005 -290.02447) (xy 72.48715 -290.030402) (xy 72.437975 -290.028421)
			(xy 72.389756 -290.018577) (xy 72.34374 -290.001125) (xy 72.301119 -289.976518) (xy 72.262998 -289.945393)
			(xy 72.230363 -289.908556) (xy 72.20406 -289.86696) (xy 72.184769 -289.821684) (xy 72.172992 -289.7739)
			(xy 72.169032 -289.724846) (xy 71.830184 -289.724846) (xy 71.829689 -289.749453) (xy 71.821794 -289.79803)
			(xy 71.80621 -289.844711) (xy 71.783339 -289.888288) (xy 71.753774 -289.927632) (xy 71.718281 -289.961724)
			(xy 71.677778 -289.98968) (xy 71.633316 -290.010778) (xy 71.586045 -290.02447) (xy 71.53719 -290.030402)
			(xy 71.488015 -290.028421) (xy 71.439796 -290.018577) (xy 71.39378 -290.001125) (xy 71.351159 -289.976518)
			(xy 71.313038 -289.945393) (xy 71.280403 -289.908556) (xy 71.2541 -289.86696) (xy 71.234809 -289.821684)
			(xy 71.223032 -289.7739) (xy 71.219072 -289.724846) (xy 70.880224 -289.724846) (xy 70.879729 -289.749453)
			(xy 70.871834 -289.79803) (xy 70.85625 -289.844711) (xy 70.833379 -289.888288) (xy 70.803814 -289.927632)
			(xy 70.768321 -289.961724) (xy 70.727818 -289.98968) (xy 70.683356 -290.010778) (xy 70.636085 -290.02447)
			(xy 70.58723 -290.030402) (xy 70.538055 -290.028421) (xy 70.489836 -290.018577) (xy 70.44382 -290.001125)
			(xy 70.401199 -289.976518) (xy 70.363078 -289.945393) (xy 70.330443 -289.908556) (xy 70.30414 -289.86696)
			(xy 70.284849 -289.821684) (xy 70.273072 -289.7739) (xy 70.269112 -289.724846) (xy 69.930264 -289.724846)
			(xy 69.929769 -289.749453) (xy 69.921874 -289.79803) (xy 69.90629 -289.844711) (xy 69.883419 -289.888288)
			(xy 69.853854 -289.927632) (xy 69.818361 -289.961724) (xy 69.777858 -289.98968) (xy 69.733396 -290.010778)
			(xy 69.686125 -290.02447) (xy 69.63727 -290.030402) (xy 69.588095 -290.028421) (xy 69.539876 -290.018577)
			(xy 69.49386 -290.001125) (xy 69.451239 -289.976518) (xy 69.413118 -289.945393) (xy 69.380483 -289.908556)
			(xy 69.35418 -289.86696) (xy 69.334889 -289.821684) (xy 69.323112 -289.7739) (xy 69.319152 -289.724846)
			(xy 68.98005 -289.724846) (xy 68.979555 -289.749453) (xy 68.97166 -289.79803) (xy 68.956076 -289.844711)
			(xy 68.933205 -289.888288) (xy 68.90364 -289.927632) (xy 68.868147 -289.961724) (xy 68.827644 -289.98968)
			(xy 68.783182 -290.010778) (xy 68.735911 -290.02447) (xy 68.687056 -290.030402) (xy 68.637881 -290.028421)
			(xy 68.589662 -290.018577) (xy 68.543646 -290.001125) (xy 68.501025 -289.976518) (xy 68.462904 -289.945393)
			(xy 68.430269 -289.908556) (xy 68.403966 -289.86696) (xy 68.384675 -289.821684) (xy 68.372898 -289.7739)
			(xy 68.368938 -289.724846) (xy 68.03009 -289.724846) (xy 68.029595 -289.749453) (xy 68.0217 -289.79803)
			(xy 68.006116 -289.844711) (xy 67.983245 -289.888288) (xy 67.95368 -289.927632) (xy 67.918187 -289.961724)
			(xy 67.877684 -289.98968) (xy 67.833222 -290.010778) (xy 67.785951 -290.02447) (xy 67.737096 -290.030402)
			(xy 67.687921 -290.028421) (xy 67.639702 -290.018577) (xy 67.593686 -290.001125) (xy 67.551065 -289.976518)
			(xy 67.512944 -289.945393) (xy 67.480309 -289.908556) (xy 67.454006 -289.86696) (xy 67.434715 -289.821684)
			(xy 67.422938 -289.7739) (xy 67.418978 -289.724846) (xy 67.08013 -289.724846) (xy 67.079635 -289.749453)
			(xy 67.07174 -289.79803) (xy 67.056156 -289.844711) (xy 67.033285 -289.888288) (xy 67.00372 -289.927632)
			(xy 66.968227 -289.961724) (xy 66.927724 -289.98968) (xy 66.883262 -290.010778) (xy 66.835991 -290.02447)
			(xy 66.787136 -290.030402) (xy 66.737961 -290.028421) (xy 66.689742 -290.018577) (xy 66.643726 -290.001125)
			(xy 66.601105 -289.976518) (xy 66.562984 -289.945393) (xy 66.530349 -289.908556) (xy 66.504046 -289.86696)
			(xy 66.484755 -289.821684) (xy 66.472978 -289.7739) (xy 66.469018 -289.724846) (xy 66.13017 -289.724846)
			(xy 66.129675 -289.749453) (xy 66.12178 -289.79803) (xy 66.106196 -289.844711) (xy 66.083325 -289.888288)
			(xy 66.05376 -289.927632) (xy 66.018267 -289.961724) (xy 65.977764 -289.98968) (xy 65.933302 -290.010778)
			(xy 65.886031 -290.02447) (xy 65.837176 -290.030402) (xy 65.788001 -290.028421) (xy 65.739782 -290.018577)
			(xy 65.693766 -290.001125) (xy 65.651145 -289.976518) (xy 65.613024 -289.945393) (xy 65.580389 -289.908556)
			(xy 65.554086 -289.86696) (xy 65.534795 -289.821684) (xy 65.523018 -289.7739) (xy 65.519058 -289.724846)
			(xy 65.18021 -289.724846) (xy 65.179715 -289.749453) (xy 65.17182 -289.79803) (xy 65.156236 -289.844711)
			(xy 65.133365 -289.888288) (xy 65.1038 -289.927632) (xy 65.068307 -289.961724) (xy 65.027804 -289.98968)
			(xy 64.983342 -290.010778) (xy 64.936071 -290.02447) (xy 64.887216 -290.030402) (xy 64.838041 -290.028421)
			(xy 64.789822 -290.018577) (xy 64.743806 -290.001125) (xy 64.701185 -289.976518) (xy 64.663064 -289.945393)
			(xy 64.630429 -289.908556) (xy 64.604126 -289.86696) (xy 64.584835 -289.821684) (xy 64.573058 -289.7739)
			(xy 64.569098 -289.724846) (xy 64.23025 -289.724846) (xy 64.229755 -289.749453) (xy 64.22186 -289.79803)
			(xy 64.206276 -289.844711) (xy 64.183405 -289.888288) (xy 64.15384 -289.927632) (xy 64.118347 -289.961724)
			(xy 64.077844 -289.98968) (xy 64.033382 -290.010778) (xy 63.986111 -290.02447) (xy 63.937256 -290.030402)
			(xy 63.888081 -290.028421) (xy 63.839862 -290.018577) (xy 63.793846 -290.001125) (xy 63.751225 -289.976518)
			(xy 63.713104 -289.945393) (xy 63.680469 -289.908556) (xy 63.654166 -289.86696) (xy 63.634875 -289.821684)
			(xy 63.623098 -289.7739) (xy 63.619138 -289.724846) (xy 63.28029 -289.724846) (xy 63.279795 -289.749453)
			(xy 63.2719 -289.79803) (xy 63.256316 -289.844711) (xy 63.233445 -289.888288) (xy 63.20388 -289.927632)
			(xy 63.168387 -289.961724) (xy 63.127884 -289.98968) (xy 63.083422 -290.010778) (xy 63.036151 -290.02447)
			(xy 62.987296 -290.030402) (xy 62.938121 -290.028421) (xy 62.889902 -290.018577) (xy 62.843886 -290.001125)
			(xy 62.801265 -289.976518) (xy 62.763144 -289.945393) (xy 62.730509 -289.908556) (xy 62.704206 -289.86696)
			(xy 62.684915 -289.821684) (xy 62.673138 -289.7739) (xy 62.669178 -289.724846) (xy 62.330076 -289.724846)
			(xy 62.329581 -289.749453) (xy 62.321686 -289.79803) (xy 62.306102 -289.844711) (xy 62.283231 -289.888288)
			(xy 62.253666 -289.927632) (xy 62.218173 -289.961724) (xy 62.17767 -289.98968) (xy 62.133208 -290.010778)
			(xy 62.085937 -290.02447) (xy 62.037082 -290.030402) (xy 61.987907 -290.028421) (xy 61.939688 -290.018577)
			(xy 61.893672 -290.001125) (xy 61.851051 -289.976518) (xy 61.81293 -289.945393) (xy 61.780295 -289.908556)
			(xy 61.753992 -289.86696) (xy 61.734701 -289.821684) (xy 61.722924 -289.7739) (xy 61.718964 -289.724846)
			(xy 61.380116 -289.724846) (xy 61.379621 -289.749453) (xy 61.371726 -289.79803) (xy 61.356142 -289.844711)
			(xy 61.333271 -289.888288) (xy 61.303706 -289.927632) (xy 61.268213 -289.961724) (xy 61.22771 -289.98968)
			(xy 61.183248 -290.010778) (xy 61.135977 -290.02447) (xy 61.087122 -290.030402) (xy 61.037947 -290.028421)
			(xy 60.989728 -290.018577) (xy 60.943712 -290.001125) (xy 60.901091 -289.976518) (xy 60.86297 -289.945393)
			(xy 60.830335 -289.908556) (xy 60.804032 -289.86696) (xy 60.784741 -289.821684) (xy 60.772964 -289.7739)
			(xy 60.769004 -289.724846) (xy 60.430156 -289.724846) (xy 60.429661 -289.749453) (xy 60.421766 -289.79803)
			(xy 60.406182 -289.844711) (xy 60.383311 -289.888288) (xy 60.353746 -289.927632) (xy 60.318253 -289.961724)
			(xy 60.27775 -289.98968) (xy 60.233288 -290.010778) (xy 60.186017 -290.02447) (xy 60.137162 -290.030402)
			(xy 60.087987 -290.028421) (xy 60.039768 -290.018577) (xy 59.993752 -290.001125) (xy 59.951131 -289.976518)
			(xy 59.91301 -289.945393) (xy 59.880375 -289.908556) (xy 59.854072 -289.86696) (xy 59.834781 -289.821684)
			(xy 59.823004 -289.7739) (xy 59.819044 -289.724846) (xy 58.530236 -289.724846) (xy 58.529741 -289.749453)
			(xy 58.521846 -289.79803) (xy 58.506262 -289.844711) (xy 58.483391 -289.888288) (xy 58.453826 -289.927632)
			(xy 58.418333 -289.961724) (xy 58.37783 -289.98968) (xy 58.333368 -290.010778) (xy 58.286097 -290.02447)
			(xy 58.237242 -290.030402) (xy 58.188067 -290.028421) (xy 58.139848 -290.018577) (xy 58.093832 -290.001125)
			(xy 58.051211 -289.976518) (xy 58.01309 -289.945393) (xy 57.980455 -289.908556) (xy 57.954152 -289.86696)
			(xy 57.934861 -289.821684) (xy 57.923084 -289.7739) (xy 57.919124 -289.724846) (xy 57.580276 -289.724846)
			(xy 57.579781 -289.749453) (xy 57.571886 -289.79803) (xy 57.556302 -289.844711) (xy 57.533431 -289.888288)
			(xy 57.503866 -289.927632) (xy 57.468373 -289.961724) (xy 57.42787 -289.98968) (xy 57.383408 -290.010778)
			(xy 57.336137 -290.02447) (xy 57.287282 -290.030402) (xy 57.238107 -290.028421) (xy 57.189888 -290.018577)
			(xy 57.143872 -290.001125) (xy 57.101251 -289.976518) (xy 57.06313 -289.945393) (xy 57.030495 -289.908556)
			(xy 57.004192 -289.86696) (xy 56.984901 -289.821684) (xy 56.973124 -289.7739) (xy 56.969164 -289.724846)
			(xy 56.630062 -289.724846) (xy 56.629567 -289.749453) (xy 56.621672 -289.79803) (xy 56.606088 -289.844711)
			(xy 56.583217 -289.888288) (xy 56.553652 -289.927632) (xy 56.518159 -289.961724) (xy 56.477656 -289.98968)
			(xy 56.433194 -290.010778) (xy 56.385923 -290.02447) (xy 56.337068 -290.030402) (xy 56.287893 -290.028421)
			(xy 56.239674 -290.018577) (xy 56.193658 -290.001125) (xy 56.151037 -289.976518) (xy 56.112916 -289.945393)
			(xy 56.080281 -289.908556) (xy 56.053978 -289.86696) (xy 56.034687 -289.821684) (xy 56.02291 -289.7739)
			(xy 56.01895 -289.724846) (xy 55.680102 -289.724846) (xy 55.679607 -289.749453) (xy 55.671712 -289.79803)
			(xy 55.656128 -289.844711) (xy 55.633257 -289.888288) (xy 55.603692 -289.927632) (xy 55.568199 -289.961724)
			(xy 55.527696 -289.98968) (xy 55.483234 -290.010778) (xy 55.435963 -290.02447) (xy 55.387108 -290.030402)
			(xy 55.337933 -290.028421) (xy 55.289714 -290.018577) (xy 55.243698 -290.001125) (xy 55.201077 -289.976518)
			(xy 55.162956 -289.945393) (xy 55.130321 -289.908556) (xy 55.104018 -289.86696) (xy 55.084727 -289.821684)
			(xy 55.07295 -289.7739) (xy 55.06899 -289.724846) (xy 54.730142 -289.724846) (xy 54.729647 -289.749453)
			(xy 54.721752 -289.79803) (xy 54.706168 -289.844711) (xy 54.683297 -289.888288) (xy 54.653732 -289.927632)
			(xy 54.618239 -289.961724) (xy 54.577736 -289.98968) (xy 54.533274 -290.010778) (xy 54.486003 -290.02447)
			(xy 54.437148 -290.030402) (xy 54.387973 -290.028421) (xy 54.339754 -290.018577) (xy 54.293738 -290.001125)
			(xy 54.251117 -289.976518) (xy 54.212996 -289.945393) (xy 54.180361 -289.908556) (xy 54.154058 -289.86696)
			(xy 54.134767 -289.821684) (xy 54.12299 -289.7739) (xy 54.11903 -289.724846) (xy 53.780182 -289.724846)
			(xy 53.779687 -289.749453) (xy 53.771792 -289.79803) (xy 53.756208 -289.844711) (xy 53.733337 -289.888288)
			(xy 53.703772 -289.927632) (xy 53.668279 -289.961724) (xy 53.627776 -289.98968) (xy 53.583314 -290.010778)
			(xy 53.536043 -290.02447) (xy 53.487188 -290.030402) (xy 53.438013 -290.028421) (xy 53.389794 -290.018577)
			(xy 53.343778 -290.001125) (xy 53.301157 -289.976518) (xy 53.263036 -289.945393) (xy 53.230401 -289.908556)
			(xy 53.204098 -289.86696) (xy 53.184807 -289.821684) (xy 53.17303 -289.7739) (xy 53.16907 -289.724846)
			(xy 52.830222 -289.724846) (xy 52.829727 -289.749453) (xy 52.821832 -289.79803) (xy 52.806248 -289.844711)
			(xy 52.783377 -289.888288) (xy 52.753812 -289.927632) (xy 52.718319 -289.961724) (xy 52.677816 -289.98968)
			(xy 52.633354 -290.010778) (xy 52.586083 -290.02447) (xy 52.537228 -290.030402) (xy 52.488053 -290.028421)
			(xy 52.439834 -290.018577) (xy 52.393818 -290.001125) (xy 52.351197 -289.976518) (xy 52.313076 -289.945393)
			(xy 52.280441 -289.908556) (xy 52.254138 -289.86696) (xy 52.234847 -289.821684) (xy 52.22307 -289.7739)
			(xy 52.21911 -289.724846) (xy 51.880262 -289.724846) (xy 51.879767 -289.749453) (xy 51.871872 -289.79803)
			(xy 51.856288 -289.844711) (xy 51.833417 -289.888288) (xy 51.803852 -289.927632) (xy 51.768359 -289.961724)
			(xy 51.727856 -289.98968) (xy 51.683394 -290.010778) (xy 51.636123 -290.02447) (xy 51.587268 -290.030402)
			(xy 51.538093 -290.028421) (xy 51.489874 -290.018577) (xy 51.443858 -290.001125) (xy 51.401237 -289.976518)
			(xy 51.363116 -289.945393) (xy 51.330481 -289.908556) (xy 51.304178 -289.86696) (xy 51.284887 -289.821684)
			(xy 51.27311 -289.7739) (xy 51.26915 -289.724846) (xy 50.930302 -289.724846) (xy 50.929807 -289.749453)
			(xy 50.921912 -289.79803) (xy 50.906328 -289.844711) (xy 50.883457 -289.888288) (xy 50.853892 -289.927632)
			(xy 50.818399 -289.961724) (xy 50.777896 -289.98968) (xy 50.733434 -290.010778) (xy 50.686163 -290.02447)
			(xy 50.637308 -290.030402) (xy 50.588133 -290.028421) (xy 50.539914 -290.018577) (xy 50.493898 -290.001125)
			(xy 50.451277 -289.976518) (xy 50.413156 -289.945393) (xy 50.380521 -289.908556) (xy 50.354218 -289.86696)
			(xy 50.334927 -289.821684) (xy 50.32315 -289.7739) (xy 50.31919 -289.724846) (xy 49.980088 -289.724846)
			(xy 49.979593 -289.749453) (xy 49.971698 -289.79803) (xy 49.956114 -289.844711) (xy 49.933243 -289.888288)
			(xy 49.903678 -289.927632) (xy 49.868185 -289.961724) (xy 49.827682 -289.98968) (xy 49.78322 -290.010778)
			(xy 49.735949 -290.02447) (xy 49.687094 -290.030402) (xy 49.637919 -290.028421) (xy 49.5897 -290.018577)
			(xy 49.543684 -290.001125) (xy 49.501063 -289.976518) (xy 49.462942 -289.945393) (xy 49.430307 -289.908556)
			(xy 49.404004 -289.86696) (xy 49.384713 -289.821684) (xy 49.372936 -289.7739) (xy 49.368976 -289.724846)
			(xy 49.030128 -289.724846) (xy 49.029633 -289.749453) (xy 49.021738 -289.79803) (xy 49.006154 -289.844711)
			(xy 48.983283 -289.888288) (xy 48.953718 -289.927632) (xy 48.918225 -289.961724) (xy 48.877722 -289.98968)
			(xy 48.83326 -290.010778) (xy 48.785989 -290.02447) (xy 48.737134 -290.030402) (xy 48.687959 -290.028421)
			(xy 48.63974 -290.018577) (xy 48.593724 -290.001125) (xy 48.551103 -289.976518) (xy 48.512982 -289.945393)
			(xy 48.480347 -289.908556) (xy 48.454044 -289.86696) (xy 48.434753 -289.821684) (xy 48.422976 -289.7739)
			(xy 48.419016 -289.724846) (xy 48.080168 -289.724846) (xy 48.079673 -289.749453) (xy 48.071778 -289.79803)
			(xy 48.056194 -289.844711) (xy 48.033323 -289.888288) (xy 48.003758 -289.927632) (xy 47.968265 -289.961724)
			(xy 47.927762 -289.98968) (xy 47.8833 -290.010778) (xy 47.836029 -290.02447) (xy 47.787174 -290.030402)
			(xy 47.737999 -290.028421) (xy 47.68978 -290.018577) (xy 47.643764 -290.001125) (xy 47.601143 -289.976518)
			(xy 47.563022 -289.945393) (xy 47.530387 -289.908556) (xy 47.504084 -289.86696) (xy 47.484793 -289.821684)
			(xy 47.473016 -289.7739) (xy 47.469056 -289.724846) (xy 47.130208 -289.724846) (xy 47.129713 -289.749453)
			(xy 47.121818 -289.79803) (xy 47.106234 -289.844711) (xy 47.083363 -289.888288) (xy 47.053798 -289.927632)
			(xy 47.018305 -289.961724) (xy 46.977802 -289.98968) (xy 46.93334 -290.010778) (xy 46.886069 -290.02447)
			(xy 46.837214 -290.030402) (xy 46.788039 -290.028421) (xy 46.73982 -290.018577) (xy 46.693804 -290.001125)
			(xy 46.651183 -289.976518) (xy 46.613062 -289.945393) (xy 46.580427 -289.908556) (xy 46.554124 -289.86696)
			(xy 46.534833 -289.821684) (xy 46.523056 -289.7739) (xy 46.519096 -289.724846) (xy 46.180248 -289.724846)
			(xy 46.179753 -289.749453) (xy 46.171858 -289.79803) (xy 46.156274 -289.844711) (xy 46.133403 -289.888288)
			(xy 46.103838 -289.927632) (xy 46.068345 -289.961724) (xy 46.027842 -289.98968) (xy 45.98338 -290.010778)
			(xy 45.936109 -290.02447) (xy 45.887254 -290.030402) (xy 45.838079 -290.028421) (xy 45.78986 -290.018577)
			(xy 45.743844 -290.001125) (xy 45.701223 -289.976518) (xy 45.663102 -289.945393) (xy 45.630467 -289.908556)
			(xy 45.604164 -289.86696) (xy 45.584873 -289.821684) (xy 45.573096 -289.7739) (xy 45.569136 -289.724846)
			(xy 45.230288 -289.724846) (xy 45.229793 -289.749453) (xy 45.221898 -289.79803) (xy 45.206314 -289.844711)
			(xy 45.183443 -289.888288) (xy 45.153878 -289.927632) (xy 45.118385 -289.961724) (xy 45.077882 -289.98968)
			(xy 45.03342 -290.010778) (xy 44.986149 -290.02447) (xy 44.937294 -290.030402) (xy 44.888119 -290.028421)
			(xy 44.8399 -290.018577) (xy 44.793884 -290.001125) (xy 44.751263 -289.976518) (xy 44.713142 -289.945393)
			(xy 44.680507 -289.908556) (xy 44.654204 -289.86696) (xy 44.634913 -289.821684) (xy 44.623136 -289.7739)
			(xy 44.619176 -289.724846) (xy 44.280074 -289.724846) (xy 44.279579 -289.749453) (xy 44.271684 -289.79803)
			(xy 44.2561 -289.844711) (xy 44.233229 -289.888288) (xy 44.203664 -289.927632) (xy 44.168171 -289.961724)
			(xy 44.127668 -289.98968) (xy 44.083206 -290.010778) (xy 44.035935 -290.02447) (xy 43.98708 -290.030402)
			(xy 43.937905 -290.028421) (xy 43.889686 -290.018577) (xy 43.84367 -290.001125) (xy 43.801049 -289.976518)
			(xy 43.762928 -289.945393) (xy 43.730293 -289.908556) (xy 43.70399 -289.86696) (xy 43.684699 -289.821684)
			(xy 43.672922 -289.7739) (xy 43.668962 -289.724846) (xy 43.330114 -289.724846) (xy 43.329619 -289.749453)
			(xy 43.321724 -289.79803) (xy 43.30614 -289.844711) (xy 43.283269 -289.888288) (xy 43.253704 -289.927632)
			(xy 43.218211 -289.961724) (xy 43.177708 -289.98968) (xy 43.133246 -290.010778) (xy 43.085975 -290.02447)
			(xy 43.03712 -290.030402) (xy 42.987945 -290.028421) (xy 42.939726 -290.018577) (xy 42.89371 -290.001125)
			(xy 42.851089 -289.976518) (xy 42.812968 -289.945393) (xy 42.780333 -289.908556) (xy 42.75403 -289.86696)
			(xy 42.734739 -289.821684) (xy 42.722962 -289.7739) (xy 42.719002 -289.724846) (xy 42.380154 -289.724846)
			(xy 42.379659 -289.749453) (xy 42.371764 -289.79803) (xy 42.35618 -289.844711) (xy 42.333309 -289.888288)
			(xy 42.303744 -289.927632) (xy 42.268251 -289.961724) (xy 42.227748 -289.98968) (xy 42.183286 -290.010778)
			(xy 42.136015 -290.02447) (xy 42.08716 -290.030402) (xy 42.037985 -290.028421) (xy 41.989766 -290.018577)
			(xy 41.94375 -290.001125) (xy 41.901129 -289.976518) (xy 41.863008 -289.945393) (xy 41.830373 -289.908556)
			(xy 41.80407 -289.86696) (xy 41.784779 -289.821684) (xy 41.773002 -289.7739) (xy 41.769042 -289.724846)
			(xy 41.430194 -289.724846) (xy 41.429699 -289.749453) (xy 41.421804 -289.79803) (xy 41.40622 -289.844711)
			(xy 41.383349 -289.888288) (xy 41.353784 -289.927632) (xy 41.318291 -289.961724) (xy 41.277788 -289.98968)
			(xy 41.233326 -290.010778) (xy 41.186055 -290.02447) (xy 41.1372 -290.030402) (xy 41.088025 -290.028421)
			(xy 41.039806 -290.018577) (xy 40.99379 -290.001125) (xy 40.951169 -289.976518) (xy 40.913048 -289.945393)
			(xy 40.880413 -289.908556) (xy 40.85411 -289.86696) (xy 40.834819 -289.821684) (xy 40.823042 -289.7739)
			(xy 40.819082 -289.724846) (xy 40.480234 -289.724846) (xy 40.479739 -289.749453) (xy 40.471844 -289.79803)
			(xy 40.45626 -289.844711) (xy 40.433389 -289.888288) (xy 40.403824 -289.927632) (xy 40.368331 -289.961724)
			(xy 40.327828 -289.98968) (xy 40.283366 -290.010778) (xy 40.236095 -290.02447) (xy 40.18724 -290.030402)
			(xy 40.138065 -290.028421) (xy 40.089846 -290.018577) (xy 40.04383 -290.001125) (xy 40.001209 -289.976518)
			(xy 39.963088 -289.945393) (xy 39.930453 -289.908556) (xy 39.90415 -289.86696) (xy 39.884859 -289.821684)
			(xy 39.873082 -289.7739) (xy 39.869122 -289.724846) (xy 39.530274 -289.724846) (xy 39.529779 -289.749453)
			(xy 39.521884 -289.79803) (xy 39.5063 -289.844711) (xy 39.483429 -289.888288) (xy 39.453864 -289.927632)
			(xy 39.418371 -289.961724) (xy 39.377868 -289.98968) (xy 39.333406 -290.010778) (xy 39.286135 -290.02447)
			(xy 39.23728 -290.030402) (xy 39.188105 -290.028421) (xy 39.139886 -290.018577) (xy 39.09387 -290.001125)
			(xy 39.051249 -289.976518) (xy 39.013128 -289.945393) (xy 38.980493 -289.908556) (xy 38.95419 -289.86696)
			(xy 38.934899 -289.821684) (xy 38.923122 -289.7739) (xy 38.919162 -289.724846) (xy 38.580314 -289.724846)
			(xy 38.579819 -289.749453) (xy 38.571924 -289.79803) (xy 38.55634 -289.844711) (xy 38.533469 -289.888288)
			(xy 38.503904 -289.927632) (xy 38.468411 -289.961724) (xy 38.427908 -289.98968) (xy 38.383446 -290.010778)
			(xy 38.336175 -290.02447) (xy 38.28732 -290.030402) (xy 38.238145 -290.028421) (xy 38.189926 -290.018577)
			(xy 38.14391 -290.001125) (xy 38.101289 -289.976518) (xy 38.063168 -289.945393) (xy 38.030533 -289.908556)
			(xy 38.00423 -289.86696) (xy 37.984939 -289.821684) (xy 37.973162 -289.7739) (xy 37.969202 -289.724846)
			(xy 37.6301 -289.724846) (xy 37.629605 -289.749453) (xy 37.62171 -289.79803) (xy 37.606126 -289.844711)
			(xy 37.583255 -289.888288) (xy 37.55369 -289.927632) (xy 37.518197 -289.961724) (xy 37.477694 -289.98968)
			(xy 37.433232 -290.010778) (xy 37.385961 -290.02447) (xy 37.337106 -290.030402) (xy 37.287931 -290.028421)
			(xy 37.239712 -290.018577) (xy 37.193696 -290.001125) (xy 37.151075 -289.976518) (xy 37.112954 -289.945393)
			(xy 37.080319 -289.908556) (xy 37.054016 -289.86696) (xy 37.034725 -289.821684) (xy 37.022948 -289.7739)
			(xy 37.018988 -289.724846) (xy 36.68014 -289.724846) (xy 36.6797 -289.7486) (xy 36.672323 -289.795533)
			(xy 36.657754 -289.840753) (xy 36.636348 -289.883165) (xy 36.608621 -289.921744) (xy 36.592256 -289.938968)
			(xy 36.586199 -289.945555) (xy 36.578782 -289.961826) (xy 36.577778 -289.970718) (xy 36.575492 -290.001706)
			(xy 36.575141 -290.010625) (xy 36.579946 -290.027803) (xy 36.58489 -290.035234) (xy 36.598243 -290.054707)
			(xy 36.619461 -290.096885) (xy 36.633932 -290.141827) (xy 36.641312 -290.188461) (xy 36.641426 -290.235675)
			(xy 36.63427 -290.282344) (xy 36.627562 -290.304982) (xy 36.602924 -290.38296) (xy 36.600502 -290.391929)
			(xy 36.601533 -290.410463) (xy 36.609102 -290.427411) (xy 36.61537 -290.434268) (xy 36.622225 -290.440545)
			(xy 36.639171 -290.44814) (xy 36.657712 -290.449162) (xy 36.666678 -290.446714) (xy 36.813236 -290.400486)
			(xy 36.820007 -290.398595) (xy 36.834055 -290.398218) (xy 36.840922 -290.399724) (xy 36.99256 -290.43757)
			(xy 36.99764 -290.44265) (xy 37.014658 -290.450016) (xy 37.102796 -290.453572) (xy 37.12083 -290.447476)
			(xy 37.127942 -290.44138) (xy 37.148773 -290.424576) (xy 37.195072 -290.397739) (xy 37.245338 -290.379378)
			(xy 37.298035 -290.370054) (xy 37.324792 -290.369498) (xy 37.348785 -290.369946) (xy 37.396181 -290.377451)
			(xy 37.441819 -290.392279) (xy 37.484576 -290.414064) (xy 37.523398 -290.442269) (xy 37.557329 -290.476201)
			(xy 37.585535 -290.515023) (xy 37.60732 -290.557779) (xy 37.622148 -290.603417) (xy 37.629654 -290.650813)
			(xy 37.6301 -290.674806) (xy 37.969202 -290.674806) (xy 37.973162 -290.625752) (xy 37.984939 -290.577968)
			(xy 38.00423 -290.532692) (xy 38.030533 -290.491096) (xy 38.063168 -290.454259) (xy 38.101289 -290.423134)
			(xy 38.14391 -290.398527) (xy 38.189926 -290.381075) (xy 38.238145 -290.371231) (xy 38.28732 -290.36925)
			(xy 38.336175 -290.375182) (xy 38.383446 -290.388874) (xy 38.427908 -290.409972) (xy 38.468411 -290.437928)
			(xy 38.503904 -290.47202) (xy 38.533469 -290.511364) (xy 38.55634 -290.554941) (xy 38.571924 -290.601622)
			(xy 38.579819 -290.650199) (xy 38.580314 -290.674806) (xy 40.819082 -290.674806) (xy 40.823042 -290.625752)
			(xy 40.834819 -290.577968) (xy 40.85411 -290.532692) (xy 40.880413 -290.491096) (xy 40.913048 -290.454259)
			(xy 40.951169 -290.423134) (xy 40.99379 -290.398527) (xy 41.039806 -290.381075) (xy 41.088025 -290.371231)
			(xy 41.1372 -290.36925) (xy 41.186055 -290.375182) (xy 41.233326 -290.388874) (xy 41.277788 -290.409972)
			(xy 41.318291 -290.437928) (xy 41.353784 -290.47202) (xy 41.383349 -290.511364) (xy 41.40622 -290.554941)
			(xy 41.421804 -290.601622) (xy 41.429699 -290.650199) (xy 41.430194 -290.674806) (xy 41.769042 -290.674806)
			(xy 41.773002 -290.625752) (xy 41.784779 -290.577968) (xy 41.80407 -290.532692) (xy 41.830373 -290.491096)
			(xy 41.863008 -290.454259) (xy 41.901129 -290.423134) (xy 41.94375 -290.398527) (xy 41.989766 -290.381075)
			(xy 42.037985 -290.371231) (xy 42.08716 -290.36925) (xy 42.136015 -290.375182) (xy 42.183286 -290.388874)
			(xy 42.227748 -290.409972) (xy 42.268251 -290.437928) (xy 42.303744 -290.47202) (xy 42.333309 -290.511364)
			(xy 42.35618 -290.554941) (xy 42.371764 -290.601622) (xy 42.379659 -290.650199) (xy 42.380154 -290.674806)
			(xy 42.719002 -290.674806) (xy 42.722962 -290.625752) (xy 42.734739 -290.577968) (xy 42.75403 -290.532692)
			(xy 42.780333 -290.491096) (xy 42.812968 -290.454259) (xy 42.851089 -290.423134) (xy 42.89371 -290.398527)
			(xy 42.939726 -290.381075) (xy 42.987945 -290.371231) (xy 43.03712 -290.36925) (xy 43.085975 -290.375182)
			(xy 43.133246 -290.388874) (xy 43.177708 -290.409972) (xy 43.218211 -290.437928) (xy 43.253704 -290.47202)
			(xy 43.283269 -290.511364) (xy 43.30614 -290.554941) (xy 43.321724 -290.601622) (xy 43.329619 -290.650199)
			(xy 43.330114 -290.674806) (xy 43.668962 -290.674806) (xy 43.672922 -290.625752) (xy 43.684699 -290.577968)
			(xy 43.70399 -290.532692) (xy 43.730293 -290.491096) (xy 43.762928 -290.454259) (xy 43.801049 -290.423134)
			(xy 43.84367 -290.398527) (xy 43.889686 -290.381075) (xy 43.937905 -290.371231) (xy 43.98708 -290.36925)
			(xy 44.035935 -290.375182) (xy 44.083206 -290.388874) (xy 44.127668 -290.409972) (xy 44.168171 -290.437928)
			(xy 44.203664 -290.47202) (xy 44.233229 -290.511364) (xy 44.2561 -290.554941) (xy 44.271684 -290.601622)
			(xy 44.279579 -290.650199) (xy 44.280074 -290.674806) (xy 44.619176 -290.674806) (xy 44.623136 -290.625752)
			(xy 44.634913 -290.577968) (xy 44.654204 -290.532692) (xy 44.680507 -290.491096) (xy 44.713142 -290.454259)
			(xy 44.751263 -290.423134) (xy 44.793884 -290.398527) (xy 44.8399 -290.381075) (xy 44.888119 -290.371231)
			(xy 44.937294 -290.36925) (xy 44.986149 -290.375182) (xy 45.03342 -290.388874) (xy 45.077882 -290.409972)
			(xy 45.118385 -290.437928) (xy 45.153878 -290.47202) (xy 45.183443 -290.511364) (xy 45.206314 -290.554941)
			(xy 45.221898 -290.601622) (xy 45.229793 -290.650199) (xy 45.230288 -290.674806) (xy 45.569136 -290.674806)
			(xy 45.573096 -290.625752) (xy 45.584873 -290.577968) (xy 45.604164 -290.532692) (xy 45.630467 -290.491096)
			(xy 45.663102 -290.454259) (xy 45.701223 -290.423134) (xy 45.743844 -290.398527) (xy 45.78986 -290.381075)
			(xy 45.838079 -290.371231) (xy 45.887254 -290.36925) (xy 45.936109 -290.375182) (xy 45.98338 -290.388874)
			(xy 46.027842 -290.409972) (xy 46.068345 -290.437928) (xy 46.103838 -290.47202) (xy 46.133403 -290.511364)
			(xy 46.156274 -290.554941) (xy 46.171858 -290.601622) (xy 46.179753 -290.650199) (xy 46.180248 -290.674806)
			(xy 46.519096 -290.674806) (xy 46.523056 -290.625752) (xy 46.534833 -290.577968) (xy 46.554124 -290.532692)
			(xy 46.580427 -290.491096) (xy 46.613062 -290.454259) (xy 46.651183 -290.423134) (xy 46.693804 -290.398527)
			(xy 46.73982 -290.381075) (xy 46.788039 -290.371231) (xy 46.837214 -290.36925) (xy 46.886069 -290.375182)
			(xy 46.93334 -290.388874) (xy 46.977802 -290.409972) (xy 47.018305 -290.437928) (xy 47.053798 -290.47202)
			(xy 47.083363 -290.511364) (xy 47.106234 -290.554941) (xy 47.121818 -290.601622) (xy 47.129713 -290.650199)
			(xy 47.130208 -290.674806) (xy 47.469056 -290.674806) (xy 47.473016 -290.625752) (xy 47.484793 -290.577968)
			(xy 47.504084 -290.532692) (xy 47.530387 -290.491096) (xy 47.563022 -290.454259) (xy 47.601143 -290.423134)
			(xy 47.643764 -290.398527) (xy 47.68978 -290.381075) (xy 47.737999 -290.371231) (xy 47.787174 -290.36925)
			(xy 47.836029 -290.375182) (xy 47.8833 -290.388874) (xy 47.927762 -290.409972) (xy 47.968265 -290.437928)
			(xy 48.003758 -290.47202) (xy 48.033323 -290.511364) (xy 48.056194 -290.554941) (xy 48.071778 -290.601622)
			(xy 48.079673 -290.650199) (xy 48.080168 -290.674806) (xy 48.419016 -290.674806) (xy 48.422976 -290.625752)
			(xy 48.434753 -290.577968) (xy 48.454044 -290.532692) (xy 48.480347 -290.491096) (xy 48.512982 -290.454259)
			(xy 48.551103 -290.423134) (xy 48.593724 -290.398527) (xy 48.63974 -290.381075) (xy 48.687959 -290.371231)
			(xy 48.737134 -290.36925) (xy 48.785989 -290.375182) (xy 48.83326 -290.388874) (xy 48.877722 -290.409972)
			(xy 48.918225 -290.437928) (xy 48.953718 -290.47202) (xy 48.983283 -290.511364) (xy 49.006154 -290.554941)
			(xy 49.021738 -290.601622) (xy 49.029633 -290.650199) (xy 49.030128 -290.674806) (xy 49.368976 -290.674806)
			(xy 49.372936 -290.625752) (xy 49.384713 -290.577968) (xy 49.404004 -290.532692) (xy 49.430307 -290.491096)
			(xy 49.462942 -290.454259) (xy 49.501063 -290.423134) (xy 49.543684 -290.398527) (xy 49.5897 -290.381075)
			(xy 49.637919 -290.371231) (xy 49.687094 -290.36925) (xy 49.735949 -290.375182) (xy 49.78322 -290.388874)
			(xy 49.827682 -290.409972) (xy 49.868185 -290.437928) (xy 49.903678 -290.47202) (xy 49.933243 -290.511364)
			(xy 49.956114 -290.554941) (xy 49.971698 -290.601622) (xy 49.979593 -290.650199) (xy 49.980088 -290.674806)
			(xy 50.31919 -290.674806) (xy 50.32315 -290.625752) (xy 50.334927 -290.577968) (xy 50.354218 -290.532692)
			(xy 50.380521 -290.491096) (xy 50.413156 -290.454259) (xy 50.451277 -290.423134) (xy 50.493898 -290.398527)
			(xy 50.539914 -290.381075) (xy 50.588133 -290.371231) (xy 50.637308 -290.36925) (xy 50.686163 -290.375182)
			(xy 50.733434 -290.388874) (xy 50.777896 -290.409972) (xy 50.818399 -290.437928) (xy 50.853892 -290.47202)
			(xy 50.883457 -290.511364) (xy 50.906328 -290.554941) (xy 50.921912 -290.601622) (xy 50.929807 -290.650199)
			(xy 50.930302 -290.674806) (xy 51.26915 -290.674806) (xy 51.27311 -290.625752) (xy 51.284887 -290.577968)
			(xy 51.304178 -290.532692) (xy 51.330481 -290.491096) (xy 51.363116 -290.454259) (xy 51.401237 -290.423134)
			(xy 51.443858 -290.398527) (xy 51.489874 -290.381075) (xy 51.538093 -290.371231) (xy 51.587268 -290.36925)
			(xy 51.636123 -290.375182) (xy 51.683394 -290.388874) (xy 51.727856 -290.409972) (xy 51.768359 -290.437928)
			(xy 51.803852 -290.47202) (xy 51.833417 -290.511364) (xy 51.856288 -290.554941) (xy 51.871872 -290.601622)
			(xy 51.879767 -290.650199) (xy 51.880262 -290.674806) (xy 52.21911 -290.674806) (xy 52.22307 -290.625752)
			(xy 52.234847 -290.577968) (xy 52.254138 -290.532692) (xy 52.280441 -290.491096) (xy 52.313076 -290.454259)
			(xy 52.351197 -290.423134) (xy 52.393818 -290.398527) (xy 52.439834 -290.381075) (xy 52.488053 -290.371231)
			(xy 52.537228 -290.36925) (xy 52.586083 -290.375182) (xy 52.633354 -290.388874) (xy 52.677816 -290.409972)
			(xy 52.718319 -290.437928) (xy 52.753812 -290.47202) (xy 52.783377 -290.511364) (xy 52.806248 -290.554941)
			(xy 52.821832 -290.601622) (xy 52.829727 -290.650199) (xy 52.830222 -290.674806) (xy 53.16907 -290.674806)
			(xy 53.17303 -290.625752) (xy 53.184807 -290.577968) (xy 53.204098 -290.532692) (xy 53.230401 -290.491096)
			(xy 53.263036 -290.454259) (xy 53.301157 -290.423134) (xy 53.343778 -290.398527) (xy 53.389794 -290.381075)
			(xy 53.438013 -290.371231) (xy 53.487188 -290.36925) (xy 53.536043 -290.375182) (xy 53.583314 -290.388874)
			(xy 53.627776 -290.409972) (xy 53.668279 -290.437928) (xy 53.703772 -290.47202) (xy 53.733337 -290.511364)
			(xy 53.756208 -290.554941) (xy 53.771792 -290.601622) (xy 53.779687 -290.650199) (xy 53.780182 -290.674806)
			(xy 54.11903 -290.674806) (xy 54.12299 -290.625752) (xy 54.134767 -290.577968) (xy 54.154058 -290.532692)
			(xy 54.180361 -290.491096) (xy 54.212996 -290.454259) (xy 54.251117 -290.423134) (xy 54.293738 -290.398527)
			(xy 54.339754 -290.381075) (xy 54.387973 -290.371231) (xy 54.437148 -290.36925) (xy 54.486003 -290.375182)
			(xy 54.533274 -290.388874) (xy 54.577736 -290.409972) (xy 54.618239 -290.437928) (xy 54.653732 -290.47202)
			(xy 54.683297 -290.511364) (xy 54.706168 -290.554941) (xy 54.721752 -290.601622) (xy 54.729647 -290.650199)
			(xy 54.730142 -290.674806) (xy 55.06899 -290.674806) (xy 55.07295 -290.625752) (xy 55.084727 -290.577968)
			(xy 55.104018 -290.532692) (xy 55.130321 -290.491096) (xy 55.162956 -290.454259) (xy 55.201077 -290.423134)
			(xy 55.243698 -290.398527) (xy 55.289714 -290.381075) (xy 55.337933 -290.371231) (xy 55.387108 -290.36925)
			(xy 55.435963 -290.375182) (xy 55.483234 -290.388874) (xy 55.527696 -290.409972) (xy 55.568199 -290.437928)
			(xy 55.603692 -290.47202) (xy 55.633257 -290.511364) (xy 55.656128 -290.554941) (xy 55.671712 -290.601622)
			(xy 55.679607 -290.650199) (xy 55.680102 -290.674806) (xy 56.01895 -290.674806) (xy 56.02291 -290.625752)
			(xy 56.034687 -290.577968) (xy 56.053978 -290.532692) (xy 56.080281 -290.491096) (xy 56.112916 -290.454259)
			(xy 56.151037 -290.423134) (xy 56.193658 -290.398527) (xy 56.239674 -290.381075) (xy 56.287893 -290.371231)
			(xy 56.337068 -290.36925) (xy 56.385923 -290.375182) (xy 56.433194 -290.388874) (xy 56.477656 -290.409972)
			(xy 56.518159 -290.437928) (xy 56.553652 -290.47202) (xy 56.583217 -290.511364) (xy 56.606088 -290.554941)
			(xy 56.621672 -290.601622) (xy 56.629567 -290.650199) (xy 56.630062 -290.674806) (xy 56.969164 -290.674806)
			(xy 56.973124 -290.625752) (xy 56.984901 -290.577968) (xy 57.004192 -290.532692) (xy 57.030495 -290.491096)
			(xy 57.06313 -290.454259) (xy 57.101251 -290.423134) (xy 57.143872 -290.398527) (xy 57.189888 -290.381075)
			(xy 57.238107 -290.371231) (xy 57.287282 -290.36925) (xy 57.336137 -290.375182) (xy 57.383408 -290.388874)
			(xy 57.42787 -290.409972) (xy 57.468373 -290.437928) (xy 57.503866 -290.47202) (xy 57.533431 -290.511364)
			(xy 57.556302 -290.554941) (xy 57.571886 -290.601622) (xy 57.579781 -290.650199) (xy 57.580276 -290.674806)
			(xy 57.919124 -290.674806) (xy 57.923084 -290.625752) (xy 57.934861 -290.577968) (xy 57.954152 -290.532692)
			(xy 57.980455 -290.491096) (xy 58.01309 -290.454259) (xy 58.051211 -290.423134) (xy 58.093832 -290.398527)
			(xy 58.139848 -290.381075) (xy 58.188067 -290.371231) (xy 58.237242 -290.36925) (xy 58.286097 -290.375182)
			(xy 58.333368 -290.388874) (xy 58.37783 -290.409972) (xy 58.418333 -290.437928) (xy 58.453826 -290.47202)
			(xy 58.483391 -290.511364) (xy 58.506262 -290.554941) (xy 58.521846 -290.601622) (xy 58.529741 -290.650199)
			(xy 58.530236 -290.674806) (xy 59.819044 -290.674806) (xy 59.823004 -290.625752) (xy 59.834781 -290.577968)
			(xy 59.854072 -290.532692) (xy 59.880375 -290.491096) (xy 59.91301 -290.454259) (xy 59.951131 -290.423134)
			(xy 59.993752 -290.398527) (xy 60.039768 -290.381075) (xy 60.087987 -290.371231) (xy 60.137162 -290.36925)
			(xy 60.186017 -290.375182) (xy 60.233288 -290.388874) (xy 60.27775 -290.409972) (xy 60.318253 -290.437928)
			(xy 60.353746 -290.47202) (xy 60.383311 -290.511364) (xy 60.406182 -290.554941) (xy 60.421766 -290.601622)
			(xy 60.429661 -290.650199) (xy 60.430156 -290.674806) (xy 60.769004 -290.674806) (xy 60.772964 -290.625752)
			(xy 60.784741 -290.577968) (xy 60.804032 -290.532692) (xy 60.830335 -290.491096) (xy 60.86297 -290.454259)
			(xy 60.901091 -290.423134) (xy 60.943712 -290.398527) (xy 60.989728 -290.381075) (xy 61.037947 -290.371231)
			(xy 61.087122 -290.36925) (xy 61.135977 -290.375182) (xy 61.183248 -290.388874) (xy 61.22771 -290.409972)
			(xy 61.268213 -290.437928) (xy 61.303706 -290.47202) (xy 61.333271 -290.511364) (xy 61.356142 -290.554941)
			(xy 61.371726 -290.601622) (xy 61.379621 -290.650199) (xy 61.380116 -290.674806) (xy 61.718964 -290.674806)
			(xy 61.722924 -290.625752) (xy 61.734701 -290.577968) (xy 61.753992 -290.532692) (xy 61.780295 -290.491096)
			(xy 61.81293 -290.454259) (xy 61.851051 -290.423134) (xy 61.893672 -290.398527) (xy 61.939688 -290.381075)
			(xy 61.987907 -290.371231) (xy 62.037082 -290.36925) (xy 62.085937 -290.375182) (xy 62.133208 -290.388874)
			(xy 62.17767 -290.409972) (xy 62.218173 -290.437928) (xy 62.253666 -290.47202) (xy 62.283231 -290.511364)
			(xy 62.306102 -290.554941) (xy 62.321686 -290.601622) (xy 62.329581 -290.650199) (xy 62.330076 -290.674806)
			(xy 62.669178 -290.674806) (xy 62.673138 -290.625752) (xy 62.684915 -290.577968) (xy 62.704206 -290.532692)
			(xy 62.730509 -290.491096) (xy 62.763144 -290.454259) (xy 62.801265 -290.423134) (xy 62.843886 -290.398527)
			(xy 62.889902 -290.381075) (xy 62.938121 -290.371231) (xy 62.987296 -290.36925) (xy 63.036151 -290.375182)
			(xy 63.083422 -290.388874) (xy 63.127884 -290.409972) (xy 63.168387 -290.437928) (xy 63.20388 -290.47202)
			(xy 63.233445 -290.511364) (xy 63.256316 -290.554941) (xy 63.2719 -290.601622) (xy 63.279795 -290.650199)
			(xy 63.28029 -290.674806) (xy 63.619138 -290.674806) (xy 63.623098 -290.625752) (xy 63.634875 -290.577968)
			(xy 63.654166 -290.532692) (xy 63.680469 -290.491096) (xy 63.713104 -290.454259) (xy 63.751225 -290.423134)
			(xy 63.793846 -290.398527) (xy 63.839862 -290.381075) (xy 63.888081 -290.371231) (xy 63.937256 -290.36925)
			(xy 63.986111 -290.375182) (xy 64.033382 -290.388874) (xy 64.077844 -290.409972) (xy 64.118347 -290.437928)
			(xy 64.15384 -290.47202) (xy 64.183405 -290.511364) (xy 64.206276 -290.554941) (xy 64.22186 -290.601622)
			(xy 64.229755 -290.650199) (xy 64.23025 -290.674806) (xy 64.569098 -290.674806) (xy 64.573058 -290.625752)
			(xy 64.584835 -290.577968) (xy 64.604126 -290.532692) (xy 64.630429 -290.491096) (xy 64.663064 -290.454259)
			(xy 64.701185 -290.423134) (xy 64.743806 -290.398527) (xy 64.789822 -290.381075) (xy 64.838041 -290.371231)
			(xy 64.887216 -290.36925) (xy 64.936071 -290.375182) (xy 64.983342 -290.388874) (xy 65.027804 -290.409972)
			(xy 65.068307 -290.437928) (xy 65.1038 -290.47202) (xy 65.133365 -290.511364) (xy 65.156236 -290.554941)
			(xy 65.17182 -290.601622) (xy 65.179715 -290.650199) (xy 65.18021 -290.674806) (xy 65.519058 -290.674806)
			(xy 65.523018 -290.625752) (xy 65.534795 -290.577968) (xy 65.554086 -290.532692) (xy 65.580389 -290.491096)
			(xy 65.613024 -290.454259) (xy 65.651145 -290.423134) (xy 65.693766 -290.398527) (xy 65.739782 -290.381075)
			(xy 65.788001 -290.371231) (xy 65.837176 -290.36925) (xy 65.886031 -290.375182) (xy 65.933302 -290.388874)
			(xy 65.977764 -290.409972) (xy 66.018267 -290.437928) (xy 66.05376 -290.47202) (xy 66.083325 -290.511364)
			(xy 66.106196 -290.554941) (xy 66.12178 -290.601622) (xy 66.129675 -290.650199) (xy 66.13017 -290.674806)
			(xy 66.469018 -290.674806) (xy 66.472978 -290.625752) (xy 66.484755 -290.577968) (xy 66.504046 -290.532692)
			(xy 66.530349 -290.491096) (xy 66.562984 -290.454259) (xy 66.601105 -290.423134) (xy 66.643726 -290.398527)
			(xy 66.689742 -290.381075) (xy 66.737961 -290.371231) (xy 66.787136 -290.36925) (xy 66.835991 -290.375182)
			(xy 66.883262 -290.388874) (xy 66.927724 -290.409972) (xy 66.968227 -290.437928) (xy 67.00372 -290.47202)
			(xy 67.033285 -290.511364) (xy 67.056156 -290.554941) (xy 67.07174 -290.601622) (xy 67.079635 -290.650199)
			(xy 67.08013 -290.674806) (xy 67.418978 -290.674806) (xy 67.422938 -290.625752) (xy 67.434715 -290.577968)
			(xy 67.454006 -290.532692) (xy 67.480309 -290.491096) (xy 67.512944 -290.454259) (xy 67.551065 -290.423134)
			(xy 67.593686 -290.398527) (xy 67.639702 -290.381075) (xy 67.687921 -290.371231) (xy 67.737096 -290.36925)
			(xy 67.785951 -290.375182) (xy 67.833222 -290.388874) (xy 67.877684 -290.409972) (xy 67.918187 -290.437928)
			(xy 67.95368 -290.47202) (xy 67.983245 -290.511364) (xy 68.006116 -290.554941) (xy 68.0217 -290.601622)
			(xy 68.029595 -290.650199) (xy 68.03009 -290.674806) (xy 68.368938 -290.674806) (xy 68.372898 -290.625752)
			(xy 68.384675 -290.577968) (xy 68.403966 -290.532692) (xy 68.430269 -290.491096) (xy 68.462904 -290.454259)
			(xy 68.501025 -290.423134) (xy 68.543646 -290.398527) (xy 68.589662 -290.381075) (xy 68.637881 -290.371231)
			(xy 68.687056 -290.36925) (xy 68.735911 -290.375182) (xy 68.783182 -290.388874) (xy 68.827644 -290.409972)
			(xy 68.868147 -290.437928) (xy 68.90364 -290.47202) (xy 68.933205 -290.511364) (xy 68.956076 -290.554941)
			(xy 68.97166 -290.601622) (xy 68.979555 -290.650199) (xy 68.98005 -290.674806) (xy 69.319152 -290.674806)
			(xy 69.323112 -290.625752) (xy 69.334889 -290.577968) (xy 69.35418 -290.532692) (xy 69.380483 -290.491096)
			(xy 69.413118 -290.454259) (xy 69.451239 -290.423134) (xy 69.49386 -290.398527) (xy 69.539876 -290.381075)
			(xy 69.588095 -290.371231) (xy 69.63727 -290.36925) (xy 69.686125 -290.375182) (xy 69.733396 -290.388874)
			(xy 69.777858 -290.409972) (xy 69.818361 -290.437928) (xy 69.853854 -290.47202) (xy 69.883419 -290.511364)
			(xy 69.90629 -290.554941) (xy 69.921874 -290.601622) (xy 69.929769 -290.650199) (xy 69.930264 -290.674806)
			(xy 70.269112 -290.674806) (xy 70.273072 -290.625752) (xy 70.284849 -290.577968) (xy 70.30414 -290.532692)
			(xy 70.330443 -290.491096) (xy 70.363078 -290.454259) (xy 70.401199 -290.423134) (xy 70.44382 -290.398527)
			(xy 70.489836 -290.381075) (xy 70.538055 -290.371231) (xy 70.58723 -290.36925) (xy 70.636085 -290.375182)
			(xy 70.683356 -290.388874) (xy 70.727818 -290.409972) (xy 70.768321 -290.437928) (xy 70.803814 -290.47202)
			(xy 70.833379 -290.511364) (xy 70.85625 -290.554941) (xy 70.871834 -290.601622) (xy 70.879729 -290.650199)
			(xy 70.880224 -290.674806) (xy 71.219072 -290.674806) (xy 71.223032 -290.625752) (xy 71.234809 -290.577968)
			(xy 71.2541 -290.532692) (xy 71.280403 -290.491096) (xy 71.313038 -290.454259) (xy 71.351159 -290.423134)
			(xy 71.39378 -290.398527) (xy 71.439796 -290.381075) (xy 71.488015 -290.371231) (xy 71.53719 -290.36925)
			(xy 71.586045 -290.375182) (xy 71.633316 -290.388874) (xy 71.677778 -290.409972) (xy 71.718281 -290.437928)
			(xy 71.753774 -290.47202) (xy 71.783339 -290.511364) (xy 71.80621 -290.554941) (xy 71.821794 -290.601622)
			(xy 71.829689 -290.650199) (xy 71.830184 -290.674806) (xy 72.169032 -290.674806) (xy 72.172992 -290.625752)
			(xy 72.184769 -290.577968) (xy 72.20406 -290.532692) (xy 72.230363 -290.491096) (xy 72.262998 -290.454259)
			(xy 72.301119 -290.423134) (xy 72.34374 -290.398527) (xy 72.389756 -290.381075) (xy 72.437975 -290.371231)
			(xy 72.48715 -290.36925) (xy 72.536005 -290.375182) (xy 72.583276 -290.388874) (xy 72.627738 -290.409972)
			(xy 72.668241 -290.437928) (xy 72.703734 -290.47202) (xy 72.733299 -290.511364) (xy 72.75617 -290.554941)
			(xy 72.771754 -290.601622) (xy 72.779649 -290.650199) (xy 72.780144 -290.674806) (xy 73.118992 -290.674806)
			(xy 73.122952 -290.625752) (xy 73.134729 -290.577968) (xy 73.15402 -290.532692) (xy 73.180323 -290.491096)
			(xy 73.212958 -290.454259) (xy 73.251079 -290.423134) (xy 73.2937 -290.398527) (xy 73.339716 -290.381075)
			(xy 73.387935 -290.371231) (xy 73.43711 -290.36925) (xy 73.485965 -290.375182) (xy 73.533236 -290.388874)
			(xy 73.577698 -290.409972) (xy 73.618201 -290.437928) (xy 73.653694 -290.47202) (xy 73.683259 -290.511364)
			(xy 73.70613 -290.554941) (xy 73.721714 -290.601622) (xy 73.729609 -290.650199) (xy 73.730104 -290.674806)
			(xy 74.068952 -290.674806) (xy 74.072912 -290.625752) (xy 74.084689 -290.577968) (xy 74.10398 -290.532692)
			(xy 74.130283 -290.491096) (xy 74.162918 -290.454259) (xy 74.201039 -290.423134) (xy 74.24366 -290.398527)
			(xy 74.289676 -290.381075) (xy 74.337895 -290.371231) (xy 74.38707 -290.36925) (xy 74.435925 -290.375182)
			(xy 74.483196 -290.388874) (xy 74.527658 -290.409972) (xy 74.568161 -290.437928) (xy 74.603654 -290.47202)
			(xy 74.633219 -290.511364) (xy 74.65609 -290.554941) (xy 74.671674 -290.601622) (xy 74.679569 -290.650199)
			(xy 74.680064 -290.674806) (xy 75.019166 -290.674806) (xy 75.023126 -290.625752) (xy 75.034903 -290.577968)
			(xy 75.054194 -290.532692) (xy 75.080497 -290.491096) (xy 75.113132 -290.454259) (xy 75.151253 -290.423134)
			(xy 75.193874 -290.398527) (xy 75.23989 -290.381075) (xy 75.288109 -290.371231) (xy 75.337284 -290.36925)
			(xy 75.386139 -290.375182) (xy 75.43341 -290.388874) (xy 75.477872 -290.409972) (xy 75.518375 -290.437928)
			(xy 75.553868 -290.47202) (xy 75.583433 -290.511364) (xy 75.606304 -290.554941) (xy 75.621888 -290.601622)
			(xy 75.629783 -290.650199) (xy 75.630278 -290.674806) (xy 75.969126 -290.674806) (xy 75.973086 -290.625752)
			(xy 75.984863 -290.577968) (xy 76.004154 -290.532692) (xy 76.030457 -290.491096) (xy 76.063092 -290.454259)
			(xy 76.101213 -290.423134) (xy 76.143834 -290.398527) (xy 76.18985 -290.381075) (xy 76.238069 -290.371231)
			(xy 76.287244 -290.36925) (xy 76.336099 -290.375182) (xy 76.38337 -290.388874) (xy 76.427832 -290.409972)
			(xy 76.468335 -290.437928) (xy 76.503828 -290.47202) (xy 76.533393 -290.511364) (xy 76.556264 -290.554941)
			(xy 76.571848 -290.601622) (xy 76.579743 -290.650199) (xy 76.580238 -290.674806) (xy 76.919086 -290.674806)
			(xy 76.923046 -290.625752) (xy 76.934823 -290.577968) (xy 76.954114 -290.532692) (xy 76.980417 -290.491096)
			(xy 77.013052 -290.454259) (xy 77.051173 -290.423134) (xy 77.093794 -290.398527) (xy 77.13981 -290.381075)
			(xy 77.188029 -290.371231) (xy 77.237204 -290.36925) (xy 77.286059 -290.375182) (xy 77.33333 -290.388874)
			(xy 77.377792 -290.409972) (xy 77.418295 -290.437928) (xy 77.453788 -290.47202) (xy 77.483353 -290.511364)
			(xy 77.506224 -290.554941) (xy 77.521808 -290.601622) (xy 77.529703 -290.650199) (xy 77.530198 -290.674806)
			(xy 77.869046 -290.674806) (xy 77.873006 -290.625752) (xy 77.884783 -290.577968) (xy 77.904074 -290.532692)
			(xy 77.930377 -290.491096) (xy 77.963012 -290.454259) (xy 78.001133 -290.423134) (xy 78.043754 -290.398527)
			(xy 78.08977 -290.381075) (xy 78.137989 -290.371231) (xy 78.187164 -290.36925) (xy 78.236019 -290.375182)
			(xy 78.28329 -290.388874) (xy 78.327752 -290.409972) (xy 78.368255 -290.437928) (xy 78.403748 -290.47202)
			(xy 78.433313 -290.511364) (xy 78.456184 -290.554941) (xy 78.471768 -290.601622) (xy 78.479663 -290.650199)
			(xy 78.480158 -290.674806) (xy 78.819006 -290.674806) (xy 78.822966 -290.625752) (xy 78.834743 -290.577968)
			(xy 78.854034 -290.532692) (xy 78.880337 -290.491096) (xy 78.912972 -290.454259) (xy 78.951093 -290.423134)
			(xy 78.993714 -290.398527) (xy 79.03973 -290.381075) (xy 79.087949 -290.371231) (xy 79.137124 -290.36925)
			(xy 79.185979 -290.375182) (xy 79.23325 -290.388874) (xy 79.277712 -290.409972) (xy 79.318215 -290.437928)
			(xy 79.353708 -290.47202) (xy 79.383273 -290.511364) (xy 79.406144 -290.554941) (xy 79.421728 -290.601622)
			(xy 79.429623 -290.650199) (xy 79.430118 -290.674806) (xy 79.768966 -290.674806) (xy 79.772926 -290.625752)
			(xy 79.784703 -290.577968) (xy 79.803994 -290.532692) (xy 79.830297 -290.491096) (xy 79.862932 -290.454259)
			(xy 79.901053 -290.423134) (xy 79.943674 -290.398527) (xy 79.98969 -290.381075) (xy 80.037909 -290.371231)
			(xy 80.087084 -290.36925) (xy 80.135939 -290.375182) (xy 80.18321 -290.388874) (xy 80.227672 -290.409972)
			(xy 80.268175 -290.437928) (xy 80.303668 -290.47202) (xy 80.333233 -290.511364) (xy 80.356104 -290.554941)
			(xy 80.371688 -290.601622) (xy 80.379583 -290.650199) (xy 80.380078 -290.674806) (xy 80.71918 -290.674806)
			(xy 80.72314 -290.625752) (xy 80.734917 -290.577968) (xy 80.754208 -290.532692) (xy 80.780511 -290.491096)
			(xy 80.813146 -290.454259) (xy 80.851267 -290.423134) (xy 80.893888 -290.398527) (xy 80.939904 -290.381075)
			(xy 80.988123 -290.371231) (xy 81.037298 -290.36925) (xy 81.086153 -290.375182) (xy 81.133424 -290.388874)
			(xy 81.177886 -290.409972) (xy 81.218389 -290.437928) (xy 81.253882 -290.47202) (xy 81.283447 -290.511364)
			(xy 81.306318 -290.554941) (xy 81.321902 -290.601622) (xy 81.329797 -290.650199) (xy 81.330292 -290.674806)
			(xy 81.66914 -290.674806) (xy 81.6731 -290.625752) (xy 81.684877 -290.577968) (xy 81.704168 -290.532692)
			(xy 81.730471 -290.491096) (xy 81.763106 -290.454259) (xy 81.801227 -290.423134) (xy 81.843848 -290.398527)
			(xy 81.889864 -290.381075) (xy 81.938083 -290.371231) (xy 81.987258 -290.36925) (xy 82.036113 -290.375182)
			(xy 82.083384 -290.388874) (xy 82.127846 -290.409972) (xy 82.168349 -290.437928) (xy 82.203842 -290.47202)
			(xy 82.233407 -290.511364) (xy 82.256278 -290.554941) (xy 82.271862 -290.601622) (xy 82.279757 -290.650199)
			(xy 82.280252 -290.674806) (xy 82.6191 -290.674806) (xy 82.62306 -290.625752) (xy 82.634837 -290.577968)
			(xy 82.654128 -290.532692) (xy 82.680431 -290.491096) (xy 82.713066 -290.454259) (xy 82.751187 -290.423134)
			(xy 82.793808 -290.398527) (xy 82.839824 -290.381075) (xy 82.888043 -290.371231) (xy 82.937218 -290.36925)
			(xy 82.986073 -290.375182) (xy 83.033344 -290.388874) (xy 83.077806 -290.409972) (xy 83.118309 -290.437928)
			(xy 83.153802 -290.47202) (xy 83.183367 -290.511364) (xy 83.206238 -290.554941) (xy 83.221822 -290.601622)
			(xy 83.229717 -290.650199) (xy 83.230212 -290.674806) (xy 83.229717 -290.699413) (xy 83.221822 -290.74799)
			(xy 83.206238 -290.794671) (xy 83.183367 -290.838248) (xy 83.153802 -290.877592) (xy 83.118309 -290.911684)
			(xy 83.077806 -290.93964) (xy 83.033344 -290.960738) (xy 82.986073 -290.97443) (xy 82.937218 -290.980362)
			(xy 82.888043 -290.978381) (xy 82.839824 -290.968537) (xy 82.793808 -290.951085) (xy 82.751187 -290.926478)
			(xy 82.713066 -290.895353) (xy 82.680431 -290.858516) (xy 82.654128 -290.81692) (xy 82.634837 -290.771644)
			(xy 82.62306 -290.72386) (xy 82.6191 -290.674806) (xy 82.280252 -290.674806) (xy 82.279757 -290.699413)
			(xy 82.271862 -290.74799) (xy 82.256278 -290.794671) (xy 82.233407 -290.838248) (xy 82.203842 -290.877592)
			(xy 82.168349 -290.911684) (xy 82.127846 -290.93964) (xy 82.083384 -290.960738) (xy 82.036113 -290.97443)
			(xy 81.987258 -290.980362) (xy 81.938083 -290.978381) (xy 81.889864 -290.968537) (xy 81.843848 -290.951085)
			(xy 81.801227 -290.926478) (xy 81.763106 -290.895353) (xy 81.730471 -290.858516) (xy 81.704168 -290.81692)
			(xy 81.684877 -290.771644) (xy 81.6731 -290.72386) (xy 81.66914 -290.674806) (xy 81.330292 -290.674806)
			(xy 81.329797 -290.699413) (xy 81.321902 -290.74799) (xy 81.306318 -290.794671) (xy 81.283447 -290.838248)
			(xy 81.253882 -290.877592) (xy 81.218389 -290.911684) (xy 81.177886 -290.93964) (xy 81.133424 -290.960738)
			(xy 81.086153 -290.97443) (xy 81.037298 -290.980362) (xy 80.988123 -290.978381) (xy 80.939904 -290.968537)
			(xy 80.893888 -290.951085) (xy 80.851267 -290.926478) (xy 80.813146 -290.895353) (xy 80.780511 -290.858516)
			(xy 80.754208 -290.81692) (xy 80.734917 -290.771644) (xy 80.72314 -290.72386) (xy 80.71918 -290.674806)
			(xy 80.380078 -290.674806) (xy 80.379583 -290.699413) (xy 80.371688 -290.74799) (xy 80.356104 -290.794671)
			(xy 80.333233 -290.838248) (xy 80.303668 -290.877592) (xy 80.268175 -290.911684) (xy 80.227672 -290.93964)
			(xy 80.18321 -290.960738) (xy 80.135939 -290.97443) (xy 80.087084 -290.980362) (xy 80.037909 -290.978381)
			(xy 79.98969 -290.968537) (xy 79.943674 -290.951085) (xy 79.901053 -290.926478) (xy 79.862932 -290.895353)
			(xy 79.830297 -290.858516) (xy 79.803994 -290.81692) (xy 79.784703 -290.771644) (xy 79.772926 -290.72386)
			(xy 79.768966 -290.674806) (xy 79.430118 -290.674806) (xy 79.429623 -290.699413) (xy 79.421728 -290.74799)
			(xy 79.406144 -290.794671) (xy 79.383273 -290.838248) (xy 79.353708 -290.877592) (xy 79.318215 -290.911684)
			(xy 79.277712 -290.93964) (xy 79.23325 -290.960738) (xy 79.185979 -290.97443) (xy 79.137124 -290.980362)
			(xy 79.087949 -290.978381) (xy 79.03973 -290.968537) (xy 78.993714 -290.951085) (xy 78.951093 -290.926478)
			(xy 78.912972 -290.895353) (xy 78.880337 -290.858516) (xy 78.854034 -290.81692) (xy 78.834743 -290.771644)
			(xy 78.822966 -290.72386) (xy 78.819006 -290.674806) (xy 78.480158 -290.674806) (xy 78.479663 -290.699413)
			(xy 78.471768 -290.74799) (xy 78.456184 -290.794671) (xy 78.433313 -290.838248) (xy 78.403748 -290.877592)
			(xy 78.368255 -290.911684) (xy 78.327752 -290.93964) (xy 78.28329 -290.960738) (xy 78.236019 -290.97443)
			(xy 78.187164 -290.980362) (xy 78.137989 -290.978381) (xy 78.08977 -290.968537) (xy 78.043754 -290.951085)
			(xy 78.001133 -290.926478) (xy 77.963012 -290.895353) (xy 77.930377 -290.858516) (xy 77.904074 -290.81692)
			(xy 77.884783 -290.771644) (xy 77.873006 -290.72386) (xy 77.869046 -290.674806) (xy 77.530198 -290.674806)
			(xy 77.529703 -290.699413) (xy 77.521808 -290.74799) (xy 77.506224 -290.794671) (xy 77.483353 -290.838248)
			(xy 77.453788 -290.877592) (xy 77.418295 -290.911684) (xy 77.377792 -290.93964) (xy 77.33333 -290.960738)
			(xy 77.286059 -290.97443) (xy 77.237204 -290.980362) (xy 77.188029 -290.978381) (xy 77.13981 -290.968537)
			(xy 77.093794 -290.951085) (xy 77.051173 -290.926478) (xy 77.013052 -290.895353) (xy 76.980417 -290.858516)
			(xy 76.954114 -290.81692) (xy 76.934823 -290.771644) (xy 76.923046 -290.72386) (xy 76.919086 -290.674806)
			(xy 76.580238 -290.674806) (xy 76.579743 -290.699413) (xy 76.571848 -290.74799) (xy 76.556264 -290.794671)
			(xy 76.533393 -290.838248) (xy 76.503828 -290.877592) (xy 76.468335 -290.911684) (xy 76.427832 -290.93964)
			(xy 76.38337 -290.960738) (xy 76.336099 -290.97443) (xy 76.287244 -290.980362) (xy 76.238069 -290.978381)
			(xy 76.18985 -290.968537) (xy 76.143834 -290.951085) (xy 76.101213 -290.926478) (xy 76.063092 -290.895353)
			(xy 76.030457 -290.858516) (xy 76.004154 -290.81692) (xy 75.984863 -290.771644) (xy 75.973086 -290.72386)
			(xy 75.969126 -290.674806) (xy 75.630278 -290.674806) (xy 75.629783 -290.699413) (xy 75.621888 -290.74799)
			(xy 75.606304 -290.794671) (xy 75.583433 -290.838248) (xy 75.553868 -290.877592) (xy 75.518375 -290.911684)
			(xy 75.477872 -290.93964) (xy 75.43341 -290.960738) (xy 75.386139 -290.97443) (xy 75.337284 -290.980362)
			(xy 75.288109 -290.978381) (xy 75.23989 -290.968537) (xy 75.193874 -290.951085) (xy 75.151253 -290.926478)
			(xy 75.113132 -290.895353) (xy 75.080497 -290.858516) (xy 75.054194 -290.81692) (xy 75.034903 -290.771644)
			(xy 75.023126 -290.72386) (xy 75.019166 -290.674806) (xy 74.680064 -290.674806) (xy 74.679569 -290.699413)
			(xy 74.671674 -290.74799) (xy 74.65609 -290.794671) (xy 74.633219 -290.838248) (xy 74.603654 -290.877592)
			(xy 74.568161 -290.911684) (xy 74.527658 -290.93964) (xy 74.483196 -290.960738) (xy 74.435925 -290.97443)
			(xy 74.38707 -290.980362) (xy 74.337895 -290.978381) (xy 74.289676 -290.968537) (xy 74.24366 -290.951085)
			(xy 74.201039 -290.926478) (xy 74.162918 -290.895353) (xy 74.130283 -290.858516) (xy 74.10398 -290.81692)
			(xy 74.084689 -290.771644) (xy 74.072912 -290.72386) (xy 74.068952 -290.674806) (xy 73.730104 -290.674806)
			(xy 73.729609 -290.699413) (xy 73.721714 -290.74799) (xy 73.70613 -290.794671) (xy 73.683259 -290.838248)
			(xy 73.653694 -290.877592) (xy 73.618201 -290.911684) (xy 73.577698 -290.93964) (xy 73.533236 -290.960738)
			(xy 73.485965 -290.97443) (xy 73.43711 -290.980362) (xy 73.387935 -290.978381) (xy 73.339716 -290.968537)
			(xy 73.2937 -290.951085) (xy 73.251079 -290.926478) (xy 73.212958 -290.895353) (xy 73.180323 -290.858516)
			(xy 73.15402 -290.81692) (xy 73.134729 -290.771644) (xy 73.122952 -290.72386) (xy 73.118992 -290.674806)
			(xy 72.780144 -290.674806) (xy 72.779649 -290.699413) (xy 72.771754 -290.74799) (xy 72.75617 -290.794671)
			(xy 72.733299 -290.838248) (xy 72.703734 -290.877592) (xy 72.668241 -290.911684) (xy 72.627738 -290.93964)
			(xy 72.583276 -290.960738) (xy 72.536005 -290.97443) (xy 72.48715 -290.980362) (xy 72.437975 -290.978381)
			(xy 72.389756 -290.968537) (xy 72.34374 -290.951085) (xy 72.301119 -290.926478) (xy 72.262998 -290.895353)
			(xy 72.230363 -290.858516) (xy 72.20406 -290.81692) (xy 72.184769 -290.771644) (xy 72.172992 -290.72386)
			(xy 72.169032 -290.674806) (xy 71.830184 -290.674806) (xy 71.829689 -290.699413) (xy 71.821794 -290.74799)
			(xy 71.80621 -290.794671) (xy 71.783339 -290.838248) (xy 71.753774 -290.877592) (xy 71.718281 -290.911684)
			(xy 71.677778 -290.93964) (xy 71.633316 -290.960738) (xy 71.586045 -290.97443) (xy 71.53719 -290.980362)
			(xy 71.488015 -290.978381) (xy 71.439796 -290.968537) (xy 71.39378 -290.951085) (xy 71.351159 -290.926478)
			(xy 71.313038 -290.895353) (xy 71.280403 -290.858516) (xy 71.2541 -290.81692) (xy 71.234809 -290.771644)
			(xy 71.223032 -290.72386) (xy 71.219072 -290.674806) (xy 70.880224 -290.674806) (xy 70.879729 -290.699413)
			(xy 70.871834 -290.74799) (xy 70.85625 -290.794671) (xy 70.833379 -290.838248) (xy 70.803814 -290.877592)
			(xy 70.768321 -290.911684) (xy 70.727818 -290.93964) (xy 70.683356 -290.960738) (xy 70.636085 -290.97443)
			(xy 70.58723 -290.980362) (xy 70.538055 -290.978381) (xy 70.489836 -290.968537) (xy 70.44382 -290.951085)
			(xy 70.401199 -290.926478) (xy 70.363078 -290.895353) (xy 70.330443 -290.858516) (xy 70.30414 -290.81692)
			(xy 70.284849 -290.771644) (xy 70.273072 -290.72386) (xy 70.269112 -290.674806) (xy 69.930264 -290.674806)
			(xy 69.929769 -290.699413) (xy 69.921874 -290.74799) (xy 69.90629 -290.794671) (xy 69.883419 -290.838248)
			(xy 69.853854 -290.877592) (xy 69.818361 -290.911684) (xy 69.777858 -290.93964) (xy 69.733396 -290.960738)
			(xy 69.686125 -290.97443) (xy 69.63727 -290.980362) (xy 69.588095 -290.978381) (xy 69.539876 -290.968537)
			(xy 69.49386 -290.951085) (xy 69.451239 -290.926478) (xy 69.413118 -290.895353) (xy 69.380483 -290.858516)
			(xy 69.35418 -290.81692) (xy 69.334889 -290.771644) (xy 69.323112 -290.72386) (xy 69.319152 -290.674806)
			(xy 68.98005 -290.674806) (xy 68.979555 -290.699413) (xy 68.97166 -290.74799) (xy 68.956076 -290.794671)
			(xy 68.933205 -290.838248) (xy 68.90364 -290.877592) (xy 68.868147 -290.911684) (xy 68.827644 -290.93964)
			(xy 68.783182 -290.960738) (xy 68.735911 -290.97443) (xy 68.687056 -290.980362) (xy 68.637881 -290.978381)
			(xy 68.589662 -290.968537) (xy 68.543646 -290.951085) (xy 68.501025 -290.926478) (xy 68.462904 -290.895353)
			(xy 68.430269 -290.858516) (xy 68.403966 -290.81692) (xy 68.384675 -290.771644) (xy 68.372898 -290.72386)
			(xy 68.368938 -290.674806) (xy 68.03009 -290.674806) (xy 68.029595 -290.699413) (xy 68.0217 -290.74799)
			(xy 68.006116 -290.794671) (xy 67.983245 -290.838248) (xy 67.95368 -290.877592) (xy 67.918187 -290.911684)
			(xy 67.877684 -290.93964) (xy 67.833222 -290.960738) (xy 67.785951 -290.97443) (xy 67.737096 -290.980362)
			(xy 67.687921 -290.978381) (xy 67.639702 -290.968537) (xy 67.593686 -290.951085) (xy 67.551065 -290.926478)
			(xy 67.512944 -290.895353) (xy 67.480309 -290.858516) (xy 67.454006 -290.81692) (xy 67.434715 -290.771644)
			(xy 67.422938 -290.72386) (xy 67.418978 -290.674806) (xy 67.08013 -290.674806) (xy 67.079635 -290.699413)
			(xy 67.07174 -290.74799) (xy 67.056156 -290.794671) (xy 67.033285 -290.838248) (xy 67.00372 -290.877592)
			(xy 66.968227 -290.911684) (xy 66.927724 -290.93964) (xy 66.883262 -290.960738) (xy 66.835991 -290.97443)
			(xy 66.787136 -290.980362) (xy 66.737961 -290.978381) (xy 66.689742 -290.968537) (xy 66.643726 -290.951085)
			(xy 66.601105 -290.926478) (xy 66.562984 -290.895353) (xy 66.530349 -290.858516) (xy 66.504046 -290.81692)
			(xy 66.484755 -290.771644) (xy 66.472978 -290.72386) (xy 66.469018 -290.674806) (xy 66.13017 -290.674806)
			(xy 66.129675 -290.699413) (xy 66.12178 -290.74799) (xy 66.106196 -290.794671) (xy 66.083325 -290.838248)
			(xy 66.05376 -290.877592) (xy 66.018267 -290.911684) (xy 65.977764 -290.93964) (xy 65.933302 -290.960738)
			(xy 65.886031 -290.97443) (xy 65.837176 -290.980362) (xy 65.788001 -290.978381) (xy 65.739782 -290.968537)
			(xy 65.693766 -290.951085) (xy 65.651145 -290.926478) (xy 65.613024 -290.895353) (xy 65.580389 -290.858516)
			(xy 65.554086 -290.81692) (xy 65.534795 -290.771644) (xy 65.523018 -290.72386) (xy 65.519058 -290.674806)
			(xy 65.18021 -290.674806) (xy 65.179715 -290.699413) (xy 65.17182 -290.74799) (xy 65.156236 -290.794671)
			(xy 65.133365 -290.838248) (xy 65.1038 -290.877592) (xy 65.068307 -290.911684) (xy 65.027804 -290.93964)
			(xy 64.983342 -290.960738) (xy 64.936071 -290.97443) (xy 64.887216 -290.980362) (xy 64.838041 -290.978381)
			(xy 64.789822 -290.968537) (xy 64.743806 -290.951085) (xy 64.701185 -290.926478) (xy 64.663064 -290.895353)
			(xy 64.630429 -290.858516) (xy 64.604126 -290.81692) (xy 64.584835 -290.771644) (xy 64.573058 -290.72386)
			(xy 64.569098 -290.674806) (xy 64.23025 -290.674806) (xy 64.229755 -290.699413) (xy 64.22186 -290.74799)
			(xy 64.206276 -290.794671) (xy 64.183405 -290.838248) (xy 64.15384 -290.877592) (xy 64.118347 -290.911684)
			(xy 64.077844 -290.93964) (xy 64.033382 -290.960738) (xy 63.986111 -290.97443) (xy 63.937256 -290.980362)
			(xy 63.888081 -290.978381) (xy 63.839862 -290.968537) (xy 63.793846 -290.951085) (xy 63.751225 -290.926478)
			(xy 63.713104 -290.895353) (xy 63.680469 -290.858516) (xy 63.654166 -290.81692) (xy 63.634875 -290.771644)
			(xy 63.623098 -290.72386) (xy 63.619138 -290.674806) (xy 63.28029 -290.674806) (xy 63.279795 -290.699413)
			(xy 63.2719 -290.74799) (xy 63.256316 -290.794671) (xy 63.233445 -290.838248) (xy 63.20388 -290.877592)
			(xy 63.168387 -290.911684) (xy 63.127884 -290.93964) (xy 63.083422 -290.960738) (xy 63.036151 -290.97443)
			(xy 62.987296 -290.980362) (xy 62.938121 -290.978381) (xy 62.889902 -290.968537) (xy 62.843886 -290.951085)
			(xy 62.801265 -290.926478) (xy 62.763144 -290.895353) (xy 62.730509 -290.858516) (xy 62.704206 -290.81692)
			(xy 62.684915 -290.771644) (xy 62.673138 -290.72386) (xy 62.669178 -290.674806) (xy 62.330076 -290.674806)
			(xy 62.329581 -290.699413) (xy 62.321686 -290.74799) (xy 62.306102 -290.794671) (xy 62.283231 -290.838248)
			(xy 62.253666 -290.877592) (xy 62.218173 -290.911684) (xy 62.17767 -290.93964) (xy 62.133208 -290.960738)
			(xy 62.085937 -290.97443) (xy 62.037082 -290.980362) (xy 61.987907 -290.978381) (xy 61.939688 -290.968537)
			(xy 61.893672 -290.951085) (xy 61.851051 -290.926478) (xy 61.81293 -290.895353) (xy 61.780295 -290.858516)
			(xy 61.753992 -290.81692) (xy 61.734701 -290.771644) (xy 61.722924 -290.72386) (xy 61.718964 -290.674806)
			(xy 61.380116 -290.674806) (xy 61.379621 -290.699413) (xy 61.371726 -290.74799) (xy 61.356142 -290.794671)
			(xy 61.333271 -290.838248) (xy 61.303706 -290.877592) (xy 61.268213 -290.911684) (xy 61.22771 -290.93964)
			(xy 61.183248 -290.960738) (xy 61.135977 -290.97443) (xy 61.087122 -290.980362) (xy 61.037947 -290.978381)
			(xy 60.989728 -290.968537) (xy 60.943712 -290.951085) (xy 60.901091 -290.926478) (xy 60.86297 -290.895353)
			(xy 60.830335 -290.858516) (xy 60.804032 -290.81692) (xy 60.784741 -290.771644) (xy 60.772964 -290.72386)
			(xy 60.769004 -290.674806) (xy 60.430156 -290.674806) (xy 60.429661 -290.699413) (xy 60.421766 -290.74799)
			(xy 60.406182 -290.794671) (xy 60.383311 -290.838248) (xy 60.353746 -290.877592) (xy 60.318253 -290.911684)
			(xy 60.27775 -290.93964) (xy 60.233288 -290.960738) (xy 60.186017 -290.97443) (xy 60.137162 -290.980362)
			(xy 60.087987 -290.978381) (xy 60.039768 -290.968537) (xy 59.993752 -290.951085) (xy 59.951131 -290.926478)
			(xy 59.91301 -290.895353) (xy 59.880375 -290.858516) (xy 59.854072 -290.81692) (xy 59.834781 -290.771644)
			(xy 59.823004 -290.72386) (xy 59.819044 -290.674806) (xy 58.530236 -290.674806) (xy 58.529741 -290.699413)
			(xy 58.521846 -290.74799) (xy 58.506262 -290.794671) (xy 58.483391 -290.838248) (xy 58.453826 -290.877592)
			(xy 58.418333 -290.911684) (xy 58.37783 -290.93964) (xy 58.333368 -290.960738) (xy 58.286097 -290.97443)
			(xy 58.237242 -290.980362) (xy 58.188067 -290.978381) (xy 58.139848 -290.968537) (xy 58.093832 -290.951085)
			(xy 58.051211 -290.926478) (xy 58.01309 -290.895353) (xy 57.980455 -290.858516) (xy 57.954152 -290.81692)
			(xy 57.934861 -290.771644) (xy 57.923084 -290.72386) (xy 57.919124 -290.674806) (xy 57.580276 -290.674806)
			(xy 57.579781 -290.699413) (xy 57.571886 -290.74799) (xy 57.556302 -290.794671) (xy 57.533431 -290.838248)
			(xy 57.503866 -290.877592) (xy 57.468373 -290.911684) (xy 57.42787 -290.93964) (xy 57.383408 -290.960738)
			(xy 57.336137 -290.97443) (xy 57.287282 -290.980362) (xy 57.238107 -290.978381) (xy 57.189888 -290.968537)
			(xy 57.143872 -290.951085) (xy 57.101251 -290.926478) (xy 57.06313 -290.895353) (xy 57.030495 -290.858516)
			(xy 57.004192 -290.81692) (xy 56.984901 -290.771644) (xy 56.973124 -290.72386) (xy 56.969164 -290.674806)
			(xy 56.630062 -290.674806) (xy 56.629567 -290.699413) (xy 56.621672 -290.74799) (xy 56.606088 -290.794671)
			(xy 56.583217 -290.838248) (xy 56.553652 -290.877592) (xy 56.518159 -290.911684) (xy 56.477656 -290.93964)
			(xy 56.433194 -290.960738) (xy 56.385923 -290.97443) (xy 56.337068 -290.980362) (xy 56.287893 -290.978381)
			(xy 56.239674 -290.968537) (xy 56.193658 -290.951085) (xy 56.151037 -290.926478) (xy 56.112916 -290.895353)
			(xy 56.080281 -290.858516) (xy 56.053978 -290.81692) (xy 56.034687 -290.771644) (xy 56.02291 -290.72386)
			(xy 56.01895 -290.674806) (xy 55.680102 -290.674806) (xy 55.679607 -290.699413) (xy 55.671712 -290.74799)
			(xy 55.656128 -290.794671) (xy 55.633257 -290.838248) (xy 55.603692 -290.877592) (xy 55.568199 -290.911684)
			(xy 55.527696 -290.93964) (xy 55.483234 -290.960738) (xy 55.435963 -290.97443) (xy 55.387108 -290.980362)
			(xy 55.337933 -290.978381) (xy 55.289714 -290.968537) (xy 55.243698 -290.951085) (xy 55.201077 -290.926478)
			(xy 55.162956 -290.895353) (xy 55.130321 -290.858516) (xy 55.104018 -290.81692) (xy 55.084727 -290.771644)
			(xy 55.07295 -290.72386) (xy 55.06899 -290.674806) (xy 54.730142 -290.674806) (xy 54.729647 -290.699413)
			(xy 54.721752 -290.74799) (xy 54.706168 -290.794671) (xy 54.683297 -290.838248) (xy 54.653732 -290.877592)
			(xy 54.618239 -290.911684) (xy 54.577736 -290.93964) (xy 54.533274 -290.960738) (xy 54.486003 -290.97443)
			(xy 54.437148 -290.980362) (xy 54.387973 -290.978381) (xy 54.339754 -290.968537) (xy 54.293738 -290.951085)
			(xy 54.251117 -290.926478) (xy 54.212996 -290.895353) (xy 54.180361 -290.858516) (xy 54.154058 -290.81692)
			(xy 54.134767 -290.771644) (xy 54.12299 -290.72386) (xy 54.11903 -290.674806) (xy 53.780182 -290.674806)
			(xy 53.779687 -290.699413) (xy 53.771792 -290.74799) (xy 53.756208 -290.794671) (xy 53.733337 -290.838248)
			(xy 53.703772 -290.877592) (xy 53.668279 -290.911684) (xy 53.627776 -290.93964) (xy 53.583314 -290.960738)
			(xy 53.536043 -290.97443) (xy 53.487188 -290.980362) (xy 53.438013 -290.978381) (xy 53.389794 -290.968537)
			(xy 53.343778 -290.951085) (xy 53.301157 -290.926478) (xy 53.263036 -290.895353) (xy 53.230401 -290.858516)
			(xy 53.204098 -290.81692) (xy 53.184807 -290.771644) (xy 53.17303 -290.72386) (xy 53.16907 -290.674806)
			(xy 52.830222 -290.674806) (xy 52.829727 -290.699413) (xy 52.821832 -290.74799) (xy 52.806248 -290.794671)
			(xy 52.783377 -290.838248) (xy 52.753812 -290.877592) (xy 52.718319 -290.911684) (xy 52.677816 -290.93964)
			(xy 52.633354 -290.960738) (xy 52.586083 -290.97443) (xy 52.537228 -290.980362) (xy 52.488053 -290.978381)
			(xy 52.439834 -290.968537) (xy 52.393818 -290.951085) (xy 52.351197 -290.926478) (xy 52.313076 -290.895353)
			(xy 52.280441 -290.858516) (xy 52.254138 -290.81692) (xy 52.234847 -290.771644) (xy 52.22307 -290.72386)
			(xy 52.21911 -290.674806) (xy 51.880262 -290.674806) (xy 51.879767 -290.699413) (xy 51.871872 -290.74799)
			(xy 51.856288 -290.794671) (xy 51.833417 -290.838248) (xy 51.803852 -290.877592) (xy 51.768359 -290.911684)
			(xy 51.727856 -290.93964) (xy 51.683394 -290.960738) (xy 51.636123 -290.97443) (xy 51.587268 -290.980362)
			(xy 51.538093 -290.978381) (xy 51.489874 -290.968537) (xy 51.443858 -290.951085) (xy 51.401237 -290.926478)
			(xy 51.363116 -290.895353) (xy 51.330481 -290.858516) (xy 51.304178 -290.81692) (xy 51.284887 -290.771644)
			(xy 51.27311 -290.72386) (xy 51.26915 -290.674806) (xy 50.930302 -290.674806) (xy 50.929807 -290.699413)
			(xy 50.921912 -290.74799) (xy 50.906328 -290.794671) (xy 50.883457 -290.838248) (xy 50.853892 -290.877592)
			(xy 50.818399 -290.911684) (xy 50.777896 -290.93964) (xy 50.733434 -290.960738) (xy 50.686163 -290.97443)
			(xy 50.637308 -290.980362) (xy 50.588133 -290.978381) (xy 50.539914 -290.968537) (xy 50.493898 -290.951085)
			(xy 50.451277 -290.926478) (xy 50.413156 -290.895353) (xy 50.380521 -290.858516) (xy 50.354218 -290.81692)
			(xy 50.334927 -290.771644) (xy 50.32315 -290.72386) (xy 50.31919 -290.674806) (xy 49.980088 -290.674806)
			(xy 49.979593 -290.699413) (xy 49.971698 -290.74799) (xy 49.956114 -290.794671) (xy 49.933243 -290.838248)
			(xy 49.903678 -290.877592) (xy 49.868185 -290.911684) (xy 49.827682 -290.93964) (xy 49.78322 -290.960738)
			(xy 49.735949 -290.97443) (xy 49.687094 -290.980362) (xy 49.637919 -290.978381) (xy 49.5897 -290.968537)
			(xy 49.543684 -290.951085) (xy 49.501063 -290.926478) (xy 49.462942 -290.895353) (xy 49.430307 -290.858516)
			(xy 49.404004 -290.81692) (xy 49.384713 -290.771644) (xy 49.372936 -290.72386) (xy 49.368976 -290.674806)
			(xy 49.030128 -290.674806) (xy 49.029633 -290.699413) (xy 49.021738 -290.74799) (xy 49.006154 -290.794671)
			(xy 48.983283 -290.838248) (xy 48.953718 -290.877592) (xy 48.918225 -290.911684) (xy 48.877722 -290.93964)
			(xy 48.83326 -290.960738) (xy 48.785989 -290.97443) (xy 48.737134 -290.980362) (xy 48.687959 -290.978381)
			(xy 48.63974 -290.968537) (xy 48.593724 -290.951085) (xy 48.551103 -290.926478) (xy 48.512982 -290.895353)
			(xy 48.480347 -290.858516) (xy 48.454044 -290.81692) (xy 48.434753 -290.771644) (xy 48.422976 -290.72386)
			(xy 48.419016 -290.674806) (xy 48.080168 -290.674806) (xy 48.079673 -290.699413) (xy 48.071778 -290.74799)
			(xy 48.056194 -290.794671) (xy 48.033323 -290.838248) (xy 48.003758 -290.877592) (xy 47.968265 -290.911684)
			(xy 47.927762 -290.93964) (xy 47.8833 -290.960738) (xy 47.836029 -290.97443) (xy 47.787174 -290.980362)
			(xy 47.737999 -290.978381) (xy 47.68978 -290.968537) (xy 47.643764 -290.951085) (xy 47.601143 -290.926478)
			(xy 47.563022 -290.895353) (xy 47.530387 -290.858516) (xy 47.504084 -290.81692) (xy 47.484793 -290.771644)
			(xy 47.473016 -290.72386) (xy 47.469056 -290.674806) (xy 47.130208 -290.674806) (xy 47.129713 -290.699413)
			(xy 47.121818 -290.74799) (xy 47.106234 -290.794671) (xy 47.083363 -290.838248) (xy 47.053798 -290.877592)
			(xy 47.018305 -290.911684) (xy 46.977802 -290.93964) (xy 46.93334 -290.960738) (xy 46.886069 -290.97443)
			(xy 46.837214 -290.980362) (xy 46.788039 -290.978381) (xy 46.73982 -290.968537) (xy 46.693804 -290.951085)
			(xy 46.651183 -290.926478) (xy 46.613062 -290.895353) (xy 46.580427 -290.858516) (xy 46.554124 -290.81692)
			(xy 46.534833 -290.771644) (xy 46.523056 -290.72386) (xy 46.519096 -290.674806) (xy 46.180248 -290.674806)
			(xy 46.179753 -290.699413) (xy 46.171858 -290.74799) (xy 46.156274 -290.794671) (xy 46.133403 -290.838248)
			(xy 46.103838 -290.877592) (xy 46.068345 -290.911684) (xy 46.027842 -290.93964) (xy 45.98338 -290.960738)
			(xy 45.936109 -290.97443) (xy 45.887254 -290.980362) (xy 45.838079 -290.978381) (xy 45.78986 -290.968537)
			(xy 45.743844 -290.951085) (xy 45.701223 -290.926478) (xy 45.663102 -290.895353) (xy 45.630467 -290.858516)
			(xy 45.604164 -290.81692) (xy 45.584873 -290.771644) (xy 45.573096 -290.72386) (xy 45.569136 -290.674806)
			(xy 45.230288 -290.674806) (xy 45.229793 -290.699413) (xy 45.221898 -290.74799) (xy 45.206314 -290.794671)
			(xy 45.183443 -290.838248) (xy 45.153878 -290.877592) (xy 45.118385 -290.911684) (xy 45.077882 -290.93964)
			(xy 45.03342 -290.960738) (xy 44.986149 -290.97443) (xy 44.937294 -290.980362) (xy 44.888119 -290.978381)
			(xy 44.8399 -290.968537) (xy 44.793884 -290.951085) (xy 44.751263 -290.926478) (xy 44.713142 -290.895353)
			(xy 44.680507 -290.858516) (xy 44.654204 -290.81692) (xy 44.634913 -290.771644) (xy 44.623136 -290.72386)
			(xy 44.619176 -290.674806) (xy 44.280074 -290.674806) (xy 44.279579 -290.699413) (xy 44.271684 -290.74799)
			(xy 44.2561 -290.794671) (xy 44.233229 -290.838248) (xy 44.203664 -290.877592) (xy 44.168171 -290.911684)
			(xy 44.127668 -290.93964) (xy 44.083206 -290.960738) (xy 44.035935 -290.97443) (xy 43.98708 -290.980362)
			(xy 43.937905 -290.978381) (xy 43.889686 -290.968537) (xy 43.84367 -290.951085) (xy 43.801049 -290.926478)
			(xy 43.762928 -290.895353) (xy 43.730293 -290.858516) (xy 43.70399 -290.81692) (xy 43.684699 -290.771644)
			(xy 43.672922 -290.72386) (xy 43.668962 -290.674806) (xy 43.330114 -290.674806) (xy 43.329619 -290.699413)
			(xy 43.321724 -290.74799) (xy 43.30614 -290.794671) (xy 43.283269 -290.838248) (xy 43.253704 -290.877592)
			(xy 43.218211 -290.911684) (xy 43.177708 -290.93964) (xy 43.133246 -290.960738) (xy 43.085975 -290.97443)
			(xy 43.03712 -290.980362) (xy 42.987945 -290.978381) (xy 42.939726 -290.968537) (xy 42.89371 -290.951085)
			(xy 42.851089 -290.926478) (xy 42.812968 -290.895353) (xy 42.780333 -290.858516) (xy 42.75403 -290.81692)
			(xy 42.734739 -290.771644) (xy 42.722962 -290.72386) (xy 42.719002 -290.674806) (xy 42.380154 -290.674806)
			(xy 42.379659 -290.699413) (xy 42.371764 -290.74799) (xy 42.35618 -290.794671) (xy 42.333309 -290.838248)
			(xy 42.303744 -290.877592) (xy 42.268251 -290.911684) (xy 42.227748 -290.93964) (xy 42.183286 -290.960738)
			(xy 42.136015 -290.97443) (xy 42.08716 -290.980362) (xy 42.037985 -290.978381) (xy 41.989766 -290.968537)
			(xy 41.94375 -290.951085) (xy 41.901129 -290.926478) (xy 41.863008 -290.895353) (xy 41.830373 -290.858516)
			(xy 41.80407 -290.81692) (xy 41.784779 -290.771644) (xy 41.773002 -290.72386) (xy 41.769042 -290.674806)
			(xy 41.430194 -290.674806) (xy 41.429699 -290.699413) (xy 41.421804 -290.74799) (xy 41.40622 -290.794671)
			(xy 41.383349 -290.838248) (xy 41.353784 -290.877592) (xy 41.318291 -290.911684) (xy 41.277788 -290.93964)
			(xy 41.233326 -290.960738) (xy 41.186055 -290.97443) (xy 41.1372 -290.980362) (xy 41.088025 -290.978381)
			(xy 41.039806 -290.968537) (xy 40.99379 -290.951085) (xy 40.951169 -290.926478) (xy 40.913048 -290.895353)
			(xy 40.880413 -290.858516) (xy 40.85411 -290.81692) (xy 40.834819 -290.771644) (xy 40.823042 -290.72386)
			(xy 40.819082 -290.674806) (xy 38.580314 -290.674806) (xy 38.579819 -290.699413) (xy 38.571924 -290.74799)
			(xy 38.55634 -290.794671) (xy 38.533469 -290.838248) (xy 38.503904 -290.877592) (xy 38.468411 -290.911684)
			(xy 38.427908 -290.93964) (xy 38.383446 -290.960738) (xy 38.336175 -290.97443) (xy 38.28732 -290.980362)
			(xy 38.238145 -290.978381) (xy 38.189926 -290.968537) (xy 38.14391 -290.951085) (xy 38.101289 -290.926478)
			(xy 38.063168 -290.895353) (xy 38.030533 -290.858516) (xy 38.00423 -290.81692) (xy 37.984939 -290.771644)
			(xy 37.973162 -290.72386) (xy 37.969202 -290.674806) (xy 37.6301 -290.674806) (xy 37.629646 -290.69856)
			(xy 37.622274 -290.745492) (xy 37.60771 -290.790713) (xy 37.586306 -290.833126) (xy 37.55858 -290.871704)
			(xy 37.542216 -290.888928) (xy 37.536169 -290.895522) (xy 37.528747 -290.911788) (xy 37.527738 -290.920678)
			(xy 37.525452 -290.951666) (xy 37.525078 -290.960586) (xy 37.5299 -290.977764) (xy 37.53485 -290.985194)
			(xy 37.548249 -291.004637) (xy 37.569458 -291.046824) (xy 37.583921 -291.091773) (xy 37.591292 -291.138412)
			(xy 37.591397 -291.185631) (xy 37.584233 -291.232302) (xy 37.577522 -291.254942) (xy 37.552884 -291.33292)
			(xy 37.550423 -291.34188) (xy 37.551473 -291.36042) (xy 37.559056 -291.377371) (xy 37.56533 -291.384228)
			(xy 37.572146 -291.390552) (xy 37.589113 -291.398129) (xy 37.607668 -291.399132) (xy 37.616638 -291.396674)
			(xy 37.763196 -291.350446) (xy 37.76997 -291.348571) (xy 37.784015 -291.348183) (xy 37.790882 -291.349684)
			(xy 37.94252 -291.38753) (xy 37.9476 -291.39261) (xy 37.964872 -291.40023) (xy 38.043104 -291.403532)
			(xy 38.052645 -291.403497) (xy 38.070653 -291.397234) (xy 38.078156 -291.39134) (xy 38.098977 -291.374524)
			(xy 38.14528 -291.34769) (xy 38.195549 -291.329333) (xy 38.248248 -291.320012) (xy 38.275006 -291.319458)
			(xy 38.298996 -291.319957) (xy 38.346384 -291.327463) (xy 38.392016 -291.342289) (xy 38.434766 -291.36407)
			(xy 38.473583 -291.392271) (xy 38.507511 -291.426196) (xy 38.535715 -291.46501) (xy 38.5575 -291.507759)
			(xy 38.572331 -291.553388) (xy 38.579841 -291.600776) (xy 38.580314 -291.624766) (xy 40.819082 -291.624766)
			(xy 40.823042 -291.575712) (xy 40.834819 -291.527928) (xy 40.85411 -291.482652) (xy 40.880413 -291.441056)
			(xy 40.913048 -291.404219) (xy 40.951169 -291.373094) (xy 40.99379 -291.348487) (xy 41.039806 -291.331035)
			(xy 41.088025 -291.321191) (xy 41.1372 -291.31921) (xy 41.186055 -291.325142) (xy 41.233326 -291.338834)
			(xy 41.277788 -291.359932) (xy 41.318291 -291.387888) (xy 41.353784 -291.42198) (xy 41.383349 -291.461324)
			(xy 41.40622 -291.504901) (xy 41.421804 -291.551582) (xy 41.429699 -291.600159) (xy 41.430194 -291.624766)
			(xy 41.769042 -291.624766) (xy 41.773002 -291.575712) (xy 41.784779 -291.527928) (xy 41.80407 -291.482652)
			(xy 41.830373 -291.441056) (xy 41.863008 -291.404219) (xy 41.901129 -291.373094) (xy 41.94375 -291.348487)
			(xy 41.989766 -291.331035) (xy 42.037985 -291.321191) (xy 42.08716 -291.31921) (xy 42.136015 -291.325142)
			(xy 42.183286 -291.338834) (xy 42.227748 -291.359932) (xy 42.268251 -291.387888) (xy 42.303744 -291.42198)
			(xy 42.333309 -291.461324) (xy 42.35618 -291.504901) (xy 42.371764 -291.551582) (xy 42.379659 -291.600159)
			(xy 42.380154 -291.624766) (xy 42.719002 -291.624766) (xy 42.722962 -291.575712) (xy 42.734739 -291.527928)
			(xy 42.75403 -291.482652) (xy 42.780333 -291.441056) (xy 42.812968 -291.404219) (xy 42.851089 -291.373094)
			(xy 42.89371 -291.348487) (xy 42.939726 -291.331035) (xy 42.987945 -291.321191) (xy 43.03712 -291.31921)
			(xy 43.085975 -291.325142) (xy 43.133246 -291.338834) (xy 43.177708 -291.359932) (xy 43.218211 -291.387888)
			(xy 43.253704 -291.42198) (xy 43.283269 -291.461324) (xy 43.30614 -291.504901) (xy 43.321724 -291.551582)
			(xy 43.329619 -291.600159) (xy 43.330114 -291.624766) (xy 43.668962 -291.624766) (xy 43.672922 -291.575712)
			(xy 43.684699 -291.527928) (xy 43.70399 -291.482652) (xy 43.730293 -291.441056) (xy 43.762928 -291.404219)
			(xy 43.801049 -291.373094) (xy 43.84367 -291.348487) (xy 43.889686 -291.331035) (xy 43.937905 -291.321191)
			(xy 43.98708 -291.31921) (xy 44.035935 -291.325142) (xy 44.083206 -291.338834) (xy 44.127668 -291.359932)
			(xy 44.168171 -291.387888) (xy 44.203664 -291.42198) (xy 44.233229 -291.461324) (xy 44.2561 -291.504901)
			(xy 44.271684 -291.551582) (xy 44.279579 -291.600159) (xy 44.280074 -291.624766) (xy 44.619176 -291.624766)
			(xy 44.623136 -291.575712) (xy 44.634913 -291.527928) (xy 44.654204 -291.482652) (xy 44.680507 -291.441056)
			(xy 44.713142 -291.404219) (xy 44.751263 -291.373094) (xy 44.793884 -291.348487) (xy 44.8399 -291.331035)
			(xy 44.888119 -291.321191) (xy 44.937294 -291.31921) (xy 44.986149 -291.325142) (xy 45.03342 -291.338834)
			(xy 45.077882 -291.359932) (xy 45.118385 -291.387888) (xy 45.153878 -291.42198) (xy 45.183443 -291.461324)
			(xy 45.206314 -291.504901) (xy 45.221898 -291.551582) (xy 45.229793 -291.600159) (xy 45.230288 -291.624766)
			(xy 45.569136 -291.624766) (xy 45.573096 -291.575712) (xy 45.584873 -291.527928) (xy 45.604164 -291.482652)
			(xy 45.630467 -291.441056) (xy 45.663102 -291.404219) (xy 45.701223 -291.373094) (xy 45.743844 -291.348487)
			(xy 45.78986 -291.331035) (xy 45.838079 -291.321191) (xy 45.887254 -291.31921) (xy 45.936109 -291.325142)
			(xy 45.98338 -291.338834) (xy 46.027842 -291.359932) (xy 46.068345 -291.387888) (xy 46.103838 -291.42198)
			(xy 46.133403 -291.461324) (xy 46.156274 -291.504901) (xy 46.171858 -291.551582) (xy 46.179753 -291.600159)
			(xy 46.180248 -291.624766) (xy 47.469056 -291.624766) (xy 47.473016 -291.575712) (xy 47.484793 -291.527928)
			(xy 47.504084 -291.482652) (xy 47.530387 -291.441056) (xy 47.563022 -291.404219) (xy 47.601143 -291.373094)
			(xy 47.643764 -291.348487) (xy 47.68978 -291.331035) (xy 47.737999 -291.321191) (xy 47.787174 -291.31921)
			(xy 47.836029 -291.325142) (xy 47.8833 -291.338834) (xy 47.927762 -291.359932) (xy 47.968265 -291.387888)
			(xy 48.003758 -291.42198) (xy 48.033323 -291.461324) (xy 48.056194 -291.504901) (xy 48.071778 -291.551582)
			(xy 48.079673 -291.600159) (xy 48.080168 -291.624766) (xy 48.419016 -291.624766) (xy 48.422976 -291.575712)
			(xy 48.434753 -291.527928) (xy 48.454044 -291.482652) (xy 48.480347 -291.441056) (xy 48.512982 -291.404219)
			(xy 48.551103 -291.373094) (xy 48.593724 -291.348487) (xy 48.63974 -291.331035) (xy 48.687959 -291.321191)
			(xy 48.737134 -291.31921) (xy 48.785989 -291.325142) (xy 48.83326 -291.338834) (xy 48.877722 -291.359932)
			(xy 48.918225 -291.387888) (xy 48.953718 -291.42198) (xy 48.983283 -291.461324) (xy 49.006154 -291.504901)
			(xy 49.021738 -291.551582) (xy 49.029633 -291.600159) (xy 49.030128 -291.624766) (xy 49.368976 -291.624766)
			(xy 49.372936 -291.575712) (xy 49.384713 -291.527928) (xy 49.404004 -291.482652) (xy 49.430307 -291.441056)
			(xy 49.462942 -291.404219) (xy 49.501063 -291.373094) (xy 49.543684 -291.348487) (xy 49.5897 -291.331035)
			(xy 49.637919 -291.321191) (xy 49.687094 -291.31921) (xy 49.735949 -291.325142) (xy 49.78322 -291.338834)
			(xy 49.827682 -291.359932) (xy 49.868185 -291.387888) (xy 49.903678 -291.42198) (xy 49.933243 -291.461324)
			(xy 49.956114 -291.504901) (xy 49.971698 -291.551582) (xy 49.979593 -291.600159) (xy 49.980088 -291.624766)
			(xy 50.31919 -291.624766) (xy 50.32315 -291.575712) (xy 50.334927 -291.527928) (xy 50.354218 -291.482652)
			(xy 50.380521 -291.441056) (xy 50.413156 -291.404219) (xy 50.451277 -291.373094) (xy 50.493898 -291.348487)
			(xy 50.539914 -291.331035) (xy 50.588133 -291.321191) (xy 50.637308 -291.31921) (xy 50.686163 -291.325142)
			(xy 50.733434 -291.338834) (xy 50.777896 -291.359932) (xy 50.818399 -291.387888) (xy 50.853892 -291.42198)
			(xy 50.883457 -291.461324) (xy 50.906328 -291.504901) (xy 50.921912 -291.551582) (xy 50.929807 -291.600159)
			(xy 50.930302 -291.624766) (xy 51.26915 -291.624766) (xy 51.27311 -291.575712) (xy 51.284887 -291.527928)
			(xy 51.304178 -291.482652) (xy 51.330481 -291.441056) (xy 51.363116 -291.404219) (xy 51.401237 -291.373094)
			(xy 51.443858 -291.348487) (xy 51.489874 -291.331035) (xy 51.538093 -291.321191) (xy 51.587268 -291.31921)
			(xy 51.636123 -291.325142) (xy 51.683394 -291.338834) (xy 51.727856 -291.359932) (xy 51.768359 -291.387888)
			(xy 51.803852 -291.42198) (xy 51.833417 -291.461324) (xy 51.856288 -291.504901) (xy 51.871872 -291.551582)
			(xy 51.879767 -291.600159) (xy 51.880262 -291.624766) (xy 52.21911 -291.624766) (xy 52.22307 -291.575712)
			(xy 52.234847 -291.527928) (xy 52.254138 -291.482652) (xy 52.280441 -291.441056) (xy 52.313076 -291.404219)
			(xy 52.351197 -291.373094) (xy 52.393818 -291.348487) (xy 52.439834 -291.331035) (xy 52.488053 -291.321191)
			(xy 52.537228 -291.31921) (xy 52.586083 -291.325142) (xy 52.633354 -291.338834) (xy 52.677816 -291.359932)
			(xy 52.718319 -291.387888) (xy 52.753812 -291.42198) (xy 52.783377 -291.461324) (xy 52.806248 -291.504901)
			(xy 52.821832 -291.551582) (xy 52.829727 -291.600159) (xy 52.830222 -291.624766) (xy 53.16907 -291.624766)
			(xy 53.17303 -291.575712) (xy 53.184807 -291.527928) (xy 53.204098 -291.482652) (xy 53.230401 -291.441056)
			(xy 53.263036 -291.404219) (xy 53.301157 -291.373094) (xy 53.343778 -291.348487) (xy 53.389794 -291.331035)
			(xy 53.438013 -291.321191) (xy 53.487188 -291.31921) (xy 53.536043 -291.325142) (xy 53.583314 -291.338834)
			(xy 53.627776 -291.359932) (xy 53.668279 -291.387888) (xy 53.703772 -291.42198) (xy 53.733337 -291.461324)
			(xy 53.756208 -291.504901) (xy 53.771792 -291.551582) (xy 53.779687 -291.600159) (xy 53.780182 -291.624766)
			(xy 54.11903 -291.624766) (xy 54.12299 -291.575712) (xy 54.134767 -291.527928) (xy 54.154058 -291.482652)
			(xy 54.180361 -291.441056) (xy 54.212996 -291.404219) (xy 54.251117 -291.373094) (xy 54.293738 -291.348487)
			(xy 54.339754 -291.331035) (xy 54.387973 -291.321191) (xy 54.437148 -291.31921) (xy 54.486003 -291.325142)
			(xy 54.533274 -291.338834) (xy 54.577736 -291.359932) (xy 54.618239 -291.387888) (xy 54.653732 -291.42198)
			(xy 54.683297 -291.461324) (xy 54.706168 -291.504901) (xy 54.721752 -291.551582) (xy 54.729647 -291.600159)
			(xy 54.730142 -291.624766) (xy 55.06899 -291.624766) (xy 55.07295 -291.575712) (xy 55.084727 -291.527928)
			(xy 55.104018 -291.482652) (xy 55.130321 -291.441056) (xy 55.162956 -291.404219) (xy 55.201077 -291.373094)
			(xy 55.243698 -291.348487) (xy 55.289714 -291.331035) (xy 55.337933 -291.321191) (xy 55.387108 -291.31921)
			(xy 55.435963 -291.325142) (xy 55.483234 -291.338834) (xy 55.527696 -291.359932) (xy 55.568199 -291.387888)
			(xy 55.603692 -291.42198) (xy 55.633257 -291.461324) (xy 55.656128 -291.504901) (xy 55.671712 -291.551582)
			(xy 55.679607 -291.600159) (xy 55.680102 -291.624766) (xy 56.01895 -291.624766) (xy 56.02291 -291.575712)
			(xy 56.034687 -291.527928) (xy 56.053978 -291.482652) (xy 56.080281 -291.441056) (xy 56.112916 -291.404219)
			(xy 56.151037 -291.373094) (xy 56.193658 -291.348487) (xy 56.239674 -291.331035) (xy 56.287893 -291.321191)
			(xy 56.337068 -291.31921) (xy 56.385923 -291.325142) (xy 56.433194 -291.338834) (xy 56.477656 -291.359932)
			(xy 56.518159 -291.387888) (xy 56.553652 -291.42198) (xy 56.583217 -291.461324) (xy 56.606088 -291.504901)
			(xy 56.621672 -291.551582) (xy 56.629567 -291.600159) (xy 56.630062 -291.624766) (xy 56.969164 -291.624766)
			(xy 56.973124 -291.575712) (xy 56.984901 -291.527928) (xy 57.004192 -291.482652) (xy 57.030495 -291.441056)
			(xy 57.06313 -291.404219) (xy 57.101251 -291.373094) (xy 57.143872 -291.348487) (xy 57.189888 -291.331035)
			(xy 57.238107 -291.321191) (xy 57.287282 -291.31921) (xy 57.336137 -291.325142) (xy 57.383408 -291.338834)
			(xy 57.42787 -291.359932) (xy 57.468373 -291.387888) (xy 57.503866 -291.42198) (xy 57.533431 -291.461324)
			(xy 57.556302 -291.504901) (xy 57.571886 -291.551582) (xy 57.579781 -291.600159) (xy 57.580276 -291.624766)
			(xy 57.919124 -291.624766) (xy 57.923084 -291.575712) (xy 57.934861 -291.527928) (xy 57.954152 -291.482652)
			(xy 57.980455 -291.441056) (xy 58.01309 -291.404219) (xy 58.051211 -291.373094) (xy 58.093832 -291.348487)
			(xy 58.139848 -291.331035) (xy 58.188067 -291.321191) (xy 58.237242 -291.31921) (xy 58.286097 -291.325142)
			(xy 58.333368 -291.338834) (xy 58.37783 -291.359932) (xy 58.418333 -291.387888) (xy 58.453826 -291.42198)
			(xy 58.483391 -291.461324) (xy 58.506262 -291.504901) (xy 58.521846 -291.551582) (xy 58.529741 -291.600159)
			(xy 58.530236 -291.624766) (xy 59.819044 -291.624766) (xy 59.823004 -291.575712) (xy 59.834781 -291.527928)
			(xy 59.854072 -291.482652) (xy 59.880375 -291.441056) (xy 59.91301 -291.404219) (xy 59.951131 -291.373094)
			(xy 59.993752 -291.348487) (xy 60.039768 -291.331035) (xy 60.087987 -291.321191) (xy 60.137162 -291.31921)
			(xy 60.186017 -291.325142) (xy 60.233288 -291.338834) (xy 60.27775 -291.359932) (xy 60.318253 -291.387888)
			(xy 60.353746 -291.42198) (xy 60.383311 -291.461324) (xy 60.406182 -291.504901) (xy 60.421766 -291.551582)
			(xy 60.429661 -291.600159) (xy 60.430156 -291.624766) (xy 60.769004 -291.624766) (xy 60.772964 -291.575712)
			(xy 60.784741 -291.527928) (xy 60.804032 -291.482652) (xy 60.830335 -291.441056) (xy 60.86297 -291.404219)
			(xy 60.901091 -291.373094) (xy 60.943712 -291.348487) (xy 60.989728 -291.331035) (xy 61.037947 -291.321191)
			(xy 61.087122 -291.31921) (xy 61.135977 -291.325142) (xy 61.183248 -291.338834) (xy 61.22771 -291.359932)
			(xy 61.268213 -291.387888) (xy 61.303706 -291.42198) (xy 61.333271 -291.461324) (xy 61.356142 -291.504901)
			(xy 61.371726 -291.551582) (xy 61.379621 -291.600159) (xy 61.380116 -291.624766) (xy 61.718964 -291.624766)
			(xy 61.722924 -291.575712) (xy 61.734701 -291.527928) (xy 61.753992 -291.482652) (xy 61.780295 -291.441056)
			(xy 61.81293 -291.404219) (xy 61.851051 -291.373094) (xy 61.893672 -291.348487) (xy 61.939688 -291.331035)
			(xy 61.987907 -291.321191) (xy 62.037082 -291.31921) (xy 62.085937 -291.325142) (xy 62.133208 -291.338834)
			(xy 62.17767 -291.359932) (xy 62.218173 -291.387888) (xy 62.253666 -291.42198) (xy 62.283231 -291.461324)
			(xy 62.306102 -291.504901) (xy 62.321686 -291.551582) (xy 62.329581 -291.600159) (xy 62.330076 -291.624766)
			(xy 62.669178 -291.624766) (xy 62.673138 -291.575712) (xy 62.684915 -291.527928) (xy 62.704206 -291.482652)
			(xy 62.730509 -291.441056) (xy 62.763144 -291.404219) (xy 62.801265 -291.373094) (xy 62.843886 -291.348487)
			(xy 62.889902 -291.331035) (xy 62.938121 -291.321191) (xy 62.987296 -291.31921) (xy 63.036151 -291.325142)
			(xy 63.083422 -291.338834) (xy 63.127884 -291.359932) (xy 63.168387 -291.387888) (xy 63.20388 -291.42198)
			(xy 63.233445 -291.461324) (xy 63.256316 -291.504901) (xy 63.2719 -291.551582) (xy 63.279795 -291.600159)
			(xy 63.28029 -291.624766) (xy 63.619138 -291.624766) (xy 63.623098 -291.575712) (xy 63.634875 -291.527928)
			(xy 63.654166 -291.482652) (xy 63.680469 -291.441056) (xy 63.713104 -291.404219) (xy 63.751225 -291.373094)
			(xy 63.793846 -291.348487) (xy 63.839862 -291.331035) (xy 63.888081 -291.321191) (xy 63.937256 -291.31921)
			(xy 63.986111 -291.325142) (xy 64.033382 -291.338834) (xy 64.077844 -291.359932) (xy 64.118347 -291.387888)
			(xy 64.15384 -291.42198) (xy 64.183405 -291.461324) (xy 64.206276 -291.504901) (xy 64.22186 -291.551582)
			(xy 64.229755 -291.600159) (xy 64.23025 -291.624766) (xy 64.569098 -291.624766) (xy 64.573058 -291.575712)
			(xy 64.584835 -291.527928) (xy 64.604126 -291.482652) (xy 64.630429 -291.441056) (xy 64.663064 -291.404219)
			(xy 64.701185 -291.373094) (xy 64.743806 -291.348487) (xy 64.789822 -291.331035) (xy 64.838041 -291.321191)
			(xy 64.887216 -291.31921) (xy 64.936071 -291.325142) (xy 64.983342 -291.338834) (xy 65.027804 -291.359932)
			(xy 65.068307 -291.387888) (xy 65.1038 -291.42198) (xy 65.133365 -291.461324) (xy 65.156236 -291.504901)
			(xy 65.17182 -291.551582) (xy 65.179715 -291.600159) (xy 65.18021 -291.624766) (xy 65.519058 -291.624766)
			(xy 65.523018 -291.575712) (xy 65.534795 -291.527928) (xy 65.554086 -291.482652) (xy 65.580389 -291.441056)
			(xy 65.613024 -291.404219) (xy 65.651145 -291.373094) (xy 65.693766 -291.348487) (xy 65.739782 -291.331035)
			(xy 65.788001 -291.321191) (xy 65.837176 -291.31921) (xy 65.886031 -291.325142) (xy 65.933302 -291.338834)
			(xy 65.977764 -291.359932) (xy 66.018267 -291.387888) (xy 66.05376 -291.42198) (xy 66.083325 -291.461324)
			(xy 66.106196 -291.504901) (xy 66.12178 -291.551582) (xy 66.129675 -291.600159) (xy 66.13017 -291.624766)
			(xy 66.469018 -291.624766) (xy 66.472978 -291.575712) (xy 66.484755 -291.527928) (xy 66.504046 -291.482652)
			(xy 66.530349 -291.441056) (xy 66.562984 -291.404219) (xy 66.601105 -291.373094) (xy 66.643726 -291.348487)
			(xy 66.689742 -291.331035) (xy 66.737961 -291.321191) (xy 66.787136 -291.31921) (xy 66.835991 -291.325142)
			(xy 66.883262 -291.338834) (xy 66.927724 -291.359932) (xy 66.968227 -291.387888) (xy 67.00372 -291.42198)
			(xy 67.033285 -291.461324) (xy 67.056156 -291.504901) (xy 67.07174 -291.551582) (xy 67.079635 -291.600159)
			(xy 67.08013 -291.624766) (xy 67.418978 -291.624766) (xy 67.422938 -291.575712) (xy 67.434715 -291.527928)
			(xy 67.454006 -291.482652) (xy 67.480309 -291.441056) (xy 67.512944 -291.404219) (xy 67.551065 -291.373094)
			(xy 67.593686 -291.348487) (xy 67.639702 -291.331035) (xy 67.687921 -291.321191) (xy 67.737096 -291.31921)
			(xy 67.785951 -291.325142) (xy 67.833222 -291.338834) (xy 67.877684 -291.359932) (xy 67.918187 -291.387888)
			(xy 67.95368 -291.42198) (xy 67.983245 -291.461324) (xy 68.006116 -291.504901) (xy 68.0217 -291.551582)
			(xy 68.029595 -291.600159) (xy 68.03009 -291.624766) (xy 68.368938 -291.624766) (xy 68.372898 -291.575712)
			(xy 68.384675 -291.527928) (xy 68.403966 -291.482652) (xy 68.430269 -291.441056) (xy 68.462904 -291.404219)
			(xy 68.501025 -291.373094) (xy 68.543646 -291.348487) (xy 68.589662 -291.331035) (xy 68.637881 -291.321191)
			(xy 68.687056 -291.31921) (xy 68.735911 -291.325142) (xy 68.783182 -291.338834) (xy 68.827644 -291.359932)
			(xy 68.868147 -291.387888) (xy 68.90364 -291.42198) (xy 68.933205 -291.461324) (xy 68.956076 -291.504901)
			(xy 68.97166 -291.551582) (xy 68.979555 -291.600159) (xy 68.98005 -291.624766) (xy 69.319152 -291.624766)
			(xy 69.323112 -291.575712) (xy 69.334889 -291.527928) (xy 69.35418 -291.482652) (xy 69.380483 -291.441056)
			(xy 69.413118 -291.404219) (xy 69.451239 -291.373094) (xy 69.49386 -291.348487) (xy 69.539876 -291.331035)
			(xy 69.588095 -291.321191) (xy 69.63727 -291.31921) (xy 69.686125 -291.325142) (xy 69.733396 -291.338834)
			(xy 69.777858 -291.359932) (xy 69.818361 -291.387888) (xy 69.853854 -291.42198) (xy 69.883419 -291.461324)
			(xy 69.90629 -291.504901) (xy 69.921874 -291.551582) (xy 69.929769 -291.600159) (xy 69.930264 -291.624766)
			(xy 70.269112 -291.624766) (xy 70.273072 -291.575712) (xy 70.284849 -291.527928) (xy 70.30414 -291.482652)
			(xy 70.330443 -291.441056) (xy 70.363078 -291.404219) (xy 70.401199 -291.373094) (xy 70.44382 -291.348487)
			(xy 70.489836 -291.331035) (xy 70.538055 -291.321191) (xy 70.58723 -291.31921) (xy 70.636085 -291.325142)
			(xy 70.683356 -291.338834) (xy 70.727818 -291.359932) (xy 70.768321 -291.387888) (xy 70.803814 -291.42198)
			(xy 70.833379 -291.461324) (xy 70.85625 -291.504901) (xy 70.871834 -291.551582) (xy 70.879729 -291.600159)
			(xy 70.880224 -291.624766) (xy 71.219072 -291.624766) (xy 71.223032 -291.575712) (xy 71.234809 -291.527928)
			(xy 71.2541 -291.482652) (xy 71.280403 -291.441056) (xy 71.313038 -291.404219) (xy 71.351159 -291.373094)
			(xy 71.39378 -291.348487) (xy 71.439796 -291.331035) (xy 71.488015 -291.321191) (xy 71.53719 -291.31921)
			(xy 71.586045 -291.325142) (xy 71.633316 -291.338834) (xy 71.677778 -291.359932) (xy 71.718281 -291.387888)
			(xy 71.753774 -291.42198) (xy 71.783339 -291.461324) (xy 71.80621 -291.504901) (xy 71.821794 -291.551582)
			(xy 71.829689 -291.600159) (xy 71.830184 -291.624766) (xy 72.169032 -291.624766) (xy 72.172992 -291.575712)
			(xy 72.184769 -291.527928) (xy 72.20406 -291.482652) (xy 72.230363 -291.441056) (xy 72.262998 -291.404219)
			(xy 72.301119 -291.373094) (xy 72.34374 -291.348487) (xy 72.389756 -291.331035) (xy 72.437975 -291.321191)
			(xy 72.48715 -291.31921) (xy 72.536005 -291.325142) (xy 72.583276 -291.338834) (xy 72.627738 -291.359932)
			(xy 72.668241 -291.387888) (xy 72.703734 -291.42198) (xy 72.733299 -291.461324) (xy 72.75617 -291.504901)
			(xy 72.771754 -291.551582) (xy 72.779649 -291.600159) (xy 72.780144 -291.624766) (xy 73.118992 -291.624766)
			(xy 73.122952 -291.575712) (xy 73.134729 -291.527928) (xy 73.15402 -291.482652) (xy 73.180323 -291.441056)
			(xy 73.212958 -291.404219) (xy 73.251079 -291.373094) (xy 73.2937 -291.348487) (xy 73.339716 -291.331035)
			(xy 73.387935 -291.321191) (xy 73.43711 -291.31921) (xy 73.485965 -291.325142) (xy 73.533236 -291.338834)
			(xy 73.577698 -291.359932) (xy 73.618201 -291.387888) (xy 73.653694 -291.42198) (xy 73.683259 -291.461324)
			(xy 73.70613 -291.504901) (xy 73.721714 -291.551582) (xy 73.729609 -291.600159) (xy 73.730104 -291.624766)
			(xy 74.069206 -291.624766) (xy 74.073166 -291.575712) (xy 74.084943 -291.527928) (xy 74.104234 -291.482652)
			(xy 74.130537 -291.441056) (xy 74.163172 -291.404219) (xy 74.201293 -291.373094) (xy 74.243914 -291.348487)
			(xy 74.28993 -291.331035) (xy 74.338149 -291.321191) (xy 74.387324 -291.31921) (xy 74.436179 -291.325142)
			(xy 74.48345 -291.338834) (xy 74.527912 -291.359932) (xy 74.568415 -291.387888) (xy 74.603908 -291.42198)
			(xy 74.633473 -291.461324) (xy 74.656344 -291.504901) (xy 74.671928 -291.551582) (xy 74.679823 -291.600159)
			(xy 74.680318 -291.624766) (xy 75.969126 -291.624766) (xy 75.973086 -291.575712) (xy 75.984863 -291.527928)
			(xy 76.004154 -291.482652) (xy 76.030457 -291.441056) (xy 76.063092 -291.404219) (xy 76.101213 -291.373094)
			(xy 76.143834 -291.348487) (xy 76.18985 -291.331035) (xy 76.238069 -291.321191) (xy 76.287244 -291.31921)
			(xy 76.336099 -291.325142) (xy 76.38337 -291.338834) (xy 76.427832 -291.359932) (xy 76.468335 -291.387888)
			(xy 76.503828 -291.42198) (xy 76.533393 -291.461324) (xy 76.556264 -291.504901) (xy 76.571848 -291.551582)
			(xy 76.579743 -291.600159) (xy 76.580238 -291.624766) (xy 76.919086 -291.624766) (xy 76.923046 -291.575712)
			(xy 76.934823 -291.527928) (xy 76.954114 -291.482652) (xy 76.980417 -291.441056) (xy 77.013052 -291.404219)
			(xy 77.051173 -291.373094) (xy 77.093794 -291.348487) (xy 77.13981 -291.331035) (xy 77.188029 -291.321191)
			(xy 77.237204 -291.31921) (xy 77.286059 -291.325142) (xy 77.33333 -291.338834) (xy 77.377792 -291.359932)
			(xy 77.418295 -291.387888) (xy 77.453788 -291.42198) (xy 77.483353 -291.461324) (xy 77.506224 -291.504901)
			(xy 77.521808 -291.551582) (xy 77.529703 -291.600159) (xy 77.530198 -291.624766) (xy 77.869046 -291.624766)
			(xy 77.873006 -291.575712) (xy 77.884783 -291.527928) (xy 77.904074 -291.482652) (xy 77.930377 -291.441056)
			(xy 77.963012 -291.404219) (xy 78.001133 -291.373094) (xy 78.043754 -291.348487) (xy 78.08977 -291.331035)
			(xy 78.137989 -291.321191) (xy 78.187164 -291.31921) (xy 78.236019 -291.325142) (xy 78.28329 -291.338834)
			(xy 78.327752 -291.359932) (xy 78.368255 -291.387888) (xy 78.403748 -291.42198) (xy 78.433313 -291.461324)
			(xy 78.456184 -291.504901) (xy 78.471768 -291.551582) (xy 78.479663 -291.600159) (xy 78.480158 -291.624766)
			(xy 78.819006 -291.624766) (xy 78.822966 -291.575712) (xy 78.834743 -291.527928) (xy 78.854034 -291.482652)
			(xy 78.880337 -291.441056) (xy 78.912972 -291.404219) (xy 78.951093 -291.373094) (xy 78.993714 -291.348487)
			(xy 79.03973 -291.331035) (xy 79.087949 -291.321191) (xy 79.137124 -291.31921) (xy 79.185979 -291.325142)
			(xy 79.23325 -291.338834) (xy 79.277712 -291.359932) (xy 79.318215 -291.387888) (xy 79.353708 -291.42198)
			(xy 79.383273 -291.461324) (xy 79.406144 -291.504901) (xy 79.421728 -291.551582) (xy 79.429623 -291.600159)
			(xy 79.430118 -291.624766) (xy 79.768966 -291.624766) (xy 79.772926 -291.575712) (xy 79.784703 -291.527928)
			(xy 79.803994 -291.482652) (xy 79.830297 -291.441056) (xy 79.862932 -291.404219) (xy 79.901053 -291.373094)
			(xy 79.943674 -291.348487) (xy 79.98969 -291.331035) (xy 80.037909 -291.321191) (xy 80.087084 -291.31921)
			(xy 80.135939 -291.325142) (xy 80.18321 -291.338834) (xy 80.227672 -291.359932) (xy 80.268175 -291.387888)
			(xy 80.303668 -291.42198) (xy 80.333233 -291.461324) (xy 80.356104 -291.504901) (xy 80.371688 -291.551582)
			(xy 80.379583 -291.600159) (xy 80.380078 -291.624766) (xy 80.71918 -291.624766) (xy 80.72314 -291.575712)
			(xy 80.734917 -291.527928) (xy 80.754208 -291.482652) (xy 80.780511 -291.441056) (xy 80.813146 -291.404219)
			(xy 80.851267 -291.373094) (xy 80.893888 -291.348487) (xy 80.939904 -291.331035) (xy 80.988123 -291.321191)
			(xy 81.037298 -291.31921) (xy 81.086153 -291.325142) (xy 81.133424 -291.338834) (xy 81.177886 -291.359932)
			(xy 81.218389 -291.387888) (xy 81.253882 -291.42198) (xy 81.283447 -291.461324) (xy 81.306318 -291.504901)
			(xy 81.321902 -291.551582) (xy 81.329797 -291.600159) (xy 81.330292 -291.624766) (xy 81.66914 -291.624766)
			(xy 81.6731 -291.575712) (xy 81.684877 -291.527928) (xy 81.704168 -291.482652) (xy 81.730471 -291.441056)
			(xy 81.763106 -291.404219) (xy 81.801227 -291.373094) (xy 81.843848 -291.348487) (xy 81.889864 -291.331035)
			(xy 81.938083 -291.321191) (xy 81.987258 -291.31921) (xy 82.036113 -291.325142) (xy 82.083384 -291.338834)
			(xy 82.127846 -291.359932) (xy 82.168349 -291.387888) (xy 82.203842 -291.42198) (xy 82.233407 -291.461324)
			(xy 82.256278 -291.504901) (xy 82.271862 -291.551582) (xy 82.279757 -291.600159) (xy 82.280252 -291.624766)
			(xy 82.6191 -291.624766) (xy 82.62306 -291.575712) (xy 82.634837 -291.527928) (xy 82.654128 -291.482652)
			(xy 82.680431 -291.441056) (xy 82.713066 -291.404219) (xy 82.751187 -291.373094) (xy 82.793808 -291.348487)
			(xy 82.839824 -291.331035) (xy 82.888043 -291.321191) (xy 82.937218 -291.31921) (xy 82.986073 -291.325142)
			(xy 83.033344 -291.338834) (xy 83.077806 -291.359932) (xy 83.118309 -291.387888) (xy 83.153802 -291.42198)
			(xy 83.183367 -291.461324) (xy 83.206238 -291.504901) (xy 83.221822 -291.551582) (xy 83.229717 -291.600159)
			(xy 83.230212 -291.624766) (xy 83.229717 -291.649373) (xy 83.221822 -291.69795) (xy 83.206238 -291.744631)
			(xy 83.183367 -291.788208) (xy 83.153802 -291.827552) (xy 83.118309 -291.861644) (xy 83.077806 -291.8896)
			(xy 83.033344 -291.910698) (xy 82.986073 -291.92439) (xy 82.937218 -291.930322) (xy 82.888043 -291.928341)
			(xy 82.839824 -291.918497) (xy 82.793808 -291.901045) (xy 82.751187 -291.876438) (xy 82.713066 -291.845313)
			(xy 82.680431 -291.808476) (xy 82.654128 -291.76688) (xy 82.634837 -291.721604) (xy 82.62306 -291.67382)
			(xy 82.6191 -291.624766) (xy 82.280252 -291.624766) (xy 82.279757 -291.649373) (xy 82.271862 -291.69795)
			(xy 82.256278 -291.744631) (xy 82.233407 -291.788208) (xy 82.203842 -291.827552) (xy 82.168349 -291.861644)
			(xy 82.127846 -291.8896) (xy 82.083384 -291.910698) (xy 82.036113 -291.92439) (xy 81.987258 -291.930322)
			(xy 81.938083 -291.928341) (xy 81.889864 -291.918497) (xy 81.843848 -291.901045) (xy 81.801227 -291.876438)
			(xy 81.763106 -291.845313) (xy 81.730471 -291.808476) (xy 81.704168 -291.76688) (xy 81.684877 -291.721604)
			(xy 81.6731 -291.67382) (xy 81.66914 -291.624766) (xy 81.330292 -291.624766) (xy 81.329797 -291.649373)
			(xy 81.321902 -291.69795) (xy 81.306318 -291.744631) (xy 81.283447 -291.788208) (xy 81.253882 -291.827552)
			(xy 81.218389 -291.861644) (xy 81.177886 -291.8896) (xy 81.133424 -291.910698) (xy 81.086153 -291.92439)
			(xy 81.037298 -291.930322) (xy 80.988123 -291.928341) (xy 80.939904 -291.918497) (xy 80.893888 -291.901045)
			(xy 80.851267 -291.876438) (xy 80.813146 -291.845313) (xy 80.780511 -291.808476) (xy 80.754208 -291.76688)
			(xy 80.734917 -291.721604) (xy 80.72314 -291.67382) (xy 80.71918 -291.624766) (xy 80.380078 -291.624766)
			(xy 80.379583 -291.649373) (xy 80.371688 -291.69795) (xy 80.356104 -291.744631) (xy 80.333233 -291.788208)
			(xy 80.303668 -291.827552) (xy 80.268175 -291.861644) (xy 80.227672 -291.8896) (xy 80.18321 -291.910698)
			(xy 80.135939 -291.92439) (xy 80.087084 -291.930322) (xy 80.037909 -291.928341) (xy 79.98969 -291.918497)
			(xy 79.943674 -291.901045) (xy 79.901053 -291.876438) (xy 79.862932 -291.845313) (xy 79.830297 -291.808476)
			(xy 79.803994 -291.76688) (xy 79.784703 -291.721604) (xy 79.772926 -291.67382) (xy 79.768966 -291.624766)
			(xy 79.430118 -291.624766) (xy 79.429623 -291.649373) (xy 79.421728 -291.69795) (xy 79.406144 -291.744631)
			(xy 79.383273 -291.788208) (xy 79.353708 -291.827552) (xy 79.318215 -291.861644) (xy 79.277712 -291.8896)
			(xy 79.23325 -291.910698) (xy 79.185979 -291.92439) (xy 79.137124 -291.930322) (xy 79.087949 -291.928341)
			(xy 79.03973 -291.918497) (xy 78.993714 -291.901045) (xy 78.951093 -291.876438) (xy 78.912972 -291.845313)
			(xy 78.880337 -291.808476) (xy 78.854034 -291.76688) (xy 78.834743 -291.721604) (xy 78.822966 -291.67382)
			(xy 78.819006 -291.624766) (xy 78.480158 -291.624766) (xy 78.479663 -291.649373) (xy 78.471768 -291.69795)
			(xy 78.456184 -291.744631) (xy 78.433313 -291.788208) (xy 78.403748 -291.827552) (xy 78.368255 -291.861644)
			(xy 78.327752 -291.8896) (xy 78.28329 -291.910698) (xy 78.236019 -291.92439) (xy 78.187164 -291.930322)
			(xy 78.137989 -291.928341) (xy 78.08977 -291.918497) (xy 78.043754 -291.901045) (xy 78.001133 -291.876438)
			(xy 77.963012 -291.845313) (xy 77.930377 -291.808476) (xy 77.904074 -291.76688) (xy 77.884783 -291.721604)
			(xy 77.873006 -291.67382) (xy 77.869046 -291.624766) (xy 77.530198 -291.624766) (xy 77.529703 -291.649373)
			(xy 77.521808 -291.69795) (xy 77.506224 -291.744631) (xy 77.483353 -291.788208) (xy 77.453788 -291.827552)
			(xy 77.418295 -291.861644) (xy 77.377792 -291.8896) (xy 77.33333 -291.910698) (xy 77.286059 -291.92439)
			(xy 77.237204 -291.930322) (xy 77.188029 -291.928341) (xy 77.13981 -291.918497) (xy 77.093794 -291.901045)
			(xy 77.051173 -291.876438) (xy 77.013052 -291.845313) (xy 76.980417 -291.808476) (xy 76.954114 -291.76688)
			(xy 76.934823 -291.721604) (xy 76.923046 -291.67382) (xy 76.919086 -291.624766) (xy 76.580238 -291.624766)
			(xy 76.579743 -291.649373) (xy 76.571848 -291.69795) (xy 76.556264 -291.744631) (xy 76.533393 -291.788208)
			(xy 76.503828 -291.827552) (xy 76.468335 -291.861644) (xy 76.427832 -291.8896) (xy 76.38337 -291.910698)
			(xy 76.336099 -291.92439) (xy 76.287244 -291.930322) (xy 76.238069 -291.928341) (xy 76.18985 -291.918497)
			(xy 76.143834 -291.901045) (xy 76.101213 -291.876438) (xy 76.063092 -291.845313) (xy 76.030457 -291.808476)
			(xy 76.004154 -291.76688) (xy 75.984863 -291.721604) (xy 75.973086 -291.67382) (xy 75.969126 -291.624766)
			(xy 74.680318 -291.624766) (xy 74.679823 -291.649373) (xy 74.671928 -291.69795) (xy 74.656344 -291.744631)
			(xy 74.633473 -291.788208) (xy 74.603908 -291.827552) (xy 74.568415 -291.861644) (xy 74.527912 -291.8896)
			(xy 74.48345 -291.910698) (xy 74.436179 -291.92439) (xy 74.387324 -291.930322) (xy 74.338149 -291.928341)
			(xy 74.28993 -291.918497) (xy 74.243914 -291.901045) (xy 74.201293 -291.876438) (xy 74.163172 -291.845313)
			(xy 74.130537 -291.808476) (xy 74.104234 -291.76688) (xy 74.084943 -291.721604) (xy 74.073166 -291.67382)
			(xy 74.069206 -291.624766) (xy 73.730104 -291.624766) (xy 73.729609 -291.649373) (xy 73.721714 -291.69795)
			(xy 73.70613 -291.744631) (xy 73.683259 -291.788208) (xy 73.653694 -291.827552) (xy 73.618201 -291.861644)
			(xy 73.577698 -291.8896) (xy 73.533236 -291.910698) (xy 73.485965 -291.92439) (xy 73.43711 -291.930322)
			(xy 73.387935 -291.928341) (xy 73.339716 -291.918497) (xy 73.2937 -291.901045) (xy 73.251079 -291.876438)
			(xy 73.212958 -291.845313) (xy 73.180323 -291.808476) (xy 73.15402 -291.76688) (xy 73.134729 -291.721604)
			(xy 73.122952 -291.67382) (xy 73.118992 -291.624766) (xy 72.780144 -291.624766) (xy 72.779649 -291.649373)
			(xy 72.771754 -291.69795) (xy 72.75617 -291.744631) (xy 72.733299 -291.788208) (xy 72.703734 -291.827552)
			(xy 72.668241 -291.861644) (xy 72.627738 -291.8896) (xy 72.583276 -291.910698) (xy 72.536005 -291.92439)
			(xy 72.48715 -291.930322) (xy 72.437975 -291.928341) (xy 72.389756 -291.918497) (xy 72.34374 -291.901045)
			(xy 72.301119 -291.876438) (xy 72.262998 -291.845313) (xy 72.230363 -291.808476) (xy 72.20406 -291.76688)
			(xy 72.184769 -291.721604) (xy 72.172992 -291.67382) (xy 72.169032 -291.624766) (xy 71.830184 -291.624766)
			(xy 71.829689 -291.649373) (xy 71.821794 -291.69795) (xy 71.80621 -291.744631) (xy 71.783339 -291.788208)
			(xy 71.753774 -291.827552) (xy 71.718281 -291.861644) (xy 71.677778 -291.8896) (xy 71.633316 -291.910698)
			(xy 71.586045 -291.92439) (xy 71.53719 -291.930322) (xy 71.488015 -291.928341) (xy 71.439796 -291.918497)
			(xy 71.39378 -291.901045) (xy 71.351159 -291.876438) (xy 71.313038 -291.845313) (xy 71.280403 -291.808476)
			(xy 71.2541 -291.76688) (xy 71.234809 -291.721604) (xy 71.223032 -291.67382) (xy 71.219072 -291.624766)
			(xy 70.880224 -291.624766) (xy 70.879729 -291.649373) (xy 70.871834 -291.69795) (xy 70.85625 -291.744631)
			(xy 70.833379 -291.788208) (xy 70.803814 -291.827552) (xy 70.768321 -291.861644) (xy 70.727818 -291.8896)
			(xy 70.683356 -291.910698) (xy 70.636085 -291.92439) (xy 70.58723 -291.930322) (xy 70.538055 -291.928341)
			(xy 70.489836 -291.918497) (xy 70.44382 -291.901045) (xy 70.401199 -291.876438) (xy 70.363078 -291.845313)
			(xy 70.330443 -291.808476) (xy 70.30414 -291.76688) (xy 70.284849 -291.721604) (xy 70.273072 -291.67382)
			(xy 70.269112 -291.624766) (xy 69.930264 -291.624766) (xy 69.929769 -291.649373) (xy 69.921874 -291.69795)
			(xy 69.90629 -291.744631) (xy 69.883419 -291.788208) (xy 69.853854 -291.827552) (xy 69.818361 -291.861644)
			(xy 69.777858 -291.8896) (xy 69.733396 -291.910698) (xy 69.686125 -291.92439) (xy 69.63727 -291.930322)
			(xy 69.588095 -291.928341) (xy 69.539876 -291.918497) (xy 69.49386 -291.901045) (xy 69.451239 -291.876438)
			(xy 69.413118 -291.845313) (xy 69.380483 -291.808476) (xy 69.35418 -291.76688) (xy 69.334889 -291.721604)
			(xy 69.323112 -291.67382) (xy 69.319152 -291.624766) (xy 68.98005 -291.624766) (xy 68.979555 -291.649373)
			(xy 68.97166 -291.69795) (xy 68.956076 -291.744631) (xy 68.933205 -291.788208) (xy 68.90364 -291.827552)
			(xy 68.868147 -291.861644) (xy 68.827644 -291.8896) (xy 68.783182 -291.910698) (xy 68.735911 -291.92439)
			(xy 68.687056 -291.930322) (xy 68.637881 -291.928341) (xy 68.589662 -291.918497) (xy 68.543646 -291.901045)
			(xy 68.501025 -291.876438) (xy 68.462904 -291.845313) (xy 68.430269 -291.808476) (xy 68.403966 -291.76688)
			(xy 68.384675 -291.721604) (xy 68.372898 -291.67382) (xy 68.368938 -291.624766) (xy 68.03009 -291.624766)
			(xy 68.029595 -291.649373) (xy 68.0217 -291.69795) (xy 68.006116 -291.744631) (xy 67.983245 -291.788208)
			(xy 67.95368 -291.827552) (xy 67.918187 -291.861644) (xy 67.877684 -291.8896) (xy 67.833222 -291.910698)
			(xy 67.785951 -291.92439) (xy 67.737096 -291.930322) (xy 67.687921 -291.928341) (xy 67.639702 -291.918497)
			(xy 67.593686 -291.901045) (xy 67.551065 -291.876438) (xy 67.512944 -291.845313) (xy 67.480309 -291.808476)
			(xy 67.454006 -291.76688) (xy 67.434715 -291.721604) (xy 67.422938 -291.67382) (xy 67.418978 -291.624766)
			(xy 67.08013 -291.624766) (xy 67.079635 -291.649373) (xy 67.07174 -291.69795) (xy 67.056156 -291.744631)
			(xy 67.033285 -291.788208) (xy 67.00372 -291.827552) (xy 66.968227 -291.861644) (xy 66.927724 -291.8896)
			(xy 66.883262 -291.910698) (xy 66.835991 -291.92439) (xy 66.787136 -291.930322) (xy 66.737961 -291.928341)
			(xy 66.689742 -291.918497) (xy 66.643726 -291.901045) (xy 66.601105 -291.876438) (xy 66.562984 -291.845313)
			(xy 66.530349 -291.808476) (xy 66.504046 -291.76688) (xy 66.484755 -291.721604) (xy 66.472978 -291.67382)
			(xy 66.469018 -291.624766) (xy 66.13017 -291.624766) (xy 66.129675 -291.649373) (xy 66.12178 -291.69795)
			(xy 66.106196 -291.744631) (xy 66.083325 -291.788208) (xy 66.05376 -291.827552) (xy 66.018267 -291.861644)
			(xy 65.977764 -291.8896) (xy 65.933302 -291.910698) (xy 65.886031 -291.92439) (xy 65.837176 -291.930322)
			(xy 65.788001 -291.928341) (xy 65.739782 -291.918497) (xy 65.693766 -291.901045) (xy 65.651145 -291.876438)
			(xy 65.613024 -291.845313) (xy 65.580389 -291.808476) (xy 65.554086 -291.76688) (xy 65.534795 -291.721604)
			(xy 65.523018 -291.67382) (xy 65.519058 -291.624766) (xy 65.18021 -291.624766) (xy 65.179715 -291.649373)
			(xy 65.17182 -291.69795) (xy 65.156236 -291.744631) (xy 65.133365 -291.788208) (xy 65.1038 -291.827552)
			(xy 65.068307 -291.861644) (xy 65.027804 -291.8896) (xy 64.983342 -291.910698) (xy 64.936071 -291.92439)
			(xy 64.887216 -291.930322) (xy 64.838041 -291.928341) (xy 64.789822 -291.918497) (xy 64.743806 -291.901045)
			(xy 64.701185 -291.876438) (xy 64.663064 -291.845313) (xy 64.630429 -291.808476) (xy 64.604126 -291.76688)
			(xy 64.584835 -291.721604) (xy 64.573058 -291.67382) (xy 64.569098 -291.624766) (xy 64.23025 -291.624766)
			(xy 64.229755 -291.649373) (xy 64.22186 -291.69795) (xy 64.206276 -291.744631) (xy 64.183405 -291.788208)
			(xy 64.15384 -291.827552) (xy 64.118347 -291.861644) (xy 64.077844 -291.8896) (xy 64.033382 -291.910698)
			(xy 63.986111 -291.92439) (xy 63.937256 -291.930322) (xy 63.888081 -291.928341) (xy 63.839862 -291.918497)
			(xy 63.793846 -291.901045) (xy 63.751225 -291.876438) (xy 63.713104 -291.845313) (xy 63.680469 -291.808476)
			(xy 63.654166 -291.76688) (xy 63.634875 -291.721604) (xy 63.623098 -291.67382) (xy 63.619138 -291.624766)
			(xy 63.28029 -291.624766) (xy 63.279795 -291.649373) (xy 63.2719 -291.69795) (xy 63.256316 -291.744631)
			(xy 63.233445 -291.788208) (xy 63.20388 -291.827552) (xy 63.168387 -291.861644) (xy 63.127884 -291.8896)
			(xy 63.083422 -291.910698) (xy 63.036151 -291.92439) (xy 62.987296 -291.930322) (xy 62.938121 -291.928341)
			(xy 62.889902 -291.918497) (xy 62.843886 -291.901045) (xy 62.801265 -291.876438) (xy 62.763144 -291.845313)
			(xy 62.730509 -291.808476) (xy 62.704206 -291.76688) (xy 62.684915 -291.721604) (xy 62.673138 -291.67382)
			(xy 62.669178 -291.624766) (xy 62.330076 -291.624766) (xy 62.329581 -291.649373) (xy 62.321686 -291.69795)
			(xy 62.306102 -291.744631) (xy 62.283231 -291.788208) (xy 62.253666 -291.827552) (xy 62.218173 -291.861644)
			(xy 62.17767 -291.8896) (xy 62.133208 -291.910698) (xy 62.085937 -291.92439) (xy 62.037082 -291.930322)
			(xy 61.987907 -291.928341) (xy 61.939688 -291.918497) (xy 61.893672 -291.901045) (xy 61.851051 -291.876438)
			(xy 61.81293 -291.845313) (xy 61.780295 -291.808476) (xy 61.753992 -291.76688) (xy 61.734701 -291.721604)
			(xy 61.722924 -291.67382) (xy 61.718964 -291.624766) (xy 61.380116 -291.624766) (xy 61.379621 -291.649373)
			(xy 61.371726 -291.69795) (xy 61.356142 -291.744631) (xy 61.333271 -291.788208) (xy 61.303706 -291.827552)
			(xy 61.268213 -291.861644) (xy 61.22771 -291.8896) (xy 61.183248 -291.910698) (xy 61.135977 -291.92439)
			(xy 61.087122 -291.930322) (xy 61.037947 -291.928341) (xy 60.989728 -291.918497) (xy 60.943712 -291.901045)
			(xy 60.901091 -291.876438) (xy 60.86297 -291.845313) (xy 60.830335 -291.808476) (xy 60.804032 -291.76688)
			(xy 60.784741 -291.721604) (xy 60.772964 -291.67382) (xy 60.769004 -291.624766) (xy 60.430156 -291.624766)
			(xy 60.429661 -291.649373) (xy 60.421766 -291.69795) (xy 60.406182 -291.744631) (xy 60.383311 -291.788208)
			(xy 60.353746 -291.827552) (xy 60.318253 -291.861644) (xy 60.27775 -291.8896) (xy 60.233288 -291.910698)
			(xy 60.186017 -291.92439) (xy 60.137162 -291.930322) (xy 60.087987 -291.928341) (xy 60.039768 -291.918497)
			(xy 59.993752 -291.901045) (xy 59.951131 -291.876438) (xy 59.91301 -291.845313) (xy 59.880375 -291.808476)
			(xy 59.854072 -291.76688) (xy 59.834781 -291.721604) (xy 59.823004 -291.67382) (xy 59.819044 -291.624766)
			(xy 58.530236 -291.624766) (xy 58.529741 -291.649373) (xy 58.521846 -291.69795) (xy 58.506262 -291.744631)
			(xy 58.483391 -291.788208) (xy 58.453826 -291.827552) (xy 58.418333 -291.861644) (xy 58.37783 -291.8896)
			(xy 58.333368 -291.910698) (xy 58.286097 -291.92439) (xy 58.237242 -291.930322) (xy 58.188067 -291.928341)
			(xy 58.139848 -291.918497) (xy 58.093832 -291.901045) (xy 58.051211 -291.876438) (xy 58.01309 -291.845313)
			(xy 57.980455 -291.808476) (xy 57.954152 -291.76688) (xy 57.934861 -291.721604) (xy 57.923084 -291.67382)
			(xy 57.919124 -291.624766) (xy 57.580276 -291.624766) (xy 57.579781 -291.649373) (xy 57.571886 -291.69795)
			(xy 57.556302 -291.744631) (xy 57.533431 -291.788208) (xy 57.503866 -291.827552) (xy 57.468373 -291.861644)
			(xy 57.42787 -291.8896) (xy 57.383408 -291.910698) (xy 57.336137 -291.92439) (xy 57.287282 -291.930322)
			(xy 57.238107 -291.928341) (xy 57.189888 -291.918497) (xy 57.143872 -291.901045) (xy 57.101251 -291.876438)
			(xy 57.06313 -291.845313) (xy 57.030495 -291.808476) (xy 57.004192 -291.76688) (xy 56.984901 -291.721604)
			(xy 56.973124 -291.67382) (xy 56.969164 -291.624766) (xy 56.630062 -291.624766) (xy 56.629567 -291.649373)
			(xy 56.621672 -291.69795) (xy 56.606088 -291.744631) (xy 56.583217 -291.788208) (xy 56.553652 -291.827552)
			(xy 56.518159 -291.861644) (xy 56.477656 -291.8896) (xy 56.433194 -291.910698) (xy 56.385923 -291.92439)
			(xy 56.337068 -291.930322) (xy 56.287893 -291.928341) (xy 56.239674 -291.918497) (xy 56.193658 -291.901045)
			(xy 56.151037 -291.876438) (xy 56.112916 -291.845313) (xy 56.080281 -291.808476) (xy 56.053978 -291.76688)
			(xy 56.034687 -291.721604) (xy 56.02291 -291.67382) (xy 56.01895 -291.624766) (xy 55.680102 -291.624766)
			(xy 55.679607 -291.649373) (xy 55.671712 -291.69795) (xy 55.656128 -291.744631) (xy 55.633257 -291.788208)
			(xy 55.603692 -291.827552) (xy 55.568199 -291.861644) (xy 55.527696 -291.8896) (xy 55.483234 -291.910698)
			(xy 55.435963 -291.92439) (xy 55.387108 -291.930322) (xy 55.337933 -291.928341) (xy 55.289714 -291.918497)
			(xy 55.243698 -291.901045) (xy 55.201077 -291.876438) (xy 55.162956 -291.845313) (xy 55.130321 -291.808476)
			(xy 55.104018 -291.76688) (xy 55.084727 -291.721604) (xy 55.07295 -291.67382) (xy 55.06899 -291.624766)
			(xy 54.730142 -291.624766) (xy 54.729647 -291.649373) (xy 54.721752 -291.69795) (xy 54.706168 -291.744631)
			(xy 54.683297 -291.788208) (xy 54.653732 -291.827552) (xy 54.618239 -291.861644) (xy 54.577736 -291.8896)
			(xy 54.533274 -291.910698) (xy 54.486003 -291.92439) (xy 54.437148 -291.930322) (xy 54.387973 -291.928341)
			(xy 54.339754 -291.918497) (xy 54.293738 -291.901045) (xy 54.251117 -291.876438) (xy 54.212996 -291.845313)
			(xy 54.180361 -291.808476) (xy 54.154058 -291.76688) (xy 54.134767 -291.721604) (xy 54.12299 -291.67382)
			(xy 54.11903 -291.624766) (xy 53.780182 -291.624766) (xy 53.779687 -291.649373) (xy 53.771792 -291.69795)
			(xy 53.756208 -291.744631) (xy 53.733337 -291.788208) (xy 53.703772 -291.827552) (xy 53.668279 -291.861644)
			(xy 53.627776 -291.8896) (xy 53.583314 -291.910698) (xy 53.536043 -291.92439) (xy 53.487188 -291.930322)
			(xy 53.438013 -291.928341) (xy 53.389794 -291.918497) (xy 53.343778 -291.901045) (xy 53.301157 -291.876438)
			(xy 53.263036 -291.845313) (xy 53.230401 -291.808476) (xy 53.204098 -291.76688) (xy 53.184807 -291.721604)
			(xy 53.17303 -291.67382) (xy 53.16907 -291.624766) (xy 52.830222 -291.624766) (xy 52.829727 -291.649373)
			(xy 52.821832 -291.69795) (xy 52.806248 -291.744631) (xy 52.783377 -291.788208) (xy 52.753812 -291.827552)
			(xy 52.718319 -291.861644) (xy 52.677816 -291.8896) (xy 52.633354 -291.910698) (xy 52.586083 -291.92439)
			(xy 52.537228 -291.930322) (xy 52.488053 -291.928341) (xy 52.439834 -291.918497) (xy 52.393818 -291.901045)
			(xy 52.351197 -291.876438) (xy 52.313076 -291.845313) (xy 52.280441 -291.808476) (xy 52.254138 -291.76688)
			(xy 52.234847 -291.721604) (xy 52.22307 -291.67382) (xy 52.21911 -291.624766) (xy 51.880262 -291.624766)
			(xy 51.879767 -291.649373) (xy 51.871872 -291.69795) (xy 51.856288 -291.744631) (xy 51.833417 -291.788208)
			(xy 51.803852 -291.827552) (xy 51.768359 -291.861644) (xy 51.727856 -291.8896) (xy 51.683394 -291.910698)
			(xy 51.636123 -291.92439) (xy 51.587268 -291.930322) (xy 51.538093 -291.928341) (xy 51.489874 -291.918497)
			(xy 51.443858 -291.901045) (xy 51.401237 -291.876438) (xy 51.363116 -291.845313) (xy 51.330481 -291.808476)
			(xy 51.304178 -291.76688) (xy 51.284887 -291.721604) (xy 51.27311 -291.67382) (xy 51.26915 -291.624766)
			(xy 50.930302 -291.624766) (xy 50.929807 -291.649373) (xy 50.921912 -291.69795) (xy 50.906328 -291.744631)
			(xy 50.883457 -291.788208) (xy 50.853892 -291.827552) (xy 50.818399 -291.861644) (xy 50.777896 -291.8896)
			(xy 50.733434 -291.910698) (xy 50.686163 -291.92439) (xy 50.637308 -291.930322) (xy 50.588133 -291.928341)
			(xy 50.539914 -291.918497) (xy 50.493898 -291.901045) (xy 50.451277 -291.876438) (xy 50.413156 -291.845313)
			(xy 50.380521 -291.808476) (xy 50.354218 -291.76688) (xy 50.334927 -291.721604) (xy 50.32315 -291.67382)
			(xy 50.31919 -291.624766) (xy 49.980088 -291.624766) (xy 49.979593 -291.649373) (xy 49.971698 -291.69795)
			(xy 49.956114 -291.744631) (xy 49.933243 -291.788208) (xy 49.903678 -291.827552) (xy 49.868185 -291.861644)
			(xy 49.827682 -291.8896) (xy 49.78322 -291.910698) (xy 49.735949 -291.92439) (xy 49.687094 -291.930322)
			(xy 49.637919 -291.928341) (xy 49.5897 -291.918497) (xy 49.543684 -291.901045) (xy 49.501063 -291.876438)
			(xy 49.462942 -291.845313) (xy 49.430307 -291.808476) (xy 49.404004 -291.76688) (xy 49.384713 -291.721604)
			(xy 49.372936 -291.67382) (xy 49.368976 -291.624766) (xy 49.030128 -291.624766) (xy 49.029633 -291.649373)
			(xy 49.021738 -291.69795) (xy 49.006154 -291.744631) (xy 48.983283 -291.788208) (xy 48.953718 -291.827552)
			(xy 48.918225 -291.861644) (xy 48.877722 -291.8896) (xy 48.83326 -291.910698) (xy 48.785989 -291.92439)
			(xy 48.737134 -291.930322) (xy 48.687959 -291.928341) (xy 48.63974 -291.918497) (xy 48.593724 -291.901045)
			(xy 48.551103 -291.876438) (xy 48.512982 -291.845313) (xy 48.480347 -291.808476) (xy 48.454044 -291.76688)
			(xy 48.434753 -291.721604) (xy 48.422976 -291.67382) (xy 48.419016 -291.624766) (xy 48.080168 -291.624766)
			(xy 48.079673 -291.649373) (xy 48.071778 -291.69795) (xy 48.056194 -291.744631) (xy 48.033323 -291.788208)
			(xy 48.003758 -291.827552) (xy 47.968265 -291.861644) (xy 47.927762 -291.8896) (xy 47.8833 -291.910698)
			(xy 47.836029 -291.92439) (xy 47.787174 -291.930322) (xy 47.737999 -291.928341) (xy 47.68978 -291.918497)
			(xy 47.643764 -291.901045) (xy 47.601143 -291.876438) (xy 47.563022 -291.845313) (xy 47.530387 -291.808476)
			(xy 47.504084 -291.76688) (xy 47.484793 -291.721604) (xy 47.473016 -291.67382) (xy 47.469056 -291.624766)
			(xy 46.180248 -291.624766) (xy 46.179753 -291.649373) (xy 46.171858 -291.69795) (xy 46.156274 -291.744631)
			(xy 46.133403 -291.788208) (xy 46.103838 -291.827552) (xy 46.068345 -291.861644) (xy 46.027842 -291.8896)
			(xy 45.98338 -291.910698) (xy 45.936109 -291.92439) (xy 45.887254 -291.930322) (xy 45.838079 -291.928341)
			(xy 45.78986 -291.918497) (xy 45.743844 -291.901045) (xy 45.701223 -291.876438) (xy 45.663102 -291.845313)
			(xy 45.630467 -291.808476) (xy 45.604164 -291.76688) (xy 45.584873 -291.721604) (xy 45.573096 -291.67382)
			(xy 45.569136 -291.624766) (xy 45.230288 -291.624766) (xy 45.229793 -291.649373) (xy 45.221898 -291.69795)
			(xy 45.206314 -291.744631) (xy 45.183443 -291.788208) (xy 45.153878 -291.827552) (xy 45.118385 -291.861644)
			(xy 45.077882 -291.8896) (xy 45.03342 -291.910698) (xy 44.986149 -291.92439) (xy 44.937294 -291.930322)
			(xy 44.888119 -291.928341) (xy 44.8399 -291.918497) (xy 44.793884 -291.901045) (xy 44.751263 -291.876438)
			(xy 44.713142 -291.845313) (xy 44.680507 -291.808476) (xy 44.654204 -291.76688) (xy 44.634913 -291.721604)
			(xy 44.623136 -291.67382) (xy 44.619176 -291.624766) (xy 44.280074 -291.624766) (xy 44.279579 -291.649373)
			(xy 44.271684 -291.69795) (xy 44.2561 -291.744631) (xy 44.233229 -291.788208) (xy 44.203664 -291.827552)
			(xy 44.168171 -291.861644) (xy 44.127668 -291.8896) (xy 44.083206 -291.910698) (xy 44.035935 -291.92439)
			(xy 43.98708 -291.930322) (xy 43.937905 -291.928341) (xy 43.889686 -291.918497) (xy 43.84367 -291.901045)
			(xy 43.801049 -291.876438) (xy 43.762928 -291.845313) (xy 43.730293 -291.808476) (xy 43.70399 -291.76688)
			(xy 43.684699 -291.721604) (xy 43.672922 -291.67382) (xy 43.668962 -291.624766) (xy 43.330114 -291.624766)
			(xy 43.329619 -291.649373) (xy 43.321724 -291.69795) (xy 43.30614 -291.744631) (xy 43.283269 -291.788208)
			(xy 43.253704 -291.827552) (xy 43.218211 -291.861644) (xy 43.177708 -291.8896) (xy 43.133246 -291.910698)
			(xy 43.085975 -291.92439) (xy 43.03712 -291.930322) (xy 42.987945 -291.928341) (xy 42.939726 -291.918497)
			(xy 42.89371 -291.901045) (xy 42.851089 -291.876438) (xy 42.812968 -291.845313) (xy 42.780333 -291.808476)
			(xy 42.75403 -291.76688) (xy 42.734739 -291.721604) (xy 42.722962 -291.67382) (xy 42.719002 -291.624766)
			(xy 42.380154 -291.624766) (xy 42.379659 -291.649373) (xy 42.371764 -291.69795) (xy 42.35618 -291.744631)
			(xy 42.333309 -291.788208) (xy 42.303744 -291.827552) (xy 42.268251 -291.861644) (xy 42.227748 -291.8896)
			(xy 42.183286 -291.910698) (xy 42.136015 -291.92439) (xy 42.08716 -291.930322) (xy 42.037985 -291.928341)
			(xy 41.989766 -291.918497) (xy 41.94375 -291.901045) (xy 41.901129 -291.876438) (xy 41.863008 -291.845313)
			(xy 41.830373 -291.808476) (xy 41.80407 -291.76688) (xy 41.784779 -291.721604) (xy 41.773002 -291.67382)
			(xy 41.769042 -291.624766) (xy 41.430194 -291.624766) (xy 41.429699 -291.649373) (xy 41.421804 -291.69795)
			(xy 41.40622 -291.744631) (xy 41.383349 -291.788208) (xy 41.353784 -291.827552) (xy 41.318291 -291.861644)
			(xy 41.277788 -291.8896) (xy 41.233326 -291.910698) (xy 41.186055 -291.92439) (xy 41.1372 -291.930322)
			(xy 41.088025 -291.928341) (xy 41.039806 -291.918497) (xy 40.99379 -291.901045) (xy 40.951169 -291.876438)
			(xy 40.913048 -291.845313) (xy 40.880413 -291.808476) (xy 40.85411 -291.76688) (xy 40.834819 -291.721604)
			(xy 40.823042 -291.67382) (xy 40.819082 -291.624766) (xy 38.580314 -291.624766) (xy 38.57986 -291.648544)
			(xy 38.572502 -291.695526) (xy 38.557944 -291.740798) (xy 38.536538 -291.783264) (xy 38.508803 -291.821893)
			(xy 38.49243 -291.839142) (xy 38.486509 -291.845746) (xy 38.479099 -291.861844) (xy 38.477952 -291.870638)
			(xy 38.475412 -291.901626) (xy 38.475038 -291.910608) (xy 38.479841 -291.927917) (xy 38.48481 -291.935408)
			(xy 38.498198 -291.954862) (xy 38.519458 -291.997029) (xy 38.533972 -292.041966) (xy 38.541394 -292.088602)
			(xy 38.541547 -292.135825) (xy 38.534427 -292.182508) (xy 38.527736 -292.205156) (xy 38.503098 -292.283134)
			(xy 38.500705 -292.292109) (xy 38.501726 -292.310636) (xy 38.509283 -292.327583) (xy 38.515544 -292.334442)
			(xy 38.522416 -292.340699) (xy 38.539352 -292.348302) (xy 38.557888 -292.349332) (xy 38.566852 -292.346888)
			(xy 38.71341 -292.30066) (xy 38.720183 -292.298779) (xy 38.734229 -292.298394) (xy 38.741096 -292.299898)
			(xy 38.892734 -292.337744) (xy 38.89756 -292.34257) (xy 38.914832 -292.35019) (xy 38.993064 -292.353492)
			(xy 39.002604 -292.353446) (xy 39.020613 -292.347191) (xy 39.028116 -292.3413) (xy 39.048923 -292.324465)
			(xy 39.09523 -292.297634) (xy 39.145504 -292.279281) (xy 39.198206 -292.269968) (xy 39.224966 -292.269418)
			(xy 39.24896 -292.26987) (xy 39.296356 -292.277372) (xy 39.341996 -292.292198) (xy 39.384754 -292.313981)
			(xy 39.423577 -292.342186) (xy 39.457509 -292.376117) (xy 39.485715 -292.41494) (xy 39.507499 -292.457697)
			(xy 39.522326 -292.503336) (xy 39.52983 -292.550732) (xy 39.530274 -292.574726) (xy 39.869122 -292.574726)
			(xy 39.873082 -292.525672) (xy 39.884859 -292.477888) (xy 39.90415 -292.432612) (xy 39.930453 -292.391016)
			(xy 39.963088 -292.354179) (xy 40.001209 -292.323054) (xy 40.04383 -292.298447) (xy 40.089846 -292.280995)
			(xy 40.138065 -292.271151) (xy 40.18724 -292.26917) (xy 40.236095 -292.275102) (xy 40.283366 -292.288794)
			(xy 40.327828 -292.309892) (xy 40.368331 -292.337848) (xy 40.403824 -292.37194) (xy 40.433389 -292.411284)
			(xy 40.45626 -292.454861) (xy 40.471844 -292.501542) (xy 40.479739 -292.550119) (xy 40.480234 -292.574726)
			(xy 40.480229 -292.57498) (xy 40.819082 -292.57498) (xy 40.823042 -292.525926) (xy 40.834819 -292.478142)
			(xy 40.85411 -292.432866) (xy 40.880413 -292.39127) (xy 40.913048 -292.354433) (xy 40.951169 -292.323308)
			(xy 40.99379 -292.298701) (xy 41.039806 -292.281249) (xy 41.088025 -292.271405) (xy 41.1372 -292.269424)
			(xy 41.186055 -292.275356) (xy 41.233326 -292.289048) (xy 41.277788 -292.310146) (xy 41.318291 -292.338102)
			(xy 41.353784 -292.372194) (xy 41.383349 -292.411538) (xy 41.40622 -292.455115) (xy 41.421804 -292.501796)
			(xy 41.429699 -292.550373) (xy 41.430194 -292.57498) (xy 41.429699 -292.599587) (xy 41.429367 -292.601629)
			(xy 41.719236 -292.601629) (xy 41.719236 -292.548331) (xy 41.727179 -292.495627) (xy 41.742889 -292.444697)
			(xy 41.766015 -292.396676) (xy 41.796039 -292.352639) (xy 41.832291 -292.313568) (xy 41.873962 -292.280337)
			(xy 41.92012 -292.253688) (xy 41.969734 -292.234216) (xy 42.021696 -292.222356) (xy 42.074846 -292.218373)
			(xy 42.127996 -292.222356) (xy 42.179958 -292.234216) (xy 42.229572 -292.253688) (xy 42.27573 -292.280337)
			(xy 42.317401 -292.313568) (xy 42.353653 -292.352639) (xy 42.383677 -292.396676) (xy 42.406803 -292.444697)
			(xy 42.422513 -292.495627) (xy 42.430456 -292.548331) (xy 42.430954 -292.57498) (xy 42.719002 -292.57498)
			(xy 42.722962 -292.525926) (xy 42.734739 -292.478142) (xy 42.75403 -292.432866) (xy 42.780333 -292.39127)
			(xy 42.812968 -292.354433) (xy 42.851089 -292.323308) (xy 42.89371 -292.298701) (xy 42.939726 -292.281249)
			(xy 42.987945 -292.271405) (xy 43.03712 -292.269424) (xy 43.085975 -292.275356) (xy 43.133246 -292.289048)
			(xy 43.177708 -292.310146) (xy 43.218211 -292.338102) (xy 43.253704 -292.372194) (xy 43.283269 -292.411538)
			(xy 43.30614 -292.455115) (xy 43.321724 -292.501796) (xy 43.329619 -292.550373) (xy 43.330114 -292.57498)
			(xy 43.668962 -292.57498) (xy 43.672922 -292.525926) (xy 43.684699 -292.478142) (xy 43.70399 -292.432866)
			(xy 43.730293 -292.39127) (xy 43.762928 -292.354433) (xy 43.801049 -292.323308) (xy 43.84367 -292.298701)
			(xy 43.889686 -292.281249) (xy 43.937905 -292.271405) (xy 43.98708 -292.269424) (xy 44.035935 -292.275356)
			(xy 44.083206 -292.289048) (xy 44.127668 -292.310146) (xy 44.168171 -292.338102) (xy 44.203664 -292.372194)
			(xy 44.233229 -292.411538) (xy 44.2561 -292.455115) (xy 44.271684 -292.501796) (xy 44.279579 -292.550373)
			(xy 44.280074 -292.57498) (xy 44.619176 -292.57498) (xy 44.623136 -292.525926) (xy 44.634913 -292.478142)
			(xy 44.654204 -292.432866) (xy 44.680507 -292.39127) (xy 44.713142 -292.354433) (xy 44.751263 -292.323308)
			(xy 44.793884 -292.298701) (xy 44.8399 -292.281249) (xy 44.888119 -292.271405) (xy 44.937294 -292.269424)
			(xy 44.986149 -292.275356) (xy 45.03342 -292.289048) (xy 45.077882 -292.310146) (xy 45.118385 -292.338102)
			(xy 45.153878 -292.372194) (xy 45.183443 -292.411538) (xy 45.206314 -292.455115) (xy 45.221898 -292.501796)
			(xy 45.229793 -292.550373) (xy 45.230288 -292.57498) (xy 45.569136 -292.57498) (xy 45.573096 -292.525926)
			(xy 45.584873 -292.478142) (xy 45.604164 -292.432866) (xy 45.630467 -292.39127) (xy 45.663102 -292.354433)
			(xy 45.701223 -292.323308) (xy 45.743844 -292.298701) (xy 45.78986 -292.281249) (xy 45.838079 -292.271405)
			(xy 45.887254 -292.269424) (xy 45.936109 -292.275356) (xy 45.98338 -292.289048) (xy 46.027842 -292.310146)
			(xy 46.068345 -292.338102) (xy 46.103838 -292.372194) (xy 46.133403 -292.411538) (xy 46.156274 -292.455115)
			(xy 46.171858 -292.501796) (xy 46.179753 -292.550373) (xy 46.180248 -292.57498) (xy 46.519096 -292.57498)
			(xy 46.523056 -292.525926) (xy 46.534833 -292.478142) (xy 46.554124 -292.432866) (xy 46.580427 -292.39127)
			(xy 46.613062 -292.354433) (xy 46.651183 -292.323308) (xy 46.693804 -292.298701) (xy 46.73982 -292.281249)
			(xy 46.788039 -292.271405) (xy 46.837214 -292.269424) (xy 46.886069 -292.275356) (xy 46.93334 -292.289048)
			(xy 46.977802 -292.310146) (xy 47.018305 -292.338102) (xy 47.053798 -292.372194) (xy 47.083363 -292.411538)
			(xy 47.106234 -292.455115) (xy 47.121818 -292.501796) (xy 47.129713 -292.550373) (xy 47.130208 -292.57498)
			(xy 47.469056 -292.57498) (xy 47.473016 -292.525926) (xy 47.484793 -292.478142) (xy 47.504084 -292.432866)
			(xy 47.530387 -292.39127) (xy 47.563022 -292.354433) (xy 47.601143 -292.323308) (xy 47.643764 -292.298701)
			(xy 47.68978 -292.281249) (xy 47.737999 -292.271405) (xy 47.787174 -292.269424) (xy 47.836029 -292.275356)
			(xy 47.8833 -292.289048) (xy 47.927762 -292.310146) (xy 47.968265 -292.338102) (xy 48.003758 -292.372194)
			(xy 48.033323 -292.411538) (xy 48.056194 -292.455115) (xy 48.071778 -292.501796) (xy 48.079673 -292.550373)
			(xy 48.080163 -292.574726) (xy 48.419016 -292.574726) (xy 48.422976 -292.525672) (xy 48.434753 -292.477888)
			(xy 48.454044 -292.432612) (xy 48.480347 -292.391016) (xy 48.512982 -292.354179) (xy 48.551103 -292.323054)
			(xy 48.593724 -292.298447) (xy 48.63974 -292.280995) (xy 48.687959 -292.271151) (xy 48.737134 -292.26917)
			(xy 48.785989 -292.275102) (xy 48.83326 -292.288794) (xy 48.877722 -292.309892) (xy 48.918225 -292.337848)
			(xy 48.953718 -292.37194) (xy 48.983283 -292.411284) (xy 49.006154 -292.454861) (xy 49.021738 -292.501542)
			(xy 49.029633 -292.550119) (xy 49.030128 -292.574726) (xy 49.368976 -292.574726) (xy 49.372936 -292.525672)
			(xy 49.384713 -292.477888) (xy 49.404004 -292.432612) (xy 49.430307 -292.391016) (xy 49.462942 -292.354179)
			(xy 49.501063 -292.323054) (xy 49.543684 -292.298447) (xy 49.5897 -292.280995) (xy 49.637919 -292.271151)
			(xy 49.687094 -292.26917) (xy 49.735949 -292.275102) (xy 49.78322 -292.288794) (xy 49.827682 -292.309892)
			(xy 49.868185 -292.337848) (xy 49.903678 -292.37194) (xy 49.933243 -292.411284) (xy 49.956114 -292.454861)
			(xy 49.971698 -292.501542) (xy 49.979593 -292.550119) (xy 49.980088 -292.574726) (xy 49.980083 -292.57498)
			(xy 50.31919 -292.57498) (xy 50.32315 -292.525926) (xy 50.334927 -292.478142) (xy 50.354218 -292.432866)
			(xy 50.380521 -292.39127) (xy 50.413156 -292.354433) (xy 50.451277 -292.323308) (xy 50.493898 -292.298701)
			(xy 50.539914 -292.281249) (xy 50.588133 -292.271405) (xy 50.637308 -292.269424) (xy 50.686163 -292.275356)
			(xy 50.733434 -292.289048) (xy 50.777896 -292.310146) (xy 50.818399 -292.338102) (xy 50.853892 -292.372194)
			(xy 50.883457 -292.411538) (xy 50.906328 -292.455115) (xy 50.921912 -292.501796) (xy 50.929807 -292.550373)
			(xy 50.930302 -292.57498) (xy 51.26915 -292.57498) (xy 51.27311 -292.525926) (xy 51.284887 -292.478142)
			(xy 51.304178 -292.432866) (xy 51.330481 -292.39127) (xy 51.363116 -292.354433) (xy 51.401237 -292.323308)
			(xy 51.443858 -292.298701) (xy 51.489874 -292.281249) (xy 51.538093 -292.271405) (xy 51.587268 -292.269424)
			(xy 51.636123 -292.275356) (xy 51.683394 -292.289048) (xy 51.727856 -292.310146) (xy 51.768359 -292.338102)
			(xy 51.803852 -292.372194) (xy 51.833417 -292.411538) (xy 51.856288 -292.455115) (xy 51.871872 -292.501796)
			(xy 51.879767 -292.550373) (xy 51.880262 -292.57498) (xy 52.21911 -292.57498) (xy 52.22307 -292.525926)
			(xy 52.234847 -292.478142) (xy 52.254138 -292.432866) (xy 52.280441 -292.39127) (xy 52.313076 -292.354433)
			(xy 52.351197 -292.323308) (xy 52.393818 -292.298701) (xy 52.439834 -292.281249) (xy 52.488053 -292.271405)
			(xy 52.537228 -292.269424) (xy 52.586083 -292.275356) (xy 52.633354 -292.289048) (xy 52.677816 -292.310146)
			(xy 52.718319 -292.338102) (xy 52.753812 -292.372194) (xy 52.783377 -292.411538) (xy 52.806248 -292.455115)
			(xy 52.821832 -292.501796) (xy 52.829727 -292.550373) (xy 52.830222 -292.57498) (xy 53.16907 -292.57498)
			(xy 53.17303 -292.525926) (xy 53.184807 -292.478142) (xy 53.204098 -292.432866) (xy 53.230401 -292.39127)
			(xy 53.263036 -292.354433) (xy 53.301157 -292.323308) (xy 53.343778 -292.298701) (xy 53.389794 -292.281249)
			(xy 53.438013 -292.271405) (xy 53.487188 -292.269424) (xy 53.536043 -292.275356) (xy 53.583314 -292.289048)
			(xy 53.627776 -292.310146) (xy 53.668279 -292.338102) (xy 53.703772 -292.372194) (xy 53.733337 -292.411538)
			(xy 53.756208 -292.455115) (xy 53.771792 -292.501796) (xy 53.779687 -292.550373) (xy 53.780182 -292.57498)
			(xy 54.11903 -292.57498) (xy 54.12299 -292.525926) (xy 54.134767 -292.478142) (xy 54.154058 -292.432866)
			(xy 54.180361 -292.39127) (xy 54.212996 -292.354433) (xy 54.251117 -292.323308) (xy 54.293738 -292.298701)
			(xy 54.339754 -292.281249) (xy 54.387973 -292.271405) (xy 54.437148 -292.269424) (xy 54.486003 -292.275356)
			(xy 54.533274 -292.289048) (xy 54.577736 -292.310146) (xy 54.618239 -292.338102) (xy 54.653732 -292.372194)
			(xy 54.683297 -292.411538) (xy 54.706168 -292.455115) (xy 54.721752 -292.501796) (xy 54.729647 -292.550373)
			(xy 54.730142 -292.57498) (xy 55.06899 -292.57498) (xy 55.07295 -292.525926) (xy 55.084727 -292.478142)
			(xy 55.104018 -292.432866) (xy 55.130321 -292.39127) (xy 55.162956 -292.354433) (xy 55.201077 -292.323308)
			(xy 55.243698 -292.298701) (xy 55.289714 -292.281249) (xy 55.337933 -292.271405) (xy 55.387108 -292.269424)
			(xy 55.435963 -292.275356) (xy 55.483234 -292.289048) (xy 55.527696 -292.310146) (xy 55.568199 -292.338102)
			(xy 55.603692 -292.372194) (xy 55.633257 -292.411538) (xy 55.656128 -292.455115) (xy 55.671712 -292.501796)
			(xy 55.679607 -292.550373) (xy 55.680102 -292.57498) (xy 56.019204 -292.57498) (xy 56.023164 -292.525926)
			(xy 56.034941 -292.478142) (xy 56.054232 -292.432866) (xy 56.080535 -292.39127) (xy 56.11317 -292.354433)
			(xy 56.151291 -292.323308) (xy 56.193912 -292.298701) (xy 56.239928 -292.281249) (xy 56.288147 -292.271405)
			(xy 56.337322 -292.269424) (xy 56.386177 -292.275356) (xy 56.433448 -292.289048) (xy 56.47791 -292.310146)
			(xy 56.518413 -292.338102) (xy 56.553906 -292.372194) (xy 56.583471 -292.411538) (xy 56.606342 -292.455115)
			(xy 56.621926 -292.501796) (xy 56.629821 -292.550373) (xy 56.630316 -292.57498) (xy 56.969164 -292.57498)
			(xy 56.973124 -292.525926) (xy 56.984901 -292.478142) (xy 57.004192 -292.432866) (xy 57.030495 -292.39127)
			(xy 57.06313 -292.354433) (xy 57.101251 -292.323308) (xy 57.143872 -292.298701) (xy 57.189888 -292.281249)
			(xy 57.238107 -292.271405) (xy 57.287282 -292.269424) (xy 57.336137 -292.275356) (xy 57.383408 -292.289048)
			(xy 57.42787 -292.310146) (xy 57.468373 -292.338102) (xy 57.503866 -292.372194) (xy 57.533431 -292.411538)
			(xy 57.556302 -292.455115) (xy 57.571886 -292.501796) (xy 57.579781 -292.550373) (xy 57.580276 -292.57498)
			(xy 57.919124 -292.57498) (xy 57.923084 -292.525926) (xy 57.934861 -292.478142) (xy 57.954152 -292.432866)
			(xy 57.980455 -292.39127) (xy 58.01309 -292.354433) (xy 58.051211 -292.323308) (xy 58.093832 -292.298701)
			(xy 58.139848 -292.281249) (xy 58.188067 -292.271405) (xy 58.237242 -292.269424) (xy 58.286097 -292.275356)
			(xy 58.333368 -292.289048) (xy 58.37783 -292.310146) (xy 58.418333 -292.338102) (xy 58.453826 -292.372194)
			(xy 58.483391 -292.411538) (xy 58.506262 -292.455115) (xy 58.521846 -292.501796) (xy 58.529741 -292.550373)
			(xy 58.530231 -292.574726) (xy 59.819044 -292.574726) (xy 59.823004 -292.525672) (xy 59.834781 -292.477888)
			(xy 59.854072 -292.432612) (xy 59.880375 -292.391016) (xy 59.91301 -292.354179) (xy 59.951131 -292.323054)
			(xy 59.993752 -292.298447) (xy 60.039768 -292.280995) (xy 60.087987 -292.271151) (xy 60.137162 -292.26917)
			(xy 60.186017 -292.275102) (xy 60.233288 -292.288794) (xy 60.27775 -292.309892) (xy 60.318253 -292.337848)
			(xy 60.353746 -292.37194) (xy 60.383311 -292.411284) (xy 60.406182 -292.454861) (xy 60.421766 -292.501542)
			(xy 60.429661 -292.550119) (xy 60.430156 -292.574726) (xy 60.769004 -292.574726) (xy 60.772964 -292.525672)
			(xy 60.784741 -292.477888) (xy 60.804032 -292.432612) (xy 60.830335 -292.391016) (xy 60.86297 -292.354179)
			(xy 60.901091 -292.323054) (xy 60.943712 -292.298447) (xy 60.989728 -292.280995) (xy 61.037947 -292.271151)
			(xy 61.087122 -292.26917) (xy 61.135977 -292.275102) (xy 61.183248 -292.288794) (xy 61.22771 -292.309892)
			(xy 61.268213 -292.337848) (xy 61.303706 -292.37194) (xy 61.333271 -292.411284) (xy 61.356142 -292.454861)
			(xy 61.371726 -292.501542) (xy 61.379621 -292.550119) (xy 61.380116 -292.574726) (xy 61.718964 -292.574726)
			(xy 61.722924 -292.525672) (xy 61.734701 -292.477888) (xy 61.753992 -292.432612) (xy 61.780295 -292.391016)
			(xy 61.81293 -292.354179) (xy 61.851051 -292.323054) (xy 61.893672 -292.298447) (xy 61.939688 -292.280995)
			(xy 61.987907 -292.271151) (xy 62.037082 -292.26917) (xy 62.085937 -292.275102) (xy 62.133208 -292.288794)
			(xy 62.17767 -292.309892) (xy 62.218173 -292.337848) (xy 62.253666 -292.37194) (xy 62.283231 -292.411284)
			(xy 62.306102 -292.454861) (xy 62.321686 -292.501542) (xy 62.329581 -292.550119) (xy 62.330076 -292.574726)
			(xy 62.669178 -292.574726) (xy 62.673138 -292.525672) (xy 62.684915 -292.477888) (xy 62.704206 -292.432612)
			(xy 62.730509 -292.391016) (xy 62.763144 -292.354179) (xy 62.801265 -292.323054) (xy 62.843886 -292.298447)
			(xy 62.889902 -292.280995) (xy 62.938121 -292.271151) (xy 62.987296 -292.26917) (xy 63.036151 -292.275102)
			(xy 63.083422 -292.288794) (xy 63.127884 -292.309892) (xy 63.168387 -292.337848) (xy 63.20388 -292.37194)
			(xy 63.233445 -292.411284) (xy 63.256316 -292.454861) (xy 63.2719 -292.501542) (xy 63.279795 -292.550119)
			(xy 63.28029 -292.574726) (xy 63.619138 -292.574726) (xy 63.623098 -292.525672) (xy 63.634875 -292.477888)
			(xy 63.654166 -292.432612) (xy 63.680469 -292.391016) (xy 63.713104 -292.354179) (xy 63.751225 -292.323054)
			(xy 63.793846 -292.298447) (xy 63.839862 -292.280995) (xy 63.888081 -292.271151) (xy 63.937256 -292.26917)
			(xy 63.986111 -292.275102) (xy 64.033382 -292.288794) (xy 64.077844 -292.309892) (xy 64.118347 -292.337848)
			(xy 64.15384 -292.37194) (xy 64.183405 -292.411284) (xy 64.206276 -292.454861) (xy 64.22186 -292.501542)
			(xy 64.229755 -292.550119) (xy 64.23025 -292.574726) (xy 64.569098 -292.574726) (xy 64.573058 -292.525672)
			(xy 64.584835 -292.477888) (xy 64.604126 -292.432612) (xy 64.630429 -292.391016) (xy 64.663064 -292.354179)
			(xy 64.701185 -292.323054) (xy 64.743806 -292.298447) (xy 64.789822 -292.280995) (xy 64.838041 -292.271151)
			(xy 64.887216 -292.26917) (xy 64.936071 -292.275102) (xy 64.983342 -292.288794) (xy 65.027804 -292.309892)
			(xy 65.068307 -292.337848) (xy 65.1038 -292.37194) (xy 65.133365 -292.411284) (xy 65.156236 -292.454861)
			(xy 65.17182 -292.501542) (xy 65.179715 -292.550119) (xy 65.18021 -292.574726) (xy 65.519058 -292.574726)
			(xy 65.523018 -292.525672) (xy 65.534795 -292.477888) (xy 65.554086 -292.432612) (xy 65.580389 -292.391016)
			(xy 65.613024 -292.354179) (xy 65.651145 -292.323054) (xy 65.693766 -292.298447) (xy 65.739782 -292.280995)
			(xy 65.788001 -292.271151) (xy 65.837176 -292.26917) (xy 65.886031 -292.275102) (xy 65.933302 -292.288794)
			(xy 65.977764 -292.309892) (xy 66.018267 -292.337848) (xy 66.05376 -292.37194) (xy 66.083325 -292.411284)
			(xy 66.106196 -292.454861) (xy 66.12178 -292.501542) (xy 66.129675 -292.550119) (xy 66.13017 -292.574726)
			(xy 66.469018 -292.574726) (xy 66.472978 -292.525672) (xy 66.484755 -292.477888) (xy 66.504046 -292.432612)
			(xy 66.530349 -292.391016) (xy 66.562984 -292.354179) (xy 66.601105 -292.323054) (xy 66.643726 -292.298447)
			(xy 66.689742 -292.280995) (xy 66.737961 -292.271151) (xy 66.787136 -292.26917) (xy 66.835991 -292.275102)
			(xy 66.883262 -292.288794) (xy 66.927724 -292.309892) (xy 66.968227 -292.337848) (xy 67.00372 -292.37194)
			(xy 67.033285 -292.411284) (xy 67.056156 -292.454861) (xy 67.07174 -292.501542) (xy 67.079635 -292.550119)
			(xy 67.08013 -292.574726) (xy 67.418978 -292.574726) (xy 67.422938 -292.525672) (xy 67.434715 -292.477888)
			(xy 67.454006 -292.432612) (xy 67.480309 -292.391016) (xy 67.512944 -292.354179) (xy 67.551065 -292.323054)
			(xy 67.593686 -292.298447) (xy 67.639702 -292.280995) (xy 67.687921 -292.271151) (xy 67.737096 -292.26917)
			(xy 67.785951 -292.275102) (xy 67.833222 -292.288794) (xy 67.877684 -292.309892) (xy 67.918187 -292.337848)
			(xy 67.95368 -292.37194) (xy 67.983245 -292.411284) (xy 68.006116 -292.454861) (xy 68.0217 -292.501542)
			(xy 68.029595 -292.550119) (xy 68.03009 -292.574726) (xy 68.368938 -292.574726) (xy 68.372898 -292.525672)
			(xy 68.384675 -292.477888) (xy 68.403966 -292.432612) (xy 68.430269 -292.391016) (xy 68.462904 -292.354179)
			(xy 68.501025 -292.323054) (xy 68.543646 -292.298447) (xy 68.589662 -292.280995) (xy 68.637881 -292.271151)
			(xy 68.687056 -292.26917) (xy 68.735911 -292.275102) (xy 68.783182 -292.288794) (xy 68.827644 -292.309892)
			(xy 68.868147 -292.337848) (xy 68.90364 -292.37194) (xy 68.933205 -292.411284) (xy 68.956076 -292.454861)
			(xy 68.97166 -292.501542) (xy 68.979555 -292.550119) (xy 68.98005 -292.574726) (xy 69.319152 -292.574726)
			(xy 69.323112 -292.525672) (xy 69.334889 -292.477888) (xy 69.35418 -292.432612) (xy 69.380483 -292.391016)
			(xy 69.413118 -292.354179) (xy 69.451239 -292.323054) (xy 69.49386 -292.298447) (xy 69.539876 -292.280995)
			(xy 69.588095 -292.271151) (xy 69.63727 -292.26917) (xy 69.686125 -292.275102) (xy 69.733396 -292.288794)
			(xy 69.777858 -292.309892) (xy 69.818361 -292.337848) (xy 69.853854 -292.37194) (xy 69.883419 -292.411284)
			(xy 69.90629 -292.454861) (xy 69.921874 -292.501542) (xy 69.929769 -292.550119) (xy 69.930264 -292.574726)
			(xy 69.930259 -292.57498) (xy 70.269112 -292.57498) (xy 70.273072 -292.525926) (xy 70.284849 -292.478142)
			(xy 70.30414 -292.432866) (xy 70.330443 -292.39127) (xy 70.363078 -292.354433) (xy 70.401199 -292.323308)
			(xy 70.44382 -292.298701) (xy 70.489836 -292.281249) (xy 70.538055 -292.271405) (xy 70.58723 -292.269424)
			(xy 70.636085 -292.275356) (xy 70.683356 -292.289048) (xy 70.727818 -292.310146) (xy 70.768321 -292.338102)
			(xy 70.803814 -292.372194) (xy 70.833379 -292.411538) (xy 70.85625 -292.455115) (xy 70.871834 -292.501796)
			(xy 70.879729 -292.550373) (xy 70.880219 -292.574726) (xy 71.219072 -292.574726) (xy 71.223032 -292.525672)
			(xy 71.234809 -292.477888) (xy 71.2541 -292.432612) (xy 71.280403 -292.391016) (xy 71.313038 -292.354179)
			(xy 71.351159 -292.323054) (xy 71.39378 -292.298447) (xy 71.439796 -292.280995) (xy 71.488015 -292.271151)
			(xy 71.53719 -292.26917) (xy 71.586045 -292.275102) (xy 71.633316 -292.288794) (xy 71.677778 -292.309892)
			(xy 71.718281 -292.337848) (xy 71.753774 -292.37194) (xy 71.783339 -292.411284) (xy 71.80621 -292.454861)
			(xy 71.821794 -292.501542) (xy 71.829689 -292.550119) (xy 71.830184 -292.574726) (xy 72.169032 -292.574726)
			(xy 72.172992 -292.525672) (xy 72.184769 -292.477888) (xy 72.20406 -292.432612) (xy 72.230363 -292.391016)
			(xy 72.262998 -292.354179) (xy 72.301119 -292.323054) (xy 72.34374 -292.298447) (xy 72.389756 -292.280995)
			(xy 72.437975 -292.271151) (xy 72.48715 -292.26917) (xy 72.536005 -292.275102) (xy 72.583276 -292.288794)
			(xy 72.627738 -292.309892) (xy 72.668241 -292.337848) (xy 72.703734 -292.37194) (xy 72.733299 -292.411284)
			(xy 72.75617 -292.454861) (xy 72.771754 -292.501542) (xy 72.779649 -292.550119) (xy 72.780144 -292.574726)
			(xy 73.118992 -292.574726) (xy 73.122952 -292.525672) (xy 73.134729 -292.477888) (xy 73.15402 -292.432612)
			(xy 73.180323 -292.391016) (xy 73.212958 -292.354179) (xy 73.251079 -292.323054) (xy 73.2937 -292.298447)
			(xy 73.339716 -292.280995) (xy 73.387935 -292.271151) (xy 73.43711 -292.26917) (xy 73.485965 -292.275102)
			(xy 73.533236 -292.288794) (xy 73.577698 -292.309892) (xy 73.618201 -292.337848) (xy 73.653694 -292.37194)
			(xy 73.683259 -292.411284) (xy 73.70613 -292.454861) (xy 73.721714 -292.501542) (xy 73.729609 -292.550119)
			(xy 73.730104 -292.574726) (xy 74.068952 -292.574726) (xy 74.072912 -292.525672) (xy 74.084689 -292.477888)
			(xy 74.10398 -292.432612) (xy 74.130283 -292.391016) (xy 74.162918 -292.354179) (xy 74.201039 -292.323054)
			(xy 74.24366 -292.298447) (xy 74.289676 -292.280995) (xy 74.337895 -292.271151) (xy 74.38707 -292.26917)
			(xy 74.435925 -292.275102) (xy 74.483196 -292.288794) (xy 74.527658 -292.309892) (xy 74.568161 -292.337848)
			(xy 74.603654 -292.37194) (xy 74.633219 -292.411284) (xy 74.65609 -292.454861) (xy 74.671674 -292.501542)
			(xy 74.679569 -292.550119) (xy 74.680064 -292.574726) (xy 75.019166 -292.574726) (xy 75.023126 -292.525672)
			(xy 75.034903 -292.477888) (xy 75.054194 -292.432612) (xy 75.080497 -292.391016) (xy 75.113132 -292.354179)
			(xy 75.151253 -292.323054) (xy 75.193874 -292.298447) (xy 75.23989 -292.280995) (xy 75.288109 -292.271151)
			(xy 75.337284 -292.26917) (xy 75.386139 -292.275102) (xy 75.43341 -292.288794) (xy 75.477872 -292.309892)
			(xy 75.518375 -292.337848) (xy 75.553868 -292.37194) (xy 75.583433 -292.411284) (xy 75.606304 -292.454861)
			(xy 75.621888 -292.501542) (xy 75.629783 -292.550119) (xy 75.630278 -292.574726) (xy 75.969126 -292.574726)
			(xy 75.973086 -292.525672) (xy 75.984863 -292.477888) (xy 76.004154 -292.432612) (xy 76.030457 -292.391016)
			(xy 76.063092 -292.354179) (xy 76.101213 -292.323054) (xy 76.143834 -292.298447) (xy 76.18985 -292.280995)
			(xy 76.238069 -292.271151) (xy 76.287244 -292.26917) (xy 76.336099 -292.275102) (xy 76.38337 -292.288794)
			(xy 76.427832 -292.309892) (xy 76.468335 -292.337848) (xy 76.503828 -292.37194) (xy 76.533393 -292.411284)
			(xy 76.556264 -292.454861) (xy 76.571848 -292.501542) (xy 76.579743 -292.550119) (xy 76.580238 -292.574726)
			(xy 76.919086 -292.574726) (xy 76.923046 -292.525672) (xy 76.934823 -292.477888) (xy 76.954114 -292.432612)
			(xy 76.980417 -292.391016) (xy 77.013052 -292.354179) (xy 77.051173 -292.323054) (xy 77.093794 -292.298447)
			(xy 77.13981 -292.280995) (xy 77.188029 -292.271151) (xy 77.237204 -292.26917) (xy 77.286059 -292.275102)
			(xy 77.33333 -292.288794) (xy 77.377792 -292.309892) (xy 77.418295 -292.337848) (xy 77.453788 -292.37194)
			(xy 77.483353 -292.411284) (xy 77.506224 -292.454861) (xy 77.521808 -292.501542) (xy 77.529703 -292.550119)
			(xy 77.530198 -292.574726) (xy 77.869046 -292.574726) (xy 77.873006 -292.525672) (xy 77.884783 -292.477888)
			(xy 77.904074 -292.432612) (xy 77.930377 -292.391016) (xy 77.963012 -292.354179) (xy 78.001133 -292.323054)
			(xy 78.043754 -292.298447) (xy 78.08977 -292.280995) (xy 78.137989 -292.271151) (xy 78.187164 -292.26917)
			(xy 78.236019 -292.275102) (xy 78.28329 -292.288794) (xy 78.327752 -292.309892) (xy 78.368255 -292.337848)
			(xy 78.403748 -292.37194) (xy 78.433313 -292.411284) (xy 78.456184 -292.454861) (xy 78.471768 -292.501542)
			(xy 78.479663 -292.550119) (xy 78.480158 -292.574726) (xy 78.819006 -292.574726) (xy 78.822966 -292.525672)
			(xy 78.834743 -292.477888) (xy 78.854034 -292.432612) (xy 78.880337 -292.391016) (xy 78.912972 -292.354179)
			(xy 78.951093 -292.323054) (xy 78.993714 -292.298447) (xy 79.03973 -292.280995) (xy 79.087949 -292.271151)
			(xy 79.137124 -292.26917) (xy 79.185979 -292.275102) (xy 79.23325 -292.288794) (xy 79.277712 -292.309892)
			(xy 79.318215 -292.337848) (xy 79.353708 -292.37194) (xy 79.383273 -292.411284) (xy 79.406144 -292.454861)
			(xy 79.421728 -292.501542) (xy 79.429623 -292.550119) (xy 79.430118 -292.574726) (xy 79.768966 -292.574726)
			(xy 79.772926 -292.525672) (xy 79.784703 -292.477888) (xy 79.803994 -292.432612) (xy 79.830297 -292.391016)
			(xy 79.862932 -292.354179) (xy 79.901053 -292.323054) (xy 79.943674 -292.298447) (xy 79.98969 -292.280995)
			(xy 80.037909 -292.271151) (xy 80.087084 -292.26917) (xy 80.135939 -292.275102) (xy 80.18321 -292.288794)
			(xy 80.227672 -292.309892) (xy 80.268175 -292.337848) (xy 80.303668 -292.37194) (xy 80.333233 -292.411284)
			(xy 80.356104 -292.454861) (xy 80.371688 -292.501542) (xy 80.379583 -292.550119) (xy 80.380078 -292.574726)
			(xy 80.71918 -292.574726) (xy 80.72314 -292.525672) (xy 80.734917 -292.477888) (xy 80.754208 -292.432612)
			(xy 80.780511 -292.391016) (xy 80.813146 -292.354179) (xy 80.851267 -292.323054) (xy 80.893888 -292.298447)
			(xy 80.939904 -292.280995) (xy 80.988123 -292.271151) (xy 81.037298 -292.26917) (xy 81.086153 -292.275102)
			(xy 81.133424 -292.288794) (xy 81.177886 -292.309892) (xy 81.218389 -292.337848) (xy 81.253882 -292.37194)
			(xy 81.283447 -292.411284) (xy 81.306318 -292.454861) (xy 81.321902 -292.501542) (xy 81.329797 -292.550119)
			(xy 81.330292 -292.574726) (xy 81.330287 -292.57498) (xy 81.66914 -292.57498) (xy 81.6731 -292.525926)
			(xy 81.684877 -292.478142) (xy 81.704168 -292.432866) (xy 81.730471 -292.39127) (xy 81.763106 -292.354433)
			(xy 81.801227 -292.323308) (xy 81.843848 -292.298701) (xy 81.889864 -292.281249) (xy 81.938083 -292.271405)
			(xy 81.987258 -292.269424) (xy 82.036113 -292.275356) (xy 82.083384 -292.289048) (xy 82.127846 -292.310146)
			(xy 82.168349 -292.338102) (xy 82.203842 -292.372194) (xy 82.233407 -292.411538) (xy 82.256278 -292.455115)
			(xy 82.271862 -292.501796) (xy 82.279757 -292.550373) (xy 82.280252 -292.57498) (xy 82.6191 -292.57498)
			(xy 82.62306 -292.525926) (xy 82.634837 -292.478142) (xy 82.654128 -292.432866) (xy 82.680431 -292.39127)
			(xy 82.713066 -292.354433) (xy 82.751187 -292.323308) (xy 82.793808 -292.298701) (xy 82.839824 -292.281249)
			(xy 82.888043 -292.271405) (xy 82.937218 -292.269424) (xy 82.986073 -292.275356) (xy 83.033344 -292.289048)
			(xy 83.077806 -292.310146) (xy 83.118309 -292.338102) (xy 83.153802 -292.372194) (xy 83.183367 -292.411538)
			(xy 83.206238 -292.455115) (xy 83.221822 -292.501796) (xy 83.229717 -292.550373) (xy 83.230212 -292.57498)
			(xy 83.229717 -292.599587) (xy 83.221822 -292.648164) (xy 83.206238 -292.694845) (xy 83.183367 -292.738422)
			(xy 83.153802 -292.777766) (xy 83.118309 -292.811858) (xy 83.077806 -292.839814) (xy 83.033344 -292.860912)
			(xy 82.986073 -292.874604) (xy 82.937218 -292.880536) (xy 82.888043 -292.878555) (xy 82.839824 -292.868711)
			(xy 82.793808 -292.851259) (xy 82.751187 -292.826652) (xy 82.713066 -292.795527) (xy 82.680431 -292.75869)
			(xy 82.654128 -292.717094) (xy 82.634837 -292.671818) (xy 82.62306 -292.624034) (xy 82.6191 -292.57498)
			(xy 82.280252 -292.57498) (xy 82.279757 -292.599587) (xy 82.271862 -292.648164) (xy 82.256278 -292.694845)
			(xy 82.233407 -292.738422) (xy 82.203842 -292.777766) (xy 82.168349 -292.811858) (xy 82.127846 -292.839814)
			(xy 82.083384 -292.860912) (xy 82.036113 -292.874604) (xy 81.987258 -292.880536) (xy 81.938083 -292.878555)
			(xy 81.889864 -292.868711) (xy 81.843848 -292.851259) (xy 81.801227 -292.826652) (xy 81.763106 -292.795527)
			(xy 81.730471 -292.75869) (xy 81.704168 -292.717094) (xy 81.684877 -292.671818) (xy 81.6731 -292.624034)
			(xy 81.66914 -292.57498) (xy 81.330287 -292.57498) (xy 81.329797 -292.599333) (xy 81.321902 -292.64791)
			(xy 81.306318 -292.694591) (xy 81.283447 -292.738168) (xy 81.253882 -292.777512) (xy 81.218389 -292.811604)
			(xy 81.177886 -292.83956) (xy 81.133424 -292.860658) (xy 81.086153 -292.87435) (xy 81.037298 -292.880282)
			(xy 80.988123 -292.878301) (xy 80.939904 -292.868457) (xy 80.893888 -292.851005) (xy 80.851267 -292.826398)
			(xy 80.813146 -292.795273) (xy 80.780511 -292.758436) (xy 80.754208 -292.71684) (xy 80.734917 -292.671564)
			(xy 80.72314 -292.62378) (xy 80.71918 -292.574726) (xy 80.380078 -292.574726) (xy 80.379583 -292.599333)
			(xy 80.371688 -292.64791) (xy 80.356104 -292.694591) (xy 80.333233 -292.738168) (xy 80.303668 -292.777512)
			(xy 80.268175 -292.811604) (xy 80.227672 -292.83956) (xy 80.18321 -292.860658) (xy 80.135939 -292.87435)
			(xy 80.087084 -292.880282) (xy 80.037909 -292.878301) (xy 79.98969 -292.868457) (xy 79.943674 -292.851005)
			(xy 79.901053 -292.826398) (xy 79.862932 -292.795273) (xy 79.830297 -292.758436) (xy 79.803994 -292.71684)
			(xy 79.784703 -292.671564) (xy 79.772926 -292.62378) (xy 79.768966 -292.574726) (xy 79.430118 -292.574726)
			(xy 79.429623 -292.599333) (xy 79.421728 -292.64791) (xy 79.406144 -292.694591) (xy 79.383273 -292.738168)
			(xy 79.353708 -292.777512) (xy 79.318215 -292.811604) (xy 79.277712 -292.83956) (xy 79.23325 -292.860658)
			(xy 79.185979 -292.87435) (xy 79.137124 -292.880282) (xy 79.087949 -292.878301) (xy 79.03973 -292.868457)
			(xy 78.993714 -292.851005) (xy 78.951093 -292.826398) (xy 78.912972 -292.795273) (xy 78.880337 -292.758436)
			(xy 78.854034 -292.71684) (xy 78.834743 -292.671564) (xy 78.822966 -292.62378) (xy 78.819006 -292.574726)
			(xy 78.480158 -292.574726) (xy 78.479663 -292.599333) (xy 78.471768 -292.64791) (xy 78.456184 -292.694591)
			(xy 78.433313 -292.738168) (xy 78.403748 -292.777512) (xy 78.368255 -292.811604) (xy 78.327752 -292.83956)
			(xy 78.28329 -292.860658) (xy 78.236019 -292.87435) (xy 78.187164 -292.880282) (xy 78.137989 -292.878301)
			(xy 78.08977 -292.868457) (xy 78.043754 -292.851005) (xy 78.001133 -292.826398) (xy 77.963012 -292.795273)
			(xy 77.930377 -292.758436) (xy 77.904074 -292.71684) (xy 77.884783 -292.671564) (xy 77.873006 -292.62378)
			(xy 77.869046 -292.574726) (xy 77.530198 -292.574726) (xy 77.529703 -292.599333) (xy 77.521808 -292.64791)
			(xy 77.506224 -292.694591) (xy 77.483353 -292.738168) (xy 77.453788 -292.777512) (xy 77.418295 -292.811604)
			(xy 77.377792 -292.83956) (xy 77.33333 -292.860658) (xy 77.286059 -292.87435) (xy 77.237204 -292.880282)
			(xy 77.188029 -292.878301) (xy 77.13981 -292.868457) (xy 77.093794 -292.851005) (xy 77.051173 -292.826398)
			(xy 77.013052 -292.795273) (xy 76.980417 -292.758436) (xy 76.954114 -292.71684) (xy 76.934823 -292.671564)
			(xy 76.923046 -292.62378) (xy 76.919086 -292.574726) (xy 76.580238 -292.574726) (xy 76.579743 -292.599333)
			(xy 76.571848 -292.64791) (xy 76.556264 -292.694591) (xy 76.533393 -292.738168) (xy 76.503828 -292.777512)
			(xy 76.468335 -292.811604) (xy 76.427832 -292.83956) (xy 76.38337 -292.860658) (xy 76.336099 -292.87435)
			(xy 76.287244 -292.880282) (xy 76.238069 -292.878301) (xy 76.18985 -292.868457) (xy 76.143834 -292.851005)
			(xy 76.101213 -292.826398) (xy 76.063092 -292.795273) (xy 76.030457 -292.758436) (xy 76.004154 -292.71684)
			(xy 75.984863 -292.671564) (xy 75.973086 -292.62378) (xy 75.969126 -292.574726) (xy 75.630278 -292.574726)
			(xy 75.629783 -292.599333) (xy 75.621888 -292.64791) (xy 75.606304 -292.694591) (xy 75.583433 -292.738168)
			(xy 75.553868 -292.777512) (xy 75.518375 -292.811604) (xy 75.477872 -292.83956) (xy 75.43341 -292.860658)
			(xy 75.386139 -292.87435) (xy 75.337284 -292.880282) (xy 75.288109 -292.878301) (xy 75.23989 -292.868457)
			(xy 75.193874 -292.851005) (xy 75.151253 -292.826398) (xy 75.113132 -292.795273) (xy 75.080497 -292.758436)
			(xy 75.054194 -292.71684) (xy 75.034903 -292.671564) (xy 75.023126 -292.62378) (xy 75.019166 -292.574726)
			(xy 74.680064 -292.574726) (xy 74.679569 -292.599333) (xy 74.671674 -292.64791) (xy 74.65609 -292.694591)
			(xy 74.633219 -292.738168) (xy 74.603654 -292.777512) (xy 74.568161 -292.811604) (xy 74.527658 -292.83956)
			(xy 74.483196 -292.860658) (xy 74.435925 -292.87435) (xy 74.38707 -292.880282) (xy 74.337895 -292.878301)
			(xy 74.289676 -292.868457) (xy 74.24366 -292.851005) (xy 74.201039 -292.826398) (xy 74.162918 -292.795273)
			(xy 74.130283 -292.758436) (xy 74.10398 -292.71684) (xy 74.084689 -292.671564) (xy 74.072912 -292.62378)
			(xy 74.068952 -292.574726) (xy 73.730104 -292.574726) (xy 73.729609 -292.599333) (xy 73.721714 -292.64791)
			(xy 73.70613 -292.694591) (xy 73.683259 -292.738168) (xy 73.653694 -292.777512) (xy 73.618201 -292.811604)
			(xy 73.577698 -292.83956) (xy 73.533236 -292.860658) (xy 73.485965 -292.87435) (xy 73.43711 -292.880282)
			(xy 73.387935 -292.878301) (xy 73.339716 -292.868457) (xy 73.2937 -292.851005) (xy 73.251079 -292.826398)
			(xy 73.212958 -292.795273) (xy 73.180323 -292.758436) (xy 73.15402 -292.71684) (xy 73.134729 -292.671564)
			(xy 73.122952 -292.62378) (xy 73.118992 -292.574726) (xy 72.780144 -292.574726) (xy 72.779649 -292.599333)
			(xy 72.771754 -292.64791) (xy 72.75617 -292.694591) (xy 72.733299 -292.738168) (xy 72.703734 -292.777512)
			(xy 72.668241 -292.811604) (xy 72.627738 -292.83956) (xy 72.583276 -292.860658) (xy 72.536005 -292.87435)
			(xy 72.48715 -292.880282) (xy 72.437975 -292.878301) (xy 72.389756 -292.868457) (xy 72.34374 -292.851005)
			(xy 72.301119 -292.826398) (xy 72.262998 -292.795273) (xy 72.230363 -292.758436) (xy 72.20406 -292.71684)
			(xy 72.184769 -292.671564) (xy 72.172992 -292.62378) (xy 72.169032 -292.574726) (xy 71.830184 -292.574726)
			(xy 71.829689 -292.599333) (xy 71.821794 -292.64791) (xy 71.80621 -292.694591) (xy 71.783339 -292.738168)
			(xy 71.753774 -292.777512) (xy 71.718281 -292.811604) (xy 71.677778 -292.83956) (xy 71.633316 -292.860658)
			(xy 71.586045 -292.87435) (xy 71.53719 -292.880282) (xy 71.488015 -292.878301) (xy 71.439796 -292.868457)
			(xy 71.39378 -292.851005) (xy 71.351159 -292.826398) (xy 71.313038 -292.795273) (xy 71.280403 -292.758436)
			(xy 71.2541 -292.71684) (xy 71.234809 -292.671564) (xy 71.223032 -292.62378) (xy 71.219072 -292.574726)
			(xy 70.880219 -292.574726) (xy 70.880224 -292.57498) (xy 70.879729 -292.599587) (xy 70.871834 -292.648164)
			(xy 70.85625 -292.694845) (xy 70.833379 -292.738422) (xy 70.803814 -292.777766) (xy 70.768321 -292.811858)
			(xy 70.727818 -292.839814) (xy 70.683356 -292.860912) (xy 70.636085 -292.874604) (xy 70.58723 -292.880536)
			(xy 70.538055 -292.878555) (xy 70.489836 -292.868711) (xy 70.44382 -292.851259) (xy 70.401199 -292.826652)
			(xy 70.363078 -292.795527) (xy 70.330443 -292.75869) (xy 70.30414 -292.717094) (xy 70.284849 -292.671818)
			(xy 70.273072 -292.624034) (xy 70.269112 -292.57498) (xy 69.930259 -292.57498) (xy 69.929769 -292.599333)
			(xy 69.921874 -292.64791) (xy 69.90629 -292.694591) (xy 69.883419 -292.738168) (xy 69.853854 -292.777512)
			(xy 69.818361 -292.811604) (xy 69.777858 -292.83956) (xy 69.733396 -292.860658) (xy 69.686125 -292.87435)
			(xy 69.63727 -292.880282) (xy 69.588095 -292.878301) (xy 69.539876 -292.868457) (xy 69.49386 -292.851005)
			(xy 69.451239 -292.826398) (xy 69.413118 -292.795273) (xy 69.380483 -292.758436) (xy 69.35418 -292.71684)
			(xy 69.334889 -292.671564) (xy 69.323112 -292.62378) (xy 69.319152 -292.574726) (xy 68.98005 -292.574726)
			(xy 68.979555 -292.599333) (xy 68.97166 -292.64791) (xy 68.956076 -292.694591) (xy 68.933205 -292.738168)
			(xy 68.90364 -292.777512) (xy 68.868147 -292.811604) (xy 68.827644 -292.83956) (xy 68.783182 -292.860658)
			(xy 68.735911 -292.87435) (xy 68.687056 -292.880282) (xy 68.637881 -292.878301) (xy 68.589662 -292.868457)
			(xy 68.543646 -292.851005) (xy 68.501025 -292.826398) (xy 68.462904 -292.795273) (xy 68.430269 -292.758436)
			(xy 68.403966 -292.71684) (xy 68.384675 -292.671564) (xy 68.372898 -292.62378) (xy 68.368938 -292.574726)
			(xy 68.03009 -292.574726) (xy 68.029595 -292.599333) (xy 68.0217 -292.64791) (xy 68.006116 -292.694591)
			(xy 67.983245 -292.738168) (xy 67.95368 -292.777512) (xy 67.918187 -292.811604) (xy 67.877684 -292.83956)
			(xy 67.833222 -292.860658) (xy 67.785951 -292.87435) (xy 67.737096 -292.880282) (xy 67.687921 -292.878301)
			(xy 67.639702 -292.868457) (xy 67.593686 -292.851005) (xy 67.551065 -292.826398) (xy 67.512944 -292.795273)
			(xy 67.480309 -292.758436) (xy 67.454006 -292.71684) (xy 67.434715 -292.671564) (xy 67.422938 -292.62378)
			(xy 67.418978 -292.574726) (xy 67.08013 -292.574726) (xy 67.079635 -292.599333) (xy 67.07174 -292.64791)
			(xy 67.056156 -292.694591) (xy 67.033285 -292.738168) (xy 67.00372 -292.777512) (xy 66.968227 -292.811604)
			(xy 66.927724 -292.83956) (xy 66.883262 -292.860658) (xy 66.835991 -292.87435) (xy 66.787136 -292.880282)
			(xy 66.737961 -292.878301) (xy 66.689742 -292.868457) (xy 66.643726 -292.851005) (xy 66.601105 -292.826398)
			(xy 66.562984 -292.795273) (xy 66.530349 -292.758436) (xy 66.504046 -292.71684) (xy 66.484755 -292.671564)
			(xy 66.472978 -292.62378) (xy 66.469018 -292.574726) (xy 66.13017 -292.574726) (xy 66.129675 -292.599333)
			(xy 66.12178 -292.64791) (xy 66.106196 -292.694591) (xy 66.083325 -292.738168) (xy 66.05376 -292.777512)
			(xy 66.018267 -292.811604) (xy 65.977764 -292.83956) (xy 65.933302 -292.860658) (xy 65.886031 -292.87435)
			(xy 65.837176 -292.880282) (xy 65.788001 -292.878301) (xy 65.739782 -292.868457) (xy 65.693766 -292.851005)
			(xy 65.651145 -292.826398) (xy 65.613024 -292.795273) (xy 65.580389 -292.758436) (xy 65.554086 -292.71684)
			(xy 65.534795 -292.671564) (xy 65.523018 -292.62378) (xy 65.519058 -292.574726) (xy 65.18021 -292.574726)
			(xy 65.179715 -292.599333) (xy 65.17182 -292.64791) (xy 65.156236 -292.694591) (xy 65.133365 -292.738168)
			(xy 65.1038 -292.777512) (xy 65.068307 -292.811604) (xy 65.027804 -292.83956) (xy 64.983342 -292.860658)
			(xy 64.936071 -292.87435) (xy 64.887216 -292.880282) (xy 64.838041 -292.878301) (xy 64.789822 -292.868457)
			(xy 64.743806 -292.851005) (xy 64.701185 -292.826398) (xy 64.663064 -292.795273) (xy 64.630429 -292.758436)
			(xy 64.604126 -292.71684) (xy 64.584835 -292.671564) (xy 64.573058 -292.62378) (xy 64.569098 -292.574726)
			(xy 64.23025 -292.574726) (xy 64.229755 -292.599333) (xy 64.22186 -292.64791) (xy 64.206276 -292.694591)
			(xy 64.183405 -292.738168) (xy 64.15384 -292.777512) (xy 64.118347 -292.811604) (xy 64.077844 -292.83956)
			(xy 64.033382 -292.860658) (xy 63.986111 -292.87435) (xy 63.937256 -292.880282) (xy 63.888081 -292.878301)
			(xy 63.839862 -292.868457) (xy 63.793846 -292.851005) (xy 63.751225 -292.826398) (xy 63.713104 -292.795273)
			(xy 63.680469 -292.758436) (xy 63.654166 -292.71684) (xy 63.634875 -292.671564) (xy 63.623098 -292.62378)
			(xy 63.619138 -292.574726) (xy 63.28029 -292.574726) (xy 63.279795 -292.599333) (xy 63.2719 -292.64791)
			(xy 63.256316 -292.694591) (xy 63.233445 -292.738168) (xy 63.20388 -292.777512) (xy 63.168387 -292.811604)
			(xy 63.127884 -292.83956) (xy 63.083422 -292.860658) (xy 63.036151 -292.87435) (xy 62.987296 -292.880282)
			(xy 62.938121 -292.878301) (xy 62.889902 -292.868457) (xy 62.843886 -292.851005) (xy 62.801265 -292.826398)
			(xy 62.763144 -292.795273) (xy 62.730509 -292.758436) (xy 62.704206 -292.71684) (xy 62.684915 -292.671564)
			(xy 62.673138 -292.62378) (xy 62.669178 -292.574726) (xy 62.330076 -292.574726) (xy 62.329581 -292.599333)
			(xy 62.321686 -292.64791) (xy 62.306102 -292.694591) (xy 62.283231 -292.738168) (xy 62.253666 -292.777512)
			(xy 62.218173 -292.811604) (xy 62.17767 -292.83956) (xy 62.133208 -292.860658) (xy 62.085937 -292.87435)
			(xy 62.037082 -292.880282) (xy 61.987907 -292.878301) (xy 61.939688 -292.868457) (xy 61.893672 -292.851005)
			(xy 61.851051 -292.826398) (xy 61.81293 -292.795273) (xy 61.780295 -292.758436) (xy 61.753992 -292.71684)
			(xy 61.734701 -292.671564) (xy 61.722924 -292.62378) (xy 61.718964 -292.574726) (xy 61.380116 -292.574726)
			(xy 61.379621 -292.599333) (xy 61.371726 -292.64791) (xy 61.356142 -292.694591) (xy 61.333271 -292.738168)
			(xy 61.303706 -292.777512) (xy 61.268213 -292.811604) (xy 61.22771 -292.83956) (xy 61.183248 -292.860658)
			(xy 61.135977 -292.87435) (xy 61.087122 -292.880282) (xy 61.037947 -292.878301) (xy 60.989728 -292.868457)
			(xy 60.943712 -292.851005) (xy 60.901091 -292.826398) (xy 60.86297 -292.795273) (xy 60.830335 -292.758436)
			(xy 60.804032 -292.71684) (xy 60.784741 -292.671564) (xy 60.772964 -292.62378) (xy 60.769004 -292.574726)
			(xy 60.430156 -292.574726) (xy 60.429661 -292.599333) (xy 60.421766 -292.64791) (xy 60.406182 -292.694591)
			(xy 60.383311 -292.738168) (xy 60.353746 -292.777512) (xy 60.318253 -292.811604) (xy 60.27775 -292.83956)
			(xy 60.233288 -292.860658) (xy 60.186017 -292.87435) (xy 60.137162 -292.880282) (xy 60.087987 -292.878301)
			(xy 60.039768 -292.868457) (xy 59.993752 -292.851005) (xy 59.951131 -292.826398) (xy 59.91301 -292.795273)
			(xy 59.880375 -292.758436) (xy 59.854072 -292.71684) (xy 59.834781 -292.671564) (xy 59.823004 -292.62378)
			(xy 59.819044 -292.574726) (xy 58.530231 -292.574726) (xy 58.530236 -292.57498) (xy 58.529741 -292.599587)
			(xy 58.521846 -292.648164) (xy 58.506262 -292.694845) (xy 58.483391 -292.738422) (xy 58.453826 -292.777766)
			(xy 58.418333 -292.811858) (xy 58.37783 -292.839814) (xy 58.333368 -292.860912) (xy 58.286097 -292.874604)
			(xy 58.237242 -292.880536) (xy 58.188067 -292.878555) (xy 58.139848 -292.868711) (xy 58.093832 -292.851259)
			(xy 58.051211 -292.826652) (xy 58.01309 -292.795527) (xy 57.980455 -292.75869) (xy 57.954152 -292.717094)
			(xy 57.934861 -292.671818) (xy 57.923084 -292.624034) (xy 57.919124 -292.57498) (xy 57.580276 -292.57498)
			(xy 57.579781 -292.599587) (xy 57.571886 -292.648164) (xy 57.556302 -292.694845) (xy 57.533431 -292.738422)
			(xy 57.503866 -292.777766) (xy 57.468373 -292.811858) (xy 57.42787 -292.839814) (xy 57.383408 -292.860912)
			(xy 57.336137 -292.874604) (xy 57.287282 -292.880536) (xy 57.238107 -292.878555) (xy 57.189888 -292.868711)
			(xy 57.143872 -292.851259) (xy 57.101251 -292.826652) (xy 57.06313 -292.795527) (xy 57.030495 -292.75869)
			(xy 57.004192 -292.717094) (xy 56.984901 -292.671818) (xy 56.973124 -292.624034) (xy 56.969164 -292.57498)
			(xy 56.630316 -292.57498) (xy 56.629821 -292.599587) (xy 56.621926 -292.648164) (xy 56.606342 -292.694845)
			(xy 56.583471 -292.738422) (xy 56.553906 -292.777766) (xy 56.518413 -292.811858) (xy 56.47791 -292.839814)
			(xy 56.433448 -292.860912) (xy 56.386177 -292.874604) (xy 56.337322 -292.880536) (xy 56.288147 -292.878555)
			(xy 56.239928 -292.868711) (xy 56.193912 -292.851259) (xy 56.151291 -292.826652) (xy 56.11317 -292.795527)
			(xy 56.080535 -292.75869) (xy 56.054232 -292.717094) (xy 56.034941 -292.671818) (xy 56.023164 -292.624034)
			(xy 56.019204 -292.57498) (xy 55.680102 -292.57498) (xy 55.679607 -292.599587) (xy 55.671712 -292.648164)
			(xy 55.656128 -292.694845) (xy 55.633257 -292.738422) (xy 55.603692 -292.777766) (xy 55.568199 -292.811858)
			(xy 55.527696 -292.839814) (xy 55.483234 -292.860912) (xy 55.435963 -292.874604) (xy 55.387108 -292.880536)
			(xy 55.337933 -292.878555) (xy 55.289714 -292.868711) (xy 55.243698 -292.851259) (xy 55.201077 -292.826652)
			(xy 55.162956 -292.795527) (xy 55.130321 -292.75869) (xy 55.104018 -292.717094) (xy 55.084727 -292.671818)
			(xy 55.07295 -292.624034) (xy 55.06899 -292.57498) (xy 54.730142 -292.57498) (xy 54.729647 -292.599587)
			(xy 54.721752 -292.648164) (xy 54.706168 -292.694845) (xy 54.683297 -292.738422) (xy 54.653732 -292.777766)
			(xy 54.618239 -292.811858) (xy 54.577736 -292.839814) (xy 54.533274 -292.860912) (xy 54.486003 -292.874604)
			(xy 54.437148 -292.880536) (xy 54.387973 -292.878555) (xy 54.339754 -292.868711) (xy 54.293738 -292.851259)
			(xy 54.251117 -292.826652) (xy 54.212996 -292.795527) (xy 54.180361 -292.75869) (xy 54.154058 -292.717094)
			(xy 54.134767 -292.671818) (xy 54.12299 -292.624034) (xy 54.11903 -292.57498) (xy 53.780182 -292.57498)
			(xy 53.779687 -292.599587) (xy 53.771792 -292.648164) (xy 53.756208 -292.694845) (xy 53.733337 -292.738422)
			(xy 53.703772 -292.777766) (xy 53.668279 -292.811858) (xy 53.627776 -292.839814) (xy 53.583314 -292.860912)
			(xy 53.536043 -292.874604) (xy 53.487188 -292.880536) (xy 53.438013 -292.878555) (xy 53.389794 -292.868711)
			(xy 53.343778 -292.851259) (xy 53.301157 -292.826652) (xy 53.263036 -292.795527) (xy 53.230401 -292.75869)
			(xy 53.204098 -292.717094) (xy 53.184807 -292.671818) (xy 53.17303 -292.624034) (xy 53.16907 -292.57498)
			(xy 52.830222 -292.57498) (xy 52.829727 -292.599587) (xy 52.821832 -292.648164) (xy 52.806248 -292.694845)
			(xy 52.783377 -292.738422) (xy 52.753812 -292.777766) (xy 52.718319 -292.811858) (xy 52.677816 -292.839814)
			(xy 52.633354 -292.860912) (xy 52.586083 -292.874604) (xy 52.537228 -292.880536) (xy 52.488053 -292.878555)
			(xy 52.439834 -292.868711) (xy 52.393818 -292.851259) (xy 52.351197 -292.826652) (xy 52.313076 -292.795527)
			(xy 52.280441 -292.75869) (xy 52.254138 -292.717094) (xy 52.234847 -292.671818) (xy 52.22307 -292.624034)
			(xy 52.21911 -292.57498) (xy 51.880262 -292.57498) (xy 51.879767 -292.599587) (xy 51.871872 -292.648164)
			(xy 51.856288 -292.694845) (xy 51.833417 -292.738422) (xy 51.803852 -292.777766) (xy 51.768359 -292.811858)
			(xy 51.727856 -292.839814) (xy 51.683394 -292.860912) (xy 51.636123 -292.874604) (xy 51.587268 -292.880536)
			(xy 51.538093 -292.878555) (xy 51.489874 -292.868711) (xy 51.443858 -292.851259) (xy 51.401237 -292.826652)
			(xy 51.363116 -292.795527) (xy 51.330481 -292.75869) (xy 51.304178 -292.717094) (xy 51.284887 -292.671818)
			(xy 51.27311 -292.624034) (xy 51.26915 -292.57498) (xy 50.930302 -292.57498) (xy 50.929807 -292.599587)
			(xy 50.921912 -292.648164) (xy 50.906328 -292.694845) (xy 50.883457 -292.738422) (xy 50.853892 -292.777766)
			(xy 50.818399 -292.811858) (xy 50.777896 -292.839814) (xy 50.733434 -292.860912) (xy 50.686163 -292.874604)
			(xy 50.637308 -292.880536) (xy 50.588133 -292.878555) (xy 50.539914 -292.868711) (xy 50.493898 -292.851259)
			(xy 50.451277 -292.826652) (xy 50.413156 -292.795527) (xy 50.380521 -292.75869) (xy 50.354218 -292.717094)
			(xy 50.334927 -292.671818) (xy 50.32315 -292.624034) (xy 50.31919 -292.57498) (xy 49.980083 -292.57498)
			(xy 49.979593 -292.599333) (xy 49.971698 -292.64791) (xy 49.956114 -292.694591) (xy 49.933243 -292.738168)
			(xy 49.903678 -292.777512) (xy 49.868185 -292.811604) (xy 49.827682 -292.83956) (xy 49.78322 -292.860658)
			(xy 49.735949 -292.87435) (xy 49.687094 -292.880282) (xy 49.637919 -292.878301) (xy 49.5897 -292.868457)
			(xy 49.543684 -292.851005) (xy 49.501063 -292.826398) (xy 49.462942 -292.795273) (xy 49.430307 -292.758436)
			(xy 49.404004 -292.71684) (xy 49.384713 -292.671564) (xy 49.372936 -292.62378) (xy 49.368976 -292.574726)
			(xy 49.030128 -292.574726) (xy 49.029633 -292.599333) (xy 49.021738 -292.64791) (xy 49.006154 -292.694591)
			(xy 48.983283 -292.738168) (xy 48.953718 -292.777512) (xy 48.918225 -292.811604) (xy 48.877722 -292.83956)
			(xy 48.83326 -292.860658) (xy 48.785989 -292.87435) (xy 48.737134 -292.880282) (xy 48.687959 -292.878301)
			(xy 48.63974 -292.868457) (xy 48.593724 -292.851005) (xy 48.551103 -292.826398) (xy 48.512982 -292.795273)
			(xy 48.480347 -292.758436) (xy 48.454044 -292.71684) (xy 48.434753 -292.671564) (xy 48.422976 -292.62378)
			(xy 48.419016 -292.574726) (xy 48.080163 -292.574726) (xy 48.080168 -292.57498) (xy 48.079673 -292.599587)
			(xy 48.071778 -292.648164) (xy 48.056194 -292.694845) (xy 48.033323 -292.738422) (xy 48.003758 -292.777766)
			(xy 47.968265 -292.811858) (xy 47.927762 -292.839814) (xy 47.8833 -292.860912) (xy 47.836029 -292.874604)
			(xy 47.787174 -292.880536) (xy 47.737999 -292.878555) (xy 47.68978 -292.868711) (xy 47.643764 -292.851259)
			(xy 47.601143 -292.826652) (xy 47.563022 -292.795527) (xy 47.530387 -292.75869) (xy 47.504084 -292.717094)
			(xy 47.484793 -292.671818) (xy 47.473016 -292.624034) (xy 47.469056 -292.57498) (xy 47.130208 -292.57498)
			(xy 47.129713 -292.599587) (xy 47.121818 -292.648164) (xy 47.106234 -292.694845) (xy 47.083363 -292.738422)
			(xy 47.053798 -292.777766) (xy 47.018305 -292.811858) (xy 46.977802 -292.839814) (xy 46.93334 -292.860912)
			(xy 46.886069 -292.874604) (xy 46.837214 -292.880536) (xy 46.788039 -292.878555) (xy 46.73982 -292.868711)
			(xy 46.693804 -292.851259) (xy 46.651183 -292.826652) (xy 46.613062 -292.795527) (xy 46.580427 -292.75869)
			(xy 46.554124 -292.717094) (xy 46.534833 -292.671818) (xy 46.523056 -292.624034) (xy 46.519096 -292.57498)
			(xy 46.180248 -292.57498) (xy 46.179753 -292.599587) (xy 46.171858 -292.648164) (xy 46.156274 -292.694845)
			(xy 46.133403 -292.738422) (xy 46.103838 -292.777766) (xy 46.068345 -292.811858) (xy 46.027842 -292.839814)
			(xy 45.98338 -292.860912) (xy 45.936109 -292.874604) (xy 45.887254 -292.880536) (xy 45.838079 -292.878555)
			(xy 45.78986 -292.868711) (xy 45.743844 -292.851259) (xy 45.701223 -292.826652) (xy 45.663102 -292.795527)
			(xy 45.630467 -292.75869) (xy 45.604164 -292.717094) (xy 45.584873 -292.671818) (xy 45.573096 -292.624034)
			(xy 45.569136 -292.57498) (xy 45.230288 -292.57498) (xy 45.229793 -292.599587) (xy 45.221898 -292.648164)
			(xy 45.206314 -292.694845) (xy 45.183443 -292.738422) (xy 45.153878 -292.777766) (xy 45.118385 -292.811858)
			(xy 45.077882 -292.839814) (xy 45.03342 -292.860912) (xy 44.986149 -292.874604) (xy 44.937294 -292.880536)
			(xy 44.888119 -292.878555) (xy 44.8399 -292.868711) (xy 44.793884 -292.851259) (xy 44.751263 -292.826652)
			(xy 44.713142 -292.795527) (xy 44.680507 -292.75869) (xy 44.654204 -292.717094) (xy 44.634913 -292.671818)
			(xy 44.623136 -292.624034) (xy 44.619176 -292.57498) (xy 44.280074 -292.57498) (xy 44.279579 -292.599587)
			(xy 44.271684 -292.648164) (xy 44.2561 -292.694845) (xy 44.233229 -292.738422) (xy 44.203664 -292.777766)
			(xy 44.168171 -292.811858) (xy 44.127668 -292.839814) (xy 44.083206 -292.860912) (xy 44.035935 -292.874604)
			(xy 43.98708 -292.880536) (xy 43.937905 -292.878555) (xy 43.889686 -292.868711) (xy 43.84367 -292.851259)
			(xy 43.801049 -292.826652) (xy 43.762928 -292.795527) (xy 43.730293 -292.75869) (xy 43.70399 -292.717094)
			(xy 43.684699 -292.671818) (xy 43.672922 -292.624034) (xy 43.668962 -292.57498) (xy 43.330114 -292.57498)
			(xy 43.329619 -292.599587) (xy 43.321724 -292.648164) (xy 43.30614 -292.694845) (xy 43.283269 -292.738422)
			(xy 43.253704 -292.777766) (xy 43.218211 -292.811858) (xy 43.177708 -292.839814) (xy 43.133246 -292.860912)
			(xy 43.085975 -292.874604) (xy 43.03712 -292.880536) (xy 42.987945 -292.878555) (xy 42.939726 -292.868711)
			(xy 42.89371 -292.851259) (xy 42.851089 -292.826652) (xy 42.812968 -292.795527) (xy 42.780333 -292.75869)
			(xy 42.75403 -292.717094) (xy 42.734739 -292.671818) (xy 42.722962 -292.624034) (xy 42.719002 -292.57498)
			(xy 42.430954 -292.57498) (xy 42.430456 -292.601629) (xy 42.422513 -292.654333) (xy 42.406803 -292.705263)
			(xy 42.383677 -292.753284) (xy 42.353653 -292.797321) (xy 42.317401 -292.836392) (xy 42.27573 -292.869623)
			(xy 42.229572 -292.896272) (xy 42.179958 -292.915744) (xy 42.127996 -292.927604) (xy 42.074846 -292.931588)
			(xy 42.021696 -292.927604) (xy 41.969734 -292.915744) (xy 41.92012 -292.896272) (xy 41.873962 -292.869623)
			(xy 41.832291 -292.836392) (xy 41.796039 -292.797321) (xy 41.766015 -292.753284) (xy 41.742889 -292.705263)
			(xy 41.727179 -292.654333) (xy 41.719236 -292.601629) (xy 41.429367 -292.601629) (xy 41.421804 -292.648164)
			(xy 41.40622 -292.694845) (xy 41.383349 -292.738422) (xy 41.353784 -292.777766) (xy 41.318291 -292.811858)
			(xy 41.277788 -292.839814) (xy 41.233326 -292.860912) (xy 41.186055 -292.874604) (xy 41.1372 -292.880536)
			(xy 41.088025 -292.878555) (xy 41.039806 -292.868711) (xy 40.99379 -292.851259) (xy 40.951169 -292.826652)
			(xy 40.913048 -292.795527) (xy 40.880413 -292.75869) (xy 40.85411 -292.717094) (xy 40.834819 -292.671818)
			(xy 40.823042 -292.624034) (xy 40.819082 -292.57498) (xy 40.480229 -292.57498) (xy 40.479739 -292.599333)
			(xy 40.471844 -292.64791) (xy 40.45626 -292.694591) (xy 40.433389 -292.738168) (xy 40.403824 -292.777512)
			(xy 40.368331 -292.811604) (xy 40.327828 -292.83956) (xy 40.283366 -292.860658) (xy 40.236095 -292.87435)
			(xy 40.18724 -292.880282) (xy 40.138065 -292.878301) (xy 40.089846 -292.868457) (xy 40.04383 -292.851005)
			(xy 40.001209 -292.826398) (xy 39.963088 -292.795273) (xy 39.930453 -292.758436) (xy 39.90415 -292.71684)
			(xy 39.884859 -292.671564) (xy 39.873082 -292.62378) (xy 39.869122 -292.574726) (xy 39.530274 -292.574726)
			(xy 39.52984 -292.598504) (xy 39.522475 -292.645487) (xy 39.507911 -292.690759) (xy 39.486501 -292.733224)
			(xy 39.458764 -292.771853) (xy 39.44239 -292.789102) (xy 39.436441 -292.795683) (xy 39.429048 -292.811798)
			(xy 39.427912 -292.820598) (xy 39.425372 -292.851586) (xy 39.424976 -292.860568) (xy 39.429795 -292.877878)
			(xy 39.43477 -292.885368) (xy 39.448136 -292.904837) (xy 39.469395 -292.947) (xy 39.483911 -292.991934)
			(xy 39.491337 -293.038567) (xy 39.491495 -293.085787) (xy 39.484383 -293.132468) (xy 39.477696 -293.155116)
			(xy 39.453058 -293.233094) (xy 39.450599 -293.242056) (xy 39.451641 -293.260597) (xy 39.459227 -293.277547)
			(xy 39.465504 -293.284402) (xy 39.472337 -293.290706) (xy 39.489295 -293.298291) (xy 39.507844 -293.299302)
			(xy 39.516812 -293.296848) (xy 39.66337 -293.25062) (xy 39.670146 -293.248755) (xy 39.68419 -293.248361)
			(xy 39.691056 -293.249858) (xy 39.842694 -293.287704) (xy 39.847774 -293.292784) (xy 39.864792 -293.30015)
			(xy 39.95293 -293.303706) (xy 39.970964 -293.29761) (xy 39.978076 -293.291514) (xy 39.998899 -293.274699)
			(xy 40.0452 -293.247863) (xy 40.095469 -293.229505) (xy 40.148168 -293.220185) (xy 40.174926 -293.219632)
			(xy 40.200572 -293.220147) (xy 40.251145 -293.228707) (xy 40.299575 -293.245599) (xy 40.344502 -293.270347)
			(xy 40.38466 -293.302255) (xy 40.418921 -293.340426) (xy 40.446321 -293.383786) (xy 40.466089 -293.431116)
			(xy 40.477669 -293.481083) (xy 40.479726 -293.506652) (xy 40.480742 -293.525194) (xy 40.506904 -293.552372)
			(xy 40.518334 -293.553388) (xy 40.521382 -293.556182) (xy 40.52873 -293.562699) (xy 40.54688 -293.570155)
			(xy 40.556688 -293.57066) (xy 40.74287 -293.57066) (xy 40.752774 -293.570165) (xy 40.771074 -293.562578)
			(xy 40.77843 -293.555928) (xy 40.805862 -293.529004) (xy 40.811904 -293.522512) (xy 40.819577 -293.506539)
			(xy 40.820848 -293.497762) (xy 40.820848 -293.497254) (xy 40.823668 -293.472291) (xy 40.836345 -293.423686)
			(xy 40.856809 -293.377811) (xy 40.884506 -293.335906) (xy 40.91869 -293.2991) (xy 40.958438 -293.268387)
			(xy 41.002679 -293.244596) (xy 41.050217 -293.228369) (xy 41.09977 -293.220143) (xy 41.124886 -293.219632)
			(xy 41.150531 -293.220184) (xy 41.201102 -293.228737) (xy 41.249532 -293.245623) (xy 41.294458 -293.270366)
			(xy 41.334617 -293.302269) (xy 41.368879 -293.340437) (xy 41.39628 -293.383793) (xy 41.416048 -293.43112)
			(xy 41.427629 -293.481085) (xy 41.429686 -293.506652) (xy 41.430702 -293.525194) (xy 41.456864 -293.552372)
			(xy 41.468294 -293.553388) (xy 41.471342 -293.556182) (xy 41.47867 -293.562725) (xy 41.496835 -293.570166)
			(xy 41.506648 -293.57066) (xy 41.69283 -293.57066) (xy 41.702731 -293.570144) (xy 41.721032 -293.562572)
			(xy 41.72839 -293.555928) (xy 41.755822 -293.529004) (xy 41.761873 -293.522519) (xy 41.76954 -293.50654)
			(xy 41.770808 -293.497762) (xy 41.770808 -293.497254) (xy 41.77357 -293.472283) (xy 41.78625 -293.423672)
			(xy 41.806719 -293.377793) (xy 41.834422 -293.335885) (xy 41.868614 -293.299078) (xy 41.908371 -293.268366)
			(xy 41.95262 -293.244578) (xy 42.000166 -293.228357) (xy 42.049727 -293.220139) (xy 42.074846 -293.219632)
			(xy 42.100493 -293.220129) (xy 42.151066 -293.228692) (xy 42.199497 -293.245586) (xy 42.244423 -293.270337)
			(xy 42.284582 -293.302248) (xy 42.318842 -293.340421) (xy 42.346242 -293.383783) (xy 42.366009 -293.431114)
			(xy 42.377589 -293.481083) (xy 42.379646 -293.506652) (xy 42.380662 -293.525194) (xy 42.406824 -293.552372)
			(xy 42.418254 -293.553388) (xy 42.421302 -293.556182) (xy 42.428644 -293.562708) (xy 42.446799 -293.570159)
			(xy 42.456608 -293.57066) (xy 42.63898 -293.57066) (xy 42.668444 -293.54145) (xy 42.668698 -293.520622)
			(xy 42.669501 -293.494184) (xy 42.677957 -293.441972) (xy 42.694043 -293.391586) (xy 42.717404 -293.344132)
			(xy 42.747526 -293.300656) (xy 42.783747 -293.262113) (xy 42.82527 -293.229351) (xy 42.871182 -293.20309)
			(xy 42.920474 -293.183909) (xy 42.97206 -293.172228) (xy 43.024806 -293.168306) (xy 43.077552 -293.172228)
			(xy 43.129138 -293.183909) (xy 43.17843 -293.20309) (xy 43.224342 -293.229351) (xy 43.265865 -293.262113)
			(xy 43.302086 -293.300656) (xy 43.332208 -293.344132) (xy 43.355569 -293.391586) (xy 43.371655 -293.441972)
			(xy 43.380111 -293.494184) (xy 43.380914 -293.520622) (xy 43.381168 -293.54145) (xy 43.410632 -293.57066)
			(xy 43.59275 -293.57066) (xy 43.602652 -293.570154) (xy 43.620953 -293.562575) (xy 43.62831 -293.555928)
			(xy 43.655742 -293.529004) (xy 43.661796 -293.522521) (xy 43.66946 -293.506541) (xy 43.670728 -293.497762)
			(xy 43.670728 -293.497254) (xy 43.673568 -293.472294) (xy 43.686244 -293.42369) (xy 43.706705 -293.377817)
			(xy 43.7344 -293.335913) (xy 43.768582 -293.299107) (xy 43.808328 -293.268394) (xy 43.852565 -293.244602)
			(xy 43.9001 -293.228373) (xy 43.949651 -293.220145) (xy 43.974766 -293.219632) (xy 44.000413 -293.220111)
			(xy 44.050987 -293.228677) (xy 44.099419 -293.245574) (xy 44.144345 -293.270327) (xy 44.184503 -293.30224)
			(xy 44.218763 -293.340416) (xy 44.246162 -293.383779) (xy 44.26593 -293.431112) (xy 44.277509 -293.481082)
			(xy 44.279566 -293.506652) (xy 44.280582 -293.525194) (xy 44.306744 -293.552372) (xy 44.318174 -293.553388)
			(xy 44.321222 -293.556182) (xy 44.328557 -293.562717) (xy 44.346717 -293.570162) (xy 44.356528 -293.57066)
			(xy 45.492924 -293.57066) (xy 45.502825 -293.570141) (xy 45.521126 -293.562571) (xy 45.528484 -293.555928)
			(xy 45.555916 -293.529004) (xy 45.561966 -293.522518) (xy 45.569633 -293.50654) (xy 45.570902 -293.497762)
			(xy 45.570902 -293.497254) (xy 45.57367 -293.472284) (xy 45.58635 -293.423673) (xy 45.606818 -293.377795)
			(xy 45.634521 -293.335887) (xy 45.668712 -293.29908) (xy 45.708468 -293.268368) (xy 45.752716 -293.24458)
			(xy 45.800261 -293.228358) (xy 45.849821 -293.220139) (xy 45.87494 -293.219632) (xy 45.900586 -293.220134)
			(xy 45.951159 -293.228696) (xy 45.99959 -293.24559) (xy 46.044517 -293.27034) (xy 46.084675 -293.30225)
			(xy 46.118936 -293.340422) (xy 46.146336 -293.383784) (xy 46.166103 -293.431114) (xy 46.177683 -293.481083)
			(xy 46.17974 -293.506652) (xy 46.180742 -293.52494) (xy 47.469056 -293.52494) (xy 47.473016 -293.475886)
			(xy 47.484793 -293.428102) (xy 47.504084 -293.382826) (xy 47.530387 -293.34123) (xy 47.563022 -293.304393)
			(xy 47.601143 -293.273268) (xy 47.643764 -293.248661) (xy 47.68978 -293.231209) (xy 47.737999 -293.221365)
			(xy 47.787174 -293.219384) (xy 47.836029 -293.225316) (xy 47.8833 -293.239008) (xy 47.927762 -293.260106)
			(xy 47.968265 -293.288062) (xy 48.003758 -293.322154) (xy 48.033323 -293.361498) (xy 48.056194 -293.405075)
			(xy 48.071778 -293.451756) (xy 48.079673 -293.500333) (xy 48.080168 -293.52494) (xy 48.419016 -293.52494)
			(xy 48.422976 -293.475886) (xy 48.434753 -293.428102) (xy 48.454044 -293.382826) (xy 48.480347 -293.34123)
			(xy 48.512982 -293.304393) (xy 48.551103 -293.273268) (xy 48.593724 -293.248661) (xy 48.63974 -293.231209)
			(xy 48.687959 -293.221365) (xy 48.737134 -293.219384) (xy 48.785989 -293.225316) (xy 48.83326 -293.239008)
			(xy 48.877722 -293.260106) (xy 48.918225 -293.288062) (xy 48.953718 -293.322154) (xy 48.983283 -293.361498)
			(xy 49.006154 -293.405075) (xy 49.021738 -293.451756) (xy 49.029633 -293.500333) (xy 49.030128 -293.52494)
			(xy 49.368976 -293.52494) (xy 49.372936 -293.475886) (xy 49.384713 -293.428102) (xy 49.404004 -293.382826)
			(xy 49.430307 -293.34123) (xy 49.462942 -293.304393) (xy 49.501063 -293.273268) (xy 49.543684 -293.248661)
			(xy 49.5897 -293.231209) (xy 49.637919 -293.221365) (xy 49.687094 -293.219384) (xy 49.735949 -293.225316)
			(xy 49.78322 -293.239008) (xy 49.827682 -293.260106) (xy 49.868185 -293.288062) (xy 49.903678 -293.322154)
			(xy 49.933243 -293.361498) (xy 49.956114 -293.405075) (xy 49.971698 -293.451756) (xy 49.979593 -293.500333)
			(xy 49.980088 -293.52494) (xy 50.31919 -293.52494) (xy 50.32315 -293.475886) (xy 50.334927 -293.428102)
			(xy 50.354218 -293.382826) (xy 50.380521 -293.34123) (xy 50.413156 -293.304393) (xy 50.451277 -293.273268)
			(xy 50.493898 -293.248661) (xy 50.539914 -293.231209) (xy 50.588133 -293.221365) (xy 50.637308 -293.219384)
			(xy 50.686163 -293.225316) (xy 50.733434 -293.239008) (xy 50.777896 -293.260106) (xy 50.818399 -293.288062)
			(xy 50.853892 -293.322154) (xy 50.883457 -293.361498) (xy 50.906328 -293.405075) (xy 50.921912 -293.451756)
			(xy 50.929807 -293.500333) (xy 50.930302 -293.52494) (xy 51.26915 -293.52494) (xy 51.27311 -293.475886)
			(xy 51.284887 -293.428102) (xy 51.304178 -293.382826) (xy 51.330481 -293.34123) (xy 51.363116 -293.304393)
			(xy 51.401237 -293.273268) (xy 51.443858 -293.248661) (xy 51.489874 -293.231209) (xy 51.538093 -293.221365)
			(xy 51.587268 -293.219384) (xy 51.636123 -293.225316) (xy 51.683394 -293.239008) (xy 51.727856 -293.260106)
			(xy 51.768359 -293.288062) (xy 51.803852 -293.322154) (xy 51.833417 -293.361498) (xy 51.856288 -293.405075)
			(xy 51.871872 -293.451756) (xy 51.879767 -293.500333) (xy 51.880262 -293.52494) (xy 52.21911 -293.52494)
			(xy 52.22307 -293.475886) (xy 52.234847 -293.428102) (xy 52.254138 -293.382826) (xy 52.280441 -293.34123)
			(xy 52.313076 -293.304393) (xy 52.351197 -293.273268) (xy 52.393818 -293.248661) (xy 52.439834 -293.231209)
			(xy 52.488053 -293.221365) (xy 52.537228 -293.219384) (xy 52.586083 -293.225316) (xy 52.633354 -293.239008)
			(xy 52.677816 -293.260106) (xy 52.718319 -293.288062) (xy 52.753812 -293.322154) (xy 52.783377 -293.361498)
			(xy 52.806248 -293.405075) (xy 52.821832 -293.451756) (xy 52.829727 -293.500333) (xy 52.830222 -293.52494)
			(xy 53.16907 -293.52494) (xy 53.17303 -293.475886) (xy 53.184807 -293.428102) (xy 53.204098 -293.382826)
			(xy 53.230401 -293.34123) (xy 53.263036 -293.304393) (xy 53.301157 -293.273268) (xy 53.343778 -293.248661)
			(xy 53.389794 -293.231209) (xy 53.438013 -293.221365) (xy 53.487188 -293.219384) (xy 53.536043 -293.225316)
			(xy 53.583314 -293.239008) (xy 53.627776 -293.260106) (xy 53.668279 -293.288062) (xy 53.703772 -293.322154)
			(xy 53.733337 -293.361498) (xy 53.756208 -293.405075) (xy 53.771792 -293.451756) (xy 53.779687 -293.500333)
			(xy 53.780182 -293.52494) (xy 54.11903 -293.52494) (xy 54.12299 -293.475886) (xy 54.134767 -293.428102)
			(xy 54.154058 -293.382826) (xy 54.180361 -293.34123) (xy 54.212996 -293.304393) (xy 54.251117 -293.273268)
			(xy 54.293738 -293.248661) (xy 54.339754 -293.231209) (xy 54.387973 -293.221365) (xy 54.437148 -293.219384)
			(xy 54.486003 -293.225316) (xy 54.533274 -293.239008) (xy 54.577736 -293.260106) (xy 54.618239 -293.288062)
			(xy 54.653732 -293.322154) (xy 54.683297 -293.361498) (xy 54.706168 -293.405075) (xy 54.721752 -293.451756)
			(xy 54.729647 -293.500333) (xy 54.730142 -293.52494) (xy 55.06899 -293.52494) (xy 55.07295 -293.475886)
			(xy 55.084727 -293.428102) (xy 55.104018 -293.382826) (xy 55.130321 -293.34123) (xy 55.162956 -293.304393)
			(xy 55.201077 -293.273268) (xy 55.243698 -293.248661) (xy 55.289714 -293.231209) (xy 55.337933 -293.221365)
			(xy 55.387108 -293.219384) (xy 55.435963 -293.225316) (xy 55.483234 -293.239008) (xy 55.527696 -293.260106)
			(xy 55.568199 -293.288062) (xy 55.603692 -293.322154) (xy 55.633257 -293.361498) (xy 55.656128 -293.405075)
			(xy 55.671712 -293.451756) (xy 55.679607 -293.500333) (xy 55.680102 -293.52494) (xy 56.01895 -293.52494)
			(xy 56.02291 -293.475886) (xy 56.034687 -293.428102) (xy 56.053978 -293.382826) (xy 56.080281 -293.34123)
			(xy 56.112916 -293.304393) (xy 56.151037 -293.273268) (xy 56.193658 -293.248661) (xy 56.239674 -293.231209)
			(xy 56.287893 -293.221365) (xy 56.337068 -293.219384) (xy 56.385923 -293.225316) (xy 56.433194 -293.239008)
			(xy 56.477656 -293.260106) (xy 56.518159 -293.288062) (xy 56.553652 -293.322154) (xy 56.583217 -293.361498)
			(xy 56.606088 -293.405075) (xy 56.621672 -293.451756) (xy 56.629567 -293.500333) (xy 56.630062 -293.52494)
			(xy 56.969164 -293.52494) (xy 56.973124 -293.475886) (xy 56.984901 -293.428102) (xy 57.004192 -293.382826)
			(xy 57.030495 -293.34123) (xy 57.06313 -293.304393) (xy 57.101251 -293.273268) (xy 57.143872 -293.248661)
			(xy 57.189888 -293.231209) (xy 57.238107 -293.221365) (xy 57.287282 -293.219384) (xy 57.336137 -293.225316)
			(xy 57.383408 -293.239008) (xy 57.42787 -293.260106) (xy 57.468373 -293.288062) (xy 57.503866 -293.322154)
			(xy 57.533431 -293.361498) (xy 57.556302 -293.405075) (xy 57.571886 -293.451756) (xy 57.579781 -293.500333)
			(xy 57.580276 -293.52494) (xy 57.919124 -293.52494) (xy 57.923084 -293.475886) (xy 57.934861 -293.428102)
			(xy 57.954152 -293.382826) (xy 57.980455 -293.34123) (xy 58.01309 -293.304393) (xy 58.051211 -293.273268)
			(xy 58.093832 -293.248661) (xy 58.139848 -293.231209) (xy 58.188067 -293.221365) (xy 58.237242 -293.219384)
			(xy 58.286097 -293.225316) (xy 58.333368 -293.239008) (xy 58.37783 -293.260106) (xy 58.418333 -293.288062)
			(xy 58.453826 -293.322154) (xy 58.483391 -293.361498) (xy 58.506262 -293.405075) (xy 58.521846 -293.451756)
			(xy 58.529741 -293.500333) (xy 58.530236 -293.52494) (xy 59.819044 -293.52494) (xy 59.823004 -293.475886)
			(xy 59.834781 -293.428102) (xy 59.854072 -293.382826) (xy 59.880375 -293.34123) (xy 59.91301 -293.304393)
			(xy 59.951131 -293.273268) (xy 59.993752 -293.248661) (xy 60.039768 -293.231209) (xy 60.087987 -293.221365)
			(xy 60.137162 -293.219384) (xy 60.186017 -293.225316) (xy 60.233288 -293.239008) (xy 60.27775 -293.260106)
			(xy 60.318253 -293.288062) (xy 60.353746 -293.322154) (xy 60.383311 -293.361498) (xy 60.406182 -293.405075)
			(xy 60.421766 -293.451756) (xy 60.429661 -293.500333) (xy 60.430156 -293.52494) (xy 60.769004 -293.52494)
			(xy 60.772964 -293.475886) (xy 60.784741 -293.428102) (xy 60.804032 -293.382826) (xy 60.830335 -293.34123)
			(xy 60.86297 -293.304393) (xy 60.901091 -293.273268) (xy 60.943712 -293.248661) (xy 60.989728 -293.231209)
			(xy 61.037947 -293.221365) (xy 61.087122 -293.219384) (xy 61.135977 -293.225316) (xy 61.183248 -293.239008)
			(xy 61.22771 -293.260106) (xy 61.268213 -293.288062) (xy 61.303706 -293.322154) (xy 61.333271 -293.361498)
			(xy 61.356142 -293.405075) (xy 61.371726 -293.451756) (xy 61.379621 -293.500333) (xy 61.380116 -293.52494)
			(xy 61.718964 -293.52494) (xy 61.722924 -293.475886) (xy 61.734701 -293.428102) (xy 61.753992 -293.382826)
			(xy 61.780295 -293.34123) (xy 61.81293 -293.304393) (xy 61.851051 -293.273268) (xy 61.893672 -293.248661)
			(xy 61.939688 -293.231209) (xy 61.987907 -293.221365) (xy 62.037082 -293.219384) (xy 62.085937 -293.225316)
			(xy 62.133208 -293.239008) (xy 62.17767 -293.260106) (xy 62.218173 -293.288062) (xy 62.253666 -293.322154)
			(xy 62.283231 -293.361498) (xy 62.306102 -293.405075) (xy 62.321686 -293.451756) (xy 62.329581 -293.500333)
			(xy 62.330076 -293.52494) (xy 62.669178 -293.52494) (xy 62.673138 -293.475886) (xy 62.684915 -293.428102)
			(xy 62.704206 -293.382826) (xy 62.730509 -293.34123) (xy 62.763144 -293.304393) (xy 62.801265 -293.273268)
			(xy 62.843886 -293.248661) (xy 62.889902 -293.231209) (xy 62.938121 -293.221365) (xy 62.987296 -293.219384)
			(xy 63.036151 -293.225316) (xy 63.083422 -293.239008) (xy 63.127884 -293.260106) (xy 63.168387 -293.288062)
			(xy 63.20388 -293.322154) (xy 63.233445 -293.361498) (xy 63.256316 -293.405075) (xy 63.2719 -293.451756)
			(xy 63.279795 -293.500333) (xy 63.28029 -293.52494) (xy 63.619138 -293.52494) (xy 63.623098 -293.475886)
			(xy 63.634875 -293.428102) (xy 63.654166 -293.382826) (xy 63.680469 -293.34123) (xy 63.713104 -293.304393)
			(xy 63.751225 -293.273268) (xy 63.793846 -293.248661) (xy 63.839862 -293.231209) (xy 63.888081 -293.221365)
			(xy 63.937256 -293.219384) (xy 63.986111 -293.225316) (xy 64.033382 -293.239008) (xy 64.077844 -293.260106)
			(xy 64.118347 -293.288062) (xy 64.15384 -293.322154) (xy 64.183405 -293.361498) (xy 64.206276 -293.405075)
			(xy 64.22186 -293.451756) (xy 64.229755 -293.500333) (xy 64.23025 -293.52494) (xy 64.569098 -293.52494)
			(xy 64.573058 -293.475886) (xy 64.584835 -293.428102) (xy 64.604126 -293.382826) (xy 64.630429 -293.34123)
			(xy 64.663064 -293.304393) (xy 64.701185 -293.273268) (xy 64.743806 -293.248661) (xy 64.789822 -293.231209)
			(xy 64.838041 -293.221365) (xy 64.887216 -293.219384) (xy 64.936071 -293.225316) (xy 64.983342 -293.239008)
			(xy 65.027804 -293.260106) (xy 65.068307 -293.288062) (xy 65.1038 -293.322154) (xy 65.133365 -293.361498)
			(xy 65.156236 -293.405075) (xy 65.17182 -293.451756) (xy 65.179715 -293.500333) (xy 65.18021 -293.52494)
			(xy 65.519058 -293.52494) (xy 65.523018 -293.475886) (xy 65.534795 -293.428102) (xy 65.554086 -293.382826)
			(xy 65.580389 -293.34123) (xy 65.613024 -293.304393) (xy 65.651145 -293.273268) (xy 65.693766 -293.248661)
			(xy 65.739782 -293.231209) (xy 65.788001 -293.221365) (xy 65.837176 -293.219384) (xy 65.886031 -293.225316)
			(xy 65.933302 -293.239008) (xy 65.977764 -293.260106) (xy 66.018267 -293.288062) (xy 66.05376 -293.322154)
			(xy 66.083325 -293.361498) (xy 66.106196 -293.405075) (xy 66.12178 -293.451756) (xy 66.129675 -293.500333)
			(xy 66.13017 -293.52494) (xy 66.469018 -293.52494) (xy 66.472978 -293.475886) (xy 66.484755 -293.428102)
			(xy 66.504046 -293.382826) (xy 66.530349 -293.34123) (xy 66.562984 -293.304393) (xy 66.601105 -293.273268)
			(xy 66.643726 -293.248661) (xy 66.689742 -293.231209) (xy 66.737961 -293.221365) (xy 66.787136 -293.219384)
			(xy 66.835991 -293.225316) (xy 66.883262 -293.239008) (xy 66.927724 -293.260106) (xy 66.968227 -293.288062)
			(xy 67.00372 -293.322154) (xy 67.033285 -293.361498) (xy 67.056156 -293.405075) (xy 67.07174 -293.451756)
			(xy 67.079635 -293.500333) (xy 67.08013 -293.52494) (xy 67.418978 -293.52494) (xy 67.422938 -293.475886)
			(xy 67.434715 -293.428102) (xy 67.454006 -293.382826) (xy 67.480309 -293.34123) (xy 67.512944 -293.304393)
			(xy 67.551065 -293.273268) (xy 67.593686 -293.248661) (xy 67.639702 -293.231209) (xy 67.687921 -293.221365)
			(xy 67.737096 -293.219384) (xy 67.785951 -293.225316) (xy 67.833222 -293.239008) (xy 67.877684 -293.260106)
			(xy 67.918187 -293.288062) (xy 67.95368 -293.322154) (xy 67.983245 -293.361498) (xy 68.006116 -293.405075)
			(xy 68.0217 -293.451756) (xy 68.029595 -293.500333) (xy 68.03009 -293.52494) (xy 68.368938 -293.52494)
			(xy 68.372898 -293.475886) (xy 68.384675 -293.428102) (xy 68.403966 -293.382826) (xy 68.430269 -293.34123)
			(xy 68.462904 -293.304393) (xy 68.501025 -293.273268) (xy 68.543646 -293.248661) (xy 68.589662 -293.231209)
			(xy 68.637881 -293.221365) (xy 68.687056 -293.219384) (xy 68.735911 -293.225316) (xy 68.783182 -293.239008)
			(xy 68.827644 -293.260106) (xy 68.868147 -293.288062) (xy 68.90364 -293.322154) (xy 68.933205 -293.361498)
			(xy 68.956076 -293.405075) (xy 68.97166 -293.451756) (xy 68.979555 -293.500333) (xy 68.98005 -293.52494)
			(xy 69.319152 -293.52494) (xy 69.323112 -293.475886) (xy 69.334889 -293.428102) (xy 69.35418 -293.382826)
			(xy 69.380483 -293.34123) (xy 69.413118 -293.304393) (xy 69.451239 -293.273268) (xy 69.49386 -293.248661)
			(xy 69.539876 -293.231209) (xy 69.588095 -293.221365) (xy 69.63727 -293.219384) (xy 69.686125 -293.225316)
			(xy 69.733396 -293.239008) (xy 69.777858 -293.260106) (xy 69.818361 -293.288062) (xy 69.853854 -293.322154)
			(xy 69.883419 -293.361498) (xy 69.90629 -293.405075) (xy 69.921874 -293.451756) (xy 69.929769 -293.500333)
			(xy 69.930264 -293.52494) (xy 70.269112 -293.52494) (xy 70.273072 -293.475886) (xy 70.284849 -293.428102)
			(xy 70.30414 -293.382826) (xy 70.330443 -293.34123) (xy 70.363078 -293.304393) (xy 70.401199 -293.273268)
			(xy 70.44382 -293.248661) (xy 70.489836 -293.231209) (xy 70.538055 -293.221365) (xy 70.58723 -293.219384)
			(xy 70.636085 -293.225316) (xy 70.683356 -293.239008) (xy 70.727818 -293.260106) (xy 70.768321 -293.288062)
			(xy 70.803814 -293.322154) (xy 70.833379 -293.361498) (xy 70.85625 -293.405075) (xy 70.871834 -293.451756)
			(xy 70.879729 -293.500333) (xy 70.880224 -293.52494) (xy 71.219072 -293.52494) (xy 71.223032 -293.475886)
			(xy 71.234809 -293.428102) (xy 71.2541 -293.382826) (xy 71.280403 -293.34123) (xy 71.313038 -293.304393)
			(xy 71.351159 -293.273268) (xy 71.39378 -293.248661) (xy 71.439796 -293.231209) (xy 71.488015 -293.221365)
			(xy 71.53719 -293.219384) (xy 71.586045 -293.225316) (xy 71.633316 -293.239008) (xy 71.677778 -293.260106)
			(xy 71.718281 -293.288062) (xy 71.753774 -293.322154) (xy 71.783339 -293.361498) (xy 71.80621 -293.405075)
			(xy 71.821794 -293.451756) (xy 71.829689 -293.500333) (xy 71.830184 -293.52494) (xy 73.118992 -293.52494)
			(xy 73.122952 -293.475886) (xy 73.134729 -293.428102) (xy 73.15402 -293.382826) (xy 73.180323 -293.34123)
			(xy 73.212958 -293.304393) (xy 73.251079 -293.273268) (xy 73.2937 -293.248661) (xy 73.339716 -293.231209)
			(xy 73.387935 -293.221365) (xy 73.43711 -293.219384) (xy 73.485965 -293.225316) (xy 73.533236 -293.239008)
			(xy 73.577698 -293.260106) (xy 73.618201 -293.288062) (xy 73.653694 -293.322154) (xy 73.683259 -293.361498)
			(xy 73.70613 -293.405075) (xy 73.721714 -293.451756) (xy 73.729609 -293.500333) (xy 73.730104 -293.52494)
			(xy 74.069206 -293.52494) (xy 74.073166 -293.475886) (xy 74.084943 -293.428102) (xy 74.104234 -293.382826)
			(xy 74.130537 -293.34123) (xy 74.163172 -293.304393) (xy 74.201293 -293.273268) (xy 74.243914 -293.248661)
			(xy 74.28993 -293.231209) (xy 74.338149 -293.221365) (xy 74.387324 -293.219384) (xy 74.436179 -293.225316)
			(xy 74.48345 -293.239008) (xy 74.527912 -293.260106) (xy 74.568415 -293.288062) (xy 74.603908 -293.322154)
			(xy 74.633473 -293.361498) (xy 74.656344 -293.405075) (xy 74.671928 -293.451756) (xy 74.679823 -293.500333)
			(xy 74.680318 -293.52494) (xy 75.019166 -293.52494) (xy 75.023126 -293.475886) (xy 75.034903 -293.428102)
			(xy 75.054194 -293.382826) (xy 75.080497 -293.34123) (xy 75.113132 -293.304393) (xy 75.151253 -293.273268)
			(xy 75.193874 -293.248661) (xy 75.23989 -293.231209) (xy 75.288109 -293.221365) (xy 75.337284 -293.219384)
			(xy 75.386139 -293.225316) (xy 75.43341 -293.239008) (xy 75.477872 -293.260106) (xy 75.518375 -293.288062)
			(xy 75.553868 -293.322154) (xy 75.583433 -293.361498) (xy 75.606304 -293.405075) (xy 75.621888 -293.451756)
			(xy 75.629783 -293.500333) (xy 75.630278 -293.52494) (xy 75.969126 -293.52494) (xy 75.973086 -293.475886)
			(xy 75.984863 -293.428102) (xy 76.004154 -293.382826) (xy 76.030457 -293.34123) (xy 76.063092 -293.304393)
			(xy 76.101213 -293.273268) (xy 76.143834 -293.248661) (xy 76.18985 -293.231209) (xy 76.238069 -293.221365)
			(xy 76.287244 -293.219384) (xy 76.336099 -293.225316) (xy 76.38337 -293.239008) (xy 76.427832 -293.260106)
			(xy 76.468335 -293.288062) (xy 76.503828 -293.322154) (xy 76.533393 -293.361498) (xy 76.556264 -293.405075)
			(xy 76.571848 -293.451756) (xy 76.579743 -293.500333) (xy 76.580238 -293.52494) (xy 76.919086 -293.52494)
			(xy 76.923046 -293.475886) (xy 76.934823 -293.428102) (xy 76.954114 -293.382826) (xy 76.980417 -293.34123)
			(xy 77.013052 -293.304393) (xy 77.051173 -293.273268) (xy 77.093794 -293.248661) (xy 77.13981 -293.231209)
			(xy 77.188029 -293.221365) (xy 77.237204 -293.219384) (xy 77.286059 -293.225316) (xy 77.33333 -293.239008)
			(xy 77.377792 -293.260106) (xy 77.418295 -293.288062) (xy 77.453788 -293.322154) (xy 77.483353 -293.361498)
			(xy 77.506224 -293.405075) (xy 77.521808 -293.451756) (xy 77.529703 -293.500333) (xy 77.530198 -293.52494)
			(xy 77.869046 -293.52494) (xy 77.873006 -293.475886) (xy 77.884783 -293.428102) (xy 77.904074 -293.382826)
			(xy 77.930377 -293.34123) (xy 77.963012 -293.304393) (xy 78.001133 -293.273268) (xy 78.043754 -293.248661)
			(xy 78.08977 -293.231209) (xy 78.137989 -293.221365) (xy 78.187164 -293.219384) (xy 78.236019 -293.225316)
			(xy 78.28329 -293.239008) (xy 78.327752 -293.260106) (xy 78.368255 -293.288062) (xy 78.403748 -293.322154)
			(xy 78.433313 -293.361498) (xy 78.456184 -293.405075) (xy 78.471768 -293.451756) (xy 78.479663 -293.500333)
			(xy 78.480158 -293.52494) (xy 78.819006 -293.52494) (xy 78.822966 -293.475886) (xy 78.834743 -293.428102)
			(xy 78.854034 -293.382826) (xy 78.880337 -293.34123) (xy 78.912972 -293.304393) (xy 78.951093 -293.273268)
			(xy 78.993714 -293.248661) (xy 79.03973 -293.231209) (xy 79.087949 -293.221365) (xy 79.137124 -293.219384)
			(xy 79.185979 -293.225316) (xy 79.23325 -293.239008) (xy 79.277712 -293.260106) (xy 79.318215 -293.288062)
			(xy 79.353708 -293.322154) (xy 79.383273 -293.361498) (xy 79.406144 -293.405075) (xy 79.421728 -293.451756)
			(xy 79.429623 -293.500333) (xy 79.430118 -293.52494) (xy 79.768966 -293.52494) (xy 79.772926 -293.475886)
			(xy 79.784703 -293.428102) (xy 79.803994 -293.382826) (xy 79.830297 -293.34123) (xy 79.862932 -293.304393)
			(xy 79.901053 -293.273268) (xy 79.943674 -293.248661) (xy 79.98969 -293.231209) (xy 80.037909 -293.221365)
			(xy 80.087084 -293.219384) (xy 80.135939 -293.225316) (xy 80.18321 -293.239008) (xy 80.227672 -293.260106)
			(xy 80.268175 -293.288062) (xy 80.303668 -293.322154) (xy 80.333233 -293.361498) (xy 80.356104 -293.405075)
			(xy 80.371688 -293.451756) (xy 80.379583 -293.500333) (xy 80.380078 -293.52494) (xy 80.71918 -293.52494)
			(xy 80.72314 -293.475886) (xy 80.734917 -293.428102) (xy 80.754208 -293.382826) (xy 80.780511 -293.34123)
			(xy 80.813146 -293.304393) (xy 80.851267 -293.273268) (xy 80.893888 -293.248661) (xy 80.939904 -293.231209)
			(xy 80.988123 -293.221365) (xy 81.037298 -293.219384) (xy 81.086153 -293.225316) (xy 81.133424 -293.239008)
			(xy 81.177886 -293.260106) (xy 81.218389 -293.288062) (xy 81.253882 -293.322154) (xy 81.283447 -293.361498)
			(xy 81.306318 -293.405075) (xy 81.321902 -293.451756) (xy 81.329797 -293.500333) (xy 81.330292 -293.52494)
			(xy 81.66914 -293.52494) (xy 81.6731 -293.475886) (xy 81.684877 -293.428102) (xy 81.704168 -293.382826)
			(xy 81.730471 -293.34123) (xy 81.763106 -293.304393) (xy 81.801227 -293.273268) (xy 81.843848 -293.248661)
			(xy 81.889864 -293.231209) (xy 81.938083 -293.221365) (xy 81.987258 -293.219384) (xy 82.036113 -293.225316)
			(xy 82.083384 -293.239008) (xy 82.127846 -293.260106) (xy 82.168349 -293.288062) (xy 82.203842 -293.322154)
			(xy 82.233407 -293.361498) (xy 82.256278 -293.405075) (xy 82.271862 -293.451756) (xy 82.279757 -293.500333)
			(xy 82.280252 -293.52494) (xy 82.6191 -293.52494) (xy 82.62306 -293.475886) (xy 82.634837 -293.428102)
			(xy 82.654128 -293.382826) (xy 82.680431 -293.34123) (xy 82.713066 -293.304393) (xy 82.751187 -293.273268)
			(xy 82.793808 -293.248661) (xy 82.839824 -293.231209) (xy 82.888043 -293.221365) (xy 82.937218 -293.219384)
			(xy 82.986073 -293.225316) (xy 83.033344 -293.239008) (xy 83.077806 -293.260106) (xy 83.118309 -293.288062)
			(xy 83.153802 -293.322154) (xy 83.183367 -293.361498) (xy 83.206238 -293.405075) (xy 83.221822 -293.451756)
			(xy 83.229717 -293.500333) (xy 83.230212 -293.52494) (xy 83.229717 -293.549547) (xy 83.221822 -293.598124)
			(xy 83.206238 -293.644805) (xy 83.183367 -293.688382) (xy 83.153802 -293.727726) (xy 83.118309 -293.761818)
			(xy 83.077806 -293.789774) (xy 83.033344 -293.810872) (xy 82.986073 -293.824564) (xy 82.937218 -293.830496)
			(xy 82.888043 -293.828515) (xy 82.839824 -293.818671) (xy 82.793808 -293.801219) (xy 82.751187 -293.776612)
			(xy 82.713066 -293.745487) (xy 82.680431 -293.70865) (xy 82.654128 -293.667054) (xy 82.634837 -293.621778)
			(xy 82.62306 -293.573994) (xy 82.6191 -293.52494) (xy 82.280252 -293.52494) (xy 82.279757 -293.549547)
			(xy 82.271862 -293.598124) (xy 82.256278 -293.644805) (xy 82.233407 -293.688382) (xy 82.203842 -293.727726)
			(xy 82.168349 -293.761818) (xy 82.127846 -293.789774) (xy 82.083384 -293.810872) (xy 82.036113 -293.824564)
			(xy 81.987258 -293.830496) (xy 81.938083 -293.828515) (xy 81.889864 -293.818671) (xy 81.843848 -293.801219)
			(xy 81.801227 -293.776612) (xy 81.763106 -293.745487) (xy 81.730471 -293.70865) (xy 81.704168 -293.667054)
			(xy 81.684877 -293.621778) (xy 81.6731 -293.573994) (xy 81.66914 -293.52494) (xy 81.330292 -293.52494)
			(xy 81.329797 -293.549547) (xy 81.321902 -293.598124) (xy 81.306318 -293.644805) (xy 81.283447 -293.688382)
			(xy 81.253882 -293.727726) (xy 81.218389 -293.761818) (xy 81.177886 -293.789774) (xy 81.133424 -293.810872)
			(xy 81.086153 -293.824564) (xy 81.037298 -293.830496) (xy 80.988123 -293.828515) (xy 80.939904 -293.818671)
			(xy 80.893888 -293.801219) (xy 80.851267 -293.776612) (xy 80.813146 -293.745487) (xy 80.780511 -293.70865)
			(xy 80.754208 -293.667054) (xy 80.734917 -293.621778) (xy 80.72314 -293.573994) (xy 80.71918 -293.52494)
			(xy 80.380078 -293.52494) (xy 80.379583 -293.549547) (xy 80.371688 -293.598124) (xy 80.356104 -293.644805)
			(xy 80.333233 -293.688382) (xy 80.303668 -293.727726) (xy 80.268175 -293.761818) (xy 80.227672 -293.789774)
			(xy 80.18321 -293.810872) (xy 80.135939 -293.824564) (xy 80.087084 -293.830496) (xy 80.037909 -293.828515)
			(xy 79.98969 -293.818671) (xy 79.943674 -293.801219) (xy 79.901053 -293.776612) (xy 79.862932 -293.745487)
			(xy 79.830297 -293.70865) (xy 79.803994 -293.667054) (xy 79.784703 -293.621778) (xy 79.772926 -293.573994)
			(xy 79.768966 -293.52494) (xy 79.430118 -293.52494) (xy 79.429623 -293.549547) (xy 79.421728 -293.598124)
			(xy 79.406144 -293.644805) (xy 79.383273 -293.688382) (xy 79.353708 -293.727726) (xy 79.318215 -293.761818)
			(xy 79.277712 -293.789774) (xy 79.23325 -293.810872) (xy 79.185979 -293.824564) (xy 79.137124 -293.830496)
			(xy 79.087949 -293.828515) (xy 79.03973 -293.818671) (xy 78.993714 -293.801219) (xy 78.951093 -293.776612)
			(xy 78.912972 -293.745487) (xy 78.880337 -293.70865) (xy 78.854034 -293.667054) (xy 78.834743 -293.621778)
			(xy 78.822966 -293.573994) (xy 78.819006 -293.52494) (xy 78.480158 -293.52494) (xy 78.479663 -293.549547)
			(xy 78.471768 -293.598124) (xy 78.456184 -293.644805) (xy 78.433313 -293.688382) (xy 78.403748 -293.727726)
			(xy 78.368255 -293.761818) (xy 78.327752 -293.789774) (xy 78.28329 -293.810872) (xy 78.236019 -293.824564)
			(xy 78.187164 -293.830496) (xy 78.137989 -293.828515) (xy 78.08977 -293.818671) (xy 78.043754 -293.801219)
			(xy 78.001133 -293.776612) (xy 77.963012 -293.745487) (xy 77.930377 -293.70865) (xy 77.904074 -293.667054)
			(xy 77.884783 -293.621778) (xy 77.873006 -293.573994) (xy 77.869046 -293.52494) (xy 77.530198 -293.52494)
			(xy 77.529703 -293.549547) (xy 77.521808 -293.598124) (xy 77.506224 -293.644805) (xy 77.483353 -293.688382)
			(xy 77.453788 -293.727726) (xy 77.418295 -293.761818) (xy 77.377792 -293.789774) (xy 77.33333 -293.810872)
			(xy 77.286059 -293.824564) (xy 77.237204 -293.830496) (xy 77.188029 -293.828515) (xy 77.13981 -293.818671)
			(xy 77.093794 -293.801219) (xy 77.051173 -293.776612) (xy 77.013052 -293.745487) (xy 76.980417 -293.70865)
			(xy 76.954114 -293.667054) (xy 76.934823 -293.621778) (xy 76.923046 -293.573994) (xy 76.919086 -293.52494)
			(xy 76.580238 -293.52494) (xy 76.579743 -293.549547) (xy 76.571848 -293.598124) (xy 76.556264 -293.644805)
			(xy 76.533393 -293.688382) (xy 76.503828 -293.727726) (xy 76.468335 -293.761818) (xy 76.427832 -293.789774)
			(xy 76.38337 -293.810872) (xy 76.336099 -293.824564) (xy 76.287244 -293.830496) (xy 76.238069 -293.828515)
			(xy 76.18985 -293.818671) (xy 76.143834 -293.801219) (xy 76.101213 -293.776612) (xy 76.063092 -293.745487)
			(xy 76.030457 -293.70865) (xy 76.004154 -293.667054) (xy 75.984863 -293.621778) (xy 75.973086 -293.573994)
			(xy 75.969126 -293.52494) (xy 75.630278 -293.52494) (xy 75.629783 -293.549547) (xy 75.621888 -293.598124)
			(xy 75.606304 -293.644805) (xy 75.583433 -293.688382) (xy 75.553868 -293.727726) (xy 75.518375 -293.761818)
			(xy 75.477872 -293.789774) (xy 75.43341 -293.810872) (xy 75.386139 -293.824564) (xy 75.337284 -293.830496)
			(xy 75.288109 -293.828515) (xy 75.23989 -293.818671) (xy 75.193874 -293.801219) (xy 75.151253 -293.776612)
			(xy 75.113132 -293.745487) (xy 75.080497 -293.70865) (xy 75.054194 -293.667054) (xy 75.034903 -293.621778)
			(xy 75.023126 -293.573994) (xy 75.019166 -293.52494) (xy 74.680318 -293.52494) (xy 74.679823 -293.549547)
			(xy 74.671928 -293.598124) (xy 74.656344 -293.644805) (xy 74.633473 -293.688382) (xy 74.603908 -293.727726)
			(xy 74.568415 -293.761818) (xy 74.527912 -293.789774) (xy 74.48345 -293.810872) (xy 74.436179 -293.824564)
			(xy 74.387324 -293.830496) (xy 74.338149 -293.828515) (xy 74.28993 -293.818671) (xy 74.243914 -293.801219)
			(xy 74.201293 -293.776612) (xy 74.163172 -293.745487) (xy 74.130537 -293.70865) (xy 74.104234 -293.667054)
			(xy 74.084943 -293.621778) (xy 74.073166 -293.573994) (xy 74.069206 -293.52494) (xy 73.730104 -293.52494)
			(xy 73.729609 -293.549547) (xy 73.721714 -293.598124) (xy 73.70613 -293.644805) (xy 73.683259 -293.688382)
			(xy 73.653694 -293.727726) (xy 73.618201 -293.761818) (xy 73.577698 -293.789774) (xy 73.533236 -293.810872)
			(xy 73.485965 -293.824564) (xy 73.43711 -293.830496) (xy 73.387935 -293.828515) (xy 73.339716 -293.818671)
			(xy 73.2937 -293.801219) (xy 73.251079 -293.776612) (xy 73.212958 -293.745487) (xy 73.180323 -293.70865)
			(xy 73.15402 -293.667054) (xy 73.134729 -293.621778) (xy 73.122952 -293.573994) (xy 73.118992 -293.52494)
			(xy 71.830184 -293.52494) (xy 71.829689 -293.549547) (xy 71.821794 -293.598124) (xy 71.80621 -293.644805)
			(xy 71.783339 -293.688382) (xy 71.753774 -293.727726) (xy 71.718281 -293.761818) (xy 71.677778 -293.789774)
			(xy 71.633316 -293.810872) (xy 71.586045 -293.824564) (xy 71.53719 -293.830496) (xy 71.488015 -293.828515)
			(xy 71.439796 -293.818671) (xy 71.39378 -293.801219) (xy 71.351159 -293.776612) (xy 71.313038 -293.745487)
			(xy 71.280403 -293.70865) (xy 71.2541 -293.667054) (xy 71.234809 -293.621778) (xy 71.223032 -293.573994)
			(xy 71.219072 -293.52494) (xy 70.880224 -293.52494) (xy 70.879729 -293.549547) (xy 70.871834 -293.598124)
			(xy 70.85625 -293.644805) (xy 70.833379 -293.688382) (xy 70.803814 -293.727726) (xy 70.768321 -293.761818)
			(xy 70.727818 -293.789774) (xy 70.683356 -293.810872) (xy 70.636085 -293.824564) (xy 70.58723 -293.830496)
			(xy 70.538055 -293.828515) (xy 70.489836 -293.818671) (xy 70.44382 -293.801219) (xy 70.401199 -293.776612)
			(xy 70.363078 -293.745487) (xy 70.330443 -293.70865) (xy 70.30414 -293.667054) (xy 70.284849 -293.621778)
			(xy 70.273072 -293.573994) (xy 70.269112 -293.52494) (xy 69.930264 -293.52494) (xy 69.929769 -293.549547)
			(xy 69.921874 -293.598124) (xy 69.90629 -293.644805) (xy 69.883419 -293.688382) (xy 69.853854 -293.727726)
			(xy 69.818361 -293.761818) (xy 69.777858 -293.789774) (xy 69.733396 -293.810872) (xy 69.686125 -293.824564)
			(xy 69.63727 -293.830496) (xy 69.588095 -293.828515) (xy 69.539876 -293.818671) (xy 69.49386 -293.801219)
			(xy 69.451239 -293.776612) (xy 69.413118 -293.745487) (xy 69.380483 -293.70865) (xy 69.35418 -293.667054)
			(xy 69.334889 -293.621778) (xy 69.323112 -293.573994) (xy 69.319152 -293.52494) (xy 68.98005 -293.52494)
			(xy 68.979555 -293.549547) (xy 68.97166 -293.598124) (xy 68.956076 -293.644805) (xy 68.933205 -293.688382)
			(xy 68.90364 -293.727726) (xy 68.868147 -293.761818) (xy 68.827644 -293.789774) (xy 68.783182 -293.810872)
			(xy 68.735911 -293.824564) (xy 68.687056 -293.830496) (xy 68.637881 -293.828515) (xy 68.589662 -293.818671)
			(xy 68.543646 -293.801219) (xy 68.501025 -293.776612) (xy 68.462904 -293.745487) (xy 68.430269 -293.70865)
			(xy 68.403966 -293.667054) (xy 68.384675 -293.621778) (xy 68.372898 -293.573994) (xy 68.368938 -293.52494)
			(xy 68.03009 -293.52494) (xy 68.029595 -293.549547) (xy 68.0217 -293.598124) (xy 68.006116 -293.644805)
			(xy 67.983245 -293.688382) (xy 67.95368 -293.727726) (xy 67.918187 -293.761818) (xy 67.877684 -293.789774)
			(xy 67.833222 -293.810872) (xy 67.785951 -293.824564) (xy 67.737096 -293.830496) (xy 67.687921 -293.828515)
			(xy 67.639702 -293.818671) (xy 67.593686 -293.801219) (xy 67.551065 -293.776612) (xy 67.512944 -293.745487)
			(xy 67.480309 -293.70865) (xy 67.454006 -293.667054) (xy 67.434715 -293.621778) (xy 67.422938 -293.573994)
			(xy 67.418978 -293.52494) (xy 67.08013 -293.52494) (xy 67.079635 -293.549547) (xy 67.07174 -293.598124)
			(xy 67.056156 -293.644805) (xy 67.033285 -293.688382) (xy 67.00372 -293.727726) (xy 66.968227 -293.761818)
			(xy 66.927724 -293.789774) (xy 66.883262 -293.810872) (xy 66.835991 -293.824564) (xy 66.787136 -293.830496)
			(xy 66.737961 -293.828515) (xy 66.689742 -293.818671) (xy 66.643726 -293.801219) (xy 66.601105 -293.776612)
			(xy 66.562984 -293.745487) (xy 66.530349 -293.70865) (xy 66.504046 -293.667054) (xy 66.484755 -293.621778)
			(xy 66.472978 -293.573994) (xy 66.469018 -293.52494) (xy 66.13017 -293.52494) (xy 66.129675 -293.549547)
			(xy 66.12178 -293.598124) (xy 66.106196 -293.644805) (xy 66.083325 -293.688382) (xy 66.05376 -293.727726)
			(xy 66.018267 -293.761818) (xy 65.977764 -293.789774) (xy 65.933302 -293.810872) (xy 65.886031 -293.824564)
			(xy 65.837176 -293.830496) (xy 65.788001 -293.828515) (xy 65.739782 -293.818671) (xy 65.693766 -293.801219)
			(xy 65.651145 -293.776612) (xy 65.613024 -293.745487) (xy 65.580389 -293.70865) (xy 65.554086 -293.667054)
			(xy 65.534795 -293.621778) (xy 65.523018 -293.573994) (xy 65.519058 -293.52494) (xy 65.18021 -293.52494)
			(xy 65.179715 -293.549547) (xy 65.17182 -293.598124) (xy 65.156236 -293.644805) (xy 65.133365 -293.688382)
			(xy 65.1038 -293.727726) (xy 65.068307 -293.761818) (xy 65.027804 -293.789774) (xy 64.983342 -293.810872)
			(xy 64.936071 -293.824564) (xy 64.887216 -293.830496) (xy 64.838041 -293.828515) (xy 64.789822 -293.818671)
			(xy 64.743806 -293.801219) (xy 64.701185 -293.776612) (xy 64.663064 -293.745487) (xy 64.630429 -293.70865)
			(xy 64.604126 -293.667054) (xy 64.584835 -293.621778) (xy 64.573058 -293.573994) (xy 64.569098 -293.52494)
			(xy 64.23025 -293.52494) (xy 64.229755 -293.549547) (xy 64.22186 -293.598124) (xy 64.206276 -293.644805)
			(xy 64.183405 -293.688382) (xy 64.15384 -293.727726) (xy 64.118347 -293.761818) (xy 64.077844 -293.789774)
			(xy 64.033382 -293.810872) (xy 63.986111 -293.824564) (xy 63.937256 -293.830496) (xy 63.888081 -293.828515)
			(xy 63.839862 -293.818671) (xy 63.793846 -293.801219) (xy 63.751225 -293.776612) (xy 63.713104 -293.745487)
			(xy 63.680469 -293.70865) (xy 63.654166 -293.667054) (xy 63.634875 -293.621778) (xy 63.623098 -293.573994)
			(xy 63.619138 -293.52494) (xy 63.28029 -293.52494) (xy 63.279795 -293.549547) (xy 63.2719 -293.598124)
			(xy 63.256316 -293.644805) (xy 63.233445 -293.688382) (xy 63.20388 -293.727726) (xy 63.168387 -293.761818)
			(xy 63.127884 -293.789774) (xy 63.083422 -293.810872) (xy 63.036151 -293.824564) (xy 62.987296 -293.830496)
			(xy 62.938121 -293.828515) (xy 62.889902 -293.818671) (xy 62.843886 -293.801219) (xy 62.801265 -293.776612)
			(xy 62.763144 -293.745487) (xy 62.730509 -293.70865) (xy 62.704206 -293.667054) (xy 62.684915 -293.621778)
			(xy 62.673138 -293.573994) (xy 62.669178 -293.52494) (xy 62.330076 -293.52494) (xy 62.329581 -293.549547)
			(xy 62.321686 -293.598124) (xy 62.306102 -293.644805) (xy 62.283231 -293.688382) (xy 62.253666 -293.727726)
			(xy 62.218173 -293.761818) (xy 62.17767 -293.789774) (xy 62.133208 -293.810872) (xy 62.085937 -293.824564)
			(xy 62.037082 -293.830496) (xy 61.987907 -293.828515) (xy 61.939688 -293.818671) (xy 61.893672 -293.801219)
			(xy 61.851051 -293.776612) (xy 61.81293 -293.745487) (xy 61.780295 -293.70865) (xy 61.753992 -293.667054)
			(xy 61.734701 -293.621778) (xy 61.722924 -293.573994) (xy 61.718964 -293.52494) (xy 61.380116 -293.52494)
			(xy 61.379621 -293.549547) (xy 61.371726 -293.598124) (xy 61.356142 -293.644805) (xy 61.333271 -293.688382)
			(xy 61.303706 -293.727726) (xy 61.268213 -293.761818) (xy 61.22771 -293.789774) (xy 61.183248 -293.810872)
			(xy 61.135977 -293.824564) (xy 61.087122 -293.830496) (xy 61.037947 -293.828515) (xy 60.989728 -293.818671)
			(xy 60.943712 -293.801219) (xy 60.901091 -293.776612) (xy 60.86297 -293.745487) (xy 60.830335 -293.70865)
			(xy 60.804032 -293.667054) (xy 60.784741 -293.621778) (xy 60.772964 -293.573994) (xy 60.769004 -293.52494)
			(xy 60.430156 -293.52494) (xy 60.429661 -293.549547) (xy 60.421766 -293.598124) (xy 60.406182 -293.644805)
			(xy 60.383311 -293.688382) (xy 60.353746 -293.727726) (xy 60.318253 -293.761818) (xy 60.27775 -293.789774)
			(xy 60.233288 -293.810872) (xy 60.186017 -293.824564) (xy 60.137162 -293.830496) (xy 60.087987 -293.828515)
			(xy 60.039768 -293.818671) (xy 59.993752 -293.801219) (xy 59.951131 -293.776612) (xy 59.91301 -293.745487)
			(xy 59.880375 -293.70865) (xy 59.854072 -293.667054) (xy 59.834781 -293.621778) (xy 59.823004 -293.573994)
			(xy 59.819044 -293.52494) (xy 58.530236 -293.52494) (xy 58.529741 -293.549547) (xy 58.521846 -293.598124)
			(xy 58.506262 -293.644805) (xy 58.483391 -293.688382) (xy 58.453826 -293.727726) (xy 58.418333 -293.761818)
			(xy 58.37783 -293.789774) (xy 58.333368 -293.810872) (xy 58.286097 -293.824564) (xy 58.237242 -293.830496)
			(xy 58.188067 -293.828515) (xy 58.139848 -293.818671) (xy 58.093832 -293.801219) (xy 58.051211 -293.776612)
			(xy 58.01309 -293.745487) (xy 57.980455 -293.70865) (xy 57.954152 -293.667054) (xy 57.934861 -293.621778)
			(xy 57.923084 -293.573994) (xy 57.919124 -293.52494) (xy 57.580276 -293.52494) (xy 57.579781 -293.549547)
			(xy 57.571886 -293.598124) (xy 57.556302 -293.644805) (xy 57.533431 -293.688382) (xy 57.503866 -293.727726)
			(xy 57.468373 -293.761818) (xy 57.42787 -293.789774) (xy 57.383408 -293.810872) (xy 57.336137 -293.824564)
			(xy 57.287282 -293.830496) (xy 57.238107 -293.828515) (xy 57.189888 -293.818671) (xy 57.143872 -293.801219)
			(xy 57.101251 -293.776612) (xy 57.06313 -293.745487) (xy 57.030495 -293.70865) (xy 57.004192 -293.667054)
			(xy 56.984901 -293.621778) (xy 56.973124 -293.573994) (xy 56.969164 -293.52494) (xy 56.630062 -293.52494)
			(xy 56.629567 -293.549547) (xy 56.621672 -293.598124) (xy 56.606088 -293.644805) (xy 56.583217 -293.688382)
			(xy 56.553652 -293.727726) (xy 56.518159 -293.761818) (xy 56.477656 -293.789774) (xy 56.433194 -293.810872)
			(xy 56.385923 -293.824564) (xy 56.337068 -293.830496) (xy 56.287893 -293.828515) (xy 56.239674 -293.818671)
			(xy 56.193658 -293.801219) (xy 56.151037 -293.776612) (xy 56.112916 -293.745487) (xy 56.080281 -293.70865)
			(xy 56.053978 -293.667054) (xy 56.034687 -293.621778) (xy 56.02291 -293.573994) (xy 56.01895 -293.52494)
			(xy 55.680102 -293.52494) (xy 55.679607 -293.549547) (xy 55.671712 -293.598124) (xy 55.656128 -293.644805)
			(xy 55.633257 -293.688382) (xy 55.603692 -293.727726) (xy 55.568199 -293.761818) (xy 55.527696 -293.789774)
			(xy 55.483234 -293.810872) (xy 55.435963 -293.824564) (xy 55.387108 -293.830496) (xy 55.337933 -293.828515)
			(xy 55.289714 -293.818671) (xy 55.243698 -293.801219) (xy 55.201077 -293.776612) (xy 55.162956 -293.745487)
			(xy 55.130321 -293.70865) (xy 55.104018 -293.667054) (xy 55.084727 -293.621778) (xy 55.07295 -293.573994)
			(xy 55.06899 -293.52494) (xy 54.730142 -293.52494) (xy 54.729647 -293.549547) (xy 54.721752 -293.598124)
			(xy 54.706168 -293.644805) (xy 54.683297 -293.688382) (xy 54.653732 -293.727726) (xy 54.618239 -293.761818)
			(xy 54.577736 -293.789774) (xy 54.533274 -293.810872) (xy 54.486003 -293.824564) (xy 54.437148 -293.830496)
			(xy 54.387973 -293.828515) (xy 54.339754 -293.818671) (xy 54.293738 -293.801219) (xy 54.251117 -293.776612)
			(xy 54.212996 -293.745487) (xy 54.180361 -293.70865) (xy 54.154058 -293.667054) (xy 54.134767 -293.621778)
			(xy 54.12299 -293.573994) (xy 54.11903 -293.52494) (xy 53.780182 -293.52494) (xy 53.779687 -293.549547)
			(xy 53.771792 -293.598124) (xy 53.756208 -293.644805) (xy 53.733337 -293.688382) (xy 53.703772 -293.727726)
			(xy 53.668279 -293.761818) (xy 53.627776 -293.789774) (xy 53.583314 -293.810872) (xy 53.536043 -293.824564)
			(xy 53.487188 -293.830496) (xy 53.438013 -293.828515) (xy 53.389794 -293.818671) (xy 53.343778 -293.801219)
			(xy 53.301157 -293.776612) (xy 53.263036 -293.745487) (xy 53.230401 -293.70865) (xy 53.204098 -293.667054)
			(xy 53.184807 -293.621778) (xy 53.17303 -293.573994) (xy 53.16907 -293.52494) (xy 52.830222 -293.52494)
			(xy 52.829727 -293.549547) (xy 52.821832 -293.598124) (xy 52.806248 -293.644805) (xy 52.783377 -293.688382)
			(xy 52.753812 -293.727726) (xy 52.718319 -293.761818) (xy 52.677816 -293.789774) (xy 52.633354 -293.810872)
			(xy 52.586083 -293.824564) (xy 52.537228 -293.830496) (xy 52.488053 -293.828515) (xy 52.439834 -293.818671)
			(xy 52.393818 -293.801219) (xy 52.351197 -293.776612) (xy 52.313076 -293.745487) (xy 52.280441 -293.70865)
			(xy 52.254138 -293.667054) (xy 52.234847 -293.621778) (xy 52.22307 -293.573994) (xy 52.21911 -293.52494)
			(xy 51.880262 -293.52494) (xy 51.879767 -293.549547) (xy 51.871872 -293.598124) (xy 51.856288 -293.644805)
			(xy 51.833417 -293.688382) (xy 51.803852 -293.727726) (xy 51.768359 -293.761818) (xy 51.727856 -293.789774)
			(xy 51.683394 -293.810872) (xy 51.636123 -293.824564) (xy 51.587268 -293.830496) (xy 51.538093 -293.828515)
			(xy 51.489874 -293.818671) (xy 51.443858 -293.801219) (xy 51.401237 -293.776612) (xy 51.363116 -293.745487)
			(xy 51.330481 -293.70865) (xy 51.304178 -293.667054) (xy 51.284887 -293.621778) (xy 51.27311 -293.573994)
			(xy 51.26915 -293.52494) (xy 50.930302 -293.52494) (xy 50.929807 -293.549547) (xy 50.921912 -293.598124)
			(xy 50.906328 -293.644805) (xy 50.883457 -293.688382) (xy 50.853892 -293.727726) (xy 50.818399 -293.761818)
			(xy 50.777896 -293.789774) (xy 50.733434 -293.810872) (xy 50.686163 -293.824564) (xy 50.637308 -293.830496)
			(xy 50.588133 -293.828515) (xy 50.539914 -293.818671) (xy 50.493898 -293.801219) (xy 50.451277 -293.776612)
			(xy 50.413156 -293.745487) (xy 50.380521 -293.70865) (xy 50.354218 -293.667054) (xy 50.334927 -293.621778)
			(xy 50.32315 -293.573994) (xy 50.31919 -293.52494) (xy 49.980088 -293.52494) (xy 49.979593 -293.549547)
			(xy 49.971698 -293.598124) (xy 49.956114 -293.644805) (xy 49.933243 -293.688382) (xy 49.903678 -293.727726)
			(xy 49.868185 -293.761818) (xy 49.827682 -293.789774) (xy 49.78322 -293.810872) (xy 49.735949 -293.824564)
			(xy 49.687094 -293.830496) (xy 49.637919 -293.828515) (xy 49.5897 -293.818671) (xy 49.543684 -293.801219)
			(xy 49.501063 -293.776612) (xy 49.462942 -293.745487) (xy 49.430307 -293.70865) (xy 49.404004 -293.667054)
			(xy 49.384713 -293.621778) (xy 49.372936 -293.573994) (xy 49.368976 -293.52494) (xy 49.030128 -293.52494)
			(xy 49.029633 -293.549547) (xy 49.021738 -293.598124) (xy 49.006154 -293.644805) (xy 48.983283 -293.688382)
			(xy 48.953718 -293.727726) (xy 48.918225 -293.761818) (xy 48.877722 -293.789774) (xy 48.83326 -293.810872)
			(xy 48.785989 -293.824564) (xy 48.737134 -293.830496) (xy 48.687959 -293.828515) (xy 48.63974 -293.818671)
			(xy 48.593724 -293.801219) (xy 48.551103 -293.776612) (xy 48.512982 -293.745487) (xy 48.480347 -293.70865)
			(xy 48.454044 -293.667054) (xy 48.434753 -293.621778) (xy 48.422976 -293.573994) (xy 48.419016 -293.52494)
			(xy 48.080168 -293.52494) (xy 48.079673 -293.549547) (xy 48.071778 -293.598124) (xy 48.056194 -293.644805)
			(xy 48.033323 -293.688382) (xy 48.003758 -293.727726) (xy 47.968265 -293.761818) (xy 47.927762 -293.789774)
			(xy 47.8833 -293.810872) (xy 47.836029 -293.824564) (xy 47.787174 -293.830496) (xy 47.737999 -293.828515)
			(xy 47.68978 -293.818671) (xy 47.643764 -293.801219) (xy 47.601143 -293.776612) (xy 47.563022 -293.745487)
			(xy 47.530387 -293.70865) (xy 47.504084 -293.667054) (xy 47.484793 -293.621778) (xy 47.473016 -293.573994)
			(xy 47.469056 -293.52494) (xy 46.180742 -293.52494) (xy 46.180756 -293.525194) (xy 46.206918 -293.552372)
			(xy 46.218348 -293.553388) (xy 46.221396 -293.556182) (xy 46.22874 -293.562705) (xy 46.246893 -293.570158)
			(xy 46.256702 -293.57066) (xy 46.463712 -293.57066) (xy 46.468792 -293.565834) (xy 46.475129 -293.560109)
			(xy 46.490567 -293.552834) (xy 46.499018 -293.55161) (xy 46.676818 -293.533576) (xy 46.685422 -293.533002)
			(xy 46.702176 -293.537036) (xy 46.709584 -293.54145) (xy 46.783498 -293.589202) (xy 46.784514 -293.589964)
			(xy 46.793677 -293.5951) (xy 46.813894 -293.600772) (xy 46.824392 -293.60114) (xy 46.8249 -293.60114)
			(xy 46.833994 -293.600964) (xy 46.851709 -293.596857) (xy 46.859952 -293.593012) (xy 46.86046 -293.592758)
			(xy 46.904402 -293.569898) (xy 46.909872 -293.56722) (xy 46.921683 -293.564265) (xy 46.92777 -293.564056)
			(xy 46.942248 -293.564056) (xy 46.94682 -293.56304) (xy 46.971044 -293.559125) (xy 47.020105 -293.558233)
			(xy 47.068674 -293.565215) (xy 47.115498 -293.579888) (xy 47.159365 -293.601873) (xy 47.199143 -293.630603)
			(xy 47.216822 -293.647622) (xy 47.348394 -293.77894) (xy 47.365061 -293.796218) (xy 47.393311 -293.835031)
			(xy 47.415142 -293.877786) (xy 47.430015 -293.92343) (xy 47.437565 -293.970838) (xy 47.438056 -293.99484)
			(xy 47.438056 -294.142922) (xy 47.438439 -294.152226) (xy 47.44502 -294.169627) (xy 47.457408 -294.183507)
			(xy 47.465488 -294.188134) (xy 47.545498 -294.229536) (xy 47.55394 -294.23338) (xy 47.572357 -294.235429)
			(xy 47.590293 -294.23077) (xy 47.598076 -294.225726) (xy 47.59833 -294.225726) (xy 47.617802 -294.212495)
			(xy 47.659945 -294.191519) (xy 47.704805 -294.177251) (xy 47.751323 -294.170029) (xy 47.77486 -294.169592)
			(xy 47.80012 -294.170082) (xy 47.849951 -294.178391) (xy 47.897736 -294.19479) (xy 47.942168 -294.21883)
			(xy 47.982038 -294.249857) (xy 48.016256 -294.287024) (xy 48.04389 -294.329316) (xy 48.064185 -294.375579)
			(xy 48.076588 -294.424553) (xy 48.08076 -294.4749) (xy 48.419016 -294.4749) (xy 48.422976 -294.425846)
			(xy 48.434753 -294.378062) (xy 48.454044 -294.332786) (xy 48.480347 -294.29119) (xy 48.512982 -294.254353)
			(xy 48.551103 -294.223228) (xy 48.593724 -294.198621) (xy 48.63974 -294.181169) (xy 48.687959 -294.171325)
			(xy 48.737134 -294.169344) (xy 48.785989 -294.175276) (xy 48.83326 -294.188968) (xy 48.877722 -294.210066)
			(xy 48.918225 -294.238022) (xy 48.953718 -294.272114) (xy 48.983283 -294.311458) (xy 49.006154 -294.355035)
			(xy 49.021738 -294.401716) (xy 49.029633 -294.450293) (xy 49.030128 -294.4749) (xy 49.368976 -294.4749)
			(xy 49.372936 -294.425846) (xy 49.384713 -294.378062) (xy 49.404004 -294.332786) (xy 49.430307 -294.29119)
			(xy 49.462942 -294.254353) (xy 49.501063 -294.223228) (xy 49.543684 -294.198621) (xy 49.5897 -294.181169)
			(xy 49.637919 -294.171325) (xy 49.687094 -294.169344) (xy 49.735949 -294.175276) (xy 49.78322 -294.188968)
			(xy 49.827682 -294.210066) (xy 49.868185 -294.238022) (xy 49.903678 -294.272114) (xy 49.933243 -294.311458)
			(xy 49.956114 -294.355035) (xy 49.971698 -294.401716) (xy 49.979593 -294.450293) (xy 49.980088 -294.4749)
			(xy 50.31919 -294.4749) (xy 50.32315 -294.425846) (xy 50.334927 -294.378062) (xy 50.354218 -294.332786)
			(xy 50.380521 -294.29119) (xy 50.413156 -294.254353) (xy 50.451277 -294.223228) (xy 50.493898 -294.198621)
			(xy 50.539914 -294.181169) (xy 50.588133 -294.171325) (xy 50.637308 -294.169344) (xy 50.686163 -294.175276)
			(xy 50.733434 -294.188968) (xy 50.777896 -294.210066) (xy 50.818399 -294.238022) (xy 50.853892 -294.272114)
			(xy 50.883457 -294.311458) (xy 50.906328 -294.355035) (xy 50.921912 -294.401716) (xy 50.929807 -294.450293)
			(xy 50.930302 -294.4749) (xy 51.26915 -294.4749) (xy 51.27311 -294.425846) (xy 51.284887 -294.378062)
			(xy 51.304178 -294.332786) (xy 51.330481 -294.29119) (xy 51.363116 -294.254353) (xy 51.401237 -294.223228)
			(xy 51.443858 -294.198621) (xy 51.489874 -294.181169) (xy 51.538093 -294.171325) (xy 51.587268 -294.169344)
			(xy 51.636123 -294.175276) (xy 51.683394 -294.188968) (xy 51.727856 -294.210066) (xy 51.768359 -294.238022)
			(xy 51.803852 -294.272114) (xy 51.833417 -294.311458) (xy 51.856288 -294.355035) (xy 51.871872 -294.401716)
			(xy 51.879767 -294.450293) (xy 51.880262 -294.4749) (xy 52.21911 -294.4749) (xy 52.22307 -294.425846)
			(xy 52.234847 -294.378062) (xy 52.254138 -294.332786) (xy 52.280441 -294.29119) (xy 52.313076 -294.254353)
			(xy 52.351197 -294.223228) (xy 52.393818 -294.198621) (xy 52.439834 -294.181169) (xy 52.488053 -294.171325)
			(xy 52.537228 -294.169344) (xy 52.586083 -294.175276) (xy 52.633354 -294.188968) (xy 52.677816 -294.210066)
			(xy 52.718319 -294.238022) (xy 52.753812 -294.272114) (xy 52.783377 -294.311458) (xy 52.806248 -294.355035)
			(xy 52.821832 -294.401716) (xy 52.829727 -294.450293) (xy 52.830222 -294.4749) (xy 53.16907 -294.4749)
			(xy 53.17303 -294.425846) (xy 53.184807 -294.378062) (xy 53.204098 -294.332786) (xy 53.230401 -294.29119)
			(xy 53.263036 -294.254353) (xy 53.301157 -294.223228) (xy 53.343778 -294.198621) (xy 53.389794 -294.181169)
			(xy 53.438013 -294.171325) (xy 53.487188 -294.169344) (xy 53.536043 -294.175276) (xy 53.583314 -294.188968)
			(xy 53.627776 -294.210066) (xy 53.668279 -294.238022) (xy 53.703772 -294.272114) (xy 53.733337 -294.311458)
			(xy 53.756208 -294.355035) (xy 53.771792 -294.401716) (xy 53.779687 -294.450293) (xy 53.780182 -294.4749)
			(xy 54.11903 -294.4749) (xy 54.12299 -294.425846) (xy 54.134767 -294.378062) (xy 54.154058 -294.332786)
			(xy 54.180361 -294.29119) (xy 54.212996 -294.254353) (xy 54.251117 -294.223228) (xy 54.293738 -294.198621)
			(xy 54.339754 -294.181169) (xy 54.387973 -294.171325) (xy 54.437148 -294.169344) (xy 54.486003 -294.175276)
			(xy 54.533274 -294.188968) (xy 54.577736 -294.210066) (xy 54.618239 -294.238022) (xy 54.653732 -294.272114)
			(xy 54.683297 -294.311458) (xy 54.706168 -294.355035) (xy 54.721752 -294.401716) (xy 54.729647 -294.450293)
			(xy 54.730142 -294.4749) (xy 55.06899 -294.4749) (xy 55.07295 -294.425846) (xy 55.084727 -294.378062)
			(xy 55.104018 -294.332786) (xy 55.130321 -294.29119) (xy 55.162956 -294.254353) (xy 55.201077 -294.223228)
			(xy 55.243698 -294.198621) (xy 55.289714 -294.181169) (xy 55.337933 -294.171325) (xy 55.387108 -294.169344)
			(xy 55.435963 -294.175276) (xy 55.483234 -294.188968) (xy 55.527696 -294.210066) (xy 55.568199 -294.238022)
			(xy 55.603692 -294.272114) (xy 55.633257 -294.311458) (xy 55.656128 -294.355035) (xy 55.671712 -294.401716)
			(xy 55.679607 -294.450293) (xy 55.680102 -294.4749) (xy 56.01895 -294.4749) (xy 56.02291 -294.425846)
			(xy 56.034687 -294.378062) (xy 56.053978 -294.332786) (xy 56.080281 -294.29119) (xy 56.112916 -294.254353)
			(xy 56.151037 -294.223228) (xy 56.193658 -294.198621) (xy 56.239674 -294.181169) (xy 56.287893 -294.171325)
			(xy 56.337068 -294.169344) (xy 56.385923 -294.175276) (xy 56.433194 -294.188968) (xy 56.477656 -294.210066)
			(xy 56.518159 -294.238022) (xy 56.553652 -294.272114) (xy 56.583217 -294.311458) (xy 56.606088 -294.355035)
			(xy 56.621672 -294.401716) (xy 56.629567 -294.450293) (xy 56.630062 -294.4749) (xy 56.969164 -294.4749)
			(xy 56.973124 -294.425846) (xy 56.984901 -294.378062) (xy 57.004192 -294.332786) (xy 57.030495 -294.29119)
			(xy 57.06313 -294.254353) (xy 57.101251 -294.223228) (xy 57.143872 -294.198621) (xy 57.189888 -294.181169)
			(xy 57.238107 -294.171325) (xy 57.287282 -294.169344) (xy 57.336137 -294.175276) (xy 57.383408 -294.188968)
			(xy 57.42787 -294.210066) (xy 57.468373 -294.238022) (xy 57.503866 -294.272114) (xy 57.533431 -294.311458)
			(xy 57.556302 -294.355035) (xy 57.571886 -294.401716) (xy 57.579781 -294.450293) (xy 57.580276 -294.4749)
			(xy 57.919124 -294.4749) (xy 57.923084 -294.425846) (xy 57.934861 -294.378062) (xy 57.954152 -294.332786)
			(xy 57.980455 -294.29119) (xy 58.01309 -294.254353) (xy 58.051211 -294.223228) (xy 58.093832 -294.198621)
			(xy 58.139848 -294.181169) (xy 58.188067 -294.171325) (xy 58.237242 -294.169344) (xy 58.286097 -294.175276)
			(xy 58.333368 -294.188968) (xy 58.37783 -294.210066) (xy 58.418333 -294.238022) (xy 58.453826 -294.272114)
			(xy 58.483391 -294.311458) (xy 58.506262 -294.355035) (xy 58.521846 -294.401716) (xy 58.529741 -294.450293)
			(xy 58.530236 -294.4749) (xy 59.819044 -294.4749) (xy 59.823004 -294.425846) (xy 59.834781 -294.378062)
			(xy 59.854072 -294.332786) (xy 59.880375 -294.29119) (xy 59.91301 -294.254353) (xy 59.951131 -294.223228)
			(xy 59.993752 -294.198621) (xy 60.039768 -294.181169) (xy 60.087987 -294.171325) (xy 60.137162 -294.169344)
			(xy 60.186017 -294.175276) (xy 60.233288 -294.188968) (xy 60.27775 -294.210066) (xy 60.318253 -294.238022)
			(xy 60.353746 -294.272114) (xy 60.383311 -294.311458) (xy 60.406182 -294.355035) (xy 60.421766 -294.401716)
			(xy 60.429661 -294.450293) (xy 60.430156 -294.4749) (xy 60.769004 -294.4749) (xy 60.772964 -294.425846)
			(xy 60.784741 -294.378062) (xy 60.804032 -294.332786) (xy 60.830335 -294.29119) (xy 60.86297 -294.254353)
			(xy 60.901091 -294.223228) (xy 60.943712 -294.198621) (xy 60.989728 -294.181169) (xy 61.037947 -294.171325)
			(xy 61.087122 -294.169344) (xy 61.135977 -294.175276) (xy 61.183248 -294.188968) (xy 61.22771 -294.210066)
			(xy 61.268213 -294.238022) (xy 61.303706 -294.272114) (xy 61.333271 -294.311458) (xy 61.356142 -294.355035)
			(xy 61.371726 -294.401716) (xy 61.379621 -294.450293) (xy 61.380116 -294.4749) (xy 61.718964 -294.4749)
			(xy 61.722924 -294.425846) (xy 61.734701 -294.378062) (xy 61.753992 -294.332786) (xy 61.780295 -294.29119)
			(xy 61.81293 -294.254353) (xy 61.851051 -294.223228) (xy 61.893672 -294.198621) (xy 61.939688 -294.181169)
			(xy 61.987907 -294.171325) (xy 62.037082 -294.169344) (xy 62.085937 -294.175276) (xy 62.133208 -294.188968)
			(xy 62.17767 -294.210066) (xy 62.218173 -294.238022) (xy 62.253666 -294.272114) (xy 62.283231 -294.311458)
			(xy 62.306102 -294.355035) (xy 62.321686 -294.401716) (xy 62.329581 -294.450293) (xy 62.330076 -294.4749)
			(xy 62.669178 -294.4749) (xy 62.673138 -294.425846) (xy 62.684915 -294.378062) (xy 62.704206 -294.332786)
			(xy 62.730509 -294.29119) (xy 62.763144 -294.254353) (xy 62.801265 -294.223228) (xy 62.843886 -294.198621)
			(xy 62.889902 -294.181169) (xy 62.938121 -294.171325) (xy 62.987296 -294.169344) (xy 63.036151 -294.175276)
			(xy 63.083422 -294.188968) (xy 63.127884 -294.210066) (xy 63.168387 -294.238022) (xy 63.20388 -294.272114)
			(xy 63.233445 -294.311458) (xy 63.256316 -294.355035) (xy 63.2719 -294.401716) (xy 63.279795 -294.450293)
			(xy 63.28029 -294.4749) (xy 63.619138 -294.4749) (xy 63.623098 -294.425846) (xy 63.634875 -294.378062)
			(xy 63.654166 -294.332786) (xy 63.680469 -294.29119) (xy 63.713104 -294.254353) (xy 63.751225 -294.223228)
			(xy 63.793846 -294.198621) (xy 63.839862 -294.181169) (xy 63.888081 -294.171325) (xy 63.937256 -294.169344)
			(xy 63.986111 -294.175276) (xy 64.033382 -294.188968) (xy 64.077844 -294.210066) (xy 64.118347 -294.238022)
			(xy 64.15384 -294.272114) (xy 64.183405 -294.311458) (xy 64.206276 -294.355035) (xy 64.22186 -294.401716)
			(xy 64.229755 -294.450293) (xy 64.23025 -294.4749) (xy 64.569098 -294.4749) (xy 64.573058 -294.425846)
			(xy 64.584835 -294.378062) (xy 64.604126 -294.332786) (xy 64.630429 -294.29119) (xy 64.663064 -294.254353)
			(xy 64.701185 -294.223228) (xy 64.743806 -294.198621) (xy 64.789822 -294.181169) (xy 64.838041 -294.171325)
			(xy 64.887216 -294.169344) (xy 64.936071 -294.175276) (xy 64.983342 -294.188968) (xy 65.027804 -294.210066)
			(xy 65.068307 -294.238022) (xy 65.1038 -294.272114) (xy 65.133365 -294.311458) (xy 65.156236 -294.355035)
			(xy 65.17182 -294.401716) (xy 65.179715 -294.450293) (xy 65.18021 -294.4749) (xy 65.519058 -294.4749)
			(xy 65.523018 -294.425846) (xy 65.534795 -294.378062) (xy 65.554086 -294.332786) (xy 65.580389 -294.29119)
			(xy 65.613024 -294.254353) (xy 65.651145 -294.223228) (xy 65.693766 -294.198621) (xy 65.739782 -294.181169)
			(xy 65.788001 -294.171325) (xy 65.837176 -294.169344) (xy 65.886031 -294.175276) (xy 65.933302 -294.188968)
			(xy 65.977764 -294.210066) (xy 66.018267 -294.238022) (xy 66.05376 -294.272114) (xy 66.083325 -294.311458)
			(xy 66.106196 -294.355035) (xy 66.12178 -294.401716) (xy 66.129675 -294.450293) (xy 66.13017 -294.4749)
			(xy 66.469018 -294.4749) (xy 66.472978 -294.425846) (xy 66.484755 -294.378062) (xy 66.504046 -294.332786)
			(xy 66.530349 -294.29119) (xy 66.562984 -294.254353) (xy 66.601105 -294.223228) (xy 66.643726 -294.198621)
			(xy 66.689742 -294.181169) (xy 66.737961 -294.171325) (xy 66.787136 -294.169344) (xy 66.835991 -294.175276)
			(xy 66.883262 -294.188968) (xy 66.927724 -294.210066) (xy 66.968227 -294.238022) (xy 67.00372 -294.272114)
			(xy 67.033285 -294.311458) (xy 67.056156 -294.355035) (xy 67.07174 -294.401716) (xy 67.079635 -294.450293)
			(xy 67.08013 -294.4749) (xy 67.418978 -294.4749) (xy 67.422938 -294.425846) (xy 67.434715 -294.378062)
			(xy 67.454006 -294.332786) (xy 67.480309 -294.29119) (xy 67.512944 -294.254353) (xy 67.551065 -294.223228)
			(xy 67.593686 -294.198621) (xy 67.639702 -294.181169) (xy 67.687921 -294.171325) (xy 67.737096 -294.169344)
			(xy 67.785951 -294.175276) (xy 67.833222 -294.188968) (xy 67.877684 -294.210066) (xy 67.918187 -294.238022)
			(xy 67.95368 -294.272114) (xy 67.983245 -294.311458) (xy 68.006116 -294.355035) (xy 68.0217 -294.401716)
			(xy 68.029595 -294.450293) (xy 68.03009 -294.4749) (xy 68.368938 -294.4749) (xy 68.372898 -294.425846)
			(xy 68.384675 -294.378062) (xy 68.403966 -294.332786) (xy 68.430269 -294.29119) (xy 68.462904 -294.254353)
			(xy 68.501025 -294.223228) (xy 68.543646 -294.198621) (xy 68.589662 -294.181169) (xy 68.637881 -294.171325)
			(xy 68.687056 -294.169344) (xy 68.735911 -294.175276) (xy 68.783182 -294.188968) (xy 68.827644 -294.210066)
			(xy 68.868147 -294.238022) (xy 68.90364 -294.272114) (xy 68.933205 -294.311458) (xy 68.956076 -294.355035)
			(xy 68.97166 -294.401716) (xy 68.979555 -294.450293) (xy 68.98005 -294.4749) (xy 69.319152 -294.4749)
			(xy 69.323112 -294.425846) (xy 69.334889 -294.378062) (xy 69.35418 -294.332786) (xy 69.380483 -294.29119)
			(xy 69.413118 -294.254353) (xy 69.451239 -294.223228) (xy 69.49386 -294.198621) (xy 69.539876 -294.181169)
			(xy 69.588095 -294.171325) (xy 69.63727 -294.169344) (xy 69.686125 -294.175276) (xy 69.733396 -294.188968)
			(xy 69.777858 -294.210066) (xy 69.818361 -294.238022) (xy 69.853854 -294.272114) (xy 69.883419 -294.311458)
			(xy 69.90629 -294.355035) (xy 69.921874 -294.401716) (xy 69.929769 -294.450293) (xy 69.930264 -294.4749)
			(xy 70.269112 -294.4749) (xy 70.273072 -294.425846) (xy 70.284849 -294.378062) (xy 70.30414 -294.332786)
			(xy 70.330443 -294.29119) (xy 70.363078 -294.254353) (xy 70.401199 -294.223228) (xy 70.44382 -294.198621)
			(xy 70.489836 -294.181169) (xy 70.538055 -294.171325) (xy 70.58723 -294.169344) (xy 70.636085 -294.175276)
			(xy 70.683356 -294.188968) (xy 70.727818 -294.210066) (xy 70.768321 -294.238022) (xy 70.803814 -294.272114)
			(xy 70.833379 -294.311458) (xy 70.85625 -294.355035) (xy 70.871834 -294.401716) (xy 70.879729 -294.450293)
			(xy 70.880224 -294.4749) (xy 71.219072 -294.4749) (xy 71.223032 -294.425846) (xy 71.234809 -294.378062)
			(xy 71.2541 -294.332786) (xy 71.280403 -294.29119) (xy 71.313038 -294.254353) (xy 71.351159 -294.223228)
			(xy 71.39378 -294.198621) (xy 71.439796 -294.181169) (xy 71.488015 -294.171325) (xy 71.53719 -294.169344)
			(xy 71.586045 -294.175276) (xy 71.633316 -294.188968) (xy 71.677778 -294.210066) (xy 71.718281 -294.238022)
			(xy 71.753774 -294.272114) (xy 71.783339 -294.311458) (xy 71.80621 -294.355035) (xy 71.821794 -294.401716)
			(xy 71.829689 -294.450293) (xy 71.830184 -294.4749) (xy 73.118992 -294.4749) (xy 73.122952 -294.425846)
			(xy 73.134729 -294.378062) (xy 73.15402 -294.332786) (xy 73.180323 -294.29119) (xy 73.212958 -294.254353)
			(xy 73.251079 -294.223228) (xy 73.2937 -294.198621) (xy 73.339716 -294.181169) (xy 73.387935 -294.171325)
			(xy 73.43711 -294.169344) (xy 73.485965 -294.175276) (xy 73.533236 -294.188968) (xy 73.577698 -294.210066)
			(xy 73.618201 -294.238022) (xy 73.653694 -294.272114) (xy 73.683259 -294.311458) (xy 73.70613 -294.355035)
			(xy 73.721714 -294.401716) (xy 73.729609 -294.450293) (xy 73.730104 -294.4749) (xy 74.068952 -294.4749)
			(xy 74.072912 -294.425846) (xy 74.084689 -294.378062) (xy 74.10398 -294.332786) (xy 74.130283 -294.29119)
			(xy 74.162918 -294.254353) (xy 74.201039 -294.223228) (xy 74.24366 -294.198621) (xy 74.289676 -294.181169)
			(xy 74.337895 -294.171325) (xy 74.38707 -294.169344) (xy 74.435925 -294.175276) (xy 74.483196 -294.188968)
			(xy 74.527658 -294.210066) (xy 74.568161 -294.238022) (xy 74.603654 -294.272114) (xy 74.633219 -294.311458)
			(xy 74.65609 -294.355035) (xy 74.671674 -294.401716) (xy 74.679569 -294.450293) (xy 74.680064 -294.4749)
			(xy 75.019166 -294.4749) (xy 75.023126 -294.425846) (xy 75.034903 -294.378062) (xy 75.054194 -294.332786)
			(xy 75.080497 -294.29119) (xy 75.113132 -294.254353) (xy 75.151253 -294.223228) (xy 75.193874 -294.198621)
			(xy 75.23989 -294.181169) (xy 75.288109 -294.171325) (xy 75.337284 -294.169344) (xy 75.386139 -294.175276)
			(xy 75.43341 -294.188968) (xy 75.477872 -294.210066) (xy 75.518375 -294.238022) (xy 75.553868 -294.272114)
			(xy 75.583433 -294.311458) (xy 75.606304 -294.355035) (xy 75.621888 -294.401716) (xy 75.629783 -294.450293)
			(xy 75.630278 -294.4749) (xy 75.969126 -294.4749) (xy 75.973086 -294.425846) (xy 75.984863 -294.378062)
			(xy 76.004154 -294.332786) (xy 76.030457 -294.29119) (xy 76.063092 -294.254353) (xy 76.101213 -294.223228)
			(xy 76.143834 -294.198621) (xy 76.18985 -294.181169) (xy 76.238069 -294.171325) (xy 76.287244 -294.169344)
			(xy 76.336099 -294.175276) (xy 76.38337 -294.188968) (xy 76.427832 -294.210066) (xy 76.468335 -294.238022)
			(xy 76.503828 -294.272114) (xy 76.533393 -294.311458) (xy 76.556264 -294.355035) (xy 76.571848 -294.401716)
			(xy 76.579743 -294.450293) (xy 76.580238 -294.4749) (xy 76.919086 -294.4749) (xy 76.923046 -294.425846)
			(xy 76.934823 -294.378062) (xy 76.954114 -294.332786) (xy 76.980417 -294.29119) (xy 77.013052 -294.254353)
			(xy 77.051173 -294.223228) (xy 77.093794 -294.198621) (xy 77.13981 -294.181169) (xy 77.188029 -294.171325)
			(xy 77.237204 -294.169344) (xy 77.286059 -294.175276) (xy 77.33333 -294.188968) (xy 77.377792 -294.210066)
			(xy 77.418295 -294.238022) (xy 77.453788 -294.272114) (xy 77.483353 -294.311458) (xy 77.506224 -294.355035)
			(xy 77.521808 -294.401716) (xy 77.529703 -294.450293) (xy 77.530198 -294.4749) (xy 77.869046 -294.4749)
			(xy 77.873006 -294.425846) (xy 77.884783 -294.378062) (xy 77.904074 -294.332786) (xy 77.930377 -294.29119)
			(xy 77.963012 -294.254353) (xy 78.001133 -294.223228) (xy 78.043754 -294.198621) (xy 78.08977 -294.181169)
			(xy 78.137989 -294.171325) (xy 78.187164 -294.169344) (xy 78.236019 -294.175276) (xy 78.28329 -294.188968)
			(xy 78.327752 -294.210066) (xy 78.368255 -294.238022) (xy 78.403748 -294.272114) (xy 78.433313 -294.311458)
			(xy 78.456184 -294.355035) (xy 78.471768 -294.401716) (xy 78.479663 -294.450293) (xy 78.480158 -294.4749)
			(xy 78.819006 -294.4749) (xy 78.822966 -294.425846) (xy 78.834743 -294.378062) (xy 78.854034 -294.332786)
			(xy 78.880337 -294.29119) (xy 78.912972 -294.254353) (xy 78.951093 -294.223228) (xy 78.993714 -294.198621)
			(xy 79.03973 -294.181169) (xy 79.087949 -294.171325) (xy 79.137124 -294.169344) (xy 79.185979 -294.175276)
			(xy 79.23325 -294.188968) (xy 79.277712 -294.210066) (xy 79.318215 -294.238022) (xy 79.353708 -294.272114)
			(xy 79.383273 -294.311458) (xy 79.406144 -294.355035) (xy 79.421728 -294.401716) (xy 79.429623 -294.450293)
			(xy 79.430118 -294.4749) (xy 79.768966 -294.4749) (xy 79.772926 -294.425846) (xy 79.784703 -294.378062)
			(xy 79.803994 -294.332786) (xy 79.830297 -294.29119) (xy 79.862932 -294.254353) (xy 79.901053 -294.223228)
			(xy 79.943674 -294.198621) (xy 79.98969 -294.181169) (xy 80.037909 -294.171325) (xy 80.087084 -294.169344)
			(xy 80.135939 -294.175276) (xy 80.18321 -294.188968) (xy 80.227672 -294.210066) (xy 80.268175 -294.238022)
			(xy 80.303668 -294.272114) (xy 80.333233 -294.311458) (xy 80.356104 -294.355035) (xy 80.371688 -294.401716)
			(xy 80.379583 -294.450293) (xy 80.380078 -294.4749) (xy 80.71918 -294.4749) (xy 80.72314 -294.425846)
			(xy 80.734917 -294.378062) (xy 80.754208 -294.332786) (xy 80.780511 -294.29119) (xy 80.813146 -294.254353)
			(xy 80.851267 -294.223228) (xy 80.893888 -294.198621) (xy 80.939904 -294.181169) (xy 80.988123 -294.171325)
			(xy 81.037298 -294.169344) (xy 81.086153 -294.175276) (xy 81.133424 -294.188968) (xy 81.177886 -294.210066)
			(xy 81.218389 -294.238022) (xy 81.253882 -294.272114) (xy 81.283447 -294.311458) (xy 81.306318 -294.355035)
			(xy 81.321902 -294.401716) (xy 81.329797 -294.450293) (xy 81.330292 -294.4749) (xy 81.66914 -294.4749)
			(xy 81.6731 -294.425846) (xy 81.684877 -294.378062) (xy 81.704168 -294.332786) (xy 81.730471 -294.29119)
			(xy 81.763106 -294.254353) (xy 81.801227 -294.223228) (xy 81.843848 -294.198621) (xy 81.889864 -294.181169)
			(xy 81.938083 -294.171325) (xy 81.987258 -294.169344) (xy 82.036113 -294.175276) (xy 82.083384 -294.188968)
			(xy 82.127846 -294.210066) (xy 82.168349 -294.238022) (xy 82.203842 -294.272114) (xy 82.233407 -294.311458)
			(xy 82.256278 -294.355035) (xy 82.271862 -294.401716) (xy 82.279757 -294.450293) (xy 82.280252 -294.4749)
			(xy 82.6191 -294.4749) (xy 82.62306 -294.425846) (xy 82.634837 -294.378062) (xy 82.654128 -294.332786)
			(xy 82.680431 -294.29119) (xy 82.713066 -294.254353) (xy 82.751187 -294.223228) (xy 82.793808 -294.198621)
			(xy 82.839824 -294.181169) (xy 82.888043 -294.171325) (xy 82.937218 -294.169344) (xy 82.986073 -294.175276)
			(xy 83.033344 -294.188968) (xy 83.077806 -294.210066) (xy 83.118309 -294.238022) (xy 83.153802 -294.272114)
			(xy 83.183367 -294.311458) (xy 83.206238 -294.355035) (xy 83.221822 -294.401716) (xy 83.229717 -294.450293)
			(xy 83.230212 -294.4749) (xy 83.229717 -294.499507) (xy 83.221822 -294.548084) (xy 83.206238 -294.594765)
			(xy 83.183367 -294.638342) (xy 83.153802 -294.677686) (xy 83.118309 -294.711778) (xy 83.077806 -294.739734)
			(xy 83.033344 -294.760832) (xy 82.986073 -294.774524) (xy 82.937218 -294.780456) (xy 82.888043 -294.778475)
			(xy 82.839824 -294.768631) (xy 82.793808 -294.751179) (xy 82.751187 -294.726572) (xy 82.713066 -294.695447)
			(xy 82.680431 -294.65861) (xy 82.654128 -294.617014) (xy 82.634837 -294.571738) (xy 82.62306 -294.523954)
			(xy 82.6191 -294.4749) (xy 82.280252 -294.4749) (xy 82.279757 -294.499507) (xy 82.271862 -294.548084)
			(xy 82.256278 -294.594765) (xy 82.233407 -294.638342) (xy 82.203842 -294.677686) (xy 82.168349 -294.711778)
			(xy 82.127846 -294.739734) (xy 82.083384 -294.760832) (xy 82.036113 -294.774524) (xy 81.987258 -294.780456)
			(xy 81.938083 -294.778475) (xy 81.889864 -294.768631) (xy 81.843848 -294.751179) (xy 81.801227 -294.726572)
			(xy 81.763106 -294.695447) (xy 81.730471 -294.65861) (xy 81.704168 -294.617014) (xy 81.684877 -294.571738)
			(xy 81.6731 -294.523954) (xy 81.66914 -294.4749) (xy 81.330292 -294.4749) (xy 81.329797 -294.499507)
			(xy 81.321902 -294.548084) (xy 81.306318 -294.594765) (xy 81.283447 -294.638342) (xy 81.253882 -294.677686)
			(xy 81.218389 -294.711778) (xy 81.177886 -294.739734) (xy 81.133424 -294.760832) (xy 81.086153 -294.774524)
			(xy 81.037298 -294.780456) (xy 80.988123 -294.778475) (xy 80.939904 -294.768631) (xy 80.893888 -294.751179)
			(xy 80.851267 -294.726572) (xy 80.813146 -294.695447) (xy 80.780511 -294.65861) (xy 80.754208 -294.617014)
			(xy 80.734917 -294.571738) (xy 80.72314 -294.523954) (xy 80.71918 -294.4749) (xy 80.380078 -294.4749)
			(xy 80.379583 -294.499507) (xy 80.371688 -294.548084) (xy 80.356104 -294.594765) (xy 80.333233 -294.638342)
			(xy 80.303668 -294.677686) (xy 80.268175 -294.711778) (xy 80.227672 -294.739734) (xy 80.18321 -294.760832)
			(xy 80.135939 -294.774524) (xy 80.087084 -294.780456) (xy 80.037909 -294.778475) (xy 79.98969 -294.768631)
			(xy 79.943674 -294.751179) (xy 79.901053 -294.726572) (xy 79.862932 -294.695447) (xy 79.830297 -294.65861)
			(xy 79.803994 -294.617014) (xy 79.784703 -294.571738) (xy 79.772926 -294.523954) (xy 79.768966 -294.4749)
			(xy 79.430118 -294.4749) (xy 79.429623 -294.499507) (xy 79.421728 -294.548084) (xy 79.406144 -294.594765)
			(xy 79.383273 -294.638342) (xy 79.353708 -294.677686) (xy 79.318215 -294.711778) (xy 79.277712 -294.739734)
			(xy 79.23325 -294.760832) (xy 79.185979 -294.774524) (xy 79.137124 -294.780456) (xy 79.087949 -294.778475)
			(xy 79.03973 -294.768631) (xy 78.993714 -294.751179) (xy 78.951093 -294.726572) (xy 78.912972 -294.695447)
			(xy 78.880337 -294.65861) (xy 78.854034 -294.617014) (xy 78.834743 -294.571738) (xy 78.822966 -294.523954)
			(xy 78.819006 -294.4749) (xy 78.480158 -294.4749) (xy 78.479663 -294.499507) (xy 78.471768 -294.548084)
			(xy 78.456184 -294.594765) (xy 78.433313 -294.638342) (xy 78.403748 -294.677686) (xy 78.368255 -294.711778)
			(xy 78.327752 -294.739734) (xy 78.28329 -294.760832) (xy 78.236019 -294.774524) (xy 78.187164 -294.780456)
			(xy 78.137989 -294.778475) (xy 78.08977 -294.768631) (xy 78.043754 -294.751179) (xy 78.001133 -294.726572)
			(xy 77.963012 -294.695447) (xy 77.930377 -294.65861) (xy 77.904074 -294.617014) (xy 77.884783 -294.571738)
			(xy 77.873006 -294.523954) (xy 77.869046 -294.4749) (xy 77.530198 -294.4749) (xy 77.529703 -294.499507)
			(xy 77.521808 -294.548084) (xy 77.506224 -294.594765) (xy 77.483353 -294.638342) (xy 77.453788 -294.677686)
			(xy 77.418295 -294.711778) (xy 77.377792 -294.739734) (xy 77.33333 -294.760832) (xy 77.286059 -294.774524)
			(xy 77.237204 -294.780456) (xy 77.188029 -294.778475) (xy 77.13981 -294.768631) (xy 77.093794 -294.751179)
			(xy 77.051173 -294.726572) (xy 77.013052 -294.695447) (xy 76.980417 -294.65861) (xy 76.954114 -294.617014)
			(xy 76.934823 -294.571738) (xy 76.923046 -294.523954) (xy 76.919086 -294.4749) (xy 76.580238 -294.4749)
			(xy 76.579743 -294.499507) (xy 76.571848 -294.548084) (xy 76.556264 -294.594765) (xy 76.533393 -294.638342)
			(xy 76.503828 -294.677686) (xy 76.468335 -294.711778) (xy 76.427832 -294.739734) (xy 76.38337 -294.760832)
			(xy 76.336099 -294.774524) (xy 76.287244 -294.780456) (xy 76.238069 -294.778475) (xy 76.18985 -294.768631)
			(xy 76.143834 -294.751179) (xy 76.101213 -294.726572) (xy 76.063092 -294.695447) (xy 76.030457 -294.65861)
			(xy 76.004154 -294.617014) (xy 75.984863 -294.571738) (xy 75.973086 -294.523954) (xy 75.969126 -294.4749)
			(xy 75.630278 -294.4749) (xy 75.629783 -294.499507) (xy 75.621888 -294.548084) (xy 75.606304 -294.594765)
			(xy 75.583433 -294.638342) (xy 75.553868 -294.677686) (xy 75.518375 -294.711778) (xy 75.477872 -294.739734)
			(xy 75.43341 -294.760832) (xy 75.386139 -294.774524) (xy 75.337284 -294.780456) (xy 75.288109 -294.778475)
			(xy 75.23989 -294.768631) (xy 75.193874 -294.751179) (xy 75.151253 -294.726572) (xy 75.113132 -294.695447)
			(xy 75.080497 -294.65861) (xy 75.054194 -294.617014) (xy 75.034903 -294.571738) (xy 75.023126 -294.523954)
			(xy 75.019166 -294.4749) (xy 74.680064 -294.4749) (xy 74.679569 -294.499507) (xy 74.671674 -294.548084)
			(xy 74.65609 -294.594765) (xy 74.633219 -294.638342) (xy 74.603654 -294.677686) (xy 74.568161 -294.711778)
			(xy 74.527658 -294.739734) (xy 74.483196 -294.760832) (xy 74.435925 -294.774524) (xy 74.38707 -294.780456)
			(xy 74.337895 -294.778475) (xy 74.289676 -294.768631) (xy 74.24366 -294.751179) (xy 74.201039 -294.726572)
			(xy 74.162918 -294.695447) (xy 74.130283 -294.65861) (xy 74.10398 -294.617014) (xy 74.084689 -294.571738)
			(xy 74.072912 -294.523954) (xy 74.068952 -294.4749) (xy 73.730104 -294.4749) (xy 73.729609 -294.499507)
			(xy 73.721714 -294.548084) (xy 73.70613 -294.594765) (xy 73.683259 -294.638342) (xy 73.653694 -294.677686)
			(xy 73.618201 -294.711778) (xy 73.577698 -294.739734) (xy 73.533236 -294.760832) (xy 73.485965 -294.774524)
			(xy 73.43711 -294.780456) (xy 73.387935 -294.778475) (xy 73.339716 -294.768631) (xy 73.2937 -294.751179)
			(xy 73.251079 -294.726572) (xy 73.212958 -294.695447) (xy 73.180323 -294.65861) (xy 73.15402 -294.617014)
			(xy 73.134729 -294.571738) (xy 73.122952 -294.523954) (xy 73.118992 -294.4749) (xy 71.830184 -294.4749)
			(xy 71.829689 -294.499507) (xy 71.821794 -294.548084) (xy 71.80621 -294.594765) (xy 71.783339 -294.638342)
			(xy 71.753774 -294.677686) (xy 71.718281 -294.711778) (xy 71.677778 -294.739734) (xy 71.633316 -294.760832)
			(xy 71.586045 -294.774524) (xy 71.53719 -294.780456) (xy 71.488015 -294.778475) (xy 71.439796 -294.768631)
			(xy 71.39378 -294.751179) (xy 71.351159 -294.726572) (xy 71.313038 -294.695447) (xy 71.280403 -294.65861)
			(xy 71.2541 -294.617014) (xy 71.234809 -294.571738) (xy 71.223032 -294.523954) (xy 71.219072 -294.4749)
			(xy 70.880224 -294.4749) (xy 70.879729 -294.499507) (xy 70.871834 -294.548084) (xy 70.85625 -294.594765)
			(xy 70.833379 -294.638342) (xy 70.803814 -294.677686) (xy 70.768321 -294.711778) (xy 70.727818 -294.739734)
			(xy 70.683356 -294.760832) (xy 70.636085 -294.774524) (xy 70.58723 -294.780456) (xy 70.538055 -294.778475)
			(xy 70.489836 -294.768631) (xy 70.44382 -294.751179) (xy 70.401199 -294.726572) (xy 70.363078 -294.695447)
			(xy 70.330443 -294.65861) (xy 70.30414 -294.617014) (xy 70.284849 -294.571738) (xy 70.273072 -294.523954)
			(xy 70.269112 -294.4749) (xy 69.930264 -294.4749) (xy 69.929769 -294.499507) (xy 69.921874 -294.548084)
			(xy 69.90629 -294.594765) (xy 69.883419 -294.638342) (xy 69.853854 -294.677686) (xy 69.818361 -294.711778)
			(xy 69.777858 -294.739734) (xy 69.733396 -294.760832) (xy 69.686125 -294.774524) (xy 69.63727 -294.780456)
			(xy 69.588095 -294.778475) (xy 69.539876 -294.768631) (xy 69.49386 -294.751179) (xy 69.451239 -294.726572)
			(xy 69.413118 -294.695447) (xy 69.380483 -294.65861) (xy 69.35418 -294.617014) (xy 69.334889 -294.571738)
			(xy 69.323112 -294.523954) (xy 69.319152 -294.4749) (xy 68.98005 -294.4749) (xy 68.979555 -294.499507)
			(xy 68.97166 -294.548084) (xy 68.956076 -294.594765) (xy 68.933205 -294.638342) (xy 68.90364 -294.677686)
			(xy 68.868147 -294.711778) (xy 68.827644 -294.739734) (xy 68.783182 -294.760832) (xy 68.735911 -294.774524)
			(xy 68.687056 -294.780456) (xy 68.637881 -294.778475) (xy 68.589662 -294.768631) (xy 68.543646 -294.751179)
			(xy 68.501025 -294.726572) (xy 68.462904 -294.695447) (xy 68.430269 -294.65861) (xy 68.403966 -294.617014)
			(xy 68.384675 -294.571738) (xy 68.372898 -294.523954) (xy 68.368938 -294.4749) (xy 68.03009 -294.4749)
			(xy 68.029595 -294.499507) (xy 68.0217 -294.548084) (xy 68.006116 -294.594765) (xy 67.983245 -294.638342)
			(xy 67.95368 -294.677686) (xy 67.918187 -294.711778) (xy 67.877684 -294.739734) (xy 67.833222 -294.760832)
			(xy 67.785951 -294.774524) (xy 67.737096 -294.780456) (xy 67.687921 -294.778475) (xy 67.639702 -294.768631)
			(xy 67.593686 -294.751179) (xy 67.551065 -294.726572) (xy 67.512944 -294.695447) (xy 67.480309 -294.65861)
			(xy 67.454006 -294.617014) (xy 67.434715 -294.571738) (xy 67.422938 -294.523954) (xy 67.418978 -294.4749)
			(xy 67.08013 -294.4749) (xy 67.079635 -294.499507) (xy 67.07174 -294.548084) (xy 67.056156 -294.594765)
			(xy 67.033285 -294.638342) (xy 67.00372 -294.677686) (xy 66.968227 -294.711778) (xy 66.927724 -294.739734)
			(xy 66.883262 -294.760832) (xy 66.835991 -294.774524) (xy 66.787136 -294.780456) (xy 66.737961 -294.778475)
			(xy 66.689742 -294.768631) (xy 66.643726 -294.751179) (xy 66.601105 -294.726572) (xy 66.562984 -294.695447)
			(xy 66.530349 -294.65861) (xy 66.504046 -294.617014) (xy 66.484755 -294.571738) (xy 66.472978 -294.523954)
			(xy 66.469018 -294.4749) (xy 66.13017 -294.4749) (xy 66.129675 -294.499507) (xy 66.12178 -294.548084)
			(xy 66.106196 -294.594765) (xy 66.083325 -294.638342) (xy 66.05376 -294.677686) (xy 66.018267 -294.711778)
			(xy 65.977764 -294.739734) (xy 65.933302 -294.760832) (xy 65.886031 -294.774524) (xy 65.837176 -294.780456)
			(xy 65.788001 -294.778475) (xy 65.739782 -294.768631) (xy 65.693766 -294.751179) (xy 65.651145 -294.726572)
			(xy 65.613024 -294.695447) (xy 65.580389 -294.65861) (xy 65.554086 -294.617014) (xy 65.534795 -294.571738)
			(xy 65.523018 -294.523954) (xy 65.519058 -294.4749) (xy 65.18021 -294.4749) (xy 65.179715 -294.499507)
			(xy 65.17182 -294.548084) (xy 65.156236 -294.594765) (xy 65.133365 -294.638342) (xy 65.1038 -294.677686)
			(xy 65.068307 -294.711778) (xy 65.027804 -294.739734) (xy 64.983342 -294.760832) (xy 64.936071 -294.774524)
			(xy 64.887216 -294.780456) (xy 64.838041 -294.778475) (xy 64.789822 -294.768631) (xy 64.743806 -294.751179)
			(xy 64.701185 -294.726572) (xy 64.663064 -294.695447) (xy 64.630429 -294.65861) (xy 64.604126 -294.617014)
			(xy 64.584835 -294.571738) (xy 64.573058 -294.523954) (xy 64.569098 -294.4749) (xy 64.23025 -294.4749)
			(xy 64.229755 -294.499507) (xy 64.22186 -294.548084) (xy 64.206276 -294.594765) (xy 64.183405 -294.638342)
			(xy 64.15384 -294.677686) (xy 64.118347 -294.711778) (xy 64.077844 -294.739734) (xy 64.033382 -294.760832)
			(xy 63.986111 -294.774524) (xy 63.937256 -294.780456) (xy 63.888081 -294.778475) (xy 63.839862 -294.768631)
			(xy 63.793846 -294.751179) (xy 63.751225 -294.726572) (xy 63.713104 -294.695447) (xy 63.680469 -294.65861)
			(xy 63.654166 -294.617014) (xy 63.634875 -294.571738) (xy 63.623098 -294.523954) (xy 63.619138 -294.4749)
			(xy 63.28029 -294.4749) (xy 63.279795 -294.499507) (xy 63.2719 -294.548084) (xy 63.256316 -294.594765)
			(xy 63.233445 -294.638342) (xy 63.20388 -294.677686) (xy 63.168387 -294.711778) (xy 63.127884 -294.739734)
			(xy 63.083422 -294.760832) (xy 63.036151 -294.774524) (xy 62.987296 -294.780456) (xy 62.938121 -294.778475)
			(xy 62.889902 -294.768631) (xy 62.843886 -294.751179) (xy 62.801265 -294.726572) (xy 62.763144 -294.695447)
			(xy 62.730509 -294.65861) (xy 62.704206 -294.617014) (xy 62.684915 -294.571738) (xy 62.673138 -294.523954)
			(xy 62.669178 -294.4749) (xy 62.330076 -294.4749) (xy 62.329581 -294.499507) (xy 62.321686 -294.548084)
			(xy 62.306102 -294.594765) (xy 62.283231 -294.638342) (xy 62.253666 -294.677686) (xy 62.218173 -294.711778)
			(xy 62.17767 -294.739734) (xy 62.133208 -294.760832) (xy 62.085937 -294.774524) (xy 62.037082 -294.780456)
			(xy 61.987907 -294.778475) (xy 61.939688 -294.768631) (xy 61.893672 -294.751179) (xy 61.851051 -294.726572)
			(xy 61.81293 -294.695447) (xy 61.780295 -294.65861) (xy 61.753992 -294.617014) (xy 61.734701 -294.571738)
			(xy 61.722924 -294.523954) (xy 61.718964 -294.4749) (xy 61.380116 -294.4749) (xy 61.379621 -294.499507)
			(xy 61.371726 -294.548084) (xy 61.356142 -294.594765) (xy 61.333271 -294.638342) (xy 61.303706 -294.677686)
			(xy 61.268213 -294.711778) (xy 61.22771 -294.739734) (xy 61.183248 -294.760832) (xy 61.135977 -294.774524)
			(xy 61.087122 -294.780456) (xy 61.037947 -294.778475) (xy 60.989728 -294.768631) (xy 60.943712 -294.751179)
			(xy 60.901091 -294.726572) (xy 60.86297 -294.695447) (xy 60.830335 -294.65861) (xy 60.804032 -294.617014)
			(xy 60.784741 -294.571738) (xy 60.772964 -294.523954) (xy 60.769004 -294.4749) (xy 60.430156 -294.4749)
			(xy 60.429661 -294.499507) (xy 60.421766 -294.548084) (xy 60.406182 -294.594765) (xy 60.383311 -294.638342)
			(xy 60.353746 -294.677686) (xy 60.318253 -294.711778) (xy 60.27775 -294.739734) (xy 60.233288 -294.760832)
			(xy 60.186017 -294.774524) (xy 60.137162 -294.780456) (xy 60.087987 -294.778475) (xy 60.039768 -294.768631)
			(xy 59.993752 -294.751179) (xy 59.951131 -294.726572) (xy 59.91301 -294.695447) (xy 59.880375 -294.65861)
			(xy 59.854072 -294.617014) (xy 59.834781 -294.571738) (xy 59.823004 -294.523954) (xy 59.819044 -294.4749)
			(xy 58.530236 -294.4749) (xy 58.529741 -294.499507) (xy 58.521846 -294.548084) (xy 58.506262 -294.594765)
			(xy 58.483391 -294.638342) (xy 58.453826 -294.677686) (xy 58.418333 -294.711778) (xy 58.37783 -294.739734)
			(xy 58.333368 -294.760832) (xy 58.286097 -294.774524) (xy 58.237242 -294.780456) (xy 58.188067 -294.778475)
			(xy 58.139848 -294.768631) (xy 58.093832 -294.751179) (xy 58.051211 -294.726572) (xy 58.01309 -294.695447)
			(xy 57.980455 -294.65861) (xy 57.954152 -294.617014) (xy 57.934861 -294.571738) (xy 57.923084 -294.523954)
			(xy 57.919124 -294.4749) (xy 57.580276 -294.4749) (xy 57.579781 -294.499507) (xy 57.571886 -294.548084)
			(xy 57.556302 -294.594765) (xy 57.533431 -294.638342) (xy 57.503866 -294.677686) (xy 57.468373 -294.711778)
			(xy 57.42787 -294.739734) (xy 57.383408 -294.760832) (xy 57.336137 -294.774524) (xy 57.287282 -294.780456)
			(xy 57.238107 -294.778475) (xy 57.189888 -294.768631) (xy 57.143872 -294.751179) (xy 57.101251 -294.726572)
			(xy 57.06313 -294.695447) (xy 57.030495 -294.65861) (xy 57.004192 -294.617014) (xy 56.984901 -294.571738)
			(xy 56.973124 -294.523954) (xy 56.969164 -294.4749) (xy 56.630062 -294.4749) (xy 56.629567 -294.499507)
			(xy 56.621672 -294.548084) (xy 56.606088 -294.594765) (xy 56.583217 -294.638342) (xy 56.553652 -294.677686)
			(xy 56.518159 -294.711778) (xy 56.477656 -294.739734) (xy 56.433194 -294.760832) (xy 56.385923 -294.774524)
			(xy 56.337068 -294.780456) (xy 56.287893 -294.778475) (xy 56.239674 -294.768631) (xy 56.193658 -294.751179)
			(xy 56.151037 -294.726572) (xy 56.112916 -294.695447) (xy 56.080281 -294.65861) (xy 56.053978 -294.617014)
			(xy 56.034687 -294.571738) (xy 56.02291 -294.523954) (xy 56.01895 -294.4749) (xy 55.680102 -294.4749)
			(xy 55.679607 -294.499507) (xy 55.671712 -294.548084) (xy 55.656128 -294.594765) (xy 55.633257 -294.638342)
			(xy 55.603692 -294.677686) (xy 55.568199 -294.711778) (xy 55.527696 -294.739734) (xy 55.483234 -294.760832)
			(xy 55.435963 -294.774524) (xy 55.387108 -294.780456) (xy 55.337933 -294.778475) (xy 55.289714 -294.768631)
			(xy 55.243698 -294.751179) (xy 55.201077 -294.726572) (xy 55.162956 -294.695447) (xy 55.130321 -294.65861)
			(xy 55.104018 -294.617014) (xy 55.084727 -294.571738) (xy 55.07295 -294.523954) (xy 55.06899 -294.4749)
			(xy 54.730142 -294.4749) (xy 54.729647 -294.499507) (xy 54.721752 -294.548084) (xy 54.706168 -294.594765)
			(xy 54.683297 -294.638342) (xy 54.653732 -294.677686) (xy 54.618239 -294.711778) (xy 54.577736 -294.739734)
			(xy 54.533274 -294.760832) (xy 54.486003 -294.774524) (xy 54.437148 -294.780456) (xy 54.387973 -294.778475)
			(xy 54.339754 -294.768631) (xy 54.293738 -294.751179) (xy 54.251117 -294.726572) (xy 54.212996 -294.695447)
			(xy 54.180361 -294.65861) (xy 54.154058 -294.617014) (xy 54.134767 -294.571738) (xy 54.12299 -294.523954)
			(xy 54.11903 -294.4749) (xy 53.780182 -294.4749) (xy 53.779687 -294.499507) (xy 53.771792 -294.548084)
			(xy 53.756208 -294.594765) (xy 53.733337 -294.638342) (xy 53.703772 -294.677686) (xy 53.668279 -294.711778)
			(xy 53.627776 -294.739734) (xy 53.583314 -294.760832) (xy 53.536043 -294.774524) (xy 53.487188 -294.780456)
			(xy 53.438013 -294.778475) (xy 53.389794 -294.768631) (xy 53.343778 -294.751179) (xy 53.301157 -294.726572)
			(xy 53.263036 -294.695447) (xy 53.230401 -294.65861) (xy 53.204098 -294.617014) (xy 53.184807 -294.571738)
			(xy 53.17303 -294.523954) (xy 53.16907 -294.4749) (xy 52.830222 -294.4749) (xy 52.829727 -294.499507)
			(xy 52.821832 -294.548084) (xy 52.806248 -294.594765) (xy 52.783377 -294.638342) (xy 52.753812 -294.677686)
			(xy 52.718319 -294.711778) (xy 52.677816 -294.739734) (xy 52.633354 -294.760832) (xy 52.586083 -294.774524)
			(xy 52.537228 -294.780456) (xy 52.488053 -294.778475) (xy 52.439834 -294.768631) (xy 52.393818 -294.751179)
			(xy 52.351197 -294.726572) (xy 52.313076 -294.695447) (xy 52.280441 -294.65861) (xy 52.254138 -294.617014)
			(xy 52.234847 -294.571738) (xy 52.22307 -294.523954) (xy 52.21911 -294.4749) (xy 51.880262 -294.4749)
			(xy 51.879767 -294.499507) (xy 51.871872 -294.548084) (xy 51.856288 -294.594765) (xy 51.833417 -294.638342)
			(xy 51.803852 -294.677686) (xy 51.768359 -294.711778) (xy 51.727856 -294.739734) (xy 51.683394 -294.760832)
			(xy 51.636123 -294.774524) (xy 51.587268 -294.780456) (xy 51.538093 -294.778475) (xy 51.489874 -294.768631)
			(xy 51.443858 -294.751179) (xy 51.401237 -294.726572) (xy 51.363116 -294.695447) (xy 51.330481 -294.65861)
			(xy 51.304178 -294.617014) (xy 51.284887 -294.571738) (xy 51.27311 -294.523954) (xy 51.26915 -294.4749)
			(xy 50.930302 -294.4749) (xy 50.929807 -294.499507) (xy 50.921912 -294.548084) (xy 50.906328 -294.594765)
			(xy 50.883457 -294.638342) (xy 50.853892 -294.677686) (xy 50.818399 -294.711778) (xy 50.777896 -294.739734)
			(xy 50.733434 -294.760832) (xy 50.686163 -294.774524) (xy 50.637308 -294.780456) (xy 50.588133 -294.778475)
			(xy 50.539914 -294.768631) (xy 50.493898 -294.751179) (xy 50.451277 -294.726572) (xy 50.413156 -294.695447)
			(xy 50.380521 -294.65861) (xy 50.354218 -294.617014) (xy 50.334927 -294.571738) (xy 50.32315 -294.523954)
			(xy 50.31919 -294.4749) (xy 49.980088 -294.4749) (xy 49.979593 -294.499507) (xy 49.971698 -294.548084)
			(xy 49.956114 -294.594765) (xy 49.933243 -294.638342) (xy 49.903678 -294.677686) (xy 49.868185 -294.711778)
			(xy 49.827682 -294.739734) (xy 49.78322 -294.760832) (xy 49.735949 -294.774524) (xy 49.687094 -294.780456)
			(xy 49.637919 -294.778475) (xy 49.5897 -294.768631) (xy 49.543684 -294.751179) (xy 49.501063 -294.726572)
			(xy 49.462942 -294.695447) (xy 49.430307 -294.65861) (xy 49.404004 -294.617014) (xy 49.384713 -294.571738)
			(xy 49.372936 -294.523954) (xy 49.368976 -294.4749) (xy 49.030128 -294.4749) (xy 49.029633 -294.499507)
			(xy 49.021738 -294.548084) (xy 49.006154 -294.594765) (xy 48.983283 -294.638342) (xy 48.953718 -294.677686)
			(xy 48.918225 -294.711778) (xy 48.877722 -294.739734) (xy 48.83326 -294.760832) (xy 48.785989 -294.774524)
			(xy 48.737134 -294.780456) (xy 48.687959 -294.778475) (xy 48.63974 -294.768631) (xy 48.593724 -294.751179)
			(xy 48.551103 -294.726572) (xy 48.512982 -294.695447) (xy 48.480347 -294.65861) (xy 48.454044 -294.617014)
			(xy 48.434753 -294.571738) (xy 48.422976 -294.523954) (xy 48.419016 -294.4749) (xy 48.08076 -294.4749)
			(xy 48.076588 -294.525247) (xy 48.064185 -294.574221) (xy 48.04389 -294.620484) (xy 48.016256 -294.662776)
			(xy 47.982038 -294.699943) (xy 47.942168 -294.73097) (xy 47.897736 -294.75501) (xy 47.849951 -294.771409)
			(xy 47.80012 -294.779718) (xy 47.77486 -294.780208) (xy 47.751321 -294.779786) (xy 47.704799 -294.772571)
			(xy 47.659936 -294.758303) (xy 47.617793 -294.73732) (xy 47.59833 -294.724074) (xy 47.598076 -294.724074)
			(xy 47.590268 -294.719075) (xy 47.572344 -294.714413) (xy 47.553931 -294.716418) (xy 47.545498 -294.720264)
			(xy 47.465488 -294.761666) (xy 47.457449 -294.766342) (xy 47.445103 -294.780228) (xy 47.438479 -294.797588)
			(xy 47.438056 -294.806878) (xy 47.438056 -295.598088) (xy 47.437612 -295.622094) (xy 47.430065 -295.669508)
			(xy 47.415187 -295.715157) (xy 47.393344 -295.757912) (xy 47.365076 -295.79672) (xy 47.348394 -295.813988)
			(xy 47.110142 -296.05224) (xy 47.092844 -296.068832) (xy 47.054065 -296.097) (xy 47.011366 -296.11877)
			(xy 46.965792 -296.133608) (xy 46.91846 -296.14115) (xy 46.894496 -296.141648) (xy 46.867826 -296.141648)
			(xy 46.857577 -296.142102) (xy 46.838703 -296.150093) (xy 46.83125 -296.157142) (xy 46.780704 -296.209974)
			(xy 46.773592 -296.229532) (xy 46.7741 -296.2402) (xy 46.7741 -296.240708) (xy 46.774862 -296.25798)
			(xy 46.762416 -296.346372) (xy 46.759876 -296.354754) (xy 46.759622 -296.356278) (xy 46.758399 -296.360625)
			(xy 46.756998 -296.369546) (xy 46.756828 -296.374058) (xy 46.756828 -296.37482) (xy 47.469056 -296.37482)
			(xy 47.473016 -296.325766) (xy 47.484793 -296.277982) (xy 47.504084 -296.232706) (xy 47.530387 -296.19111)
			(xy 47.563022 -296.154273) (xy 47.601143 -296.123148) (xy 47.643764 -296.098541) (xy 47.68978 -296.081089)
			(xy 47.737999 -296.071245) (xy 47.787174 -296.069264) (xy 47.836029 -296.075196) (xy 47.8833 -296.088888)
			(xy 47.927762 -296.109986) (xy 47.968265 -296.137942) (xy 48.003758 -296.172034) (xy 48.033323 -296.211378)
			(xy 48.056194 -296.254955) (xy 48.071778 -296.301636) (xy 48.079673 -296.350213) (xy 48.080168 -296.37482)
			(xy 48.419016 -296.37482) (xy 48.422976 -296.325766) (xy 48.434753 -296.277982) (xy 48.454044 -296.232706)
			(xy 48.480347 -296.19111) (xy 48.512982 -296.154273) (xy 48.551103 -296.123148) (xy 48.593724 -296.098541)
			(xy 48.63974 -296.081089) (xy 48.687959 -296.071245) (xy 48.737134 -296.069264) (xy 48.785989 -296.075196)
			(xy 48.83326 -296.088888) (xy 48.877722 -296.109986) (xy 48.918225 -296.137942) (xy 48.953718 -296.172034)
			(xy 48.983283 -296.211378) (xy 49.006154 -296.254955) (xy 49.021738 -296.301636) (xy 49.029633 -296.350213)
			(xy 49.030128 -296.37482) (xy 49.368976 -296.37482) (xy 49.372936 -296.325766) (xy 49.384713 -296.277982)
			(xy 49.404004 -296.232706) (xy 49.430307 -296.19111) (xy 49.462942 -296.154273) (xy 49.501063 -296.123148)
			(xy 49.543684 -296.098541) (xy 49.5897 -296.081089) (xy 49.637919 -296.071245) (xy 49.687094 -296.069264)
			(xy 49.735949 -296.075196) (xy 49.78322 -296.088888) (xy 49.827682 -296.109986) (xy 49.868185 -296.137942)
			(xy 49.903678 -296.172034) (xy 49.933243 -296.211378) (xy 49.956114 -296.254955) (xy 49.971698 -296.301636)
			(xy 49.979593 -296.350213) (xy 49.980088 -296.37482) (xy 50.31919 -296.37482) (xy 50.32315 -296.325766)
			(xy 50.334927 -296.277982) (xy 50.354218 -296.232706) (xy 50.380521 -296.19111) (xy 50.413156 -296.154273)
			(xy 50.451277 -296.123148) (xy 50.493898 -296.098541) (xy 50.539914 -296.081089) (xy 50.588133 -296.071245)
			(xy 50.637308 -296.069264) (xy 50.686163 -296.075196) (xy 50.733434 -296.088888) (xy 50.777896 -296.109986)
			(xy 50.818399 -296.137942) (xy 50.853892 -296.172034) (xy 50.883457 -296.211378) (xy 50.906328 -296.254955)
			(xy 50.921912 -296.301636) (xy 50.929807 -296.350213) (xy 50.930302 -296.37482) (xy 51.26915 -296.37482)
			(xy 51.27311 -296.325766) (xy 51.284887 -296.277982) (xy 51.304178 -296.232706) (xy 51.330481 -296.19111)
			(xy 51.363116 -296.154273) (xy 51.401237 -296.123148) (xy 51.443858 -296.098541) (xy 51.489874 -296.081089)
			(xy 51.538093 -296.071245) (xy 51.587268 -296.069264) (xy 51.636123 -296.075196) (xy 51.683394 -296.088888)
			(xy 51.727856 -296.109986) (xy 51.768359 -296.137942) (xy 51.803852 -296.172034) (xy 51.833417 -296.211378)
			(xy 51.856288 -296.254955) (xy 51.871872 -296.301636) (xy 51.879767 -296.350213) (xy 51.880262 -296.37482)
			(xy 52.21911 -296.37482) (xy 52.22307 -296.325766) (xy 52.234847 -296.277982) (xy 52.254138 -296.232706)
			(xy 52.280441 -296.19111) (xy 52.313076 -296.154273) (xy 52.351197 -296.123148) (xy 52.393818 -296.098541)
			(xy 52.439834 -296.081089) (xy 52.488053 -296.071245) (xy 52.537228 -296.069264) (xy 52.586083 -296.075196)
			(xy 52.633354 -296.088888) (xy 52.677816 -296.109986) (xy 52.718319 -296.137942) (xy 52.753812 -296.172034)
			(xy 52.783377 -296.211378) (xy 52.806248 -296.254955) (xy 52.821832 -296.301636) (xy 52.829727 -296.350213)
			(xy 52.830222 -296.37482) (xy 53.16907 -296.37482) (xy 53.17303 -296.325766) (xy 53.184807 -296.277982)
			(xy 53.204098 -296.232706) (xy 53.230401 -296.19111) (xy 53.263036 -296.154273) (xy 53.301157 -296.123148)
			(xy 53.343778 -296.098541) (xy 53.389794 -296.081089) (xy 53.438013 -296.071245) (xy 53.487188 -296.069264)
			(xy 53.536043 -296.075196) (xy 53.583314 -296.088888) (xy 53.627776 -296.109986) (xy 53.668279 -296.137942)
			(xy 53.703772 -296.172034) (xy 53.733337 -296.211378) (xy 53.756208 -296.254955) (xy 53.771792 -296.301636)
			(xy 53.779687 -296.350213) (xy 53.780182 -296.37482) (xy 54.11903 -296.37482) (xy 54.12299 -296.325766)
			(xy 54.134767 -296.277982) (xy 54.154058 -296.232706) (xy 54.180361 -296.19111) (xy 54.212996 -296.154273)
			(xy 54.251117 -296.123148) (xy 54.293738 -296.098541) (xy 54.339754 -296.081089) (xy 54.387973 -296.071245)
			(xy 54.437148 -296.069264) (xy 54.486003 -296.075196) (xy 54.533274 -296.088888) (xy 54.577736 -296.109986)
			(xy 54.618239 -296.137942) (xy 54.653732 -296.172034) (xy 54.683297 -296.211378) (xy 54.706168 -296.254955)
			(xy 54.721752 -296.301636) (xy 54.729647 -296.350213) (xy 54.730142 -296.37482) (xy 55.06899 -296.37482)
			(xy 55.07295 -296.325766) (xy 55.084727 -296.277982) (xy 55.104018 -296.232706) (xy 55.130321 -296.19111)
			(xy 55.162956 -296.154273) (xy 55.201077 -296.123148) (xy 55.243698 -296.098541) (xy 55.289714 -296.081089)
			(xy 55.337933 -296.071245) (xy 55.387108 -296.069264) (xy 55.435963 -296.075196) (xy 55.483234 -296.088888)
			(xy 55.527696 -296.109986) (xy 55.568199 -296.137942) (xy 55.603692 -296.172034) (xy 55.633257 -296.211378)
			(xy 55.656128 -296.254955) (xy 55.671712 -296.301636) (xy 55.679607 -296.350213) (xy 55.680102 -296.37482)
			(xy 56.019204 -296.37482) (xy 56.023164 -296.325766) (xy 56.034941 -296.277982) (xy 56.054232 -296.232706)
			(xy 56.080535 -296.19111) (xy 56.11317 -296.154273) (xy 56.151291 -296.123148) (xy 56.193912 -296.098541)
			(xy 56.239928 -296.081089) (xy 56.288147 -296.071245) (xy 56.337322 -296.069264) (xy 56.386177 -296.075196)
			(xy 56.433448 -296.088888) (xy 56.47791 -296.109986) (xy 56.518413 -296.137942) (xy 56.553906 -296.172034)
			(xy 56.583471 -296.211378) (xy 56.606342 -296.254955) (xy 56.621926 -296.301636) (xy 56.629821 -296.350213)
			(xy 56.630316 -296.37482) (xy 56.969164 -296.37482) (xy 56.973124 -296.325766) (xy 56.984901 -296.277982)
			(xy 57.004192 -296.232706) (xy 57.030495 -296.19111) (xy 57.06313 -296.154273) (xy 57.101251 -296.123148)
			(xy 57.143872 -296.098541) (xy 57.189888 -296.081089) (xy 57.238107 -296.071245) (xy 57.287282 -296.069264)
			(xy 57.336137 -296.075196) (xy 57.383408 -296.088888) (xy 57.42787 -296.109986) (xy 57.468373 -296.137942)
			(xy 57.503866 -296.172034) (xy 57.533431 -296.211378) (xy 57.556302 -296.254955) (xy 57.571886 -296.301636)
			(xy 57.579781 -296.350213) (xy 57.580276 -296.37482) (xy 57.919124 -296.37482) (xy 57.923084 -296.325766)
			(xy 57.934861 -296.277982) (xy 57.954152 -296.232706) (xy 57.980455 -296.19111) (xy 58.01309 -296.154273)
			(xy 58.051211 -296.123148) (xy 58.093832 -296.098541) (xy 58.139848 -296.081089) (xy 58.188067 -296.071245)
			(xy 58.237242 -296.069264) (xy 58.286097 -296.075196) (xy 58.333368 -296.088888) (xy 58.37783 -296.109986)
			(xy 58.418333 -296.137942) (xy 58.453826 -296.172034) (xy 58.483391 -296.211378) (xy 58.506262 -296.254955)
			(xy 58.521846 -296.301636) (xy 58.529741 -296.350213) (xy 58.530236 -296.37482) (xy 59.819044 -296.37482)
			(xy 59.823004 -296.325766) (xy 59.834781 -296.277982) (xy 59.854072 -296.232706) (xy 59.880375 -296.19111)
			(xy 59.91301 -296.154273) (xy 59.951131 -296.123148) (xy 59.993752 -296.098541) (xy 60.039768 -296.081089)
			(xy 60.087987 -296.071245) (xy 60.137162 -296.069264) (xy 60.186017 -296.075196) (xy 60.233288 -296.088888)
			(xy 60.27775 -296.109986) (xy 60.318253 -296.137942) (xy 60.353746 -296.172034) (xy 60.383311 -296.211378)
			(xy 60.406182 -296.254955) (xy 60.421766 -296.301636) (xy 60.429661 -296.350213) (xy 60.430156 -296.37482)
			(xy 60.769004 -296.37482) (xy 60.772964 -296.325766) (xy 60.784741 -296.277982) (xy 60.804032 -296.232706)
			(xy 60.830335 -296.19111) (xy 60.86297 -296.154273) (xy 60.901091 -296.123148) (xy 60.943712 -296.098541)
			(xy 60.989728 -296.081089) (xy 61.037947 -296.071245) (xy 61.087122 -296.069264) (xy 61.135977 -296.075196)
			(xy 61.183248 -296.088888) (xy 61.22771 -296.109986) (xy 61.268213 -296.137942) (xy 61.303706 -296.172034)
			(xy 61.333271 -296.211378) (xy 61.356142 -296.254955) (xy 61.371726 -296.301636) (xy 61.379621 -296.350213)
			(xy 61.380116 -296.37482) (xy 61.718964 -296.37482) (xy 61.722924 -296.325766) (xy 61.734701 -296.277982)
			(xy 61.753992 -296.232706) (xy 61.780295 -296.19111) (xy 61.81293 -296.154273) (xy 61.851051 -296.123148)
			(xy 61.893672 -296.098541) (xy 61.939688 -296.081089) (xy 61.987907 -296.071245) (xy 62.037082 -296.069264)
			(xy 62.085937 -296.075196) (xy 62.133208 -296.088888) (xy 62.17767 -296.109986) (xy 62.218173 -296.137942)
			(xy 62.253666 -296.172034) (xy 62.283231 -296.211378) (xy 62.306102 -296.254955) (xy 62.321686 -296.301636)
			(xy 62.329581 -296.350213) (xy 62.330076 -296.37482) (xy 62.669178 -296.37482) (xy 62.673138 -296.325766)
			(xy 62.684915 -296.277982) (xy 62.704206 -296.232706) (xy 62.730509 -296.19111) (xy 62.763144 -296.154273)
			(xy 62.801265 -296.123148) (xy 62.843886 -296.098541) (xy 62.889902 -296.081089) (xy 62.938121 -296.071245)
			(xy 62.987296 -296.069264) (xy 63.036151 -296.075196) (xy 63.083422 -296.088888) (xy 63.127884 -296.109986)
			(xy 63.168387 -296.137942) (xy 63.20388 -296.172034) (xy 63.233445 -296.211378) (xy 63.256316 -296.254955)
			(xy 63.2719 -296.301636) (xy 63.279795 -296.350213) (xy 63.28029 -296.37482) (xy 63.619138 -296.37482)
			(xy 63.623098 -296.325766) (xy 63.634875 -296.277982) (xy 63.654166 -296.232706) (xy 63.680469 -296.19111)
			(xy 63.713104 -296.154273) (xy 63.751225 -296.123148) (xy 63.793846 -296.098541) (xy 63.839862 -296.081089)
			(xy 63.888081 -296.071245) (xy 63.937256 -296.069264) (xy 63.986111 -296.075196) (xy 64.033382 -296.088888)
			(xy 64.077844 -296.109986) (xy 64.118347 -296.137942) (xy 64.15384 -296.172034) (xy 64.183405 -296.211378)
			(xy 64.206276 -296.254955) (xy 64.22186 -296.301636) (xy 64.229755 -296.350213) (xy 64.23025 -296.37482)
			(xy 64.569098 -296.37482) (xy 64.573058 -296.325766) (xy 64.584835 -296.277982) (xy 64.604126 -296.232706)
			(xy 64.630429 -296.19111) (xy 64.663064 -296.154273) (xy 64.701185 -296.123148) (xy 64.743806 -296.098541)
			(xy 64.789822 -296.081089) (xy 64.838041 -296.071245) (xy 64.887216 -296.069264) (xy 64.936071 -296.075196)
			(xy 64.983342 -296.088888) (xy 65.027804 -296.109986) (xy 65.068307 -296.137942) (xy 65.1038 -296.172034)
			(xy 65.133365 -296.211378) (xy 65.156236 -296.254955) (xy 65.17182 -296.301636) (xy 65.179715 -296.350213)
			(xy 65.18021 -296.37482) (xy 65.519058 -296.37482) (xy 65.523018 -296.325766) (xy 65.534795 -296.277982)
			(xy 65.554086 -296.232706) (xy 65.580389 -296.19111) (xy 65.613024 -296.154273) (xy 65.651145 -296.123148)
			(xy 65.693766 -296.098541) (xy 65.739782 -296.081089) (xy 65.788001 -296.071245) (xy 65.837176 -296.069264)
			(xy 65.886031 -296.075196) (xy 65.933302 -296.088888) (xy 65.977764 -296.109986) (xy 66.018267 -296.137942)
			(xy 66.05376 -296.172034) (xy 66.083325 -296.211378) (xy 66.106196 -296.254955) (xy 66.12178 -296.301636)
			(xy 66.129675 -296.350213) (xy 66.13017 -296.37482) (xy 66.469018 -296.37482) (xy 66.472978 -296.325766)
			(xy 66.484755 -296.277982) (xy 66.504046 -296.232706) (xy 66.530349 -296.19111) (xy 66.562984 -296.154273)
			(xy 66.601105 -296.123148) (xy 66.643726 -296.098541) (xy 66.689742 -296.081089) (xy 66.737961 -296.071245)
			(xy 66.787136 -296.069264) (xy 66.835991 -296.075196) (xy 66.883262 -296.088888) (xy 66.927724 -296.109986)
			(xy 66.968227 -296.137942) (xy 67.00372 -296.172034) (xy 67.033285 -296.211378) (xy 67.056156 -296.254955)
			(xy 67.07174 -296.301636) (xy 67.079635 -296.350213) (xy 67.08013 -296.37482) (xy 67.418978 -296.37482)
			(xy 67.422938 -296.325766) (xy 67.434715 -296.277982) (xy 67.454006 -296.232706) (xy 67.480309 -296.19111)
			(xy 67.512944 -296.154273) (xy 67.551065 -296.123148) (xy 67.593686 -296.098541) (xy 67.639702 -296.081089)
			(xy 67.687921 -296.071245) (xy 67.737096 -296.069264) (xy 67.785951 -296.075196) (xy 67.833222 -296.088888)
			(xy 67.877684 -296.109986) (xy 67.918187 -296.137942) (xy 67.95368 -296.172034) (xy 67.983245 -296.211378)
			(xy 68.006116 -296.254955) (xy 68.0217 -296.301636) (xy 68.029595 -296.350213) (xy 68.03009 -296.37482)
			(xy 68.368938 -296.37482) (xy 68.372898 -296.325766) (xy 68.384675 -296.277982) (xy 68.403966 -296.232706)
			(xy 68.430269 -296.19111) (xy 68.462904 -296.154273) (xy 68.501025 -296.123148) (xy 68.543646 -296.098541)
			(xy 68.589662 -296.081089) (xy 68.637881 -296.071245) (xy 68.687056 -296.069264) (xy 68.735911 -296.075196)
			(xy 68.783182 -296.088888) (xy 68.827644 -296.109986) (xy 68.868147 -296.137942) (xy 68.90364 -296.172034)
			(xy 68.933205 -296.211378) (xy 68.956076 -296.254955) (xy 68.97166 -296.301636) (xy 68.979555 -296.350213)
			(xy 68.98005 -296.37482) (xy 69.319152 -296.37482) (xy 69.323112 -296.325766) (xy 69.334889 -296.277982)
			(xy 69.35418 -296.232706) (xy 69.380483 -296.19111) (xy 69.413118 -296.154273) (xy 69.451239 -296.123148)
			(xy 69.49386 -296.098541) (xy 69.539876 -296.081089) (xy 69.588095 -296.071245) (xy 69.63727 -296.069264)
			(xy 69.686125 -296.075196) (xy 69.733396 -296.088888) (xy 69.777858 -296.109986) (xy 69.818361 -296.137942)
			(xy 69.853854 -296.172034) (xy 69.883419 -296.211378) (xy 69.90629 -296.254955) (xy 69.921874 -296.301636)
			(xy 69.929769 -296.350213) (xy 69.930264 -296.37482) (xy 70.269112 -296.37482) (xy 70.273072 -296.325766)
			(xy 70.284849 -296.277982) (xy 70.30414 -296.232706) (xy 70.330443 -296.19111) (xy 70.363078 -296.154273)
			(xy 70.401199 -296.123148) (xy 70.44382 -296.098541) (xy 70.489836 -296.081089) (xy 70.538055 -296.071245)
			(xy 70.58723 -296.069264) (xy 70.636085 -296.075196) (xy 70.683356 -296.088888) (xy 70.727818 -296.109986)
			(xy 70.768321 -296.137942) (xy 70.803814 -296.172034) (xy 70.833379 -296.211378) (xy 70.85625 -296.254955)
			(xy 70.871834 -296.301636) (xy 70.879729 -296.350213) (xy 70.880224 -296.37482) (xy 71.219072 -296.37482)
			(xy 71.223032 -296.325766) (xy 71.234809 -296.277982) (xy 71.2541 -296.232706) (xy 71.280403 -296.19111)
			(xy 71.313038 -296.154273) (xy 71.351159 -296.123148) (xy 71.39378 -296.098541) (xy 71.439796 -296.081089)
			(xy 71.488015 -296.071245) (xy 71.53719 -296.069264) (xy 71.586045 -296.075196) (xy 71.633316 -296.088888)
			(xy 71.677778 -296.109986) (xy 71.718281 -296.137942) (xy 71.753774 -296.172034) (xy 71.783339 -296.211378)
			(xy 71.80621 -296.254955) (xy 71.821794 -296.301636) (xy 71.829689 -296.350213) (xy 71.830184 -296.37482)
			(xy 73.118992 -296.37482) (xy 73.122952 -296.325766) (xy 73.134729 -296.277982) (xy 73.15402 -296.232706)
			(xy 73.180323 -296.19111) (xy 73.212958 -296.154273) (xy 73.251079 -296.123148) (xy 73.2937 -296.098541)
			(xy 73.339716 -296.081089) (xy 73.387935 -296.071245) (xy 73.43711 -296.069264) (xy 73.485965 -296.075196)
			(xy 73.533236 -296.088888) (xy 73.577698 -296.109986) (xy 73.618201 -296.137942) (xy 73.653694 -296.172034)
			(xy 73.683259 -296.211378) (xy 73.70613 -296.254955) (xy 73.721714 -296.301636) (xy 73.729609 -296.350213)
			(xy 73.730104 -296.37482) (xy 74.068952 -296.37482) (xy 74.072912 -296.325766) (xy 74.084689 -296.277982)
			(xy 74.10398 -296.232706) (xy 74.130283 -296.19111) (xy 74.162918 -296.154273) (xy 74.201039 -296.123148)
			(xy 74.24366 -296.098541) (xy 74.289676 -296.081089) (xy 74.337895 -296.071245) (xy 74.38707 -296.069264)
			(xy 74.435925 -296.075196) (xy 74.483196 -296.088888) (xy 74.527658 -296.109986) (xy 74.568161 -296.137942)
			(xy 74.603654 -296.172034) (xy 74.633219 -296.211378) (xy 74.65609 -296.254955) (xy 74.671674 -296.301636)
			(xy 74.679569 -296.350213) (xy 74.680064 -296.37482) (xy 75.019166 -296.37482) (xy 75.023126 -296.325766)
			(xy 75.034903 -296.277982) (xy 75.054194 -296.232706) (xy 75.080497 -296.19111) (xy 75.113132 -296.154273)
			(xy 75.151253 -296.123148) (xy 75.193874 -296.098541) (xy 75.23989 -296.081089) (xy 75.288109 -296.071245)
			(xy 75.337284 -296.069264) (xy 75.386139 -296.075196) (xy 75.43341 -296.088888) (xy 75.477872 -296.109986)
			(xy 75.518375 -296.137942) (xy 75.553868 -296.172034) (xy 75.583433 -296.211378) (xy 75.606304 -296.254955)
			(xy 75.621888 -296.301636) (xy 75.629783 -296.350213) (xy 75.630278 -296.37482) (xy 75.969126 -296.37482)
			(xy 75.973086 -296.325766) (xy 75.984863 -296.277982) (xy 76.004154 -296.232706) (xy 76.030457 -296.19111)
			(xy 76.063092 -296.154273) (xy 76.101213 -296.123148) (xy 76.143834 -296.098541) (xy 76.18985 -296.081089)
			(xy 76.238069 -296.071245) (xy 76.287244 -296.069264) (xy 76.336099 -296.075196) (xy 76.38337 -296.088888)
			(xy 76.427832 -296.109986) (xy 76.468335 -296.137942) (xy 76.503828 -296.172034) (xy 76.533393 -296.211378)
			(xy 76.556264 -296.254955) (xy 76.571848 -296.301636) (xy 76.579743 -296.350213) (xy 76.580238 -296.37482)
			(xy 76.919086 -296.37482) (xy 76.923046 -296.325766) (xy 76.934823 -296.277982) (xy 76.954114 -296.232706)
			(xy 76.980417 -296.19111) (xy 77.013052 -296.154273) (xy 77.051173 -296.123148) (xy 77.093794 -296.098541)
			(xy 77.13981 -296.081089) (xy 77.188029 -296.071245) (xy 77.237204 -296.069264) (xy 77.286059 -296.075196)
			(xy 77.33333 -296.088888) (xy 77.377792 -296.109986) (xy 77.418295 -296.137942) (xy 77.453788 -296.172034)
			(xy 77.483353 -296.211378) (xy 77.506224 -296.254955) (xy 77.521808 -296.301636) (xy 77.529703 -296.350213)
			(xy 77.530198 -296.37482) (xy 77.869046 -296.37482) (xy 77.873006 -296.325766) (xy 77.884783 -296.277982)
			(xy 77.904074 -296.232706) (xy 77.930377 -296.19111) (xy 77.963012 -296.154273) (xy 78.001133 -296.123148)
			(xy 78.043754 -296.098541) (xy 78.08977 -296.081089) (xy 78.137989 -296.071245) (xy 78.187164 -296.069264)
			(xy 78.236019 -296.075196) (xy 78.28329 -296.088888) (xy 78.327752 -296.109986) (xy 78.368255 -296.137942)
			(xy 78.403748 -296.172034) (xy 78.433313 -296.211378) (xy 78.456184 -296.254955) (xy 78.471768 -296.301636)
			(xy 78.479663 -296.350213) (xy 78.480158 -296.37482) (xy 78.819006 -296.37482) (xy 78.822966 -296.325766)
			(xy 78.834743 -296.277982) (xy 78.854034 -296.232706) (xy 78.880337 -296.19111) (xy 78.912972 -296.154273)
			(xy 78.951093 -296.123148) (xy 78.993714 -296.098541) (xy 79.03973 -296.081089) (xy 79.087949 -296.071245)
			(xy 79.137124 -296.069264) (xy 79.185979 -296.075196) (xy 79.23325 -296.088888) (xy 79.277712 -296.109986)
			(xy 79.318215 -296.137942) (xy 79.353708 -296.172034) (xy 79.383273 -296.211378) (xy 79.406144 -296.254955)
			(xy 79.421728 -296.301636) (xy 79.429623 -296.350213) (xy 79.430118 -296.37482) (xy 79.768966 -296.37482)
			(xy 79.772926 -296.325766) (xy 79.784703 -296.277982) (xy 79.803994 -296.232706) (xy 79.830297 -296.19111)
			(xy 79.862932 -296.154273) (xy 79.901053 -296.123148) (xy 79.943674 -296.098541) (xy 79.98969 -296.081089)
			(xy 80.037909 -296.071245) (xy 80.087084 -296.069264) (xy 80.135939 -296.075196) (xy 80.18321 -296.088888)
			(xy 80.227672 -296.109986) (xy 80.268175 -296.137942) (xy 80.303668 -296.172034) (xy 80.333233 -296.211378)
			(xy 80.356104 -296.254955) (xy 80.371688 -296.301636) (xy 80.379583 -296.350213) (xy 80.380078 -296.37482)
			(xy 80.71918 -296.37482) (xy 80.72314 -296.325766) (xy 80.734917 -296.277982) (xy 80.754208 -296.232706)
			(xy 80.780511 -296.19111) (xy 80.813146 -296.154273) (xy 80.851267 -296.123148) (xy 80.893888 -296.098541)
			(xy 80.939904 -296.081089) (xy 80.988123 -296.071245) (xy 81.037298 -296.069264) (xy 81.086153 -296.075196)
			(xy 81.133424 -296.088888) (xy 81.177886 -296.109986) (xy 81.218389 -296.137942) (xy 81.253882 -296.172034)
			(xy 81.283447 -296.211378) (xy 81.306318 -296.254955) (xy 81.321902 -296.301636) (xy 81.329797 -296.350213)
			(xy 81.330292 -296.37482) (xy 81.66914 -296.37482) (xy 81.6731 -296.325766) (xy 81.684877 -296.277982)
			(xy 81.704168 -296.232706) (xy 81.730471 -296.19111) (xy 81.763106 -296.154273) (xy 81.801227 -296.123148)
			(xy 81.843848 -296.098541) (xy 81.889864 -296.081089) (xy 81.938083 -296.071245) (xy 81.987258 -296.069264)
			(xy 82.036113 -296.075196) (xy 82.083384 -296.088888) (xy 82.127846 -296.109986) (xy 82.168349 -296.137942)
			(xy 82.203842 -296.172034) (xy 82.233407 -296.211378) (xy 82.256278 -296.254955) (xy 82.271862 -296.301636)
			(xy 82.279757 -296.350213) (xy 82.280252 -296.37482) (xy 82.6191 -296.37482) (xy 82.62306 -296.325766)
			(xy 82.634837 -296.277982) (xy 82.654128 -296.232706) (xy 82.680431 -296.19111) (xy 82.713066 -296.154273)
			(xy 82.751187 -296.123148) (xy 82.793808 -296.098541) (xy 82.839824 -296.081089) (xy 82.888043 -296.071245)
			(xy 82.937218 -296.069264) (xy 82.986073 -296.075196) (xy 83.033344 -296.088888) (xy 83.077806 -296.109986)
			(xy 83.118309 -296.137942) (xy 83.153802 -296.172034) (xy 83.183367 -296.211378) (xy 83.206238 -296.254955)
			(xy 83.221822 -296.301636) (xy 83.229717 -296.350213) (xy 83.230212 -296.37482) (xy 83.229717 -296.399427)
			(xy 83.221822 -296.448004) (xy 83.206238 -296.494685) (xy 83.183367 -296.538262) (xy 83.153802 -296.577606)
			(xy 83.118309 -296.611698) (xy 83.077806 -296.639654) (xy 83.033344 -296.660752) (xy 82.986073 -296.674444)
			(xy 82.937218 -296.680376) (xy 82.888043 -296.678395) (xy 82.839824 -296.668551) (xy 82.793808 -296.651099)
			(xy 82.751187 -296.626492) (xy 82.713066 -296.595367) (xy 82.680431 -296.55853) (xy 82.654128 -296.516934)
			(xy 82.634837 -296.471658) (xy 82.62306 -296.423874) (xy 82.6191 -296.37482) (xy 82.280252 -296.37482)
			(xy 82.279757 -296.399427) (xy 82.271862 -296.448004) (xy 82.256278 -296.494685) (xy 82.233407 -296.538262)
			(xy 82.203842 -296.577606) (xy 82.168349 -296.611698) (xy 82.127846 -296.639654) (xy 82.083384 -296.660752)
			(xy 82.036113 -296.674444) (xy 81.987258 -296.680376) (xy 81.938083 -296.678395) (xy 81.889864 -296.668551)
			(xy 81.843848 -296.651099) (xy 81.801227 -296.626492) (xy 81.763106 -296.595367) (xy 81.730471 -296.55853)
			(xy 81.704168 -296.516934) (xy 81.684877 -296.471658) (xy 81.6731 -296.423874) (xy 81.66914 -296.37482)
			(xy 81.330292 -296.37482) (xy 81.329797 -296.399427) (xy 81.321902 -296.448004) (xy 81.306318 -296.494685)
			(xy 81.283447 -296.538262) (xy 81.253882 -296.577606) (xy 81.218389 -296.611698) (xy 81.177886 -296.639654)
			(xy 81.133424 -296.660752) (xy 81.086153 -296.674444) (xy 81.037298 -296.680376) (xy 80.988123 -296.678395)
			(xy 80.939904 -296.668551) (xy 80.893888 -296.651099) (xy 80.851267 -296.626492) (xy 80.813146 -296.595367)
			(xy 80.780511 -296.55853) (xy 80.754208 -296.516934) (xy 80.734917 -296.471658) (xy 80.72314 -296.423874)
			(xy 80.71918 -296.37482) (xy 80.380078 -296.37482) (xy 80.379583 -296.399427) (xy 80.371688 -296.448004)
			(xy 80.356104 -296.494685) (xy 80.333233 -296.538262) (xy 80.303668 -296.577606) (xy 80.268175 -296.611698)
			(xy 80.227672 -296.639654) (xy 80.18321 -296.660752) (xy 80.135939 -296.674444) (xy 80.087084 -296.680376)
			(xy 80.037909 -296.678395) (xy 79.98969 -296.668551) (xy 79.943674 -296.651099) (xy 79.901053 -296.626492)
			(xy 79.862932 -296.595367) (xy 79.830297 -296.55853) (xy 79.803994 -296.516934) (xy 79.784703 -296.471658)
			(xy 79.772926 -296.423874) (xy 79.768966 -296.37482) (xy 79.430118 -296.37482) (xy 79.429623 -296.399427)
			(xy 79.421728 -296.448004) (xy 79.406144 -296.494685) (xy 79.383273 -296.538262) (xy 79.353708 -296.577606)
			(xy 79.318215 -296.611698) (xy 79.277712 -296.639654) (xy 79.23325 -296.660752) (xy 79.185979 -296.674444)
			(xy 79.137124 -296.680376) (xy 79.087949 -296.678395) (xy 79.03973 -296.668551) (xy 78.993714 -296.651099)
			(xy 78.951093 -296.626492) (xy 78.912972 -296.595367) (xy 78.880337 -296.55853) (xy 78.854034 -296.516934)
			(xy 78.834743 -296.471658) (xy 78.822966 -296.423874) (xy 78.819006 -296.37482) (xy 78.480158 -296.37482)
			(xy 78.479663 -296.399427) (xy 78.471768 -296.448004) (xy 78.456184 -296.494685) (xy 78.433313 -296.538262)
			(xy 78.403748 -296.577606) (xy 78.368255 -296.611698) (xy 78.327752 -296.639654) (xy 78.28329 -296.660752)
			(xy 78.236019 -296.674444) (xy 78.187164 -296.680376) (xy 78.137989 -296.678395) (xy 78.08977 -296.668551)
			(xy 78.043754 -296.651099) (xy 78.001133 -296.626492) (xy 77.963012 -296.595367) (xy 77.930377 -296.55853)
			(xy 77.904074 -296.516934) (xy 77.884783 -296.471658) (xy 77.873006 -296.423874) (xy 77.869046 -296.37482)
			(xy 77.530198 -296.37482) (xy 77.529703 -296.399427) (xy 77.521808 -296.448004) (xy 77.506224 -296.494685)
			(xy 77.483353 -296.538262) (xy 77.453788 -296.577606) (xy 77.418295 -296.611698) (xy 77.377792 -296.639654)
			(xy 77.33333 -296.660752) (xy 77.286059 -296.674444) (xy 77.237204 -296.680376) (xy 77.188029 -296.678395)
			(xy 77.13981 -296.668551) (xy 77.093794 -296.651099) (xy 77.051173 -296.626492) (xy 77.013052 -296.595367)
			(xy 76.980417 -296.55853) (xy 76.954114 -296.516934) (xy 76.934823 -296.471658) (xy 76.923046 -296.423874)
			(xy 76.919086 -296.37482) (xy 76.580238 -296.37482) (xy 76.579743 -296.399427) (xy 76.571848 -296.448004)
			(xy 76.556264 -296.494685) (xy 76.533393 -296.538262) (xy 76.503828 -296.577606) (xy 76.468335 -296.611698)
			(xy 76.427832 -296.639654) (xy 76.38337 -296.660752) (xy 76.336099 -296.674444) (xy 76.287244 -296.680376)
			(xy 76.238069 -296.678395) (xy 76.18985 -296.668551) (xy 76.143834 -296.651099) (xy 76.101213 -296.626492)
			(xy 76.063092 -296.595367) (xy 76.030457 -296.55853) (xy 76.004154 -296.516934) (xy 75.984863 -296.471658)
			(xy 75.973086 -296.423874) (xy 75.969126 -296.37482) (xy 75.630278 -296.37482) (xy 75.629783 -296.399427)
			(xy 75.621888 -296.448004) (xy 75.606304 -296.494685) (xy 75.583433 -296.538262) (xy 75.553868 -296.577606)
			(xy 75.518375 -296.611698) (xy 75.477872 -296.639654) (xy 75.43341 -296.660752) (xy 75.386139 -296.674444)
			(xy 75.337284 -296.680376) (xy 75.288109 -296.678395) (xy 75.23989 -296.668551) (xy 75.193874 -296.651099)
			(xy 75.151253 -296.626492) (xy 75.113132 -296.595367) (xy 75.080497 -296.55853) (xy 75.054194 -296.516934)
			(xy 75.034903 -296.471658) (xy 75.023126 -296.423874) (xy 75.019166 -296.37482) (xy 74.680064 -296.37482)
			(xy 74.679569 -296.399427) (xy 74.671674 -296.448004) (xy 74.65609 -296.494685) (xy 74.633219 -296.538262)
			(xy 74.603654 -296.577606) (xy 74.568161 -296.611698) (xy 74.527658 -296.639654) (xy 74.483196 -296.660752)
			(xy 74.435925 -296.674444) (xy 74.38707 -296.680376) (xy 74.337895 -296.678395) (xy 74.289676 -296.668551)
			(xy 74.24366 -296.651099) (xy 74.201039 -296.626492) (xy 74.162918 -296.595367) (xy 74.130283 -296.55853)
			(xy 74.10398 -296.516934) (xy 74.084689 -296.471658) (xy 74.072912 -296.423874) (xy 74.068952 -296.37482)
			(xy 73.730104 -296.37482) (xy 73.729609 -296.399427) (xy 73.721714 -296.448004) (xy 73.70613 -296.494685)
			(xy 73.683259 -296.538262) (xy 73.653694 -296.577606) (xy 73.618201 -296.611698) (xy 73.577698 -296.639654)
			(xy 73.533236 -296.660752) (xy 73.485965 -296.674444) (xy 73.43711 -296.680376) (xy 73.387935 -296.678395)
			(xy 73.339716 -296.668551) (xy 73.2937 -296.651099) (xy 73.251079 -296.626492) (xy 73.212958 -296.595367)
			(xy 73.180323 -296.55853) (xy 73.15402 -296.516934) (xy 73.134729 -296.471658) (xy 73.122952 -296.423874)
			(xy 73.118992 -296.37482) (xy 71.830184 -296.37482) (xy 71.829689 -296.399427) (xy 71.821794 -296.448004)
			(xy 71.80621 -296.494685) (xy 71.783339 -296.538262) (xy 71.753774 -296.577606) (xy 71.718281 -296.611698)
			(xy 71.677778 -296.639654) (xy 71.633316 -296.660752) (xy 71.586045 -296.674444) (xy 71.53719 -296.680376)
			(xy 71.488015 -296.678395) (xy 71.439796 -296.668551) (xy 71.39378 -296.651099) (xy 71.351159 -296.626492)
			(xy 71.313038 -296.595367) (xy 71.280403 -296.55853) (xy 71.2541 -296.516934) (xy 71.234809 -296.471658)
			(xy 71.223032 -296.423874) (xy 71.219072 -296.37482) (xy 70.880224 -296.37482) (xy 70.879729 -296.399427)
			(xy 70.871834 -296.448004) (xy 70.85625 -296.494685) (xy 70.833379 -296.538262) (xy 70.803814 -296.577606)
			(xy 70.768321 -296.611698) (xy 70.727818 -296.639654) (xy 70.683356 -296.660752) (xy 70.636085 -296.674444)
			(xy 70.58723 -296.680376) (xy 70.538055 -296.678395) (xy 70.489836 -296.668551) (xy 70.44382 -296.651099)
			(xy 70.401199 -296.626492) (xy 70.363078 -296.595367) (xy 70.330443 -296.55853) (xy 70.30414 -296.516934)
			(xy 70.284849 -296.471658) (xy 70.273072 -296.423874) (xy 70.269112 -296.37482) (xy 69.930264 -296.37482)
			(xy 69.929769 -296.399427) (xy 69.921874 -296.448004) (xy 69.90629 -296.494685) (xy 69.883419 -296.538262)
			(xy 69.853854 -296.577606) (xy 69.818361 -296.611698) (xy 69.777858 -296.639654) (xy 69.733396 -296.660752)
			(xy 69.686125 -296.674444) (xy 69.63727 -296.680376) (xy 69.588095 -296.678395) (xy 69.539876 -296.668551)
			(xy 69.49386 -296.651099) (xy 69.451239 -296.626492) (xy 69.413118 -296.595367) (xy 69.380483 -296.55853)
			(xy 69.35418 -296.516934) (xy 69.334889 -296.471658) (xy 69.323112 -296.423874) (xy 69.319152 -296.37482)
			(xy 68.98005 -296.37482) (xy 68.979555 -296.399427) (xy 68.97166 -296.448004) (xy 68.956076 -296.494685)
			(xy 68.933205 -296.538262) (xy 68.90364 -296.577606) (xy 68.868147 -296.611698) (xy 68.827644 -296.639654)
			(xy 68.783182 -296.660752) (xy 68.735911 -296.674444) (xy 68.687056 -296.680376) (xy 68.637881 -296.678395)
			(xy 68.589662 -296.668551) (xy 68.543646 -296.651099) (xy 68.501025 -296.626492) (xy 68.462904 -296.595367)
			(xy 68.430269 -296.55853) (xy 68.403966 -296.516934) (xy 68.384675 -296.471658) (xy 68.372898 -296.423874)
			(xy 68.368938 -296.37482) (xy 68.03009 -296.37482) (xy 68.029595 -296.399427) (xy 68.0217 -296.448004)
			(xy 68.006116 -296.494685) (xy 67.983245 -296.538262) (xy 67.95368 -296.577606) (xy 67.918187 -296.611698)
			(xy 67.877684 -296.639654) (xy 67.833222 -296.660752) (xy 67.785951 -296.674444) (xy 67.737096 -296.680376)
			(xy 67.687921 -296.678395) (xy 67.639702 -296.668551) (xy 67.593686 -296.651099) (xy 67.551065 -296.626492)
			(xy 67.512944 -296.595367) (xy 67.480309 -296.55853) (xy 67.454006 -296.516934) (xy 67.434715 -296.471658)
			(xy 67.422938 -296.423874) (xy 67.418978 -296.37482) (xy 67.08013 -296.37482) (xy 67.079635 -296.399427)
			(xy 67.07174 -296.448004) (xy 67.056156 -296.494685) (xy 67.033285 -296.538262) (xy 67.00372 -296.577606)
			(xy 66.968227 -296.611698) (xy 66.927724 -296.639654) (xy 66.883262 -296.660752) (xy 66.835991 -296.674444)
			(xy 66.787136 -296.680376) (xy 66.737961 -296.678395) (xy 66.689742 -296.668551) (xy 66.643726 -296.651099)
			(xy 66.601105 -296.626492) (xy 66.562984 -296.595367) (xy 66.530349 -296.55853) (xy 66.504046 -296.516934)
			(xy 66.484755 -296.471658) (xy 66.472978 -296.423874) (xy 66.469018 -296.37482) (xy 66.13017 -296.37482)
			(xy 66.129675 -296.399427) (xy 66.12178 -296.448004) (xy 66.106196 -296.494685) (xy 66.083325 -296.538262)
			(xy 66.05376 -296.577606) (xy 66.018267 -296.611698) (xy 65.977764 -296.639654) (xy 65.933302 -296.660752)
			(xy 65.886031 -296.674444) (xy 65.837176 -296.680376) (xy 65.788001 -296.678395) (xy 65.739782 -296.668551)
			(xy 65.693766 -296.651099) (xy 65.651145 -296.626492) (xy 65.613024 -296.595367) (xy 65.580389 -296.55853)
			(xy 65.554086 -296.516934) (xy 65.534795 -296.471658) (xy 65.523018 -296.423874) (xy 65.519058 -296.37482)
			(xy 65.18021 -296.37482) (xy 65.179715 -296.399427) (xy 65.17182 -296.448004) (xy 65.156236 -296.494685)
			(xy 65.133365 -296.538262) (xy 65.1038 -296.577606) (xy 65.068307 -296.611698) (xy 65.027804 -296.639654)
			(xy 64.983342 -296.660752) (xy 64.936071 -296.674444) (xy 64.887216 -296.680376) (xy 64.838041 -296.678395)
			(xy 64.789822 -296.668551) (xy 64.743806 -296.651099) (xy 64.701185 -296.626492) (xy 64.663064 -296.595367)
			(xy 64.630429 -296.55853) (xy 64.604126 -296.516934) (xy 64.584835 -296.471658) (xy 64.573058 -296.423874)
			(xy 64.569098 -296.37482) (xy 64.23025 -296.37482) (xy 64.229755 -296.399427) (xy 64.22186 -296.448004)
			(xy 64.206276 -296.494685) (xy 64.183405 -296.538262) (xy 64.15384 -296.577606) (xy 64.118347 -296.611698)
			(xy 64.077844 -296.639654) (xy 64.033382 -296.660752) (xy 63.986111 -296.674444) (xy 63.937256 -296.680376)
			(xy 63.888081 -296.678395) (xy 63.839862 -296.668551) (xy 63.793846 -296.651099) (xy 63.751225 -296.626492)
			(xy 63.713104 -296.595367) (xy 63.680469 -296.55853) (xy 63.654166 -296.516934) (xy 63.634875 -296.471658)
			(xy 63.623098 -296.423874) (xy 63.619138 -296.37482) (xy 63.28029 -296.37482) (xy 63.279795 -296.399427)
			(xy 63.2719 -296.448004) (xy 63.256316 -296.494685) (xy 63.233445 -296.538262) (xy 63.20388 -296.577606)
			(xy 63.168387 -296.611698) (xy 63.127884 -296.639654) (xy 63.083422 -296.660752) (xy 63.036151 -296.674444)
			(xy 62.987296 -296.680376) (xy 62.938121 -296.678395) (xy 62.889902 -296.668551) (xy 62.843886 -296.651099)
			(xy 62.801265 -296.626492) (xy 62.763144 -296.595367) (xy 62.730509 -296.55853) (xy 62.704206 -296.516934)
			(xy 62.684915 -296.471658) (xy 62.673138 -296.423874) (xy 62.669178 -296.37482) (xy 62.330076 -296.37482)
			(xy 62.329581 -296.399427) (xy 62.321686 -296.448004) (xy 62.306102 -296.494685) (xy 62.283231 -296.538262)
			(xy 62.253666 -296.577606) (xy 62.218173 -296.611698) (xy 62.17767 -296.639654) (xy 62.133208 -296.660752)
			(xy 62.085937 -296.674444) (xy 62.037082 -296.680376) (xy 61.987907 -296.678395) (xy 61.939688 -296.668551)
			(xy 61.893672 -296.651099) (xy 61.851051 -296.626492) (xy 61.81293 -296.595367) (xy 61.780295 -296.55853)
			(xy 61.753992 -296.516934) (xy 61.734701 -296.471658) (xy 61.722924 -296.423874) (xy 61.718964 -296.37482)
			(xy 61.380116 -296.37482) (xy 61.379621 -296.399427) (xy 61.371726 -296.448004) (xy 61.356142 -296.494685)
			(xy 61.333271 -296.538262) (xy 61.303706 -296.577606) (xy 61.268213 -296.611698) (xy 61.22771 -296.639654)
			(xy 61.183248 -296.660752) (xy 61.135977 -296.674444) (xy 61.087122 -296.680376) (xy 61.037947 -296.678395)
			(xy 60.989728 -296.668551) (xy 60.943712 -296.651099) (xy 60.901091 -296.626492) (xy 60.86297 -296.595367)
			(xy 60.830335 -296.55853) (xy 60.804032 -296.516934) (xy 60.784741 -296.471658) (xy 60.772964 -296.423874)
			(xy 60.769004 -296.37482) (xy 60.430156 -296.37482) (xy 60.429661 -296.399427) (xy 60.421766 -296.448004)
			(xy 60.406182 -296.494685) (xy 60.383311 -296.538262) (xy 60.353746 -296.577606) (xy 60.318253 -296.611698)
			(xy 60.27775 -296.639654) (xy 60.233288 -296.660752) (xy 60.186017 -296.674444) (xy 60.137162 -296.680376)
			(xy 60.087987 -296.678395) (xy 60.039768 -296.668551) (xy 59.993752 -296.651099) (xy 59.951131 -296.626492)
			(xy 59.91301 -296.595367) (xy 59.880375 -296.55853) (xy 59.854072 -296.516934) (xy 59.834781 -296.471658)
			(xy 59.823004 -296.423874) (xy 59.819044 -296.37482) (xy 58.530236 -296.37482) (xy 58.529741 -296.399427)
			(xy 58.521846 -296.448004) (xy 58.506262 -296.494685) (xy 58.483391 -296.538262) (xy 58.453826 -296.577606)
			(xy 58.418333 -296.611698) (xy 58.37783 -296.639654) (xy 58.333368 -296.660752) (xy 58.286097 -296.674444)
			(xy 58.237242 -296.680376) (xy 58.188067 -296.678395) (xy 58.139848 -296.668551) (xy 58.093832 -296.651099)
			(xy 58.051211 -296.626492) (xy 58.01309 -296.595367) (xy 57.980455 -296.55853) (xy 57.954152 -296.516934)
			(xy 57.934861 -296.471658) (xy 57.923084 -296.423874) (xy 57.919124 -296.37482) (xy 57.580276 -296.37482)
			(xy 57.579781 -296.399427) (xy 57.571886 -296.448004) (xy 57.556302 -296.494685) (xy 57.533431 -296.538262)
			(xy 57.503866 -296.577606) (xy 57.468373 -296.611698) (xy 57.42787 -296.639654) (xy 57.383408 -296.660752)
			(xy 57.336137 -296.674444) (xy 57.287282 -296.680376) (xy 57.238107 -296.678395) (xy 57.189888 -296.668551)
			(xy 57.143872 -296.651099) (xy 57.101251 -296.626492) (xy 57.06313 -296.595367) (xy 57.030495 -296.55853)
			(xy 57.004192 -296.516934) (xy 56.984901 -296.471658) (xy 56.973124 -296.423874) (xy 56.969164 -296.37482)
			(xy 56.630316 -296.37482) (xy 56.629821 -296.399427) (xy 56.621926 -296.448004) (xy 56.606342 -296.494685)
			(xy 56.583471 -296.538262) (xy 56.553906 -296.577606) (xy 56.518413 -296.611698) (xy 56.47791 -296.639654)
			(xy 56.433448 -296.660752) (xy 56.386177 -296.674444) (xy 56.337322 -296.680376) (xy 56.288147 -296.678395)
			(xy 56.239928 -296.668551) (xy 56.193912 -296.651099) (xy 56.151291 -296.626492) (xy 56.11317 -296.595367)
			(xy 56.080535 -296.55853) (xy 56.054232 -296.516934) (xy 56.034941 -296.471658) (xy 56.023164 -296.423874)
			(xy 56.019204 -296.37482) (xy 55.680102 -296.37482) (xy 55.679607 -296.399427) (xy 55.671712 -296.448004)
			(xy 55.656128 -296.494685) (xy 55.633257 -296.538262) (xy 55.603692 -296.577606) (xy 55.568199 -296.611698)
			(xy 55.527696 -296.639654) (xy 55.483234 -296.660752) (xy 55.435963 -296.674444) (xy 55.387108 -296.680376)
			(xy 55.337933 -296.678395) (xy 55.289714 -296.668551) (xy 55.243698 -296.651099) (xy 55.201077 -296.626492)
			(xy 55.162956 -296.595367) (xy 55.130321 -296.55853) (xy 55.104018 -296.516934) (xy 55.084727 -296.471658)
			(xy 55.07295 -296.423874) (xy 55.06899 -296.37482) (xy 54.730142 -296.37482) (xy 54.729647 -296.399427)
			(xy 54.721752 -296.448004) (xy 54.706168 -296.494685) (xy 54.683297 -296.538262) (xy 54.653732 -296.577606)
			(xy 54.618239 -296.611698) (xy 54.577736 -296.639654) (xy 54.533274 -296.660752) (xy 54.486003 -296.674444)
			(xy 54.437148 -296.680376) (xy 54.387973 -296.678395) (xy 54.339754 -296.668551) (xy 54.293738 -296.651099)
			(xy 54.251117 -296.626492) (xy 54.212996 -296.595367) (xy 54.180361 -296.55853) (xy 54.154058 -296.516934)
			(xy 54.134767 -296.471658) (xy 54.12299 -296.423874) (xy 54.11903 -296.37482) (xy 53.780182 -296.37482)
			(xy 53.779687 -296.399427) (xy 53.771792 -296.448004) (xy 53.756208 -296.494685) (xy 53.733337 -296.538262)
			(xy 53.703772 -296.577606) (xy 53.668279 -296.611698) (xy 53.627776 -296.639654) (xy 53.583314 -296.660752)
			(xy 53.536043 -296.674444) (xy 53.487188 -296.680376) (xy 53.438013 -296.678395) (xy 53.389794 -296.668551)
			(xy 53.343778 -296.651099) (xy 53.301157 -296.626492) (xy 53.263036 -296.595367) (xy 53.230401 -296.55853)
			(xy 53.204098 -296.516934) (xy 53.184807 -296.471658) (xy 53.17303 -296.423874) (xy 53.16907 -296.37482)
			(xy 52.830222 -296.37482) (xy 52.829727 -296.399427) (xy 52.821832 -296.448004) (xy 52.806248 -296.494685)
			(xy 52.783377 -296.538262) (xy 52.753812 -296.577606) (xy 52.718319 -296.611698) (xy 52.677816 -296.639654)
			(xy 52.633354 -296.660752) (xy 52.586083 -296.674444) (xy 52.537228 -296.680376) (xy 52.488053 -296.678395)
			(xy 52.439834 -296.668551) (xy 52.393818 -296.651099) (xy 52.351197 -296.626492) (xy 52.313076 -296.595367)
			(xy 52.280441 -296.55853) (xy 52.254138 -296.516934) (xy 52.234847 -296.471658) (xy 52.22307 -296.423874)
			(xy 52.21911 -296.37482) (xy 51.880262 -296.37482) (xy 51.879767 -296.399427) (xy 51.871872 -296.448004)
			(xy 51.856288 -296.494685) (xy 51.833417 -296.538262) (xy 51.803852 -296.577606) (xy 51.768359 -296.611698)
			(xy 51.727856 -296.639654) (xy 51.683394 -296.660752) (xy 51.636123 -296.674444) (xy 51.587268 -296.680376)
			(xy 51.538093 -296.678395) (xy 51.489874 -296.668551) (xy 51.443858 -296.651099) (xy 51.401237 -296.626492)
			(xy 51.363116 -296.595367) (xy 51.330481 -296.55853) (xy 51.304178 -296.516934) (xy 51.284887 -296.471658)
			(xy 51.27311 -296.423874) (xy 51.26915 -296.37482) (xy 50.930302 -296.37482) (xy 50.929807 -296.399427)
			(xy 50.921912 -296.448004) (xy 50.906328 -296.494685) (xy 50.883457 -296.538262) (xy 50.853892 -296.577606)
			(xy 50.818399 -296.611698) (xy 50.777896 -296.639654) (xy 50.733434 -296.660752) (xy 50.686163 -296.674444)
			(xy 50.637308 -296.680376) (xy 50.588133 -296.678395) (xy 50.539914 -296.668551) (xy 50.493898 -296.651099)
			(xy 50.451277 -296.626492) (xy 50.413156 -296.595367) (xy 50.380521 -296.55853) (xy 50.354218 -296.516934)
			(xy 50.334927 -296.471658) (xy 50.32315 -296.423874) (xy 50.31919 -296.37482) (xy 49.980088 -296.37482)
			(xy 49.979593 -296.399427) (xy 49.971698 -296.448004) (xy 49.956114 -296.494685) (xy 49.933243 -296.538262)
			(xy 49.903678 -296.577606) (xy 49.868185 -296.611698) (xy 49.827682 -296.639654) (xy 49.78322 -296.660752)
			(xy 49.735949 -296.674444) (xy 49.687094 -296.680376) (xy 49.637919 -296.678395) (xy 49.5897 -296.668551)
			(xy 49.543684 -296.651099) (xy 49.501063 -296.626492) (xy 49.462942 -296.595367) (xy 49.430307 -296.55853)
			(xy 49.404004 -296.516934) (xy 49.384713 -296.471658) (xy 49.372936 -296.423874) (xy 49.368976 -296.37482)
			(xy 49.030128 -296.37482) (xy 49.029633 -296.399427) (xy 49.021738 -296.448004) (xy 49.006154 -296.494685)
			(xy 48.983283 -296.538262) (xy 48.953718 -296.577606) (xy 48.918225 -296.611698) (xy 48.877722 -296.639654)
			(xy 48.83326 -296.660752) (xy 48.785989 -296.674444) (xy 48.737134 -296.680376) (xy 48.687959 -296.678395)
			(xy 48.63974 -296.668551) (xy 48.593724 -296.651099) (xy 48.551103 -296.626492) (xy 48.512982 -296.595367)
			(xy 48.480347 -296.55853) (xy 48.454044 -296.516934) (xy 48.434753 -296.471658) (xy 48.422976 -296.423874)
			(xy 48.419016 -296.37482) (xy 48.080168 -296.37482) (xy 48.079673 -296.399427) (xy 48.071778 -296.448004)
			(xy 48.056194 -296.494685) (xy 48.033323 -296.538262) (xy 48.003758 -296.577606) (xy 47.968265 -296.611698)
			(xy 47.927762 -296.639654) (xy 47.8833 -296.660752) (xy 47.836029 -296.674444) (xy 47.787174 -296.680376)
			(xy 47.737999 -296.678395) (xy 47.68978 -296.668551) (xy 47.643764 -296.651099) (xy 47.601143 -296.626492)
			(xy 47.563022 -296.595367) (xy 47.530387 -296.55853) (xy 47.504084 -296.516934) (xy 47.484793 -296.471658)
			(xy 47.473016 -296.423874) (xy 47.469056 -296.37482) (xy 46.756828 -296.37482) (xy 46.756828 -296.37609)
			(xy 46.75742 -296.386671) (xy 46.764269 -296.406713) (xy 46.776913 -296.423705) (xy 46.794142 -296.436024)
			(xy 46.81431 -296.442493) (xy 46.8249 -296.442892) (xy 46.833972 -296.442608) (xy 46.851481 -296.43785)
			(xy 46.859444 -296.433494) (xy 46.860968 -296.432478) (xy 46.92269 -296.397172) (xy 46.928407 -296.394172)
			(xy 46.940877 -296.390839) (xy 46.947328 -296.390568) (xy 47.087282 -296.389044) (xy 47.094006 -296.389274)
			(xy 47.106999 -296.39274) (xy 47.112936 -296.395902) (xy 47.246032 -296.471848) (xy 47.247556 -296.47261)
			(xy 47.268186 -296.484546) (xy 47.305912 -296.513668) (xy 47.338789 -296.548171) (xy 47.366057 -296.587259)
			(xy 47.387086 -296.630027) (xy 47.401391 -296.675489) (xy 47.40864 -296.722593) (xy 47.4091 -296.746422)
			(xy 47.4091 -297.026076) (xy 47.409551 -297.035887) (xy 47.416889 -297.054083) (xy 47.430535 -297.068181)
			(xy 47.439326 -297.072558) (xy 47.516034 -297.106594) (xy 47.525126 -297.110064) (xy 47.544556 -297.110701)
			(xy 47.56284 -297.104095) (xy 47.57039 -297.097958) (xy 47.570644 -297.097704) (xy 47.58756 -297.083053)
			(xy 47.62486 -297.058329) (xy 47.665367 -297.039308) (xy 47.708214 -297.026395) (xy 47.752485 -297.019865)
			(xy 47.77486 -297.019472) (xy 47.800118 -297.020001) (xy 47.849947 -297.02831) (xy 47.897727 -297.044708)
			(xy 47.942157 -297.068747) (xy 47.982024 -297.099772) (xy 48.01624 -297.136936) (xy 48.043872 -297.179225)
			(xy 48.064166 -297.225486) (xy 48.076568 -297.274456) (xy 48.080738 -297.32478) (xy 48.419016 -297.32478)
			(xy 48.422976 -297.275726) (xy 48.434753 -297.227942) (xy 48.454044 -297.182666) (xy 48.480347 -297.14107)
			(xy 48.512982 -297.104233) (xy 48.551103 -297.073108) (xy 48.593724 -297.048501) (xy 48.63974 -297.031049)
			(xy 48.687959 -297.021205) (xy 48.737134 -297.019224) (xy 48.785989 -297.025156) (xy 48.83326 -297.038848)
			(xy 48.877722 -297.059946) (xy 48.918225 -297.087902) (xy 48.953718 -297.121994) (xy 48.983283 -297.161338)
			(xy 49.006154 -297.204915) (xy 49.021738 -297.251596) (xy 49.029633 -297.300173) (xy 49.030128 -297.32478)
			(xy 49.368976 -297.32478) (xy 49.372936 -297.275726) (xy 49.384713 -297.227942) (xy 49.404004 -297.182666)
			(xy 49.430307 -297.14107) (xy 49.462942 -297.104233) (xy 49.501063 -297.073108) (xy 49.543684 -297.048501)
			(xy 49.5897 -297.031049) (xy 49.637919 -297.021205) (xy 49.687094 -297.019224) (xy 49.735949 -297.025156)
			(xy 49.78322 -297.038848) (xy 49.827682 -297.059946) (xy 49.868185 -297.087902) (xy 49.903678 -297.121994)
			(xy 49.933243 -297.161338) (xy 49.956114 -297.204915) (xy 49.971698 -297.251596) (xy 49.979593 -297.300173)
			(xy 49.980088 -297.32478) (xy 50.31919 -297.32478) (xy 50.32315 -297.275726) (xy 50.334927 -297.227942)
			(xy 50.354218 -297.182666) (xy 50.380521 -297.14107) (xy 50.413156 -297.104233) (xy 50.451277 -297.073108)
			(xy 50.493898 -297.048501) (xy 50.539914 -297.031049) (xy 50.588133 -297.021205) (xy 50.637308 -297.019224)
			(xy 50.686163 -297.025156) (xy 50.733434 -297.038848) (xy 50.777896 -297.059946) (xy 50.818399 -297.087902)
			(xy 50.853892 -297.121994) (xy 50.883457 -297.161338) (xy 50.906328 -297.204915) (xy 50.921912 -297.251596)
			(xy 50.929807 -297.300173) (xy 50.930302 -297.32478) (xy 51.26915 -297.32478) (xy 51.27311 -297.275726)
			(xy 51.284887 -297.227942) (xy 51.304178 -297.182666) (xy 51.330481 -297.14107) (xy 51.363116 -297.104233)
			(xy 51.401237 -297.073108) (xy 51.443858 -297.048501) (xy 51.489874 -297.031049) (xy 51.538093 -297.021205)
			(xy 51.587268 -297.019224) (xy 51.636123 -297.025156) (xy 51.683394 -297.038848) (xy 51.727856 -297.059946)
			(xy 51.768359 -297.087902) (xy 51.803852 -297.121994) (xy 51.833417 -297.161338) (xy 51.856288 -297.204915)
			(xy 51.871872 -297.251596) (xy 51.879767 -297.300173) (xy 51.880262 -297.32478) (xy 52.21911 -297.32478)
			(xy 52.22307 -297.275726) (xy 52.234847 -297.227942) (xy 52.254138 -297.182666) (xy 52.280441 -297.14107)
			(xy 52.313076 -297.104233) (xy 52.351197 -297.073108) (xy 52.393818 -297.048501) (xy 52.439834 -297.031049)
			(xy 52.488053 -297.021205) (xy 52.537228 -297.019224) (xy 52.586083 -297.025156) (xy 52.633354 -297.038848)
			(xy 52.677816 -297.059946) (xy 52.718319 -297.087902) (xy 52.753812 -297.121994) (xy 52.783377 -297.161338)
			(xy 52.806248 -297.204915) (xy 52.821832 -297.251596) (xy 52.829727 -297.300173) (xy 52.830222 -297.32478)
			(xy 53.16907 -297.32478) (xy 53.17303 -297.275726) (xy 53.184807 -297.227942) (xy 53.204098 -297.182666)
			(xy 53.230401 -297.14107) (xy 53.263036 -297.104233) (xy 53.301157 -297.073108) (xy 53.343778 -297.048501)
			(xy 53.389794 -297.031049) (xy 53.438013 -297.021205) (xy 53.487188 -297.019224) (xy 53.536043 -297.025156)
			(xy 53.583314 -297.038848) (xy 53.627776 -297.059946) (xy 53.668279 -297.087902) (xy 53.703772 -297.121994)
			(xy 53.733337 -297.161338) (xy 53.756208 -297.204915) (xy 53.771792 -297.251596) (xy 53.779687 -297.300173)
			(xy 53.780182 -297.32478) (xy 54.11903 -297.32478) (xy 54.12299 -297.275726) (xy 54.134767 -297.227942)
			(xy 54.154058 -297.182666) (xy 54.180361 -297.14107) (xy 54.212996 -297.104233) (xy 54.251117 -297.073108)
			(xy 54.293738 -297.048501) (xy 54.339754 -297.031049) (xy 54.387973 -297.021205) (xy 54.437148 -297.019224)
			(xy 54.486003 -297.025156) (xy 54.533274 -297.038848) (xy 54.577736 -297.059946) (xy 54.618239 -297.087902)
			(xy 54.653732 -297.121994) (xy 54.683297 -297.161338) (xy 54.706168 -297.204915) (xy 54.721752 -297.251596)
			(xy 54.729647 -297.300173) (xy 54.730142 -297.32478) (xy 55.06899 -297.32478) (xy 55.07295 -297.275726)
			(xy 55.084727 -297.227942) (xy 55.104018 -297.182666) (xy 55.130321 -297.14107) (xy 55.162956 -297.104233)
			(xy 55.201077 -297.073108) (xy 55.243698 -297.048501) (xy 55.289714 -297.031049) (xy 55.337933 -297.021205)
			(xy 55.387108 -297.019224) (xy 55.435963 -297.025156) (xy 55.483234 -297.038848) (xy 55.527696 -297.059946)
			(xy 55.568199 -297.087902) (xy 55.603692 -297.121994) (xy 55.633257 -297.161338) (xy 55.656128 -297.204915)
			(xy 55.671712 -297.251596) (xy 55.679607 -297.300173) (xy 55.680102 -297.32478) (xy 56.01895 -297.32478)
			(xy 56.02291 -297.275726) (xy 56.034687 -297.227942) (xy 56.053978 -297.182666) (xy 56.080281 -297.14107)
			(xy 56.112916 -297.104233) (xy 56.151037 -297.073108) (xy 56.193658 -297.048501) (xy 56.239674 -297.031049)
			(xy 56.287893 -297.021205) (xy 56.337068 -297.019224) (xy 56.385923 -297.025156) (xy 56.433194 -297.038848)
			(xy 56.477656 -297.059946) (xy 56.518159 -297.087902) (xy 56.553652 -297.121994) (xy 56.583217 -297.161338)
			(xy 56.606088 -297.204915) (xy 56.621672 -297.251596) (xy 56.629567 -297.300173) (xy 56.630062 -297.32478)
			(xy 56.969164 -297.32478) (xy 56.973124 -297.275726) (xy 56.984901 -297.227942) (xy 57.004192 -297.182666)
			(xy 57.030495 -297.14107) (xy 57.06313 -297.104233) (xy 57.101251 -297.073108) (xy 57.143872 -297.048501)
			(xy 57.189888 -297.031049) (xy 57.238107 -297.021205) (xy 57.287282 -297.019224) (xy 57.336137 -297.025156)
			(xy 57.383408 -297.038848) (xy 57.42787 -297.059946) (xy 57.468373 -297.087902) (xy 57.503866 -297.121994)
			(xy 57.533431 -297.161338) (xy 57.556302 -297.204915) (xy 57.571886 -297.251596) (xy 57.579781 -297.300173)
			(xy 57.580276 -297.32478) (xy 57.919124 -297.32478) (xy 57.923084 -297.275726) (xy 57.934861 -297.227942)
			(xy 57.954152 -297.182666) (xy 57.980455 -297.14107) (xy 58.01309 -297.104233) (xy 58.051211 -297.073108)
			(xy 58.093832 -297.048501) (xy 58.139848 -297.031049) (xy 58.188067 -297.021205) (xy 58.237242 -297.019224)
			(xy 58.286097 -297.025156) (xy 58.333368 -297.038848) (xy 58.37783 -297.059946) (xy 58.418333 -297.087902)
			(xy 58.453826 -297.121994) (xy 58.483391 -297.161338) (xy 58.506262 -297.204915) (xy 58.521846 -297.251596)
			(xy 58.529741 -297.300173) (xy 58.530236 -297.32478) (xy 59.819044 -297.32478) (xy 59.823004 -297.275726)
			(xy 59.834781 -297.227942) (xy 59.854072 -297.182666) (xy 59.880375 -297.14107) (xy 59.91301 -297.104233)
			(xy 59.951131 -297.073108) (xy 59.993752 -297.048501) (xy 60.039768 -297.031049) (xy 60.087987 -297.021205)
			(xy 60.137162 -297.019224) (xy 60.186017 -297.025156) (xy 60.233288 -297.038848) (xy 60.27775 -297.059946)
			(xy 60.318253 -297.087902) (xy 60.353746 -297.121994) (xy 60.383311 -297.161338) (xy 60.406182 -297.204915)
			(xy 60.421766 -297.251596) (xy 60.429661 -297.300173) (xy 60.430156 -297.32478) (xy 60.769004 -297.32478)
			(xy 60.772964 -297.275726) (xy 60.784741 -297.227942) (xy 60.804032 -297.182666) (xy 60.830335 -297.14107)
			(xy 60.86297 -297.104233) (xy 60.901091 -297.073108) (xy 60.943712 -297.048501) (xy 60.989728 -297.031049)
			(xy 61.037947 -297.021205) (xy 61.087122 -297.019224) (xy 61.135977 -297.025156) (xy 61.183248 -297.038848)
			(xy 61.22771 -297.059946) (xy 61.268213 -297.087902) (xy 61.303706 -297.121994) (xy 61.333271 -297.161338)
			(xy 61.356142 -297.204915) (xy 61.371726 -297.251596) (xy 61.379621 -297.300173) (xy 61.380116 -297.32478)
			(xy 61.718964 -297.32478) (xy 61.722924 -297.275726) (xy 61.734701 -297.227942) (xy 61.753992 -297.182666)
			(xy 61.780295 -297.14107) (xy 61.81293 -297.104233) (xy 61.851051 -297.073108) (xy 61.893672 -297.048501)
			(xy 61.939688 -297.031049) (xy 61.987907 -297.021205) (xy 62.037082 -297.019224) (xy 62.085937 -297.025156)
			(xy 62.133208 -297.038848) (xy 62.17767 -297.059946) (xy 62.218173 -297.087902) (xy 62.253666 -297.121994)
			(xy 62.283231 -297.161338) (xy 62.306102 -297.204915) (xy 62.321686 -297.251596) (xy 62.329581 -297.300173)
			(xy 62.330076 -297.32478) (xy 62.669178 -297.32478) (xy 62.673138 -297.275726) (xy 62.684915 -297.227942)
			(xy 62.704206 -297.182666) (xy 62.730509 -297.14107) (xy 62.763144 -297.104233) (xy 62.801265 -297.073108)
			(xy 62.843886 -297.048501) (xy 62.889902 -297.031049) (xy 62.938121 -297.021205) (xy 62.987296 -297.019224)
			(xy 63.036151 -297.025156) (xy 63.083422 -297.038848) (xy 63.127884 -297.059946) (xy 63.168387 -297.087902)
			(xy 63.20388 -297.121994) (xy 63.233445 -297.161338) (xy 63.256316 -297.204915) (xy 63.2719 -297.251596)
			(xy 63.279795 -297.300173) (xy 63.28029 -297.32478) (xy 63.619138 -297.32478) (xy 63.623098 -297.275726)
			(xy 63.634875 -297.227942) (xy 63.654166 -297.182666) (xy 63.680469 -297.14107) (xy 63.713104 -297.104233)
			(xy 63.751225 -297.073108) (xy 63.793846 -297.048501) (xy 63.839862 -297.031049) (xy 63.888081 -297.021205)
			(xy 63.937256 -297.019224) (xy 63.986111 -297.025156) (xy 64.033382 -297.038848) (xy 64.077844 -297.059946)
			(xy 64.118347 -297.087902) (xy 64.15384 -297.121994) (xy 64.183405 -297.161338) (xy 64.206276 -297.204915)
			(xy 64.22186 -297.251596) (xy 64.229755 -297.300173) (xy 64.23025 -297.32478) (xy 64.569098 -297.32478)
			(xy 64.573058 -297.275726) (xy 64.584835 -297.227942) (xy 64.604126 -297.182666) (xy 64.630429 -297.14107)
			(xy 64.663064 -297.104233) (xy 64.701185 -297.073108) (xy 64.743806 -297.048501) (xy 64.789822 -297.031049)
			(xy 64.838041 -297.021205) (xy 64.887216 -297.019224) (xy 64.936071 -297.025156) (xy 64.983342 -297.038848)
			(xy 65.027804 -297.059946) (xy 65.068307 -297.087902) (xy 65.1038 -297.121994) (xy 65.133365 -297.161338)
			(xy 65.156236 -297.204915) (xy 65.17182 -297.251596) (xy 65.179715 -297.300173) (xy 65.18021 -297.32478)
			(xy 65.519058 -297.32478) (xy 65.523018 -297.275726) (xy 65.534795 -297.227942) (xy 65.554086 -297.182666)
			(xy 65.580389 -297.14107) (xy 65.613024 -297.104233) (xy 65.651145 -297.073108) (xy 65.693766 -297.048501)
			(xy 65.739782 -297.031049) (xy 65.788001 -297.021205) (xy 65.837176 -297.019224) (xy 65.886031 -297.025156)
			(xy 65.933302 -297.038848) (xy 65.977764 -297.059946) (xy 66.018267 -297.087902) (xy 66.05376 -297.121994)
			(xy 66.083325 -297.161338) (xy 66.106196 -297.204915) (xy 66.12178 -297.251596) (xy 66.129675 -297.300173)
			(xy 66.13017 -297.32478) (xy 66.469018 -297.32478) (xy 66.472978 -297.275726) (xy 66.484755 -297.227942)
			(xy 66.504046 -297.182666) (xy 66.530349 -297.14107) (xy 66.562984 -297.104233) (xy 66.601105 -297.073108)
			(xy 66.643726 -297.048501) (xy 66.689742 -297.031049) (xy 66.737961 -297.021205) (xy 66.787136 -297.019224)
			(xy 66.835991 -297.025156) (xy 66.883262 -297.038848) (xy 66.927724 -297.059946) (xy 66.968227 -297.087902)
			(xy 67.00372 -297.121994) (xy 67.033285 -297.161338) (xy 67.056156 -297.204915) (xy 67.07174 -297.251596)
			(xy 67.079635 -297.300173) (xy 67.08013 -297.32478) (xy 67.418978 -297.32478) (xy 67.422938 -297.275726)
			(xy 67.434715 -297.227942) (xy 67.454006 -297.182666) (xy 67.480309 -297.14107) (xy 67.512944 -297.104233)
			(xy 67.551065 -297.073108) (xy 67.593686 -297.048501) (xy 67.639702 -297.031049) (xy 67.687921 -297.021205)
			(xy 67.737096 -297.019224) (xy 67.785951 -297.025156) (xy 67.833222 -297.038848) (xy 67.877684 -297.059946)
			(xy 67.918187 -297.087902) (xy 67.95368 -297.121994) (xy 67.983245 -297.161338) (xy 68.006116 -297.204915)
			(xy 68.0217 -297.251596) (xy 68.029595 -297.300173) (xy 68.03009 -297.32478) (xy 68.368938 -297.32478)
			(xy 68.372898 -297.275726) (xy 68.384675 -297.227942) (xy 68.403966 -297.182666) (xy 68.430269 -297.14107)
			(xy 68.462904 -297.104233) (xy 68.501025 -297.073108) (xy 68.543646 -297.048501) (xy 68.589662 -297.031049)
			(xy 68.637881 -297.021205) (xy 68.687056 -297.019224) (xy 68.735911 -297.025156) (xy 68.783182 -297.038848)
			(xy 68.827644 -297.059946) (xy 68.868147 -297.087902) (xy 68.90364 -297.121994) (xy 68.933205 -297.161338)
			(xy 68.956076 -297.204915) (xy 68.97166 -297.251596) (xy 68.979555 -297.300173) (xy 68.98005 -297.32478)
			(xy 69.319152 -297.32478) (xy 69.323112 -297.275726) (xy 69.334889 -297.227942) (xy 69.35418 -297.182666)
			(xy 69.380483 -297.14107) (xy 69.413118 -297.104233) (xy 69.451239 -297.073108) (xy 69.49386 -297.048501)
			(xy 69.539876 -297.031049) (xy 69.588095 -297.021205) (xy 69.63727 -297.019224) (xy 69.686125 -297.025156)
			(xy 69.733396 -297.038848) (xy 69.777858 -297.059946) (xy 69.818361 -297.087902) (xy 69.853854 -297.121994)
			(xy 69.883419 -297.161338) (xy 69.90629 -297.204915) (xy 69.921874 -297.251596) (xy 69.929769 -297.300173)
			(xy 69.930264 -297.32478) (xy 70.269112 -297.32478) (xy 70.273072 -297.275726) (xy 70.284849 -297.227942)
			(xy 70.30414 -297.182666) (xy 70.330443 -297.14107) (xy 70.363078 -297.104233) (xy 70.401199 -297.073108)
			(xy 70.44382 -297.048501) (xy 70.489836 -297.031049) (xy 70.538055 -297.021205) (xy 70.58723 -297.019224)
			(xy 70.636085 -297.025156) (xy 70.683356 -297.038848) (xy 70.727818 -297.059946) (xy 70.768321 -297.087902)
			(xy 70.803814 -297.121994) (xy 70.833379 -297.161338) (xy 70.85625 -297.204915) (xy 70.871834 -297.251596)
			(xy 70.879729 -297.300173) (xy 70.880224 -297.32478) (xy 71.219072 -297.32478) (xy 71.223032 -297.275726)
			(xy 71.234809 -297.227942) (xy 71.2541 -297.182666) (xy 71.280403 -297.14107) (xy 71.313038 -297.104233)
			(xy 71.351159 -297.073108) (xy 71.39378 -297.048501) (xy 71.439796 -297.031049) (xy 71.488015 -297.021205)
			(xy 71.53719 -297.019224) (xy 71.586045 -297.025156) (xy 71.633316 -297.038848) (xy 71.677778 -297.059946)
			(xy 71.718281 -297.087902) (xy 71.753774 -297.121994) (xy 71.783339 -297.161338) (xy 71.80621 -297.204915)
			(xy 71.821794 -297.251596) (xy 71.829689 -297.300173) (xy 71.830184 -297.32478) (xy 73.118992 -297.32478)
			(xy 73.122952 -297.275726) (xy 73.134729 -297.227942) (xy 73.15402 -297.182666) (xy 73.180323 -297.14107)
			(xy 73.212958 -297.104233) (xy 73.251079 -297.073108) (xy 73.2937 -297.048501) (xy 73.339716 -297.031049)
			(xy 73.387935 -297.021205) (xy 73.43711 -297.019224) (xy 73.485965 -297.025156) (xy 73.533236 -297.038848)
			(xy 73.577698 -297.059946) (xy 73.618201 -297.087902) (xy 73.653694 -297.121994) (xy 73.683259 -297.161338)
			(xy 73.70613 -297.204915) (xy 73.721714 -297.251596) (xy 73.729609 -297.300173) (xy 73.730104 -297.32478)
			(xy 74.069206 -297.32478) (xy 74.073166 -297.275726) (xy 74.084943 -297.227942) (xy 74.104234 -297.182666)
			(xy 74.130537 -297.14107) (xy 74.163172 -297.104233) (xy 74.201293 -297.073108) (xy 74.243914 -297.048501)
			(xy 74.28993 -297.031049) (xy 74.338149 -297.021205) (xy 74.387324 -297.019224) (xy 74.436179 -297.025156)
			(xy 74.48345 -297.038848) (xy 74.527912 -297.059946) (xy 74.568415 -297.087902) (xy 74.603908 -297.121994)
			(xy 74.633473 -297.161338) (xy 74.656344 -297.204915) (xy 74.671928 -297.251596) (xy 74.679823 -297.300173)
			(xy 74.680318 -297.32478) (xy 75.019166 -297.32478) (xy 75.023126 -297.275726) (xy 75.034903 -297.227942)
			(xy 75.054194 -297.182666) (xy 75.080497 -297.14107) (xy 75.113132 -297.104233) (xy 75.151253 -297.073108)
			(xy 75.193874 -297.048501) (xy 75.23989 -297.031049) (xy 75.288109 -297.021205) (xy 75.337284 -297.019224)
			(xy 75.386139 -297.025156) (xy 75.43341 -297.038848) (xy 75.477872 -297.059946) (xy 75.518375 -297.087902)
			(xy 75.553868 -297.121994) (xy 75.583433 -297.161338) (xy 75.606304 -297.204915) (xy 75.621888 -297.251596)
			(xy 75.629783 -297.300173) (xy 75.630278 -297.32478) (xy 75.969126 -297.32478) (xy 75.973086 -297.275726)
			(xy 75.984863 -297.227942) (xy 76.004154 -297.182666) (xy 76.030457 -297.14107) (xy 76.063092 -297.104233)
			(xy 76.101213 -297.073108) (xy 76.143834 -297.048501) (xy 76.18985 -297.031049) (xy 76.238069 -297.021205)
			(xy 76.287244 -297.019224) (xy 76.336099 -297.025156) (xy 76.38337 -297.038848) (xy 76.427832 -297.059946)
			(xy 76.468335 -297.087902) (xy 76.503828 -297.121994) (xy 76.533393 -297.161338) (xy 76.556264 -297.204915)
			(xy 76.571848 -297.251596) (xy 76.579743 -297.300173) (xy 76.580238 -297.32478) (xy 76.919086 -297.32478)
			(xy 76.923046 -297.275726) (xy 76.934823 -297.227942) (xy 76.954114 -297.182666) (xy 76.980417 -297.14107)
			(xy 77.013052 -297.104233) (xy 77.051173 -297.073108) (xy 77.093794 -297.048501) (xy 77.13981 -297.031049)
			(xy 77.188029 -297.021205) (xy 77.237204 -297.019224) (xy 77.286059 -297.025156) (xy 77.33333 -297.038848)
			(xy 77.377792 -297.059946) (xy 77.418295 -297.087902) (xy 77.453788 -297.121994) (xy 77.483353 -297.161338)
			(xy 77.506224 -297.204915) (xy 77.521808 -297.251596) (xy 77.529703 -297.300173) (xy 77.530198 -297.32478)
			(xy 77.869046 -297.32478) (xy 77.873006 -297.275726) (xy 77.884783 -297.227942) (xy 77.904074 -297.182666)
			(xy 77.930377 -297.14107) (xy 77.963012 -297.104233) (xy 78.001133 -297.073108) (xy 78.043754 -297.048501)
			(xy 78.08977 -297.031049) (xy 78.137989 -297.021205) (xy 78.187164 -297.019224) (xy 78.236019 -297.025156)
			(xy 78.28329 -297.038848) (xy 78.327752 -297.059946) (xy 78.368255 -297.087902) (xy 78.403748 -297.121994)
			(xy 78.433313 -297.161338) (xy 78.456184 -297.204915) (xy 78.471768 -297.251596) (xy 78.479663 -297.300173)
			(xy 78.480158 -297.32478) (xy 78.819006 -297.32478) (xy 78.822966 -297.275726) (xy 78.834743 -297.227942)
			(xy 78.854034 -297.182666) (xy 78.880337 -297.14107) (xy 78.912972 -297.104233) (xy 78.951093 -297.073108)
			(xy 78.993714 -297.048501) (xy 79.03973 -297.031049) (xy 79.087949 -297.021205) (xy 79.137124 -297.019224)
			(xy 79.185979 -297.025156) (xy 79.23325 -297.038848) (xy 79.277712 -297.059946) (xy 79.318215 -297.087902)
			(xy 79.353708 -297.121994) (xy 79.383273 -297.161338) (xy 79.406144 -297.204915) (xy 79.421728 -297.251596)
			(xy 79.429623 -297.300173) (xy 79.430118 -297.32478) (xy 79.768966 -297.32478) (xy 79.772926 -297.275726)
			(xy 79.784703 -297.227942) (xy 79.803994 -297.182666) (xy 79.830297 -297.14107) (xy 79.862932 -297.104233)
			(xy 79.901053 -297.073108) (xy 79.943674 -297.048501) (xy 79.98969 -297.031049) (xy 80.037909 -297.021205)
			(xy 80.087084 -297.019224) (xy 80.135939 -297.025156) (xy 80.18321 -297.038848) (xy 80.227672 -297.059946)
			(xy 80.268175 -297.087902) (xy 80.303668 -297.121994) (xy 80.333233 -297.161338) (xy 80.356104 -297.204915)
			(xy 80.371688 -297.251596) (xy 80.379583 -297.300173) (xy 80.380078 -297.32478) (xy 80.71918 -297.32478)
			(xy 80.72314 -297.275726) (xy 80.734917 -297.227942) (xy 80.754208 -297.182666) (xy 80.780511 -297.14107)
			(xy 80.813146 -297.104233) (xy 80.851267 -297.073108) (xy 80.893888 -297.048501) (xy 80.939904 -297.031049)
			(xy 80.988123 -297.021205) (xy 81.037298 -297.019224) (xy 81.086153 -297.025156) (xy 81.133424 -297.038848)
			(xy 81.177886 -297.059946) (xy 81.218389 -297.087902) (xy 81.253882 -297.121994) (xy 81.283447 -297.161338)
			(xy 81.306318 -297.204915) (xy 81.321902 -297.251596) (xy 81.329797 -297.300173) (xy 81.330292 -297.32478)
			(xy 81.66914 -297.32478) (xy 81.6731 -297.275726) (xy 81.684877 -297.227942) (xy 81.704168 -297.182666)
			(xy 81.730471 -297.14107) (xy 81.763106 -297.104233) (xy 81.801227 -297.073108) (xy 81.843848 -297.048501)
			(xy 81.889864 -297.031049) (xy 81.938083 -297.021205) (xy 81.987258 -297.019224) (xy 82.036113 -297.025156)
			(xy 82.083384 -297.038848) (xy 82.127846 -297.059946) (xy 82.168349 -297.087902) (xy 82.203842 -297.121994)
			(xy 82.233407 -297.161338) (xy 82.256278 -297.204915) (xy 82.271862 -297.251596) (xy 82.279757 -297.300173)
			(xy 82.280252 -297.32478) (xy 82.6191 -297.32478) (xy 82.62306 -297.275726) (xy 82.634837 -297.227942)
			(xy 82.654128 -297.182666) (xy 82.680431 -297.14107) (xy 82.713066 -297.104233) (xy 82.751187 -297.073108)
			(xy 82.793808 -297.048501) (xy 82.839824 -297.031049) (xy 82.888043 -297.021205) (xy 82.937218 -297.019224)
			(xy 82.986073 -297.025156) (xy 83.033344 -297.038848) (xy 83.077806 -297.059946) (xy 83.118309 -297.087902)
			(xy 83.153802 -297.121994) (xy 83.183367 -297.161338) (xy 83.206238 -297.204915) (xy 83.221822 -297.251596)
			(xy 83.229717 -297.300173) (xy 83.230212 -297.32478) (xy 83.229717 -297.349387) (xy 83.221822 -297.397964)
			(xy 83.206238 -297.444645) (xy 83.183367 -297.488222) (xy 83.153802 -297.527566) (xy 83.118309 -297.561658)
			(xy 83.077806 -297.589614) (xy 83.033344 -297.610712) (xy 82.986073 -297.624404) (xy 82.937218 -297.630336)
			(xy 82.888043 -297.628355) (xy 82.839824 -297.618511) (xy 82.793808 -297.601059) (xy 82.751187 -297.576452)
			(xy 82.713066 -297.545327) (xy 82.680431 -297.50849) (xy 82.654128 -297.466894) (xy 82.634837 -297.421618)
			(xy 82.62306 -297.373834) (xy 82.6191 -297.32478) (xy 82.280252 -297.32478) (xy 82.279757 -297.349387)
			(xy 82.271862 -297.397964) (xy 82.256278 -297.444645) (xy 82.233407 -297.488222) (xy 82.203842 -297.527566)
			(xy 82.168349 -297.561658) (xy 82.127846 -297.589614) (xy 82.083384 -297.610712) (xy 82.036113 -297.624404)
			(xy 81.987258 -297.630336) (xy 81.938083 -297.628355) (xy 81.889864 -297.618511) (xy 81.843848 -297.601059)
			(xy 81.801227 -297.576452) (xy 81.763106 -297.545327) (xy 81.730471 -297.50849) (xy 81.704168 -297.466894)
			(xy 81.684877 -297.421618) (xy 81.6731 -297.373834) (xy 81.66914 -297.32478) (xy 81.330292 -297.32478)
			(xy 81.329797 -297.349387) (xy 81.321902 -297.397964) (xy 81.306318 -297.444645) (xy 81.283447 -297.488222)
			(xy 81.253882 -297.527566) (xy 81.218389 -297.561658) (xy 81.177886 -297.589614) (xy 81.133424 -297.610712)
			(xy 81.086153 -297.624404) (xy 81.037298 -297.630336) (xy 80.988123 -297.628355) (xy 80.939904 -297.618511)
			(xy 80.893888 -297.601059) (xy 80.851267 -297.576452) (xy 80.813146 -297.545327) (xy 80.780511 -297.50849)
			(xy 80.754208 -297.466894) (xy 80.734917 -297.421618) (xy 80.72314 -297.373834) (xy 80.71918 -297.32478)
			(xy 80.380078 -297.32478) (xy 80.379583 -297.349387) (xy 80.371688 -297.397964) (xy 80.356104 -297.444645)
			(xy 80.333233 -297.488222) (xy 80.303668 -297.527566) (xy 80.268175 -297.561658) (xy 80.227672 -297.589614)
			(xy 80.18321 -297.610712) (xy 80.135939 -297.624404) (xy 80.087084 -297.630336) (xy 80.037909 -297.628355)
			(xy 79.98969 -297.618511) (xy 79.943674 -297.601059) (xy 79.901053 -297.576452) (xy 79.862932 -297.545327)
			(xy 79.830297 -297.50849) (xy 79.803994 -297.466894) (xy 79.784703 -297.421618) (xy 79.772926 -297.373834)
			(xy 79.768966 -297.32478) (xy 79.430118 -297.32478) (xy 79.429623 -297.349387) (xy 79.421728 -297.397964)
			(xy 79.406144 -297.444645) (xy 79.383273 -297.488222) (xy 79.353708 -297.527566) (xy 79.318215 -297.561658)
			(xy 79.277712 -297.589614) (xy 79.23325 -297.610712) (xy 79.185979 -297.624404) (xy 79.137124 -297.630336)
			(xy 79.087949 -297.628355) (xy 79.03973 -297.618511) (xy 78.993714 -297.601059) (xy 78.951093 -297.576452)
			(xy 78.912972 -297.545327) (xy 78.880337 -297.50849) (xy 78.854034 -297.466894) (xy 78.834743 -297.421618)
			(xy 78.822966 -297.373834) (xy 78.819006 -297.32478) (xy 78.480158 -297.32478) (xy 78.479663 -297.349387)
			(xy 78.471768 -297.397964) (xy 78.456184 -297.444645) (xy 78.433313 -297.488222) (xy 78.403748 -297.527566)
			(xy 78.368255 -297.561658) (xy 78.327752 -297.589614) (xy 78.28329 -297.610712) (xy 78.236019 -297.624404)
			(xy 78.187164 -297.630336) (xy 78.137989 -297.628355) (xy 78.08977 -297.618511) (xy 78.043754 -297.601059)
			(xy 78.001133 -297.576452) (xy 77.963012 -297.545327) (xy 77.930377 -297.50849) (xy 77.904074 -297.466894)
			(xy 77.884783 -297.421618) (xy 77.873006 -297.373834) (xy 77.869046 -297.32478) (xy 77.530198 -297.32478)
			(xy 77.529703 -297.349387) (xy 77.521808 -297.397964) (xy 77.506224 -297.444645) (xy 77.483353 -297.488222)
			(xy 77.453788 -297.527566) (xy 77.418295 -297.561658) (xy 77.377792 -297.589614) (xy 77.33333 -297.610712)
			(xy 77.286059 -297.624404) (xy 77.237204 -297.630336) (xy 77.188029 -297.628355) (xy 77.13981 -297.618511)
			(xy 77.093794 -297.601059) (xy 77.051173 -297.576452) (xy 77.013052 -297.545327) (xy 76.980417 -297.50849)
			(xy 76.954114 -297.466894) (xy 76.934823 -297.421618) (xy 76.923046 -297.373834) (xy 76.919086 -297.32478)
			(xy 76.580238 -297.32478) (xy 76.579743 -297.349387) (xy 76.571848 -297.397964) (xy 76.556264 -297.444645)
			(xy 76.533393 -297.488222) (xy 76.503828 -297.527566) (xy 76.468335 -297.561658) (xy 76.427832 -297.589614)
			(xy 76.38337 -297.610712) (xy 76.336099 -297.624404) (xy 76.287244 -297.630336) (xy 76.238069 -297.628355)
			(xy 76.18985 -297.618511) (xy 76.143834 -297.601059) (xy 76.101213 -297.576452) (xy 76.063092 -297.545327)
			(xy 76.030457 -297.50849) (xy 76.004154 -297.466894) (xy 75.984863 -297.421618) (xy 75.973086 -297.373834)
			(xy 75.969126 -297.32478) (xy 75.630278 -297.32478) (xy 75.629783 -297.349387) (xy 75.621888 -297.397964)
			(xy 75.606304 -297.444645) (xy 75.583433 -297.488222) (xy 75.553868 -297.527566) (xy 75.518375 -297.561658)
			(xy 75.477872 -297.589614) (xy 75.43341 -297.610712) (xy 75.386139 -297.624404) (xy 75.337284 -297.630336)
			(xy 75.288109 -297.628355) (xy 75.23989 -297.618511) (xy 75.193874 -297.601059) (xy 75.151253 -297.576452)
			(xy 75.113132 -297.545327) (xy 75.080497 -297.50849) (xy 75.054194 -297.466894) (xy 75.034903 -297.421618)
			(xy 75.023126 -297.373834) (xy 75.019166 -297.32478) (xy 74.680318 -297.32478) (xy 74.679823 -297.349387)
			(xy 74.671928 -297.397964) (xy 74.656344 -297.444645) (xy 74.633473 -297.488222) (xy 74.603908 -297.527566)
			(xy 74.568415 -297.561658) (xy 74.527912 -297.589614) (xy 74.48345 -297.610712) (xy 74.436179 -297.624404)
			(xy 74.387324 -297.630336) (xy 74.338149 -297.628355) (xy 74.28993 -297.618511) (xy 74.243914 -297.601059)
			(xy 74.201293 -297.576452) (xy 74.163172 -297.545327) (xy 74.130537 -297.50849) (xy 74.104234 -297.466894)
			(xy 74.084943 -297.421618) (xy 74.073166 -297.373834) (xy 74.069206 -297.32478) (xy 73.730104 -297.32478)
			(xy 73.729609 -297.349387) (xy 73.721714 -297.397964) (xy 73.70613 -297.444645) (xy 73.683259 -297.488222)
			(xy 73.653694 -297.527566) (xy 73.618201 -297.561658) (xy 73.577698 -297.589614) (xy 73.533236 -297.610712)
			(xy 73.485965 -297.624404) (xy 73.43711 -297.630336) (xy 73.387935 -297.628355) (xy 73.339716 -297.618511)
			(xy 73.2937 -297.601059) (xy 73.251079 -297.576452) (xy 73.212958 -297.545327) (xy 73.180323 -297.50849)
			(xy 73.15402 -297.466894) (xy 73.134729 -297.421618) (xy 73.122952 -297.373834) (xy 73.118992 -297.32478)
			(xy 71.830184 -297.32478) (xy 71.829689 -297.349387) (xy 71.821794 -297.397964) (xy 71.80621 -297.444645)
			(xy 71.783339 -297.488222) (xy 71.753774 -297.527566) (xy 71.718281 -297.561658) (xy 71.677778 -297.589614)
			(xy 71.633316 -297.610712) (xy 71.586045 -297.624404) (xy 71.53719 -297.630336) (xy 71.488015 -297.628355)
			(xy 71.439796 -297.618511) (xy 71.39378 -297.601059) (xy 71.351159 -297.576452) (xy 71.313038 -297.545327)
			(xy 71.280403 -297.50849) (xy 71.2541 -297.466894) (xy 71.234809 -297.421618) (xy 71.223032 -297.373834)
			(xy 71.219072 -297.32478) (xy 70.880224 -297.32478) (xy 70.879729 -297.349387) (xy 70.871834 -297.397964)
			(xy 70.85625 -297.444645) (xy 70.833379 -297.488222) (xy 70.803814 -297.527566) (xy 70.768321 -297.561658)
			(xy 70.727818 -297.589614) (xy 70.683356 -297.610712) (xy 70.636085 -297.624404) (xy 70.58723 -297.630336)
			(xy 70.538055 -297.628355) (xy 70.489836 -297.618511) (xy 70.44382 -297.601059) (xy 70.401199 -297.576452)
			(xy 70.363078 -297.545327) (xy 70.330443 -297.50849) (xy 70.30414 -297.466894) (xy 70.284849 -297.421618)
			(xy 70.273072 -297.373834) (xy 70.269112 -297.32478) (xy 69.930264 -297.32478) (xy 69.929769 -297.349387)
			(xy 69.921874 -297.397964) (xy 69.90629 -297.444645) (xy 69.883419 -297.488222) (xy 69.853854 -297.527566)
			(xy 69.818361 -297.561658) (xy 69.777858 -297.589614) (xy 69.733396 -297.610712) (xy 69.686125 -297.624404)
			(xy 69.63727 -297.630336) (xy 69.588095 -297.628355) (xy 69.539876 -297.618511) (xy 69.49386 -297.601059)
			(xy 69.451239 -297.576452) (xy 69.413118 -297.545327) (xy 69.380483 -297.50849) (xy 69.35418 -297.466894)
			(xy 69.334889 -297.421618) (xy 69.323112 -297.373834) (xy 69.319152 -297.32478) (xy 68.98005 -297.32478)
			(xy 68.979555 -297.349387) (xy 68.97166 -297.397964) (xy 68.956076 -297.444645) (xy 68.933205 -297.488222)
			(xy 68.90364 -297.527566) (xy 68.868147 -297.561658) (xy 68.827644 -297.589614) (xy 68.783182 -297.610712)
			(xy 68.735911 -297.624404) (xy 68.687056 -297.630336) (xy 68.637881 -297.628355) (xy 68.589662 -297.618511)
			(xy 68.543646 -297.601059) (xy 68.501025 -297.576452) (xy 68.462904 -297.545327) (xy 68.430269 -297.50849)
			(xy 68.403966 -297.466894) (xy 68.384675 -297.421618) (xy 68.372898 -297.373834) (xy 68.368938 -297.32478)
			(xy 68.03009 -297.32478) (xy 68.029595 -297.349387) (xy 68.0217 -297.397964) (xy 68.006116 -297.444645)
			(xy 67.983245 -297.488222) (xy 67.95368 -297.527566) (xy 67.918187 -297.561658) (xy 67.877684 -297.589614)
			(xy 67.833222 -297.610712) (xy 67.785951 -297.624404) (xy 67.737096 -297.630336) (xy 67.687921 -297.628355)
			(xy 67.639702 -297.618511) (xy 67.593686 -297.601059) (xy 67.551065 -297.576452) (xy 67.512944 -297.545327)
			(xy 67.480309 -297.50849) (xy 67.454006 -297.466894) (xy 67.434715 -297.421618) (xy 67.422938 -297.373834)
			(xy 67.418978 -297.32478) (xy 67.08013 -297.32478) (xy 67.079635 -297.349387) (xy 67.07174 -297.397964)
			(xy 67.056156 -297.444645) (xy 67.033285 -297.488222) (xy 67.00372 -297.527566) (xy 66.968227 -297.561658)
			(xy 66.927724 -297.589614) (xy 66.883262 -297.610712) (xy 66.835991 -297.624404) (xy 66.787136 -297.630336)
			(xy 66.737961 -297.628355) (xy 66.689742 -297.618511) (xy 66.643726 -297.601059) (xy 66.601105 -297.576452)
			(xy 66.562984 -297.545327) (xy 66.530349 -297.50849) (xy 66.504046 -297.466894) (xy 66.484755 -297.421618)
			(xy 66.472978 -297.373834) (xy 66.469018 -297.32478) (xy 66.13017 -297.32478) (xy 66.129675 -297.349387)
			(xy 66.12178 -297.397964) (xy 66.106196 -297.444645) (xy 66.083325 -297.488222) (xy 66.05376 -297.527566)
			(xy 66.018267 -297.561658) (xy 65.977764 -297.589614) (xy 65.933302 -297.610712) (xy 65.886031 -297.624404)
			(xy 65.837176 -297.630336) (xy 65.788001 -297.628355) (xy 65.739782 -297.618511) (xy 65.693766 -297.601059)
			(xy 65.651145 -297.576452) (xy 65.613024 -297.545327) (xy 65.580389 -297.50849) (xy 65.554086 -297.466894)
			(xy 65.534795 -297.421618) (xy 65.523018 -297.373834) (xy 65.519058 -297.32478) (xy 65.18021 -297.32478)
			(xy 65.179715 -297.349387) (xy 65.17182 -297.397964) (xy 65.156236 -297.444645) (xy 65.133365 -297.488222)
			(xy 65.1038 -297.527566) (xy 65.068307 -297.561658) (xy 65.027804 -297.589614) (xy 64.983342 -297.610712)
			(xy 64.936071 -297.624404) (xy 64.887216 -297.630336) (xy 64.838041 -297.628355) (xy 64.789822 -297.618511)
			(xy 64.743806 -297.601059) (xy 64.701185 -297.576452) (xy 64.663064 -297.545327) (xy 64.630429 -297.50849)
			(xy 64.604126 -297.466894) (xy 64.584835 -297.421618) (xy 64.573058 -297.373834) (xy 64.569098 -297.32478)
			(xy 64.23025 -297.32478) (xy 64.229755 -297.349387) (xy 64.22186 -297.397964) (xy 64.206276 -297.444645)
			(xy 64.183405 -297.488222) (xy 64.15384 -297.527566) (xy 64.118347 -297.561658) (xy 64.077844 -297.589614)
			(xy 64.033382 -297.610712) (xy 63.986111 -297.624404) (xy 63.937256 -297.630336) (xy 63.888081 -297.628355)
			(xy 63.839862 -297.618511) (xy 63.793846 -297.601059) (xy 63.751225 -297.576452) (xy 63.713104 -297.545327)
			(xy 63.680469 -297.50849) (xy 63.654166 -297.466894) (xy 63.634875 -297.421618) (xy 63.623098 -297.373834)
			(xy 63.619138 -297.32478) (xy 63.28029 -297.32478) (xy 63.279795 -297.349387) (xy 63.2719 -297.397964)
			(xy 63.256316 -297.444645) (xy 63.233445 -297.488222) (xy 63.20388 -297.527566) (xy 63.168387 -297.561658)
			(xy 63.127884 -297.589614) (xy 63.083422 -297.610712) (xy 63.036151 -297.624404) (xy 62.987296 -297.630336)
			(xy 62.938121 -297.628355) (xy 62.889902 -297.618511) (xy 62.843886 -297.601059) (xy 62.801265 -297.576452)
			(xy 62.763144 -297.545327) (xy 62.730509 -297.50849) (xy 62.704206 -297.466894) (xy 62.684915 -297.421618)
			(xy 62.673138 -297.373834) (xy 62.669178 -297.32478) (xy 62.330076 -297.32478) (xy 62.329581 -297.349387)
			(xy 62.321686 -297.397964) (xy 62.306102 -297.444645) (xy 62.283231 -297.488222) (xy 62.253666 -297.527566)
			(xy 62.218173 -297.561658) (xy 62.17767 -297.589614) (xy 62.133208 -297.610712) (xy 62.085937 -297.624404)
			(xy 62.037082 -297.630336) (xy 61.987907 -297.628355) (xy 61.939688 -297.618511) (xy 61.893672 -297.601059)
			(xy 61.851051 -297.576452) (xy 61.81293 -297.545327) (xy 61.780295 -297.50849) (xy 61.753992 -297.466894)
			(xy 61.734701 -297.421618) (xy 61.722924 -297.373834) (xy 61.718964 -297.32478) (xy 61.380116 -297.32478)
			(xy 61.379621 -297.349387) (xy 61.371726 -297.397964) (xy 61.356142 -297.444645) (xy 61.333271 -297.488222)
			(xy 61.303706 -297.527566) (xy 61.268213 -297.561658) (xy 61.22771 -297.589614) (xy 61.183248 -297.610712)
			(xy 61.135977 -297.624404) (xy 61.087122 -297.630336) (xy 61.037947 -297.628355) (xy 60.989728 -297.618511)
			(xy 60.943712 -297.601059) (xy 60.901091 -297.576452) (xy 60.86297 -297.545327) (xy 60.830335 -297.50849)
			(xy 60.804032 -297.466894) (xy 60.784741 -297.421618) (xy 60.772964 -297.373834) (xy 60.769004 -297.32478)
			(xy 60.430156 -297.32478) (xy 60.429661 -297.349387) (xy 60.421766 -297.397964) (xy 60.406182 -297.444645)
			(xy 60.383311 -297.488222) (xy 60.353746 -297.527566) (xy 60.318253 -297.561658) (xy 60.27775 -297.589614)
			(xy 60.233288 -297.610712) (xy 60.186017 -297.624404) (xy 60.137162 -297.630336) (xy 60.087987 -297.628355)
			(xy 60.039768 -297.618511) (xy 59.993752 -297.601059) (xy 59.951131 -297.576452) (xy 59.91301 -297.545327)
			(xy 59.880375 -297.50849) (xy 59.854072 -297.466894) (xy 59.834781 -297.421618) (xy 59.823004 -297.373834)
			(xy 59.819044 -297.32478) (xy 58.530236 -297.32478) (xy 58.529741 -297.349387) (xy 58.521846 -297.397964)
			(xy 58.506262 -297.444645) (xy 58.483391 -297.488222) (xy 58.453826 -297.527566) (xy 58.418333 -297.561658)
			(xy 58.37783 -297.589614) (xy 58.333368 -297.610712) (xy 58.286097 -297.624404) (xy 58.237242 -297.630336)
			(xy 58.188067 -297.628355) (xy 58.139848 -297.618511) (xy 58.093832 -297.601059) (xy 58.051211 -297.576452)
			(xy 58.01309 -297.545327) (xy 57.980455 -297.50849) (xy 57.954152 -297.466894) (xy 57.934861 -297.421618)
			(xy 57.923084 -297.373834) (xy 57.919124 -297.32478) (xy 57.580276 -297.32478) (xy 57.579781 -297.349387)
			(xy 57.571886 -297.397964) (xy 57.556302 -297.444645) (xy 57.533431 -297.488222) (xy 57.503866 -297.527566)
			(xy 57.468373 -297.561658) (xy 57.42787 -297.589614) (xy 57.383408 -297.610712) (xy 57.336137 -297.624404)
			(xy 57.287282 -297.630336) (xy 57.238107 -297.628355) (xy 57.189888 -297.618511) (xy 57.143872 -297.601059)
			(xy 57.101251 -297.576452) (xy 57.06313 -297.545327) (xy 57.030495 -297.50849) (xy 57.004192 -297.466894)
			(xy 56.984901 -297.421618) (xy 56.973124 -297.373834) (xy 56.969164 -297.32478) (xy 56.630062 -297.32478)
			(xy 56.629567 -297.349387) (xy 56.621672 -297.397964) (xy 56.606088 -297.444645) (xy 56.583217 -297.488222)
			(xy 56.553652 -297.527566) (xy 56.518159 -297.561658) (xy 56.477656 -297.589614) (xy 56.433194 -297.610712)
			(xy 56.385923 -297.624404) (xy 56.337068 -297.630336) (xy 56.287893 -297.628355) (xy 56.239674 -297.618511)
			(xy 56.193658 -297.601059) (xy 56.151037 -297.576452) (xy 56.112916 -297.545327) (xy 56.080281 -297.50849)
			(xy 56.053978 -297.466894) (xy 56.034687 -297.421618) (xy 56.02291 -297.373834) (xy 56.01895 -297.32478)
			(xy 55.680102 -297.32478) (xy 55.679607 -297.349387) (xy 55.671712 -297.397964) (xy 55.656128 -297.444645)
			(xy 55.633257 -297.488222) (xy 55.603692 -297.527566) (xy 55.568199 -297.561658) (xy 55.527696 -297.589614)
			(xy 55.483234 -297.610712) (xy 55.435963 -297.624404) (xy 55.387108 -297.630336) (xy 55.337933 -297.628355)
			(xy 55.289714 -297.618511) (xy 55.243698 -297.601059) (xy 55.201077 -297.576452) (xy 55.162956 -297.545327)
			(xy 55.130321 -297.50849) (xy 55.104018 -297.466894) (xy 55.084727 -297.421618) (xy 55.07295 -297.373834)
			(xy 55.06899 -297.32478) (xy 54.730142 -297.32478) (xy 54.729647 -297.349387) (xy 54.721752 -297.397964)
			(xy 54.706168 -297.444645) (xy 54.683297 -297.488222) (xy 54.653732 -297.527566) (xy 54.618239 -297.561658)
			(xy 54.577736 -297.589614) (xy 54.533274 -297.610712) (xy 54.486003 -297.624404) (xy 54.437148 -297.630336)
			(xy 54.387973 -297.628355) (xy 54.339754 -297.618511) (xy 54.293738 -297.601059) (xy 54.251117 -297.576452)
			(xy 54.212996 -297.545327) (xy 54.180361 -297.50849) (xy 54.154058 -297.466894) (xy 54.134767 -297.421618)
			(xy 54.12299 -297.373834) (xy 54.11903 -297.32478) (xy 53.780182 -297.32478) (xy 53.779687 -297.349387)
			(xy 53.771792 -297.397964) (xy 53.756208 -297.444645) (xy 53.733337 -297.488222) (xy 53.703772 -297.527566)
			(xy 53.668279 -297.561658) (xy 53.627776 -297.589614) (xy 53.583314 -297.610712) (xy 53.536043 -297.624404)
			(xy 53.487188 -297.630336) (xy 53.438013 -297.628355) (xy 53.389794 -297.618511) (xy 53.343778 -297.601059)
			(xy 53.301157 -297.576452) (xy 53.263036 -297.545327) (xy 53.230401 -297.50849) (xy 53.204098 -297.466894)
			(xy 53.184807 -297.421618) (xy 53.17303 -297.373834) (xy 53.16907 -297.32478) (xy 52.830222 -297.32478)
			(xy 52.829727 -297.349387) (xy 52.821832 -297.397964) (xy 52.806248 -297.444645) (xy 52.783377 -297.488222)
			(xy 52.753812 -297.527566) (xy 52.718319 -297.561658) (xy 52.677816 -297.589614) (xy 52.633354 -297.610712)
			(xy 52.586083 -297.624404) (xy 52.537228 -297.630336) (xy 52.488053 -297.628355) (xy 52.439834 -297.618511)
			(xy 52.393818 -297.601059) (xy 52.351197 -297.576452) (xy 52.313076 -297.545327) (xy 52.280441 -297.50849)
			(xy 52.254138 -297.466894) (xy 52.234847 -297.421618) (xy 52.22307 -297.373834) (xy 52.21911 -297.32478)
			(xy 51.880262 -297.32478) (xy 51.879767 -297.349387) (xy 51.871872 -297.397964) (xy 51.856288 -297.444645)
			(xy 51.833417 -297.488222) (xy 51.803852 -297.527566) (xy 51.768359 -297.561658) (xy 51.727856 -297.589614)
			(xy 51.683394 -297.610712) (xy 51.636123 -297.624404) (xy 51.587268 -297.630336) (xy 51.538093 -297.628355)
			(xy 51.489874 -297.618511) (xy 51.443858 -297.601059) (xy 51.401237 -297.576452) (xy 51.363116 -297.545327)
			(xy 51.330481 -297.50849) (xy 51.304178 -297.466894) (xy 51.284887 -297.421618) (xy 51.27311 -297.373834)
			(xy 51.26915 -297.32478) (xy 50.930302 -297.32478) (xy 50.929807 -297.349387) (xy 50.921912 -297.397964)
			(xy 50.906328 -297.444645) (xy 50.883457 -297.488222) (xy 50.853892 -297.527566) (xy 50.818399 -297.561658)
			(xy 50.777896 -297.589614) (xy 50.733434 -297.610712) (xy 50.686163 -297.624404) (xy 50.637308 -297.630336)
			(xy 50.588133 -297.628355) (xy 50.539914 -297.618511) (xy 50.493898 -297.601059) (xy 50.451277 -297.576452)
			(xy 50.413156 -297.545327) (xy 50.380521 -297.50849) (xy 50.354218 -297.466894) (xy 50.334927 -297.421618)
			(xy 50.32315 -297.373834) (xy 50.31919 -297.32478) (xy 49.980088 -297.32478) (xy 49.979593 -297.349387)
			(xy 49.971698 -297.397964) (xy 49.956114 -297.444645) (xy 49.933243 -297.488222) (xy 49.903678 -297.527566)
			(xy 49.868185 -297.561658) (xy 49.827682 -297.589614) (xy 49.78322 -297.610712) (xy 49.735949 -297.624404)
			(xy 49.687094 -297.630336) (xy 49.637919 -297.628355) (xy 49.5897 -297.618511) (xy 49.543684 -297.601059)
			(xy 49.501063 -297.576452) (xy 49.462942 -297.545327) (xy 49.430307 -297.50849) (xy 49.404004 -297.466894)
			(xy 49.384713 -297.421618) (xy 49.372936 -297.373834) (xy 49.368976 -297.32478) (xy 49.030128 -297.32478)
			(xy 49.029633 -297.349387) (xy 49.021738 -297.397964) (xy 49.006154 -297.444645) (xy 48.983283 -297.488222)
			(xy 48.953718 -297.527566) (xy 48.918225 -297.561658) (xy 48.877722 -297.589614) (xy 48.83326 -297.610712)
			(xy 48.785989 -297.624404) (xy 48.737134 -297.630336) (xy 48.687959 -297.628355) (xy 48.63974 -297.618511)
			(xy 48.593724 -297.601059) (xy 48.551103 -297.576452) (xy 48.512982 -297.545327) (xy 48.480347 -297.50849)
			(xy 48.454044 -297.466894) (xy 48.434753 -297.421618) (xy 48.422976 -297.373834) (xy 48.419016 -297.32478)
			(xy 48.080738 -297.32478) (xy 48.08074 -297.3248) (xy 48.076568 -297.375144) (xy 48.064166 -297.424114)
			(xy 48.043872 -297.470375) (xy 48.01624 -297.512664) (xy 47.982024 -297.549828) (xy 47.942157 -297.580853)
			(xy 47.897727 -297.604892) (xy 47.849947 -297.62129) (xy 47.800118 -297.629599) (xy 47.77486 -297.630088)
			(xy 47.752482 -297.62973) (xy 47.708205 -297.623207) (xy 47.665354 -297.610292) (xy 47.624846 -297.591261)
			(xy 47.587549 -297.566523) (xy 47.570644 -297.551856) (xy 47.57039 -297.551602) (xy 47.562881 -297.545386)
			(xy 47.544577 -297.538722) (xy 47.52511 -297.539406) (xy 47.516034 -297.542966) (xy 47.439326 -297.577002)
			(xy 47.430539 -297.581383) (xy 47.416905 -297.595489) (xy 47.409549 -297.613675) (xy 47.4091 -297.623484)
			(xy 47.4091 -297.903138) (xy 47.408634 -297.926963) (xy 47.401347 -297.974054) (xy 47.387022 -298.019502)
			(xy 47.365988 -298.06226) (xy 47.33873 -298.101345) (xy 47.305874 -298.135859) (xy 47.268177 -298.165007)
			(xy 47.247556 -298.17695) (xy 47.246032 -298.177712) (xy 47.112936 -298.253658) (xy 47.107013 -298.25686)
			(xy 47.094013 -298.260343) (xy 47.087282 -298.260516) (xy 46.947328 -298.258992) (xy 46.94087 -298.258781)
			(xy 46.928394 -298.255425) (xy 46.92269 -298.252388) (xy 46.860968 -298.217082) (xy 46.859444 -298.216066)
			(xy 46.851485 -298.211703) (xy 46.833973 -298.206949) (xy 46.8249 -298.206668) (xy 46.812619 -298.207121)
			(xy 46.789609 -298.215711) (xy 46.771104 -298.231859) (xy 46.759479 -298.253493) (xy 46.757336 -298.265596)
			(xy 46.7559 -298.27474) (xy 47.469056 -298.27474) (xy 47.473016 -298.225686) (xy 47.484793 -298.177902)
			(xy 47.504084 -298.132626) (xy 47.530387 -298.09103) (xy 47.563022 -298.054193) (xy 47.601143 -298.023068)
			(xy 47.643764 -297.998461) (xy 47.68978 -297.981009) (xy 47.737999 -297.971165) (xy 47.787174 -297.969184)
			(xy 47.836029 -297.975116) (xy 47.8833 -297.988808) (xy 47.927762 -298.009906) (xy 47.968265 -298.037862)
			(xy 48.003758 -298.071954) (xy 48.033323 -298.111298) (xy 48.056194 -298.154875) (xy 48.071778 -298.201556)
			(xy 48.079673 -298.250133) (xy 48.080168 -298.27474) (xy 48.419016 -298.27474) (xy 48.422976 -298.225686)
			(xy 48.434753 -298.177902) (xy 48.454044 -298.132626) (xy 48.480347 -298.09103) (xy 48.512982 -298.054193)
			(xy 48.551103 -298.023068) (xy 48.593724 -297.998461) (xy 48.63974 -297.981009) (xy 48.687959 -297.971165)
			(xy 48.737134 -297.969184) (xy 48.785989 -297.975116) (xy 48.83326 -297.988808) (xy 48.877722 -298.009906)
			(xy 48.918225 -298.037862) (xy 48.953718 -298.071954) (xy 48.983283 -298.111298) (xy 49.006154 -298.154875)
			(xy 49.021738 -298.201556) (xy 49.029633 -298.250133) (xy 49.030128 -298.27474) (xy 49.368976 -298.27474)
			(xy 49.372936 -298.225686) (xy 49.384713 -298.177902) (xy 49.404004 -298.132626) (xy 49.430307 -298.09103)
			(xy 49.462942 -298.054193) (xy 49.501063 -298.023068) (xy 49.543684 -297.998461) (xy 49.5897 -297.981009)
			(xy 49.637919 -297.971165) (xy 49.687094 -297.969184) (xy 49.735949 -297.975116) (xy 49.78322 -297.988808)
			(xy 49.827682 -298.009906) (xy 49.868185 -298.037862) (xy 49.903678 -298.071954) (xy 49.933243 -298.111298)
			(xy 49.956114 -298.154875) (xy 49.971698 -298.201556) (xy 49.979593 -298.250133) (xy 49.980088 -298.27474)
			(xy 50.31919 -298.27474) (xy 50.32315 -298.225686) (xy 50.334927 -298.177902) (xy 50.354218 -298.132626)
			(xy 50.380521 -298.09103) (xy 50.413156 -298.054193) (xy 50.451277 -298.023068) (xy 50.493898 -297.998461)
			(xy 50.539914 -297.981009) (xy 50.588133 -297.971165) (xy 50.637308 -297.969184) (xy 50.686163 -297.975116)
			(xy 50.733434 -297.988808) (xy 50.777896 -298.009906) (xy 50.818399 -298.037862) (xy 50.853892 -298.071954)
			(xy 50.883457 -298.111298) (xy 50.906328 -298.154875) (xy 50.921912 -298.201556) (xy 50.929807 -298.250133)
			(xy 50.930302 -298.27474) (xy 51.26915 -298.27474) (xy 51.27311 -298.225686) (xy 51.284887 -298.177902)
			(xy 51.304178 -298.132626) (xy 51.330481 -298.09103) (xy 51.363116 -298.054193) (xy 51.401237 -298.023068)
			(xy 51.443858 -297.998461) (xy 51.489874 -297.981009) (xy 51.538093 -297.971165) (xy 51.587268 -297.969184)
			(xy 51.636123 -297.975116) (xy 51.683394 -297.988808) (xy 51.727856 -298.009906) (xy 51.768359 -298.037862)
			(xy 51.803852 -298.071954) (xy 51.833417 -298.111298) (xy 51.856288 -298.154875) (xy 51.871872 -298.201556)
			(xy 51.879767 -298.250133) (xy 51.880262 -298.27474) (xy 52.21911 -298.27474) (xy 52.22307 -298.225686)
			(xy 52.234847 -298.177902) (xy 52.254138 -298.132626) (xy 52.280441 -298.09103) (xy 52.313076 -298.054193)
			(xy 52.351197 -298.023068) (xy 52.393818 -297.998461) (xy 52.439834 -297.981009) (xy 52.488053 -297.971165)
			(xy 52.537228 -297.969184) (xy 52.586083 -297.975116) (xy 52.633354 -297.988808) (xy 52.677816 -298.009906)
			(xy 52.718319 -298.037862) (xy 52.753812 -298.071954) (xy 52.783377 -298.111298) (xy 52.806248 -298.154875)
			(xy 52.821832 -298.201556) (xy 52.829727 -298.250133) (xy 52.830222 -298.27474) (xy 53.16907 -298.27474)
			(xy 53.17303 -298.225686) (xy 53.184807 -298.177902) (xy 53.204098 -298.132626) (xy 53.230401 -298.09103)
			(xy 53.263036 -298.054193) (xy 53.301157 -298.023068) (xy 53.343778 -297.998461) (xy 53.389794 -297.981009)
			(xy 53.438013 -297.971165) (xy 53.487188 -297.969184) (xy 53.536043 -297.975116) (xy 53.583314 -297.988808)
			(xy 53.627776 -298.009906) (xy 53.668279 -298.037862) (xy 53.703772 -298.071954) (xy 53.733337 -298.111298)
			(xy 53.756208 -298.154875) (xy 53.771792 -298.201556) (xy 53.779687 -298.250133) (xy 53.780182 -298.27474)
			(xy 54.11903 -298.27474) (xy 54.12299 -298.225686) (xy 54.134767 -298.177902) (xy 54.154058 -298.132626)
			(xy 54.180361 -298.09103) (xy 54.212996 -298.054193) (xy 54.251117 -298.023068) (xy 54.293738 -297.998461)
			(xy 54.339754 -297.981009) (xy 54.387973 -297.971165) (xy 54.437148 -297.969184) (xy 54.486003 -297.975116)
			(xy 54.533274 -297.988808) (xy 54.577736 -298.009906) (xy 54.618239 -298.037862) (xy 54.653732 -298.071954)
			(xy 54.683297 -298.111298) (xy 54.706168 -298.154875) (xy 54.721752 -298.201556) (xy 54.729647 -298.250133)
			(xy 54.730142 -298.27474) (xy 55.06899 -298.27474) (xy 55.07295 -298.225686) (xy 55.084727 -298.177902)
			(xy 55.104018 -298.132626) (xy 55.130321 -298.09103) (xy 55.162956 -298.054193) (xy 55.201077 -298.023068)
			(xy 55.243698 -297.998461) (xy 55.289714 -297.981009) (xy 55.337933 -297.971165) (xy 55.387108 -297.969184)
			(xy 55.435963 -297.975116) (xy 55.483234 -297.988808) (xy 55.527696 -298.009906) (xy 55.568199 -298.037862)
			(xy 55.603692 -298.071954) (xy 55.633257 -298.111298) (xy 55.656128 -298.154875) (xy 55.671712 -298.201556)
			(xy 55.679607 -298.250133) (xy 55.680102 -298.27474) (xy 56.01895 -298.27474) (xy 56.02291 -298.225686)
			(xy 56.034687 -298.177902) (xy 56.053978 -298.132626) (xy 56.080281 -298.09103) (xy 56.112916 -298.054193)
			(xy 56.151037 -298.023068) (xy 56.193658 -297.998461) (xy 56.239674 -297.981009) (xy 56.287893 -297.971165)
			(xy 56.337068 -297.969184) (xy 56.385923 -297.975116) (xy 56.433194 -297.988808) (xy 56.477656 -298.009906)
			(xy 56.518159 -298.037862) (xy 56.553652 -298.071954) (xy 56.583217 -298.111298) (xy 56.606088 -298.154875)
			(xy 56.621672 -298.201556) (xy 56.629567 -298.250133) (xy 56.630062 -298.27474) (xy 56.969164 -298.27474)
			(xy 56.973124 -298.225686) (xy 56.984901 -298.177902) (xy 57.004192 -298.132626) (xy 57.030495 -298.09103)
			(xy 57.06313 -298.054193) (xy 57.101251 -298.023068) (xy 57.143872 -297.998461) (xy 57.189888 -297.981009)
			(xy 57.238107 -297.971165) (xy 57.287282 -297.969184) (xy 57.336137 -297.975116) (xy 57.383408 -297.988808)
			(xy 57.42787 -298.009906) (xy 57.468373 -298.037862) (xy 57.503866 -298.071954) (xy 57.533431 -298.111298)
			(xy 57.556302 -298.154875) (xy 57.571886 -298.201556) (xy 57.579781 -298.250133) (xy 57.580276 -298.27474)
			(xy 57.919124 -298.27474) (xy 57.923084 -298.225686) (xy 57.934861 -298.177902) (xy 57.954152 -298.132626)
			(xy 57.980455 -298.09103) (xy 58.01309 -298.054193) (xy 58.051211 -298.023068) (xy 58.093832 -297.998461)
			(xy 58.139848 -297.981009) (xy 58.188067 -297.971165) (xy 58.237242 -297.969184) (xy 58.286097 -297.975116)
			(xy 58.333368 -297.988808) (xy 58.37783 -298.009906) (xy 58.418333 -298.037862) (xy 58.453826 -298.071954)
			(xy 58.483391 -298.111298) (xy 58.506262 -298.154875) (xy 58.521846 -298.201556) (xy 58.529741 -298.250133)
			(xy 58.530236 -298.27474) (xy 59.819044 -298.27474) (xy 59.823004 -298.225686) (xy 59.834781 -298.177902)
			(xy 59.854072 -298.132626) (xy 59.880375 -298.09103) (xy 59.91301 -298.054193) (xy 59.951131 -298.023068)
			(xy 59.993752 -297.998461) (xy 60.039768 -297.981009) (xy 60.087987 -297.971165) (xy 60.137162 -297.969184)
			(xy 60.186017 -297.975116) (xy 60.233288 -297.988808) (xy 60.27775 -298.009906) (xy 60.318253 -298.037862)
			(xy 60.353746 -298.071954) (xy 60.383311 -298.111298) (xy 60.406182 -298.154875) (xy 60.421766 -298.201556)
			(xy 60.429661 -298.250133) (xy 60.430156 -298.27474) (xy 60.769004 -298.27474) (xy 60.772964 -298.225686)
			(xy 60.784741 -298.177902) (xy 60.804032 -298.132626) (xy 60.830335 -298.09103) (xy 60.86297 -298.054193)
			(xy 60.901091 -298.023068) (xy 60.943712 -297.998461) (xy 60.989728 -297.981009) (xy 61.037947 -297.971165)
			(xy 61.087122 -297.969184) (xy 61.135977 -297.975116) (xy 61.183248 -297.988808) (xy 61.22771 -298.009906)
			(xy 61.268213 -298.037862) (xy 61.303706 -298.071954) (xy 61.333271 -298.111298) (xy 61.356142 -298.154875)
			(xy 61.371726 -298.201556) (xy 61.379621 -298.250133) (xy 61.380116 -298.27474) (xy 61.718964 -298.27474)
			(xy 61.722924 -298.225686) (xy 61.734701 -298.177902) (xy 61.753992 -298.132626) (xy 61.780295 -298.09103)
			(xy 61.81293 -298.054193) (xy 61.851051 -298.023068) (xy 61.893672 -297.998461) (xy 61.939688 -297.981009)
			(xy 61.987907 -297.971165) (xy 62.037082 -297.969184) (xy 62.085937 -297.975116) (xy 62.133208 -297.988808)
			(xy 62.17767 -298.009906) (xy 62.218173 -298.037862) (xy 62.253666 -298.071954) (xy 62.283231 -298.111298)
			(xy 62.306102 -298.154875) (xy 62.321686 -298.201556) (xy 62.329581 -298.250133) (xy 62.330076 -298.27474)
			(xy 62.669178 -298.27474) (xy 62.673138 -298.225686) (xy 62.684915 -298.177902) (xy 62.704206 -298.132626)
			(xy 62.730509 -298.09103) (xy 62.763144 -298.054193) (xy 62.801265 -298.023068) (xy 62.843886 -297.998461)
			(xy 62.889902 -297.981009) (xy 62.938121 -297.971165) (xy 62.987296 -297.969184) (xy 63.036151 -297.975116)
			(xy 63.083422 -297.988808) (xy 63.127884 -298.009906) (xy 63.168387 -298.037862) (xy 63.20388 -298.071954)
			(xy 63.233445 -298.111298) (xy 63.256316 -298.154875) (xy 63.2719 -298.201556) (xy 63.279795 -298.250133)
			(xy 63.28029 -298.27474) (xy 63.619138 -298.27474) (xy 63.623098 -298.225686) (xy 63.634875 -298.177902)
			(xy 63.654166 -298.132626) (xy 63.680469 -298.09103) (xy 63.713104 -298.054193) (xy 63.751225 -298.023068)
			(xy 63.793846 -297.998461) (xy 63.839862 -297.981009) (xy 63.888081 -297.971165) (xy 63.937256 -297.969184)
			(xy 63.986111 -297.975116) (xy 64.033382 -297.988808) (xy 64.077844 -298.009906) (xy 64.118347 -298.037862)
			(xy 64.15384 -298.071954) (xy 64.183405 -298.111298) (xy 64.206276 -298.154875) (xy 64.22186 -298.201556)
			(xy 64.229755 -298.250133) (xy 64.23025 -298.27474) (xy 64.569098 -298.27474) (xy 64.573058 -298.225686)
			(xy 64.584835 -298.177902) (xy 64.604126 -298.132626) (xy 64.630429 -298.09103) (xy 64.663064 -298.054193)
			(xy 64.701185 -298.023068) (xy 64.743806 -297.998461) (xy 64.789822 -297.981009) (xy 64.838041 -297.971165)
			(xy 64.887216 -297.969184) (xy 64.936071 -297.975116) (xy 64.983342 -297.988808) (xy 65.027804 -298.009906)
			(xy 65.068307 -298.037862) (xy 65.1038 -298.071954) (xy 65.133365 -298.111298) (xy 65.156236 -298.154875)
			(xy 65.17182 -298.201556) (xy 65.179715 -298.250133) (xy 65.18021 -298.27474) (xy 65.519058 -298.27474)
			(xy 65.523018 -298.225686) (xy 65.534795 -298.177902) (xy 65.554086 -298.132626) (xy 65.580389 -298.09103)
			(xy 65.613024 -298.054193) (xy 65.651145 -298.023068) (xy 65.693766 -297.998461) (xy 65.739782 -297.981009)
			(xy 65.788001 -297.971165) (xy 65.837176 -297.969184) (xy 65.886031 -297.975116) (xy 65.933302 -297.988808)
			(xy 65.977764 -298.009906) (xy 66.018267 -298.037862) (xy 66.05376 -298.071954) (xy 66.083325 -298.111298)
			(xy 66.106196 -298.154875) (xy 66.12178 -298.201556) (xy 66.129675 -298.250133) (xy 66.13017 -298.27474)
			(xy 66.469018 -298.27474) (xy 66.472978 -298.225686) (xy 66.484755 -298.177902) (xy 66.504046 -298.132626)
			(xy 66.530349 -298.09103) (xy 66.562984 -298.054193) (xy 66.601105 -298.023068) (xy 66.643726 -297.998461)
			(xy 66.689742 -297.981009) (xy 66.737961 -297.971165) (xy 66.787136 -297.969184) (xy 66.835991 -297.975116)
			(xy 66.883262 -297.988808) (xy 66.927724 -298.009906) (xy 66.968227 -298.037862) (xy 67.00372 -298.071954)
			(xy 67.033285 -298.111298) (xy 67.056156 -298.154875) (xy 67.07174 -298.201556) (xy 67.079635 -298.250133)
			(xy 67.08013 -298.27474) (xy 67.418978 -298.27474) (xy 67.422938 -298.225686) (xy 67.434715 -298.177902)
			(xy 67.454006 -298.132626) (xy 67.480309 -298.09103) (xy 67.512944 -298.054193) (xy 67.551065 -298.023068)
			(xy 67.593686 -297.998461) (xy 67.639702 -297.981009) (xy 67.687921 -297.971165) (xy 67.737096 -297.969184)
			(xy 67.785951 -297.975116) (xy 67.833222 -297.988808) (xy 67.877684 -298.009906) (xy 67.918187 -298.037862)
			(xy 67.95368 -298.071954) (xy 67.983245 -298.111298) (xy 68.006116 -298.154875) (xy 68.0217 -298.201556)
			(xy 68.029595 -298.250133) (xy 68.03009 -298.27474) (xy 68.368938 -298.27474) (xy 68.372898 -298.225686)
			(xy 68.384675 -298.177902) (xy 68.403966 -298.132626) (xy 68.430269 -298.09103) (xy 68.462904 -298.054193)
			(xy 68.501025 -298.023068) (xy 68.543646 -297.998461) (xy 68.589662 -297.981009) (xy 68.637881 -297.971165)
			(xy 68.687056 -297.969184) (xy 68.735911 -297.975116) (xy 68.783182 -297.988808) (xy 68.827644 -298.009906)
			(xy 68.868147 -298.037862) (xy 68.90364 -298.071954) (xy 68.933205 -298.111298) (xy 68.956076 -298.154875)
			(xy 68.97166 -298.201556) (xy 68.979555 -298.250133) (xy 68.98005 -298.27474) (xy 69.319152 -298.27474)
			(xy 69.323112 -298.225686) (xy 69.334889 -298.177902) (xy 69.35418 -298.132626) (xy 69.380483 -298.09103)
			(xy 69.413118 -298.054193) (xy 69.451239 -298.023068) (xy 69.49386 -297.998461) (xy 69.539876 -297.981009)
			(xy 69.588095 -297.971165) (xy 69.63727 -297.969184) (xy 69.686125 -297.975116) (xy 69.733396 -297.988808)
			(xy 69.777858 -298.009906) (xy 69.818361 -298.037862) (xy 69.853854 -298.071954) (xy 69.883419 -298.111298)
			(xy 69.90629 -298.154875) (xy 69.921874 -298.201556) (xy 69.929769 -298.250133) (xy 69.930264 -298.27474)
			(xy 70.269112 -298.27474) (xy 70.273072 -298.225686) (xy 70.284849 -298.177902) (xy 70.30414 -298.132626)
			(xy 70.330443 -298.09103) (xy 70.363078 -298.054193) (xy 70.401199 -298.023068) (xy 70.44382 -297.998461)
			(xy 70.489836 -297.981009) (xy 70.538055 -297.971165) (xy 70.58723 -297.969184) (xy 70.636085 -297.975116)
			(xy 70.683356 -297.988808) (xy 70.727818 -298.009906) (xy 70.768321 -298.037862) (xy 70.803814 -298.071954)
			(xy 70.833379 -298.111298) (xy 70.85625 -298.154875) (xy 70.871834 -298.201556) (xy 70.879729 -298.250133)
			(xy 70.880224 -298.27474) (xy 71.219072 -298.27474) (xy 71.223032 -298.225686) (xy 71.234809 -298.177902)
			(xy 71.2541 -298.132626) (xy 71.280403 -298.09103) (xy 71.313038 -298.054193) (xy 71.351159 -298.023068)
			(xy 71.39378 -297.998461) (xy 71.439796 -297.981009) (xy 71.488015 -297.971165) (xy 71.53719 -297.969184)
			(xy 71.586045 -297.975116) (xy 71.633316 -297.988808) (xy 71.677778 -298.009906) (xy 71.718281 -298.037862)
			(xy 71.753774 -298.071954) (xy 71.783339 -298.111298) (xy 71.80621 -298.154875) (xy 71.821794 -298.201556)
			(xy 71.829689 -298.250133) (xy 71.830184 -298.27474) (xy 73.118992 -298.27474) (xy 73.122952 -298.225686)
			(xy 73.134729 -298.177902) (xy 73.15402 -298.132626) (xy 73.180323 -298.09103) (xy 73.212958 -298.054193)
			(xy 73.251079 -298.023068) (xy 73.2937 -297.998461) (xy 73.339716 -297.981009) (xy 73.387935 -297.971165)
			(xy 73.43711 -297.969184) (xy 73.485965 -297.975116) (xy 73.533236 -297.988808) (xy 73.577698 -298.009906)
			(xy 73.618201 -298.037862) (xy 73.653694 -298.071954) (xy 73.683259 -298.111298) (xy 73.70613 -298.154875)
			(xy 73.721714 -298.201556) (xy 73.729609 -298.250133) (xy 73.730104 -298.27474) (xy 74.068952 -298.27474)
			(xy 74.072912 -298.225686) (xy 74.084689 -298.177902) (xy 74.10398 -298.132626) (xy 74.130283 -298.09103)
			(xy 74.162918 -298.054193) (xy 74.201039 -298.023068) (xy 74.24366 -297.998461) (xy 74.289676 -297.981009)
			(xy 74.337895 -297.971165) (xy 74.38707 -297.969184) (xy 74.435925 -297.975116) (xy 74.483196 -297.988808)
			(xy 74.527658 -298.009906) (xy 74.568161 -298.037862) (xy 74.603654 -298.071954) (xy 74.633219 -298.111298)
			(xy 74.65609 -298.154875) (xy 74.671674 -298.201556) (xy 74.679569 -298.250133) (xy 74.680064 -298.27474)
			(xy 75.019166 -298.27474) (xy 75.023126 -298.225686) (xy 75.034903 -298.177902) (xy 75.054194 -298.132626)
			(xy 75.080497 -298.09103) (xy 75.113132 -298.054193) (xy 75.151253 -298.023068) (xy 75.193874 -297.998461)
			(xy 75.23989 -297.981009) (xy 75.288109 -297.971165) (xy 75.337284 -297.969184) (xy 75.386139 -297.975116)
			(xy 75.43341 -297.988808) (xy 75.477872 -298.009906) (xy 75.518375 -298.037862) (xy 75.553868 -298.071954)
			(xy 75.583433 -298.111298) (xy 75.606304 -298.154875) (xy 75.621888 -298.201556) (xy 75.629783 -298.250133)
			(xy 75.630278 -298.27474) (xy 75.969126 -298.27474) (xy 75.973086 -298.225686) (xy 75.984863 -298.177902)
			(xy 76.004154 -298.132626) (xy 76.030457 -298.09103) (xy 76.063092 -298.054193) (xy 76.101213 -298.023068)
			(xy 76.143834 -297.998461) (xy 76.18985 -297.981009) (xy 76.238069 -297.971165) (xy 76.287244 -297.969184)
			(xy 76.336099 -297.975116) (xy 76.38337 -297.988808) (xy 76.427832 -298.009906) (xy 76.468335 -298.037862)
			(xy 76.503828 -298.071954) (xy 76.533393 -298.111298) (xy 76.556264 -298.154875) (xy 76.571848 -298.201556)
			(xy 76.579743 -298.250133) (xy 76.580238 -298.27474) (xy 76.919086 -298.27474) (xy 76.923046 -298.225686)
			(xy 76.934823 -298.177902) (xy 76.954114 -298.132626) (xy 76.980417 -298.09103) (xy 77.013052 -298.054193)
			(xy 77.051173 -298.023068) (xy 77.093794 -297.998461) (xy 77.13981 -297.981009) (xy 77.188029 -297.971165)
			(xy 77.237204 -297.969184) (xy 77.286059 -297.975116) (xy 77.33333 -297.988808) (xy 77.377792 -298.009906)
			(xy 77.418295 -298.037862) (xy 77.453788 -298.071954) (xy 77.483353 -298.111298) (xy 77.506224 -298.154875)
			(xy 77.521808 -298.201556) (xy 77.529703 -298.250133) (xy 77.530198 -298.27474) (xy 77.869046 -298.27474)
			(xy 77.873006 -298.225686) (xy 77.884783 -298.177902) (xy 77.904074 -298.132626) (xy 77.930377 -298.09103)
			(xy 77.963012 -298.054193) (xy 78.001133 -298.023068) (xy 78.043754 -297.998461) (xy 78.08977 -297.981009)
			(xy 78.137989 -297.971165) (xy 78.187164 -297.969184) (xy 78.236019 -297.975116) (xy 78.28329 -297.988808)
			(xy 78.327752 -298.009906) (xy 78.368255 -298.037862) (xy 78.403748 -298.071954) (xy 78.433313 -298.111298)
			(xy 78.456184 -298.154875) (xy 78.471768 -298.201556) (xy 78.479663 -298.250133) (xy 78.480158 -298.27474)
			(xy 78.819006 -298.27474) (xy 78.822966 -298.225686) (xy 78.834743 -298.177902) (xy 78.854034 -298.132626)
			(xy 78.880337 -298.09103) (xy 78.912972 -298.054193) (xy 78.951093 -298.023068) (xy 78.993714 -297.998461)
			(xy 79.03973 -297.981009) (xy 79.087949 -297.971165) (xy 79.137124 -297.969184) (xy 79.185979 -297.975116)
			(xy 79.23325 -297.988808) (xy 79.277712 -298.009906) (xy 79.318215 -298.037862) (xy 79.353708 -298.071954)
			(xy 79.383273 -298.111298) (xy 79.406144 -298.154875) (xy 79.421728 -298.201556) (xy 79.429623 -298.250133)
			(xy 79.430118 -298.27474) (xy 79.768966 -298.27474) (xy 79.772926 -298.225686) (xy 79.784703 -298.177902)
			(xy 79.803994 -298.132626) (xy 79.830297 -298.09103) (xy 79.862932 -298.054193) (xy 79.901053 -298.023068)
			(xy 79.943674 -297.998461) (xy 79.98969 -297.981009) (xy 80.037909 -297.971165) (xy 80.087084 -297.969184)
			(xy 80.135939 -297.975116) (xy 80.18321 -297.988808) (xy 80.227672 -298.009906) (xy 80.268175 -298.037862)
			(xy 80.303668 -298.071954) (xy 80.333233 -298.111298) (xy 80.356104 -298.154875) (xy 80.371688 -298.201556)
			(xy 80.379583 -298.250133) (xy 80.380078 -298.27474) (xy 80.71918 -298.27474) (xy 80.72314 -298.225686)
			(xy 80.734917 -298.177902) (xy 80.754208 -298.132626) (xy 80.780511 -298.09103) (xy 80.813146 -298.054193)
			(xy 80.851267 -298.023068) (xy 80.893888 -297.998461) (xy 80.939904 -297.981009) (xy 80.988123 -297.971165)
			(xy 81.037298 -297.969184) (xy 81.086153 -297.975116) (xy 81.133424 -297.988808) (xy 81.177886 -298.009906)
			(xy 81.218389 -298.037862) (xy 81.253882 -298.071954) (xy 81.283447 -298.111298) (xy 81.306318 -298.154875)
			(xy 81.321902 -298.201556) (xy 81.329797 -298.250133) (xy 81.330292 -298.27474) (xy 81.66914 -298.27474)
			(xy 81.6731 -298.225686) (xy 81.684877 -298.177902) (xy 81.704168 -298.132626) (xy 81.730471 -298.09103)
			(xy 81.763106 -298.054193) (xy 81.801227 -298.023068) (xy 81.843848 -297.998461) (xy 81.889864 -297.981009)
			(xy 81.938083 -297.971165) (xy 81.987258 -297.969184) (xy 82.036113 -297.975116) (xy 82.083384 -297.988808)
			(xy 82.127846 -298.009906) (xy 82.168349 -298.037862) (xy 82.203842 -298.071954) (xy 82.233407 -298.111298)
			(xy 82.256278 -298.154875) (xy 82.271862 -298.201556) (xy 82.279757 -298.250133) (xy 82.280252 -298.27474)
			(xy 82.6191 -298.27474) (xy 82.62306 -298.225686) (xy 82.634837 -298.177902) (xy 82.654128 -298.132626)
			(xy 82.680431 -298.09103) (xy 82.713066 -298.054193) (xy 82.751187 -298.023068) (xy 82.793808 -297.998461)
			(xy 82.839824 -297.981009) (xy 82.888043 -297.971165) (xy 82.937218 -297.969184) (xy 82.986073 -297.975116)
			(xy 83.033344 -297.988808) (xy 83.077806 -298.009906) (xy 83.118309 -298.037862) (xy 83.153802 -298.071954)
			(xy 83.183367 -298.111298) (xy 83.206238 -298.154875) (xy 83.221822 -298.201556) (xy 83.229717 -298.250133)
			(xy 83.230212 -298.27474) (xy 83.229717 -298.299347) (xy 83.221822 -298.347924) (xy 83.206238 -298.394605)
			(xy 83.183367 -298.438182) (xy 83.153802 -298.477526) (xy 83.118309 -298.511618) (xy 83.077806 -298.539574)
			(xy 83.033344 -298.560672) (xy 82.986073 -298.574364) (xy 82.937218 -298.580296) (xy 82.888043 -298.578315)
			(xy 82.839824 -298.568471) (xy 82.793808 -298.551019) (xy 82.751187 -298.526412) (xy 82.713066 -298.495287)
			(xy 82.680431 -298.45845) (xy 82.654128 -298.416854) (xy 82.634837 -298.371578) (xy 82.62306 -298.323794)
			(xy 82.6191 -298.27474) (xy 82.280252 -298.27474) (xy 82.279757 -298.299347) (xy 82.271862 -298.347924)
			(xy 82.256278 -298.394605) (xy 82.233407 -298.438182) (xy 82.203842 -298.477526) (xy 82.168349 -298.511618)
			(xy 82.127846 -298.539574) (xy 82.083384 -298.560672) (xy 82.036113 -298.574364) (xy 81.987258 -298.580296)
			(xy 81.938083 -298.578315) (xy 81.889864 -298.568471) (xy 81.843848 -298.551019) (xy 81.801227 -298.526412)
			(xy 81.763106 -298.495287) (xy 81.730471 -298.45845) (xy 81.704168 -298.416854) (xy 81.684877 -298.371578)
			(xy 81.6731 -298.323794) (xy 81.66914 -298.27474) (xy 81.330292 -298.27474) (xy 81.329797 -298.299347)
			(xy 81.321902 -298.347924) (xy 81.306318 -298.394605) (xy 81.283447 -298.438182) (xy 81.253882 -298.477526)
			(xy 81.218389 -298.511618) (xy 81.177886 -298.539574) (xy 81.133424 -298.560672) (xy 81.086153 -298.574364)
			(xy 81.037298 -298.580296) (xy 80.988123 -298.578315) (xy 80.939904 -298.568471) (xy 80.893888 -298.551019)
			(xy 80.851267 -298.526412) (xy 80.813146 -298.495287) (xy 80.780511 -298.45845) (xy 80.754208 -298.416854)
			(xy 80.734917 -298.371578) (xy 80.72314 -298.323794) (xy 80.71918 -298.27474) (xy 80.380078 -298.27474)
			(xy 80.379583 -298.299347) (xy 80.371688 -298.347924) (xy 80.356104 -298.394605) (xy 80.333233 -298.438182)
			(xy 80.303668 -298.477526) (xy 80.268175 -298.511618) (xy 80.227672 -298.539574) (xy 80.18321 -298.560672)
			(xy 80.135939 -298.574364) (xy 80.087084 -298.580296) (xy 80.037909 -298.578315) (xy 79.98969 -298.568471)
			(xy 79.943674 -298.551019) (xy 79.901053 -298.526412) (xy 79.862932 -298.495287) (xy 79.830297 -298.45845)
			(xy 79.803994 -298.416854) (xy 79.784703 -298.371578) (xy 79.772926 -298.323794) (xy 79.768966 -298.27474)
			(xy 79.430118 -298.27474) (xy 79.429623 -298.299347) (xy 79.421728 -298.347924) (xy 79.406144 -298.394605)
			(xy 79.383273 -298.438182) (xy 79.353708 -298.477526) (xy 79.318215 -298.511618) (xy 79.277712 -298.539574)
			(xy 79.23325 -298.560672) (xy 79.185979 -298.574364) (xy 79.137124 -298.580296) (xy 79.087949 -298.578315)
			(xy 79.03973 -298.568471) (xy 78.993714 -298.551019) (xy 78.951093 -298.526412) (xy 78.912972 -298.495287)
			(xy 78.880337 -298.45845) (xy 78.854034 -298.416854) (xy 78.834743 -298.371578) (xy 78.822966 -298.323794)
			(xy 78.819006 -298.27474) (xy 78.480158 -298.27474) (xy 78.479663 -298.299347) (xy 78.471768 -298.347924)
			(xy 78.456184 -298.394605) (xy 78.433313 -298.438182) (xy 78.403748 -298.477526) (xy 78.368255 -298.511618)
			(xy 78.327752 -298.539574) (xy 78.28329 -298.560672) (xy 78.236019 -298.574364) (xy 78.187164 -298.580296)
			(xy 78.137989 -298.578315) (xy 78.08977 -298.568471) (xy 78.043754 -298.551019) (xy 78.001133 -298.526412)
			(xy 77.963012 -298.495287) (xy 77.930377 -298.45845) (xy 77.904074 -298.416854) (xy 77.884783 -298.371578)
			(xy 77.873006 -298.323794) (xy 77.869046 -298.27474) (xy 77.530198 -298.27474) (xy 77.529703 -298.299347)
			(xy 77.521808 -298.347924) (xy 77.506224 -298.394605) (xy 77.483353 -298.438182) (xy 77.453788 -298.477526)
			(xy 77.418295 -298.511618) (xy 77.377792 -298.539574) (xy 77.33333 -298.560672) (xy 77.286059 -298.574364)
			(xy 77.237204 -298.580296) (xy 77.188029 -298.578315) (xy 77.13981 -298.568471) (xy 77.093794 -298.551019)
			(xy 77.051173 -298.526412) (xy 77.013052 -298.495287) (xy 76.980417 -298.45845) (xy 76.954114 -298.416854)
			(xy 76.934823 -298.371578) (xy 76.923046 -298.323794) (xy 76.919086 -298.27474) (xy 76.580238 -298.27474)
			(xy 76.579743 -298.299347) (xy 76.571848 -298.347924) (xy 76.556264 -298.394605) (xy 76.533393 -298.438182)
			(xy 76.503828 -298.477526) (xy 76.468335 -298.511618) (xy 76.427832 -298.539574) (xy 76.38337 -298.560672)
			(xy 76.336099 -298.574364) (xy 76.287244 -298.580296) (xy 76.238069 -298.578315) (xy 76.18985 -298.568471)
			(xy 76.143834 -298.551019) (xy 76.101213 -298.526412) (xy 76.063092 -298.495287) (xy 76.030457 -298.45845)
			(xy 76.004154 -298.416854) (xy 75.984863 -298.371578) (xy 75.973086 -298.323794) (xy 75.969126 -298.27474)
			(xy 75.630278 -298.27474) (xy 75.629783 -298.299347) (xy 75.621888 -298.347924) (xy 75.606304 -298.394605)
			(xy 75.583433 -298.438182) (xy 75.553868 -298.477526) (xy 75.518375 -298.511618) (xy 75.477872 -298.539574)
			(xy 75.43341 -298.560672) (xy 75.386139 -298.574364) (xy 75.337284 -298.580296) (xy 75.288109 -298.578315)
			(xy 75.23989 -298.568471) (xy 75.193874 -298.551019) (xy 75.151253 -298.526412) (xy 75.113132 -298.495287)
			(xy 75.080497 -298.45845) (xy 75.054194 -298.416854) (xy 75.034903 -298.371578) (xy 75.023126 -298.323794)
			(xy 75.019166 -298.27474) (xy 74.680064 -298.27474) (xy 74.679569 -298.299347) (xy 74.671674 -298.347924)
			(xy 74.65609 -298.394605) (xy 74.633219 -298.438182) (xy 74.603654 -298.477526) (xy 74.568161 -298.511618)
			(xy 74.527658 -298.539574) (xy 74.483196 -298.560672) (xy 74.435925 -298.574364) (xy 74.38707 -298.580296)
			(xy 74.337895 -298.578315) (xy 74.289676 -298.568471) (xy 74.24366 -298.551019) (xy 74.201039 -298.526412)
			(xy 74.162918 -298.495287) (xy 74.130283 -298.45845) (xy 74.10398 -298.416854) (xy 74.084689 -298.371578)
			(xy 74.072912 -298.323794) (xy 74.068952 -298.27474) (xy 73.730104 -298.27474) (xy 73.729609 -298.299347)
			(xy 73.721714 -298.347924) (xy 73.70613 -298.394605) (xy 73.683259 -298.438182) (xy 73.653694 -298.477526)
			(xy 73.618201 -298.511618) (xy 73.577698 -298.539574) (xy 73.533236 -298.560672) (xy 73.485965 -298.574364)
			(xy 73.43711 -298.580296) (xy 73.387935 -298.578315) (xy 73.339716 -298.568471) (xy 73.2937 -298.551019)
			(xy 73.251079 -298.526412) (xy 73.212958 -298.495287) (xy 73.180323 -298.45845) (xy 73.15402 -298.416854)
			(xy 73.134729 -298.371578) (xy 73.122952 -298.323794) (xy 73.118992 -298.27474) (xy 71.830184 -298.27474)
			(xy 71.829689 -298.299347) (xy 71.821794 -298.347924) (xy 71.80621 -298.394605) (xy 71.783339 -298.438182)
			(xy 71.753774 -298.477526) (xy 71.718281 -298.511618) (xy 71.677778 -298.539574) (xy 71.633316 -298.560672)
			(xy 71.586045 -298.574364) (xy 71.53719 -298.580296) (xy 71.488015 -298.578315) (xy 71.439796 -298.568471)
			(xy 71.39378 -298.551019) (xy 71.351159 -298.526412) (xy 71.313038 -298.495287) (xy 71.280403 -298.45845)
			(xy 71.2541 -298.416854) (xy 71.234809 -298.371578) (xy 71.223032 -298.323794) (xy 71.219072 -298.27474)
			(xy 70.880224 -298.27474) (xy 70.879729 -298.299347) (xy 70.871834 -298.347924) (xy 70.85625 -298.394605)
			(xy 70.833379 -298.438182) (xy 70.803814 -298.477526) (xy 70.768321 -298.511618) (xy 70.727818 -298.539574)
			(xy 70.683356 -298.560672) (xy 70.636085 -298.574364) (xy 70.58723 -298.580296) (xy 70.538055 -298.578315)
			(xy 70.489836 -298.568471) (xy 70.44382 -298.551019) (xy 70.401199 -298.526412) (xy 70.363078 -298.495287)
			(xy 70.330443 -298.45845) (xy 70.30414 -298.416854) (xy 70.284849 -298.371578) (xy 70.273072 -298.323794)
			(xy 70.269112 -298.27474) (xy 69.930264 -298.27474) (xy 69.929769 -298.299347) (xy 69.921874 -298.347924)
			(xy 69.90629 -298.394605) (xy 69.883419 -298.438182) (xy 69.853854 -298.477526) (xy 69.818361 -298.511618)
			(xy 69.777858 -298.539574) (xy 69.733396 -298.560672) (xy 69.686125 -298.574364) (xy 69.63727 -298.580296)
			(xy 69.588095 -298.578315) (xy 69.539876 -298.568471) (xy 69.49386 -298.551019) (xy 69.451239 -298.526412)
			(xy 69.413118 -298.495287) (xy 69.380483 -298.45845) (xy 69.35418 -298.416854) (xy 69.334889 -298.371578)
			(xy 69.323112 -298.323794) (xy 69.319152 -298.27474) (xy 68.98005 -298.27474) (xy 68.979555 -298.299347)
			(xy 68.97166 -298.347924) (xy 68.956076 -298.394605) (xy 68.933205 -298.438182) (xy 68.90364 -298.477526)
			(xy 68.868147 -298.511618) (xy 68.827644 -298.539574) (xy 68.783182 -298.560672) (xy 68.735911 -298.574364)
			(xy 68.687056 -298.580296) (xy 68.637881 -298.578315) (xy 68.589662 -298.568471) (xy 68.543646 -298.551019)
			(xy 68.501025 -298.526412) (xy 68.462904 -298.495287) (xy 68.430269 -298.45845) (xy 68.403966 -298.416854)
			(xy 68.384675 -298.371578) (xy 68.372898 -298.323794) (xy 68.368938 -298.27474) (xy 68.03009 -298.27474)
			(xy 68.029595 -298.299347) (xy 68.0217 -298.347924) (xy 68.006116 -298.394605) (xy 67.983245 -298.438182)
			(xy 67.95368 -298.477526) (xy 67.918187 -298.511618) (xy 67.877684 -298.539574) (xy 67.833222 -298.560672)
			(xy 67.785951 -298.574364) (xy 67.737096 -298.580296) (xy 67.687921 -298.578315) (xy 67.639702 -298.568471)
			(xy 67.593686 -298.551019) (xy 67.551065 -298.526412) (xy 67.512944 -298.495287) (xy 67.480309 -298.45845)
			(xy 67.454006 -298.416854) (xy 67.434715 -298.371578) (xy 67.422938 -298.323794) (xy 67.418978 -298.27474)
			(xy 67.08013 -298.27474) (xy 67.079635 -298.299347) (xy 67.07174 -298.347924) (xy 67.056156 -298.394605)
			(xy 67.033285 -298.438182) (xy 67.00372 -298.477526) (xy 66.968227 -298.511618) (xy 66.927724 -298.539574)
			(xy 66.883262 -298.560672) (xy 66.835991 -298.574364) (xy 66.787136 -298.580296) (xy 66.737961 -298.578315)
			(xy 66.689742 -298.568471) (xy 66.643726 -298.551019) (xy 66.601105 -298.526412) (xy 66.562984 -298.495287)
			(xy 66.530349 -298.45845) (xy 66.504046 -298.416854) (xy 66.484755 -298.371578) (xy 66.472978 -298.323794)
			(xy 66.469018 -298.27474) (xy 66.13017 -298.27474) (xy 66.129675 -298.299347) (xy 66.12178 -298.347924)
			(xy 66.106196 -298.394605) (xy 66.083325 -298.438182) (xy 66.05376 -298.477526) (xy 66.018267 -298.511618)
			(xy 65.977764 -298.539574) (xy 65.933302 -298.560672) (xy 65.886031 -298.574364) (xy 65.837176 -298.580296)
			(xy 65.788001 -298.578315) (xy 65.739782 -298.568471) (xy 65.693766 -298.551019) (xy 65.651145 -298.526412)
			(xy 65.613024 -298.495287) (xy 65.580389 -298.45845) (xy 65.554086 -298.416854) (xy 65.534795 -298.371578)
			(xy 65.523018 -298.323794) (xy 65.519058 -298.27474) (xy 65.18021 -298.27474) (xy 65.179715 -298.299347)
			(xy 65.17182 -298.347924) (xy 65.156236 -298.394605) (xy 65.133365 -298.438182) (xy 65.1038 -298.477526)
			(xy 65.068307 -298.511618) (xy 65.027804 -298.539574) (xy 64.983342 -298.560672) (xy 64.936071 -298.574364)
			(xy 64.887216 -298.580296) (xy 64.838041 -298.578315) (xy 64.789822 -298.568471) (xy 64.743806 -298.551019)
			(xy 64.701185 -298.526412) (xy 64.663064 -298.495287) (xy 64.630429 -298.45845) (xy 64.604126 -298.416854)
			(xy 64.584835 -298.371578) (xy 64.573058 -298.323794) (xy 64.569098 -298.27474) (xy 64.23025 -298.27474)
			(xy 64.229755 -298.299347) (xy 64.22186 -298.347924) (xy 64.206276 -298.394605) (xy 64.183405 -298.438182)
			(xy 64.15384 -298.477526) (xy 64.118347 -298.511618) (xy 64.077844 -298.539574) (xy 64.033382 -298.560672)
			(xy 63.986111 -298.574364) (xy 63.937256 -298.580296) (xy 63.888081 -298.578315) (xy 63.839862 -298.568471)
			(xy 63.793846 -298.551019) (xy 63.751225 -298.526412) (xy 63.713104 -298.495287) (xy 63.680469 -298.45845)
			(xy 63.654166 -298.416854) (xy 63.634875 -298.371578) (xy 63.623098 -298.323794) (xy 63.619138 -298.27474)
			(xy 63.28029 -298.27474) (xy 63.279795 -298.299347) (xy 63.2719 -298.347924) (xy 63.256316 -298.394605)
			(xy 63.233445 -298.438182) (xy 63.20388 -298.477526) (xy 63.168387 -298.511618) (xy 63.127884 -298.539574)
			(xy 63.083422 -298.560672) (xy 63.036151 -298.574364) (xy 62.987296 -298.580296) (xy 62.938121 -298.578315)
			(xy 62.889902 -298.568471) (xy 62.843886 -298.551019) (xy 62.801265 -298.526412) (xy 62.763144 -298.495287)
			(xy 62.730509 -298.45845) (xy 62.704206 -298.416854) (xy 62.684915 -298.371578) (xy 62.673138 -298.323794)
			(xy 62.669178 -298.27474) (xy 62.330076 -298.27474) (xy 62.329581 -298.299347) (xy 62.321686 -298.347924)
			(xy 62.306102 -298.394605) (xy 62.283231 -298.438182) (xy 62.253666 -298.477526) (xy 62.218173 -298.511618)
			(xy 62.17767 -298.539574) (xy 62.133208 -298.560672) (xy 62.085937 -298.574364) (xy 62.037082 -298.580296)
			(xy 61.987907 -298.578315) (xy 61.939688 -298.568471) (xy 61.893672 -298.551019) (xy 61.851051 -298.526412)
			(xy 61.81293 -298.495287) (xy 61.780295 -298.45845) (xy 61.753992 -298.416854) (xy 61.734701 -298.371578)
			(xy 61.722924 -298.323794) (xy 61.718964 -298.27474) (xy 61.380116 -298.27474) (xy 61.379621 -298.299347)
			(xy 61.371726 -298.347924) (xy 61.356142 -298.394605) (xy 61.333271 -298.438182) (xy 61.303706 -298.477526)
			(xy 61.268213 -298.511618) (xy 61.22771 -298.539574) (xy 61.183248 -298.560672) (xy 61.135977 -298.574364)
			(xy 61.087122 -298.580296) (xy 61.037947 -298.578315) (xy 60.989728 -298.568471) (xy 60.943712 -298.551019)
			(xy 60.901091 -298.526412) (xy 60.86297 -298.495287) (xy 60.830335 -298.45845) (xy 60.804032 -298.416854)
			(xy 60.784741 -298.371578) (xy 60.772964 -298.323794) (xy 60.769004 -298.27474) (xy 60.430156 -298.27474)
			(xy 60.429661 -298.299347) (xy 60.421766 -298.347924) (xy 60.406182 -298.394605) (xy 60.383311 -298.438182)
			(xy 60.353746 -298.477526) (xy 60.318253 -298.511618) (xy 60.27775 -298.539574) (xy 60.233288 -298.560672)
			(xy 60.186017 -298.574364) (xy 60.137162 -298.580296) (xy 60.087987 -298.578315) (xy 60.039768 -298.568471)
			(xy 59.993752 -298.551019) (xy 59.951131 -298.526412) (xy 59.91301 -298.495287) (xy 59.880375 -298.45845)
			(xy 59.854072 -298.416854) (xy 59.834781 -298.371578) (xy 59.823004 -298.323794) (xy 59.819044 -298.27474)
			(xy 58.530236 -298.27474) (xy 58.529741 -298.299347) (xy 58.521846 -298.347924) (xy 58.506262 -298.394605)
			(xy 58.483391 -298.438182) (xy 58.453826 -298.477526) (xy 58.418333 -298.511618) (xy 58.37783 -298.539574)
			(xy 58.333368 -298.560672) (xy 58.286097 -298.574364) (xy 58.237242 -298.580296) (xy 58.188067 -298.578315)
			(xy 58.139848 -298.568471) (xy 58.093832 -298.551019) (xy 58.051211 -298.526412) (xy 58.01309 -298.495287)
			(xy 57.980455 -298.45845) (xy 57.954152 -298.416854) (xy 57.934861 -298.371578) (xy 57.923084 -298.323794)
			(xy 57.919124 -298.27474) (xy 57.580276 -298.27474) (xy 57.579781 -298.299347) (xy 57.571886 -298.347924)
			(xy 57.556302 -298.394605) (xy 57.533431 -298.438182) (xy 57.503866 -298.477526) (xy 57.468373 -298.511618)
			(xy 57.42787 -298.539574) (xy 57.383408 -298.560672) (xy 57.336137 -298.574364) (xy 57.287282 -298.580296)
			(xy 57.238107 -298.578315) (xy 57.189888 -298.568471) (xy 57.143872 -298.551019) (xy 57.101251 -298.526412)
			(xy 57.06313 -298.495287) (xy 57.030495 -298.45845) (xy 57.004192 -298.416854) (xy 56.984901 -298.371578)
			(xy 56.973124 -298.323794) (xy 56.969164 -298.27474) (xy 56.630062 -298.27474) (xy 56.629567 -298.299347)
			(xy 56.621672 -298.347924) (xy 56.606088 -298.394605) (xy 56.583217 -298.438182) (xy 56.553652 -298.477526)
			(xy 56.518159 -298.511618) (xy 56.477656 -298.539574) (xy 56.433194 -298.560672) (xy 56.385923 -298.574364)
			(xy 56.337068 -298.580296) (xy 56.287893 -298.578315) (xy 56.239674 -298.568471) (xy 56.193658 -298.551019)
			(xy 56.151037 -298.526412) (xy 56.112916 -298.495287) (xy 56.080281 -298.45845) (xy 56.053978 -298.416854)
			(xy 56.034687 -298.371578) (xy 56.02291 -298.323794) (xy 56.01895 -298.27474) (xy 55.680102 -298.27474)
			(xy 55.679607 -298.299347) (xy 55.671712 -298.347924) (xy 55.656128 -298.394605) (xy 55.633257 -298.438182)
			(xy 55.603692 -298.477526) (xy 55.568199 -298.511618) (xy 55.527696 -298.539574) (xy 55.483234 -298.560672)
			(xy 55.435963 -298.574364) (xy 55.387108 -298.580296) (xy 55.337933 -298.578315) (xy 55.289714 -298.568471)
			(xy 55.243698 -298.551019) (xy 55.201077 -298.526412) (xy 55.162956 -298.495287) (xy 55.130321 -298.45845)
			(xy 55.104018 -298.416854) (xy 55.084727 -298.371578) (xy 55.07295 -298.323794) (xy 55.06899 -298.27474)
			(xy 54.730142 -298.27474) (xy 54.729647 -298.299347) (xy 54.721752 -298.347924) (xy 54.706168 -298.394605)
			(xy 54.683297 -298.438182) (xy 54.653732 -298.477526) (xy 54.618239 -298.511618) (xy 54.577736 -298.539574)
			(xy 54.533274 -298.560672) (xy 54.486003 -298.574364) (xy 54.437148 -298.580296) (xy 54.387973 -298.578315)
			(xy 54.339754 -298.568471) (xy 54.293738 -298.551019) (xy 54.251117 -298.526412) (xy 54.212996 -298.495287)
			(xy 54.180361 -298.45845) (xy 54.154058 -298.416854) (xy 54.134767 -298.371578) (xy 54.12299 -298.323794)
			(xy 54.11903 -298.27474) (xy 53.780182 -298.27474) (xy 53.779687 -298.299347) (xy 53.771792 -298.347924)
			(xy 53.756208 -298.394605) (xy 53.733337 -298.438182) (xy 53.703772 -298.477526) (xy 53.668279 -298.511618)
			(xy 53.627776 -298.539574) (xy 53.583314 -298.560672) (xy 53.536043 -298.574364) (xy 53.487188 -298.580296)
			(xy 53.438013 -298.578315) (xy 53.389794 -298.568471) (xy 53.343778 -298.551019) (xy 53.301157 -298.526412)
			(xy 53.263036 -298.495287) (xy 53.230401 -298.45845) (xy 53.204098 -298.416854) (xy 53.184807 -298.371578)
			(xy 53.17303 -298.323794) (xy 53.16907 -298.27474) (xy 52.830222 -298.27474) (xy 52.829727 -298.299347)
			(xy 52.821832 -298.347924) (xy 52.806248 -298.394605) (xy 52.783377 -298.438182) (xy 52.753812 -298.477526)
			(xy 52.718319 -298.511618) (xy 52.677816 -298.539574) (xy 52.633354 -298.560672) (xy 52.586083 -298.574364)
			(xy 52.537228 -298.580296) (xy 52.488053 -298.578315) (xy 52.439834 -298.568471) (xy 52.393818 -298.551019)
			(xy 52.351197 -298.526412) (xy 52.313076 -298.495287) (xy 52.280441 -298.45845) (xy 52.254138 -298.416854)
			(xy 52.234847 -298.371578) (xy 52.22307 -298.323794) (xy 52.21911 -298.27474) (xy 51.880262 -298.27474)
			(xy 51.879767 -298.299347) (xy 51.871872 -298.347924) (xy 51.856288 -298.394605) (xy 51.833417 -298.438182)
			(xy 51.803852 -298.477526) (xy 51.768359 -298.511618) (xy 51.727856 -298.539574) (xy 51.683394 -298.560672)
			(xy 51.636123 -298.574364) (xy 51.587268 -298.580296) (xy 51.538093 -298.578315) (xy 51.489874 -298.568471)
			(xy 51.443858 -298.551019) (xy 51.401237 -298.526412) (xy 51.363116 -298.495287) (xy 51.330481 -298.45845)
			(xy 51.304178 -298.416854) (xy 51.284887 -298.371578) (xy 51.27311 -298.323794) (xy 51.26915 -298.27474)
			(xy 50.930302 -298.27474) (xy 50.929807 -298.299347) (xy 50.921912 -298.347924) (xy 50.906328 -298.394605)
			(xy 50.883457 -298.438182) (xy 50.853892 -298.477526) (xy 50.818399 -298.511618) (xy 50.777896 -298.539574)
			(xy 50.733434 -298.560672) (xy 50.686163 -298.574364) (xy 50.637308 -298.580296) (xy 50.588133 -298.578315)
			(xy 50.539914 -298.568471) (xy 50.493898 -298.551019) (xy 50.451277 -298.526412) (xy 50.413156 -298.495287)
			(xy 50.380521 -298.45845) (xy 50.354218 -298.416854) (xy 50.334927 -298.371578) (xy 50.32315 -298.323794)
			(xy 50.31919 -298.27474) (xy 49.980088 -298.27474) (xy 49.979593 -298.299347) (xy 49.971698 -298.347924)
			(xy 49.956114 -298.394605) (xy 49.933243 -298.438182) (xy 49.903678 -298.477526) (xy 49.868185 -298.511618)
			(xy 49.827682 -298.539574) (xy 49.78322 -298.560672) (xy 49.735949 -298.574364) (xy 49.687094 -298.580296)
			(xy 49.637919 -298.578315) (xy 49.5897 -298.568471) (xy 49.543684 -298.551019) (xy 49.501063 -298.526412)
			(xy 49.462942 -298.495287) (xy 49.430307 -298.45845) (xy 49.404004 -298.416854) (xy 49.384713 -298.371578)
			(xy 49.372936 -298.323794) (xy 49.368976 -298.27474) (xy 49.030128 -298.27474) (xy 49.029633 -298.299347)
			(xy 49.021738 -298.347924) (xy 49.006154 -298.394605) (xy 48.983283 -298.438182) (xy 48.953718 -298.477526)
			(xy 48.918225 -298.511618) (xy 48.877722 -298.539574) (xy 48.83326 -298.560672) (xy 48.785989 -298.574364)
			(xy 48.737134 -298.580296) (xy 48.687959 -298.578315) (xy 48.63974 -298.568471) (xy 48.593724 -298.551019)
			(xy 48.551103 -298.526412) (xy 48.512982 -298.495287) (xy 48.480347 -298.45845) (xy 48.454044 -298.416854)
			(xy 48.434753 -298.371578) (xy 48.422976 -298.323794) (xy 48.419016 -298.27474) (xy 48.080168 -298.27474)
			(xy 48.079673 -298.299347) (xy 48.071778 -298.347924) (xy 48.056194 -298.394605) (xy 48.033323 -298.438182)
			(xy 48.003758 -298.477526) (xy 47.968265 -298.511618) (xy 47.927762 -298.539574) (xy 47.8833 -298.560672)
			(xy 47.836029 -298.574364) (xy 47.787174 -298.580296) (xy 47.737999 -298.578315) (xy 47.68978 -298.568471)
			(xy 47.643764 -298.551019) (xy 47.601143 -298.526412) (xy 47.563022 -298.495287) (xy 47.530387 -298.45845)
			(xy 47.504084 -298.416854) (xy 47.484793 -298.371578) (xy 47.473016 -298.323794) (xy 47.469056 -298.27474)
			(xy 46.7559 -298.27474) (xy 46.753125 -298.292417) (xy 46.736644 -298.344144) (xy 46.711484 -298.39225)
			(xy 46.6784 -298.435293) (xy 46.658784 -298.454064) (xy 46.63694 -298.47413) (xy 46.619534 -298.489619)
			(xy 46.58098 -298.515781) (xy 46.538981 -298.535954) (xy 46.494461 -298.549696) (xy 46.448399 -298.556704)
			(xy 46.425104 -298.557188) (xy 46.274736 -298.557188) (xy 46.247057 -298.556567) (xy 46.192573 -298.54675)
			(xy 46.140658 -298.527522) (xy 46.116494 -298.514008) (xy 46.107587 -298.50941) (xy 46.087735 -298.506776)
			(xy 46.068374 -298.511895) (xy 46.060106 -298.517564) (xy 46.040022 -298.532263) (xy 45.99608 -298.555623)
			(xy 45.948931 -298.571549) (xy 45.899823 -298.579619) (xy 45.850057 -298.579619) (xy 45.800949 -298.571549)
			(xy 45.7538 -298.555623) (xy 45.709858 -298.532263) (xy 45.689774 -298.517564) (xy 45.681536 -298.511816)
			(xy 45.66215 -298.50663) (xy 45.642263 -298.509312) (xy 45.633386 -298.514008) (xy 45.609214 -298.527506)
			(xy 45.557303 -298.546736) (xy 45.502822 -298.556551) (xy 45.475144 -298.557188) (xy 45.324776 -298.557188)
			(xy 45.297097 -298.55655) (xy 45.242614 -298.546741) (xy 45.190699 -298.527519) (xy 45.166534 -298.514008)
			(xy 45.157612 -298.509445) (xy 45.13777 -298.506799) (xy 45.118414 -298.511903) (xy 45.110146 -298.517564)
			(xy 45.090062 -298.532263) (xy 45.04612 -298.555623) (xy 44.998971 -298.571549) (xy 44.949863 -298.579619)
			(xy 44.900097 -298.579619) (xy 44.850989 -298.571549) (xy 44.80384 -298.555623) (xy 44.759898 -298.532263)
			(xy 44.739814 -298.517564) (xy 44.731606 -298.511767) (xy 44.712202 -298.506596) (xy 44.692304 -298.5093)
			(xy 44.683426 -298.514008) (xy 44.659265 -298.527529) (xy 44.607349 -298.54675) (xy 44.552863 -298.556556)
			(xy 44.525184 -298.557188) (xy 44.374562 -298.557188) (xy 44.346883 -298.556556) (xy 44.2924 -298.546744)
			(xy 44.240485 -298.52752) (xy 44.21632 -298.514008) (xy 44.207403 -298.509433) (xy 44.187558 -298.506791)
			(xy 44.1682 -298.511901) (xy 44.159932 -298.517564) (xy 44.139848 -298.532263) (xy 44.095906 -298.555623)
			(xy 44.048757 -298.571549) (xy 43.999649 -298.579619) (xy 43.949883 -298.579619) (xy 43.900775 -298.571549)
			(xy 43.853626 -298.555623) (xy 43.809684 -298.532263) (xy 43.7896 -298.517564) (xy 43.781399 -298.511756)
			(xy 43.761991 -298.506588) (xy 43.742091 -298.509297) (xy 43.733212 -298.514008) (xy 43.709054 -298.527534)
			(xy 43.657136 -298.546754) (xy 43.60265 -298.556558) (xy 43.57497 -298.557188) (xy 42.474642 -298.557188)
			(xy 42.446963 -298.556564) (xy 42.392479 -298.546749) (xy 42.340565 -298.527522) (xy 42.3164 -298.514008)
			(xy 42.307491 -298.509415) (xy 42.28764 -298.50678) (xy 42.26828 -298.511896) (xy 42.260012 -298.517564)
			(xy 42.239928 -298.532263) (xy 42.195986 -298.555623) (xy 42.148837 -298.571549) (xy 42.099729 -298.579619)
			(xy 42.049963 -298.579619) (xy 42.000855 -298.571549) (xy 41.953706 -298.555623) (xy 41.909764 -298.532263)
			(xy 41.88968 -298.517564) (xy 41.881489 -298.511739) (xy 41.862075 -298.506577) (xy 41.842171 -298.509293)
			(xy 41.833292 -298.514008) (xy 41.809138 -298.527541) (xy 41.757218 -298.546759) (xy 41.70273 -298.556559)
			(xy 41.67505 -298.557188) (xy 41.524682 -298.557188) (xy 41.497004 -298.556548) (xy 41.44252 -298.546739)
			(xy 41.390605 -298.527519) (xy 41.36644 -298.514008) (xy 41.357516 -298.50945) (xy 41.337675 -298.506802)
			(xy 41.31832 -298.511904) (xy 41.310052 -298.517564) (xy 41.289971 -298.532262) (xy 41.246021 -298.555596)
			(xy 41.19887 -298.571502) (xy 41.149766 -298.579561) (xy 41.124886 -298.580048) (xy 41.115845 -298.57995)
			(xy 41.097799 -298.578804) (xy 41.088818 -298.577762) (xy 41.07688 -298.576238) (xy 41.054528 -298.584366)
			(xy 40.981376 -298.660566) (xy 40.974264 -298.683426) (xy 40.976296 -298.695364) (xy 40.978415 -298.708854)
			(xy 40.980705 -298.736066) (xy 40.980868 -298.74972) (xy 40.980723 -298.763438) (xy 40.978434 -298.790779)
			(xy 40.976296 -298.80433) (xy 40.974264 -298.816268) (xy 40.981376 -298.839128) (xy 41.054528 -298.915328)
			(xy 41.07688 -298.923456) (xy 41.088818 -298.921932) (xy 41.0978 -298.920897) (xy 41.115845 -298.919751)
			(xy 41.124886 -298.919646) (xy 41.149709 -298.920163) (xy 41.198701 -298.928193) (xy 41.245749 -298.944043)
			(xy 41.289613 -298.967297) (xy 41.329136 -298.997341) (xy 41.363278 -299.033383) (xy 41.391139 -299.074474)
			(xy 41.411985 -299.119532) (xy 41.425266 -299.167368) (xy 41.430633 -299.216724) (xy 41.4302 -299.2247)
			(xy 41.769042 -299.2247) (xy 41.773002 -299.175646) (xy 41.784779 -299.127862) (xy 41.80407 -299.082586)
			(xy 41.830373 -299.04099) (xy 41.863008 -299.004153) (xy 41.901129 -298.973028) (xy 41.94375 -298.948421)
			(xy 41.989766 -298.930969) (xy 42.037985 -298.921125) (xy 42.08716 -298.919144) (xy 42.136015 -298.925076)
			(xy 42.183286 -298.938768) (xy 42.227748 -298.959866) (xy 42.268251 -298.987822) (xy 42.303744 -299.021914)
			(xy 42.333309 -299.061258) (xy 42.35618 -299.104835) (xy 42.371764 -299.151516) (xy 42.379659 -299.200093)
			(xy 42.380154 -299.2247) (xy 42.380149 -299.224954) (xy 43.668962 -299.224954) (xy 43.672922 -299.1759)
			(xy 43.684699 -299.128116) (xy 43.70399 -299.08284) (xy 43.730293 -299.041244) (xy 43.762928 -299.004407)
			(xy 43.801049 -298.973282) (xy 43.84367 -298.948675) (xy 43.889686 -298.931223) (xy 43.937905 -298.921379)
			(xy 43.98708 -298.919398) (xy 44.035935 -298.92533) (xy 44.083206 -298.939022) (xy 44.127668 -298.96012)
			(xy 44.168171 -298.988076) (xy 44.203664 -299.022168) (xy 44.233229 -299.061512) (xy 44.2561 -299.105089)
			(xy 44.271684 -299.15177) (xy 44.279579 -299.200347) (xy 44.280074 -299.224954) (xy 44.619176 -299.224954)
			(xy 44.623136 -299.1759) (xy 44.634913 -299.128116) (xy 44.654204 -299.08284) (xy 44.680507 -299.041244)
			(xy 44.713142 -299.004407) (xy 44.751263 -298.973282) (xy 44.793884 -298.948675) (xy 44.8399 -298.931223)
			(xy 44.888119 -298.921379) (xy 44.937294 -298.919398) (xy 44.986149 -298.92533) (xy 45.03342 -298.939022)
			(xy 45.077882 -298.96012) (xy 45.118385 -298.988076) (xy 45.153878 -299.022168) (xy 45.183443 -299.061512)
			(xy 45.206314 -299.105089) (xy 45.221898 -299.15177) (xy 45.229793 -299.200347) (xy 45.230288 -299.224954)
			(xy 45.569136 -299.224954) (xy 45.573096 -299.1759) (xy 45.584873 -299.128116) (xy 45.604164 -299.08284)
			(xy 45.630467 -299.041244) (xy 45.663102 -299.004407) (xy 45.701223 -298.973282) (xy 45.743844 -298.948675)
			(xy 45.78986 -298.931223) (xy 45.838079 -298.921379) (xy 45.887254 -298.919398) (xy 45.936109 -298.92533)
			(xy 45.98338 -298.939022) (xy 46.027842 -298.96012) (xy 46.068345 -298.988076) (xy 46.103838 -299.022168)
			(xy 46.133403 -299.061512) (xy 46.156274 -299.105089) (xy 46.171858 -299.15177) (xy 46.179753 -299.200347)
			(xy 46.180248 -299.224954) (xy 46.519096 -299.224954) (xy 46.523056 -299.1759) (xy 46.534833 -299.128116)
			(xy 46.554124 -299.08284) (xy 46.580427 -299.041244) (xy 46.613062 -299.004407) (xy 46.651183 -298.973282)
			(xy 46.693804 -298.948675) (xy 46.73982 -298.931223) (xy 46.788039 -298.921379) (xy 46.837214 -298.919398)
			(xy 46.886069 -298.92533) (xy 46.93334 -298.939022) (xy 46.977802 -298.96012) (xy 47.018305 -298.988076)
			(xy 47.053798 -299.022168) (xy 47.083363 -299.061512) (xy 47.106234 -299.105089) (xy 47.121818 -299.15177)
			(xy 47.129713 -299.200347) (xy 47.130208 -299.224954) (xy 47.469056 -299.224954) (xy 47.473016 -299.1759)
			(xy 47.484793 -299.128116) (xy 47.504084 -299.08284) (xy 47.530387 -299.041244) (xy 47.563022 -299.004407)
			(xy 47.601143 -298.973282) (xy 47.643764 -298.948675) (xy 47.68978 -298.931223) (xy 47.737999 -298.921379)
			(xy 47.787174 -298.919398) (xy 47.836029 -298.92533) (xy 47.8833 -298.939022) (xy 47.927762 -298.96012)
			(xy 47.968265 -298.988076) (xy 48.003758 -299.022168) (xy 48.033323 -299.061512) (xy 48.056194 -299.105089)
			(xy 48.071778 -299.15177) (xy 48.079673 -299.200347) (xy 48.080168 -299.224954) (xy 48.419016 -299.224954)
			(xy 48.422976 -299.1759) (xy 48.434753 -299.128116) (xy 48.454044 -299.08284) (xy 48.480347 -299.041244)
			(xy 48.512982 -299.004407) (xy 48.551103 -298.973282) (xy 48.593724 -298.948675) (xy 48.63974 -298.931223)
			(xy 48.687959 -298.921379) (xy 48.737134 -298.919398) (xy 48.785989 -298.92533) (xy 48.83326 -298.939022)
			(xy 48.877722 -298.96012) (xy 48.918225 -298.988076) (xy 48.953718 -299.022168) (xy 48.983283 -299.061512)
			(xy 49.006154 -299.105089) (xy 49.021738 -299.15177) (xy 49.029633 -299.200347) (xy 49.030128 -299.224954)
			(xy 49.368976 -299.224954) (xy 49.372936 -299.1759) (xy 49.384713 -299.128116) (xy 49.404004 -299.08284)
			(xy 49.430307 -299.041244) (xy 49.462942 -299.004407) (xy 49.501063 -298.973282) (xy 49.543684 -298.948675)
			(xy 49.5897 -298.931223) (xy 49.637919 -298.921379) (xy 49.687094 -298.919398) (xy 49.735949 -298.92533)
			(xy 49.78322 -298.939022) (xy 49.827682 -298.96012) (xy 49.868185 -298.988076) (xy 49.903678 -299.022168)
			(xy 49.933243 -299.061512) (xy 49.956114 -299.105089) (xy 49.971698 -299.15177) (xy 49.979593 -299.200347)
			(xy 49.980088 -299.224954) (xy 50.31919 -299.224954) (xy 50.32315 -299.1759) (xy 50.334927 -299.128116)
			(xy 50.354218 -299.08284) (xy 50.380521 -299.041244) (xy 50.413156 -299.004407) (xy 50.451277 -298.973282)
			(xy 50.493898 -298.948675) (xy 50.539914 -298.931223) (xy 50.588133 -298.921379) (xy 50.637308 -298.919398)
			(xy 50.686163 -298.92533) (xy 50.733434 -298.939022) (xy 50.777896 -298.96012) (xy 50.818399 -298.988076)
			(xy 50.853892 -299.022168) (xy 50.883457 -299.061512) (xy 50.906328 -299.105089) (xy 50.921912 -299.15177)
			(xy 50.929807 -299.200347) (xy 50.930302 -299.224954) (xy 51.26915 -299.224954) (xy 51.27311 -299.1759)
			(xy 51.284887 -299.128116) (xy 51.304178 -299.08284) (xy 51.330481 -299.041244) (xy 51.363116 -299.004407)
			(xy 51.401237 -298.973282) (xy 51.443858 -298.948675) (xy 51.489874 -298.931223) (xy 51.538093 -298.921379)
			(xy 51.587268 -298.919398) (xy 51.636123 -298.92533) (xy 51.683394 -298.939022) (xy 51.727856 -298.96012)
			(xy 51.768359 -298.988076) (xy 51.803852 -299.022168) (xy 51.833417 -299.061512) (xy 51.856288 -299.105089)
			(xy 51.871872 -299.15177) (xy 51.879767 -299.200347) (xy 51.880262 -299.224954) (xy 52.21911 -299.224954)
			(xy 52.22307 -299.1759) (xy 52.234847 -299.128116) (xy 52.254138 -299.08284) (xy 52.280441 -299.041244)
			(xy 52.313076 -299.004407) (xy 52.351197 -298.973282) (xy 52.393818 -298.948675) (xy 52.439834 -298.931223)
			(xy 52.488053 -298.921379) (xy 52.537228 -298.919398) (xy 52.586083 -298.92533) (xy 52.633354 -298.939022)
			(xy 52.677816 -298.96012) (xy 52.718319 -298.988076) (xy 52.753812 -299.022168) (xy 52.783377 -299.061512)
			(xy 52.806248 -299.105089) (xy 52.821832 -299.15177) (xy 52.829727 -299.200347) (xy 52.830222 -299.224954)
			(xy 53.16907 -299.224954) (xy 53.17303 -299.1759) (xy 53.184807 -299.128116) (xy 53.204098 -299.08284)
			(xy 53.230401 -299.041244) (xy 53.263036 -299.004407) (xy 53.301157 -298.973282) (xy 53.343778 -298.948675)
			(xy 53.389794 -298.931223) (xy 53.438013 -298.921379) (xy 53.487188 -298.919398) (xy 53.536043 -298.92533)
			(xy 53.583314 -298.939022) (xy 53.627776 -298.96012) (xy 53.668279 -298.988076) (xy 53.703772 -299.022168)
			(xy 53.733337 -299.061512) (xy 53.756208 -299.105089) (xy 53.771792 -299.15177) (xy 53.779687 -299.200347)
			(xy 53.780182 -299.224954) (xy 54.11903 -299.224954) (xy 54.12299 -299.1759) (xy 54.134767 -299.128116)
			(xy 54.154058 -299.08284) (xy 54.180361 -299.041244) (xy 54.212996 -299.004407) (xy 54.251117 -298.973282)
			(xy 54.293738 -298.948675) (xy 54.339754 -298.931223) (xy 54.387973 -298.921379) (xy 54.437148 -298.919398)
			(xy 54.486003 -298.92533) (xy 54.533274 -298.939022) (xy 54.577736 -298.96012) (xy 54.618239 -298.988076)
			(xy 54.653732 -299.022168) (xy 54.683297 -299.061512) (xy 54.706168 -299.105089) (xy 54.721752 -299.15177)
			(xy 54.729647 -299.200347) (xy 54.730142 -299.224954) (xy 55.06899 -299.224954) (xy 55.07295 -299.1759)
			(xy 55.084727 -299.128116) (xy 55.104018 -299.08284) (xy 55.130321 -299.041244) (xy 55.162956 -299.004407)
			(xy 55.201077 -298.973282) (xy 55.243698 -298.948675) (xy 55.289714 -298.931223) (xy 55.337933 -298.921379)
			(xy 55.387108 -298.919398) (xy 55.435963 -298.92533) (xy 55.483234 -298.939022) (xy 55.527696 -298.96012)
			(xy 55.568199 -298.988076) (xy 55.603692 -299.022168) (xy 55.633257 -299.061512) (xy 55.656128 -299.105089)
			(xy 55.671712 -299.15177) (xy 55.679607 -299.200347) (xy 55.680102 -299.224954) (xy 56.01895 -299.224954)
			(xy 56.02291 -299.1759) (xy 56.034687 -299.128116) (xy 56.053978 -299.08284) (xy 56.080281 -299.041244)
			(xy 56.112916 -299.004407) (xy 56.151037 -298.973282) (xy 56.193658 -298.948675) (xy 56.239674 -298.931223)
			(xy 56.287893 -298.921379) (xy 56.337068 -298.919398) (xy 56.385923 -298.92533) (xy 56.433194 -298.939022)
			(xy 56.477656 -298.96012) (xy 56.518159 -298.988076) (xy 56.553652 -299.022168) (xy 56.583217 -299.061512)
			(xy 56.606088 -299.105089) (xy 56.621672 -299.15177) (xy 56.629567 -299.200347) (xy 56.630062 -299.224954)
			(xy 56.969164 -299.224954) (xy 56.973124 -299.1759) (xy 56.984901 -299.128116) (xy 57.004192 -299.08284)
			(xy 57.030495 -299.041244) (xy 57.06313 -299.004407) (xy 57.101251 -298.973282) (xy 57.143872 -298.948675)
			(xy 57.189888 -298.931223) (xy 57.238107 -298.921379) (xy 57.287282 -298.919398) (xy 57.336137 -298.92533)
			(xy 57.383408 -298.939022) (xy 57.42787 -298.96012) (xy 57.468373 -298.988076) (xy 57.503866 -299.022168)
			(xy 57.533431 -299.061512) (xy 57.556302 -299.105089) (xy 57.571886 -299.15177) (xy 57.579781 -299.200347)
			(xy 57.580276 -299.224954) (xy 57.919124 -299.224954) (xy 57.923084 -299.1759) (xy 57.934861 -299.128116)
			(xy 57.954152 -299.08284) (xy 57.980455 -299.041244) (xy 58.01309 -299.004407) (xy 58.051211 -298.973282)
			(xy 58.093832 -298.948675) (xy 58.139848 -298.931223) (xy 58.188067 -298.921379) (xy 58.237242 -298.919398)
			(xy 58.286097 -298.92533) (xy 58.333368 -298.939022) (xy 58.37783 -298.96012) (xy 58.418333 -298.988076)
			(xy 58.453826 -299.022168) (xy 58.483391 -299.061512) (xy 58.506262 -299.105089) (xy 58.521846 -299.15177)
			(xy 58.529741 -299.200347) (xy 58.530236 -299.224954) (xy 59.819044 -299.224954) (xy 59.823004 -299.1759)
			(xy 59.834781 -299.128116) (xy 59.854072 -299.08284) (xy 59.880375 -299.041244) (xy 59.91301 -299.004407)
			(xy 59.951131 -298.973282) (xy 59.993752 -298.948675) (xy 60.039768 -298.931223) (xy 60.087987 -298.921379)
			(xy 60.137162 -298.919398) (xy 60.186017 -298.92533) (xy 60.233288 -298.939022) (xy 60.27775 -298.96012)
			(xy 60.318253 -298.988076) (xy 60.353746 -299.022168) (xy 60.383311 -299.061512) (xy 60.406182 -299.105089)
			(xy 60.421766 -299.15177) (xy 60.429661 -299.200347) (xy 60.430156 -299.224954) (xy 60.769004 -299.224954)
			(xy 60.772964 -299.1759) (xy 60.784741 -299.128116) (xy 60.804032 -299.08284) (xy 60.830335 -299.041244)
			(xy 60.86297 -299.004407) (xy 60.901091 -298.973282) (xy 60.943712 -298.948675) (xy 60.989728 -298.931223)
			(xy 61.037947 -298.921379) (xy 61.087122 -298.919398) (xy 61.135977 -298.92533) (xy 61.183248 -298.939022)
			(xy 61.22771 -298.96012) (xy 61.268213 -298.988076) (xy 61.303706 -299.022168) (xy 61.333271 -299.061512)
			(xy 61.356142 -299.105089) (xy 61.371726 -299.15177) (xy 61.379621 -299.200347) (xy 61.380116 -299.224954)
			(xy 61.718964 -299.224954) (xy 61.722924 -299.1759) (xy 61.734701 -299.128116) (xy 61.753992 -299.08284)
			(xy 61.780295 -299.041244) (xy 61.81293 -299.004407) (xy 61.851051 -298.973282) (xy 61.893672 -298.948675)
			(xy 61.939688 -298.931223) (xy 61.987907 -298.921379) (xy 62.037082 -298.919398) (xy 62.085937 -298.92533)
			(xy 62.133208 -298.939022) (xy 62.17767 -298.96012) (xy 62.218173 -298.988076) (xy 62.253666 -299.022168)
			(xy 62.283231 -299.061512) (xy 62.306102 -299.105089) (xy 62.321686 -299.15177) (xy 62.329581 -299.200347)
			(xy 62.330076 -299.224954) (xy 62.669178 -299.224954) (xy 62.673138 -299.1759) (xy 62.684915 -299.128116)
			(xy 62.704206 -299.08284) (xy 62.730509 -299.041244) (xy 62.763144 -299.004407) (xy 62.801265 -298.973282)
			(xy 62.843886 -298.948675) (xy 62.889902 -298.931223) (xy 62.938121 -298.921379) (xy 62.987296 -298.919398)
			(xy 63.036151 -298.92533) (xy 63.083422 -298.939022) (xy 63.127884 -298.96012) (xy 63.168387 -298.988076)
			(xy 63.20388 -299.022168) (xy 63.233445 -299.061512) (xy 63.256316 -299.105089) (xy 63.2719 -299.15177)
			(xy 63.279795 -299.200347) (xy 63.28029 -299.224954) (xy 63.619138 -299.224954) (xy 63.623098 -299.1759)
			(xy 63.634875 -299.128116) (xy 63.654166 -299.08284) (xy 63.680469 -299.041244) (xy 63.713104 -299.004407)
			(xy 63.751225 -298.973282) (xy 63.793846 -298.948675) (xy 63.839862 -298.931223) (xy 63.888081 -298.921379)
			(xy 63.937256 -298.919398) (xy 63.986111 -298.92533) (xy 64.033382 -298.939022) (xy 64.077844 -298.96012)
			(xy 64.118347 -298.988076) (xy 64.15384 -299.022168) (xy 64.183405 -299.061512) (xy 64.206276 -299.105089)
			(xy 64.22186 -299.15177) (xy 64.229755 -299.200347) (xy 64.23025 -299.224954) (xy 64.569098 -299.224954)
			(xy 64.573058 -299.1759) (xy 64.584835 -299.128116) (xy 64.604126 -299.08284) (xy 64.630429 -299.041244)
			(xy 64.663064 -299.004407) (xy 64.701185 -298.973282) (xy 64.743806 -298.948675) (xy 64.789822 -298.931223)
			(xy 64.838041 -298.921379) (xy 64.887216 -298.919398) (xy 64.936071 -298.92533) (xy 64.983342 -298.939022)
			(xy 65.027804 -298.96012) (xy 65.068307 -298.988076) (xy 65.1038 -299.022168) (xy 65.133365 -299.061512)
			(xy 65.156236 -299.105089) (xy 65.17182 -299.15177) (xy 65.179715 -299.200347) (xy 65.18021 -299.224954)
			(xy 65.519058 -299.224954) (xy 65.523018 -299.1759) (xy 65.534795 -299.128116) (xy 65.554086 -299.08284)
			(xy 65.580389 -299.041244) (xy 65.613024 -299.004407) (xy 65.651145 -298.973282) (xy 65.693766 -298.948675)
			(xy 65.739782 -298.931223) (xy 65.788001 -298.921379) (xy 65.837176 -298.919398) (xy 65.886031 -298.92533)
			(xy 65.933302 -298.939022) (xy 65.977764 -298.96012) (xy 66.018267 -298.988076) (xy 66.05376 -299.022168)
			(xy 66.083325 -299.061512) (xy 66.106196 -299.105089) (xy 66.12178 -299.15177) (xy 66.129675 -299.200347)
			(xy 66.13017 -299.224954) (xy 66.469018 -299.224954) (xy 66.472978 -299.1759) (xy 66.484755 -299.128116)
			(xy 66.504046 -299.08284) (xy 66.530349 -299.041244) (xy 66.562984 -299.004407) (xy 66.601105 -298.973282)
			(xy 66.643726 -298.948675) (xy 66.689742 -298.931223) (xy 66.737961 -298.921379) (xy 66.787136 -298.919398)
			(xy 66.835991 -298.92533) (xy 66.883262 -298.939022) (xy 66.927724 -298.96012) (xy 66.968227 -298.988076)
			(xy 67.00372 -299.022168) (xy 67.033285 -299.061512) (xy 67.056156 -299.105089) (xy 67.07174 -299.15177)
			(xy 67.079635 -299.200347) (xy 67.08013 -299.224954) (xy 67.418978 -299.224954) (xy 67.422938 -299.1759)
			(xy 67.434715 -299.128116) (xy 67.454006 -299.08284) (xy 67.480309 -299.041244) (xy 67.512944 -299.004407)
			(xy 67.551065 -298.973282) (xy 67.593686 -298.948675) (xy 67.639702 -298.931223) (xy 67.687921 -298.921379)
			(xy 67.737096 -298.919398) (xy 67.785951 -298.92533) (xy 67.833222 -298.939022) (xy 67.877684 -298.96012)
			(xy 67.918187 -298.988076) (xy 67.95368 -299.022168) (xy 67.983245 -299.061512) (xy 68.006116 -299.105089)
			(xy 68.0217 -299.15177) (xy 68.029595 -299.200347) (xy 68.03009 -299.224954) (xy 68.368938 -299.224954)
			(xy 68.372898 -299.1759) (xy 68.384675 -299.128116) (xy 68.403966 -299.08284) (xy 68.430269 -299.041244)
			(xy 68.462904 -299.004407) (xy 68.501025 -298.973282) (xy 68.543646 -298.948675) (xy 68.589662 -298.931223)
			(xy 68.637881 -298.921379) (xy 68.687056 -298.919398) (xy 68.735911 -298.92533) (xy 68.783182 -298.939022)
			(xy 68.827644 -298.96012) (xy 68.868147 -298.988076) (xy 68.90364 -299.022168) (xy 68.933205 -299.061512)
			(xy 68.956076 -299.105089) (xy 68.97166 -299.15177) (xy 68.979555 -299.200347) (xy 68.98005 -299.224954)
			(xy 69.319152 -299.224954) (xy 69.323112 -299.1759) (xy 69.334889 -299.128116) (xy 69.35418 -299.08284)
			(xy 69.380483 -299.041244) (xy 69.413118 -299.004407) (xy 69.451239 -298.973282) (xy 69.49386 -298.948675)
			(xy 69.539876 -298.931223) (xy 69.588095 -298.921379) (xy 69.63727 -298.919398) (xy 69.686125 -298.92533)
			(xy 69.733396 -298.939022) (xy 69.777858 -298.96012) (xy 69.818361 -298.988076) (xy 69.853854 -299.022168)
			(xy 69.883419 -299.061512) (xy 69.90629 -299.105089) (xy 69.921874 -299.15177) (xy 69.929769 -299.200347)
			(xy 69.930264 -299.224954) (xy 70.269112 -299.224954) (xy 70.273072 -299.1759) (xy 70.284849 -299.128116)
			(xy 70.30414 -299.08284) (xy 70.330443 -299.041244) (xy 70.363078 -299.004407) (xy 70.401199 -298.973282)
			(xy 70.44382 -298.948675) (xy 70.489836 -298.931223) (xy 70.538055 -298.921379) (xy 70.58723 -298.919398)
			(xy 70.636085 -298.92533) (xy 70.683356 -298.939022) (xy 70.727818 -298.96012) (xy 70.768321 -298.988076)
			(xy 70.803814 -299.022168) (xy 70.833379 -299.061512) (xy 70.85625 -299.105089) (xy 70.871834 -299.15177)
			(xy 70.879729 -299.200347) (xy 70.880224 -299.224954) (xy 71.219072 -299.224954) (xy 71.223032 -299.1759)
			(xy 71.234809 -299.128116) (xy 71.2541 -299.08284) (xy 71.280403 -299.041244) (xy 71.313038 -299.004407)
			(xy 71.351159 -298.973282) (xy 71.39378 -298.948675) (xy 71.439796 -298.931223) (xy 71.488015 -298.921379)
			(xy 71.53719 -298.919398) (xy 71.586045 -298.92533) (xy 71.633316 -298.939022) (xy 71.677778 -298.96012)
			(xy 71.718281 -298.988076) (xy 71.753774 -299.022168) (xy 71.783339 -299.061512) (xy 71.80621 -299.105089)
			(xy 71.821794 -299.15177) (xy 71.829689 -299.200347) (xy 71.830184 -299.224954) (xy 72.169032 -299.224954)
			(xy 72.172992 -299.1759) (xy 72.184769 -299.128116) (xy 72.20406 -299.08284) (xy 72.230363 -299.041244)
			(xy 72.262998 -299.004407) (xy 72.301119 -298.973282) (xy 72.34374 -298.948675) (xy 72.389756 -298.931223)
			(xy 72.437975 -298.921379) (xy 72.48715 -298.919398) (xy 72.536005 -298.92533) (xy 72.583276 -298.939022)
			(xy 72.627738 -298.96012) (xy 72.668241 -298.988076) (xy 72.703734 -299.022168) (xy 72.733299 -299.061512)
			(xy 72.75617 -299.105089) (xy 72.771754 -299.15177) (xy 72.779649 -299.200347) (xy 72.780144 -299.224954)
			(xy 73.118992 -299.224954) (xy 73.122952 -299.1759) (xy 73.134729 -299.128116) (xy 73.15402 -299.08284)
			(xy 73.180323 -299.041244) (xy 73.212958 -299.004407) (xy 73.251079 -298.973282) (xy 73.2937 -298.948675)
			(xy 73.339716 -298.931223) (xy 73.387935 -298.921379) (xy 73.43711 -298.919398) (xy 73.485965 -298.92533)
			(xy 73.533236 -298.939022) (xy 73.577698 -298.96012) (xy 73.618201 -298.988076) (xy 73.653694 -299.022168)
			(xy 73.683259 -299.061512) (xy 73.70613 -299.105089) (xy 73.721714 -299.15177) (xy 73.729609 -299.200347)
			(xy 73.730104 -299.224954) (xy 75.969126 -299.224954) (xy 75.973086 -299.1759) (xy 75.984863 -299.128116)
			(xy 76.004154 -299.08284) (xy 76.030457 -299.041244) (xy 76.063092 -299.004407) (xy 76.101213 -298.973282)
			(xy 76.143834 -298.948675) (xy 76.18985 -298.931223) (xy 76.238069 -298.921379) (xy 76.287244 -298.919398)
			(xy 76.336099 -298.92533) (xy 76.38337 -298.939022) (xy 76.427832 -298.96012) (xy 76.468335 -298.988076)
			(xy 76.503828 -299.022168) (xy 76.533393 -299.061512) (xy 76.556264 -299.105089) (xy 76.571848 -299.15177)
			(xy 76.579743 -299.200347) (xy 76.580238 -299.224954) (xy 76.919086 -299.224954) (xy 76.923046 -299.1759)
			(xy 76.934823 -299.128116) (xy 76.954114 -299.08284) (xy 76.980417 -299.041244) (xy 77.013052 -299.004407)
			(xy 77.051173 -298.973282) (xy 77.093794 -298.948675) (xy 77.13981 -298.931223) (xy 77.188029 -298.921379)
			(xy 77.237204 -298.919398) (xy 77.286059 -298.92533) (xy 77.33333 -298.939022) (xy 77.377792 -298.96012)
			(xy 77.418295 -298.988076) (xy 77.453788 -299.022168) (xy 77.483353 -299.061512) (xy 77.506224 -299.105089)
			(xy 77.521808 -299.15177) (xy 77.529703 -299.200347) (xy 77.530198 -299.224954) (xy 77.869046 -299.224954)
			(xy 77.873006 -299.1759) (xy 77.884783 -299.128116) (xy 77.904074 -299.08284) (xy 77.930377 -299.041244)
			(xy 77.963012 -299.004407) (xy 78.001133 -298.973282) (xy 78.043754 -298.948675) (xy 78.08977 -298.931223)
			(xy 78.137989 -298.921379) (xy 78.187164 -298.919398) (xy 78.236019 -298.92533) (xy 78.28329 -298.939022)
			(xy 78.327752 -298.96012) (xy 78.368255 -298.988076) (xy 78.403748 -299.022168) (xy 78.433313 -299.061512)
			(xy 78.456184 -299.105089) (xy 78.471768 -299.15177) (xy 78.479663 -299.200347) (xy 78.480158 -299.224954)
			(xy 78.819006 -299.224954) (xy 78.822966 -299.1759) (xy 78.834743 -299.128116) (xy 78.854034 -299.08284)
			(xy 78.880337 -299.041244) (xy 78.912972 -299.004407) (xy 78.951093 -298.973282) (xy 78.993714 -298.948675)
			(xy 79.03973 -298.931223) (xy 79.087949 -298.921379) (xy 79.137124 -298.919398) (xy 79.185979 -298.92533)
			(xy 79.23325 -298.939022) (xy 79.277712 -298.96012) (xy 79.318215 -298.988076) (xy 79.353708 -299.022168)
			(xy 79.383273 -299.061512) (xy 79.406144 -299.105089) (xy 79.421728 -299.15177) (xy 79.429623 -299.200347)
			(xy 79.430118 -299.224954) (xy 79.768966 -299.224954) (xy 79.772926 -299.1759) (xy 79.784703 -299.128116)
			(xy 79.803994 -299.08284) (xy 79.830297 -299.041244) (xy 79.862932 -299.004407) (xy 79.901053 -298.973282)
			(xy 79.943674 -298.948675) (xy 79.98969 -298.931223) (xy 80.037909 -298.921379) (xy 80.087084 -298.919398)
			(xy 80.135939 -298.92533) (xy 80.18321 -298.939022) (xy 80.227672 -298.96012) (xy 80.268175 -298.988076)
			(xy 80.303668 -299.022168) (xy 80.333233 -299.061512) (xy 80.356104 -299.105089) (xy 80.371688 -299.15177)
			(xy 80.379583 -299.200347) (xy 80.380078 -299.224954) (xy 80.71918 -299.224954) (xy 80.72314 -299.1759)
			(xy 80.734917 -299.128116) (xy 80.754208 -299.08284) (xy 80.780511 -299.041244) (xy 80.813146 -299.004407)
			(xy 80.851267 -298.973282) (xy 80.893888 -298.948675) (xy 80.939904 -298.931223) (xy 80.988123 -298.921379)
			(xy 81.037298 -298.919398) (xy 81.086153 -298.92533) (xy 81.133424 -298.939022) (xy 81.177886 -298.96012)
			(xy 81.218389 -298.988076) (xy 81.253882 -299.022168) (xy 81.283447 -299.061512) (xy 81.306318 -299.105089)
			(xy 81.321902 -299.15177) (xy 81.329797 -299.200347) (xy 81.330292 -299.224954) (xy 81.66914 -299.224954)
			(xy 81.6731 -299.1759) (xy 81.684877 -299.128116) (xy 81.704168 -299.08284) (xy 81.730471 -299.041244)
			(xy 81.763106 -299.004407) (xy 81.801227 -298.973282) (xy 81.843848 -298.948675) (xy 81.889864 -298.931223)
			(xy 81.938083 -298.921379) (xy 81.987258 -298.919398) (xy 82.036113 -298.92533) (xy 82.083384 -298.939022)
			(xy 82.127846 -298.96012) (xy 82.168349 -298.988076) (xy 82.203842 -299.022168) (xy 82.233407 -299.061512)
			(xy 82.256278 -299.105089) (xy 82.271862 -299.15177) (xy 82.279757 -299.200347) (xy 82.280252 -299.224954)
			(xy 82.6191 -299.224954) (xy 82.62306 -299.1759) (xy 82.634837 -299.128116) (xy 82.654128 -299.08284)
			(xy 82.680431 -299.041244) (xy 82.713066 -299.004407) (xy 82.751187 -298.973282) (xy 82.793808 -298.948675)
			(xy 82.839824 -298.931223) (xy 82.888043 -298.921379) (xy 82.937218 -298.919398) (xy 82.986073 -298.92533)
			(xy 83.033344 -298.939022) (xy 83.077806 -298.96012) (xy 83.118309 -298.988076) (xy 83.153802 -299.022168)
			(xy 83.183367 -299.061512) (xy 83.206238 -299.105089) (xy 83.221822 -299.15177) (xy 83.229717 -299.200347)
			(xy 83.230212 -299.224954) (xy 83.229717 -299.249561) (xy 83.221822 -299.298138) (xy 83.206238 -299.344819)
			(xy 83.183367 -299.388396) (xy 83.153802 -299.42774) (xy 83.118309 -299.461832) (xy 83.077806 -299.489788)
			(xy 83.033344 -299.510886) (xy 82.986073 -299.524578) (xy 82.937218 -299.53051) (xy 82.888043 -299.528529)
			(xy 82.839824 -299.518685) (xy 82.793808 -299.501233) (xy 82.751187 -299.476626) (xy 82.713066 -299.445501)
			(xy 82.680431 -299.408664) (xy 82.654128 -299.367068) (xy 82.634837 -299.321792) (xy 82.62306 -299.274008)
			(xy 82.6191 -299.224954) (xy 82.280252 -299.224954) (xy 82.279757 -299.249561) (xy 82.271862 -299.298138)
			(xy 82.256278 -299.344819) (xy 82.233407 -299.388396) (xy 82.203842 -299.42774) (xy 82.168349 -299.461832)
			(xy 82.127846 -299.489788) (xy 82.083384 -299.510886) (xy 82.036113 -299.524578) (xy 81.987258 -299.53051)
			(xy 81.938083 -299.528529) (xy 81.889864 -299.518685) (xy 81.843848 -299.501233) (xy 81.801227 -299.476626)
			(xy 81.763106 -299.445501) (xy 81.730471 -299.408664) (xy 81.704168 -299.367068) (xy 81.684877 -299.321792)
			(xy 81.6731 -299.274008) (xy 81.66914 -299.224954) (xy 81.330292 -299.224954) (xy 81.329797 -299.249561)
			(xy 81.321902 -299.298138) (xy 81.306318 -299.344819) (xy 81.283447 -299.388396) (xy 81.253882 -299.42774)
			(xy 81.218389 -299.461832) (xy 81.177886 -299.489788) (xy 81.133424 -299.510886) (xy 81.086153 -299.524578)
			(xy 81.037298 -299.53051) (xy 80.988123 -299.528529) (xy 80.939904 -299.518685) (xy 80.893888 -299.501233)
			(xy 80.851267 -299.476626) (xy 80.813146 -299.445501) (xy 80.780511 -299.408664) (xy 80.754208 -299.367068)
			(xy 80.734917 -299.321792) (xy 80.72314 -299.274008) (xy 80.71918 -299.224954) (xy 80.380078 -299.224954)
			(xy 80.379583 -299.249561) (xy 80.371688 -299.298138) (xy 80.356104 -299.344819) (xy 80.333233 -299.388396)
			(xy 80.303668 -299.42774) (xy 80.268175 -299.461832) (xy 80.227672 -299.489788) (xy 80.18321 -299.510886)
			(xy 80.135939 -299.524578) (xy 80.087084 -299.53051) (xy 80.037909 -299.528529) (xy 79.98969 -299.518685)
			(xy 79.943674 -299.501233) (xy 79.901053 -299.476626) (xy 79.862932 -299.445501) (xy 79.830297 -299.408664)
			(xy 79.803994 -299.367068) (xy 79.784703 -299.321792) (xy 79.772926 -299.274008) (xy 79.768966 -299.224954)
			(xy 79.430118 -299.224954) (xy 79.429623 -299.249561) (xy 79.421728 -299.298138) (xy 79.406144 -299.344819)
			(xy 79.383273 -299.388396) (xy 79.353708 -299.42774) (xy 79.318215 -299.461832) (xy 79.277712 -299.489788)
			(xy 79.23325 -299.510886) (xy 79.185979 -299.524578) (xy 79.137124 -299.53051) (xy 79.087949 -299.528529)
			(xy 79.03973 -299.518685) (xy 78.993714 -299.501233) (xy 78.951093 -299.476626) (xy 78.912972 -299.445501)
			(xy 78.880337 -299.408664) (xy 78.854034 -299.367068) (xy 78.834743 -299.321792) (xy 78.822966 -299.274008)
			(xy 78.819006 -299.224954) (xy 78.480158 -299.224954) (xy 78.479663 -299.249561) (xy 78.471768 -299.298138)
			(xy 78.456184 -299.344819) (xy 78.433313 -299.388396) (xy 78.403748 -299.42774) (xy 78.368255 -299.461832)
			(xy 78.327752 -299.489788) (xy 78.28329 -299.510886) (xy 78.236019 -299.524578) (xy 78.187164 -299.53051)
			(xy 78.137989 -299.528529) (xy 78.08977 -299.518685) (xy 78.043754 -299.501233) (xy 78.001133 -299.476626)
			(xy 77.963012 -299.445501) (xy 77.930377 -299.408664) (xy 77.904074 -299.367068) (xy 77.884783 -299.321792)
			(xy 77.873006 -299.274008) (xy 77.869046 -299.224954) (xy 77.530198 -299.224954) (xy 77.529703 -299.249561)
			(xy 77.521808 -299.298138) (xy 77.506224 -299.344819) (xy 77.483353 -299.388396) (xy 77.453788 -299.42774)
			(xy 77.418295 -299.461832) (xy 77.377792 -299.489788) (xy 77.33333 -299.510886) (xy 77.286059 -299.524578)
			(xy 77.237204 -299.53051) (xy 77.188029 -299.528529) (xy 77.13981 -299.518685) (xy 77.093794 -299.501233)
			(xy 77.051173 -299.476626) (xy 77.013052 -299.445501) (xy 76.980417 -299.408664) (xy 76.954114 -299.367068)
			(xy 76.934823 -299.321792) (xy 76.923046 -299.274008) (xy 76.919086 -299.224954) (xy 76.580238 -299.224954)
			(xy 76.579743 -299.249561) (xy 76.571848 -299.298138) (xy 76.556264 -299.344819) (xy 76.533393 -299.388396)
			(xy 76.503828 -299.42774) (xy 76.468335 -299.461832) (xy 76.427832 -299.489788) (xy 76.38337 -299.510886)
			(xy 76.336099 -299.524578) (xy 76.287244 -299.53051) (xy 76.238069 -299.528529) (xy 76.18985 -299.518685)
			(xy 76.143834 -299.501233) (xy 76.101213 -299.476626) (xy 76.063092 -299.445501) (xy 76.030457 -299.408664)
			(xy 76.004154 -299.367068) (xy 75.984863 -299.321792) (xy 75.973086 -299.274008) (xy 75.969126 -299.224954)
			(xy 73.730104 -299.224954) (xy 73.729609 -299.249561) (xy 73.721714 -299.298138) (xy 73.70613 -299.344819)
			(xy 73.683259 -299.388396) (xy 73.653694 -299.42774) (xy 73.618201 -299.461832) (xy 73.577698 -299.489788)
			(xy 73.533236 -299.510886) (xy 73.485965 -299.524578) (xy 73.43711 -299.53051) (xy 73.387935 -299.528529)
			(xy 73.339716 -299.518685) (xy 73.2937 -299.501233) (xy 73.251079 -299.476626) (xy 73.212958 -299.445501)
			(xy 73.180323 -299.408664) (xy 73.15402 -299.367068) (xy 73.134729 -299.321792) (xy 73.122952 -299.274008)
			(xy 73.118992 -299.224954) (xy 72.780144 -299.224954) (xy 72.779649 -299.249561) (xy 72.771754 -299.298138)
			(xy 72.75617 -299.344819) (xy 72.733299 -299.388396) (xy 72.703734 -299.42774) (xy 72.668241 -299.461832)
			(xy 72.627738 -299.489788) (xy 72.583276 -299.510886) (xy 72.536005 -299.524578) (xy 72.48715 -299.53051)
			(xy 72.437975 -299.528529) (xy 72.389756 -299.518685) (xy 72.34374 -299.501233) (xy 72.301119 -299.476626)
			(xy 72.262998 -299.445501) (xy 72.230363 -299.408664) (xy 72.20406 -299.367068) (xy 72.184769 -299.321792)
			(xy 72.172992 -299.274008) (xy 72.169032 -299.224954) (xy 71.830184 -299.224954) (xy 71.829689 -299.249561)
			(xy 71.821794 -299.298138) (xy 71.80621 -299.344819) (xy 71.783339 -299.388396) (xy 71.753774 -299.42774)
			(xy 71.718281 -299.461832) (xy 71.677778 -299.489788) (xy 71.633316 -299.510886) (xy 71.586045 -299.524578)
			(xy 71.53719 -299.53051) (xy 71.488015 -299.528529) (xy 71.439796 -299.518685) (xy 71.39378 -299.501233)
			(xy 71.351159 -299.476626) (xy 71.313038 -299.445501) (xy 71.280403 -299.408664) (xy 71.2541 -299.367068)
			(xy 71.234809 -299.321792) (xy 71.223032 -299.274008) (xy 71.219072 -299.224954) (xy 70.880224 -299.224954)
			(xy 70.879729 -299.249561) (xy 70.871834 -299.298138) (xy 70.85625 -299.344819) (xy 70.833379 -299.388396)
			(xy 70.803814 -299.42774) (xy 70.768321 -299.461832) (xy 70.727818 -299.489788) (xy 70.683356 -299.510886)
			(xy 70.636085 -299.524578) (xy 70.58723 -299.53051) (xy 70.538055 -299.528529) (xy 70.489836 -299.518685)
			(xy 70.44382 -299.501233) (xy 70.401199 -299.476626) (xy 70.363078 -299.445501) (xy 70.330443 -299.408664)
			(xy 70.30414 -299.367068) (xy 70.284849 -299.321792) (xy 70.273072 -299.274008) (xy 70.269112 -299.224954)
			(xy 69.930264 -299.224954) (xy 69.929769 -299.249561) (xy 69.921874 -299.298138) (xy 69.90629 -299.344819)
			(xy 69.883419 -299.388396) (xy 69.853854 -299.42774) (xy 69.818361 -299.461832) (xy 69.777858 -299.489788)
			(xy 69.733396 -299.510886) (xy 69.686125 -299.524578) (xy 69.63727 -299.53051) (xy 69.588095 -299.528529)
			(xy 69.539876 -299.518685) (xy 69.49386 -299.501233) (xy 69.451239 -299.476626) (xy 69.413118 -299.445501)
			(xy 69.380483 -299.408664) (xy 69.35418 -299.367068) (xy 69.334889 -299.321792) (xy 69.323112 -299.274008)
			(xy 69.319152 -299.224954) (xy 68.98005 -299.224954) (xy 68.979555 -299.249561) (xy 68.97166 -299.298138)
			(xy 68.956076 -299.344819) (xy 68.933205 -299.388396) (xy 68.90364 -299.42774) (xy 68.868147 -299.461832)
			(xy 68.827644 -299.489788) (xy 68.783182 -299.510886) (xy 68.735911 -299.524578) (xy 68.687056 -299.53051)
			(xy 68.637881 -299.528529) (xy 68.589662 -299.518685) (xy 68.543646 -299.501233) (xy 68.501025 -299.476626)
			(xy 68.462904 -299.445501) (xy 68.430269 -299.408664) (xy 68.403966 -299.367068) (xy 68.384675 -299.321792)
			(xy 68.372898 -299.274008) (xy 68.368938 -299.224954) (xy 68.03009 -299.224954) (xy 68.029595 -299.249561)
			(xy 68.0217 -299.298138) (xy 68.006116 -299.344819) (xy 67.983245 -299.388396) (xy 67.95368 -299.42774)
			(xy 67.918187 -299.461832) (xy 67.877684 -299.489788) (xy 67.833222 -299.510886) (xy 67.785951 -299.524578)
			(xy 67.737096 -299.53051) (xy 67.687921 -299.528529) (xy 67.639702 -299.518685) (xy 67.593686 -299.501233)
			(xy 67.551065 -299.476626) (xy 67.512944 -299.445501) (xy 67.480309 -299.408664) (xy 67.454006 -299.367068)
			(xy 67.434715 -299.321792) (xy 67.422938 -299.274008) (xy 67.418978 -299.224954) (xy 67.08013 -299.224954)
			(xy 67.079635 -299.249561) (xy 67.07174 -299.298138) (xy 67.056156 -299.344819) (xy 67.033285 -299.388396)
			(xy 67.00372 -299.42774) (xy 66.968227 -299.461832) (xy 66.927724 -299.489788) (xy 66.883262 -299.510886)
			(xy 66.835991 -299.524578) (xy 66.787136 -299.53051) (xy 66.737961 -299.528529) (xy 66.689742 -299.518685)
			(xy 66.643726 -299.501233) (xy 66.601105 -299.476626) (xy 66.562984 -299.445501) (xy 66.530349 -299.408664)
			(xy 66.504046 -299.367068) (xy 66.484755 -299.321792) (xy 66.472978 -299.274008) (xy 66.469018 -299.224954)
			(xy 66.13017 -299.224954) (xy 66.129675 -299.249561) (xy 66.12178 -299.298138) (xy 66.106196 -299.344819)
			(xy 66.083325 -299.388396) (xy 66.05376 -299.42774) (xy 66.018267 -299.461832) (xy 65.977764 -299.489788)
			(xy 65.933302 -299.510886) (xy 65.886031 -299.524578) (xy 65.837176 -299.53051) (xy 65.788001 -299.528529)
			(xy 65.739782 -299.518685) (xy 65.693766 -299.501233) (xy 65.651145 -299.476626) (xy 65.613024 -299.445501)
			(xy 65.580389 -299.408664) (xy 65.554086 -299.367068) (xy 65.534795 -299.321792) (xy 65.523018 -299.274008)
			(xy 65.519058 -299.224954) (xy 65.18021 -299.224954) (xy 65.179715 -299.249561) (xy 65.17182 -299.298138)
			(xy 65.156236 -299.344819) (xy 65.133365 -299.388396) (xy 65.1038 -299.42774) (xy 65.068307 -299.461832)
			(xy 65.027804 -299.489788) (xy 64.983342 -299.510886) (xy 64.936071 -299.524578) (xy 64.887216 -299.53051)
			(xy 64.838041 -299.528529) (xy 64.789822 -299.518685) (xy 64.743806 -299.501233) (xy 64.701185 -299.476626)
			(xy 64.663064 -299.445501) (xy 64.630429 -299.408664) (xy 64.604126 -299.367068) (xy 64.584835 -299.321792)
			(xy 64.573058 -299.274008) (xy 64.569098 -299.224954) (xy 64.23025 -299.224954) (xy 64.229755 -299.249561)
			(xy 64.22186 -299.298138) (xy 64.206276 -299.344819) (xy 64.183405 -299.388396) (xy 64.15384 -299.42774)
			(xy 64.118347 -299.461832) (xy 64.077844 -299.489788) (xy 64.033382 -299.510886) (xy 63.986111 -299.524578)
			(xy 63.937256 -299.53051) (xy 63.888081 -299.528529) (xy 63.839862 -299.518685) (xy 63.793846 -299.501233)
			(xy 63.751225 -299.476626) (xy 63.713104 -299.445501) (xy 63.680469 -299.408664) (xy 63.654166 -299.367068)
			(xy 63.634875 -299.321792) (xy 63.623098 -299.274008) (xy 63.619138 -299.224954) (xy 63.28029 -299.224954)
			(xy 63.279795 -299.249561) (xy 63.2719 -299.298138) (xy 63.256316 -299.344819) (xy 63.233445 -299.388396)
			(xy 63.20388 -299.42774) (xy 63.168387 -299.461832) (xy 63.127884 -299.489788) (xy 63.083422 -299.510886)
			(xy 63.036151 -299.524578) (xy 62.987296 -299.53051) (xy 62.938121 -299.528529) (xy 62.889902 -299.518685)
			(xy 62.843886 -299.501233) (xy 62.801265 -299.476626) (xy 62.763144 -299.445501) (xy 62.730509 -299.408664)
			(xy 62.704206 -299.367068) (xy 62.684915 -299.321792) (xy 62.673138 -299.274008) (xy 62.669178 -299.224954)
			(xy 62.330076 -299.224954) (xy 62.329581 -299.249561) (xy 62.321686 -299.298138) (xy 62.306102 -299.344819)
			(xy 62.283231 -299.388396) (xy 62.253666 -299.42774) (xy 62.218173 -299.461832) (xy 62.17767 -299.489788)
			(xy 62.133208 -299.510886) (xy 62.085937 -299.524578) (xy 62.037082 -299.53051) (xy 61.987907 -299.528529)
			(xy 61.939688 -299.518685) (xy 61.893672 -299.501233) (xy 61.851051 -299.476626) (xy 61.81293 -299.445501)
			(xy 61.780295 -299.408664) (xy 61.753992 -299.367068) (xy 61.734701 -299.321792) (xy 61.722924 -299.274008)
			(xy 61.718964 -299.224954) (xy 61.380116 -299.224954) (xy 61.379621 -299.249561) (xy 61.371726 -299.298138)
			(xy 61.356142 -299.344819) (xy 61.333271 -299.388396) (xy 61.303706 -299.42774) (xy 61.268213 -299.461832)
			(xy 61.22771 -299.489788) (xy 61.183248 -299.510886) (xy 61.135977 -299.524578) (xy 61.087122 -299.53051)
			(xy 61.037947 -299.528529) (xy 60.989728 -299.518685) (xy 60.943712 -299.501233) (xy 60.901091 -299.476626)
			(xy 60.86297 -299.445501) (xy 60.830335 -299.408664) (xy 60.804032 -299.367068) (xy 60.784741 -299.321792)
			(xy 60.772964 -299.274008) (xy 60.769004 -299.224954) (xy 60.430156 -299.224954) (xy 60.429661 -299.249561)
			(xy 60.421766 -299.298138) (xy 60.406182 -299.344819) (xy 60.383311 -299.388396) (xy 60.353746 -299.42774)
			(xy 60.318253 -299.461832) (xy 60.27775 -299.489788) (xy 60.233288 -299.510886) (xy 60.186017 -299.524578)
			(xy 60.137162 -299.53051) (xy 60.087987 -299.528529) (xy 60.039768 -299.518685) (xy 59.993752 -299.501233)
			(xy 59.951131 -299.476626) (xy 59.91301 -299.445501) (xy 59.880375 -299.408664) (xy 59.854072 -299.367068)
			(xy 59.834781 -299.321792) (xy 59.823004 -299.274008) (xy 59.819044 -299.224954) (xy 58.530236 -299.224954)
			(xy 58.529741 -299.249561) (xy 58.521846 -299.298138) (xy 58.506262 -299.344819) (xy 58.483391 -299.388396)
			(xy 58.453826 -299.42774) (xy 58.418333 -299.461832) (xy 58.37783 -299.489788) (xy 58.333368 -299.510886)
			(xy 58.286097 -299.524578) (xy 58.237242 -299.53051) (xy 58.188067 -299.528529) (xy 58.139848 -299.518685)
			(xy 58.093832 -299.501233) (xy 58.051211 -299.476626) (xy 58.01309 -299.445501) (xy 57.980455 -299.408664)
			(xy 57.954152 -299.367068) (xy 57.934861 -299.321792) (xy 57.923084 -299.274008) (xy 57.919124 -299.224954)
			(xy 57.580276 -299.224954) (xy 57.579781 -299.249561) (xy 57.571886 -299.298138) (xy 57.556302 -299.344819)
			(xy 57.533431 -299.388396) (xy 57.503866 -299.42774) (xy 57.468373 -299.461832) (xy 57.42787 -299.489788)
			(xy 57.383408 -299.510886) (xy 57.336137 -299.524578) (xy 57.287282 -299.53051) (xy 57.238107 -299.528529)
			(xy 57.189888 -299.518685) (xy 57.143872 -299.501233) (xy 57.101251 -299.476626) (xy 57.06313 -299.445501)
			(xy 57.030495 -299.408664) (xy 57.004192 -299.367068) (xy 56.984901 -299.321792) (xy 56.973124 -299.274008)
			(xy 56.969164 -299.224954) (xy 56.630062 -299.224954) (xy 56.629567 -299.249561) (xy 56.621672 -299.298138)
			(xy 56.606088 -299.344819) (xy 56.583217 -299.388396) (xy 56.553652 -299.42774) (xy 56.518159 -299.461832)
			(xy 56.477656 -299.489788) (xy 56.433194 -299.510886) (xy 56.385923 -299.524578) (xy 56.337068 -299.53051)
			(xy 56.287893 -299.528529) (xy 56.239674 -299.518685) (xy 56.193658 -299.501233) (xy 56.151037 -299.476626)
			(xy 56.112916 -299.445501) (xy 56.080281 -299.408664) (xy 56.053978 -299.367068) (xy 56.034687 -299.321792)
			(xy 56.02291 -299.274008) (xy 56.01895 -299.224954) (xy 55.680102 -299.224954) (xy 55.679607 -299.249561)
			(xy 55.671712 -299.298138) (xy 55.656128 -299.344819) (xy 55.633257 -299.388396) (xy 55.603692 -299.42774)
			(xy 55.568199 -299.461832) (xy 55.527696 -299.489788) (xy 55.483234 -299.510886) (xy 55.435963 -299.524578)
			(xy 55.387108 -299.53051) (xy 55.337933 -299.528529) (xy 55.289714 -299.518685) (xy 55.243698 -299.501233)
			(xy 55.201077 -299.476626) (xy 55.162956 -299.445501) (xy 55.130321 -299.408664) (xy 55.104018 -299.367068)
			(xy 55.084727 -299.321792) (xy 55.07295 -299.274008) (xy 55.06899 -299.224954) (xy 54.730142 -299.224954)
			(xy 54.729647 -299.249561) (xy 54.721752 -299.298138) (xy 54.706168 -299.344819) (xy 54.683297 -299.388396)
			(xy 54.653732 -299.42774) (xy 54.618239 -299.461832) (xy 54.577736 -299.489788) (xy 54.533274 -299.510886)
			(xy 54.486003 -299.524578) (xy 54.437148 -299.53051) (xy 54.387973 -299.528529) (xy 54.339754 -299.518685)
			(xy 54.293738 -299.501233) (xy 54.251117 -299.476626) (xy 54.212996 -299.445501) (xy 54.180361 -299.408664)
			(xy 54.154058 -299.367068) (xy 54.134767 -299.321792) (xy 54.12299 -299.274008) (xy 54.11903 -299.224954)
			(xy 53.780182 -299.224954) (xy 53.779687 -299.249561) (xy 53.771792 -299.298138) (xy 53.756208 -299.344819)
			(xy 53.733337 -299.388396) (xy 53.703772 -299.42774) (xy 53.668279 -299.461832) (xy 53.627776 -299.489788)
			(xy 53.583314 -299.510886) (xy 53.536043 -299.524578) (xy 53.487188 -299.53051) (xy 53.438013 -299.528529)
			(xy 53.389794 -299.518685) (xy 53.343778 -299.501233) (xy 53.301157 -299.476626) (xy 53.263036 -299.445501)
			(xy 53.230401 -299.408664) (xy 53.204098 -299.367068) (xy 53.184807 -299.321792) (xy 53.17303 -299.274008)
			(xy 53.16907 -299.224954) (xy 52.830222 -299.224954) (xy 52.829727 -299.249561) (xy 52.821832 -299.298138)
			(xy 52.806248 -299.344819) (xy 52.783377 -299.388396) (xy 52.753812 -299.42774) (xy 52.718319 -299.461832)
			(xy 52.677816 -299.489788) (xy 52.633354 -299.510886) (xy 52.586083 -299.524578) (xy 52.537228 -299.53051)
			(xy 52.488053 -299.528529) (xy 52.439834 -299.518685) (xy 52.393818 -299.501233) (xy 52.351197 -299.476626)
			(xy 52.313076 -299.445501) (xy 52.280441 -299.408664) (xy 52.254138 -299.367068) (xy 52.234847 -299.321792)
			(xy 52.22307 -299.274008) (xy 52.21911 -299.224954) (xy 51.880262 -299.224954) (xy 51.879767 -299.249561)
			(xy 51.871872 -299.298138) (xy 51.856288 -299.344819) (xy 51.833417 -299.388396) (xy 51.803852 -299.42774)
			(xy 51.768359 -299.461832) (xy 51.727856 -299.489788) (xy 51.683394 -299.510886) (xy 51.636123 -299.524578)
			(xy 51.587268 -299.53051) (xy 51.538093 -299.528529) (xy 51.489874 -299.518685) (xy 51.443858 -299.501233)
			(xy 51.401237 -299.476626) (xy 51.363116 -299.445501) (xy 51.330481 -299.408664) (xy 51.304178 -299.367068)
			(xy 51.284887 -299.321792) (xy 51.27311 -299.274008) (xy 51.26915 -299.224954) (xy 50.930302 -299.224954)
			(xy 50.929807 -299.249561) (xy 50.921912 -299.298138) (xy 50.906328 -299.344819) (xy 50.883457 -299.388396)
			(xy 50.853892 -299.42774) (xy 50.818399 -299.461832) (xy 50.777896 -299.489788) (xy 50.733434 -299.510886)
			(xy 50.686163 -299.524578) (xy 50.637308 -299.53051) (xy 50.588133 -299.528529) (xy 50.539914 -299.518685)
			(xy 50.493898 -299.501233) (xy 50.451277 -299.476626) (xy 50.413156 -299.445501) (xy 50.380521 -299.408664)
			(xy 50.354218 -299.367068) (xy 50.334927 -299.321792) (xy 50.32315 -299.274008) (xy 50.31919 -299.224954)
			(xy 49.980088 -299.224954) (xy 49.979593 -299.249561) (xy 49.971698 -299.298138) (xy 49.956114 -299.344819)
			(xy 49.933243 -299.388396) (xy 49.903678 -299.42774) (xy 49.868185 -299.461832) (xy 49.827682 -299.489788)
			(xy 49.78322 -299.510886) (xy 49.735949 -299.524578) (xy 49.687094 -299.53051) (xy 49.637919 -299.528529)
			(xy 49.5897 -299.518685) (xy 49.543684 -299.501233) (xy 49.501063 -299.476626) (xy 49.462942 -299.445501)
			(xy 49.430307 -299.408664) (xy 49.404004 -299.367068) (xy 49.384713 -299.321792) (xy 49.372936 -299.274008)
			(xy 49.368976 -299.224954) (xy 49.030128 -299.224954) (xy 49.029633 -299.249561) (xy 49.021738 -299.298138)
			(xy 49.006154 -299.344819) (xy 48.983283 -299.388396) (xy 48.953718 -299.42774) (xy 48.918225 -299.461832)
			(xy 48.877722 -299.489788) (xy 48.83326 -299.510886) (xy 48.785989 -299.524578) (xy 48.737134 -299.53051)
			(xy 48.687959 -299.528529) (xy 48.63974 -299.518685) (xy 48.593724 -299.501233) (xy 48.551103 -299.476626)
			(xy 48.512982 -299.445501) (xy 48.480347 -299.408664) (xy 48.454044 -299.367068) (xy 48.434753 -299.321792)
			(xy 48.422976 -299.274008) (xy 48.419016 -299.224954) (xy 48.080168 -299.224954) (xy 48.079673 -299.249561)
			(xy 48.071778 -299.298138) (xy 48.056194 -299.344819) (xy 48.033323 -299.388396) (xy 48.003758 -299.42774)
			(xy 47.968265 -299.461832) (xy 47.927762 -299.489788) (xy 47.8833 -299.510886) (xy 47.836029 -299.524578)
			(xy 47.787174 -299.53051) (xy 47.737999 -299.528529) (xy 47.68978 -299.518685) (xy 47.643764 -299.501233)
			(xy 47.601143 -299.476626) (xy 47.563022 -299.445501) (xy 47.530387 -299.408664) (xy 47.504084 -299.367068)
			(xy 47.484793 -299.321792) (xy 47.473016 -299.274008) (xy 47.469056 -299.224954) (xy 47.130208 -299.224954)
			(xy 47.129713 -299.249561) (xy 47.121818 -299.298138) (xy 47.106234 -299.344819) (xy 47.083363 -299.388396)
			(xy 47.053798 -299.42774) (xy 47.018305 -299.461832) (xy 46.977802 -299.489788) (xy 46.93334 -299.510886)
			(xy 46.886069 -299.524578) (xy 46.837214 -299.53051) (xy 46.788039 -299.528529) (xy 46.73982 -299.518685)
			(xy 46.693804 -299.501233) (xy 46.651183 -299.476626) (xy 46.613062 -299.445501) (xy 46.580427 -299.408664)
			(xy 46.554124 -299.367068) (xy 46.534833 -299.321792) (xy 46.523056 -299.274008) (xy 46.519096 -299.224954)
			(xy 46.180248 -299.224954) (xy 46.179753 -299.249561) (xy 46.171858 -299.298138) (xy 46.156274 -299.344819)
			(xy 46.133403 -299.388396) (xy 46.103838 -299.42774) (xy 46.068345 -299.461832) (xy 46.027842 -299.489788)
			(xy 45.98338 -299.510886) (xy 45.936109 -299.524578) (xy 45.887254 -299.53051) (xy 45.838079 -299.528529)
			(xy 45.78986 -299.518685) (xy 45.743844 -299.501233) (xy 45.701223 -299.476626) (xy 45.663102 -299.445501)
			(xy 45.630467 -299.408664) (xy 45.604164 -299.367068) (xy 45.584873 -299.321792) (xy 45.573096 -299.274008)
			(xy 45.569136 -299.224954) (xy 45.230288 -299.224954) (xy 45.229793 -299.249561) (xy 45.221898 -299.298138)
			(xy 45.206314 -299.344819) (xy 45.183443 -299.388396) (xy 45.153878 -299.42774) (xy 45.118385 -299.461832)
			(xy 45.077882 -299.489788) (xy 45.03342 -299.510886) (xy 44.986149 -299.524578) (xy 44.937294 -299.53051)
			(xy 44.888119 -299.528529) (xy 44.8399 -299.518685) (xy 44.793884 -299.501233) (xy 44.751263 -299.476626)
			(xy 44.713142 -299.445501) (xy 44.680507 -299.408664) (xy 44.654204 -299.367068) (xy 44.634913 -299.321792)
			(xy 44.623136 -299.274008) (xy 44.619176 -299.224954) (xy 44.280074 -299.224954) (xy 44.279579 -299.249561)
			(xy 44.271684 -299.298138) (xy 44.2561 -299.344819) (xy 44.233229 -299.388396) (xy 44.203664 -299.42774)
			(xy 44.168171 -299.461832) (xy 44.127668 -299.489788) (xy 44.083206 -299.510886) (xy 44.035935 -299.524578)
			(xy 43.98708 -299.53051) (xy 43.937905 -299.528529) (xy 43.889686 -299.518685) (xy 43.84367 -299.501233)
			(xy 43.801049 -299.476626) (xy 43.762928 -299.445501) (xy 43.730293 -299.408664) (xy 43.70399 -299.367068)
			(xy 43.684699 -299.321792) (xy 43.672922 -299.274008) (xy 43.668962 -299.224954) (xy 42.380149 -299.224954)
			(xy 42.379659 -299.249307) (xy 42.371764 -299.297884) (xy 42.35618 -299.344565) (xy 42.333309 -299.388142)
			(xy 42.303744 -299.427486) (xy 42.268251 -299.461578) (xy 42.227748 -299.489534) (xy 42.183286 -299.510632)
			(xy 42.136015 -299.524324) (xy 42.08716 -299.530256) (xy 42.037985 -299.528275) (xy 41.989766 -299.518431)
			(xy 41.94375 -299.500979) (xy 41.901129 -299.476372) (xy 41.863008 -299.445247) (xy 41.830373 -299.40841)
			(xy 41.80407 -299.366814) (xy 41.784779 -299.321538) (xy 41.773002 -299.273754) (xy 41.769042 -299.2247)
			(xy 41.4302 -299.2247) (xy 41.427944 -299.266297) (xy 41.41727 -299.314782) (xy 41.398893 -299.360901)
			(xy 41.373296 -299.40344) (xy 41.341154 -299.441276) (xy 41.303314 -299.473414) (xy 41.260772 -299.499007)
			(xy 41.214651 -299.51738) (xy 41.166165 -299.528048) (xy 41.116592 -299.530732) (xy 41.067237 -299.52536)
			(xy 41.019402 -299.512074) (xy 40.974346 -299.491223) (xy 40.933258 -299.463358) (xy 40.897219 -299.429212)
			(xy 40.86718 -299.389686) (xy 40.843931 -299.34582) (xy 40.828085 -299.29877) (xy 40.82006 -299.249777)
			(xy 40.819578 -299.224954) (xy 40.819668 -299.21585) (xy 40.820814 -299.197676) (xy 40.821864 -299.188632)
			(xy 40.821864 -299.188378) (xy 40.822642 -299.176582) (xy 40.814695 -299.154345) (xy 40.806624 -299.145706)
			(xy 40.73906 -299.08119) (xy 40.7162 -299.074078) (xy 40.704262 -299.07611) (xy 40.690769 -299.078172)
			(xy 40.663556 -299.08033) (xy 40.649906 -299.080428) (xy 39.699946 -299.080428) (xy 39.673951 -299.07991)
			(xy 39.6226 -299.071787) (xy 39.573151 -299.055733) (xy 39.526821 -299.032144) (xy 39.48475 -299.0016)
			(xy 39.447973 -298.964853) (xy 39.417395 -298.922806) (xy 39.393769 -298.876495) (xy 39.377675 -298.827059)
			(xy 39.369511 -298.775714) (xy 39.368984 -298.74972) (xy 39.369139 -298.736066) (xy 39.371427 -298.708852)
			(xy 39.373556 -298.695364) (xy 39.375588 -298.683426) (xy 39.368476 -298.660566) (xy 39.295324 -298.584366)
			(xy 39.272972 -298.576238) (xy 39.261034 -298.577762) (xy 39.252053 -298.578801) (xy 39.234007 -298.579944)
			(xy 39.224966 -298.580048) (xy 39.200086 -298.579555) (xy 39.150982 -298.5715) (xy 39.103834 -298.555592)
			(xy 39.059888 -298.532252) (xy 39.0398 -298.517564) (xy 39.031599 -298.511756) (xy 39.012191 -298.506588)
			(xy 38.992291 -298.509297) (xy 38.983412 -298.514008) (xy 38.959254 -298.527534) (xy 38.907336 -298.546754)
			(xy 38.85285 -298.556558) (xy 38.82517 -298.557188) (xy 38.674548 -298.557188) (xy 38.646869 -298.556562)
			(xy 38.592385 -298.546748) (xy 38.540471 -298.527521) (xy 38.516306 -298.514008) (xy 38.507394 -298.509421)
			(xy 38.487545 -298.506784) (xy 38.468186 -298.511898) (xy 38.459918 -298.517564) (xy 38.439834 -298.532263)
			(xy 38.395892 -298.555623) (xy 38.348743 -298.571549) (xy 38.299635 -298.579619) (xy 38.249869 -298.579619)
			(xy 38.200761 -298.571549) (xy 38.153612 -298.555623) (xy 38.10967 -298.532263) (xy 38.089586 -298.517564)
			(xy 38.081392 -298.511744) (xy 38.06198 -298.50658) (xy 38.042077 -298.509294) (xy 38.033198 -298.514008)
			(xy 38.009043 -298.527539) (xy 37.957124 -298.546757) (xy 37.902636 -298.556559) (xy 37.874956 -298.557188)
			(xy 37.724334 -298.557188) (xy 37.696655 -298.556568) (xy 37.642171 -298.546751) (xy 37.590256 -298.527522)
			(xy 37.566092 -298.514008) (xy 37.557186 -298.509409) (xy 37.537333 -298.506775) (xy 37.517972 -298.511895)
			(xy 37.509704 -298.517564) (xy 37.48962 -298.532263) (xy 37.445678 -298.555623) (xy 37.398529 -298.571549)
			(xy 37.349421 -298.579619) (xy 37.299655 -298.579619) (xy 37.250547 -298.571549) (xy 37.203398 -298.555623)
			(xy 37.159456 -298.532263) (xy 37.139372 -298.517564) (xy 37.131135 -298.511815) (xy 37.111749 -298.506629)
			(xy 37.091861 -298.509312) (xy 37.082984 -298.514008) (xy 37.058812 -298.527507) (xy 37.006901 -298.546736)
			(xy 36.95242 -298.556551) (xy 36.924742 -298.557188) (xy 33.742376 -298.557188) (xy 33.717745 -298.556669)
			(xy 33.669103 -298.548869) (xy 33.622279 -298.533559) (xy 33.578424 -298.511116) (xy 33.538618 -298.482091)
			(xy 33.520888 -298.464986) (xy 33.39592 -298.340018) (xy 33.378843 -298.322275) (xy 33.349874 -298.282456)
			(xy 33.327486 -298.238598) (xy 33.312229 -298.191779) (xy 33.30448 -298.14315) (xy 33.303972 -298.11853)
			(xy 33.303972 -298.051474) (xy 33.304339 -298.029588) (xy 33.310459 -297.986247) (xy 33.316164 -297.965114)
			(xy 33.318196 -297.958256) (xy 33.318196 -297.688762) (xy 33.317568 -297.677537) (xy 33.30794 -297.657246)
			(xy 33.299654 -297.649646) (xy 33.238694 -297.5991) (xy 33.216342 -297.593512) (xy 33.205166 -297.595798)
			(xy 33.186688 -297.599237) (xy 33.149283 -297.602929) (xy 33.13049 -297.603164) (xy 33.130236 -297.603164)
			(xy 33.102978 -297.602792) (xy 33.049017 -297.595038) (xy 32.996709 -297.579683) (xy 32.947119 -297.55704)
			(xy 32.901256 -297.52757) (xy 32.860054 -297.491872) (xy 32.824352 -297.450673) (xy 32.794877 -297.404813)
			(xy 32.77223 -297.355225) (xy 32.75687 -297.302918) (xy 32.749111 -297.248958) (xy 32.749111 -297.194442)
			(xy 32.75687 -297.140482) (xy 32.77223 -297.088175) (xy 32.794877 -297.038587) (xy 32.824352 -296.992727)
			(xy 32.860054 -296.951528) (xy 32.901256 -296.91583) (xy 32.947119 -296.88636) (xy 32.996709 -296.863717)
			(xy 33.049017 -296.848362) (xy 33.102978 -296.840608) (xy 33.130236 -296.840148) (xy 33.160267 -296.840708)
			(xy 33.219589 -296.8501) (xy 33.276709 -296.868664) (xy 33.303718 -296.881804) (xy 33.303972 -296.881804)
			(xy 33.311761 -296.885429) (xy 33.328769 -296.887768) (xy 33.337246 -296.886376) (xy 33.363408 -296.881042)
			(xy 33.378648 -296.87139) (xy 33.384236 -296.864024) (xy 33.400211 -296.844304) (xy 33.437412 -296.809787)
			(xy 33.479682 -296.781707) (xy 33.5026 -296.770806) (xy 33.58134 -296.735246) (xy 33.597596 -296.7101)
			(xy 33.597596 -296.695114) (xy 33.597161 -296.685376) (xy 33.589829 -296.667327) (xy 33.576323 -296.653288)
			(xy 33.567624 -296.648886) (xy 33.432242 -296.587672) (xy 33.425672 -296.584434) (xy 33.414565 -296.574898)
			(xy 33.410398 -296.568876) (xy 33.370266 -296.5069) (xy 33.366202 -296.49928) (xy 33.328356 -296.410888)
			(xy 33.320578 -296.391474) (xy 33.309675 -296.351096) (xy 33.304248 -296.309627) (xy 33.303972 -296.288714)
			(xy 33.303972 -295.895014) (xy 33.303547 -295.884945) (xy 33.295827 -295.866346) (xy 33.288986 -295.858946)
			(xy 33.133538 -295.703498) (xy 33.126119 -295.696682) (xy 33.107534 -295.688948) (xy 33.09747 -295.688512)
			(xy 32.183832 -295.688512) (xy 32.171769 -295.689199) (xy 32.150295 -295.700209) (xy 32.142684 -295.709594)
			(xy 32.093408 -295.77792) (xy 32.089598 -295.80205) (xy 32.093408 -295.81348) (xy 32.102284 -295.842394)
			(xy 32.111857 -295.902112) (xy 32.112458 -295.932352) (xy 32.112458 -295.933114) (xy 32.111954 -295.95969)
			(xy 32.104562 -296.012325) (xy 32.089937 -296.063426) (xy 32.068363 -296.112002) (xy 32.040256 -296.157115)
			(xy 32.006161 -296.19789) (xy 31.966737 -296.23354) (xy 31.922747 -296.263373) (xy 31.899098 -296.275506)
			(xy 31.898844 -296.275506) (xy 31.887992 -296.281538) (xy 31.87349 -296.301663) (xy 31.871158 -296.31386)
			(xy 31.858966 -296.396918) (xy 31.857765 -296.409299) (xy 31.866013 -296.432734) (xy 31.874714 -296.441622)
			(xy 31.874968 -296.441622) (xy 31.893963 -296.459769) (xy 31.927348 -296.500326) (xy 31.95485 -296.545083)
			(xy 31.975947 -296.593191) (xy 31.990241 -296.64374) (xy 31.997461 -296.695773) (xy 31.997904 -296.722038)
			(xy 31.997418 -296.749289) (xy 31.989662 -296.803237) (xy 31.974307 -296.855532) (xy 31.951665 -296.905109)
			(xy 31.922199 -296.950959) (xy 31.886508 -296.99215) (xy 31.845317 -297.027841) (xy 31.799467 -297.057307)
			(xy 31.74989 -297.079949) (xy 31.697595 -297.095304) (xy 31.643647 -297.10306) (xy 31.589145 -297.10306)
			(xy 31.535197 -297.095304) (xy 31.482902 -297.079949) (xy 31.433325 -297.057307) (xy 31.387475 -297.027841)
			(xy 31.346284 -296.99215) (xy 31.310593 -296.950959) (xy 31.281127 -296.905109) (xy 31.258485 -296.855532)
			(xy 31.24313 -296.803237) (xy 31.235374 -296.749289) (xy 31.234888 -296.722038) (xy 31.235327 -296.69546)
			(xy 31.242726 -296.64282) (xy 31.257359 -296.591717) (xy 31.278942 -296.543139) (xy 31.307058 -296.498026)
			(xy 31.341163 -296.457252) (xy 31.380596 -296.421605) (xy 31.424594 -296.391776) (xy 31.448248 -296.379646)
			(xy 31.448502 -296.379646) (xy 31.459324 -296.373571) (xy 31.473843 -296.353478) (xy 31.476188 -296.341292)
			(xy 31.48838 -296.258234) (xy 31.489598 -296.245854) (xy 31.481336 -296.222418) (xy 31.472632 -296.21353)
			(xy 31.472378 -296.21353) (xy 31.45335 -296.195417) (xy 31.419969 -296.154851) (xy 31.392474 -296.110087)
			(xy 31.371382 -296.061972) (xy 31.357095 -296.011418) (xy 31.349882 -295.959381) (xy 31.349442 -295.933114)
			(xy 31.349922 -295.90571) (xy 31.357769 -295.851466) (xy 31.373302 -295.798904) (xy 31.396202 -295.749109)
			(xy 31.425996 -295.703106) (xy 31.443676 -295.682162) (xy 31.44393 -295.681908) (xy 31.449686 -295.674549)
			(xy 31.455939 -295.656959) (xy 31.456122 -295.647618) (xy 31.455868 -295.628314) (xy 31.455168 -295.618589)
			(xy 31.44748 -295.600693) (xy 31.440882 -295.593516) (xy 31.276036 -295.428416) (xy 31.259041 -295.410693)
			(xy 31.230221 -295.370941) (xy 31.207955 -295.327179) (xy 31.192788 -295.28048) (xy 31.185092 -295.231986)
			(xy 31.184596 -295.207436) (xy 31.184596 -293.181024) (xy 31.18515 -293.156395) (xy 31.192942 -293.107754)
			(xy 31.208244 -293.06093) (xy 31.230679 -293.017075) (xy 31.259696 -292.977268) (xy 31.276798 -292.959536)
			(xy 31.280354 -292.95598) (xy 31.291313 -292.945214) (xy 31.314974 -292.925618) (xy 31.327598 -292.916864)
			(xy 31.360872 -292.894512) (xy 31.372048 -292.863016) (xy 31.366968 -292.84676) (xy 31.358793 -292.81896)
			(xy 31.349997 -292.761686) (xy 31.349442 -292.732714) (xy 31.349684 -292.712235) (xy 31.354007 -292.671506)
			(xy 31.358078 -292.651434) (xy 31.359759 -292.641911) (xy 31.356609 -292.622843) (xy 31.351982 -292.61435)
			(xy 31.311088 -292.546278) (xy 31.295594 -292.534594) (xy 31.28645 -292.532054) (xy 31.261452 -292.524507)
			(xy 31.214313 -292.502053) (xy 31.171672 -292.471917) (xy 31.152846 -292.453822) (xy 31.084266 -292.385242)
			(xy 31.067583 -292.367978) (xy 31.039337 -292.32916) (xy 31.01751 -292.286402) (xy 31.00264 -292.240756)
			(xy 30.995094 -292.193345) (xy 30.994604 -292.169342) (xy 1.420114 -292.169342) (xy 1.420114 -292.732714)
			(xy 25.811478 -292.732714) (xy 25.815549 -292.677092) (xy 25.827675 -292.622655) (xy 25.847598 -292.570564)
			(xy 25.874894 -292.521929) (xy 25.90898 -292.477786) (xy 25.949129 -292.439077) (xy 25.994487 -292.406626)
			(xy 26.044087 -292.381125) (xy 26.096871 -292.363118) (xy 26.151714 -292.352988) (xy 26.207448 -292.350951)
			(xy 26.262885 -292.357051) (xy 26.316842 -292.371157) (xy 26.368171 -292.392969) (xy 26.415777 -292.422023)
			(xy 26.458645 -292.457698) (xy 26.495862 -292.499235) (xy 26.526635 -292.545748) (xy 26.550307 -292.596245)
			(xy 26.566375 -292.649652) (xy 26.574495 -292.704828) (xy 26.575004 -292.732714) (xy 27.286964 -292.732714)
			(xy 27.291035 -292.677092) (xy 27.303161 -292.622655) (xy 27.323084 -292.570564) (xy 27.35038 -292.521929)
			(xy 27.384466 -292.477786) (xy 27.424615 -292.439077) (xy 27.469973 -292.406626) (xy 27.519573 -292.381125)
			(xy 27.572357 -292.363118) (xy 27.6272 -292.352988) (xy 27.682934 -292.350951) (xy 27.738371 -292.357051)
			(xy 27.792328 -292.371157) (xy 27.843657 -292.392969) (xy 27.891263 -292.422023) (xy 27.934131 -292.457698)
			(xy 27.971348 -292.499235) (xy 28.002121 -292.545748) (xy 28.025793 -292.596245) (xy 28.041861 -292.649652)
			(xy 28.049981 -292.704828) (xy 28.05049 -292.732714) (xy 28.175964 -292.732714) (xy 28.180035 -292.677092)
			(xy 28.192161 -292.622655) (xy 28.212084 -292.570564) (xy 28.23938 -292.521929) (xy 28.273466 -292.477786)
			(xy 28.313615 -292.439077) (xy 28.358973 -292.406626) (xy 28.408573 -292.381125) (xy 28.461357 -292.363118)
			(xy 28.5162 -292.352988) (xy 28.571934 -292.350951) (xy 28.627371 -292.357051) (xy 28.681328 -292.371157)
			(xy 28.732657 -292.392969) (xy 28.780263 -292.422023) (xy 28.823131 -292.457698) (xy 28.860348 -292.499235)
			(xy 28.891121 -292.545748) (xy 28.914793 -292.596245) (xy 28.930861 -292.649652) (xy 28.938981 -292.704828)
			(xy 28.93949 -292.732714) (xy 28.938981 -292.7606) (xy 28.930861 -292.815776) (xy 28.914793 -292.869183)
			(xy 28.891121 -292.91968) (xy 28.860348 -292.966193) (xy 28.823131 -293.00773) (xy 28.780263 -293.043405)
			(xy 28.732657 -293.072459) (xy 28.681328 -293.094271) (xy 28.627371 -293.108377) (xy 28.571934 -293.114477)
			(xy 28.5162 -293.11244) (xy 28.461357 -293.10231) (xy 28.408573 -293.084303) (xy 28.358973 -293.058802)
			(xy 28.313615 -293.026351) (xy 28.273466 -292.987642) (xy 28.23938 -292.943499) (xy 28.212084 -292.894864)
			(xy 28.192161 -292.842773) (xy 28.180035 -292.788336) (xy 28.175964 -292.732714) (xy 28.05049 -292.732714)
			(xy 28.049981 -292.7606) (xy 28.041861 -292.815776) (xy 28.025793 -292.869183) (xy 28.002121 -292.91968)
			(xy 27.971348 -292.966193) (xy 27.934131 -293.00773) (xy 27.891263 -293.043405) (xy 27.843657 -293.072459)
			(xy 27.792328 -293.094271) (xy 27.738371 -293.108377) (xy 27.682934 -293.114477) (xy 27.6272 -293.11244)
			(xy 27.572357 -293.10231) (xy 27.519573 -293.084303) (xy 27.469973 -293.058802) (xy 27.424615 -293.026351)
			(xy 27.384466 -292.987642) (xy 27.35038 -292.943499) (xy 27.323084 -292.894864) (xy 27.303161 -292.842773)
			(xy 27.291035 -292.788336) (xy 27.286964 -292.732714) (xy 26.575004 -292.732714) (xy 26.574495 -292.7606)
			(xy 26.566375 -292.815776) (xy 26.550307 -292.869183) (xy 26.526635 -292.91968) (xy 26.495862 -292.966193)
			(xy 26.458645 -293.00773) (xy 26.415777 -293.043405) (xy 26.368171 -293.072459) (xy 26.316842 -293.094271)
			(xy 26.262885 -293.108377) (xy 26.207448 -293.114477) (xy 26.151714 -293.11244) (xy 26.096871 -293.10231)
			(xy 26.044087 -293.084303) (xy 25.994487 -293.058802) (xy 25.949129 -293.026351) (xy 25.90898 -292.987642)
			(xy 25.874894 -292.943499) (xy 25.847598 -292.894864) (xy 25.827675 -292.842773) (xy 25.815549 -292.788336)
			(xy 25.811478 -292.732714) (xy 1.420114 -292.732714) (xy 1.420114 -294.630856) (xy 25.811478 -294.630856)
			(xy 25.815549 -294.575234) (xy 25.827675 -294.520797) (xy 25.847598 -294.468706) (xy 25.874894 -294.420071)
			(xy 25.90898 -294.375928) (xy 25.949129 -294.337219) (xy 25.994487 -294.304768) (xy 26.044087 -294.279267)
			(xy 26.096871 -294.26126) (xy 26.151714 -294.25113) (xy 26.207448 -294.249093) (xy 26.262885 -294.255193)
			(xy 26.316842 -294.269299) (xy 26.368171 -294.291111) (xy 26.415777 -294.320165) (xy 26.458645 -294.35584)
			(xy 26.495862 -294.397377) (xy 26.526635 -294.44389) (xy 26.550307 -294.494387) (xy 26.566375 -294.547794)
			(xy 26.574495 -294.60297) (xy 26.575004 -294.630856) (xy 27.296616 -294.630856) (xy 27.300687 -294.575234)
			(xy 27.312813 -294.520797) (xy 27.332736 -294.468706) (xy 27.360032 -294.420071) (xy 27.394118 -294.375928)
			(xy 27.434267 -294.337219) (xy 27.479625 -294.304768) (xy 27.529225 -294.279267) (xy 27.582009 -294.26126)
			(xy 27.636852 -294.25113) (xy 27.692586 -294.249093) (xy 27.748023 -294.255193) (xy 27.80198 -294.269299)
			(xy 27.853309 -294.291111) (xy 27.900915 -294.320165) (xy 27.943783 -294.35584) (xy 27.981 -294.397377)
			(xy 28.011773 -294.44389) (xy 28.035445 -294.494387) (xy 28.051513 -294.547794) (xy 28.059633 -294.60297)
			(xy 28.060142 -294.630856) (xy 28.059633 -294.658742) (xy 28.051513 -294.713918) (xy 28.035445 -294.767325)
			(xy 28.011773 -294.817822) (xy 27.981 -294.864335) (xy 27.943783 -294.905872) (xy 27.900915 -294.941547)
			(xy 27.853309 -294.970601) (xy 27.80198 -294.992413) (xy 27.748023 -295.006519) (xy 27.692586 -295.012619)
			(xy 27.636852 -295.010582) (xy 27.582009 -295.000452) (xy 27.529225 -294.982445) (xy 27.479625 -294.956944)
			(xy 27.434267 -294.924493) (xy 27.394118 -294.885784) (xy 27.360032 -294.841641) (xy 27.332736 -294.793006)
			(xy 27.312813 -294.740915) (xy 27.300687 -294.686478) (xy 27.296616 -294.630856) (xy 26.575004 -294.630856)
			(xy 26.574495 -294.658742) (xy 26.566375 -294.713918) (xy 26.550307 -294.767325) (xy 26.526635 -294.817822)
			(xy 26.495862 -294.864335) (xy 26.458645 -294.905872) (xy 26.415777 -294.941547) (xy 26.368171 -294.970601)
			(xy 26.316842 -294.992413) (xy 26.262885 -295.006519) (xy 26.207448 -295.012619) (xy 26.151714 -295.010582)
			(xy 26.096871 -295.000452) (xy 26.044087 -294.982445) (xy 25.994487 -294.956944) (xy 25.949129 -294.924493)
			(xy 25.90898 -294.885784) (xy 25.874894 -294.841641) (xy 25.847598 -294.793006) (xy 25.827675 -294.740915)
			(xy 25.815549 -294.686478) (xy 25.811478 -294.630856) (xy 1.420114 -294.630856) (xy 1.420114 -295.933114)
			(xy 25.811478 -295.933114) (xy 25.815549 -295.877492) (xy 25.827675 -295.823055) (xy 25.847598 -295.770964)
			(xy 25.874894 -295.722329) (xy 25.90898 -295.678186) (xy 25.949129 -295.639477) (xy 25.994487 -295.607026)
			(xy 26.044087 -295.581525) (xy 26.096871 -295.563518) (xy 26.151714 -295.553388) (xy 26.207448 -295.551351)
			(xy 26.262885 -295.557451) (xy 26.316842 -295.571557) (xy 26.368171 -295.593369) (xy 26.415777 -295.622423)
			(xy 26.458645 -295.658098) (xy 26.495862 -295.699635) (xy 26.526635 -295.746148) (xy 26.550307 -295.796645)
			(xy 26.566375 -295.850052) (xy 26.574495 -295.905228) (xy 26.575004 -295.933114) (xy 27.286964 -295.933114)
			(xy 27.291035 -295.877492) (xy 27.303161 -295.823055) (xy 27.323084 -295.770964) (xy 27.35038 -295.722329)
			(xy 27.384466 -295.678186) (xy 27.424615 -295.639477) (xy 27.469973 -295.607026) (xy 27.519573 -295.581525)
			(xy 27.572357 -295.563518) (xy 27.6272 -295.553388) (xy 27.682934 -295.551351) (xy 27.738371 -295.557451)
			(xy 27.792328 -295.571557) (xy 27.843657 -295.593369) (xy 27.891263 -295.622423) (xy 27.934131 -295.658098)
			(xy 27.971348 -295.699635) (xy 28.002121 -295.746148) (xy 28.025793 -295.796645) (xy 28.041861 -295.850052)
			(xy 28.049981 -295.905228) (xy 28.05049 -295.933114) (xy 28.175964 -295.933114) (xy 28.180035 -295.877492)
			(xy 28.192161 -295.823055) (xy 28.212084 -295.770964) (xy 28.23938 -295.722329) (xy 28.273466 -295.678186)
			(xy 28.313615 -295.639477) (xy 28.358973 -295.607026) (xy 28.408573 -295.581525) (xy 28.461357 -295.563518)
			(xy 28.5162 -295.553388) (xy 28.571934 -295.551351) (xy 28.627371 -295.557451) (xy 28.681328 -295.571557)
			(xy 28.732657 -295.593369) (xy 28.780263 -295.622423) (xy 28.823131 -295.658098) (xy 28.860348 -295.699635)
			(xy 28.891121 -295.746148) (xy 28.914793 -295.796645) (xy 28.930861 -295.850052) (xy 28.938981 -295.905228)
			(xy 28.93949 -295.933114) (xy 28.938981 -295.961) (xy 28.930861 -296.016176) (xy 28.914793 -296.069583)
			(xy 28.891121 -296.12008) (xy 28.860348 -296.166593) (xy 28.823131 -296.20813) (xy 28.780263 -296.243805)
			(xy 28.732657 -296.272859) (xy 28.681328 -296.294671) (xy 28.627371 -296.308777) (xy 28.571934 -296.314877)
			(xy 28.5162 -296.31284) (xy 28.461357 -296.30271) (xy 28.408573 -296.284703) (xy 28.358973 -296.259202)
			(xy 28.313615 -296.226751) (xy 28.273466 -296.188042) (xy 28.23938 -296.143899) (xy 28.212084 -296.095264)
			(xy 28.192161 -296.043173) (xy 28.180035 -295.988736) (xy 28.175964 -295.933114) (xy 28.05049 -295.933114)
			(xy 28.049981 -295.961) (xy 28.041861 -296.016176) (xy 28.025793 -296.069583) (xy 28.002121 -296.12008)
			(xy 27.971348 -296.166593) (xy 27.934131 -296.20813) (xy 27.891263 -296.243805) (xy 27.843657 -296.272859)
			(xy 27.792328 -296.294671) (xy 27.738371 -296.308777) (xy 27.682934 -296.314877) (xy 27.6272 -296.31284)
			(xy 27.572357 -296.30271) (xy 27.519573 -296.284703) (xy 27.469973 -296.259202) (xy 27.424615 -296.226751)
			(xy 27.384466 -296.188042) (xy 27.35038 -296.143899) (xy 27.323084 -296.095264) (xy 27.303161 -296.043173)
			(xy 27.291035 -295.988736) (xy 27.286964 -295.933114) (xy 26.575004 -295.933114) (xy 26.574495 -295.961)
			(xy 26.566375 -296.016176) (xy 26.550307 -296.069583) (xy 26.526635 -296.12008) (xy 26.495862 -296.166593)
			(xy 26.458645 -296.20813) (xy 26.415777 -296.243805) (xy 26.368171 -296.272859) (xy 26.316842 -296.294671)
			(xy 26.262885 -296.308777) (xy 26.207448 -296.314877) (xy 26.151714 -296.31284) (xy 26.096871 -296.30271)
			(xy 26.044087 -296.284703) (xy 25.994487 -296.259202) (xy 25.949129 -296.226751) (xy 25.90898 -296.188042)
			(xy 25.874894 -296.143899) (xy 25.847598 -296.095264) (xy 25.827675 -296.043173) (xy 25.815549 -295.988736)
			(xy 25.811478 -295.933114) (xy 1.420114 -295.933114) (xy 1.420114 -297.1292) (xy 1.420287 -297.135208)
			(xy 1.423122 -297.146885) (xy 1.425702 -297.152314) (xy 1.427541 -297.155788) (xy 1.432135 -297.162167)
			(xy 1.434846 -297.165014) (xy 2.101088 -297.831256) (xy 25.811478 -297.831256) (xy 25.815549 -297.775634)
			(xy 25.827675 -297.721197) (xy 25.847598 -297.669106) (xy 25.874894 -297.620471) (xy 25.90898 -297.576328)
			(xy 25.949129 -297.537619) (xy 25.994487 -297.505168) (xy 26.044087 -297.479667) (xy 26.096871 -297.46166)
			(xy 26.151714 -297.45153) (xy 26.207448 -297.449493) (xy 26.262885 -297.455593) (xy 26.316842 -297.469699)
			(xy 26.368171 -297.491511) (xy 26.415777 -297.520565) (xy 26.458645 -297.55624) (xy 26.495862 -297.597777)
			(xy 26.526635 -297.64429) (xy 26.550307 -297.694787) (xy 26.566375 -297.748194) (xy 26.574495 -297.80337)
			(xy 26.575004 -297.831256) (xy 27.296616 -297.831256) (xy 27.300687 -297.775634) (xy 27.312813 -297.721197)
			(xy 27.332736 -297.669106) (xy 27.360032 -297.620471) (xy 27.394118 -297.576328) (xy 27.434267 -297.537619)
			(xy 27.479625 -297.505168) (xy 27.529225 -297.479667) (xy 27.582009 -297.46166) (xy 27.636852 -297.45153)
			(xy 27.692586 -297.449493) (xy 27.748023 -297.455593) (xy 27.80198 -297.469699) (xy 27.853309 -297.491511)
			(xy 27.900915 -297.520565) (xy 27.943783 -297.55624) (xy 27.981 -297.597777) (xy 28.011773 -297.64429)
			(xy 28.035445 -297.694787) (xy 28.051513 -297.748194) (xy 28.059633 -297.80337) (xy 28.060142 -297.831256)
			(xy 28.059633 -297.859142) (xy 28.051513 -297.914318) (xy 28.035445 -297.967725) (xy 28.011773 -298.018222)
			(xy 27.981 -298.064735) (xy 27.943783 -298.106272) (xy 27.900915 -298.141947) (xy 27.853309 -298.171001)
			(xy 27.80198 -298.192813) (xy 27.748023 -298.206919) (xy 27.692586 -298.213019) (xy 27.636852 -298.210982)
			(xy 27.582009 -298.200852) (xy 27.529225 -298.182845) (xy 27.479625 -298.157344) (xy 27.434267 -298.124893)
			(xy 27.394118 -298.086184) (xy 27.360032 -298.042041) (xy 27.332736 -297.993406) (xy 27.312813 -297.941315)
			(xy 27.300687 -297.886878) (xy 27.296616 -297.831256) (xy 26.575004 -297.831256) (xy 26.574495 -297.859142)
			(xy 26.566375 -297.914318) (xy 26.550307 -297.967725) (xy 26.526635 -298.018222) (xy 26.495862 -298.064735)
			(xy 26.458645 -298.106272) (xy 26.415777 -298.141947) (xy 26.368171 -298.171001) (xy 26.316842 -298.192813)
			(xy 26.262885 -298.206919) (xy 26.207448 -298.213019) (xy 26.151714 -298.210982) (xy 26.096871 -298.200852)
			(xy 26.044087 -298.182845) (xy 25.994487 -298.157344) (xy 25.949129 -298.124893) (xy 25.90898 -298.086184)
			(xy 25.874894 -298.042041) (xy 25.847598 -297.993406) (xy 25.827675 -297.941315) (xy 25.815549 -297.886878)
			(xy 25.811478 -297.831256) (xy 2.101088 -297.831256) (xy 2.676398 -298.406566) (xy 2.679249 -298.409272)
			(xy 2.685627 -298.413865) (xy 2.689098 -298.41571) (xy 2.694524 -298.418297) (xy 2.706203 -298.421131)
			(xy 2.712212 -298.421298) (xy 18.523458 -298.421298) (xy 18.53565 -298.419774) (xy 18.547588 -298.416726)
			(xy 18.556224 -298.413678) (xy 18.558764 -298.412408) (xy 18.632147 -298.374014) (xy 18.78206 -298.303573)
			(xy 18.935231 -298.24053) (xy 19.091295 -298.185035) (xy 19.249881 -298.137219) (xy 19.410611 -298.097198)
			(xy 19.573101 -298.065065) (xy 19.736966 -298.040898) (xy 19.901815 -298.024755) (xy 20.067255 -298.016672)
			(xy 20.150074 -298.016168) (xy 20.232097 -298.016664) (xy 20.39595 -298.024589) (xy 20.559229 -298.040422)
			(xy 20.721553 -298.064125) (xy 20.882541 -298.095643) (xy 21.04182 -298.134901) (xy 21.199015 -298.18181)
			(xy 21.353761 -298.236258) (xy 21.505695 -298.298118) (xy 21.654463 -298.367247) (xy 21.799718 -298.443483)
			(xy 21.941119 -298.526647) (xy 22.078338 -298.616546) (xy 22.211053 -298.712969) (xy 22.338955 -298.815692)
			(xy 22.461744 -298.924474) (xy 22.579134 -299.039061) (xy 22.666977 -299.133514) (xy 25.826718 -299.133514)
			(xy 25.830789 -299.077892) (xy 25.842915 -299.023455) (xy 25.862838 -298.971364) (xy 25.890134 -298.922729)
			(xy 25.92422 -298.878586) (xy 25.964369 -298.839877) (xy 26.009727 -298.807426) (xy 26.059327 -298.781925)
			(xy 26.112111 -298.763918) (xy 26.166954 -298.753788) (xy 26.222688 -298.751751) (xy 26.278125 -298.757851)
			(xy 26.332082 -298.771957) (xy 26.383411 -298.793769) (xy 26.431017 -298.822823) (xy 26.473885 -298.858498)
			(xy 26.511102 -298.900035) (xy 26.541875 -298.946548) (xy 26.565547 -298.997045) (xy 26.581615 -299.050452)
			(xy 26.589735 -299.105628) (xy 26.590244 -299.133514) (xy 27.286964 -299.133514) (xy 27.291035 -299.077892)
			(xy 27.303161 -299.023455) (xy 27.323084 -298.971364) (xy 27.35038 -298.922729) (xy 27.384466 -298.878586)
			(xy 27.424615 -298.839877) (xy 27.469973 -298.807426) (xy 27.519573 -298.781925) (xy 27.572357 -298.763918)
			(xy 27.6272 -298.753788) (xy 27.682934 -298.751751) (xy 27.738371 -298.757851) (xy 27.792328 -298.771957)
			(xy 27.843657 -298.793769) (xy 27.891263 -298.822823) (xy 27.934131 -298.858498) (xy 27.971348 -298.900035)
			(xy 28.002121 -298.946548) (xy 28.025793 -298.997045) (xy 28.041861 -299.050452) (xy 28.049981 -299.105628)
			(xy 28.05049 -299.133514) (xy 28.175964 -299.133514) (xy 28.180035 -299.077892) (xy 28.192161 -299.023455)
			(xy 28.212084 -298.971364) (xy 28.23938 -298.922729) (xy 28.273466 -298.878586) (xy 28.313615 -298.839877)
			(xy 28.358973 -298.807426) (xy 28.408573 -298.781925) (xy 28.461357 -298.763918) (xy 28.5162 -298.753788)
			(xy 28.571934 -298.751751) (xy 28.627371 -298.757851) (xy 28.681328 -298.771957) (xy 28.732657 -298.793769)
			(xy 28.780263 -298.822823) (xy 28.823131 -298.858498) (xy 28.860348 -298.900035) (xy 28.891121 -298.946548)
			(xy 28.914793 -298.997045) (xy 28.930861 -299.050452) (xy 28.938981 -299.105628) (xy 28.93949 -299.133514)
			(xy 28.938981 -299.1614) (xy 28.930861 -299.216576) (xy 28.914793 -299.269983) (xy 28.891121 -299.32048)
			(xy 28.860348 -299.366993) (xy 28.823131 -299.40853) (xy 28.780263 -299.444205) (xy 28.732657 -299.473259)
			(xy 28.681328 -299.495071) (xy 28.627371 -299.509177) (xy 28.571934 -299.515277) (xy 28.5162 -299.51324)
			(xy 28.461357 -299.50311) (xy 28.408573 -299.485103) (xy 28.358973 -299.459602) (xy 28.313615 -299.427151)
			(xy 28.273466 -299.388442) (xy 28.23938 -299.344299) (xy 28.212084 -299.295664) (xy 28.192161 -299.243573)
			(xy 28.180035 -299.189136) (xy 28.175964 -299.133514) (xy 28.05049 -299.133514) (xy 28.049981 -299.1614)
			(xy 28.041861 -299.216576) (xy 28.025793 -299.269983) (xy 28.002121 -299.32048) (xy 27.971348 -299.366993)
			(xy 27.934131 -299.40853) (xy 27.891263 -299.444205) (xy 27.843657 -299.473259) (xy 27.792328 -299.495071)
			(xy 27.738371 -299.509177) (xy 27.682934 -299.515277) (xy 27.6272 -299.51324) (xy 27.572357 -299.50311)
			(xy 27.519573 -299.485103) (xy 27.469973 -299.459602) (xy 27.424615 -299.427151) (xy 27.384466 -299.388442)
			(xy 27.35038 -299.344299) (xy 27.323084 -299.295664) (xy 27.303161 -299.243573) (xy 27.291035 -299.189136)
			(xy 27.286964 -299.133514) (xy 26.590244 -299.133514) (xy 26.589735 -299.1614) (xy 26.581615 -299.216576)
			(xy 26.565547 -299.269983) (xy 26.541875 -299.32048) (xy 26.511102 -299.366993) (xy 26.473885 -299.40853)
			(xy 26.431017 -299.444205) (xy 26.383411 -299.473259) (xy 26.332082 -299.495071) (xy 26.278125 -299.509177)
			(xy 26.222688 -299.515277) (xy 26.166954 -299.51324) (xy 26.112111 -299.50311) (xy 26.059327 -299.485103)
			(xy 26.009727 -299.459602) (xy 25.964369 -299.427151) (xy 25.92422 -299.388442) (xy 25.890134 -299.344299)
			(xy 25.862838 -299.295664) (xy 25.842915 -299.243573) (xy 25.830789 -299.189136) (xy 25.826718 -299.133514)
			(xy 22.666977 -299.133514) (xy 22.690852 -299.159186) (xy 22.796635 -299.284569) (xy 22.896237 -299.414915)
			(xy 22.989425 -299.549922) (xy 23.075981 -299.689273) (xy 23.155705 -299.832643) (xy 23.186788 -299.895514)
			(xy 31.308802 -299.895514) (xy 31.309274 -299.869238) (xy 31.31648 -299.817183) (xy 31.330758 -299.766608)
			(xy 31.351838 -299.71847) (xy 31.379322 -299.673678) (xy 31.412689 -299.633079) (xy 31.45131 -299.59744)
			(xy 31.472632 -299.582078) (xy 31.48503 -299.572838) (xy 31.503983 -299.548423) (xy 31.514782 -299.519463)
			(xy 31.516441 -299.4886) (xy 31.50881 -299.458649) (xy 31.492584 -299.432342) (xy 31.481268 -299.421804)
			(xy 31.460981 -299.4036) (xy 31.425279 -299.362414) (xy 31.395796 -299.316571) (xy 31.37313 -299.267001)
			(xy 31.357744 -299.214712) (xy 31.349949 -299.160767) (xy 31.349442 -299.133514) (xy 31.349928 -299.106263)
			(xy 31.357684 -299.052315) (xy 31.373039 -299.00002) (xy 31.395681 -298.950443) (xy 31.425147 -298.904593)
			(xy 31.460838 -298.863402) (xy 31.502029 -298.827711) (xy 31.547879 -298.798245) (xy 31.597456 -298.775603)
			(xy 31.649751 -298.760248) (xy 31.703699 -298.752492) (xy 31.758201 -298.752492) (xy 31.812149 -298.760248)
			(xy 31.864444 -298.775603) (xy 31.914021 -298.798245) (xy 31.959871 -298.827711) (xy 32.001062 -298.863402)
			(xy 32.036753 -298.904593) (xy 32.066219 -298.950443) (xy 32.088861 -299.00002) (xy 32.104216 -299.052315)
			(xy 32.111972 -299.106263) (xy 32.112458 -299.133514) (xy 32.112024 -299.159791) (xy 32.104814 -299.211849)
			(xy 32.101185 -299.2247) (xy 35.433769 -299.2247) (xy 35.43794 -299.174364) (xy 35.450338 -299.125401)
			(xy 35.470626 -299.079147) (xy 35.498251 -299.036862) (xy 35.532458 -298.999701) (xy 35.572315 -298.968676)
			(xy 35.616734 -298.944635) (xy 35.664505 -298.928232) (xy 35.714324 -298.919915) (xy 35.739578 -298.919392)
			(xy 35.764974 -298.919894) (xy 35.815064 -298.92831) (xy 35.863072 -298.944895) (xy 35.907674 -298.969195)
			(xy 35.947642 -299.000538) (xy 35.96513 -299.01896) (xy 35.972894 -299.026717) (xy 35.993023 -299.035406)
			(xy 36.003992 -299.035724) (xy 36.09213 -299.033184) (xy 36.111688 -299.023786) (xy 36.1188 -299.01515)
			(xy 36.134607 -298.996582) (xy 36.170723 -298.963822) (xy 36.211253 -298.93671) (xy 36.255319 -298.915834)
			(xy 36.30197 -298.901645) (xy 36.350198 -298.894449) (xy 36.374578 -298.893992) (xy 37.324538 -298.893992)
			(xy 37.35054 -298.894597) (xy 37.401902 -298.902737) (xy 37.451358 -298.918812) (xy 37.497691 -298.942425)
			(xy 37.539761 -298.972994) (xy 37.576531 -299.009768) (xy 37.607095 -299.051841) (xy 37.630703 -299.098177)
			(xy 37.646771 -299.147635) (xy 37.654906 -299.198998) (xy 37.654906 -299.224954) (xy 37.968948 -299.224954)
			(xy 37.972908 -299.1759) (xy 37.984685 -299.128116) (xy 38.003976 -299.08284) (xy 38.030279 -299.041244)
			(xy 38.062914 -299.004407) (xy 38.101035 -298.973282) (xy 38.143656 -298.948675) (xy 38.189672 -298.931223)
			(xy 38.237891 -298.921379) (xy 38.287066 -298.919398) (xy 38.335921 -298.92533) (xy 38.383192 -298.939022)
			(xy 38.427654 -298.96012) (xy 38.468157 -298.988076) (xy 38.50365 -299.022168) (xy 38.533215 -299.061512)
			(xy 38.556086 -299.105089) (xy 38.57167 -299.15177) (xy 38.579565 -299.200347) (xy 38.58006 -299.224954)
			(xy 38.579565 -299.249561) (xy 38.57167 -299.298138) (xy 38.556086 -299.344819) (xy 38.533215 -299.388396)
			(xy 38.50365 -299.42774) (xy 38.468157 -299.461832) (xy 38.427654 -299.489788) (xy 38.383192 -299.510886)
			(xy 38.335921 -299.524578) (xy 38.287066 -299.53051) (xy 38.237891 -299.528529) (xy 38.189672 -299.518685)
			(xy 38.143656 -299.501233) (xy 38.101035 -299.476626) (xy 38.062914 -299.445501) (xy 38.030279 -299.408664)
			(xy 38.003976 -299.367068) (xy 37.984685 -299.321792) (xy 37.972908 -299.274008) (xy 37.968948 -299.224954)
			(xy 37.654906 -299.224954) (xy 37.654906 -299.251002) (xy 37.646771 -299.302365) (xy 37.630703 -299.351823)
			(xy 37.607095 -299.398159) (xy 37.576531 -299.440232) (xy 37.539761 -299.477006) (xy 37.497691 -299.507575)
			(xy 37.451358 -299.531188) (xy 37.401902 -299.547263) (xy 37.35054 -299.555403) (xy 37.324538 -299.555916)
			(xy 36.374578 -299.555916) (xy 36.350193 -299.555511) (xy 36.301954 -299.548332) (xy 36.255293 -299.534147)
			(xy 36.21122 -299.513263) (xy 36.170692 -299.486135) (xy 36.134587 -299.453348) (xy 36.1188 -299.434758)
			(xy 36.111424 -299.426596) (xy 36.091674 -299.416969) (xy 36.0807 -299.416216) (xy 35.992562 -299.413676)
			(xy 35.972496 -299.422312) (xy 35.96513 -299.43044) (xy 35.947646 -299.448867) (xy 35.907681 -299.480216)
			(xy 35.863078 -299.504518) (xy 35.815068 -299.5211) (xy 35.764975 -299.529505) (xy 35.739578 -299.530008)
			(xy 35.714324 -299.529485) (xy 35.664505 -299.521168) (xy 35.616734 -299.504765) (xy 35.572315 -299.480724)
			(xy 35.532458 -299.449699) (xy 35.498251 -299.412538) (xy 35.470626 -299.370253) (xy 35.450338 -299.323999)
			(xy 35.43794 -299.275036) (xy 35.433769 -299.2247) (xy 32.101185 -299.2247) (xy 32.09053 -299.262425)
			(xy 32.069444 -299.310565) (xy 32.041954 -299.355356) (xy 32.00858 -299.395954) (xy 31.969953 -299.43159)
			(xy 31.948628 -299.44695) (xy 31.936206 -299.456158) (xy 31.917259 -299.480583) (xy 31.906467 -299.509551)
			(xy 31.904813 -299.540418) (xy 31.912448 -299.570373) (xy 31.928675 -299.596683) (xy 31.939992 -299.607224)
			(xy 31.960304 -299.625401) (xy 31.996002 -299.666593) (xy 32.025481 -299.712443) (xy 32.048141 -299.762018)
			(xy 32.055655 -299.787564) (xy 32.891982 -299.787564) (xy 32.896053 -299.731942) (xy 32.908179 -299.677505)
			(xy 32.928102 -299.625414) (xy 32.955398 -299.576779) (xy 32.989484 -299.532636) (xy 33.029633 -299.493927)
			(xy 33.074991 -299.461476) (xy 33.124591 -299.435975) (xy 33.177375 -299.417968) (xy 33.232218 -299.407838)
			(xy 33.287952 -299.405801) (xy 33.343389 -299.411901) (xy 33.397346 -299.426007) (xy 33.448675 -299.447819)
			(xy 33.496281 -299.476873) (xy 33.539149 -299.512548) (xy 33.576366 -299.554085) (xy 33.607139 -299.600598)
			(xy 33.630811 -299.651095) (xy 33.646879 -299.704502) (xy 33.654999 -299.759678) (xy 33.655508 -299.787564)
			(xy 33.654999 -299.81545) (xy 33.646879 -299.870626) (xy 33.642219 -299.886116) (xy 33.77006 -299.886116)
			(xy 33.774131 -299.830494) (xy 33.786257 -299.776057) (xy 33.80618 -299.723966) (xy 33.833476 -299.675331)
			(xy 33.867562 -299.631188) (xy 33.907711 -299.592479) (xy 33.953069 -299.560028) (xy 34.002669 -299.534527)
			(xy 34.055453 -299.51652) (xy 34.110296 -299.50639) (xy 34.16603 -299.504353) (xy 34.221467 -299.510453)
			(xy 34.275424 -299.524559) (xy 34.326753 -299.546371) (xy 34.374359 -299.575425) (xy 34.417227 -299.6111)
			(xy 34.454444 -299.652637) (xy 34.485217 -299.69915) (xy 34.485585 -299.699934) (xy 39.394142 -299.699934)
			(xy 39.398102 -299.65088) (xy 39.409879 -299.603096) (xy 39.42917 -299.55782) (xy 39.455473 -299.516224)
			(xy 39.488108 -299.479387) (xy 39.526229 -299.448262) (xy 39.56885 -299.423655) (xy 39.614866 -299.406203)
			(xy 39.663085 -299.396359) (xy 39.71226 -299.394378) (xy 39.761115 -299.40031) (xy 39.808386 -299.414002)
			(xy 39.852848 -299.4351) (xy 39.893351 -299.463056) (xy 39.928844 -299.497148) (xy 39.958409 -299.536492)
			(xy 39.98128 -299.580069) (xy 39.996864 -299.62675) (xy 40.004759 -299.675327) (xy 40.005254 -299.699934)
			(xy 40.004759 -299.724541) (xy 39.996864 -299.773118) (xy 39.98128 -299.819799) (xy 39.958409 -299.863376)
			(xy 39.928844 -299.90272) (xy 39.893351 -299.936812) (xy 39.852848 -299.964768) (xy 39.808386 -299.985866)
			(xy 39.761115 -299.999558) (xy 39.71226 -300.00549) (xy 39.663085 -300.003509) (xy 39.614866 -299.993665)
			(xy 39.56885 -299.976213) (xy 39.526229 -299.951606) (xy 39.488108 -299.920481) (xy 39.455473 -299.883644)
			(xy 39.42917 -299.842048) (xy 39.409879 -299.796772) (xy 39.398102 -299.748988) (xy 39.394142 -299.699934)
			(xy 34.485585 -299.699934) (xy 34.508889 -299.749647) (xy 34.524957 -299.803054) (xy 34.533077 -299.85823)
			(xy 34.533586 -299.886116) (xy 34.533077 -299.914002) (xy 34.524957 -299.969178) (xy 34.508889 -300.022585)
			(xy 34.485217 -300.073082) (xy 34.454444 -300.119595) (xy 34.417227 -300.161132) (xy 34.374359 -300.196807)
			(xy 34.326753 -300.225861) (xy 34.275424 -300.247673) (xy 34.221467 -300.261779) (xy 34.16603 -300.267879)
			(xy 34.110296 -300.265842) (xy 34.055453 -300.255712) (xy 34.002669 -300.237705) (xy 33.953069 -300.212204)
			(xy 33.907711 -300.179753) (xy 33.867562 -300.141044) (xy 33.833476 -300.096901) (xy 33.80618 -300.048266)
			(xy 33.786257 -299.996175) (xy 33.774131 -299.941738) (xy 33.77006 -299.886116) (xy 33.642219 -299.886116)
			(xy 33.630811 -299.924033) (xy 33.607139 -299.97453) (xy 33.576366 -300.021043) (xy 33.539149 -300.06258)
			(xy 33.496281 -300.098255) (xy 33.448675 -300.127309) (xy 33.397346 -300.149121) (xy 33.343389 -300.163227)
			(xy 33.287952 -300.169327) (xy 33.232218 -300.16729) (xy 33.177375 -300.15716) (xy 33.124591 -300.139153)
			(xy 33.074991 -300.113652) (xy 33.029633 -300.081201) (xy 32.989484 -300.042492) (xy 32.955398 -299.998349)
			(xy 32.928102 -299.949714) (xy 32.908179 -299.897623) (xy 32.896053 -299.843186) (xy 32.891982 -299.787564)
			(xy 32.055655 -299.787564) (xy 32.063523 -299.814311) (xy 32.071313 -299.86826) (xy 32.071818 -299.895514)
			(xy 32.071332 -299.922765) (xy 32.063576 -299.976713) (xy 32.048221 -300.029008) (xy 32.025579 -300.078585)
			(xy 31.996113 -300.124435) (xy 31.960422 -300.165626) (xy 31.919231 -300.201317) (xy 31.873381 -300.230783)
			(xy 31.823804 -300.253425) (xy 31.771509 -300.26878) (xy 31.717561 -300.276536) (xy 31.663059 -300.276536)
			(xy 31.609111 -300.26878) (xy 31.556816 -300.253425) (xy 31.507239 -300.230783) (xy 31.461389 -300.201317)
			(xy 31.420198 -300.165626) (xy 31.384507 -300.124435) (xy 31.355041 -300.078585) (xy 31.332399 -300.029008)
			(xy 31.317044 -299.976713) (xy 31.309288 -299.922765) (xy 31.308802 -299.895514) (xy 23.186788 -299.895514)
			(xy 23.228408 -299.979697) (xy 23.293922 -300.130092) (xy 23.352093 -300.283477) (xy 23.392085 -300.406562)
			(xy 25.998676 -300.406562) (xy 26.002747 -300.35094) (xy 26.014873 -300.296503) (xy 26.034796 -300.244412)
			(xy 26.062092 -300.195777) (xy 26.096178 -300.151634) (xy 26.136327 -300.112925) (xy 26.181685 -300.080474)
			(xy 26.231285 -300.054973) (xy 26.284069 -300.036966) (xy 26.338912 -300.026836) (xy 26.394646 -300.024799)
			(xy 26.450083 -300.030899) (xy 26.50404 -300.045005) (xy 26.555369 -300.066817) (xy 26.602975 -300.095871)
			(xy 26.645843 -300.131546) (xy 26.68306 -300.173083) (xy 26.713833 -300.219596) (xy 26.737505 -300.270093)
			(xy 26.753573 -300.3235) (xy 26.761693 -300.378676) (xy 26.762202 -300.406562) (xy 26.761693 -300.434448)
			(xy 26.753573 -300.489624) (xy 26.737505 -300.543031) (xy 26.713833 -300.593528) (xy 26.68306 -300.640041)
			(xy 26.674232 -300.649894) (xy 36.544008 -300.649894) (xy 36.547968 -300.60084) (xy 36.559745 -300.553056)
			(xy 36.579036 -300.50778) (xy 36.605339 -300.466184) (xy 36.637974 -300.429347) (xy 36.676095 -300.398222)
			(xy 36.718716 -300.373615) (xy 36.764732 -300.356163) (xy 36.812951 -300.346319) (xy 36.862126 -300.344338)
			(xy 36.910981 -300.35027) (xy 36.958252 -300.363962) (xy 37.002714 -300.38506) (xy 37.043217 -300.413016)
			(xy 37.07871 -300.447108) (xy 37.108275 -300.486452) (xy 37.131146 -300.530029) (xy 37.14673 -300.57671)
			(xy 37.154625 -300.625287) (xy 37.15512 -300.649894) (xy 37.493968 -300.649894) (xy 37.497928 -300.60084)
			(xy 37.509705 -300.553056) (xy 37.528996 -300.50778) (xy 37.555299 -300.466184) (xy 37.587934 -300.429347)
			(xy 37.626055 -300.398222) (xy 37.668676 -300.373615) (xy 37.714692 -300.356163) (xy 37.762911 -300.346319)
			(xy 37.812086 -300.344338) (xy 37.860941 -300.35027) (xy 37.908212 -300.363962) (xy 37.952674 -300.38506)
			(xy 37.993177 -300.413016) (xy 38.02867 -300.447108) (xy 38.058235 -300.486452) (xy 38.081106 -300.530029)
			(xy 38.09669 -300.57671) (xy 38.104585 -300.625287) (xy 38.10508 -300.649894) (xy 38.444182 -300.649894)
			(xy 38.448142 -300.60084) (xy 38.459919 -300.553056) (xy 38.47921 -300.50778) (xy 38.505513 -300.466184)
			(xy 38.538148 -300.429347) (xy 38.576269 -300.398222) (xy 38.61889 -300.373615) (xy 38.664906 -300.356163)
			(xy 38.713125 -300.346319) (xy 38.7623 -300.344338) (xy 38.811155 -300.35027) (xy 38.858426 -300.363962)
			(xy 38.902888 -300.38506) (xy 38.943391 -300.413016) (xy 38.978884 -300.447108) (xy 39.008449 -300.486452)
			(xy 39.03132 -300.530029) (xy 39.046904 -300.57671) (xy 39.054799 -300.625287) (xy 39.055294 -300.649894)
			(xy 39.394142 -300.649894) (xy 39.398102 -300.60084) (xy 39.409879 -300.553056) (xy 39.42917 -300.50778)
			(xy 39.455473 -300.466184) (xy 39.488108 -300.429347) (xy 39.526229 -300.398222) (xy 39.56885 -300.373615)
			(xy 39.614866 -300.356163) (xy 39.663085 -300.346319) (xy 39.71226 -300.344338) (xy 39.761115 -300.35027)
			(xy 39.808386 -300.363962) (xy 39.852848 -300.38506) (xy 39.893351 -300.413016) (xy 39.928844 -300.447108)
			(xy 39.958409 -300.486452) (xy 39.98128 -300.530029) (xy 39.996864 -300.57671) (xy 40.004759 -300.625287)
			(xy 40.005087 -300.641616) (xy 40.344175 -300.641616) (xy 40.349543 -300.592264) (xy 40.362824 -300.544431)
			(xy 40.383669 -300.499376) (xy 40.411529 -300.458287) (xy 40.445669 -300.422247) (xy 40.48519 -300.392205)
			(xy 40.52905 -300.368952) (xy 40.576095 -300.353102) (xy 40.625084 -300.345071) (xy 40.649906 -300.344586)
			(xy 40.664089 -300.344762) (xy 40.692329 -300.347435) (xy 40.706294 -300.34992) (xy 40.71874 -300.352206)
			(xy 40.742362 -300.34484) (xy 40.819832 -300.26737) (xy 40.827198 -300.243748) (xy 40.824912 -300.231302)
			(xy 40.82244 -300.217335) (xy 40.819765 -300.189096) (xy 40.819578 -300.174914) (xy 40.8201 -300.149659)
			(xy 40.828413 -300.099837) (xy 40.844814 -300.052063) (xy 40.868855 -300.00764) (xy 40.899879 -299.96778)
			(xy 40.937041 -299.93357) (xy 40.979327 -299.905944) (xy 41.025583 -299.885654) (xy 41.074548 -299.873254)
			(xy 41.124886 -299.869083) (xy 41.175224 -299.873254) (xy 41.224189 -299.885654) (xy 41.270445 -299.905944)
			(xy 41.312731 -299.93357) (xy 41.349893 -299.96778) (xy 41.380917 -300.00764) (xy 41.404958 -300.052063)
			(xy 41.421359 -300.099837) (xy 41.429672 -300.149659) (xy 41.430194 -300.174914) (xy 41.43002 -300.189097)
			(xy 41.427346 -300.217337) (xy 41.42486 -300.231302) (xy 41.422574 -300.243748) (xy 41.42994 -300.26737)
			(xy 41.50741 -300.34484) (xy 41.531032 -300.352206) (xy 41.543478 -300.34992) (xy 41.557443 -300.347437)
			(xy 41.585683 -300.344769) (xy 41.599866 -300.344586) (xy 41.614049 -300.344767) (xy 41.642289 -300.347436)
			(xy 41.656254 -300.34992) (xy 41.6687 -300.352206) (xy 41.692322 -300.34484) (xy 41.769792 -300.26737)
			(xy 41.777158 -300.243748) (xy 41.774872 -300.231302) (xy 41.772399 -300.217335) (xy 41.769725 -300.189096)
			(xy 41.769538 -300.174914) (xy 41.77006 -300.149659) (xy 41.778373 -300.099837) (xy 41.794774 -300.052063)
			(xy 41.818815 -300.00764) (xy 41.849839 -299.96778) (xy 41.887001 -299.93357) (xy 41.929287 -299.905944)
			(xy 41.975543 -299.885654) (xy 42.024508 -299.873254) (xy 42.074846 -299.869083) (xy 42.125184 -299.873254)
			(xy 42.174149 -299.885654) (xy 42.220405 -299.905944) (xy 42.262691 -299.93357) (xy 42.299853 -299.96778)
			(xy 42.330877 -300.00764) (xy 42.354918 -300.052063) (xy 42.371319 -300.099837) (xy 42.379632 -300.149659)
			(xy 42.380154 -300.174914) (xy 43.668962 -300.174914) (xy 43.672922 -300.12586) (xy 43.684699 -300.078076)
			(xy 43.70399 -300.0328) (xy 43.730293 -299.991204) (xy 43.762928 -299.954367) (xy 43.801049 -299.923242)
			(xy 43.84367 -299.898635) (xy 43.889686 -299.881183) (xy 43.937905 -299.871339) (xy 43.98708 -299.869358)
			(xy 44.035935 -299.87529) (xy 44.083206 -299.888982) (xy 44.127668 -299.91008) (xy 44.168171 -299.938036)
			(xy 44.203664 -299.972128) (xy 44.233229 -300.011472) (xy 44.2561 -300.055049) (xy 44.271684 -300.10173)
			(xy 44.279579 -300.150307) (xy 44.280074 -300.174914) (xy 44.619176 -300.174914) (xy 44.623136 -300.12586)
			(xy 44.634913 -300.078076) (xy 44.654204 -300.0328) (xy 44.680507 -299.991204) (xy 44.713142 -299.954367)
			(xy 44.751263 -299.923242) (xy 44.793884 -299.898635) (xy 44.8399 -299.881183) (xy 44.888119 -299.871339)
			(xy 44.937294 -299.869358) (xy 44.986149 -299.87529) (xy 45.03342 -299.888982) (xy 45.077882 -299.91008)
			(xy 45.118385 -299.938036) (xy 45.153878 -299.972128) (xy 45.183443 -300.011472) (xy 45.206314 -300.055049)
			(xy 45.221898 -300.10173) (xy 45.229793 -300.150307) (xy 45.230288 -300.174914) (xy 45.569136 -300.174914)
			(xy 45.573096 -300.12586) (xy 45.584873 -300.078076) (xy 45.604164 -300.0328) (xy 45.630467 -299.991204)
			(xy 45.663102 -299.954367) (xy 45.701223 -299.923242) (xy 45.743844 -299.898635) (xy 45.78986 -299.881183)
			(xy 45.838079 -299.871339) (xy 45.887254 -299.869358) (xy 45.936109 -299.87529) (xy 45.98338 -299.888982)
			(xy 46.027842 -299.91008) (xy 46.068345 -299.938036) (xy 46.103838 -299.972128) (xy 46.133403 -300.011472)
			(xy 46.156274 -300.055049) (xy 46.171858 -300.10173) (xy 46.179753 -300.150307) (xy 46.180248 -300.174914)
			(xy 47.469056 -300.174914) (xy 47.473016 -300.12586) (xy 47.484793 -300.078076) (xy 47.504084 -300.0328)
			(xy 47.530387 -299.991204) (xy 47.563022 -299.954367) (xy 47.601143 -299.923242) (xy 47.643764 -299.898635)
			(xy 47.68978 -299.881183) (xy 47.737999 -299.871339) (xy 47.787174 -299.869358) (xy 47.836029 -299.87529)
			(xy 47.8833 -299.888982) (xy 47.927762 -299.91008) (xy 47.968265 -299.938036) (xy 48.003758 -299.972128)
			(xy 48.033323 -300.011472) (xy 48.056194 -300.055049) (xy 48.071778 -300.10173) (xy 48.079673 -300.150307)
			(xy 48.080168 -300.174914) (xy 48.419016 -300.174914) (xy 48.422976 -300.12586) (xy 48.434753 -300.078076)
			(xy 48.454044 -300.0328) (xy 48.480347 -299.991204) (xy 48.512982 -299.954367) (xy 48.551103 -299.923242)
			(xy 48.593724 -299.898635) (xy 48.63974 -299.881183) (xy 48.687959 -299.871339) (xy 48.737134 -299.869358)
			(xy 48.785989 -299.87529) (xy 48.83326 -299.888982) (xy 48.877722 -299.91008) (xy 48.918225 -299.938036)
			(xy 48.953718 -299.972128) (xy 48.983283 -300.011472) (xy 49.006154 -300.055049) (xy 49.021738 -300.10173)
			(xy 49.029633 -300.150307) (xy 49.030128 -300.174914) (xy 49.368976 -300.174914) (xy 49.372936 -300.12586)
			(xy 49.384713 -300.078076) (xy 49.404004 -300.0328) (xy 49.430307 -299.991204) (xy 49.462942 -299.954367)
			(xy 49.501063 -299.923242) (xy 49.543684 -299.898635) (xy 49.5897 -299.881183) (xy 49.637919 -299.871339)
			(xy 49.687094 -299.869358) (xy 49.735949 -299.87529) (xy 49.78322 -299.888982) (xy 49.827682 -299.91008)
			(xy 49.868185 -299.938036) (xy 49.903678 -299.972128) (xy 49.933243 -300.011472) (xy 49.956114 -300.055049)
			(xy 49.971698 -300.10173) (xy 49.979593 -300.150307) (xy 49.980088 -300.174914) (xy 50.31919 -300.174914)
			(xy 50.32315 -300.12586) (xy 50.334927 -300.078076) (xy 50.354218 -300.0328) (xy 50.380521 -299.991204)
			(xy 50.413156 -299.954367) (xy 50.451277 -299.923242) (xy 50.493898 -299.898635) (xy 50.539914 -299.881183)
			(xy 50.588133 -299.871339) (xy 50.637308 -299.869358) (xy 50.686163 -299.87529) (xy 50.733434 -299.888982)
			(xy 50.777896 -299.91008) (xy 50.818399 -299.938036) (xy 50.853892 -299.972128) (xy 50.883457 -300.011472)
			(xy 50.906328 -300.055049) (xy 50.921912 -300.10173) (xy 50.929807 -300.150307) (xy 50.930302 -300.174914)
			(xy 51.26915 -300.174914) (xy 51.27311 -300.12586) (xy 51.284887 -300.078076) (xy 51.304178 -300.0328)
			(xy 51.330481 -299.991204) (xy 51.363116 -299.954367) (xy 51.401237 -299.923242) (xy 51.443858 -299.898635)
			(xy 51.489874 -299.881183) (xy 51.538093 -299.871339) (xy 51.587268 -299.869358) (xy 51.636123 -299.87529)
			(xy 51.683394 -299.888982) (xy 51.727856 -299.91008) (xy 51.768359 -299.938036) (xy 51.803852 -299.972128)
			(xy 51.833417 -300.011472) (xy 51.856288 -300.055049) (xy 51.871872 -300.10173) (xy 51.879767 -300.150307)
			(xy 51.880262 -300.174914) (xy 52.21911 -300.174914) (xy 52.22307 -300.12586) (xy 52.234847 -300.078076)
			(xy 52.254138 -300.0328) (xy 52.280441 -299.991204) (xy 52.313076 -299.954367) (xy 52.351197 -299.923242)
			(xy 52.393818 -299.898635) (xy 52.439834 -299.881183) (xy 52.488053 -299.871339) (xy 52.537228 -299.869358)
			(xy 52.586083 -299.87529) (xy 52.633354 -299.888982) (xy 52.677816 -299.91008) (xy 52.718319 -299.938036)
			(xy 52.753812 -299.972128) (xy 52.783377 -300.011472) (xy 52.806248 -300.055049) (xy 52.821832 -300.10173)
			(xy 52.829727 -300.150307) (xy 52.830222 -300.174914) (xy 53.16907 -300.174914) (xy 53.17303 -300.12586)
			(xy 53.184807 -300.078076) (xy 53.204098 -300.0328) (xy 53.230401 -299.991204) (xy 53.263036 -299.954367)
			(xy 53.301157 -299.923242) (xy 53.343778 -299.898635) (xy 53.389794 -299.881183) (xy 53.438013 -299.871339)
			(xy 53.487188 -299.869358) (xy 53.536043 -299.87529) (xy 53.583314 -299.888982) (xy 53.627776 -299.91008)
			(xy 53.668279 -299.938036) (xy 53.703772 -299.972128) (xy 53.733337 -300.011472) (xy 53.756208 -300.055049)
			(xy 53.771792 -300.10173) (xy 53.779687 -300.150307) (xy 53.780182 -300.174914) (xy 54.11903 -300.174914)
			(xy 54.12299 -300.12586) (xy 54.134767 -300.078076) (xy 54.154058 -300.0328) (xy 54.180361 -299.991204)
			(xy 54.212996 -299.954367) (xy 54.251117 -299.923242) (xy 54.293738 -299.898635) (xy 54.339754 -299.881183)
			(xy 54.387973 -299.871339) (xy 54.437148 -299.869358) (xy 54.486003 -299.87529) (xy 54.533274 -299.888982)
			(xy 54.577736 -299.91008) (xy 54.618239 -299.938036) (xy 54.653732 -299.972128) (xy 54.683297 -300.011472)
			(xy 54.706168 -300.055049) (xy 54.721752 -300.10173) (xy 54.729647 -300.150307) (xy 54.730142 -300.174914)
			(xy 55.06899 -300.174914) (xy 55.07295 -300.12586) (xy 55.084727 -300.078076) (xy 55.104018 -300.0328)
			(xy 55.130321 -299.991204) (xy 55.162956 -299.954367) (xy 55.201077 -299.923242) (xy 55.243698 -299.898635)
			(xy 55.289714 -299.881183) (xy 55.337933 -299.871339) (xy 55.387108 -299.869358) (xy 55.435963 -299.87529)
			(xy 55.483234 -299.888982) (xy 55.527696 -299.91008) (xy 55.568199 -299.938036) (xy 55.603692 -299.972128)
			(xy 55.633257 -300.011472) (xy 55.656128 -300.055049) (xy 55.671712 -300.10173) (xy 55.679607 -300.150307)
			(xy 55.680102 -300.174914) (xy 56.01895 -300.174914) (xy 56.02291 -300.12586) (xy 56.034687 -300.078076)
			(xy 56.053978 -300.0328) (xy 56.080281 -299.991204) (xy 56.112916 -299.954367) (xy 56.151037 -299.923242)
			(xy 56.193658 -299.898635) (xy 56.239674 -299.881183) (xy 56.287893 -299.871339) (xy 56.337068 -299.869358)
			(xy 56.385923 -299.87529) (xy 56.433194 -299.888982) (xy 56.477656 -299.91008) (xy 56.518159 -299.938036)
			(xy 56.553652 -299.972128) (xy 56.583217 -300.011472) (xy 56.606088 -300.055049) (xy 56.621672 -300.10173)
			(xy 56.629567 -300.150307) (xy 56.630062 -300.174914) (xy 56.969164 -300.174914) (xy 56.973124 -300.12586)
			(xy 56.984901 -300.078076) (xy 57.004192 -300.0328) (xy 57.030495 -299.991204) (xy 57.06313 -299.954367)
			(xy 57.101251 -299.923242) (xy 57.143872 -299.898635) (xy 57.189888 -299.881183) (xy 57.238107 -299.871339)
			(xy 57.287282 -299.869358) (xy 57.336137 -299.87529) (xy 57.383408 -299.888982) (xy 57.42787 -299.91008)
			(xy 57.468373 -299.938036) (xy 57.503866 -299.972128) (xy 57.533431 -300.011472) (xy 57.556302 -300.055049)
			(xy 57.571886 -300.10173) (xy 57.579781 -300.150307) (xy 57.580276 -300.174914) (xy 57.919124 -300.174914)
			(xy 57.923084 -300.12586) (xy 57.934861 -300.078076) (xy 57.954152 -300.0328) (xy 57.980455 -299.991204)
			(xy 58.01309 -299.954367) (xy 58.051211 -299.923242) (xy 58.093832 -299.898635) (xy 58.139848 -299.881183)
			(xy 58.188067 -299.871339) (xy 58.237242 -299.869358) (xy 58.286097 -299.87529) (xy 58.333368 -299.888982)
			(xy 58.37783 -299.91008) (xy 58.418333 -299.938036) (xy 58.453826 -299.972128) (xy 58.483391 -300.011472)
			(xy 58.506262 -300.055049) (xy 58.521846 -300.10173) (xy 58.529741 -300.150307) (xy 58.530236 -300.174914)
			(xy 59.819044 -300.174914) (xy 59.823004 -300.12586) (xy 59.834781 -300.078076) (xy 59.854072 -300.0328)
			(xy 59.880375 -299.991204) (xy 59.91301 -299.954367) (xy 59.951131 -299.923242) (xy 59.993752 -299.898635)
			(xy 60.039768 -299.881183) (xy 60.087987 -299.871339) (xy 60.137162 -299.869358) (xy 60.186017 -299.87529)
			(xy 60.233288 -299.888982) (xy 60.27775 -299.91008) (xy 60.318253 -299.938036) (xy 60.353746 -299.972128)
			(xy 60.383311 -300.011472) (xy 60.406182 -300.055049) (xy 60.421766 -300.10173) (xy 60.429661 -300.150307)
			(xy 60.430156 -300.174914) (xy 60.769004 -300.174914) (xy 60.772964 -300.12586) (xy 60.784741 -300.078076)
			(xy 60.804032 -300.0328) (xy 60.830335 -299.991204) (xy 60.86297 -299.954367) (xy 60.901091 -299.923242)
			(xy 60.943712 -299.898635) (xy 60.989728 -299.881183) (xy 61.037947 -299.871339) (xy 61.087122 -299.869358)
			(xy 61.135977 -299.87529) (xy 61.183248 -299.888982) (xy 61.22771 -299.91008) (xy 61.268213 -299.938036)
			(xy 61.303706 -299.972128) (xy 61.333271 -300.011472) (xy 61.356142 -300.055049) (xy 61.371726 -300.10173)
			(xy 61.379621 -300.150307) (xy 61.380116 -300.174914) (xy 61.718964 -300.174914) (xy 61.722924 -300.12586)
			(xy 61.734701 -300.078076) (xy 61.753992 -300.0328) (xy 61.780295 -299.991204) (xy 61.81293 -299.954367)
			(xy 61.851051 -299.923242) (xy 61.893672 -299.898635) (xy 61.939688 -299.881183) (xy 61.987907 -299.871339)
			(xy 62.037082 -299.869358) (xy 62.085937 -299.87529) (xy 62.133208 -299.888982) (xy 62.17767 -299.91008)
			(xy 62.218173 -299.938036) (xy 62.253666 -299.972128) (xy 62.283231 -300.011472) (xy 62.306102 -300.055049)
			(xy 62.321686 -300.10173) (xy 62.329581 -300.150307) (xy 62.330076 -300.174914) (xy 62.669178 -300.174914)
			(xy 62.673138 -300.12586) (xy 62.684915 -300.078076) (xy 62.704206 -300.0328) (xy 62.730509 -299.991204)
			(xy 62.763144 -299.954367) (xy 62.801265 -299.923242) (xy 62.843886 -299.898635) (xy 62.889902 -299.881183)
			(xy 62.938121 -299.871339) (xy 62.987296 -299.869358) (xy 63.036151 -299.87529) (xy 63.083422 -299.888982)
			(xy 63.127884 -299.91008) (xy 63.168387 -299.938036) (xy 63.20388 -299.972128) (xy 63.233445 -300.011472)
			(xy 63.256316 -300.055049) (xy 63.2719 -300.10173) (xy 63.279795 -300.150307) (xy 63.28029 -300.174914)
			(xy 63.619138 -300.174914) (xy 63.623098 -300.12586) (xy 63.634875 -300.078076) (xy 63.654166 -300.0328)
			(xy 63.680469 -299.991204) (xy 63.713104 -299.954367) (xy 63.751225 -299.923242) (xy 63.793846 -299.898635)
			(xy 63.839862 -299.881183) (xy 63.888081 -299.871339) (xy 63.937256 -299.869358) (xy 63.986111 -299.87529)
			(xy 64.033382 -299.888982) (xy 64.077844 -299.91008) (xy 64.118347 -299.938036) (xy 64.15384 -299.972128)
			(xy 64.183405 -300.011472) (xy 64.206276 -300.055049) (xy 64.22186 -300.10173) (xy 64.229755 -300.150307)
			(xy 64.23025 -300.174914) (xy 64.569098 -300.174914) (xy 64.573058 -300.12586) (xy 64.584835 -300.078076)
			(xy 64.604126 -300.0328) (xy 64.630429 -299.991204) (xy 64.663064 -299.954367) (xy 64.701185 -299.923242)
			(xy 64.743806 -299.898635) (xy 64.789822 -299.881183) (xy 64.838041 -299.871339) (xy 64.887216 -299.869358)
			(xy 64.936071 -299.87529) (xy 64.983342 -299.888982) (xy 65.027804 -299.91008) (xy 65.068307 -299.938036)
			(xy 65.1038 -299.972128) (xy 65.133365 -300.011472) (xy 65.156236 -300.055049) (xy 65.17182 -300.10173)
			(xy 65.179715 -300.150307) (xy 65.18021 -300.174914) (xy 65.519058 -300.174914) (xy 65.523018 -300.12586)
			(xy 65.534795 -300.078076) (xy 65.554086 -300.0328) (xy 65.580389 -299.991204) (xy 65.613024 -299.954367)
			(xy 65.651145 -299.923242) (xy 65.693766 -299.898635) (xy 65.739782 -299.881183) (xy 65.788001 -299.871339)
			(xy 65.837176 -299.869358) (xy 65.886031 -299.87529) (xy 65.933302 -299.888982) (xy 65.977764 -299.91008)
			(xy 66.018267 -299.938036) (xy 66.05376 -299.972128) (xy 66.083325 -300.011472) (xy 66.106196 -300.055049)
			(xy 66.12178 -300.10173) (xy 66.129675 -300.150307) (xy 66.13017 -300.174914) (xy 66.469018 -300.174914)
			(xy 66.472978 -300.12586) (xy 66.484755 -300.078076) (xy 66.504046 -300.0328) (xy 66.530349 -299.991204)
			(xy 66.562984 -299.954367) (xy 66.601105 -299.923242) (xy 66.643726 -299.898635) (xy 66.689742 -299.881183)
			(xy 66.737961 -299.871339) (xy 66.787136 -299.869358) (xy 66.835991 -299.87529) (xy 66.883262 -299.888982)
			(xy 66.927724 -299.91008) (xy 66.968227 -299.938036) (xy 67.00372 -299.972128) (xy 67.033285 -300.011472)
			(xy 67.056156 -300.055049) (xy 67.07174 -300.10173) (xy 67.079635 -300.150307) (xy 67.08013 -300.174914)
			(xy 67.418978 -300.174914) (xy 67.422938 -300.12586) (xy 67.434715 -300.078076) (xy 67.454006 -300.0328)
			(xy 67.480309 -299.991204) (xy 67.512944 -299.954367) (xy 67.551065 -299.923242) (xy 67.593686 -299.898635)
			(xy 67.639702 -299.881183) (xy 67.687921 -299.871339) (xy 67.737096 -299.869358) (xy 67.785951 -299.87529)
			(xy 67.833222 -299.888982) (xy 67.877684 -299.91008) (xy 67.918187 -299.938036) (xy 67.95368 -299.972128)
			(xy 67.983245 -300.011472) (xy 68.006116 -300.055049) (xy 68.0217 -300.10173) (xy 68.029595 -300.150307)
			(xy 68.03009 -300.174914) (xy 68.368938 -300.174914) (xy 68.372898 -300.12586) (xy 68.384675 -300.078076)
			(xy 68.403966 -300.0328) (xy 68.430269 -299.991204) (xy 68.462904 -299.954367) (xy 68.501025 -299.923242)
			(xy 68.543646 -299.898635) (xy 68.589662 -299.881183) (xy 68.637881 -299.871339) (xy 68.687056 -299.869358)
			(xy 68.735911 -299.87529) (xy 68.783182 -299.888982) (xy 68.827644 -299.91008) (xy 68.868147 -299.938036)
			(xy 68.90364 -299.972128) (xy 68.933205 -300.011472) (xy 68.956076 -300.055049) (xy 68.97166 -300.10173)
			(xy 68.979555 -300.150307) (xy 68.98005 -300.174914) (xy 69.319152 -300.174914) (xy 69.323112 -300.12586)
			(xy 69.334889 -300.078076) (xy 69.35418 -300.0328) (xy 69.380483 -299.991204) (xy 69.413118 -299.954367)
			(xy 69.451239 -299.923242) (xy 69.49386 -299.898635) (xy 69.539876 -299.881183) (xy 69.588095 -299.871339)
			(xy 69.63727 -299.869358) (xy 69.686125 -299.87529) (xy 69.733396 -299.888982) (xy 69.777858 -299.91008)
			(xy 69.818361 -299.938036) (xy 69.853854 -299.972128) (xy 69.883419 -300.011472) (xy 69.90629 -300.055049)
			(xy 69.921874 -300.10173) (xy 69.929769 -300.150307) (xy 69.930264 -300.174914) (xy 70.269112 -300.174914)
			(xy 70.273072 -300.12586) (xy 70.284849 -300.078076) (xy 70.30414 -300.0328) (xy 70.330443 -299.991204)
			(xy 70.363078 -299.954367) (xy 70.401199 -299.923242) (xy 70.44382 -299.898635) (xy 70.489836 -299.881183)
			(xy 70.538055 -299.871339) (xy 70.58723 -299.869358) (xy 70.636085 -299.87529) (xy 70.683356 -299.888982)
			(xy 70.727818 -299.91008) (xy 70.768321 -299.938036) (xy 70.803814 -299.972128) (xy 70.833379 -300.011472)
			(xy 70.85625 -300.055049) (xy 70.871834 -300.10173) (xy 70.879729 -300.150307) (xy 70.880224 -300.174914)
			(xy 71.219072 -300.174914) (xy 71.223032 -300.12586) (xy 71.234809 -300.078076) (xy 71.2541 -300.0328)
			(xy 71.280403 -299.991204) (xy 71.313038 -299.954367) (xy 71.351159 -299.923242) (xy 71.39378 -299.898635)
			(xy 71.439796 -299.881183) (xy 71.488015 -299.871339) (xy 71.53719 -299.869358) (xy 71.586045 -299.87529)
			(xy 71.633316 -299.888982) (xy 71.677778 -299.91008) (xy 71.718281 -299.938036) (xy 71.753774 -299.972128)
			(xy 71.783339 -300.011472) (xy 71.80621 -300.055049) (xy 71.821794 -300.10173) (xy 71.829689 -300.150307)
			(xy 71.830184 -300.174914) (xy 72.169032 -300.174914) (xy 72.172992 -300.12586) (xy 72.184769 -300.078076)
			(xy 72.20406 -300.0328) (xy 72.230363 -299.991204) (xy 72.262998 -299.954367) (xy 72.301119 -299.923242)
			(xy 72.34374 -299.898635) (xy 72.389756 -299.881183) (xy 72.437975 -299.871339) (xy 72.48715 -299.869358)
			(xy 72.536005 -299.87529) (xy 72.583276 -299.888982) (xy 72.627738 -299.91008) (xy 72.668241 -299.938036)
			(xy 72.703734 -299.972128) (xy 72.733299 -300.011472) (xy 72.75617 -300.055049) (xy 72.771754 -300.10173)
			(xy 72.779649 -300.150307) (xy 72.780144 -300.174914) (xy 73.118992 -300.174914) (xy 73.122952 -300.12586)
			(xy 73.134729 -300.078076) (xy 73.15402 -300.0328) (xy 73.180323 -299.991204) (xy 73.212958 -299.954367)
			(xy 73.251079 -299.923242) (xy 73.2937 -299.898635) (xy 73.339716 -299.881183) (xy 73.387935 -299.871339)
			(xy 73.43711 -299.869358) (xy 73.485965 -299.87529) (xy 73.533236 -299.888982) (xy 73.577698 -299.91008)
			(xy 73.618201 -299.938036) (xy 73.653694 -299.972128) (xy 73.683259 -300.011472) (xy 73.70613 -300.055049)
			(xy 73.721714 -300.10173) (xy 73.729609 -300.150307) (xy 73.730104 -300.174914) (xy 74.068952 -300.174914)
			(xy 74.072912 -300.12586) (xy 74.084689 -300.078076) (xy 74.10398 -300.0328) (xy 74.130283 -299.991204)
			(xy 74.162918 -299.954367) (xy 74.201039 -299.923242) (xy 74.24366 -299.898635) (xy 74.289676 -299.881183)
			(xy 74.337895 -299.871339) (xy 74.38707 -299.869358) (xy 74.435925 -299.87529) (xy 74.483196 -299.888982)
			(xy 74.527658 -299.91008) (xy 74.568161 -299.938036) (xy 74.603654 -299.972128) (xy 74.633219 -300.011472)
			(xy 74.65609 -300.055049) (xy 74.671674 -300.10173) (xy 74.679569 -300.150307) (xy 74.680064 -300.174914)
			(xy 75.969126 -300.174914) (xy 75.973086 -300.12586) (xy 75.984863 -300.078076) (xy 76.004154 -300.0328)
			(xy 76.030457 -299.991204) (xy 76.063092 -299.954367) (xy 76.101213 -299.923242) (xy 76.143834 -299.898635)
			(xy 76.18985 -299.881183) (xy 76.238069 -299.871339) (xy 76.287244 -299.869358) (xy 76.336099 -299.87529)
			(xy 76.38337 -299.888982) (xy 76.427832 -299.91008) (xy 76.468335 -299.938036) (xy 76.503828 -299.972128)
			(xy 76.533393 -300.011472) (xy 76.556264 -300.055049) (xy 76.571848 -300.10173) (xy 76.579743 -300.150307)
			(xy 76.580238 -300.174914) (xy 76.919086 -300.174914) (xy 76.923046 -300.12586) (xy 76.934823 -300.078076)
			(xy 76.954114 -300.0328) (xy 76.980417 -299.991204) (xy 77.013052 -299.954367) (xy 77.051173 -299.923242)
			(xy 77.093794 -299.898635) (xy 77.13981 -299.881183) (xy 77.188029 -299.871339) (xy 77.237204 -299.869358)
			(xy 77.286059 -299.87529) (xy 77.33333 -299.888982) (xy 77.377792 -299.91008) (xy 77.418295 -299.938036)
			(xy 77.453788 -299.972128) (xy 77.483353 -300.011472) (xy 77.506224 -300.055049) (xy 77.521808 -300.10173)
			(xy 77.529703 -300.150307) (xy 77.530198 -300.174914) (xy 77.869046 -300.174914) (xy 77.873006 -300.12586)
			(xy 77.884783 -300.078076) (xy 77.904074 -300.0328) (xy 77.930377 -299.991204) (xy 77.963012 -299.954367)
			(xy 78.001133 -299.923242) (xy 78.043754 -299.898635) (xy 78.08977 -299.881183) (xy 78.137989 -299.871339)
			(xy 78.187164 -299.869358) (xy 78.236019 -299.87529) (xy 78.28329 -299.888982) (xy 78.327752 -299.91008)
			(xy 78.368255 -299.938036) (xy 78.403748 -299.972128) (xy 78.433313 -300.011472) (xy 78.456184 -300.055049)
			(xy 78.471768 -300.10173) (xy 78.479663 -300.150307) (xy 78.480158 -300.174914) (xy 78.819006 -300.174914)
			(xy 78.822966 -300.12586) (xy 78.834743 -300.078076) (xy 78.854034 -300.0328) (xy 78.880337 -299.991204)
			(xy 78.912972 -299.954367) (xy 78.951093 -299.923242) (xy 78.993714 -299.898635) (xy 79.03973 -299.881183)
			(xy 79.087949 -299.871339) (xy 79.137124 -299.869358) (xy 79.185979 -299.87529) (xy 79.23325 -299.888982)
			(xy 79.277712 -299.91008) (xy 79.318215 -299.938036) (xy 79.353708 -299.972128) (xy 79.383273 -300.011472)
			(xy 79.406144 -300.055049) (xy 79.421728 -300.10173) (xy 79.429623 -300.150307) (xy 79.430118 -300.174914)
			(xy 79.768966 -300.174914) (xy 79.772926 -300.12586) (xy 79.784703 -300.078076) (xy 79.803994 -300.0328)
			(xy 79.830297 -299.991204) (xy 79.862932 -299.954367) (xy 79.901053 -299.923242) (xy 79.943674 -299.898635)
			(xy 79.98969 -299.881183) (xy 80.037909 -299.871339) (xy 80.087084 -299.869358) (xy 80.135939 -299.87529)
			(xy 80.18321 -299.888982) (xy 80.227672 -299.91008) (xy 80.268175 -299.938036) (xy 80.303668 -299.972128)
			(xy 80.333233 -300.011472) (xy 80.356104 -300.055049) (xy 80.371688 -300.10173) (xy 80.379583 -300.150307)
			(xy 80.380078 -300.174914) (xy 80.71918 -300.174914) (xy 80.72314 -300.12586) (xy 80.734917 -300.078076)
			(xy 80.754208 -300.0328) (xy 80.780511 -299.991204) (xy 80.813146 -299.954367) (xy 80.851267 -299.923242)
			(xy 80.893888 -299.898635) (xy 80.939904 -299.881183) (xy 80.988123 -299.871339) (xy 81.037298 -299.869358)
			(xy 81.086153 -299.87529) (xy 81.133424 -299.888982) (xy 81.177886 -299.91008) (xy 81.218389 -299.938036)
			(xy 81.253882 -299.972128) (xy 81.283447 -300.011472) (xy 81.306318 -300.055049) (xy 81.321902 -300.10173)
			(xy 81.329797 -300.150307) (xy 81.330292 -300.174914) (xy 81.66914 -300.174914) (xy 81.6731 -300.12586)
			(xy 81.684877 -300.078076) (xy 81.704168 -300.0328) (xy 81.730471 -299.991204) (xy 81.763106 -299.954367)
			(xy 81.801227 -299.923242) (xy 81.843848 -299.898635) (xy 81.889864 -299.881183) (xy 81.938083 -299.871339)
			(xy 81.987258 -299.869358) (xy 82.036113 -299.87529) (xy 82.083384 -299.888982) (xy 82.127846 -299.91008)
			(xy 82.168349 -299.938036) (xy 82.203842 -299.972128) (xy 82.233407 -300.011472) (xy 82.256278 -300.055049)
			(xy 82.271862 -300.10173) (xy 82.279757 -300.150307) (xy 82.280252 -300.174914) (xy 82.6191 -300.174914)
			(xy 82.62306 -300.12586) (xy 82.634837 -300.078076) (xy 82.654128 -300.0328) (xy 82.680431 -299.991204)
			(xy 82.713066 -299.954367) (xy 82.751187 -299.923242) (xy 82.793808 -299.898635) (xy 82.839824 -299.881183)
			(xy 82.888043 -299.871339) (xy 82.937218 -299.869358) (xy 82.986073 -299.87529) (xy 83.033344 -299.888982)
			(xy 83.077806 -299.91008) (xy 83.118309 -299.938036) (xy 83.153802 -299.972128) (xy 83.183367 -300.011472)
			(xy 83.206238 -300.055049) (xy 83.221822 -300.10173) (xy 83.229717 -300.150307) (xy 83.230212 -300.174914)
			(xy 83.229717 -300.199521) (xy 83.221822 -300.248098) (xy 83.206238 -300.294779) (xy 83.183367 -300.338356)
			(xy 83.153802 -300.3777) (xy 83.118309 -300.411792) (xy 83.077806 -300.439748) (xy 83.033344 -300.460846)
			(xy 82.986073 -300.474538) (xy 82.937218 -300.48047) (xy 82.888043 -300.478489) (xy 82.839824 -300.468645)
			(xy 82.793808 -300.451193) (xy 82.751187 -300.426586) (xy 82.713066 -300.395461) (xy 82.680431 -300.358624)
			(xy 82.654128 -300.317028) (xy 82.634837 -300.271752) (xy 82.62306 -300.223968) (xy 82.6191 -300.174914)
			(xy 82.280252 -300.174914) (xy 82.279757 -300.199521) (xy 82.271862 -300.248098) (xy 82.256278 -300.294779)
			(xy 82.233407 -300.338356) (xy 82.203842 -300.3777) (xy 82.168349 -300.411792) (xy 82.127846 -300.439748)
			(xy 82.083384 -300.460846) (xy 82.036113 -300.474538) (xy 81.987258 -300.48047) (xy 81.938083 -300.478489)
			(xy 81.889864 -300.468645) (xy 81.843848 -300.451193) (xy 81.801227 -300.426586) (xy 81.763106 -300.395461)
			(xy 81.730471 -300.358624) (xy 81.704168 -300.317028) (xy 81.684877 -300.271752) (xy 81.6731 -300.223968)
			(xy 81.66914 -300.174914) (xy 81.330292 -300.174914) (xy 81.329797 -300.199521) (xy 81.321902 -300.248098)
			(xy 81.306318 -300.294779) (xy 81.283447 -300.338356) (xy 81.253882 -300.3777) (xy 81.218389 -300.411792)
			(xy 81.177886 -300.439748) (xy 81.133424 -300.460846) (xy 81.086153 -300.474538) (xy 81.037298 -300.48047)
			(xy 80.988123 -300.478489) (xy 80.939904 -300.468645) (xy 80.893888 -300.451193) (xy 80.851267 -300.426586)
			(xy 80.813146 -300.395461) (xy 80.780511 -300.358624) (xy 80.754208 -300.317028) (xy 80.734917 -300.271752)
			(xy 80.72314 -300.223968) (xy 80.71918 -300.174914) (xy 80.380078 -300.174914) (xy 80.379583 -300.199521)
			(xy 80.371688 -300.248098) (xy 80.356104 -300.294779) (xy 80.333233 -300.338356) (xy 80.303668 -300.3777)
			(xy 80.268175 -300.411792) (xy 80.227672 -300.439748) (xy 80.18321 -300.460846) (xy 80.135939 -300.474538)
			(xy 80.087084 -300.48047) (xy 80.037909 -300.478489) (xy 79.98969 -300.468645) (xy 79.943674 -300.451193)
			(xy 79.901053 -300.426586) (xy 79.862932 -300.395461) (xy 79.830297 -300.358624) (xy 79.803994 -300.317028)
			(xy 79.784703 -300.271752) (xy 79.772926 -300.223968) (xy 79.768966 -300.174914) (xy 79.430118 -300.174914)
			(xy 79.429623 -300.199521) (xy 79.421728 -300.248098) (xy 79.406144 -300.294779) (xy 79.383273 -300.338356)
			(xy 79.353708 -300.3777) (xy 79.318215 -300.411792) (xy 79.277712 -300.439748) (xy 79.23325 -300.460846)
			(xy 79.185979 -300.474538) (xy 79.137124 -300.48047) (xy 79.087949 -300.478489) (xy 79.03973 -300.468645)
			(xy 78.993714 -300.451193) (xy 78.951093 -300.426586) (xy 78.912972 -300.395461) (xy 78.880337 -300.358624)
			(xy 78.854034 -300.317028) (xy 78.834743 -300.271752) (xy 78.822966 -300.223968) (xy 78.819006 -300.174914)
			(xy 78.480158 -300.174914) (xy 78.479663 -300.199521) (xy 78.471768 -300.248098) (xy 78.456184 -300.294779)
			(xy 78.433313 -300.338356) (xy 78.403748 -300.3777) (xy 78.368255 -300.411792) (xy 78.327752 -300.439748)
			(xy 78.28329 -300.460846) (xy 78.236019 -300.474538) (xy 78.187164 -300.48047) (xy 78.137989 -300.478489)
			(xy 78.08977 -300.468645) (xy 78.043754 -300.451193) (xy 78.001133 -300.426586) (xy 77.963012 -300.395461)
			(xy 77.930377 -300.358624) (xy 77.904074 -300.317028) (xy 77.884783 -300.271752) (xy 77.873006 -300.223968)
			(xy 77.869046 -300.174914) (xy 77.530198 -300.174914) (xy 77.529703 -300.199521) (xy 77.521808 -300.248098)
			(xy 77.506224 -300.294779) (xy 77.483353 -300.338356) (xy 77.453788 -300.3777) (xy 77.418295 -300.411792)
			(xy 77.377792 -300.439748) (xy 77.33333 -300.460846) (xy 77.286059 -300.474538) (xy 77.237204 -300.48047)
			(xy 77.188029 -300.478489) (xy 77.13981 -300.468645) (xy 77.093794 -300.451193) (xy 77.051173 -300.426586)
			(xy 77.013052 -300.395461) (xy 76.980417 -300.358624) (xy 76.954114 -300.317028) (xy 76.934823 -300.271752)
			(xy 76.923046 -300.223968) (xy 76.919086 -300.174914) (xy 76.580238 -300.174914) (xy 76.579743 -300.199521)
			(xy 76.571848 -300.248098) (xy 76.556264 -300.294779) (xy 76.533393 -300.338356) (xy 76.503828 -300.3777)
			(xy 76.468335 -300.411792) (xy 76.427832 -300.439748) (xy 76.38337 -300.460846) (xy 76.336099 -300.474538)
			(xy 76.287244 -300.48047) (xy 76.238069 -300.478489) (xy 76.18985 -300.468645) (xy 76.143834 -300.451193)
			(xy 76.101213 -300.426586) (xy 76.063092 -300.395461) (xy 76.030457 -300.358624) (xy 76.004154 -300.317028)
			(xy 75.984863 -300.271752) (xy 75.973086 -300.223968) (xy 75.969126 -300.174914) (xy 74.680064 -300.174914)
			(xy 74.679569 -300.199521) (xy 74.671674 -300.248098) (xy 74.65609 -300.294779) (xy 74.633219 -300.338356)
			(xy 74.603654 -300.3777) (xy 74.568161 -300.411792) (xy 74.527658 -300.439748) (xy 74.483196 -300.460846)
			(xy 74.435925 -300.474538) (xy 74.38707 -300.48047) (xy 74.337895 -300.478489) (xy 74.289676 -300.468645)
			(xy 74.24366 -300.451193) (xy 74.201039 -300.426586) (xy 74.162918 -300.395461) (xy 74.130283 -300.358624)
			(xy 74.10398 -300.317028) (xy 74.084689 -300.271752) (xy 74.072912 -300.223968) (xy 74.068952 -300.174914)
			(xy 73.730104 -300.174914) (xy 73.729609 -300.199521) (xy 73.721714 -300.248098) (xy 73.70613 -300.294779)
			(xy 73.683259 -300.338356) (xy 73.653694 -300.3777) (xy 73.618201 -300.411792) (xy 73.577698 -300.439748)
			(xy 73.533236 -300.460846) (xy 73.485965 -300.474538) (xy 73.43711 -300.48047) (xy 73.387935 -300.478489)
			(xy 73.339716 -300.468645) (xy 73.2937 -300.451193) (xy 73.251079 -300.426586) (xy 73.212958 -300.395461)
			(xy 73.180323 -300.358624) (xy 73.15402 -300.317028) (xy 73.134729 -300.271752) (xy 73.122952 -300.223968)
			(xy 73.118992 -300.174914) (xy 72.780144 -300.174914) (xy 72.779649 -300.199521) (xy 72.771754 -300.248098)
			(xy 72.75617 -300.294779) (xy 72.733299 -300.338356) (xy 72.703734 -300.3777) (xy 72.668241 -300.411792)
			(xy 72.627738 -300.439748) (xy 72.583276 -300.460846) (xy 72.536005 -300.474538) (xy 72.48715 -300.48047)
			(xy 72.437975 -300.478489) (xy 72.389756 -300.468645) (xy 72.34374 -300.451193) (xy 72.301119 -300.426586)
			(xy 72.262998 -300.395461) (xy 72.230363 -300.358624) (xy 72.20406 -300.317028) (xy 72.184769 -300.271752)
			(xy 72.172992 -300.223968) (xy 72.169032 -300.174914) (xy 71.830184 -300.174914) (xy 71.829689 -300.199521)
			(xy 71.821794 -300.248098) (xy 71.80621 -300.294779) (xy 71.783339 -300.338356) (xy 71.753774 -300.3777)
			(xy 71.718281 -300.411792) (xy 71.677778 -300.439748) (xy 71.633316 -300.460846) (xy 71.586045 -300.474538)
			(xy 71.53719 -300.48047) (xy 71.488015 -300.478489) (xy 71.439796 -300.468645) (xy 71.39378 -300.451193)
			(xy 71.351159 -300.426586) (xy 71.313038 -300.395461) (xy 71.280403 -300.358624) (xy 71.2541 -300.317028)
			(xy 71.234809 -300.271752) (xy 71.223032 -300.223968) (xy 71.219072 -300.174914) (xy 70.880224 -300.174914)
			(xy 70.879729 -300.199521) (xy 70.871834 -300.248098) (xy 70.85625 -300.294779) (xy 70.833379 -300.338356)
			(xy 70.803814 -300.3777) (xy 70.768321 -300.411792) (xy 70.727818 -300.439748) (xy 70.683356 -300.460846)
			(xy 70.636085 -300.474538) (xy 70.58723 -300.48047) (xy 70.538055 -300.478489) (xy 70.489836 -300.468645)
			(xy 70.44382 -300.451193) (xy 70.401199 -300.426586) (xy 70.363078 -300.395461) (xy 70.330443 -300.358624)
			(xy 70.30414 -300.317028) (xy 70.284849 -300.271752) (xy 70.273072 -300.223968) (xy 70.269112 -300.174914)
			(xy 69.930264 -300.174914) (xy 69.929769 -300.199521) (xy 69.921874 -300.248098) (xy 69.90629 -300.294779)
			(xy 69.883419 -300.338356) (xy 69.853854 -300.3777) (xy 69.818361 -300.411792) (xy 69.777858 -300.439748)
			(xy 69.733396 -300.460846) (xy 69.686125 -300.474538) (xy 69.63727 -300.48047) (xy 69.588095 -300.478489)
			(xy 69.539876 -300.468645) (xy 69.49386 -300.451193) (xy 69.451239 -300.426586) (xy 69.413118 -300.395461)
			(xy 69.380483 -300.358624) (xy 69.35418 -300.317028) (xy 69.334889 -300.271752) (xy 69.323112 -300.223968)
			(xy 69.319152 -300.174914) (xy 68.98005 -300.174914) (xy 68.979555 -300.199521) (xy 68.97166 -300.248098)
			(xy 68.956076 -300.294779) (xy 68.933205 -300.338356) (xy 68.90364 -300.3777) (xy 68.868147 -300.411792)
			(xy 68.827644 -300.439748) (xy 68.783182 -300.460846) (xy 68.735911 -300.474538) (xy 68.687056 -300.48047)
			(xy 68.637881 -300.478489) (xy 68.589662 -300.468645) (xy 68.543646 -300.451193) (xy 68.501025 -300.426586)
			(xy 68.462904 -300.395461) (xy 68.430269 -300.358624) (xy 68.403966 -300.317028) (xy 68.384675 -300.271752)
			(xy 68.372898 -300.223968) (xy 68.368938 -300.174914) (xy 68.03009 -300.174914) (xy 68.029595 -300.199521)
			(xy 68.0217 -300.248098) (xy 68.006116 -300.294779) (xy 67.983245 -300.338356) (xy 67.95368 -300.3777)
			(xy 67.918187 -300.411792) (xy 67.877684 -300.439748) (xy 67.833222 -300.460846) (xy 67.785951 -300.474538)
			(xy 67.737096 -300.48047) (xy 67.687921 -300.478489) (xy 67.639702 -300.468645) (xy 67.593686 -300.451193)
			(xy 67.551065 -300.426586) (xy 67.512944 -300.395461) (xy 67.480309 -300.358624) (xy 67.454006 -300.317028)
			(xy 67.434715 -300.271752) (xy 67.422938 -300.223968) (xy 67.418978 -300.174914) (xy 67.08013 -300.174914)
			(xy 67.079635 -300.199521) (xy 67.07174 -300.248098) (xy 67.056156 -300.294779) (xy 67.033285 -300.338356)
			(xy 67.00372 -300.3777) (xy 66.968227 -300.411792) (xy 66.927724 -300.439748) (xy 66.883262 -300.460846)
			(xy 66.835991 -300.474538) (xy 66.787136 -300.48047) (xy 66.737961 -300.478489) (xy 66.689742 -300.468645)
			(xy 66.643726 -300.451193) (xy 66.601105 -300.426586) (xy 66.562984 -300.395461) (xy 66.530349 -300.358624)
			(xy 66.504046 -300.317028) (xy 66.484755 -300.271752) (xy 66.472978 -300.223968) (xy 66.469018 -300.174914)
			(xy 66.13017 -300.174914) (xy 66.129675 -300.199521) (xy 66.12178 -300.248098) (xy 66.106196 -300.294779)
			(xy 66.083325 -300.338356) (xy 66.05376 -300.3777) (xy 66.018267 -300.411792) (xy 65.977764 -300.439748)
			(xy 65.933302 -300.460846) (xy 65.886031 -300.474538) (xy 65.837176 -300.48047) (xy 65.788001 -300.478489)
			(xy 65.739782 -300.468645) (xy 65.693766 -300.451193) (xy 65.651145 -300.426586) (xy 65.613024 -300.395461)
			(xy 65.580389 -300.358624) (xy 65.554086 -300.317028) (xy 65.534795 -300.271752) (xy 65.523018 -300.223968)
			(xy 65.519058 -300.174914) (xy 65.18021 -300.174914) (xy 65.179715 -300.199521) (xy 65.17182 -300.248098)
			(xy 65.156236 -300.294779) (xy 65.133365 -300.338356) (xy 65.1038 -300.3777) (xy 65.068307 -300.411792)
			(xy 65.027804 -300.439748) (xy 64.983342 -300.460846) (xy 64.936071 -300.474538) (xy 64.887216 -300.48047)
			(xy 64.838041 -300.478489) (xy 64.789822 -300.468645) (xy 64.743806 -300.451193) (xy 64.701185 -300.426586)
			(xy 64.663064 -300.395461) (xy 64.630429 -300.358624) (xy 64.604126 -300.317028) (xy 64.584835 -300.271752)
			(xy 64.573058 -300.223968) (xy 64.569098 -300.174914) (xy 64.23025 -300.174914) (xy 64.229755 -300.199521)
			(xy 64.22186 -300.248098) (xy 64.206276 -300.294779) (xy 64.183405 -300.338356) (xy 64.15384 -300.3777)
			(xy 64.118347 -300.411792) (xy 64.077844 -300.439748) (xy 64.033382 -300.460846) (xy 63.986111 -300.474538)
			(xy 63.937256 -300.48047) (xy 63.888081 -300.478489) (xy 63.839862 -300.468645) (xy 63.793846 -300.451193)
			(xy 63.751225 -300.426586) (xy 63.713104 -300.395461) (xy 63.680469 -300.358624) (xy 63.654166 -300.317028)
			(xy 63.634875 -300.271752) (xy 63.623098 -300.223968) (xy 63.619138 -300.174914) (xy 63.28029 -300.174914)
			(xy 63.279795 -300.199521) (xy 63.2719 -300.248098) (xy 63.256316 -300.294779) (xy 63.233445 -300.338356)
			(xy 63.20388 -300.3777) (xy 63.168387 -300.411792) (xy 63.127884 -300.439748) (xy 63.083422 -300.460846)
			(xy 63.036151 -300.474538) (xy 62.987296 -300.48047) (xy 62.938121 -300.478489) (xy 62.889902 -300.468645)
			(xy 62.843886 -300.451193) (xy 62.801265 -300.426586) (xy 62.763144 -300.395461) (xy 62.730509 -300.358624)
			(xy 62.704206 -300.317028) (xy 62.684915 -300.271752) (xy 62.673138 -300.223968) (xy 62.669178 -300.174914)
			(xy 62.330076 -300.174914) (xy 62.329581 -300.199521) (xy 62.321686 -300.248098) (xy 62.306102 -300.294779)
			(xy 62.283231 -300.338356) (xy 62.253666 -300.3777) (xy 62.218173 -300.411792) (xy 62.17767 -300.439748)
			(xy 62.133208 -300.460846) (xy 62.085937 -300.474538) (xy 62.037082 -300.48047) (xy 61.987907 -300.478489)
			(xy 61.939688 -300.468645) (xy 61.893672 -300.451193) (xy 61.851051 -300.426586) (xy 61.81293 -300.395461)
			(xy 61.780295 -300.358624) (xy 61.753992 -300.317028) (xy 61.734701 -300.271752) (xy 61.722924 -300.223968)
			(xy 61.718964 -300.174914) (xy 61.380116 -300.174914) (xy 61.379621 -300.199521) (xy 61.371726 -300.248098)
			(xy 61.356142 -300.294779) (xy 61.333271 -300.338356) (xy 61.303706 -300.3777) (xy 61.268213 -300.411792)
			(xy 61.22771 -300.439748) (xy 61.183248 -300.460846) (xy 61.135977 -300.474538) (xy 61.087122 -300.48047)
			(xy 61.037947 -300.478489) (xy 60.989728 -300.468645) (xy 60.943712 -300.451193) (xy 60.901091 -300.426586)
			(xy 60.86297 -300.395461) (xy 60.830335 -300.358624) (xy 60.804032 -300.317028) (xy 60.784741 -300.271752)
			(xy 60.772964 -300.223968) (xy 60.769004 -300.174914) (xy 60.430156 -300.174914) (xy 60.429661 -300.199521)
			(xy 60.421766 -300.248098) (xy 60.406182 -300.294779) (xy 60.383311 -300.338356) (xy 60.353746 -300.3777)
			(xy 60.318253 -300.411792) (xy 60.27775 -300.439748) (xy 60.233288 -300.460846) (xy 60.186017 -300.474538)
			(xy 60.137162 -300.48047) (xy 60.087987 -300.478489) (xy 60.039768 -300.468645) (xy 59.993752 -300.451193)
			(xy 59.951131 -300.426586) (xy 59.91301 -300.395461) (xy 59.880375 -300.358624) (xy 59.854072 -300.317028)
			(xy 59.834781 -300.271752) (xy 59.823004 -300.223968) (xy 59.819044 -300.174914) (xy 58.530236 -300.174914)
			(xy 58.529741 -300.199521) (xy 58.521846 -300.248098) (xy 58.506262 -300.294779) (xy 58.483391 -300.338356)
			(xy 58.453826 -300.3777) (xy 58.418333 -300.411792) (xy 58.37783 -300.439748) (xy 58.333368 -300.460846)
			(xy 58.286097 -300.474538) (xy 58.237242 -300.48047) (xy 58.188067 -300.478489) (xy 58.139848 -300.468645)
			(xy 58.093832 -300.451193) (xy 58.051211 -300.426586) (xy 58.01309 -300.395461) (xy 57.980455 -300.358624)
			(xy 57.954152 -300.317028) (xy 57.934861 -300.271752) (xy 57.923084 -300.223968) (xy 57.919124 -300.174914)
			(xy 57.580276 -300.174914) (xy 57.579781 -300.199521) (xy 57.571886 -300.248098) (xy 57.556302 -300.294779)
			(xy 57.533431 -300.338356) (xy 57.503866 -300.3777) (xy 57.468373 -300.411792) (xy 57.42787 -300.439748)
			(xy 57.383408 -300.460846) (xy 57.336137 -300.474538) (xy 57.287282 -300.48047) (xy 57.238107 -300.478489)
			(xy 57.189888 -300.468645) (xy 57.143872 -300.451193) (xy 57.101251 -300.426586) (xy 57.06313 -300.395461)
			(xy 57.030495 -300.358624) (xy 57.004192 -300.317028) (xy 56.984901 -300.271752) (xy 56.973124 -300.223968)
			(xy 56.969164 -300.174914) (xy 56.630062 -300.174914) (xy 56.629567 -300.199521) (xy 56.621672 -300.248098)
			(xy 56.606088 -300.294779) (xy 56.583217 -300.338356) (xy 56.553652 -300.3777) (xy 56.518159 -300.411792)
			(xy 56.477656 -300.439748) (xy 56.433194 -300.460846) (xy 56.385923 -300.474538) (xy 56.337068 -300.48047)
			(xy 56.287893 -300.478489) (xy 56.239674 -300.468645) (xy 56.193658 -300.451193) (xy 56.151037 -300.426586)
			(xy 56.112916 -300.395461) (xy 56.080281 -300.358624) (xy 56.053978 -300.317028) (xy 56.034687 -300.271752)
			(xy 56.02291 -300.223968) (xy 56.01895 -300.174914) (xy 55.680102 -300.174914) (xy 55.679607 -300.199521)
			(xy 55.671712 -300.248098) (xy 55.656128 -300.294779) (xy 55.633257 -300.338356) (xy 55.603692 -300.3777)
			(xy 55.568199 -300.411792) (xy 55.527696 -300.439748) (xy 55.483234 -300.460846) (xy 55.435963 -300.474538)
			(xy 55.387108 -300.48047) (xy 55.337933 -300.478489) (xy 55.289714 -300.468645) (xy 55.243698 -300.451193)
			(xy 55.201077 -300.426586) (xy 55.162956 -300.395461) (xy 55.130321 -300.358624) (xy 55.104018 -300.317028)
			(xy 55.084727 -300.271752) (xy 55.07295 -300.223968) (xy 55.06899 -300.174914) (xy 54.730142 -300.174914)
			(xy 54.729647 -300.199521) (xy 54.721752 -300.248098) (xy 54.706168 -300.294779) (xy 54.683297 -300.338356)
			(xy 54.653732 -300.3777) (xy 54.618239 -300.411792) (xy 54.577736 -300.439748) (xy 54.533274 -300.460846)
			(xy 54.486003 -300.474538) (xy 54.437148 -300.48047) (xy 54.387973 -300.478489) (xy 54.339754 -300.468645)
			(xy 54.293738 -300.451193) (xy 54.251117 -300.426586) (xy 54.212996 -300.395461) (xy 54.180361 -300.358624)
			(xy 54.154058 -300.317028) (xy 54.134767 -300.271752) (xy 54.12299 -300.223968) (xy 54.11903 -300.174914)
			(xy 53.780182 -300.174914) (xy 53.779687 -300.199521) (xy 53.771792 -300.248098) (xy 53.756208 -300.294779)
			(xy 53.733337 -300.338356) (xy 53.703772 -300.3777) (xy 53.668279 -300.411792) (xy 53.627776 -300.439748)
			(xy 53.583314 -300.460846) (xy 53.536043 -300.474538) (xy 53.487188 -300.48047) (xy 53.438013 -300.478489)
			(xy 53.389794 -300.468645) (xy 53.343778 -300.451193) (xy 53.301157 -300.426586) (xy 53.263036 -300.395461)
			(xy 53.230401 -300.358624) (xy 53.204098 -300.317028) (xy 53.184807 -300.271752) (xy 53.17303 -300.223968)
			(xy 53.16907 -300.174914) (xy 52.830222 -300.174914) (xy 52.829727 -300.199521) (xy 52.821832 -300.248098)
			(xy 52.806248 -300.294779) (xy 52.783377 -300.338356) (xy 52.753812 -300.3777) (xy 52.718319 -300.411792)
			(xy 52.677816 -300.439748) (xy 52.633354 -300.460846) (xy 52.586083 -300.474538) (xy 52.537228 -300.48047)
			(xy 52.488053 -300.478489) (xy 52.439834 -300.468645) (xy 52.393818 -300.451193) (xy 52.351197 -300.426586)
			(xy 52.313076 -300.395461) (xy 52.280441 -300.358624) (xy 52.254138 -300.317028) (xy 52.234847 -300.271752)
			(xy 52.22307 -300.223968) (xy 52.21911 -300.174914) (xy 51.880262 -300.174914) (xy 51.879767 -300.199521)
			(xy 51.871872 -300.248098) (xy 51.856288 -300.294779) (xy 51.833417 -300.338356) (xy 51.803852 -300.3777)
			(xy 51.768359 -300.411792) (xy 51.727856 -300.439748) (xy 51.683394 -300.460846) (xy 51.636123 -300.474538)
			(xy 51.587268 -300.48047) (xy 51.538093 -300.478489) (xy 51.489874 -300.468645) (xy 51.443858 -300.451193)
			(xy 51.401237 -300.426586) (xy 51.363116 -300.395461) (xy 51.330481 -300.358624) (xy 51.304178 -300.317028)
			(xy 51.284887 -300.271752) (xy 51.27311 -300.223968) (xy 51.26915 -300.174914) (xy 50.930302 -300.174914)
			(xy 50.929807 -300.199521) (xy 50.921912 -300.248098) (xy 50.906328 -300.294779) (xy 50.883457 -300.338356)
			(xy 50.853892 -300.3777) (xy 50.818399 -300.411792) (xy 50.777896 -300.439748) (xy 50.733434 -300.460846)
			(xy 50.686163 -300.474538) (xy 50.637308 -300.48047) (xy 50.588133 -300.478489) (xy 50.539914 -300.468645)
			(xy 50.493898 -300.451193) (xy 50.451277 -300.426586) (xy 50.413156 -300.395461) (xy 50.380521 -300.358624)
			(xy 50.354218 -300.317028) (xy 50.334927 -300.271752) (xy 50.32315 -300.223968) (xy 50.31919 -300.174914)
			(xy 49.980088 -300.174914) (xy 49.979593 -300.199521) (xy 49.971698 -300.248098) (xy 49.956114 -300.294779)
			(xy 49.933243 -300.338356) (xy 49.903678 -300.3777) (xy 49.868185 -300.411792) (xy 49.827682 -300.439748)
			(xy 49.78322 -300.460846) (xy 49.735949 -300.474538) (xy 49.687094 -300.48047) (xy 49.637919 -300.478489)
			(xy 49.5897 -300.468645) (xy 49.543684 -300.451193) (xy 49.501063 -300.426586) (xy 49.462942 -300.395461)
			(xy 49.430307 -300.358624) (xy 49.404004 -300.317028) (xy 49.384713 -300.271752) (xy 49.372936 -300.223968)
			(xy 49.368976 -300.174914) (xy 49.030128 -300.174914) (xy 49.029633 -300.199521) (xy 49.021738 -300.248098)
			(xy 49.006154 -300.294779) (xy 48.983283 -300.338356) (xy 48.953718 -300.3777) (xy 48.918225 -300.411792)
			(xy 48.877722 -300.439748) (xy 48.83326 -300.460846) (xy 48.785989 -300.474538) (xy 48.737134 -300.48047)
			(xy 48.687959 -300.478489) (xy 48.63974 -300.468645) (xy 48.593724 -300.451193) (xy 48.551103 -300.426586)
			(xy 48.512982 -300.395461) (xy 48.480347 -300.358624) (xy 48.454044 -300.317028) (xy 48.434753 -300.271752)
			(xy 48.422976 -300.223968) (xy 48.419016 -300.174914) (xy 48.080168 -300.174914) (xy 48.079673 -300.199521)
			(xy 48.071778 -300.248098) (xy 48.056194 -300.294779) (xy 48.033323 -300.338356) (xy 48.003758 -300.3777)
			(xy 47.968265 -300.411792) (xy 47.927762 -300.439748) (xy 47.8833 -300.460846) (xy 47.836029 -300.474538)
			(xy 47.787174 -300.48047) (xy 47.737999 -300.478489) (xy 47.68978 -300.468645) (xy 47.643764 -300.451193)
			(xy 47.601143 -300.426586) (xy 47.563022 -300.395461) (xy 47.530387 -300.358624) (xy 47.504084 -300.317028)
			(xy 47.484793 -300.271752) (xy 47.473016 -300.223968) (xy 47.469056 -300.174914) (xy 46.180248 -300.174914)
			(xy 46.179753 -300.199521) (xy 46.171858 -300.248098) (xy 46.156274 -300.294779) (xy 46.133403 -300.338356)
			(xy 46.103838 -300.3777) (xy 46.068345 -300.411792) (xy 46.027842 -300.439748) (xy 45.98338 -300.460846)
			(xy 45.936109 -300.474538) (xy 45.887254 -300.48047) (xy 45.838079 -300.478489) (xy 45.78986 -300.468645)
			(xy 45.743844 -300.451193) (xy 45.701223 -300.426586) (xy 45.663102 -300.395461) (xy 45.630467 -300.358624)
			(xy 45.604164 -300.317028) (xy 45.584873 -300.271752) (xy 45.573096 -300.223968) (xy 45.569136 -300.174914)
			(xy 45.230288 -300.174914) (xy 45.229793 -300.199521) (xy 45.221898 -300.248098) (xy 45.206314 -300.294779)
			(xy 45.183443 -300.338356) (xy 45.153878 -300.3777) (xy 45.118385 -300.411792) (xy 45.077882 -300.439748)
			(xy 45.03342 -300.460846) (xy 44.986149 -300.474538) (xy 44.937294 -300.48047) (xy 44.888119 -300.478489)
			(xy 44.8399 -300.468645) (xy 44.793884 -300.451193) (xy 44.751263 -300.426586) (xy 44.713142 -300.395461)
			(xy 44.680507 -300.358624) (xy 44.654204 -300.317028) (xy 44.634913 -300.271752) (xy 44.623136 -300.223968)
			(xy 44.619176 -300.174914) (xy 44.280074 -300.174914) (xy 44.279579 -300.199521) (xy 44.271684 -300.248098)
			(xy 44.2561 -300.294779) (xy 44.233229 -300.338356) (xy 44.203664 -300.3777) (xy 44.168171 -300.411792)
			(xy 44.127668 -300.439748) (xy 44.083206 -300.460846) (xy 44.035935 -300.474538) (xy 43.98708 -300.48047)
			(xy 43.937905 -300.478489) (xy 43.889686 -300.468645) (xy 43.84367 -300.451193) (xy 43.801049 -300.426586)
			(xy 43.762928 -300.395461) (xy 43.730293 -300.358624) (xy 43.70399 -300.317028) (xy 43.684699 -300.271752)
			(xy 43.672922 -300.223968) (xy 43.668962 -300.174914) (xy 42.380154 -300.174914) (xy 42.379979 -300.189097)
			(xy 42.377306 -300.217337) (xy 42.37482 -300.231302) (xy 42.372534 -300.243748) (xy 42.3799 -300.26737)
			(xy 42.45737 -300.34484) (xy 42.480992 -300.352206) (xy 42.493438 -300.34992) (xy 42.507404 -300.347442)
			(xy 42.535643 -300.344771) (xy 42.549826 -300.344586) (xy 42.574644 -300.345106) (xy 42.623627 -300.35314)
			(xy 42.670664 -300.368993) (xy 42.714517 -300.392247) (xy 42.75403 -300.422289) (xy 42.788162 -300.458327)
			(xy 42.816015 -300.499413) (xy 42.836854 -300.544464) (xy 42.85013 -300.592292) (xy 42.855493 -300.641638)
			(xy 42.852803 -300.691202) (xy 42.84213 -300.739678) (xy 42.823754 -300.785788) (xy 42.798162 -300.828319)
			(xy 42.766025 -300.866148) (xy 42.728193 -300.89828) (xy 42.68566 -300.923869) (xy 42.639547 -300.942239)
			(xy 42.591071 -300.952907) (xy 42.541506 -300.955593) (xy 42.492161 -300.950224) (xy 42.444334 -300.936943)
			(xy 42.399285 -300.916099) (xy 42.358202 -300.888242) (xy 42.322167 -300.854106) (xy 42.29213 -300.81459)
			(xy 42.268881 -300.770734) (xy 42.253033 -300.723695) (xy 42.245003 -300.674712) (xy 42.244518 -300.649894)
			(xy 42.244693 -300.635711) (xy 42.247366 -300.607471) (xy 42.249852 -300.593506) (xy 42.252138 -300.58106)
			(xy 42.244772 -300.557438) (xy 42.167302 -300.479968) (xy 42.14368 -300.472602) (xy 42.131234 -300.474888)
			(xy 42.117269 -300.477369) (xy 42.089029 -300.480038) (xy 42.074846 -300.480222) (xy 42.060663 -300.480039)
			(xy 42.032423 -300.477371) (xy 42.018458 -300.474888) (xy 42.006012 -300.472602) (xy 41.98239 -300.479968)
			(xy 41.90492 -300.557438) (xy 41.897554 -300.58106) (xy 41.89984 -300.593506) (xy 41.902313 -300.607472)
			(xy 41.904987 -300.635712) (xy 41.905174 -300.649894) (xy 41.904652 -300.675149) (xy 41.896339 -300.724971)
			(xy 41.879938 -300.772745) (xy 41.855897 -300.817168) (xy 41.824873 -300.857028) (xy 41.787711 -300.891238)
			(xy 41.745425 -300.918864) (xy 41.699169 -300.939154) (xy 41.650204 -300.951554) (xy 41.599866 -300.955725)
			(xy 41.549528 -300.951554) (xy 41.500563 -300.939154) (xy 41.454307 -300.918864) (xy 41.412021 -300.891238)
			(xy 41.374859 -300.857028) (xy 41.343835 -300.817168) (xy 41.319794 -300.772745) (xy 41.303393 -300.724971)
			(xy 41.29508 -300.675149) (xy 41.294558 -300.649894) (xy 41.294734 -300.635711) (xy 41.297407 -300.607471)
			(xy 41.299892 -300.593506) (xy 41.302178 -300.58106) (xy 41.294812 -300.557438) (xy 41.217342 -300.479968)
			(xy 41.19372 -300.472602) (xy 41.181274 -300.474888) (xy 41.167308 -300.477364) (xy 41.139069 -300.480036)
			(xy 41.124886 -300.480222) (xy 41.110703 -300.480047) (xy 41.082463 -300.477374) (xy 41.068498 -300.474888)
			(xy 41.056052 -300.472602) (xy 41.03243 -300.479968) (xy 40.95496 -300.557438) (xy 40.947594 -300.58106)
			(xy 40.94988 -300.593506) (xy 40.952353 -300.607472) (xy 40.955027 -300.635712) (xy 40.955214 -300.649894)
			(xy 40.954729 -300.674716) (xy 40.946698 -300.723705) (xy 40.930848 -300.77075) (xy 40.907595 -300.81461)
			(xy 40.877553 -300.854131) (xy 40.841513 -300.888271) (xy 40.800424 -300.916131) (xy 40.755369 -300.936976)
			(xy 40.707536 -300.950257) (xy 40.658184 -300.955625) (xy 40.608614 -300.952937) (xy 40.560131 -300.942266)
			(xy 40.514014 -300.923891) (xy 40.471477 -300.898298) (xy 40.433641 -300.866159) (xy 40.401502 -300.828323)
			(xy 40.375909 -300.785786) (xy 40.357534 -300.739669) (xy 40.346863 -300.691186) (xy 40.344175 -300.641616)
			(xy 40.005087 -300.641616) (xy 40.005254 -300.649894) (xy 40.004759 -300.674501) (xy 39.996864 -300.723078)
			(xy 39.98128 -300.769759) (xy 39.958409 -300.813336) (xy 39.928844 -300.85268) (xy 39.893351 -300.886772)
			(xy 39.852848 -300.914728) (xy 39.808386 -300.935826) (xy 39.761115 -300.949518) (xy 39.71226 -300.95545)
			(xy 39.663085 -300.953469) (xy 39.614866 -300.943625) (xy 39.56885 -300.926173) (xy 39.526229 -300.901566)
			(xy 39.488108 -300.870441) (xy 39.455473 -300.833604) (xy 39.42917 -300.792008) (xy 39.409879 -300.746732)
			(xy 39.398102 -300.698948) (xy 39.394142 -300.649894) (xy 39.055294 -300.649894) (xy 39.054799 -300.674501)
			(xy 39.046904 -300.723078) (xy 39.03132 -300.769759) (xy 39.008449 -300.813336) (xy 38.978884 -300.85268)
			(xy 38.943391 -300.886772) (xy 38.902888 -300.914728) (xy 38.858426 -300.935826) (xy 38.811155 -300.949518)
			(xy 38.7623 -300.95545) (xy 38.713125 -300.953469) (xy 38.664906 -300.943625) (xy 38.61889 -300.926173)
			(xy 38.576269 -300.901566) (xy 38.538148 -300.870441) (xy 38.505513 -300.833604) (xy 38.47921 -300.792008)
			(xy 38.459919 -300.746732) (xy 38.448142 -300.698948) (xy 38.444182 -300.649894) (xy 38.10508 -300.649894)
			(xy 38.104585 -300.674501) (xy 38.09669 -300.723078) (xy 38.081106 -300.769759) (xy 38.058235 -300.813336)
			(xy 38.02867 -300.85268) (xy 37.993177 -300.886772) (xy 37.952674 -300.914728) (xy 37.908212 -300.935826)
			(xy 37.860941 -300.949518) (xy 37.812086 -300.95545) (xy 37.762911 -300.953469) (xy 37.714692 -300.943625)
			(xy 37.668676 -300.926173) (xy 37.626055 -300.901566) (xy 37.587934 -300.870441) (xy 37.555299 -300.833604)
			(xy 37.528996 -300.792008) (xy 37.509705 -300.746732) (xy 37.497928 -300.698948) (xy 37.493968 -300.649894)
			(xy 37.15512 -300.649894) (xy 37.154625 -300.674501) (xy 37.14673 -300.723078) (xy 37.131146 -300.769759)
			(xy 37.108275 -300.813336) (xy 37.07871 -300.85268) (xy 37.043217 -300.886772) (xy 37.002714 -300.914728)
			(xy 36.958252 -300.935826) (xy 36.910981 -300.949518) (xy 36.862126 -300.95545) (xy 36.812951 -300.953469)
			(xy 36.764732 -300.943625) (xy 36.718716 -300.926173) (xy 36.676095 -300.901566) (xy 36.637974 -300.870441)
			(xy 36.605339 -300.833604) (xy 36.579036 -300.792008) (xy 36.559745 -300.746732) (xy 36.547968 -300.698948)
			(xy 36.544008 -300.649894) (xy 26.674232 -300.649894) (xy 26.645843 -300.681578) (xy 26.602975 -300.717253)
			(xy 26.555369 -300.746307) (xy 26.50404 -300.768119) (xy 26.450083 -300.782225) (xy 26.394646 -300.788325)
			(xy 26.338912 -300.786288) (xy 26.284069 -300.776158) (xy 26.231285 -300.758151) (xy 26.181685 -300.73265)
			(xy 26.136327 -300.700199) (xy 26.096178 -300.66149) (xy 26.062092 -300.617347) (xy 26.034796 -300.568712)
			(xy 26.014873 -300.516621) (xy 26.002747 -300.462184) (xy 25.998676 -300.406562) (xy 23.392085 -300.406562)
			(xy 23.402785 -300.439493) (xy 23.445881 -300.597776) (xy 23.481279 -300.757956) (xy 23.508898 -300.91966)
			(xy 23.528671 -301.082509) (xy 23.540554 -301.246123) (xy 23.544518 -301.41012) (xy 23.540554 -301.574117)
			(xy 23.538685 -301.599854) (xy 36.544008 -301.599854) (xy 36.547968 -301.5508) (xy 36.559745 -301.503016)
			(xy 36.579036 -301.45774) (xy 36.605339 -301.416144) (xy 36.637974 -301.379307) (xy 36.676095 -301.348182)
			(xy 36.718716 -301.323575) (xy 36.764732 -301.306123) (xy 36.812951 -301.296279) (xy 36.862126 -301.294298)
			(xy 36.910981 -301.30023) (xy 36.958252 -301.313922) (xy 37.002714 -301.33502) (xy 37.043217 -301.362976)
			(xy 37.07871 -301.397068) (xy 37.108275 -301.436412) (xy 37.131146 -301.479989) (xy 37.14673 -301.52667)
			(xy 37.154625 -301.575247) (xy 37.15512 -301.599854) (xy 37.493968 -301.599854) (xy 37.497928 -301.5508)
			(xy 37.509705 -301.503016) (xy 37.528996 -301.45774) (xy 37.555299 -301.416144) (xy 37.587934 -301.379307)
			(xy 37.626055 -301.348182) (xy 37.668676 -301.323575) (xy 37.714692 -301.306123) (xy 37.762911 -301.296279)
			(xy 37.812086 -301.294298) (xy 37.860941 -301.30023) (xy 37.908212 -301.313922) (xy 37.952674 -301.33502)
			(xy 37.993177 -301.362976) (xy 38.02867 -301.397068) (xy 38.058235 -301.436412) (xy 38.081106 -301.479989)
			(xy 38.09669 -301.52667) (xy 38.104585 -301.575247) (xy 38.10508 -301.599854) (xy 38.104585 -301.624461)
			(xy 38.104406 -301.625562) (xy 38.423338 -301.625562) (xy 38.423338 -301.574146) (xy 38.431381 -301.523364)
			(xy 38.447269 -301.474465) (xy 38.470612 -301.428653) (xy 38.500833 -301.387057) (xy 38.537189 -301.350701)
			(xy 38.578785 -301.32048) (xy 38.624597 -301.297137) (xy 38.673496 -301.281249) (xy 38.724278 -301.273206)
			(xy 38.775694 -301.273206) (xy 38.826476 -301.281249) (xy 38.875375 -301.297137) (xy 38.921187 -301.32048)
			(xy 38.962783 -301.350701) (xy 38.999139 -301.387057) (xy 39.02936 -301.428653) (xy 39.052703 -301.474465)
			(xy 39.068591 -301.523364) (xy 39.076634 -301.574146) (xy 39.077138 -301.599854) (xy 39.076634 -301.625562)
			(xy 39.373298 -301.625562) (xy 39.373298 -301.574146) (xy 39.381341 -301.523364) (xy 39.397229 -301.474465)
			(xy 39.420572 -301.428653) (xy 39.450793 -301.387057) (xy 39.487149 -301.350701) (xy 39.528745 -301.32048)
			(xy 39.574557 -301.297137) (xy 39.623456 -301.281249) (xy 39.674238 -301.273206) (xy 39.725654 -301.273206)
			(xy 39.776436 -301.281249) (xy 39.825335 -301.297137) (xy 39.871147 -301.32048) (xy 39.912743 -301.350701)
			(xy 39.949099 -301.387057) (xy 39.97932 -301.428653) (xy 40.002663 -301.474465) (xy 40.018551 -301.523364)
			(xy 40.026594 -301.574146) (xy 40.027098 -301.599854) (xy 40.344102 -301.599854) (xy 40.348062 -301.5508)
			(xy 40.359839 -301.503016) (xy 40.37913 -301.45774) (xy 40.405433 -301.416144) (xy 40.438068 -301.379307)
			(xy 40.476189 -301.348182) (xy 40.51881 -301.323575) (xy 40.564826 -301.306123) (xy 40.613045 -301.296279)
			(xy 40.66222 -301.294298) (xy 40.711075 -301.30023) (xy 40.758346 -301.313922) (xy 40.802808 -301.33502)
			(xy 40.843311 -301.362976) (xy 40.878804 -301.397068) (xy 40.908369 -301.436412) (xy 40.93124 -301.479989)
			(xy 40.946824 -301.52667) (xy 40.954719 -301.575247) (xy 40.955214 -301.599854) (xy 40.954719 -301.624461)
			(xy 40.95454 -301.625562) (xy 41.273218 -301.625562) (xy 41.273218 -301.574146) (xy 41.281261 -301.523364)
			(xy 41.297149 -301.474465) (xy 41.320492 -301.428653) (xy 41.350713 -301.387057) (xy 41.387069 -301.350701)
			(xy 41.428665 -301.32048) (xy 41.474477 -301.297137) (xy 41.523376 -301.281249) (xy 41.574158 -301.273206)
			(xy 41.625574 -301.273206) (xy 41.676356 -301.281249) (xy 41.725255 -301.297137) (xy 41.771067 -301.32048)
			(xy 41.812663 -301.350701) (xy 41.849019 -301.387057) (xy 41.87924 -301.428653) (xy 41.902583 -301.474465)
			(xy 41.918471 -301.523364) (xy 41.926514 -301.574146) (xy 41.927018 -301.599854) (xy 41.926514 -301.625562)
			(xy 42.223178 -301.625562) (xy 42.223178 -301.574146) (xy 42.231221 -301.523364) (xy 42.247109 -301.474465)
			(xy 42.270452 -301.428653) (xy 42.300673 -301.387057) (xy 42.337029 -301.350701) (xy 42.378625 -301.32048)
			(xy 42.424437 -301.297137) (xy 42.473336 -301.281249) (xy 42.524118 -301.273206) (xy 42.575534 -301.273206)
			(xy 42.626316 -301.281249) (xy 42.675215 -301.297137) (xy 42.721027 -301.32048) (xy 42.762623 -301.350701)
			(xy 42.798979 -301.387057) (xy 42.8292 -301.428653) (xy 42.852543 -301.474465) (xy 42.868431 -301.523364)
			(xy 42.876474 -301.574146) (xy 42.876817 -301.591642) (xy 43.194034 -301.591642) (xy 43.199398 -301.542282)
			(xy 43.212678 -301.49444) (xy 43.233522 -301.449377) (xy 43.261382 -301.40828) (xy 43.295525 -301.372232)
			(xy 43.335049 -301.342183) (xy 43.378914 -301.318924) (xy 43.425965 -301.303068) (xy 43.474961 -301.295033)
			(xy 43.499786 -301.294546) (xy 43.513969 -301.294725) (xy 43.542209 -301.297396) (xy 43.556174 -301.29988)
			(xy 43.56862 -301.302166) (xy 43.592242 -301.2948) (xy 43.669712 -301.21733) (xy 43.677078 -301.193708)
			(xy 43.674792 -301.181262) (xy 43.672314 -301.167296) (xy 43.669643 -301.139057) (xy 43.669458 -301.124874)
			(xy 43.66998 -301.099619) (xy 43.678293 -301.049797) (xy 43.694694 -301.002023) (xy 43.718735 -300.9576)
			(xy 43.749759 -300.91774) (xy 43.786921 -300.88353) (xy 43.829207 -300.855904) (xy 43.875463 -300.835614)
			(xy 43.924428 -300.823214) (xy 43.974766 -300.819043) (xy 44.025104 -300.823214) (xy 44.074069 -300.835614)
			(xy 44.120325 -300.855904) (xy 44.162611 -300.88353) (xy 44.199773 -300.91774) (xy 44.230797 -300.9576)
			(xy 44.254838 -301.002023) (xy 44.271239 -301.049797) (xy 44.279552 -301.099619) (xy 44.280074 -301.124874)
			(xy 44.279894 -301.139057) (xy 44.277224 -301.167297) (xy 44.27474 -301.181262) (xy 44.272454 -301.193708)
			(xy 44.27982 -301.21733) (xy 44.35729 -301.2948) (xy 44.380912 -301.302166) (xy 44.393358 -301.29988)
			(xy 44.407323 -301.297399) (xy 44.435563 -301.29473) (xy 44.449746 -301.294546) (xy 44.463993 -301.294708)
			(xy 44.492361 -301.29738) (xy 44.506388 -301.29988) (xy 44.518834 -301.302166) (xy 44.542456 -301.2948)
			(xy 44.611036 -301.226474) (xy 44.619226 -301.217262) (xy 44.626513 -301.193752) (xy 44.625006 -301.181516)
			(xy 44.625006 -301.181008) (xy 44.622547 -301.167104) (xy 44.619873 -301.138993) (xy 44.619672 -301.124874)
			(xy 44.620194 -301.099619) (xy 44.628507 -301.049797) (xy 44.644908 -301.002023) (xy 44.668949 -300.9576)
			(xy 44.699973 -300.91774) (xy 44.737135 -300.88353) (xy 44.779421 -300.855904) (xy 44.825677 -300.835614)
			(xy 44.874642 -300.823214) (xy 44.92498 -300.819043) (xy 44.975318 -300.823214) (xy 45.024283 -300.835614)
			(xy 45.070539 -300.855904) (xy 45.112825 -300.88353) (xy 45.149987 -300.91774) (xy 45.181011 -300.9576)
			(xy 45.205052 -301.002023) (xy 45.221453 -301.049797) (xy 45.229766 -301.099619) (xy 45.230288 -301.124874)
			(xy 45.230108 -301.139057) (xy 45.227438 -301.167297) (xy 45.224954 -301.181262) (xy 45.222668 -301.193708)
			(xy 45.230034 -301.21733) (xy 45.307504 -301.2948) (xy 45.331126 -301.302166) (xy 45.343572 -301.29988)
			(xy 45.357537 -301.297397) (xy 45.385777 -301.29473) (xy 45.39996 -301.294546) (xy 45.424786 -301.295035)
			(xy 45.473784 -301.303062) (xy 45.520838 -301.31891) (xy 45.564707 -301.342163) (xy 45.604237 -301.372207)
			(xy 45.638385 -301.40825) (xy 45.666252 -301.449344) (xy 45.687102 -301.494405) (xy 45.700388 -301.542245)
			(xy 45.705759 -301.591605) (xy 45.705758 -301.591619) (xy 46.044135 -301.591619) (xy 46.049503 -301.542258)
			(xy 46.062786 -301.494417) (xy 46.083635 -301.449354) (xy 46.1115 -301.408259) (xy 46.145646 -301.372213)
			(xy 46.185174 -301.342167) (xy 46.229043 -301.318911) (xy 46.276096 -301.30306) (xy 46.325094 -301.29503)
			(xy 46.34992 -301.294546) (xy 46.364103 -301.294721) (xy 46.392343 -301.297394) (xy 46.406308 -301.29988)
			(xy 46.420268 -301.302096) (xy 46.448409 -301.299514) (xy 46.474764 -301.289319) (xy 46.497316 -301.27229)
			(xy 46.514337 -301.249732) (xy 46.524523 -301.223373) (xy 46.527094 -301.195232) (xy 46.524926 -301.181262)
			(xy 46.522448 -301.167296) (xy 46.519777 -301.139057) (xy 46.519592 -301.124874) (xy 46.520106 -301.100056)
			(xy 46.52814 -301.051074) (xy 46.543993 -301.004037) (xy 46.567247 -300.960184) (xy 46.597288 -300.920671)
			(xy 46.633327 -300.886538) (xy 46.674412 -300.858686) (xy 46.719462 -300.837847) (xy 46.767291 -300.82457)
			(xy 46.816636 -300.819207) (xy 46.8662 -300.821897) (xy 46.914676 -300.83257) (xy 46.960786 -300.850944)
			(xy 47.003316 -300.876537) (xy 47.041146 -300.908672) (xy 47.073278 -300.946505) (xy 47.098867 -300.989037)
			(xy 47.117238 -301.035149) (xy 47.127907 -301.083626) (xy 47.130142 -301.124874) (xy 47.469056 -301.124874)
			(xy 47.473016 -301.07582) (xy 47.484793 -301.028036) (xy 47.504084 -300.98276) (xy 47.530387 -300.941164)
			(xy 47.563022 -300.904327) (xy 47.601143 -300.873202) (xy 47.643764 -300.848595) (xy 47.68978 -300.831143)
			(xy 47.737999 -300.821299) (xy 47.787174 -300.819318) (xy 47.836029 -300.82525) (xy 47.8833 -300.838942)
			(xy 47.927762 -300.86004) (xy 47.968265 -300.887996) (xy 48.003758 -300.922088) (xy 48.033323 -300.961432)
			(xy 48.056194 -301.005009) (xy 48.071778 -301.05169) (xy 48.079673 -301.100267) (xy 48.080168 -301.124874)
			(xy 48.419016 -301.124874) (xy 48.422976 -301.07582) (xy 48.434753 -301.028036) (xy 48.454044 -300.98276)
			(xy 48.480347 -300.941164) (xy 48.512982 -300.904327) (xy 48.551103 -300.873202) (xy 48.593724 -300.848595)
			(xy 48.63974 -300.831143) (xy 48.687959 -300.821299) (xy 48.737134 -300.819318) (xy 48.785989 -300.82525)
			(xy 48.83326 -300.838942) (xy 48.877722 -300.86004) (xy 48.918225 -300.887996) (xy 48.953718 -300.922088)
			(xy 48.983283 -300.961432) (xy 49.006154 -301.005009) (xy 49.021738 -301.05169) (xy 49.029633 -301.100267)
			(xy 49.030128 -301.124874) (xy 49.368976 -301.124874) (xy 49.372936 -301.07582) (xy 49.384713 -301.028036)
			(xy 49.404004 -300.98276) (xy 49.430307 -300.941164) (xy 49.462942 -300.904327) (xy 49.501063 -300.873202)
			(xy 49.543684 -300.848595) (xy 49.5897 -300.831143) (xy 49.637919 -300.821299) (xy 49.687094 -300.819318)
			(xy 49.735949 -300.82525) (xy 49.78322 -300.838942) (xy 49.827682 -300.86004) (xy 49.868185 -300.887996)
			(xy 49.903678 -300.922088) (xy 49.933243 -300.961432) (xy 49.956114 -301.005009) (xy 49.971698 -301.05169)
			(xy 49.979593 -301.100267) (xy 49.980088 -301.124874) (xy 50.31919 -301.124874) (xy 50.32315 -301.07582)
			(xy 50.334927 -301.028036) (xy 50.354218 -300.98276) (xy 50.380521 -300.941164) (xy 50.413156 -300.904327)
			(xy 50.451277 -300.873202) (xy 50.493898 -300.848595) (xy 50.539914 -300.831143) (xy 50.588133 -300.821299)
			(xy 50.637308 -300.819318) (xy 50.686163 -300.82525) (xy 50.733434 -300.838942) (xy 50.777896 -300.86004)
			(xy 50.818399 -300.887996) (xy 50.853892 -300.922088) (xy 50.883457 -300.961432) (xy 50.906328 -301.005009)
			(xy 50.921912 -301.05169) (xy 50.929807 -301.100267) (xy 50.930302 -301.124874) (xy 51.26915 -301.124874)
			(xy 51.27311 -301.07582) (xy 51.284887 -301.028036) (xy 51.304178 -300.98276) (xy 51.330481 -300.941164)
			(xy 51.363116 -300.904327) (xy 51.401237 -300.873202) (xy 51.443858 -300.848595) (xy 51.489874 -300.831143)
			(xy 51.538093 -300.821299) (xy 51.587268 -300.819318) (xy 51.636123 -300.82525) (xy 51.683394 -300.838942)
			(xy 51.727856 -300.86004) (xy 51.768359 -300.887996) (xy 51.803852 -300.922088) (xy 51.833417 -300.961432)
			(xy 51.856288 -301.005009) (xy 51.871872 -301.05169) (xy 51.879767 -301.100267) (xy 51.880262 -301.124874)
			(xy 52.21911 -301.124874) (xy 52.22307 -301.07582) (xy 52.234847 -301.028036) (xy 52.254138 -300.98276)
			(xy 52.280441 -300.941164) (xy 52.313076 -300.904327) (xy 52.351197 -300.873202) (xy 52.393818 -300.848595)
			(xy 52.439834 -300.831143) (xy 52.488053 -300.821299) (xy 52.537228 -300.819318) (xy 52.586083 -300.82525)
			(xy 52.633354 -300.838942) (xy 52.677816 -300.86004) (xy 52.718319 -300.887996) (xy 52.753812 -300.922088)
			(xy 52.783377 -300.961432) (xy 52.806248 -301.005009) (xy 52.821832 -301.05169) (xy 52.829727 -301.100267)
			(xy 52.830222 -301.124874) (xy 53.16907 -301.124874) (xy 53.17303 -301.07582) (xy 53.184807 -301.028036)
			(xy 53.204098 -300.98276) (xy 53.230401 -300.941164) (xy 53.263036 -300.904327) (xy 53.301157 -300.873202)
			(xy 53.343778 -300.848595) (xy 53.389794 -300.831143) (xy 53.438013 -300.821299) (xy 53.487188 -300.819318)
			(xy 53.536043 -300.82525) (xy 53.583314 -300.838942) (xy 53.627776 -300.86004) (xy 53.668279 -300.887996)
			(xy 53.703772 -300.922088) (xy 53.733337 -300.961432) (xy 53.756208 -301.005009) (xy 53.771792 -301.05169)
			(xy 53.779687 -301.100267) (xy 53.780182 -301.124874) (xy 54.11903 -301.124874) (xy 54.12299 -301.07582)
			(xy 54.134767 -301.028036) (xy 54.154058 -300.98276) (xy 54.180361 -300.941164) (xy 54.212996 -300.904327)
			(xy 54.251117 -300.873202) (xy 54.293738 -300.848595) (xy 54.339754 -300.831143) (xy 54.387973 -300.821299)
			(xy 54.437148 -300.819318) (xy 54.486003 -300.82525) (xy 54.533274 -300.838942) (xy 54.577736 -300.86004)
			(xy 54.618239 -300.887996) (xy 54.653732 -300.922088) (xy 54.683297 -300.961432) (xy 54.706168 -301.005009)
			(xy 54.721752 -301.05169) (xy 54.729647 -301.100267) (xy 54.730142 -301.124874) (xy 55.06899 -301.124874)
			(xy 55.07295 -301.07582) (xy 55.084727 -301.028036) (xy 55.104018 -300.98276) (xy 55.130321 -300.941164)
			(xy 55.162956 -300.904327) (xy 55.201077 -300.873202) (xy 55.243698 -300.848595) (xy 55.289714 -300.831143)
			(xy 55.337933 -300.821299) (xy 55.387108 -300.819318) (xy 55.435963 -300.82525) (xy 55.483234 -300.838942)
			(xy 55.527696 -300.86004) (xy 55.568199 -300.887996) (xy 55.603692 -300.922088) (xy 55.633257 -300.961432)
			(xy 55.656128 -301.005009) (xy 55.671712 -301.05169) (xy 55.679607 -301.100267) (xy 55.680102 -301.124874)
			(xy 56.01895 -301.124874) (xy 56.02291 -301.07582) (xy 56.034687 -301.028036) (xy 56.053978 -300.98276)
			(xy 56.080281 -300.941164) (xy 56.112916 -300.904327) (xy 56.151037 -300.873202) (xy 56.193658 -300.848595)
			(xy 56.239674 -300.831143) (xy 56.287893 -300.821299) (xy 56.337068 -300.819318) (xy 56.385923 -300.82525)
			(xy 56.433194 -300.838942) (xy 56.477656 -300.86004) (xy 56.518159 -300.887996) (xy 56.553652 -300.922088)
			(xy 56.583217 -300.961432) (xy 56.606088 -301.005009) (xy 56.621672 -301.05169) (xy 56.629567 -301.100267)
			(xy 56.630062 -301.124874) (xy 56.969164 -301.124874) (xy 56.973124 -301.07582) (xy 56.984901 -301.028036)
			(xy 57.004192 -300.98276) (xy 57.030495 -300.941164) (xy 57.06313 -300.904327) (xy 57.101251 -300.873202)
			(xy 57.143872 -300.848595) (xy 57.189888 -300.831143) (xy 57.238107 -300.821299) (xy 57.287282 -300.819318)
			(xy 57.336137 -300.82525) (xy 57.383408 -300.838942) (xy 57.42787 -300.86004) (xy 57.468373 -300.887996)
			(xy 57.503866 -300.922088) (xy 57.533431 -300.961432) (xy 57.556302 -301.005009) (xy 57.571886 -301.05169)
			(xy 57.579781 -301.100267) (xy 57.580276 -301.124874) (xy 57.919124 -301.124874) (xy 57.923084 -301.07582)
			(xy 57.934861 -301.028036) (xy 57.954152 -300.98276) (xy 57.980455 -300.941164) (xy 58.01309 -300.904327)
			(xy 58.051211 -300.873202) (xy 58.093832 -300.848595) (xy 58.139848 -300.831143) (xy 58.188067 -300.821299)
			(xy 58.237242 -300.819318) (xy 58.286097 -300.82525) (xy 58.333368 -300.838942) (xy 58.37783 -300.86004)
			(xy 58.418333 -300.887996) (xy 58.453826 -300.922088) (xy 58.483391 -300.961432) (xy 58.506262 -301.005009)
			(xy 58.521846 -301.05169) (xy 58.529741 -301.100267) (xy 58.530236 -301.124874) (xy 59.819044 -301.124874)
			(xy 59.823004 -301.07582) (xy 59.834781 -301.028036) (xy 59.854072 -300.98276) (xy 59.880375 -300.941164)
			(xy 59.91301 -300.904327) (xy 59.951131 -300.873202) (xy 59.993752 -300.848595) (xy 60.039768 -300.831143)
			(xy 60.087987 -300.821299) (xy 60.137162 -300.819318) (xy 60.186017 -300.82525) (xy 60.233288 -300.838942)
			(xy 60.27775 -300.86004) (xy 60.318253 -300.887996) (xy 60.353746 -300.922088) (xy 60.383311 -300.961432)
			(xy 60.406182 -301.005009) (xy 60.421766 -301.05169) (xy 60.429661 -301.100267) (xy 60.430156 -301.124874)
			(xy 60.769004 -301.124874) (xy 60.772964 -301.07582) (xy 60.784741 -301.028036) (xy 60.804032 -300.98276)
			(xy 60.830335 -300.941164) (xy 60.86297 -300.904327) (xy 60.901091 -300.873202) (xy 60.943712 -300.848595)
			(xy 60.989728 -300.831143) (xy 61.037947 -300.821299) (xy 61.087122 -300.819318) (xy 61.135977 -300.82525)
			(xy 61.183248 -300.838942) (xy 61.22771 -300.86004) (xy 61.268213 -300.887996) (xy 61.303706 -300.922088)
			(xy 61.333271 -300.961432) (xy 61.356142 -301.005009) (xy 61.371726 -301.05169) (xy 61.379621 -301.100267)
			(xy 61.380116 -301.124874) (xy 61.718964 -301.124874) (xy 61.722924 -301.07582) (xy 61.734701 -301.028036)
			(xy 61.753992 -300.98276) (xy 61.780295 -300.941164) (xy 61.81293 -300.904327) (xy 61.851051 -300.873202)
			(xy 61.893672 -300.848595) (xy 61.939688 -300.831143) (xy 61.987907 -300.821299) (xy 62.037082 -300.819318)
			(xy 62.085937 -300.82525) (xy 62.133208 -300.838942) (xy 62.17767 -300.86004) (xy 62.218173 -300.887996)
			(xy 62.253666 -300.922088) (xy 62.283231 -300.961432) (xy 62.306102 -301.005009) (xy 62.321686 -301.05169)
			(xy 62.329581 -301.100267) (xy 62.330076 -301.124874) (xy 62.669178 -301.124874) (xy 62.673138 -301.07582)
			(xy 62.684915 -301.028036) (xy 62.704206 -300.98276) (xy 62.730509 -300.941164) (xy 62.763144 -300.904327)
			(xy 62.801265 -300.873202) (xy 62.843886 -300.848595) (xy 62.889902 -300.831143) (xy 62.938121 -300.821299)
			(xy 62.987296 -300.819318) (xy 63.036151 -300.82525) (xy 63.083422 -300.838942) (xy 63.127884 -300.86004)
			(xy 63.168387 -300.887996) (xy 63.20388 -300.922088) (xy 63.233445 -300.961432) (xy 63.256316 -301.005009)
			(xy 63.2719 -301.05169) (xy 63.279795 -301.100267) (xy 63.28029 -301.124874) (xy 63.619138 -301.124874)
			(xy 63.623098 -301.07582) (xy 63.634875 -301.028036) (xy 63.654166 -300.98276) (xy 63.680469 -300.941164)
			(xy 63.713104 -300.904327) (xy 63.751225 -300.873202) (xy 63.793846 -300.848595) (xy 63.839862 -300.831143)
			(xy 63.888081 -300.821299) (xy 63.937256 -300.819318) (xy 63.986111 -300.82525) (xy 64.033382 -300.838942)
			(xy 64.077844 -300.86004) (xy 64.118347 -300.887996) (xy 64.15384 -300.922088) (xy 64.183405 -300.961432)
			(xy 64.206276 -301.005009) (xy 64.22186 -301.05169) (xy 64.229755 -301.100267) (xy 64.23025 -301.124874)
			(xy 64.569098 -301.124874) (xy 64.573058 -301.07582) (xy 64.584835 -301.028036) (xy 64.604126 -300.98276)
			(xy 64.630429 -300.941164) (xy 64.663064 -300.904327) (xy 64.701185 -300.873202) (xy 64.743806 -300.848595)
			(xy 64.789822 -300.831143) (xy 64.838041 -300.821299) (xy 64.887216 -300.819318) (xy 64.936071 -300.82525)
			(xy 64.983342 -300.838942) (xy 65.027804 -300.86004) (xy 65.068307 -300.887996) (xy 65.1038 -300.922088)
			(xy 65.133365 -300.961432) (xy 65.156236 -301.005009) (xy 65.17182 -301.05169) (xy 65.179715 -301.100267)
			(xy 65.18021 -301.124874) (xy 65.519058 -301.124874) (xy 65.523018 -301.07582) (xy 65.534795 -301.028036)
			(xy 65.554086 -300.98276) (xy 65.580389 -300.941164) (xy 65.613024 -300.904327) (xy 65.651145 -300.873202)
			(xy 65.693766 -300.848595) (xy 65.739782 -300.831143) (xy 65.788001 -300.821299) (xy 65.837176 -300.819318)
			(xy 65.886031 -300.82525) (xy 65.933302 -300.838942) (xy 65.977764 -300.86004) (xy 66.018267 -300.887996)
			(xy 66.05376 -300.922088) (xy 66.083325 -300.961432) (xy 66.106196 -301.005009) (xy 66.12178 -301.05169)
			(xy 66.129675 -301.100267) (xy 66.13017 -301.124874) (xy 66.469018 -301.124874) (xy 66.472978 -301.07582)
			(xy 66.484755 -301.028036) (xy 66.504046 -300.98276) (xy 66.530349 -300.941164) (xy 66.562984 -300.904327)
			(xy 66.601105 -300.873202) (xy 66.643726 -300.848595) (xy 66.689742 -300.831143) (xy 66.737961 -300.821299)
			(xy 66.787136 -300.819318) (xy 66.835991 -300.82525) (xy 66.883262 -300.838942) (xy 66.927724 -300.86004)
			(xy 66.968227 -300.887996) (xy 67.00372 -300.922088) (xy 67.033285 -300.961432) (xy 67.056156 -301.005009)
			(xy 67.07174 -301.05169) (xy 67.079635 -301.100267) (xy 67.08013 -301.124874) (xy 67.418978 -301.124874)
			(xy 67.422938 -301.07582) (xy 67.434715 -301.028036) (xy 67.454006 -300.98276) (xy 67.480309 -300.941164)
			(xy 67.512944 -300.904327) (xy 67.551065 -300.873202) (xy 67.593686 -300.848595) (xy 67.639702 -300.831143)
			(xy 67.687921 -300.821299) (xy 67.737096 -300.819318) (xy 67.785951 -300.82525) (xy 67.833222 -300.838942)
			(xy 67.877684 -300.86004) (xy 67.918187 -300.887996) (xy 67.95368 -300.922088) (xy 67.983245 -300.961432)
			(xy 68.006116 -301.005009) (xy 68.0217 -301.05169) (xy 68.029595 -301.100267) (xy 68.03009 -301.124874)
			(xy 68.368938 -301.124874) (xy 68.372898 -301.07582) (xy 68.384675 -301.028036) (xy 68.403966 -300.98276)
			(xy 68.430269 -300.941164) (xy 68.462904 -300.904327) (xy 68.501025 -300.873202) (xy 68.543646 -300.848595)
			(xy 68.589662 -300.831143) (xy 68.637881 -300.821299) (xy 68.687056 -300.819318) (xy 68.735911 -300.82525)
			(xy 68.783182 -300.838942) (xy 68.827644 -300.86004) (xy 68.868147 -300.887996) (xy 68.90364 -300.922088)
			(xy 68.933205 -300.961432) (xy 68.956076 -301.005009) (xy 68.97166 -301.05169) (xy 68.979555 -301.100267)
			(xy 68.98005 -301.124874) (xy 69.319152 -301.124874) (xy 69.323112 -301.07582) (xy 69.334889 -301.028036)
			(xy 69.35418 -300.98276) (xy 69.380483 -300.941164) (xy 69.413118 -300.904327) (xy 69.451239 -300.873202)
			(xy 69.49386 -300.848595) (xy 69.539876 -300.831143) (xy 69.588095 -300.821299) (xy 69.63727 -300.819318)
			(xy 69.686125 -300.82525) (xy 69.733396 -300.838942) (xy 69.777858 -300.86004) (xy 69.818361 -300.887996)
			(xy 69.853854 -300.922088) (xy 69.883419 -300.961432) (xy 69.90629 -301.005009) (xy 69.921874 -301.05169)
			(xy 69.929769 -301.100267) (xy 69.930264 -301.124874) (xy 70.269112 -301.124874) (xy 70.273072 -301.07582)
			(xy 70.284849 -301.028036) (xy 70.30414 -300.98276) (xy 70.330443 -300.941164) (xy 70.363078 -300.904327)
			(xy 70.401199 -300.873202) (xy 70.44382 -300.848595) (xy 70.489836 -300.831143) (xy 70.538055 -300.821299)
			(xy 70.58723 -300.819318) (xy 70.636085 -300.82525) (xy 70.683356 -300.838942) (xy 70.727818 -300.86004)
			(xy 70.768321 -300.887996) (xy 70.803814 -300.922088) (xy 70.833379 -300.961432) (xy 70.85625 -301.005009)
			(xy 70.871834 -301.05169) (xy 70.879729 -301.100267) (xy 70.880224 -301.124874) (xy 71.219072 -301.124874)
			(xy 71.223032 -301.07582) (xy 71.234809 -301.028036) (xy 71.2541 -300.98276) (xy 71.280403 -300.941164)
			(xy 71.313038 -300.904327) (xy 71.351159 -300.873202) (xy 71.39378 -300.848595) (xy 71.439796 -300.831143)
			(xy 71.488015 -300.821299) (xy 71.53719 -300.819318) (xy 71.586045 -300.82525) (xy 71.633316 -300.838942)
			(xy 71.677778 -300.86004) (xy 71.718281 -300.887996) (xy 71.753774 -300.922088) (xy 71.783339 -300.961432)
			(xy 71.80621 -301.005009) (xy 71.821794 -301.05169) (xy 71.829689 -301.100267) (xy 71.830184 -301.124874)
			(xy 72.169032 -301.124874) (xy 72.172992 -301.07582) (xy 72.184769 -301.028036) (xy 72.20406 -300.98276)
			(xy 72.230363 -300.941164) (xy 72.262998 -300.904327) (xy 72.301119 -300.873202) (xy 72.34374 -300.848595)
			(xy 72.389756 -300.831143) (xy 72.437975 -300.821299) (xy 72.48715 -300.819318) (xy 72.536005 -300.82525)
			(xy 72.583276 -300.838942) (xy 72.627738 -300.86004) (xy 72.668241 -300.887996) (xy 72.703734 -300.922088)
			(xy 72.733299 -300.961432) (xy 72.75617 -301.005009) (xy 72.771754 -301.05169) (xy 72.779649 -301.100267)
			(xy 72.780144 -301.124874) (xy 73.118992 -301.124874) (xy 73.122952 -301.07582) (xy 73.134729 -301.028036)
			(xy 73.15402 -300.98276) (xy 73.180323 -300.941164) (xy 73.212958 -300.904327) (xy 73.251079 -300.873202)
			(xy 73.2937 -300.848595) (xy 73.339716 -300.831143) (xy 73.387935 -300.821299) (xy 73.43711 -300.819318)
			(xy 73.485965 -300.82525) (xy 73.533236 -300.838942) (xy 73.577698 -300.86004) (xy 73.618201 -300.887996)
			(xy 73.653694 -300.922088) (xy 73.683259 -300.961432) (xy 73.70613 -301.005009) (xy 73.721714 -301.05169)
			(xy 73.729609 -301.100267) (xy 73.730104 -301.124874) (xy 73.729609 -301.149481) (xy 73.721714 -301.198058)
			(xy 73.70613 -301.244739) (xy 73.683259 -301.288316) (xy 73.653694 -301.32766) (xy 73.618201 -301.361752)
			(xy 73.577698 -301.389708) (xy 73.533236 -301.410806) (xy 73.485965 -301.424498) (xy 73.43711 -301.43043)
			(xy 73.387935 -301.428449) (xy 73.339716 -301.418605) (xy 73.2937 -301.401153) (xy 73.251079 -301.376546)
			(xy 73.212958 -301.345421) (xy 73.180323 -301.308584) (xy 73.15402 -301.266988) (xy 73.134729 -301.221712)
			(xy 73.122952 -301.173928) (xy 73.118992 -301.124874) (xy 72.780144 -301.124874) (xy 72.779649 -301.149481)
			(xy 72.771754 -301.198058) (xy 72.75617 -301.244739) (xy 72.733299 -301.288316) (xy 72.703734 -301.32766)
			(xy 72.668241 -301.361752) (xy 72.627738 -301.389708) (xy 72.583276 -301.410806) (xy 72.536005 -301.424498)
			(xy 72.48715 -301.43043) (xy 72.437975 -301.428449) (xy 72.389756 -301.418605) (xy 72.34374 -301.401153)
			(xy 72.301119 -301.376546) (xy 72.262998 -301.345421) (xy 72.230363 -301.308584) (xy 72.20406 -301.266988)
			(xy 72.184769 -301.221712) (xy 72.172992 -301.173928) (xy 72.169032 -301.124874) (xy 71.830184 -301.124874)
			(xy 71.829689 -301.149481) (xy 71.821794 -301.198058) (xy 71.80621 -301.244739) (xy 71.783339 -301.288316)
			(xy 71.753774 -301.32766) (xy 71.718281 -301.361752) (xy 71.677778 -301.389708) (xy 71.633316 -301.410806)
			(xy 71.586045 -301.424498) (xy 71.53719 -301.43043) (xy 71.488015 -301.428449) (xy 71.439796 -301.418605)
			(xy 71.39378 -301.401153) (xy 71.351159 -301.376546) (xy 71.313038 -301.345421) (xy 71.280403 -301.308584)
			(xy 71.2541 -301.266988) (xy 71.234809 -301.221712) (xy 71.223032 -301.173928) (xy 71.219072 -301.124874)
			(xy 70.880224 -301.124874) (xy 70.879729 -301.149481) (xy 70.871834 -301.198058) (xy 70.85625 -301.244739)
			(xy 70.833379 -301.288316) (xy 70.803814 -301.32766) (xy 70.768321 -301.361752) (xy 70.727818 -301.389708)
			(xy 70.683356 -301.410806) (xy 70.636085 -301.424498) (xy 70.58723 -301.43043) (xy 70.538055 -301.428449)
			(xy 70.489836 -301.418605) (xy 70.44382 -301.401153) (xy 70.401199 -301.376546) (xy 70.363078 -301.345421)
			(xy 70.330443 -301.308584) (xy 70.30414 -301.266988) (xy 70.284849 -301.221712) (xy 70.273072 -301.173928)
			(xy 70.269112 -301.124874) (xy 69.930264 -301.124874) (xy 69.929769 -301.149481) (xy 69.921874 -301.198058)
			(xy 69.90629 -301.244739) (xy 69.883419 -301.288316) (xy 69.853854 -301.32766) (xy 69.818361 -301.361752)
			(xy 69.777858 -301.389708) (xy 69.733396 -301.410806) (xy 69.686125 -301.424498) (xy 69.63727 -301.43043)
			(xy 69.588095 -301.428449) (xy 69.539876 -301.418605) (xy 69.49386 -301.401153) (xy 69.451239 -301.376546)
			(xy 69.413118 -301.345421) (xy 69.380483 -301.308584) (xy 69.35418 -301.266988) (xy 69.334889 -301.221712)
			(xy 69.323112 -301.173928) (xy 69.319152 -301.124874) (xy 68.98005 -301.124874) (xy 68.979555 -301.149481)
			(xy 68.97166 -301.198058) (xy 68.956076 -301.244739) (xy 68.933205 -301.288316) (xy 68.90364 -301.32766)
			(xy 68.868147 -301.361752) (xy 68.827644 -301.389708) (xy 68.783182 -301.410806) (xy 68.735911 -301.424498)
			(xy 68.687056 -301.43043) (xy 68.637881 -301.428449) (xy 68.589662 -301.418605) (xy 68.543646 -301.401153)
			(xy 68.501025 -301.376546) (xy 68.462904 -301.345421) (xy 68.430269 -301.308584) (xy 68.403966 -301.266988)
			(xy 68.384675 -301.221712) (xy 68.372898 -301.173928) (xy 68.368938 -301.124874) (xy 68.03009 -301.124874)
			(xy 68.029595 -301.149481) (xy 68.0217 -301.198058) (xy 68.006116 -301.244739) (xy 67.983245 -301.288316)
			(xy 67.95368 -301.32766) (xy 67.918187 -301.361752) (xy 67.877684 -301.389708) (xy 67.833222 -301.410806)
			(xy 67.785951 -301.424498) (xy 67.737096 -301.43043) (xy 67.687921 -301.428449) (xy 67.639702 -301.418605)
			(xy 67.593686 -301.401153) (xy 67.551065 -301.376546) (xy 67.512944 -301.345421) (xy 67.480309 -301.308584)
			(xy 67.454006 -301.266988) (xy 67.434715 -301.221712) (xy 67.422938 -301.173928) (xy 67.418978 -301.124874)
			(xy 67.08013 -301.124874) (xy 67.079635 -301.149481) (xy 67.07174 -301.198058) (xy 67.056156 -301.244739)
			(xy 67.033285 -301.288316) (xy 67.00372 -301.32766) (xy 66.968227 -301.361752) (xy 66.927724 -301.389708)
			(xy 66.883262 -301.410806) (xy 66.835991 -301.424498) (xy 66.787136 -301.43043) (xy 66.737961 -301.428449)
			(xy 66.689742 -301.418605) (xy 66.643726 -301.401153) (xy 66.601105 -301.376546) (xy 66.562984 -301.345421)
			(xy 66.530349 -301.308584) (xy 66.504046 -301.266988) (xy 66.484755 -301.221712) (xy 66.472978 -301.173928)
			(xy 66.469018 -301.124874) (xy 66.13017 -301.124874) (xy 66.129675 -301.149481) (xy 66.12178 -301.198058)
			(xy 66.106196 -301.244739) (xy 66.083325 -301.288316) (xy 66.05376 -301.32766) (xy 66.018267 -301.361752)
			(xy 65.977764 -301.389708) (xy 65.933302 -301.410806) (xy 65.886031 -301.424498) (xy 65.837176 -301.43043)
			(xy 65.788001 -301.428449) (xy 65.739782 -301.418605) (xy 65.693766 -301.401153) (xy 65.651145 -301.376546)
			(xy 65.613024 -301.345421) (xy 65.580389 -301.308584) (xy 65.554086 -301.266988) (xy 65.534795 -301.221712)
			(xy 65.523018 -301.173928) (xy 65.519058 -301.124874) (xy 65.18021 -301.124874) (xy 65.179715 -301.149481)
			(xy 65.17182 -301.198058) (xy 65.156236 -301.244739) (xy 65.133365 -301.288316) (xy 65.1038 -301.32766)
			(xy 65.068307 -301.361752) (xy 65.027804 -301.389708) (xy 64.983342 -301.410806) (xy 64.936071 -301.424498)
			(xy 64.887216 -301.43043) (xy 64.838041 -301.428449) (xy 64.789822 -301.418605) (xy 64.743806 -301.401153)
			(xy 64.701185 -301.376546) (xy 64.663064 -301.345421) (xy 64.630429 -301.308584) (xy 64.604126 -301.266988)
			(xy 64.584835 -301.221712) (xy 64.573058 -301.173928) (xy 64.569098 -301.124874) (xy 64.23025 -301.124874)
			(xy 64.229755 -301.149481) (xy 64.22186 -301.198058) (xy 64.206276 -301.244739) (xy 64.183405 -301.288316)
			(xy 64.15384 -301.32766) (xy 64.118347 -301.361752) (xy 64.077844 -301.389708) (xy 64.033382 -301.410806)
			(xy 63.986111 -301.424498) (xy 63.937256 -301.43043) (xy 63.888081 -301.428449) (xy 63.839862 -301.418605)
			(xy 63.793846 -301.401153) (xy 63.751225 -301.376546) (xy 63.713104 -301.345421) (xy 63.680469 -301.308584)
			(xy 63.654166 -301.266988) (xy 63.634875 -301.221712) (xy 63.623098 -301.173928) (xy 63.619138 -301.124874)
			(xy 63.28029 -301.124874) (xy 63.279795 -301.149481) (xy 63.2719 -301.198058) (xy 63.256316 -301.244739)
			(xy 63.233445 -301.288316) (xy 63.20388 -301.32766) (xy 63.168387 -301.361752) (xy 63.127884 -301.389708)
			(xy 63.083422 -301.410806) (xy 63.036151 -301.424498) (xy 62.987296 -301.43043) (xy 62.938121 -301.428449)
			(xy 62.889902 -301.418605) (xy 62.843886 -301.401153) (xy 62.801265 -301.376546) (xy 62.763144 -301.345421)
			(xy 62.730509 -301.308584) (xy 62.704206 -301.266988) (xy 62.684915 -301.221712) (xy 62.673138 -301.173928)
			(xy 62.669178 -301.124874) (xy 62.330076 -301.124874) (xy 62.329581 -301.149481) (xy 62.321686 -301.198058)
			(xy 62.306102 -301.244739) (xy 62.283231 -301.288316) (xy 62.253666 -301.32766) (xy 62.218173 -301.361752)
			(xy 62.17767 -301.389708) (xy 62.133208 -301.410806) (xy 62.085937 -301.424498) (xy 62.037082 -301.43043)
			(xy 61.987907 -301.428449) (xy 61.939688 -301.418605) (xy 61.893672 -301.401153) (xy 61.851051 -301.376546)
			(xy 61.81293 -301.345421) (xy 61.780295 -301.308584) (xy 61.753992 -301.266988) (xy 61.734701 -301.221712)
			(xy 61.722924 -301.173928) (xy 61.718964 -301.124874) (xy 61.380116 -301.124874) (xy 61.379621 -301.149481)
			(xy 61.371726 -301.198058) (xy 61.356142 -301.244739) (xy 61.333271 -301.288316) (xy 61.303706 -301.32766)
			(xy 61.268213 -301.361752) (xy 61.22771 -301.389708) (xy 61.183248 -301.410806) (xy 61.135977 -301.424498)
			(xy 61.087122 -301.43043) (xy 61.037947 -301.428449) (xy 60.989728 -301.418605) (xy 60.943712 -301.401153)
			(xy 60.901091 -301.376546) (xy 60.86297 -301.345421) (xy 60.830335 -301.308584) (xy 60.804032 -301.266988)
			(xy 60.784741 -301.221712) (xy 60.772964 -301.173928) (xy 60.769004 -301.124874) (xy 60.430156 -301.124874)
			(xy 60.429661 -301.149481) (xy 60.421766 -301.198058) (xy 60.406182 -301.244739) (xy 60.383311 -301.288316)
			(xy 60.353746 -301.32766) (xy 60.318253 -301.361752) (xy 60.27775 -301.389708) (xy 60.233288 -301.410806)
			(xy 60.186017 -301.424498) (xy 60.137162 -301.43043) (xy 60.087987 -301.428449) (xy 60.039768 -301.418605)
			(xy 59.993752 -301.401153) (xy 59.951131 -301.376546) (xy 59.91301 -301.345421) (xy 59.880375 -301.308584)
			(xy 59.854072 -301.266988) (xy 59.834781 -301.221712) (xy 59.823004 -301.173928) (xy 59.819044 -301.124874)
			(xy 58.530236 -301.124874) (xy 58.529741 -301.149481) (xy 58.521846 -301.198058) (xy 58.506262 -301.244739)
			(xy 58.483391 -301.288316) (xy 58.453826 -301.32766) (xy 58.418333 -301.361752) (xy 58.37783 -301.389708)
			(xy 58.333368 -301.410806) (xy 58.286097 -301.424498) (xy 58.237242 -301.43043) (xy 58.188067 -301.428449)
			(xy 58.139848 -301.418605) (xy 58.093832 -301.401153) (xy 58.051211 -301.376546) (xy 58.01309 -301.345421)
			(xy 57.980455 -301.308584) (xy 57.954152 -301.266988) (xy 57.934861 -301.221712) (xy 57.923084 -301.173928)
			(xy 57.919124 -301.124874) (xy 57.580276 -301.124874) (xy 57.579781 -301.149481) (xy 57.571886 -301.198058)
			(xy 57.556302 -301.244739) (xy 57.533431 -301.288316) (xy 57.503866 -301.32766) (xy 57.468373 -301.361752)
			(xy 57.42787 -301.389708) (xy 57.383408 -301.410806) (xy 57.336137 -301.424498) (xy 57.287282 -301.43043)
			(xy 57.238107 -301.428449) (xy 57.189888 -301.418605) (xy 57.143872 -301.401153) (xy 57.101251 -301.376546)
			(xy 57.06313 -301.345421) (xy 57.030495 -301.308584) (xy 57.004192 -301.266988) (xy 56.984901 -301.221712)
			(xy 56.973124 -301.173928) (xy 56.969164 -301.124874) (xy 56.630062 -301.124874) (xy 56.629567 -301.149481)
			(xy 56.621672 -301.198058) (xy 56.606088 -301.244739) (xy 56.583217 -301.288316) (xy 56.553652 -301.32766)
			(xy 56.518159 -301.361752) (xy 56.477656 -301.389708) (xy 56.433194 -301.410806) (xy 56.385923 -301.424498)
			(xy 56.337068 -301.43043) (xy 56.287893 -301.428449) (xy 56.239674 -301.418605) (xy 56.193658 -301.401153)
			(xy 56.151037 -301.376546) (xy 56.112916 -301.345421) (xy 56.080281 -301.308584) (xy 56.053978 -301.266988)
			(xy 56.034687 -301.221712) (xy 56.02291 -301.173928) (xy 56.01895 -301.124874) (xy 55.680102 -301.124874)
			(xy 55.679607 -301.149481) (xy 55.671712 -301.198058) (xy 55.656128 -301.244739) (xy 55.633257 -301.288316)
			(xy 55.603692 -301.32766) (xy 55.568199 -301.361752) (xy 55.527696 -301.389708) (xy 55.483234 -301.410806)
			(xy 55.435963 -301.424498) (xy 55.387108 -301.43043) (xy 55.337933 -301.428449) (xy 55.289714 -301.418605)
			(xy 55.243698 -301.401153) (xy 55.201077 -301.376546) (xy 55.162956 -301.345421) (xy 55.130321 -301.308584)
			(xy 55.104018 -301.266988) (xy 55.084727 -301.221712) (xy 55.07295 -301.173928) (xy 55.06899 -301.124874)
			(xy 54.730142 -301.124874) (xy 54.729647 -301.149481) (xy 54.721752 -301.198058) (xy 54.706168 -301.244739)
			(xy 54.683297 -301.288316) (xy 54.653732 -301.32766) (xy 54.618239 -301.361752) (xy 54.577736 -301.389708)
			(xy 54.533274 -301.410806) (xy 54.486003 -301.424498) (xy 54.437148 -301.43043) (xy 54.387973 -301.428449)
			(xy 54.339754 -301.418605) (xy 54.293738 -301.401153) (xy 54.251117 -301.376546) (xy 54.212996 -301.345421)
			(xy 54.180361 -301.308584) (xy 54.154058 -301.266988) (xy 54.134767 -301.221712) (xy 54.12299 -301.173928)
			(xy 54.11903 -301.124874) (xy 53.780182 -301.124874) (xy 53.779687 -301.149481) (xy 53.771792 -301.198058)
			(xy 53.756208 -301.244739) (xy 53.733337 -301.288316) (xy 53.703772 -301.32766) (xy 53.668279 -301.361752)
			(xy 53.627776 -301.389708) (xy 53.583314 -301.410806) (xy 53.536043 -301.424498) (xy 53.487188 -301.43043)
			(xy 53.438013 -301.428449) (xy 53.389794 -301.418605) (xy 53.343778 -301.401153) (xy 53.301157 -301.376546)
			(xy 53.263036 -301.345421) (xy 53.230401 -301.308584) (xy 53.204098 -301.266988) (xy 53.184807 -301.221712)
			(xy 53.17303 -301.173928) (xy 53.16907 -301.124874) (xy 52.830222 -301.124874) (xy 52.829727 -301.149481)
			(xy 52.821832 -301.198058) (xy 52.806248 -301.244739) (xy 52.783377 -301.288316) (xy 52.753812 -301.32766)
			(xy 52.718319 -301.361752) (xy 52.677816 -301.389708) (xy 52.633354 -301.410806) (xy 52.586083 -301.424498)
			(xy 52.537228 -301.43043) (xy 52.488053 -301.428449) (xy 52.439834 -301.418605) (xy 52.393818 -301.401153)
			(xy 52.351197 -301.376546) (xy 52.313076 -301.345421) (xy 52.280441 -301.308584) (xy 52.254138 -301.266988)
			(xy 52.234847 -301.221712) (xy 52.22307 -301.173928) (xy 52.21911 -301.124874) (xy 51.880262 -301.124874)
			(xy 51.879767 -301.149481) (xy 51.871872 -301.198058) (xy 51.856288 -301.244739) (xy 51.833417 -301.288316)
			(xy 51.803852 -301.32766) (xy 51.768359 -301.361752) (xy 51.727856 -301.389708) (xy 51.683394 -301.410806)
			(xy 51.636123 -301.424498) (xy 51.587268 -301.43043) (xy 51.538093 -301.428449) (xy 51.489874 -301.418605)
			(xy 51.443858 -301.401153) (xy 51.401237 -301.376546) (xy 51.363116 -301.345421) (xy 51.330481 -301.308584)
			(xy 51.304178 -301.266988) (xy 51.284887 -301.221712) (xy 51.27311 -301.173928) (xy 51.26915 -301.124874)
			(xy 50.930302 -301.124874) (xy 50.929807 -301.149481) (xy 50.921912 -301.198058) (xy 50.906328 -301.244739)
			(xy 50.883457 -301.288316) (xy 50.853892 -301.32766) (xy 50.818399 -301.361752) (xy 50.777896 -301.389708)
			(xy 50.733434 -301.410806) (xy 50.686163 -301.424498) (xy 50.637308 -301.43043) (xy 50.588133 -301.428449)
			(xy 50.539914 -301.418605) (xy 50.493898 -301.401153) (xy 50.451277 -301.376546) (xy 50.413156 -301.345421)
			(xy 50.380521 -301.308584) (xy 50.354218 -301.266988) (xy 50.334927 -301.221712) (xy 50.32315 -301.173928)
			(xy 50.31919 -301.124874) (xy 49.980088 -301.124874) (xy 49.979593 -301.149481) (xy 49.971698 -301.198058)
			(xy 49.956114 -301.244739) (xy 49.933243 -301.288316) (xy 49.903678 -301.32766) (xy 49.868185 -301.361752)
			(xy 49.827682 -301.389708) (xy 49.78322 -301.410806) (xy 49.735949 -301.424498) (xy 49.687094 -301.43043)
			(xy 49.637919 -301.428449) (xy 49.5897 -301.418605) (xy 49.543684 -301.401153) (xy 49.501063 -301.376546)
			(xy 49.462942 -301.345421) (xy 49.430307 -301.308584) (xy 49.404004 -301.266988) (xy 49.384713 -301.221712)
			(xy 49.372936 -301.173928) (xy 49.368976 -301.124874) (xy 49.030128 -301.124874) (xy 49.029633 -301.149481)
			(xy 49.021738 -301.198058) (xy 49.006154 -301.244739) (xy 48.983283 -301.288316) (xy 48.953718 -301.32766)
			(xy 48.918225 -301.361752) (xy 48.877722 -301.389708) (xy 48.83326 -301.410806) (xy 48.785989 -301.424498)
			(xy 48.737134 -301.43043) (xy 48.687959 -301.428449) (xy 48.63974 -301.418605) (xy 48.593724 -301.401153)
			(xy 48.551103 -301.376546) (xy 48.512982 -301.345421) (xy 48.480347 -301.308584) (xy 48.454044 -301.266988)
			(xy 48.434753 -301.221712) (xy 48.422976 -301.173928) (xy 48.419016 -301.124874) (xy 48.080168 -301.124874)
			(xy 48.079673 -301.149481) (xy 48.071778 -301.198058) (xy 48.056194 -301.244739) (xy 48.033323 -301.288316)
			(xy 48.003758 -301.32766) (xy 47.968265 -301.361752) (xy 47.927762 -301.389708) (xy 47.8833 -301.410806)
			(xy 47.836029 -301.424498) (xy 47.787174 -301.43043) (xy 47.737999 -301.428449) (xy 47.68978 -301.418605)
			(xy 47.643764 -301.401153) (xy 47.601143 -301.376546) (xy 47.563022 -301.345421) (xy 47.530387 -301.308584)
			(xy 47.504084 -301.266988) (xy 47.484793 -301.221712) (xy 47.473016 -301.173928) (xy 47.469056 -301.124874)
			(xy 47.130142 -301.124874) (xy 47.130593 -301.13319) (xy 47.125225 -301.182535) (xy 47.111944 -301.230362)
			(xy 47.091102 -301.275411) (xy 47.063245 -301.316494) (xy 47.02911 -301.352529) (xy 46.989594 -301.382568)
			(xy 46.945739 -301.405817) (xy 46.898701 -301.421666) (xy 46.849718 -301.429696) (xy 46.8249 -301.430182)
			(xy 46.810717 -301.430006) (xy 46.782477 -301.427333) (xy 46.768512 -301.424848) (xy 46.754541 -301.422738)
			(xy 46.726418 -301.425314) (xy 46.700077 -301.435497) (xy 46.677534 -301.452508) (xy 46.660515 -301.475044)
			(xy 46.650322 -301.501382) (xy 46.647736 -301.529504) (xy 46.649894 -301.543466) (xy 46.652376 -301.557431)
			(xy 46.655044 -301.585671) (xy 46.655228 -301.599854) (xy 46.655227 -301.5999) (xy 75.494122 -301.5999)
			(xy 75.498293 -301.549559) (xy 75.510692 -301.500592) (xy 75.530981 -301.454332) (xy 75.558607 -301.412043)
			(xy 75.592815 -301.374876) (xy 75.632674 -301.343847) (xy 75.677097 -301.3198) (xy 75.724871 -301.303393)
			(xy 75.774694 -301.295071) (xy 75.79995 -301.294546) (xy 75.814133 -301.29473) (xy 75.842373 -301.297397)
			(xy 75.856338 -301.29988) (xy 75.868784 -301.302166) (xy 75.892406 -301.2948) (xy 75.969876 -301.21733)
			(xy 75.977242 -301.193708) (xy 75.974956 -301.181262) (xy 75.972479 -301.167296) (xy 75.969807 -301.139057)
			(xy 75.969622 -301.124874) (xy 75.970106 -301.100056) (xy 75.97814 -301.051075) (xy 75.993992 -301.004039)
			(xy 76.017245 -300.960187) (xy 76.047285 -300.920674) (xy 76.083322 -300.886542) (xy 76.124406 -300.858689)
			(xy 76.169455 -300.837849) (xy 76.217282 -300.824572) (xy 76.266627 -300.819207) (xy 76.316189 -300.821895)
			(xy 76.364664 -300.832566) (xy 76.410774 -300.850939) (xy 76.453305 -300.876529) (xy 76.491135 -300.908662)
			(xy 76.523269 -300.946492) (xy 76.54886 -300.989022) (xy 76.567233 -301.035132) (xy 76.577904 -301.083607)
			(xy 76.580143 -301.124874) (xy 76.919086 -301.124874) (xy 76.923046 -301.07582) (xy 76.934823 -301.028036)
			(xy 76.954114 -300.98276) (xy 76.980417 -300.941164) (xy 77.013052 -300.904327) (xy 77.051173 -300.873202)
			(xy 77.093794 -300.848595) (xy 77.13981 -300.831143) (xy 77.188029 -300.821299) (xy 77.237204 -300.819318)
			(xy 77.286059 -300.82525) (xy 77.33333 -300.838942) (xy 77.377792 -300.86004) (xy 77.418295 -300.887996)
			(xy 77.453788 -300.922088) (xy 77.483353 -300.961432) (xy 77.506224 -301.005009) (xy 77.521808 -301.05169)
			(xy 77.529703 -301.100267) (xy 77.530198 -301.124874) (xy 77.869046 -301.124874) (xy 77.873006 -301.07582)
			(xy 77.884783 -301.028036) (xy 77.904074 -300.98276) (xy 77.930377 -300.941164) (xy 77.963012 -300.904327)
			(xy 78.001133 -300.873202) (xy 78.043754 -300.848595) (xy 78.08977 -300.831143) (xy 78.137989 -300.821299)
			(xy 78.187164 -300.819318) (xy 78.236019 -300.82525) (xy 78.28329 -300.838942) (xy 78.327752 -300.86004)
			(xy 78.368255 -300.887996) (xy 78.403748 -300.922088) (xy 78.433313 -300.961432) (xy 78.456184 -301.005009)
			(xy 78.471768 -301.05169) (xy 78.479663 -301.100267) (xy 78.480158 -301.124874) (xy 78.819006 -301.124874)
			(xy 78.822966 -301.07582) (xy 78.834743 -301.028036) (xy 78.854034 -300.98276) (xy 78.880337 -300.941164)
			(xy 78.912972 -300.904327) (xy 78.951093 -300.873202) (xy 78.993714 -300.848595) (xy 79.03973 -300.831143)
			(xy 79.087949 -300.821299) (xy 79.137124 -300.819318) (xy 79.185979 -300.82525) (xy 79.23325 -300.838942)
			(xy 79.277712 -300.86004) (xy 79.318215 -300.887996) (xy 79.353708 -300.922088) (xy 79.383273 -300.961432)
			(xy 79.406144 -301.005009) (xy 79.421728 -301.05169) (xy 79.429623 -301.100267) (xy 79.430118 -301.124874)
			(xy 79.768966 -301.124874) (xy 79.772926 -301.07582) (xy 79.784703 -301.028036) (xy 79.803994 -300.98276)
			(xy 79.830297 -300.941164) (xy 79.862932 -300.904327) (xy 79.901053 -300.873202) (xy 79.943674 -300.848595)
			(xy 79.98969 -300.831143) (xy 80.037909 -300.821299) (xy 80.087084 -300.819318) (xy 80.135939 -300.82525)
			(xy 80.18321 -300.838942) (xy 80.227672 -300.86004) (xy 80.268175 -300.887996) (xy 80.303668 -300.922088)
			(xy 80.333233 -300.961432) (xy 80.356104 -301.005009) (xy 80.371688 -301.05169) (xy 80.379583 -301.100267)
			(xy 80.380078 -301.124874) (xy 80.71918 -301.124874) (xy 80.72314 -301.07582) (xy 80.734917 -301.028036)
			(xy 80.754208 -300.98276) (xy 80.780511 -300.941164) (xy 80.813146 -300.904327) (xy 80.851267 -300.873202)
			(xy 80.893888 -300.848595) (xy 80.939904 -300.831143) (xy 80.988123 -300.821299) (xy 81.037298 -300.819318)
			(xy 81.086153 -300.82525) (xy 81.133424 -300.838942) (xy 81.177886 -300.86004) (xy 81.218389 -300.887996)
			(xy 81.253882 -300.922088) (xy 81.283447 -300.961432) (xy 81.306318 -301.005009) (xy 81.321902 -301.05169)
			(xy 81.329797 -301.100267) (xy 81.330292 -301.124874) (xy 81.66914 -301.124874) (xy 81.6731 -301.07582)
			(xy 81.684877 -301.028036) (xy 81.704168 -300.98276) (xy 81.730471 -300.941164) (xy 81.763106 -300.904327)
			(xy 81.801227 -300.873202) (xy 81.843848 -300.848595) (xy 81.889864 -300.831143) (xy 81.938083 -300.821299)
			(xy 81.987258 -300.819318) (xy 82.036113 -300.82525) (xy 82.083384 -300.838942) (xy 82.127846 -300.86004)
			(xy 82.168349 -300.887996) (xy 82.203842 -300.922088) (xy 82.233407 -300.961432) (xy 82.256278 -301.005009)
			(xy 82.271862 -301.05169) (xy 82.279757 -301.100267) (xy 82.280252 -301.124874) (xy 82.6191 -301.124874)
			(xy 82.62306 -301.07582) (xy 82.634837 -301.028036) (xy 82.654128 -300.98276) (xy 82.680431 -300.941164)
			(xy 82.713066 -300.904327) (xy 82.751187 -300.873202) (xy 82.793808 -300.848595) (xy 82.839824 -300.831143)
			(xy 82.888043 -300.821299) (xy 82.937218 -300.819318) (xy 82.986073 -300.82525) (xy 83.033344 -300.838942)
			(xy 83.077806 -300.86004) (xy 83.118309 -300.887996) (xy 83.153802 -300.922088) (xy 83.183367 -300.961432)
			(xy 83.206238 -301.005009) (xy 83.221822 -301.05169) (xy 83.229717 -301.100267) (xy 83.230212 -301.124874)
			(xy 83.229717 -301.149481) (xy 83.221822 -301.198058) (xy 83.206238 -301.244739) (xy 83.183367 -301.288316)
			(xy 83.153802 -301.32766) (xy 83.118309 -301.361752) (xy 83.077806 -301.389708) (xy 83.033344 -301.410806)
			(xy 82.986073 -301.424498) (xy 82.937218 -301.43043) (xy 82.888043 -301.428449) (xy 82.839824 -301.418605)
			(xy 82.793808 -301.401153) (xy 82.751187 -301.376546) (xy 82.713066 -301.345421) (xy 82.680431 -301.308584)
			(xy 82.654128 -301.266988) (xy 82.634837 -301.221712) (xy 82.62306 -301.173928) (xy 82.6191 -301.124874)
			(xy 82.280252 -301.124874) (xy 82.279757 -301.149481) (xy 82.271862 -301.198058) (xy 82.256278 -301.244739)
			(xy 82.233407 -301.288316) (xy 82.203842 -301.32766) (xy 82.168349 -301.361752) (xy 82.127846 -301.389708)
			(xy 82.083384 -301.410806) (xy 82.036113 -301.424498) (xy 81.987258 -301.43043) (xy 81.938083 -301.428449)
			(xy 81.889864 -301.418605) (xy 81.843848 -301.401153) (xy 81.801227 -301.376546) (xy 81.763106 -301.345421)
			(xy 81.730471 -301.308584) (xy 81.704168 -301.266988) (xy 81.684877 -301.221712) (xy 81.6731 -301.173928)
			(xy 81.66914 -301.124874) (xy 81.330292 -301.124874) (xy 81.329797 -301.149481) (xy 81.321902 -301.198058)
			(xy 81.306318 -301.244739) (xy 81.283447 -301.288316) (xy 81.253882 -301.32766) (xy 81.218389 -301.361752)
			(xy 81.177886 -301.389708) (xy 81.133424 -301.410806) (xy 81.086153 -301.424498) (xy 81.037298 -301.43043)
			(xy 80.988123 -301.428449) (xy 80.939904 -301.418605) (xy 80.893888 -301.401153) (xy 80.851267 -301.376546)
			(xy 80.813146 -301.345421) (xy 80.780511 -301.308584) (xy 80.754208 -301.266988) (xy 80.734917 -301.221712)
			(xy 80.72314 -301.173928) (xy 80.71918 -301.124874) (xy 80.380078 -301.124874) (xy 80.379583 -301.149481)
			(xy 80.371688 -301.198058) (xy 80.356104 -301.244739) (xy 80.333233 -301.288316) (xy 80.303668 -301.32766)
			(xy 80.268175 -301.361752) (xy 80.227672 -301.389708) (xy 80.18321 -301.410806) (xy 80.135939 -301.424498)
			(xy 80.087084 -301.43043) (xy 80.037909 -301.428449) (xy 79.98969 -301.418605) (xy 79.943674 -301.401153)
			(xy 79.901053 -301.376546) (xy 79.862932 -301.345421) (xy 79.830297 -301.308584) (xy 79.803994 -301.266988)
			(xy 79.784703 -301.221712) (xy 79.772926 -301.173928) (xy 79.768966 -301.124874) (xy 79.430118 -301.124874)
			(xy 79.429623 -301.149481) (xy 79.421728 -301.198058) (xy 79.406144 -301.244739) (xy 79.383273 -301.288316)
			(xy 79.353708 -301.32766) (xy 79.318215 -301.361752) (xy 79.277712 -301.389708) (xy 79.23325 -301.410806)
			(xy 79.185979 -301.424498) (xy 79.137124 -301.43043) (xy 79.087949 -301.428449) (xy 79.03973 -301.418605)
			(xy 78.993714 -301.401153) (xy 78.951093 -301.376546) (xy 78.912972 -301.345421) (xy 78.880337 -301.308584)
			(xy 78.854034 -301.266988) (xy 78.834743 -301.221712) (xy 78.822966 -301.173928) (xy 78.819006 -301.124874)
			(xy 78.480158 -301.124874) (xy 78.479663 -301.149481) (xy 78.471768 -301.198058) (xy 78.456184 -301.244739)
			(xy 78.433313 -301.288316) (xy 78.403748 -301.32766) (xy 78.368255 -301.361752) (xy 78.327752 -301.389708)
			(xy 78.28329 -301.410806) (xy 78.236019 -301.424498) (xy 78.187164 -301.43043) (xy 78.137989 -301.428449)
			(xy 78.08977 -301.418605) (xy 78.043754 -301.401153) (xy 78.001133 -301.376546) (xy 77.963012 -301.345421)
			(xy 77.930377 -301.308584) (xy 77.904074 -301.266988) (xy 77.884783 -301.221712) (xy 77.873006 -301.173928)
			(xy 77.869046 -301.124874) (xy 77.530198 -301.124874) (xy 77.529703 -301.149481) (xy 77.521808 -301.198058)
			(xy 77.506224 -301.244739) (xy 77.483353 -301.288316) (xy 77.453788 -301.32766) (xy 77.418295 -301.361752)
			(xy 77.377792 -301.389708) (xy 77.33333 -301.410806) (xy 77.286059 -301.424498) (xy 77.237204 -301.43043)
			(xy 77.188029 -301.428449) (xy 77.13981 -301.418605) (xy 77.093794 -301.401153) (xy 77.051173 -301.376546)
			(xy 77.013052 -301.345421) (xy 76.980417 -301.308584) (xy 76.954114 -301.266988) (xy 76.934823 -301.221712)
			(xy 76.923046 -301.173928) (xy 76.919086 -301.124874) (xy 76.580143 -301.124874) (xy 76.580593 -301.133169)
			(xy 76.575229 -301.182514) (xy 76.561952 -301.230341) (xy 76.541113 -301.27539) (xy 76.513261 -301.316475)
			(xy 76.479129 -301.352512) (xy 76.439616 -301.382553) (xy 76.395765 -301.405806) (xy 76.348729 -301.421659)
			(xy 76.299748 -301.429694) (xy 76.27493 -301.430182) (xy 76.260747 -301.430002) (xy 76.232507 -301.427332)
			(xy 76.218542 -301.424848) (xy 76.206096 -301.422562) (xy 76.182474 -301.429928) (xy 76.105004 -301.507398)
			(xy 76.097638 -301.53102) (xy 76.099924 -301.543466) (xy 76.102406 -301.557431) (xy 76.105074 -301.585671)
			(xy 76.105258 -301.599854) (xy 76.105076 -301.614037) (xy 76.102408 -301.642277) (xy 76.099924 -301.656242)
			(xy 76.097638 -301.668688) (xy 76.105004 -301.69231) (xy 76.182474 -301.76978) (xy 76.206096 -301.777146)
			(xy 76.218542 -301.77486) (xy 76.232508 -301.772382) (xy 76.260747 -301.769711) (xy 76.27493 -301.769526)
			(xy 76.299747 -301.77001) (xy 76.348727 -301.778045) (xy 76.395762 -301.793897) (xy 76.439613 -301.81715)
			(xy 76.479125 -301.84719) (xy 76.513257 -301.883227) (xy 76.541109 -301.92431) (xy 76.561948 -301.969358)
			(xy 76.575224 -302.017184) (xy 76.580589 -302.066528) (xy 76.580139 -302.074834) (xy 76.919086 -302.074834)
			(xy 76.923046 -302.02578) (xy 76.934823 -301.977996) (xy 76.954114 -301.93272) (xy 76.980417 -301.891124)
			(xy 77.013052 -301.854287) (xy 77.051173 -301.823162) (xy 77.093794 -301.798555) (xy 77.13981 -301.781103)
			(xy 77.188029 -301.771259) (xy 77.237204 -301.769278) (xy 77.286059 -301.77521) (xy 77.33333 -301.788902)
			(xy 77.377792 -301.81) (xy 77.418295 -301.837956) (xy 77.453788 -301.872048) (xy 77.483353 -301.911392)
			(xy 77.506224 -301.954969) (xy 77.521808 -302.00165) (xy 77.529703 -302.050227) (xy 77.530198 -302.074834)
			(xy 77.869046 -302.074834) (xy 77.873006 -302.02578) (xy 77.884783 -301.977996) (xy 77.904074 -301.93272)
			(xy 77.930377 -301.891124) (xy 77.963012 -301.854287) (xy 78.001133 -301.823162) (xy 78.043754 -301.798555)
			(xy 78.08977 -301.781103) (xy 78.137989 -301.771259) (xy 78.187164 -301.769278) (xy 78.236019 -301.77521)
			(xy 78.28329 -301.788902) (xy 78.327752 -301.81) (xy 78.368255 -301.837956) (xy 78.403748 -301.872048)
			(xy 78.433313 -301.911392) (xy 78.456184 -301.954969) (xy 78.471768 -302.00165) (xy 78.479663 -302.050227)
			(xy 78.480158 -302.074834) (xy 78.819006 -302.074834) (xy 78.822966 -302.02578) (xy 78.834743 -301.977996)
			(xy 78.854034 -301.93272) (xy 78.880337 -301.891124) (xy 78.912972 -301.854287) (xy 78.951093 -301.823162)
			(xy 78.993714 -301.798555) (xy 79.03973 -301.781103) (xy 79.087949 -301.771259) (xy 79.137124 -301.769278)
			(xy 79.185979 -301.77521) (xy 79.23325 -301.788902) (xy 79.277712 -301.81) (xy 79.318215 -301.837956)
			(xy 79.353708 -301.872048) (xy 79.383273 -301.911392) (xy 79.406144 -301.954969) (xy 79.421728 -302.00165)
			(xy 79.429623 -302.050227) (xy 79.430118 -302.074834) (xy 79.768966 -302.074834) (xy 79.772926 -302.02578)
			(xy 79.784703 -301.977996) (xy 79.803994 -301.93272) (xy 79.830297 -301.891124) (xy 79.862932 -301.854287)
			(xy 79.901053 -301.823162) (xy 79.943674 -301.798555) (xy 79.98969 -301.781103) (xy 80.037909 -301.771259)
			(xy 80.087084 -301.769278) (xy 80.135939 -301.77521) (xy 80.18321 -301.788902) (xy 80.227672 -301.81)
			(xy 80.268175 -301.837956) (xy 80.303668 -301.872048) (xy 80.333233 -301.911392) (xy 80.356104 -301.954969)
			(xy 80.371688 -302.00165) (xy 80.379583 -302.050227) (xy 80.380078 -302.074834) (xy 80.71918 -302.074834)
			(xy 80.72314 -302.02578) (xy 80.734917 -301.977996) (xy 80.754208 -301.93272) (xy 80.780511 -301.891124)
			(xy 80.813146 -301.854287) (xy 80.851267 -301.823162) (xy 80.893888 -301.798555) (xy 80.939904 -301.781103)
			(xy 80.988123 -301.771259) (xy 81.037298 -301.769278) (xy 81.086153 -301.77521) (xy 81.133424 -301.788902)
			(xy 81.177886 -301.81) (xy 81.218389 -301.837956) (xy 81.253882 -301.872048) (xy 81.283447 -301.911392)
			(xy 81.306318 -301.954969) (xy 81.321902 -302.00165) (xy 81.329797 -302.050227) (xy 81.330292 -302.074834)
			(xy 81.66914 -302.074834) (xy 81.6731 -302.02578) (xy 81.684877 -301.977996) (xy 81.704168 -301.93272)
			(xy 81.730471 -301.891124) (xy 81.763106 -301.854287) (xy 81.801227 -301.823162) (xy 81.843848 -301.798555)
			(xy 81.889864 -301.781103) (xy 81.938083 -301.771259) (xy 81.987258 -301.769278) (xy 82.036113 -301.77521)
			(xy 82.083384 -301.788902) (xy 82.127846 -301.81) (xy 82.168349 -301.837956) (xy 82.203842 -301.872048)
			(xy 82.233407 -301.911392) (xy 82.256278 -301.954969) (xy 82.271862 -302.00165) (xy 82.279757 -302.050227)
			(xy 82.280252 -302.074834) (xy 82.6191 -302.074834) (xy 82.62306 -302.02578) (xy 82.634837 -301.977996)
			(xy 82.654128 -301.93272) (xy 82.680431 -301.891124) (xy 82.713066 -301.854287) (xy 82.751187 -301.823162)
			(xy 82.793808 -301.798555) (xy 82.839824 -301.781103) (xy 82.888043 -301.771259) (xy 82.937218 -301.769278)
			(xy 82.986073 -301.77521) (xy 83.033344 -301.788902) (xy 83.077806 -301.81) (xy 83.118309 -301.837956)
			(xy 83.153802 -301.872048) (xy 83.183367 -301.911392) (xy 83.206238 -301.954969) (xy 83.221822 -302.00165)
			(xy 83.229717 -302.050227) (xy 83.230212 -302.074834) (xy 83.229717 -302.099441) (xy 83.221822 -302.148018)
			(xy 83.206238 -302.194699) (xy 83.183367 -302.238276) (xy 83.153802 -302.27762) (xy 83.118309 -302.311712)
			(xy 83.077806 -302.339668) (xy 83.033344 -302.360766) (xy 82.986073 -302.374458) (xy 82.937218 -302.38039)
			(xy 82.888043 -302.378409) (xy 82.839824 -302.368565) (xy 82.793808 -302.351113) (xy 82.751187 -302.326506)
			(xy 82.713066 -302.295381) (xy 82.680431 -302.258544) (xy 82.654128 -302.216948) (xy 82.634837 -302.171672)
			(xy 82.62306 -302.123888) (xy 82.6191 -302.074834) (xy 82.280252 -302.074834) (xy 82.279757 -302.099441)
			(xy 82.271862 -302.148018) (xy 82.256278 -302.194699) (xy 82.233407 -302.238276) (xy 82.203842 -302.27762)
			(xy 82.168349 -302.311712) (xy 82.127846 -302.339668) (xy 82.083384 -302.360766) (xy 82.036113 -302.374458)
			(xy 81.987258 -302.38039) (xy 81.938083 -302.378409) (xy 81.889864 -302.368565) (xy 81.843848 -302.351113)
			(xy 81.801227 -302.326506) (xy 81.763106 -302.295381) (xy 81.730471 -302.258544) (xy 81.704168 -302.216948)
			(xy 81.684877 -302.171672) (xy 81.6731 -302.123888) (xy 81.66914 -302.074834) (xy 81.330292 -302.074834)
			(xy 81.329797 -302.099441) (xy 81.321902 -302.148018) (xy 81.306318 -302.194699) (xy 81.283447 -302.238276)
			(xy 81.253882 -302.27762) (xy 81.218389 -302.311712) (xy 81.177886 -302.339668) (xy 81.133424 -302.360766)
			(xy 81.086153 -302.374458) (xy 81.037298 -302.38039) (xy 80.988123 -302.378409) (xy 80.939904 -302.368565)
			(xy 80.893888 -302.351113) (xy 80.851267 -302.326506) (xy 80.813146 -302.295381) (xy 80.780511 -302.258544)
			(xy 80.754208 -302.216948) (xy 80.734917 -302.171672) (xy 80.72314 -302.123888) (xy 80.71918 -302.074834)
			(xy 80.380078 -302.074834) (xy 80.379583 -302.099441) (xy 80.371688 -302.148018) (xy 80.356104 -302.194699)
			(xy 80.333233 -302.238276) (xy 80.303668 -302.27762) (xy 80.268175 -302.311712) (xy 80.227672 -302.339668)
			(xy 80.18321 -302.360766) (xy 80.135939 -302.374458) (xy 80.087084 -302.38039) (xy 80.037909 -302.378409)
			(xy 79.98969 -302.368565) (xy 79.943674 -302.351113) (xy 79.901053 -302.326506) (xy 79.862932 -302.295381)
			(xy 79.830297 -302.258544) (xy 79.803994 -302.216948) (xy 79.784703 -302.171672) (xy 79.772926 -302.123888)
			(xy 79.768966 -302.074834) (xy 79.430118 -302.074834) (xy 79.429623 -302.099441) (xy 79.421728 -302.148018)
			(xy 79.406144 -302.194699) (xy 79.383273 -302.238276) (xy 79.353708 -302.27762) (xy 79.318215 -302.311712)
			(xy 79.277712 -302.339668) (xy 79.23325 -302.360766) (xy 79.185979 -302.374458) (xy 79.137124 -302.38039)
			(xy 79.087949 -302.378409) (xy 79.03973 -302.368565) (xy 78.993714 -302.351113) (xy 78.951093 -302.326506)
			(xy 78.912972 -302.295381) (xy 78.880337 -302.258544) (xy 78.854034 -302.216948) (xy 78.834743 -302.171672)
			(xy 78.822966 -302.123888) (xy 78.819006 -302.074834) (xy 78.480158 -302.074834) (xy 78.479663 -302.099441)
			(xy 78.471768 -302.148018) (xy 78.456184 -302.194699) (xy 78.433313 -302.238276) (xy 78.403748 -302.27762)
			(xy 78.368255 -302.311712) (xy 78.327752 -302.339668) (xy 78.28329 -302.360766) (xy 78.236019 -302.374458)
			(xy 78.187164 -302.38039) (xy 78.137989 -302.378409) (xy 78.08977 -302.368565) (xy 78.043754 -302.351113)
			(xy 78.001133 -302.326506) (xy 77.963012 -302.295381) (xy 77.930377 -302.258544) (xy 77.904074 -302.216948)
			(xy 77.884783 -302.171672) (xy 77.873006 -302.123888) (xy 77.869046 -302.074834) (xy 77.530198 -302.074834)
			(xy 77.529703 -302.099441) (xy 77.521808 -302.148018) (xy 77.506224 -302.194699) (xy 77.483353 -302.238276)
			(xy 77.453788 -302.27762) (xy 77.418295 -302.311712) (xy 77.377792 -302.339668) (xy 77.33333 -302.360766)
			(xy 77.286059 -302.374458) (xy 77.237204 -302.38039) (xy 77.188029 -302.378409) (xy 77.13981 -302.368565)
			(xy 77.093794 -302.351113) (xy 77.051173 -302.326506) (xy 77.013052 -302.295381) (xy 76.980417 -302.258544)
			(xy 76.954114 -302.216948) (xy 76.934823 -302.171672) (xy 76.923046 -302.123888) (xy 76.919086 -302.074834)
			(xy 76.580139 -302.074834) (xy 76.577901 -302.11609) (xy 76.56723 -302.164564) (xy 76.548858 -302.210673)
			(xy 76.523268 -302.253203) (xy 76.491135 -302.291033) (xy 76.453306 -302.323166) (xy 76.410777 -302.348756)
			(xy 76.364668 -302.367129) (xy 76.316194 -302.3778) (xy 76.266632 -302.380489) (xy 76.217288 -302.375125)
			(xy 76.169462 -302.361849) (xy 76.124414 -302.341011) (xy 76.08333 -302.313159) (xy 76.047293 -302.279028)
			(xy 76.017252 -302.239517) (xy 75.993999 -302.195666) (xy 75.978146 -302.148631) (xy 75.97011 -302.099651)
			(xy 75.969622 -302.074834) (xy 75.969803 -302.060651) (xy 75.972472 -302.032411) (xy 75.974956 -302.018446)
			(xy 75.977242 -302.006) (xy 75.969876 -301.982378) (xy 75.892406 -301.904908) (xy 75.868784 -301.897542)
			(xy 75.856338 -301.899828) (xy 75.842373 -301.902309) (xy 75.814133 -301.904978) (xy 75.79995 -301.905162)
			(xy 75.774694 -301.904729) (xy 75.724871 -301.896407) (xy 75.677097 -301.88) (xy 75.632674 -301.855953)
			(xy 75.592815 -301.824924) (xy 75.558607 -301.787757) (xy 75.530981 -301.745468) (xy 75.510692 -301.699208)
			(xy 75.498293 -301.650241) (xy 75.494122 -301.5999) (xy 46.655227 -301.5999) (xy 46.654772 -301.62468)
			(xy 46.646746 -301.673678) (xy 46.630899 -301.720733) (xy 46.607647 -301.764604) (xy 46.577604 -301.804135)
			(xy 46.541561 -301.838284) (xy 46.500468 -301.866152) (xy 46.455408 -301.887005) (xy 46.407567 -301.900292)
			(xy 46.358207 -301.905665) (xy 46.308628 -301.90298) (xy 46.260137 -301.89231) (xy 46.214011 -301.873935)
			(xy 46.171465 -301.848339) (xy 46.133621 -301.816197) (xy 46.101476 -301.778356) (xy 46.075877 -301.735813)
			(xy 46.057498 -301.689688) (xy 46.046823 -301.641197) (xy 46.044135 -301.591619) (xy 45.705758 -301.591619)
			(xy 45.703072 -301.641184) (xy 45.6924 -301.689674) (xy 45.674023 -301.735799) (xy 45.648425 -301.778344)
			(xy 45.616281 -301.816186) (xy 45.578439 -301.848329) (xy 45.535894 -301.873925) (xy 45.489769 -301.892302)
			(xy 45.441278 -301.902973) (xy 45.391699 -301.905658) (xy 45.34234 -301.900287) (xy 45.294499 -301.887)
			(xy 45.249439 -301.866149) (xy 45.208346 -301.838281) (xy 45.172303 -301.804133) (xy 45.142259 -301.764602)
			(xy 45.119008 -301.720732) (xy 45.10316 -301.673678) (xy 45.095134 -301.62468) (xy 45.094652 -301.599854)
			(xy 45.094837 -301.585671) (xy 45.097504 -301.557431) (xy 45.099986 -301.543466) (xy 45.102272 -301.53102)
			(xy 45.094906 -301.507398) (xy 45.017436 -301.429928) (xy 44.993814 -301.422562) (xy 44.981368 -301.424848)
			(xy 44.967402 -301.427324) (xy 44.939163 -301.429996) (xy 44.92498 -301.430182) (xy 44.910733 -301.430011)
			(xy 44.882366 -301.427341) (xy 44.868338 -301.424848) (xy 44.855892 -301.422562) (xy 44.83227 -301.429928)
			(xy 44.76369 -301.498254) (xy 44.755544 -301.507499) (xy 44.748231 -301.530983) (xy 44.74972 -301.543212)
			(xy 44.74972 -301.54372) (xy 44.752182 -301.557624) (xy 44.754854 -301.585735) (xy 44.755054 -301.599854)
			(xy 44.754532 -301.625109) (xy 44.746219 -301.674931) (xy 44.729818 -301.722705) (xy 44.705777 -301.767128)
			(xy 44.674753 -301.806988) (xy 44.637591 -301.841198) (xy 44.595305 -301.868824) (xy 44.549049 -301.889114)
			(xy 44.500084 -301.901514) (xy 44.449746 -301.905685) (xy 44.399408 -301.901514) (xy 44.350443 -301.889114)
			(xy 44.304187 -301.868824) (xy 44.261901 -301.841198) (xy 44.224739 -301.806988) (xy 44.193715 -301.767128)
			(xy 44.169674 -301.722705) (xy 44.153273 -301.674931) (xy 44.14496 -301.625109) (xy 44.144438 -301.599854)
			(xy 44.144621 -301.585671) (xy 44.147289 -301.557431) (xy 44.149772 -301.543466) (xy 44.152058 -301.53102)
			(xy 44.144692 -301.507398) (xy 44.067222 -301.429928) (xy 44.0436 -301.422562) (xy 44.031154 -301.424848)
			(xy 44.017188 -301.427326) (xy 43.988949 -301.429997) (xy 43.974766 -301.430182) (xy 43.960583 -301.430011)
			(xy 43.932343 -301.427335) (xy 43.918378 -301.424848) (xy 43.905932 -301.422562) (xy 43.88231 -301.429928)
			(xy 43.80484 -301.507398) (xy 43.797474 -301.53102) (xy 43.79976 -301.543466) (xy 43.802241 -301.557431)
			(xy 43.80491 -301.585671) (xy 43.805094 -301.599854) (xy 43.804672 -301.624679) (xy 43.796647 -301.673677)
			(xy 43.7808 -301.72073) (xy 43.75755 -301.7646) (xy 43.727508 -301.804131) (xy 43.691466 -301.83828)
			(xy 43.650375 -301.866148) (xy 43.605316 -301.887002) (xy 43.557477 -301.90029) (xy 43.508119 -301.905664)
			(xy 43.458541 -301.902982) (xy 43.41005 -301.892314) (xy 43.363924 -301.873942) (xy 43.321378 -301.848348)
			(xy 43.283533 -301.816209) (xy 43.251387 -301.778371) (xy 43.225785 -301.73583) (xy 43.207404 -301.689708)
			(xy 43.196726 -301.641219) (xy 43.194034 -301.591642) (xy 42.876817 -301.591642) (xy 42.876978 -301.599854)
			(xy 42.876474 -301.625562) (xy 42.868431 -301.676344) (xy 42.852543 -301.725243) (xy 42.8292 -301.771055)
			(xy 42.798979 -301.812651) (xy 42.762623 -301.849007) (xy 42.721027 -301.879228) (xy 42.675215 -301.902571)
			(xy 42.626316 -301.918459) (xy 42.575534 -301.926502) (xy 42.524118 -301.926502) (xy 42.473336 -301.918459)
			(xy 42.424437 -301.902571) (xy 42.378625 -301.879228) (xy 42.337029 -301.849007) (xy 42.300673 -301.812651)
			(xy 42.270452 -301.771055) (xy 42.247109 -301.725243) (xy 42.231221 -301.676344) (xy 42.223178 -301.625562)
			(xy 41.926514 -301.625562) (xy 41.918471 -301.676344) (xy 41.902583 -301.725243) (xy 41.87924 -301.771055)
			(xy 41.849019 -301.812651) (xy 41.812663 -301.849007) (xy 41.771067 -301.879228) (xy 41.725255 -301.902571)
			(xy 41.676356 -301.918459) (xy 41.625574 -301.926502) (xy 41.574158 -301.926502) (xy 41.523376 -301.918459)
			(xy 41.474477 -301.902571) (xy 41.428665 -301.879228) (xy 41.387069 -301.849007) (xy 41.350713 -301.812651)
			(xy 41.320492 -301.771055) (xy 41.297149 -301.725243) (xy 41.281261 -301.676344) (xy 41.273218 -301.625562)
			(xy 40.95454 -301.625562) (xy 40.946824 -301.673038) (xy 40.93124 -301.719719) (xy 40.908369 -301.763296)
			(xy 40.878804 -301.80264) (xy 40.843311 -301.836732) (xy 40.802808 -301.864688) (xy 40.758346 -301.885786)
			(xy 40.711075 -301.899478) (xy 40.66222 -301.90541) (xy 40.613045 -301.903429) (xy 40.564826 -301.893585)
			(xy 40.51881 -301.876133) (xy 40.476189 -301.851526) (xy 40.438068 -301.820401) (xy 40.405433 -301.783564)
			(xy 40.37913 -301.741968) (xy 40.359839 -301.696692) (xy 40.348062 -301.648908) (xy 40.344102 -301.599854)
			(xy 40.027098 -301.599854) (xy 40.026594 -301.625562) (xy 40.018551 -301.676344) (xy 40.002663 -301.725243)
			(xy 39.97932 -301.771055) (xy 39.949099 -301.812651) (xy 39.912743 -301.849007) (xy 39.871147 -301.879228)
			(xy 39.825335 -301.902571) (xy 39.776436 -301.918459) (xy 39.725654 -301.926502) (xy 39.674238 -301.926502)
			(xy 39.623456 -301.918459) (xy 39.574557 -301.902571) (xy 39.528745 -301.879228) (xy 39.487149 -301.849007)
			(xy 39.450793 -301.812651) (xy 39.420572 -301.771055) (xy 39.397229 -301.725243) (xy 39.381341 -301.676344)
			(xy 39.373298 -301.625562) (xy 39.076634 -301.625562) (xy 39.068591 -301.676344) (xy 39.052703 -301.725243)
			(xy 39.02936 -301.771055) (xy 38.999139 -301.812651) (xy 38.962783 -301.849007) (xy 38.921187 -301.879228)
			(xy 38.875375 -301.902571) (xy 38.826476 -301.918459) (xy 38.775694 -301.926502) (xy 38.724278 -301.926502)
			(xy 38.673496 -301.918459) (xy 38.624597 -301.902571) (xy 38.578785 -301.879228) (xy 38.537189 -301.849007)
			(xy 38.500833 -301.812651) (xy 38.470612 -301.771055) (xy 38.447269 -301.725243) (xy 38.431381 -301.676344)
			(xy 38.423338 -301.625562) (xy 38.104406 -301.625562) (xy 38.09669 -301.673038) (xy 38.081106 -301.719719)
			(xy 38.058235 -301.763296) (xy 38.02867 -301.80264) (xy 37.993177 -301.836732) (xy 37.952674 -301.864688)
			(xy 37.908212 -301.885786) (xy 37.860941 -301.899478) (xy 37.812086 -301.90541) (xy 37.762911 -301.903429)
			(xy 37.714692 -301.893585) (xy 37.668676 -301.876133) (xy 37.626055 -301.851526) (xy 37.587934 -301.820401)
			(xy 37.555299 -301.783564) (xy 37.528996 -301.741968) (xy 37.509705 -301.696692) (xy 37.497928 -301.648908)
			(xy 37.493968 -301.599854) (xy 37.15512 -301.599854) (xy 37.154625 -301.624461) (xy 37.14673 -301.673038)
			(xy 37.131146 -301.719719) (xy 37.108275 -301.763296) (xy 37.07871 -301.80264) (xy 37.043217 -301.836732)
			(xy 37.002714 -301.864688) (xy 36.958252 -301.885786) (xy 36.910981 -301.899478) (xy 36.862126 -301.90541)
			(xy 36.812951 -301.903429) (xy 36.764732 -301.893585) (xy 36.718716 -301.876133) (xy 36.676095 -301.851526)
			(xy 36.637974 -301.820401) (xy 36.605339 -301.783564) (xy 36.579036 -301.741968) (xy 36.559745 -301.696692)
			(xy 36.547968 -301.648908) (xy 36.544008 -301.599854) (xy 23.538685 -301.599854) (xy 23.528671 -301.737731)
			(xy 23.508898 -301.90058) (xy 23.481279 -302.062284) (xy 23.478506 -302.074834) (xy 49.368976 -302.074834)
			(xy 49.372936 -302.02578) (xy 49.384713 -301.977996) (xy 49.404004 -301.93272) (xy 49.430307 -301.891124)
			(xy 49.462942 -301.854287) (xy 49.501063 -301.823162) (xy 49.543684 -301.798555) (xy 49.5897 -301.781103)
			(xy 49.637919 -301.771259) (xy 49.687094 -301.769278) (xy 49.735949 -301.77521) (xy 49.78322 -301.788902)
			(xy 49.827682 -301.81) (xy 49.868185 -301.837956) (xy 49.903678 -301.872048) (xy 49.933243 -301.911392)
			(xy 49.956114 -301.954969) (xy 49.971698 -302.00165) (xy 49.979593 -302.050227) (xy 49.980088 -302.074834)
			(xy 50.31919 -302.074834) (xy 50.32315 -302.02578) (xy 50.334927 -301.977996) (xy 50.354218 -301.93272)
			(xy 50.380521 -301.891124) (xy 50.413156 -301.854287) (xy 50.451277 -301.823162) (xy 50.493898 -301.798555)
			(xy 50.539914 -301.781103) (xy 50.588133 -301.771259) (xy 50.637308 -301.769278) (xy 50.686163 -301.77521)
			(xy 50.733434 -301.788902) (xy 50.777896 -301.81) (xy 50.818399 -301.837956) (xy 50.853892 -301.872048)
			(xy 50.883457 -301.911392) (xy 50.906328 -301.954969) (xy 50.921912 -302.00165) (xy 50.929807 -302.050227)
			(xy 50.930302 -302.074834) (xy 51.26915 -302.074834) (xy 51.27311 -302.02578) (xy 51.284887 -301.977996)
			(xy 51.304178 -301.93272) (xy 51.330481 -301.891124) (xy 51.363116 -301.854287) (xy 51.401237 -301.823162)
			(xy 51.443858 -301.798555) (xy 51.489874 -301.781103) (xy 51.538093 -301.771259) (xy 51.587268 -301.769278)
			(xy 51.636123 -301.77521) (xy 51.683394 -301.788902) (xy 51.727856 -301.81) (xy 51.768359 -301.837956)
			(xy 51.803852 -301.872048) (xy 51.833417 -301.911392) (xy 51.856288 -301.954969) (xy 51.871872 -302.00165)
			(xy 51.879767 -302.050227) (xy 51.880262 -302.074834) (xy 52.21911 -302.074834) (xy 52.22307 -302.02578)
			(xy 52.234847 -301.977996) (xy 52.254138 -301.93272) (xy 52.280441 -301.891124) (xy 52.313076 -301.854287)
			(xy 52.351197 -301.823162) (xy 52.393818 -301.798555) (xy 52.439834 -301.781103) (xy 52.488053 -301.771259)
			(xy 52.537228 -301.769278) (xy 52.586083 -301.77521) (xy 52.633354 -301.788902) (xy 52.677816 -301.81)
			(xy 52.718319 -301.837956) (xy 52.753812 -301.872048) (xy 52.783377 -301.911392) (xy 52.806248 -301.954969)
			(xy 52.821832 -302.00165) (xy 52.829727 -302.050227) (xy 52.830222 -302.074834) (xy 53.16907 -302.074834)
			(xy 53.17303 -302.02578) (xy 53.184807 -301.977996) (xy 53.204098 -301.93272) (xy 53.230401 -301.891124)
			(xy 53.263036 -301.854287) (xy 53.301157 -301.823162) (xy 53.343778 -301.798555) (xy 53.389794 -301.781103)
			(xy 53.438013 -301.771259) (xy 53.487188 -301.769278) (xy 53.536043 -301.77521) (xy 53.583314 -301.788902)
			(xy 53.627776 -301.81) (xy 53.668279 -301.837956) (xy 53.703772 -301.872048) (xy 53.733337 -301.911392)
			(xy 53.756208 -301.954969) (xy 53.771792 -302.00165) (xy 53.779687 -302.050227) (xy 53.780182 -302.074834)
			(xy 54.11903 -302.074834) (xy 54.12299 -302.02578) (xy 54.134767 -301.977996) (xy 54.154058 -301.93272)
			(xy 54.180361 -301.891124) (xy 54.212996 -301.854287) (xy 54.251117 -301.823162) (xy 54.293738 -301.798555)
			(xy 54.339754 -301.781103) (xy 54.387973 -301.771259) (xy 54.437148 -301.769278) (xy 54.486003 -301.77521)
			(xy 54.533274 -301.788902) (xy 54.577736 -301.81) (xy 54.618239 -301.837956) (xy 54.653732 -301.872048)
			(xy 54.683297 -301.911392) (xy 54.706168 -301.954969) (xy 54.721752 -302.00165) (xy 54.729647 -302.050227)
			(xy 54.730142 -302.074834) (xy 55.06899 -302.074834) (xy 55.07295 -302.02578) (xy 55.084727 -301.977996)
			(xy 55.104018 -301.93272) (xy 55.130321 -301.891124) (xy 55.162956 -301.854287) (xy 55.201077 -301.823162)
			(xy 55.243698 -301.798555) (xy 55.289714 -301.781103) (xy 55.337933 -301.771259) (xy 55.387108 -301.769278)
			(xy 55.435963 -301.77521) (xy 55.483234 -301.788902) (xy 55.527696 -301.81) (xy 55.568199 -301.837956)
			(xy 55.603692 -301.872048) (xy 55.633257 -301.911392) (xy 55.656128 -301.954969) (xy 55.671712 -302.00165)
			(xy 55.679607 -302.050227) (xy 55.680102 -302.074834) (xy 56.01895 -302.074834) (xy 56.02291 -302.02578)
			(xy 56.034687 -301.977996) (xy 56.053978 -301.93272) (xy 56.080281 -301.891124) (xy 56.112916 -301.854287)
			(xy 56.151037 -301.823162) (xy 56.193658 -301.798555) (xy 56.239674 -301.781103) (xy 56.287893 -301.771259)
			(xy 56.337068 -301.769278) (xy 56.385923 -301.77521) (xy 56.433194 -301.788902) (xy 56.477656 -301.81)
			(xy 56.518159 -301.837956) (xy 56.553652 -301.872048) (xy 56.583217 -301.911392) (xy 56.606088 -301.954969)
			(xy 56.621672 -302.00165) (xy 56.629567 -302.050227) (xy 56.630062 -302.074834) (xy 56.969164 -302.074834)
			(xy 56.973124 -302.02578) (xy 56.984901 -301.977996) (xy 57.004192 -301.93272) (xy 57.030495 -301.891124)
			(xy 57.06313 -301.854287) (xy 57.101251 -301.823162) (xy 57.143872 -301.798555) (xy 57.189888 -301.781103)
			(xy 57.238107 -301.771259) (xy 57.287282 -301.769278) (xy 57.336137 -301.77521) (xy 57.383408 -301.788902)
			(xy 57.42787 -301.81) (xy 57.468373 -301.837956) (xy 57.503866 -301.872048) (xy 57.533431 -301.911392)
			(xy 57.556302 -301.954969) (xy 57.571886 -302.00165) (xy 57.579781 -302.050227) (xy 57.580276 -302.074834)
			(xy 57.919124 -302.074834) (xy 57.923084 -302.02578) (xy 57.934861 -301.977996) (xy 57.954152 -301.93272)
			(xy 57.980455 -301.891124) (xy 58.01309 -301.854287) (xy 58.051211 -301.823162) (xy 58.093832 -301.798555)
			(xy 58.139848 -301.781103) (xy 58.188067 -301.771259) (xy 58.237242 -301.769278) (xy 58.286097 -301.77521)
			(xy 58.333368 -301.788902) (xy 58.37783 -301.81) (xy 58.418333 -301.837956) (xy 58.453826 -301.872048)
			(xy 58.483391 -301.911392) (xy 58.506262 -301.954969) (xy 58.521846 -302.00165) (xy 58.529741 -302.050227)
			(xy 58.530236 -302.074834) (xy 59.819044 -302.074834) (xy 59.823004 -302.02578) (xy 59.834781 -301.977996)
			(xy 59.854072 -301.93272) (xy 59.880375 -301.891124) (xy 59.91301 -301.854287) (xy 59.951131 -301.823162)
			(xy 59.993752 -301.798555) (xy 60.039768 -301.781103) (xy 60.087987 -301.771259) (xy 60.137162 -301.769278)
			(xy 60.186017 -301.77521) (xy 60.233288 -301.788902) (xy 60.27775 -301.81) (xy 60.318253 -301.837956)
			(xy 60.353746 -301.872048) (xy 60.383311 -301.911392) (xy 60.406182 -301.954969) (xy 60.421766 -302.00165)
			(xy 60.429661 -302.050227) (xy 60.430156 -302.074834) (xy 60.769004 -302.074834) (xy 60.772964 -302.02578)
			(xy 60.784741 -301.977996) (xy 60.804032 -301.93272) (xy 60.830335 -301.891124) (xy 60.86297 -301.854287)
			(xy 60.901091 -301.823162) (xy 60.943712 -301.798555) (xy 60.989728 -301.781103) (xy 61.037947 -301.771259)
			(xy 61.087122 -301.769278) (xy 61.135977 -301.77521) (xy 61.183248 -301.788902) (xy 61.22771 -301.81)
			(xy 61.268213 -301.837956) (xy 61.303706 -301.872048) (xy 61.333271 -301.911392) (xy 61.356142 -301.954969)
			(xy 61.371726 -302.00165) (xy 61.379621 -302.050227) (xy 61.380116 -302.074834) (xy 61.718964 -302.074834)
			(xy 61.722924 -302.02578) (xy 61.734701 -301.977996) (xy 61.753992 -301.93272) (xy 61.780295 -301.891124)
			(xy 61.81293 -301.854287) (xy 61.851051 -301.823162) (xy 61.893672 -301.798555) (xy 61.939688 -301.781103)
			(xy 61.987907 -301.771259) (xy 62.037082 -301.769278) (xy 62.085937 -301.77521) (xy 62.133208 -301.788902)
			(xy 62.17767 -301.81) (xy 62.218173 -301.837956) (xy 62.253666 -301.872048) (xy 62.283231 -301.911392)
			(xy 62.306102 -301.954969) (xy 62.321686 -302.00165) (xy 62.329581 -302.050227) (xy 62.330076 -302.074834)
			(xy 62.669178 -302.074834) (xy 62.673138 -302.02578) (xy 62.684915 -301.977996) (xy 62.704206 -301.93272)
			(xy 62.730509 -301.891124) (xy 62.763144 -301.854287) (xy 62.801265 -301.823162) (xy 62.843886 -301.798555)
			(xy 62.889902 -301.781103) (xy 62.938121 -301.771259) (xy 62.987296 -301.769278) (xy 63.036151 -301.77521)
			(xy 63.083422 -301.788902) (xy 63.127884 -301.81) (xy 63.168387 -301.837956) (xy 63.20388 -301.872048)
			(xy 63.233445 -301.911392) (xy 63.256316 -301.954969) (xy 63.2719 -302.00165) (xy 63.279795 -302.050227)
			(xy 63.28029 -302.074834) (xy 63.619138 -302.074834) (xy 63.623098 -302.02578) (xy 63.634875 -301.977996)
			(xy 63.654166 -301.93272) (xy 63.680469 -301.891124) (xy 63.713104 -301.854287) (xy 63.751225 -301.823162)
			(xy 63.793846 -301.798555) (xy 63.839862 -301.781103) (xy 63.888081 -301.771259) (xy 63.937256 -301.769278)
			(xy 63.986111 -301.77521) (xy 64.033382 -301.788902) (xy 64.077844 -301.81) (xy 64.118347 -301.837956)
			(xy 64.15384 -301.872048) (xy 64.183405 -301.911392) (xy 64.206276 -301.954969) (xy 64.22186 -302.00165)
			(xy 64.229755 -302.050227) (xy 64.23025 -302.074834) (xy 64.569098 -302.074834) (xy 64.573058 -302.02578)
			(xy 64.584835 -301.977996) (xy 64.604126 -301.93272) (xy 64.630429 -301.891124) (xy 64.663064 -301.854287)
			(xy 64.701185 -301.823162) (xy 64.743806 -301.798555) (xy 64.789822 -301.781103) (xy 64.838041 -301.771259)
			(xy 64.887216 -301.769278) (xy 64.936071 -301.77521) (xy 64.983342 -301.788902) (xy 65.027804 -301.81)
			(xy 65.068307 -301.837956) (xy 65.1038 -301.872048) (xy 65.133365 -301.911392) (xy 65.156236 -301.954969)
			(xy 65.17182 -302.00165) (xy 65.179715 -302.050227) (xy 65.18021 -302.074834) (xy 65.519058 -302.074834)
			(xy 65.523018 -302.02578) (xy 65.534795 -301.977996) (xy 65.554086 -301.93272) (xy 65.580389 -301.891124)
			(xy 65.613024 -301.854287) (xy 65.651145 -301.823162) (xy 65.693766 -301.798555) (xy 65.739782 -301.781103)
			(xy 65.788001 -301.771259) (xy 65.837176 -301.769278) (xy 65.886031 -301.77521) (xy 65.933302 -301.788902)
			(xy 65.977764 -301.81) (xy 66.018267 -301.837956) (xy 66.05376 -301.872048) (xy 66.083325 -301.911392)
			(xy 66.106196 -301.954969) (xy 66.12178 -302.00165) (xy 66.129675 -302.050227) (xy 66.13017 -302.074834)
			(xy 66.469018 -302.074834) (xy 66.472978 -302.02578) (xy 66.484755 -301.977996) (xy 66.504046 -301.93272)
			(xy 66.530349 -301.891124) (xy 66.562984 -301.854287) (xy 66.601105 -301.823162) (xy 66.643726 -301.798555)
			(xy 66.689742 -301.781103) (xy 66.737961 -301.771259) (xy 66.787136 -301.769278) (xy 66.835991 -301.77521)
			(xy 66.883262 -301.788902) (xy 66.927724 -301.81) (xy 66.968227 -301.837956) (xy 67.00372 -301.872048)
			(xy 67.033285 -301.911392) (xy 67.056156 -301.954969) (xy 67.07174 -302.00165) (xy 67.079635 -302.050227)
			(xy 67.08013 -302.074834) (xy 67.418978 -302.074834) (xy 67.422938 -302.02578) (xy 67.434715 -301.977996)
			(xy 67.454006 -301.93272) (xy 67.480309 -301.891124) (xy 67.512944 -301.854287) (xy 67.551065 -301.823162)
			(xy 67.593686 -301.798555) (xy 67.639702 -301.781103) (xy 67.687921 -301.771259) (xy 67.737096 -301.769278)
			(xy 67.785951 -301.77521) (xy 67.833222 -301.788902) (xy 67.877684 -301.81) (xy 67.918187 -301.837956)
			(xy 67.95368 -301.872048) (xy 67.983245 -301.911392) (xy 68.006116 -301.954969) (xy 68.0217 -302.00165)
			(xy 68.029595 -302.050227) (xy 68.03009 -302.074834) (xy 68.368938 -302.074834) (xy 68.372898 -302.02578)
			(xy 68.384675 -301.977996) (xy 68.403966 -301.93272) (xy 68.430269 -301.891124) (xy 68.462904 -301.854287)
			(xy 68.501025 -301.823162) (xy 68.543646 -301.798555) (xy 68.589662 -301.781103) (xy 68.637881 -301.771259)
			(xy 68.687056 -301.769278) (xy 68.735911 -301.77521) (xy 68.783182 -301.788902) (xy 68.827644 -301.81)
			(xy 68.868147 -301.837956) (xy 68.90364 -301.872048) (xy 68.933205 -301.911392) (xy 68.956076 -301.954969)
			(xy 68.97166 -302.00165) (xy 68.979555 -302.050227) (xy 68.98005 -302.074834) (xy 69.319152 -302.074834)
			(xy 69.323112 -302.02578) (xy 69.334889 -301.977996) (xy 69.35418 -301.93272) (xy 69.380483 -301.891124)
			(xy 69.413118 -301.854287) (xy 69.451239 -301.823162) (xy 69.49386 -301.798555) (xy 69.539876 -301.781103)
			(xy 69.588095 -301.771259) (xy 69.63727 -301.769278) (xy 69.686125 -301.77521) (xy 69.733396 -301.788902)
			(xy 69.777858 -301.81) (xy 69.818361 -301.837956) (xy 69.853854 -301.872048) (xy 69.883419 -301.911392)
			(xy 69.90629 -301.954969) (xy 69.921874 -302.00165) (xy 69.929769 -302.050227) (xy 69.930264 -302.074834)
			(xy 70.269112 -302.074834) (xy 70.273072 -302.02578) (xy 70.284849 -301.977996) (xy 70.30414 -301.93272)
			(xy 70.330443 -301.891124) (xy 70.363078 -301.854287) (xy 70.401199 -301.823162) (xy 70.44382 -301.798555)
			(xy 70.489836 -301.781103) (xy 70.538055 -301.771259) (xy 70.58723 -301.769278) (xy 70.636085 -301.77521)
			(xy 70.683356 -301.788902) (xy 70.727818 -301.81) (xy 70.768321 -301.837956) (xy 70.803814 -301.872048)
			(xy 70.833379 -301.911392) (xy 70.85625 -301.954969) (xy 70.871834 -302.00165) (xy 70.879729 -302.050227)
			(xy 70.880224 -302.074834) (xy 71.219072 -302.074834) (xy 71.223032 -302.02578) (xy 71.234809 -301.977996)
			(xy 71.2541 -301.93272) (xy 71.280403 -301.891124) (xy 71.313038 -301.854287) (xy 71.351159 -301.823162)
			(xy 71.39378 -301.798555) (xy 71.439796 -301.781103) (xy 71.488015 -301.771259) (xy 71.53719 -301.769278)
			(xy 71.586045 -301.77521) (xy 71.633316 -301.788902) (xy 71.677778 -301.81) (xy 71.718281 -301.837956)
			(xy 71.753774 -301.872048) (xy 71.783339 -301.911392) (xy 71.80621 -301.954969) (xy 71.821794 -302.00165)
			(xy 71.829689 -302.050227) (xy 71.830184 -302.074834) (xy 72.169032 -302.074834) (xy 72.172992 -302.02578)
			(xy 72.184769 -301.977996) (xy 72.20406 -301.93272) (xy 72.230363 -301.891124) (xy 72.262998 -301.854287)
			(xy 72.301119 -301.823162) (xy 72.34374 -301.798555) (xy 72.389756 -301.781103) (xy 72.437975 -301.771259)
			(xy 72.48715 -301.769278) (xy 72.536005 -301.77521) (xy 72.583276 -301.788902) (xy 72.627738 -301.81)
			(xy 72.668241 -301.837956) (xy 72.703734 -301.872048) (xy 72.733299 -301.911392) (xy 72.75617 -301.954969)
			(xy 72.771754 -302.00165) (xy 72.779649 -302.050227) (xy 72.780144 -302.074834) (xy 72.779978 -302.083068)
			(xy 73.119085 -302.083068) (xy 73.121775 -302.033499) (xy 73.132449 -301.985018) (xy 73.150826 -301.938902)
			(xy 73.176421 -301.896368) (xy 73.208561 -301.858534) (xy 73.246398 -301.826399) (xy 73.288936 -301.800809)
			(xy 73.335054 -301.782438) (xy 73.383536 -301.77177) (xy 73.433106 -301.769086) (xy 73.482456 -301.774457)
			(xy 73.530288 -301.787742) (xy 73.57534 -301.80859) (xy 73.616426 -301.836452) (xy 73.652462 -301.870594)
			(xy 73.682501 -301.910117) (xy 73.705749 -301.953979) (xy 73.721595 -302.001024) (xy 73.729621 -302.050013)
			(xy 73.730104 -302.074834) (xy 73.729932 -302.089017) (xy 73.727257 -302.117257) (xy 73.72477 -302.131222)
			(xy 73.722484 -302.143668) (xy 73.72985 -302.16729) (xy 73.80732 -302.24476) (xy 73.830942 -302.252126)
			(xy 73.843388 -302.24984) (xy 73.857355 -302.247369) (xy 73.885594 -302.244694) (xy 73.899776 -302.244506)
			(xy 73.913959 -302.244686) (xy 73.942199 -302.247356) (xy 73.956164 -302.24984) (xy 73.96861 -302.252126)
			(xy 73.992232 -302.24476) (xy 74.069702 -302.16729) (xy 74.077068 -302.143668) (xy 74.074782 -302.131222)
			(xy 74.072299 -302.117257) (xy 74.069631 -302.089017) (xy 74.069448 -302.074834) (xy 74.069941 -302.050009)
			(xy 74.077969 -302.001012) (xy 74.093818 -301.95396) (xy 74.11707 -301.910092) (xy 74.147114 -301.870563)
			(xy 74.183158 -301.836417) (xy 74.224251 -301.808551) (xy 74.269311 -301.787702) (xy 74.31715 -301.774417)
			(xy 74.366509 -301.769047) (xy 74.416086 -301.771734) (xy 74.464575 -301.782407) (xy 74.510699 -301.800784)
			(xy 74.553242 -301.826381) (xy 74.591083 -301.858524) (xy 74.623225 -301.896366) (xy 74.648821 -301.93891)
			(xy 74.667196 -301.985034) (xy 74.677867 -302.033524) (xy 74.680552 -302.083101) (xy 74.675181 -302.13246)
			(xy 74.661895 -302.180299) (xy 74.641044 -302.225358) (xy 74.613177 -302.26645) (xy 74.579029 -302.302492)
			(xy 74.5395 -302.332535) (xy 74.495631 -302.355786) (xy 74.448578 -302.371634) (xy 74.399581 -302.379659)
			(xy 74.374756 -302.380142) (xy 74.360573 -302.379957) (xy 74.332333 -302.37729) (xy 74.318368 -302.374808)
			(xy 74.305922 -302.372522) (xy 74.2823 -302.379888) (xy 74.20483 -302.457358) (xy 74.197464 -302.48098)
			(xy 74.19975 -302.493426) (xy 74.202226 -302.507392) (xy 74.204898 -302.535632) (xy 74.205084 -302.549814)
			(xy 74.204562 -302.575069) (xy 74.196249 -302.624891) (xy 74.179848 -302.672665) (xy 74.155807 -302.717088)
			(xy 74.124783 -302.756948) (xy 74.087621 -302.791158) (xy 74.045335 -302.818784) (xy 73.999079 -302.839074)
			(xy 73.950114 -302.851474) (xy 73.899776 -302.855645) (xy 73.849438 -302.851474) (xy 73.800473 -302.839074)
			(xy 73.754217 -302.818784) (xy 73.711931 -302.791158) (xy 73.674769 -302.756948) (xy 73.643745 -302.717088)
			(xy 73.619704 -302.672665) (xy 73.603303 -302.624891) (xy 73.59499 -302.575069) (xy 73.594468 -302.549814)
			(xy 73.594647 -302.535631) (xy 73.597318 -302.507391) (xy 73.599802 -302.493426) (xy 73.602088 -302.48098)
			(xy 73.594722 -302.457358) (xy 73.517252 -302.379888) (xy 73.49363 -302.372522) (xy 73.481184 -302.374808)
			(xy 73.467218 -302.377283) (xy 73.438978 -302.379956) (xy 73.424796 -302.380142) (xy 73.399975 -302.379618)
			(xy 73.350987 -302.371586) (xy 73.303944 -302.355734) (xy 73.260085 -302.33248) (xy 73.220566 -302.302437)
			(xy 73.186428 -302.266396) (xy 73.158571 -302.225307) (xy 73.137729 -302.180252) (xy 73.12445 -302.132419)
			(xy 73.119085 -302.083068) (xy 72.779978 -302.083068) (xy 72.779649 -302.099441) (xy 72.771754 -302.148018)
			(xy 72.75617 -302.194699) (xy 72.733299 -302.238276) (xy 72.703734 -302.27762) (xy 72.668241 -302.311712)
			(xy 72.627738 -302.339668) (xy 72.583276 -302.360766) (xy 72.536005 -302.374458) (xy 72.48715 -302.38039)
			(xy 72.437975 -302.378409) (xy 72.389756 -302.368565) (xy 72.34374 -302.351113) (xy 72.301119 -302.326506)
			(xy 72.262998 -302.295381) (xy 72.230363 -302.258544) (xy 72.20406 -302.216948) (xy 72.184769 -302.171672)
			(xy 72.172992 -302.123888) (xy 72.169032 -302.074834) (xy 71.830184 -302.074834) (xy 71.829689 -302.099441)
			(xy 71.821794 -302.148018) (xy 71.80621 -302.194699) (xy 71.783339 -302.238276) (xy 71.753774 -302.27762)
			(xy 71.718281 -302.311712) (xy 71.677778 -302.339668) (xy 71.633316 -302.360766) (xy 71.586045 -302.374458)
			(xy 71.53719 -302.38039) (xy 71.488015 -302.378409) (xy 71.439796 -302.368565) (xy 71.39378 -302.351113)
			(xy 71.351159 -302.326506) (xy 71.313038 -302.295381) (xy 71.280403 -302.258544) (xy 71.2541 -302.216948)
			(xy 71.234809 -302.171672) (xy 71.223032 -302.123888) (xy 71.219072 -302.074834) (xy 70.880224 -302.074834)
			(xy 70.879729 -302.099441) (xy 70.871834 -302.148018) (xy 70.85625 -302.194699) (xy 70.833379 -302.238276)
			(xy 70.803814 -302.27762) (xy 70.768321 -302.311712) (xy 70.727818 -302.339668) (xy 70.683356 -302.360766)
			(xy 70.636085 -302.374458) (xy 70.58723 -302.38039) (xy 70.538055 -302.378409) (xy 70.489836 -302.368565)
			(xy 70.44382 -302.351113) (xy 70.401199 -302.326506) (xy 70.363078 -302.295381) (xy 70.330443 -302.258544)
			(xy 70.30414 -302.216948) (xy 70.284849 -302.171672) (xy 70.273072 -302.123888) (xy 70.269112 -302.074834)
			(xy 69.930264 -302.074834) (xy 69.929769 -302.099441) (xy 69.921874 -302.148018) (xy 69.90629 -302.194699)
			(xy 69.883419 -302.238276) (xy 69.853854 -302.27762) (xy 69.818361 -302.311712) (xy 69.777858 -302.339668)
			(xy 69.733396 -302.360766) (xy 69.686125 -302.374458) (xy 69.63727 -302.38039) (xy 69.588095 -302.378409)
			(xy 69.539876 -302.368565) (xy 69.49386 -302.351113) (xy 69.451239 -302.326506) (xy 69.413118 -302.295381)
			(xy 69.380483 -302.258544) (xy 69.35418 -302.216948) (xy 69.334889 -302.171672) (xy 69.323112 -302.123888)
			(xy 69.319152 -302.074834) (xy 68.98005 -302.074834) (xy 68.979555 -302.099441) (xy 68.97166 -302.148018)
			(xy 68.956076 -302.194699) (xy 68.933205 -302.238276) (xy 68.90364 -302.27762) (xy 68.868147 -302.311712)
			(xy 68.827644 -302.339668) (xy 68.783182 -302.360766) (xy 68.735911 -302.374458) (xy 68.687056 -302.38039)
			(xy 68.637881 -302.378409) (xy 68.589662 -302.368565) (xy 68.543646 -302.351113) (xy 68.501025 -302.326506)
			(xy 68.462904 -302.295381) (xy 68.430269 -302.258544) (xy 68.403966 -302.216948) (xy 68.384675 -302.171672)
			(xy 68.372898 -302.123888) (xy 68.368938 -302.074834) (xy 68.03009 -302.074834) (xy 68.029595 -302.099441)
			(xy 68.0217 -302.148018) (xy 68.006116 -302.194699) (xy 67.983245 -302.238276) (xy 67.95368 -302.27762)
			(xy 67.918187 -302.311712) (xy 67.877684 -302.339668) (xy 67.833222 -302.360766) (xy 67.785951 -302.374458)
			(xy 67.737096 -302.38039) (xy 67.687921 -302.378409) (xy 67.639702 -302.368565) (xy 67.593686 -302.351113)
			(xy 67.551065 -302.326506) (xy 67.512944 -302.295381) (xy 67.480309 -302.258544) (xy 67.454006 -302.216948)
			(xy 67.434715 -302.171672) (xy 67.422938 -302.123888) (xy 67.418978 -302.074834) (xy 67.08013 -302.074834)
			(xy 67.079635 -302.099441) (xy 67.07174 -302.148018) (xy 67.056156 -302.194699) (xy 67.033285 -302.238276)
			(xy 67.00372 -302.27762) (xy 66.968227 -302.311712) (xy 66.927724 -302.339668) (xy 66.883262 -302.360766)
			(xy 66.835991 -302.374458) (xy 66.787136 -302.38039) (xy 66.737961 -302.378409) (xy 66.689742 -302.368565)
			(xy 66.643726 -302.351113) (xy 66.601105 -302.326506) (xy 66.562984 -302.295381) (xy 66.530349 -302.258544)
			(xy 66.504046 -302.216948) (xy 66.484755 -302.171672) (xy 66.472978 -302.123888) (xy 66.469018 -302.074834)
			(xy 66.13017 -302.074834) (xy 66.129675 -302.099441) (xy 66.12178 -302.148018) (xy 66.106196 -302.194699)
			(xy 66.083325 -302.238276) (xy 66.05376 -302.27762) (xy 66.018267 -302.311712) (xy 65.977764 -302.339668)
			(xy 65.933302 -302.360766) (xy 65.886031 -302.374458) (xy 65.837176 -302.38039) (xy 65.788001 -302.378409)
			(xy 65.739782 -302.368565) (xy 65.693766 -302.351113) (xy 65.651145 -302.326506) (xy 65.613024 -302.295381)
			(xy 65.580389 -302.258544) (xy 65.554086 -302.216948) (xy 65.534795 -302.171672) (xy 65.523018 -302.123888)
			(xy 65.519058 -302.074834) (xy 65.18021 -302.074834) (xy 65.179715 -302.099441) (xy 65.17182 -302.148018)
			(xy 65.156236 -302.194699) (xy 65.133365 -302.238276) (xy 65.1038 -302.27762) (xy 65.068307 -302.311712)
			(xy 65.027804 -302.339668) (xy 64.983342 -302.360766) (xy 64.936071 -302.374458) (xy 64.887216 -302.38039)
			(xy 64.838041 -302.378409) (xy 64.789822 -302.368565) (xy 64.743806 -302.351113) (xy 64.701185 -302.326506)
			(xy 64.663064 -302.295381) (xy 64.630429 -302.258544) (xy 64.604126 -302.216948) (xy 64.584835 -302.171672)
			(xy 64.573058 -302.123888) (xy 64.569098 -302.074834) (xy 64.23025 -302.074834) (xy 64.229755 -302.099441)
			(xy 64.22186 -302.148018) (xy 64.206276 -302.194699) (xy 64.183405 -302.238276) (xy 64.15384 -302.27762)
			(xy 64.118347 -302.311712) (xy 64.077844 -302.339668) (xy 64.033382 -302.360766) (xy 63.986111 -302.374458)
			(xy 63.937256 -302.38039) (xy 63.888081 -302.378409) (xy 63.839862 -302.368565) (xy 63.793846 -302.351113)
			(xy 63.751225 -302.326506) (xy 63.713104 -302.295381) (xy 63.680469 -302.258544) (xy 63.654166 -302.216948)
			(xy 63.634875 -302.171672) (xy 63.623098 -302.123888) (xy 63.619138 -302.074834) (xy 63.28029 -302.074834)
			(xy 63.279795 -302.099441) (xy 63.2719 -302.148018) (xy 63.256316 -302.194699) (xy 63.233445 -302.238276)
			(xy 63.20388 -302.27762) (xy 63.168387 -302.311712) (xy 63.127884 -302.339668) (xy 63.083422 -302.360766)
			(xy 63.036151 -302.374458) (xy 62.987296 -302.38039) (xy 62.938121 -302.378409) (xy 62.889902 -302.368565)
			(xy 62.843886 -302.351113) (xy 62.801265 -302.326506) (xy 62.763144 -302.295381) (xy 62.730509 -302.258544)
			(xy 62.704206 -302.216948) (xy 62.684915 -302.171672) (xy 62.673138 -302.123888) (xy 62.669178 -302.074834)
			(xy 62.330076 -302.074834) (xy 62.329581 -302.099441) (xy 62.321686 -302.148018) (xy 62.306102 -302.194699)
			(xy 62.283231 -302.238276) (xy 62.253666 -302.27762) (xy 62.218173 -302.311712) (xy 62.17767 -302.339668)
			(xy 62.133208 -302.360766) (xy 62.085937 -302.374458) (xy 62.037082 -302.38039) (xy 61.987907 -302.378409)
			(xy 61.939688 -302.368565) (xy 61.893672 -302.351113) (xy 61.851051 -302.326506) (xy 61.81293 -302.295381)
			(xy 61.780295 -302.258544) (xy 61.753992 -302.216948) (xy 61.734701 -302.171672) (xy 61.722924 -302.123888)
			(xy 61.718964 -302.074834) (xy 61.380116 -302.074834) (xy 61.379621 -302.099441) (xy 61.371726 -302.148018)
			(xy 61.356142 -302.194699) (xy 61.333271 -302.238276) (xy 61.303706 -302.27762) (xy 61.268213 -302.311712)
			(xy 61.22771 -302.339668) (xy 61.183248 -302.360766) (xy 61.135977 -302.374458) (xy 61.087122 -302.38039)
			(xy 61.037947 -302.378409) (xy 60.989728 -302.368565) (xy 60.943712 -302.351113) (xy 60.901091 -302.326506)
			(xy 60.86297 -302.295381) (xy 60.830335 -302.258544) (xy 60.804032 -302.216948) (xy 60.784741 -302.171672)
			(xy 60.772964 -302.123888) (xy 60.769004 -302.074834) (xy 60.430156 -302.074834) (xy 60.429661 -302.099441)
			(xy 60.421766 -302.148018) (xy 60.406182 -302.194699) (xy 60.383311 -302.238276) (xy 60.353746 -302.27762)
			(xy 60.318253 -302.311712) (xy 60.27775 -302.339668) (xy 60.233288 -302.360766) (xy 60.186017 -302.374458)
			(xy 60.137162 -302.38039) (xy 60.087987 -302.378409) (xy 60.039768 -302.368565) (xy 59.993752 -302.351113)
			(xy 59.951131 -302.326506) (xy 59.91301 -302.295381) (xy 59.880375 -302.258544) (xy 59.854072 -302.216948)
			(xy 59.834781 -302.171672) (xy 59.823004 -302.123888) (xy 59.819044 -302.074834) (xy 58.530236 -302.074834)
			(xy 58.529741 -302.099441) (xy 58.521846 -302.148018) (xy 58.506262 -302.194699) (xy 58.483391 -302.238276)
			(xy 58.453826 -302.27762) (xy 58.418333 -302.311712) (xy 58.37783 -302.339668) (xy 58.333368 -302.360766)
			(xy 58.286097 -302.374458) (xy 58.237242 -302.38039) (xy 58.188067 -302.378409) (xy 58.139848 -302.368565)
			(xy 58.093832 -302.351113) (xy 58.051211 -302.326506) (xy 58.01309 -302.295381) (xy 57.980455 -302.258544)
			(xy 57.954152 -302.216948) (xy 57.934861 -302.171672) (xy 57.923084 -302.123888) (xy 57.919124 -302.074834)
			(xy 57.580276 -302.074834) (xy 57.579781 -302.099441) (xy 57.571886 -302.148018) (xy 57.556302 -302.194699)
			(xy 57.533431 -302.238276) (xy 57.503866 -302.27762) (xy 57.468373 -302.311712) (xy 57.42787 -302.339668)
			(xy 57.383408 -302.360766) (xy 57.336137 -302.374458) (xy 57.287282 -302.38039) (xy 57.238107 -302.378409)
			(xy 57.189888 -302.368565) (xy 57.143872 -302.351113) (xy 57.101251 -302.326506) (xy 57.06313 -302.295381)
			(xy 57.030495 -302.258544) (xy 57.004192 -302.216948) (xy 56.984901 -302.171672) (xy 56.973124 -302.123888)
			(xy 56.969164 -302.074834) (xy 56.630062 -302.074834) (xy 56.629567 -302.099441) (xy 56.621672 -302.148018)
			(xy 56.606088 -302.194699) (xy 56.583217 -302.238276) (xy 56.553652 -302.27762) (xy 56.518159 -302.311712)
			(xy 56.477656 -302.339668) (xy 56.433194 -302.360766) (xy 56.385923 -302.374458) (xy 56.337068 -302.38039)
			(xy 56.287893 -302.378409) (xy 56.239674 -302.368565) (xy 56.193658 -302.351113) (xy 56.151037 -302.326506)
			(xy 56.112916 -302.295381) (xy 56.080281 -302.258544) (xy 56.053978 -302.216948) (xy 56.034687 -302.171672)
			(xy 56.02291 -302.123888) (xy 56.01895 -302.074834) (xy 55.680102 -302.074834) (xy 55.679607 -302.099441)
			(xy 55.671712 -302.148018) (xy 55.656128 -302.194699) (xy 55.633257 -302.238276) (xy 55.603692 -302.27762)
			(xy 55.568199 -302.311712) (xy 55.527696 -302.339668) (xy 55.483234 -302.360766) (xy 55.435963 -302.374458)
			(xy 55.387108 -302.38039) (xy 55.337933 -302.378409) (xy 55.289714 -302.368565) (xy 55.243698 -302.351113)
			(xy 55.201077 -302.326506) (xy 55.162956 -302.295381) (xy 55.130321 -302.258544) (xy 55.104018 -302.216948)
			(xy 55.084727 -302.171672) (xy 55.07295 -302.123888) (xy 55.06899 -302.074834) (xy 54.730142 -302.074834)
			(xy 54.729647 -302.099441) (xy 54.721752 -302.148018) (xy 54.706168 -302.194699) (xy 54.683297 -302.238276)
			(xy 54.653732 -302.27762) (xy 54.618239 -302.311712) (xy 54.577736 -302.339668) (xy 54.533274 -302.360766)
			(xy 54.486003 -302.374458) (xy 54.437148 -302.38039) (xy 54.387973 -302.378409) (xy 54.339754 -302.368565)
			(xy 54.293738 -302.351113) (xy 54.251117 -302.326506) (xy 54.212996 -302.295381) (xy 54.180361 -302.258544)
			(xy 54.154058 -302.216948) (xy 54.134767 -302.171672) (xy 54.12299 -302.123888) (xy 54.11903 -302.074834)
			(xy 53.780182 -302.074834) (xy 53.779687 -302.099441) (xy 53.771792 -302.148018) (xy 53.756208 -302.194699)
			(xy 53.733337 -302.238276) (xy 53.703772 -302.27762) (xy 53.668279 -302.311712) (xy 53.627776 -302.339668)
			(xy 53.583314 -302.360766) (xy 53.536043 -302.374458) (xy 53.487188 -302.38039) (xy 53.438013 -302.378409)
			(xy 53.389794 -302.368565) (xy 53.343778 -302.351113) (xy 53.301157 -302.326506) (xy 53.263036 -302.295381)
			(xy 53.230401 -302.258544) (xy 53.204098 -302.216948) (xy 53.184807 -302.171672) (xy 53.17303 -302.123888)
			(xy 53.16907 -302.074834) (xy 52.830222 -302.074834) (xy 52.829727 -302.099441) (xy 52.821832 -302.148018)
			(xy 52.806248 -302.194699) (xy 52.783377 -302.238276) (xy 52.753812 -302.27762) (xy 52.718319 -302.311712)
			(xy 52.677816 -302.339668) (xy 52.633354 -302.360766) (xy 52.586083 -302.374458) (xy 52.537228 -302.38039)
			(xy 52.488053 -302.378409) (xy 52.439834 -302.368565) (xy 52.393818 -302.351113) (xy 52.351197 -302.326506)
			(xy 52.313076 -302.295381) (xy 52.280441 -302.258544) (xy 52.254138 -302.216948) (xy 52.234847 -302.171672)
			(xy 52.22307 -302.123888) (xy 52.21911 -302.074834) (xy 51.880262 -302.074834) (xy 51.879767 -302.099441)
			(xy 51.871872 -302.148018) (xy 51.856288 -302.194699) (xy 51.833417 -302.238276) (xy 51.803852 -302.27762)
			(xy 51.768359 -302.311712) (xy 51.727856 -302.339668) (xy 51.683394 -302.360766) (xy 51.636123 -302.374458)
			(xy 51.587268 -302.38039) (xy 51.538093 -302.378409) (xy 51.489874 -302.368565) (xy 51.443858 -302.351113)
			(xy 51.401237 -302.326506) (xy 51.363116 -302.295381) (xy 51.330481 -302.258544) (xy 51.304178 -302.216948)
			(xy 51.284887 -302.171672) (xy 51.27311 -302.123888) (xy 51.26915 -302.074834) (xy 50.930302 -302.074834)
			(xy 50.929807 -302.099441) (xy 50.921912 -302.148018) (xy 50.906328 -302.194699) (xy 50.883457 -302.238276)
			(xy 50.853892 -302.27762) (xy 50.818399 -302.311712) (xy 50.777896 -302.339668) (xy 50.733434 -302.360766)
			(xy 50.686163 -302.374458) (xy 50.637308 -302.38039) (xy 50.588133 -302.378409) (xy 50.539914 -302.368565)
			(xy 50.493898 -302.351113) (xy 50.451277 -302.326506) (xy 50.413156 -302.295381) (xy 50.380521 -302.258544)
			(xy 50.354218 -302.216948) (xy 50.334927 -302.171672) (xy 50.32315 -302.123888) (xy 50.31919 -302.074834)
			(xy 49.980088 -302.074834) (xy 49.979593 -302.099441) (xy 49.971698 -302.148018) (xy 49.956114 -302.194699)
			(xy 49.933243 -302.238276) (xy 49.903678 -302.27762) (xy 49.868185 -302.311712) (xy 49.827682 -302.339668)
			(xy 49.78322 -302.360766) (xy 49.735949 -302.374458) (xy 49.687094 -302.38039) (xy 49.637919 -302.378409)
			(xy 49.5897 -302.368565) (xy 49.543684 -302.351113) (xy 49.501063 -302.326506) (xy 49.462942 -302.295381)
			(xy 49.430307 -302.258544) (xy 49.404004 -302.216948) (xy 49.384713 -302.171672) (xy 49.372936 -302.123888)
			(xy 49.368976 -302.074834) (xy 23.478506 -302.074834) (xy 23.445881 -302.222464) (xy 23.402785 -302.380747)
			(xy 23.352093 -302.536763) (xy 23.347047 -302.550068) (xy 35.593794 -302.550068) (xy 35.597754 -302.501014)
			(xy 35.609531 -302.45323) (xy 35.628822 -302.407954) (xy 35.655125 -302.366358) (xy 35.68776 -302.329521)
			(xy 35.725881 -302.298396) (xy 35.768502 -302.273789) (xy 35.814518 -302.256337) (xy 35.862737 -302.246493)
			(xy 35.911912 -302.244512) (xy 35.960767 -302.250444) (xy 36.008038 -302.264136) (xy 36.0525 -302.285234)
			(xy 36.093003 -302.31319) (xy 36.128496 -302.347282) (xy 36.158061 -302.386626) (xy 36.180932 -302.430203)
			(xy 36.196516 -302.476884) (xy 36.204411 -302.525461) (xy 36.204906 -302.550068) (xy 36.204411 -302.574675)
			(xy 36.204273 -302.575522) (xy 36.523164 -302.575522) (xy 36.523164 -302.524106) (xy 36.531207 -302.473324)
			(xy 36.547095 -302.424425) (xy 36.570438 -302.378613) (xy 36.600659 -302.337017) (xy 36.637015 -302.300661)
			(xy 36.678611 -302.27044) (xy 36.724423 -302.247097) (xy 36.773322 -302.231209) (xy 36.824104 -302.223166)
			(xy 36.87552 -302.223166) (xy 36.926302 -302.231209) (xy 36.975201 -302.247097) (xy 37.021013 -302.27044)
			(xy 37.062609 -302.300661) (xy 37.098965 -302.337017) (xy 37.129186 -302.378613) (xy 37.152529 -302.424425)
			(xy 37.168417 -302.473324) (xy 37.17646 -302.524106) (xy 37.176964 -302.549814) (xy 37.17646 -302.575522)
			(xy 37.473124 -302.575522) (xy 37.473124 -302.524106) (xy 37.481167 -302.473324) (xy 37.497055 -302.424425)
			(xy 37.520398 -302.378613) (xy 37.550619 -302.337017) (xy 37.586975 -302.300661) (xy 37.628571 -302.27044)
			(xy 37.674383 -302.247097) (xy 37.723282 -302.231209) (xy 37.774064 -302.223166) (xy 37.82548 -302.223166)
			(xy 37.876262 -302.231209) (xy 37.925161 -302.247097) (xy 37.970973 -302.27044) (xy 38.012569 -302.300661)
			(xy 38.048925 -302.337017) (xy 38.079146 -302.378613) (xy 38.102489 -302.424425) (xy 38.118377 -302.473324)
			(xy 38.12642 -302.524106) (xy 38.126924 -302.549814) (xy 38.444182 -302.549814) (xy 38.448142 -302.50076)
			(xy 38.459919 -302.452976) (xy 38.47921 -302.4077) (xy 38.505513 -302.366104) (xy 38.538148 -302.329267)
			(xy 38.576269 -302.298142) (xy 38.61889 -302.273535) (xy 38.664906 -302.256083) (xy 38.713125 -302.246239)
			(xy 38.7623 -302.244258) (xy 38.811155 -302.25019) (xy 38.858426 -302.263882) (xy 38.902888 -302.28498)
			(xy 38.943391 -302.312936) (xy 38.978884 -302.347028) (xy 39.008449 -302.386372) (xy 39.03132 -302.429949)
			(xy 39.046904 -302.47663) (xy 39.054799 -302.525207) (xy 39.055294 -302.549814) (xy 39.394142 -302.549814)
			(xy 39.398102 -302.50076) (xy 39.409879 -302.452976) (xy 39.42917 -302.4077) (xy 39.455473 -302.366104)
			(xy 39.488108 -302.329267) (xy 39.526229 -302.298142) (xy 39.56885 -302.273535) (xy 39.614866 -302.256083)
			(xy 39.663085 -302.246239) (xy 39.71226 -302.244258) (xy 39.761115 -302.25019) (xy 39.808386 -302.263882)
			(xy 39.852848 -302.28498) (xy 39.893351 -302.312936) (xy 39.928844 -302.347028) (xy 39.958409 -302.386372)
			(xy 39.98128 -302.429949) (xy 39.996864 -302.47663) (xy 40.004759 -302.525207) (xy 40.005254 -302.549814)
			(xy 40.344102 -302.549814) (xy 40.348062 -302.50076) (xy 40.359839 -302.452976) (xy 40.37913 -302.4077)
			(xy 40.405433 -302.366104) (xy 40.438068 -302.329267) (xy 40.476189 -302.298142) (xy 40.51881 -302.273535)
			(xy 40.564826 -302.256083) (xy 40.613045 -302.246239) (xy 40.66222 -302.244258) (xy 40.711075 -302.25019)
			(xy 40.758346 -302.263882) (xy 40.802808 -302.28498) (xy 40.843311 -302.312936) (xy 40.878804 -302.347028)
			(xy 40.908369 -302.386372) (xy 40.93124 -302.429949) (xy 40.946824 -302.47663) (xy 40.954719 -302.525207)
			(xy 40.955214 -302.549814) (xy 41.294062 -302.549814) (xy 41.298022 -302.50076) (xy 41.309799 -302.452976)
			(xy 41.32909 -302.4077) (xy 41.355393 -302.366104) (xy 41.388028 -302.329267) (xy 41.426149 -302.298142)
			(xy 41.46877 -302.273535) (xy 41.514786 -302.256083) (xy 41.563005 -302.246239) (xy 41.61218 -302.244258)
			(xy 41.661035 -302.25019) (xy 41.708306 -302.263882) (xy 41.752768 -302.28498) (xy 41.793271 -302.312936)
			(xy 41.828764 -302.347028) (xy 41.858329 -302.386372) (xy 41.8812 -302.429949) (xy 41.896784 -302.47663)
			(xy 41.904679 -302.525207) (xy 41.905174 -302.549814) (xy 42.244022 -302.549814) (xy 42.247982 -302.50076)
			(xy 42.259759 -302.452976) (xy 42.27905 -302.4077) (xy 42.305353 -302.366104) (xy 42.337988 -302.329267)
			(xy 42.376109 -302.298142) (xy 42.41873 -302.273535) (xy 42.464746 -302.256083) (xy 42.512965 -302.246239)
			(xy 42.56214 -302.244258) (xy 42.610995 -302.25019) (xy 42.658266 -302.263882) (xy 42.702728 -302.28498)
			(xy 42.743231 -302.312936) (xy 42.778724 -302.347028) (xy 42.808289 -302.386372) (xy 42.83116 -302.429949)
			(xy 42.846744 -302.47663) (xy 42.854639 -302.525207) (xy 42.855134 -302.549814) (xy 42.854639 -302.574421)
			(xy 42.85446 -302.575522) (xy 43.173138 -302.575522) (xy 43.173138 -302.524106) (xy 43.181181 -302.473324)
			(xy 43.197069 -302.424425) (xy 43.220412 -302.378613) (xy 43.250633 -302.337017) (xy 43.286989 -302.300661)
			(xy 43.328585 -302.27044) (xy 43.374397 -302.247097) (xy 43.423296 -302.231209) (xy 43.474078 -302.223166)
			(xy 43.525494 -302.223166) (xy 43.576276 -302.231209) (xy 43.625175 -302.247097) (xy 43.670987 -302.27044)
			(xy 43.712583 -302.300661) (xy 43.748939 -302.337017) (xy 43.77916 -302.378613) (xy 43.802503 -302.424425)
			(xy 43.818391 -302.473324) (xy 43.826434 -302.524106) (xy 43.826938 -302.549814) (xy 43.826434 -302.575522)
			(xy 44.123098 -302.575522) (xy 44.123098 -302.524106) (xy 44.131141 -302.473324) (xy 44.147029 -302.424425)
			(xy 44.170372 -302.378613) (xy 44.200593 -302.337017) (xy 44.236949 -302.300661) (xy 44.278545 -302.27044)
			(xy 44.324357 -302.247097) (xy 44.373256 -302.231209) (xy 44.424038 -302.223166) (xy 44.475454 -302.223166)
			(xy 44.526236 -302.231209) (xy 44.575135 -302.247097) (xy 44.620947 -302.27044) (xy 44.662543 -302.300661)
			(xy 44.698899 -302.337017) (xy 44.72912 -302.378613) (xy 44.752463 -302.424425) (xy 44.768351 -302.473324)
			(xy 44.776394 -302.524106) (xy 44.776898 -302.549814) (xy 45.094156 -302.549814) (xy 45.098116 -302.50076)
			(xy 45.109893 -302.452976) (xy 45.129184 -302.4077) (xy 45.155487 -302.366104) (xy 45.188122 -302.329267)
			(xy 45.226243 -302.298142) (xy 45.268864 -302.273535) (xy 45.31488 -302.256083) (xy 45.363099 -302.246239)
			(xy 45.412274 -302.244258) (xy 45.461129 -302.25019) (xy 45.5084 -302.263882) (xy 45.552862 -302.28498)
			(xy 45.593365 -302.312936) (xy 45.628858 -302.347028) (xy 45.658423 -302.386372) (xy 45.681294 -302.429949)
			(xy 45.696878 -302.47663) (xy 45.704773 -302.525207) (xy 45.705268 -302.549814) (xy 45.705101 -302.558091)
			(xy 46.044161 -302.558091) (xy 46.046848 -302.508518) (xy 46.057519 -302.460032) (xy 46.075894 -302.413912)
			(xy 46.101489 -302.371372) (xy 46.133629 -302.333533) (xy 46.171467 -302.301392) (xy 46.214006 -302.275797)
			(xy 46.260126 -302.257421) (xy 46.308612 -302.246749) (xy 46.358185 -302.244061) (xy 46.40754 -302.249429)
			(xy 46.455376 -302.262712) (xy 46.500434 -302.283559) (xy 46.541525 -302.31142) (xy 46.577567 -302.345563)
			(xy 46.60761 -302.385087) (xy 46.630863 -302.428951) (xy 46.646713 -302.475998) (xy 46.654743 -302.524991)
			(xy 46.655228 -302.549814) (xy 46.655053 -302.563997) (xy 46.65238 -302.592237) (xy 46.649894 -302.606202)
			(xy 46.647715 -302.620166) (xy 46.650295 -302.648301) (xy 46.660486 -302.674651) (xy 46.677509 -302.697199)
			(xy 46.700059 -302.714219) (xy 46.72641 -302.724408) (xy 46.754545 -302.726985) (xy 46.768512 -302.72482)
			(xy 46.782478 -302.722346) (xy 46.810718 -302.719673) (xy 46.8249 -302.719486) (xy 46.849721 -302.719978)
			(xy 46.898709 -302.728009) (xy 46.945752 -302.74386) (xy 46.989611 -302.767113) (xy 47.029131 -302.797155)
			(xy 47.063269 -302.833195) (xy 47.091128 -302.874283) (xy 47.111972 -302.919337) (xy 47.125252 -302.967169)
			(xy 47.130619 -303.01652) (xy 47.13017 -303.024794) (xy 47.469056 -303.024794) (xy 47.473016 -302.97574)
			(xy 47.484793 -302.927956) (xy 47.504084 -302.88268) (xy 47.530387 -302.841084) (xy 47.563022 -302.804247)
			(xy 47.601143 -302.773122) (xy 47.643764 -302.748515) (xy 47.68978 -302.731063) (xy 47.737999 -302.721219)
			(xy 47.787174 -302.719238) (xy 47.836029 -302.72517) (xy 47.8833 -302.738862) (xy 47.927762 -302.75996)
			(xy 47.968265 -302.787916) (xy 48.003758 -302.822008) (xy 48.033323 -302.861352) (xy 48.056194 -302.904929)
			(xy 48.071778 -302.95161) (xy 48.079673 -303.000187) (xy 48.080168 -303.024794) (xy 48.419016 -303.024794)
			(xy 48.422976 -302.97574) (xy 48.434753 -302.927956) (xy 48.454044 -302.88268) (xy 48.480347 -302.841084)
			(xy 48.512982 -302.804247) (xy 48.551103 -302.773122) (xy 48.593724 -302.748515) (xy 48.63974 -302.731063)
			(xy 48.687959 -302.721219) (xy 48.737134 -302.719238) (xy 48.785989 -302.72517) (xy 48.83326 -302.738862)
			(xy 48.877722 -302.75996) (xy 48.918225 -302.787916) (xy 48.953718 -302.822008) (xy 48.983283 -302.861352)
			(xy 49.006154 -302.904929) (xy 49.021738 -302.95161) (xy 49.029633 -303.000187) (xy 49.030128 -303.024794)
			(xy 49.368976 -303.024794) (xy 49.372936 -302.97574) (xy 49.384713 -302.927956) (xy 49.404004 -302.88268)
			(xy 49.430307 -302.841084) (xy 49.462942 -302.804247) (xy 49.501063 -302.773122) (xy 49.543684 -302.748515)
			(xy 49.5897 -302.731063) (xy 49.637919 -302.721219) (xy 49.687094 -302.719238) (xy 49.735949 -302.72517)
			(xy 49.78322 -302.738862) (xy 49.827682 -302.75996) (xy 49.868185 -302.787916) (xy 49.903678 -302.822008)
			(xy 49.933243 -302.861352) (xy 49.956114 -302.904929) (xy 49.971698 -302.95161) (xy 49.979593 -303.000187)
			(xy 49.980088 -303.024794) (xy 50.31919 -303.024794) (xy 50.32315 -302.97574) (xy 50.334927 -302.927956)
			(xy 50.354218 -302.88268) (xy 50.380521 -302.841084) (xy 50.413156 -302.804247) (xy 50.451277 -302.773122)
			(xy 50.493898 -302.748515) (xy 50.539914 -302.731063) (xy 50.588133 -302.721219) (xy 50.637308 -302.719238)
			(xy 50.686163 -302.72517) (xy 50.733434 -302.738862) (xy 50.777896 -302.75996) (xy 50.818399 -302.787916)
			(xy 50.853892 -302.822008) (xy 50.883457 -302.861352) (xy 50.906328 -302.904929) (xy 50.921912 -302.95161)
			(xy 50.929807 -303.000187) (xy 50.930302 -303.024794) (xy 51.26915 -303.024794) (xy 51.27311 -302.97574)
			(xy 51.284887 -302.927956) (xy 51.304178 -302.88268) (xy 51.330481 -302.841084) (xy 51.363116 -302.804247)
			(xy 51.401237 -302.773122) (xy 51.443858 -302.748515) (xy 51.489874 -302.731063) (xy 51.538093 -302.721219)
			(xy 51.587268 -302.719238) (xy 51.636123 -302.72517) (xy 51.683394 -302.738862) (xy 51.727856 -302.75996)
			(xy 51.768359 -302.787916) (xy 51.803852 -302.822008) (xy 51.833417 -302.861352) (xy 51.856288 -302.904929)
			(xy 51.871872 -302.95161) (xy 51.879767 -303.000187) (xy 51.880262 -303.024794) (xy 52.21911 -303.024794)
			(xy 52.22307 -302.97574) (xy 52.234847 -302.927956) (xy 52.254138 -302.88268) (xy 52.280441 -302.841084)
			(xy 52.313076 -302.804247) (xy 52.351197 -302.773122) (xy 52.393818 -302.748515) (xy 52.439834 -302.731063)
			(xy 52.488053 -302.721219) (xy 52.537228 -302.719238) (xy 52.586083 -302.72517) (xy 52.633354 -302.738862)
			(xy 52.677816 -302.75996) (xy 52.718319 -302.787916) (xy 52.753812 -302.822008) (xy 52.783377 -302.861352)
			(xy 52.806248 -302.904929) (xy 52.821832 -302.95161) (xy 52.829727 -303.000187) (xy 52.830222 -303.024794)
			(xy 53.16907 -303.024794) (xy 53.17303 -302.97574) (xy 53.184807 -302.927956) (xy 53.204098 -302.88268)
			(xy 53.230401 -302.841084) (xy 53.263036 -302.804247) (xy 53.301157 -302.773122) (xy 53.343778 -302.748515)
			(xy 53.389794 -302.731063) (xy 53.438013 -302.721219) (xy 53.487188 -302.719238) (xy 53.536043 -302.72517)
			(xy 53.583314 -302.738862) (xy 53.627776 -302.75996) (xy 53.668279 -302.787916) (xy 53.703772 -302.822008)
			(xy 53.733337 -302.861352) (xy 53.756208 -302.904929) (xy 53.771792 -302.95161) (xy 53.779687 -303.000187)
			(xy 53.780182 -303.024794) (xy 54.11903 -303.024794) (xy 54.12299 -302.97574) (xy 54.134767 -302.927956)
			(xy 54.154058 -302.88268) (xy 54.180361 -302.841084) (xy 54.212996 -302.804247) (xy 54.251117 -302.773122)
			(xy 54.293738 -302.748515) (xy 54.339754 -302.731063) (xy 54.387973 -302.721219) (xy 54.437148 -302.719238)
			(xy 54.486003 -302.72517) (xy 54.533274 -302.738862) (xy 54.577736 -302.75996) (xy 54.618239 -302.787916)
			(xy 54.653732 -302.822008) (xy 54.683297 -302.861352) (xy 54.706168 -302.904929) (xy 54.721752 -302.95161)
			(xy 54.729647 -303.000187) (xy 54.730142 -303.024794) (xy 55.06899 -303.024794) (xy 55.07295 -302.97574)
			(xy 55.084727 -302.927956) (xy 55.104018 -302.88268) (xy 55.130321 -302.841084) (xy 55.162956 -302.804247)
			(xy 55.201077 -302.773122) (xy 55.243698 -302.748515) (xy 55.289714 -302.731063) (xy 55.337933 -302.721219)
			(xy 55.387108 -302.719238) (xy 55.435963 -302.72517) (xy 55.483234 -302.738862) (xy 55.527696 -302.75996)
			(xy 55.568199 -302.787916) (xy 55.603692 -302.822008) (xy 55.633257 -302.861352) (xy 55.656128 -302.904929)
			(xy 55.671712 -302.95161) (xy 55.679607 -303.000187) (xy 55.680102 -303.024794) (xy 56.01895 -303.024794)
			(xy 56.02291 -302.97574) (xy 56.034687 -302.927956) (xy 56.053978 -302.88268) (xy 56.080281 -302.841084)
			(xy 56.112916 -302.804247) (xy 56.151037 -302.773122) (xy 56.193658 -302.748515) (xy 56.239674 -302.731063)
			(xy 56.287893 -302.721219) (xy 56.337068 -302.719238) (xy 56.385923 -302.72517) (xy 56.433194 -302.738862)
			(xy 56.477656 -302.75996) (xy 56.518159 -302.787916) (xy 56.553652 -302.822008) (xy 56.583217 -302.861352)
			(xy 56.606088 -302.904929) (xy 56.621672 -302.95161) (xy 56.629567 -303.000187) (xy 56.630062 -303.024794)
			(xy 56.969164 -303.024794) (xy 56.973124 -302.97574) (xy 56.984901 -302.927956) (xy 57.004192 -302.88268)
			(xy 57.030495 -302.841084) (xy 57.06313 -302.804247) (xy 57.101251 -302.773122) (xy 57.143872 -302.748515)
			(xy 57.189888 -302.731063) (xy 57.238107 -302.721219) (xy 57.287282 -302.719238) (xy 57.336137 -302.72517)
			(xy 57.383408 -302.738862) (xy 57.42787 -302.75996) (xy 57.468373 -302.787916) (xy 57.503866 -302.822008)
			(xy 57.533431 -302.861352) (xy 57.556302 -302.904929) (xy 57.571886 -302.95161) (xy 57.579781 -303.000187)
			(xy 57.580276 -303.024794) (xy 57.919124 -303.024794) (xy 57.923084 -302.97574) (xy 57.934861 -302.927956)
			(xy 57.954152 -302.88268) (xy 57.980455 -302.841084) (xy 58.01309 -302.804247) (xy 58.051211 -302.773122)
			(xy 58.093832 -302.748515) (xy 58.139848 -302.731063) (xy 58.188067 -302.721219) (xy 58.237242 -302.719238)
			(xy 58.286097 -302.72517) (xy 58.333368 -302.738862) (xy 58.37783 -302.75996) (xy 58.418333 -302.787916)
			(xy 58.453826 -302.822008) (xy 58.483391 -302.861352) (xy 58.506262 -302.904929) (xy 58.521846 -302.95161)
			(xy 58.529741 -303.000187) (xy 58.530236 -303.024794) (xy 59.819044 -303.024794) (xy 59.823004 -302.97574)
			(xy 59.834781 -302.927956) (xy 59.854072 -302.88268) (xy 59.880375 -302.841084) (xy 59.91301 -302.804247)
			(xy 59.951131 -302.773122) (xy 59.993752 -302.748515) (xy 60.039768 -302.731063) (xy 60.087987 -302.721219)
			(xy 60.137162 -302.719238) (xy 60.186017 -302.72517) (xy 60.233288 -302.738862) (xy 60.27775 -302.75996)
			(xy 60.318253 -302.787916) (xy 60.353746 -302.822008) (xy 60.383311 -302.861352) (xy 60.406182 -302.904929)
			(xy 60.421766 -302.95161) (xy 60.429661 -303.000187) (xy 60.430156 -303.024794) (xy 60.769004 -303.024794)
			(xy 60.772964 -302.97574) (xy 60.784741 -302.927956) (xy 60.804032 -302.88268) (xy 60.830335 -302.841084)
			(xy 60.86297 -302.804247) (xy 60.901091 -302.773122) (xy 60.943712 -302.748515) (xy 60.989728 -302.731063)
			(xy 61.037947 -302.721219) (xy 61.087122 -302.719238) (xy 61.135977 -302.72517) (xy 61.183248 -302.738862)
			(xy 61.22771 -302.75996) (xy 61.268213 -302.787916) (xy 61.303706 -302.822008) (xy 61.333271 -302.861352)
			(xy 61.356142 -302.904929) (xy 61.371726 -302.95161) (xy 61.379621 -303.000187) (xy 61.380116 -303.024794)
			(xy 61.718964 -303.024794) (xy 61.722924 -302.97574) (xy 61.734701 -302.927956) (xy 61.753992 -302.88268)
			(xy 61.780295 -302.841084) (xy 61.81293 -302.804247) (xy 61.851051 -302.773122) (xy 61.893672 -302.748515)
			(xy 61.939688 -302.731063) (xy 61.987907 -302.721219) (xy 62.037082 -302.719238) (xy 62.085937 -302.72517)
			(xy 62.133208 -302.738862) (xy 62.17767 -302.75996) (xy 62.218173 -302.787916) (xy 62.253666 -302.822008)
			(xy 62.283231 -302.861352) (xy 62.306102 -302.904929) (xy 62.321686 -302.95161) (xy 62.329581 -303.000187)
			(xy 62.330076 -303.024794) (xy 62.669178 -303.024794) (xy 62.673138 -302.97574) (xy 62.684915 -302.927956)
			(xy 62.704206 -302.88268) (xy 62.730509 -302.841084) (xy 62.763144 -302.804247) (xy 62.801265 -302.773122)
			(xy 62.843886 -302.748515) (xy 62.889902 -302.731063) (xy 62.938121 -302.721219) (xy 62.987296 -302.719238)
			(xy 63.036151 -302.72517) (xy 63.083422 -302.738862) (xy 63.127884 -302.75996) (xy 63.168387 -302.787916)
			(xy 63.20388 -302.822008) (xy 63.233445 -302.861352) (xy 63.256316 -302.904929) (xy 63.2719 -302.95161)
			(xy 63.279795 -303.000187) (xy 63.28029 -303.024794) (xy 63.619138 -303.024794) (xy 63.623098 -302.97574)
			(xy 63.634875 -302.927956) (xy 63.654166 -302.88268) (xy 63.680469 -302.841084) (xy 63.713104 -302.804247)
			(xy 63.751225 -302.773122) (xy 63.793846 -302.748515) (xy 63.839862 -302.731063) (xy 63.888081 -302.721219)
			(xy 63.937256 -302.719238) (xy 63.986111 -302.72517) (xy 64.033382 -302.738862) (xy 64.077844 -302.75996)
			(xy 64.118347 -302.787916) (xy 64.15384 -302.822008) (xy 64.183405 -302.861352) (xy 64.206276 -302.904929)
			(xy 64.22186 -302.95161) (xy 64.229755 -303.000187) (xy 64.23025 -303.024794) (xy 64.569098 -303.024794)
			(xy 64.573058 -302.97574) (xy 64.584835 -302.927956) (xy 64.604126 -302.88268) (xy 64.630429 -302.841084)
			(xy 64.663064 -302.804247) (xy 64.701185 -302.773122) (xy 64.743806 -302.748515) (xy 64.789822 -302.731063)
			(xy 64.838041 -302.721219) (xy 64.887216 -302.719238) (xy 64.936071 -302.72517) (xy 64.983342 -302.738862)
			(xy 65.027804 -302.75996) (xy 65.068307 -302.787916) (xy 65.1038 -302.822008) (xy 65.133365 -302.861352)
			(xy 65.156236 -302.904929) (xy 65.17182 -302.95161) (xy 65.179715 -303.000187) (xy 65.18021 -303.024794)
			(xy 65.519058 -303.024794) (xy 65.523018 -302.97574) (xy 65.534795 -302.927956) (xy 65.554086 -302.88268)
			(xy 65.580389 -302.841084) (xy 65.613024 -302.804247) (xy 65.651145 -302.773122) (xy 65.693766 -302.748515)
			(xy 65.739782 -302.731063) (xy 65.788001 -302.721219) (xy 65.837176 -302.719238) (xy 65.886031 -302.72517)
			(xy 65.933302 -302.738862) (xy 65.977764 -302.75996) (xy 66.018267 -302.787916) (xy 66.05376 -302.822008)
			(xy 66.083325 -302.861352) (xy 66.106196 -302.904929) (xy 66.12178 -302.95161) (xy 66.129675 -303.000187)
			(xy 66.13017 -303.024794) (xy 66.469018 -303.024794) (xy 66.472978 -302.97574) (xy 66.484755 -302.927956)
			(xy 66.504046 -302.88268) (xy 66.530349 -302.841084) (xy 66.562984 -302.804247) (xy 66.601105 -302.773122)
			(xy 66.643726 -302.748515) (xy 66.689742 -302.731063) (xy 66.737961 -302.721219) (xy 66.787136 -302.719238)
			(xy 66.835991 -302.72517) (xy 66.883262 -302.738862) (xy 66.927724 -302.75996) (xy 66.968227 -302.787916)
			(xy 67.00372 -302.822008) (xy 67.033285 -302.861352) (xy 67.056156 -302.904929) (xy 67.07174 -302.95161)
			(xy 67.079635 -303.000187) (xy 67.08013 -303.024794) (xy 67.418978 -303.024794) (xy 67.422938 -302.97574)
			(xy 67.434715 -302.927956) (xy 67.454006 -302.88268) (xy 67.480309 -302.841084) (xy 67.512944 -302.804247)
			(xy 67.551065 -302.773122) (xy 67.593686 -302.748515) (xy 67.639702 -302.731063) (xy 67.687921 -302.721219)
			(xy 67.737096 -302.719238) (xy 67.785951 -302.72517) (xy 67.833222 -302.738862) (xy 67.877684 -302.75996)
			(xy 67.918187 -302.787916) (xy 67.95368 -302.822008) (xy 67.983245 -302.861352) (xy 68.006116 -302.904929)
			(xy 68.0217 -302.95161) (xy 68.029595 -303.000187) (xy 68.03009 -303.024794) (xy 68.368938 -303.024794)
			(xy 68.372898 -302.97574) (xy 68.384675 -302.927956) (xy 68.403966 -302.88268) (xy 68.430269 -302.841084)
			(xy 68.462904 -302.804247) (xy 68.501025 -302.773122) (xy 68.543646 -302.748515) (xy 68.589662 -302.731063)
			(xy 68.637881 -302.721219) (xy 68.687056 -302.719238) (xy 68.735911 -302.72517) (xy 68.783182 -302.738862)
			(xy 68.827644 -302.75996) (xy 68.868147 -302.787916) (xy 68.90364 -302.822008) (xy 68.933205 -302.861352)
			(xy 68.956076 -302.904929) (xy 68.97166 -302.95161) (xy 68.979555 -303.000187) (xy 68.98005 -303.024794)
			(xy 69.319152 -303.024794) (xy 69.323112 -302.97574) (xy 69.334889 -302.927956) (xy 69.35418 -302.88268)
			(xy 69.380483 -302.841084) (xy 69.413118 -302.804247) (xy 69.451239 -302.773122) (xy 69.49386 -302.748515)
			(xy 69.539876 -302.731063) (xy 69.588095 -302.721219) (xy 69.63727 -302.719238) (xy 69.686125 -302.72517)
			(xy 69.733396 -302.738862) (xy 69.777858 -302.75996) (xy 69.818361 -302.787916) (xy 69.853854 -302.822008)
			(xy 69.883419 -302.861352) (xy 69.90629 -302.904929) (xy 69.921874 -302.95161) (xy 69.929769 -303.000187)
			(xy 69.930264 -303.024794) (xy 70.269112 -303.024794) (xy 70.273072 -302.97574) (xy 70.284849 -302.927956)
			(xy 70.30414 -302.88268) (xy 70.330443 -302.841084) (xy 70.363078 -302.804247) (xy 70.401199 -302.773122)
			(xy 70.44382 -302.748515) (xy 70.489836 -302.731063) (xy 70.538055 -302.721219) (xy 70.58723 -302.719238)
			(xy 70.636085 -302.72517) (xy 70.683356 -302.738862) (xy 70.727818 -302.75996) (xy 70.768321 -302.787916)
			(xy 70.803814 -302.822008) (xy 70.833379 -302.861352) (xy 70.85625 -302.904929) (xy 70.871834 -302.95161)
			(xy 70.879729 -303.000187) (xy 70.880224 -303.024794) (xy 71.219072 -303.024794) (xy 71.223032 -302.97574)
			(xy 71.234809 -302.927956) (xy 71.2541 -302.88268) (xy 71.280403 -302.841084) (xy 71.313038 -302.804247)
			(xy 71.351159 -302.773122) (xy 71.39378 -302.748515) (xy 71.439796 -302.731063) (xy 71.488015 -302.721219)
			(xy 71.53719 -302.719238) (xy 71.586045 -302.72517) (xy 71.633316 -302.738862) (xy 71.677778 -302.75996)
			(xy 71.718281 -302.787916) (xy 71.753774 -302.822008) (xy 71.783339 -302.861352) (xy 71.80621 -302.904929)
			(xy 71.821794 -302.95161) (xy 71.829689 -303.000187) (xy 71.830184 -303.024794) (xy 72.169032 -303.024794)
			(xy 72.172992 -302.97574) (xy 72.184769 -302.927956) (xy 72.20406 -302.88268) (xy 72.230363 -302.841084)
			(xy 72.262998 -302.804247) (xy 72.301119 -302.773122) (xy 72.34374 -302.748515) (xy 72.389756 -302.731063)
			(xy 72.437975 -302.721219) (xy 72.48715 -302.719238) (xy 72.536005 -302.72517) (xy 72.583276 -302.738862)
			(xy 72.627738 -302.75996) (xy 72.668241 -302.787916) (xy 72.703734 -302.822008) (xy 72.733299 -302.861352)
			(xy 72.75617 -302.904929) (xy 72.771754 -302.95161) (xy 72.779649 -303.000187) (xy 72.780144 -303.024794)
			(xy 76.919086 -303.024794) (xy 76.923046 -302.97574) (xy 76.934823 -302.927956) (xy 76.954114 -302.88268)
			(xy 76.980417 -302.841084) (xy 77.013052 -302.804247) (xy 77.051173 -302.773122) (xy 77.093794 -302.748515)
			(xy 77.13981 -302.731063) (xy 77.188029 -302.721219) (xy 77.237204 -302.719238) (xy 77.286059 -302.72517)
			(xy 77.33333 -302.738862) (xy 77.377792 -302.75996) (xy 77.418295 -302.787916) (xy 77.453788 -302.822008)
			(xy 77.483353 -302.861352) (xy 77.506224 -302.904929) (xy 77.521808 -302.95161) (xy 77.529703 -303.000187)
			(xy 77.530198 -303.024794) (xy 77.869046 -303.024794) (xy 77.873006 -302.97574) (xy 77.884783 -302.927956)
			(xy 77.904074 -302.88268) (xy 77.930377 -302.841084) (xy 77.963012 -302.804247) (xy 78.001133 -302.773122)
			(xy 78.043754 -302.748515) (xy 78.08977 -302.731063) (xy 78.137989 -302.721219) (xy 78.187164 -302.719238)
			(xy 78.236019 -302.72517) (xy 78.28329 -302.738862) (xy 78.327752 -302.75996) (xy 78.368255 -302.787916)
			(xy 78.403748 -302.822008) (xy 78.433313 -302.861352) (xy 78.456184 -302.904929) (xy 78.471768 -302.95161)
			(xy 78.479663 -303.000187) (xy 78.480158 -303.024794) (xy 78.819006 -303.024794) (xy 78.822966 -302.97574)
			(xy 78.834743 -302.927956) (xy 78.854034 -302.88268) (xy 78.880337 -302.841084) (xy 78.912972 -302.804247)
			(xy 78.951093 -302.773122) (xy 78.993714 -302.748515) (xy 79.03973 -302.731063) (xy 79.087949 -302.721219)
			(xy 79.137124 -302.719238) (xy 79.185979 -302.72517) (xy 79.23325 -302.738862) (xy 79.277712 -302.75996)
			(xy 79.318215 -302.787916) (xy 79.353708 -302.822008) (xy 79.383273 -302.861352) (xy 79.406144 -302.904929)
			(xy 79.421728 -302.95161) (xy 79.429623 -303.000187) (xy 79.430118 -303.024794) (xy 79.768966 -303.024794)
			(xy 79.772926 -302.97574) (xy 79.784703 -302.927956) (xy 79.803994 -302.88268) (xy 79.830297 -302.841084)
			(xy 79.862932 -302.804247) (xy 79.901053 -302.773122) (xy 79.943674 -302.748515) (xy 79.98969 -302.731063)
			(xy 80.037909 -302.721219) (xy 80.087084 -302.719238) (xy 80.135939 -302.72517) (xy 80.18321 -302.738862)
			(xy 80.227672 -302.75996) (xy 80.268175 -302.787916) (xy 80.303668 -302.822008) (xy 80.333233 -302.861352)
			(xy 80.356104 -302.904929) (xy 80.371688 -302.95161) (xy 80.379583 -303.000187) (xy 80.380078 -303.024794)
			(xy 80.71918 -303.024794) (xy 80.72314 -302.97574) (xy 80.734917 -302.927956) (xy 80.754208 -302.88268)
			(xy 80.780511 -302.841084) (xy 80.813146 -302.804247) (xy 80.851267 -302.773122) (xy 80.893888 -302.748515)
			(xy 80.939904 -302.731063) (xy 80.988123 -302.721219) (xy 81.037298 -302.719238) (xy 81.086153 -302.72517)
			(xy 81.133424 -302.738862) (xy 81.177886 -302.75996) (xy 81.218389 -302.787916) (xy 81.253882 -302.822008)
			(xy 81.283447 -302.861352) (xy 81.306318 -302.904929) (xy 81.321902 -302.95161) (xy 81.329797 -303.000187)
			(xy 81.330292 -303.024794) (xy 81.66914 -303.024794) (xy 81.6731 -302.97574) (xy 81.684877 -302.927956)
			(xy 81.704168 -302.88268) (xy 81.730471 -302.841084) (xy 81.763106 -302.804247) (xy 81.801227 -302.773122)
			(xy 81.843848 -302.748515) (xy 81.889864 -302.731063) (xy 81.938083 -302.721219) (xy 81.987258 -302.719238)
			(xy 82.036113 -302.72517) (xy 82.083384 -302.738862) (xy 82.127846 -302.75996) (xy 82.168349 -302.787916)
			(xy 82.203842 -302.822008) (xy 82.233407 -302.861352) (xy 82.256278 -302.904929) (xy 82.271862 -302.95161)
			(xy 82.279757 -303.000187) (xy 82.280252 -303.024794) (xy 82.60386 -303.024794) (xy 82.60782 -302.97574)
			(xy 82.619597 -302.927956) (xy 82.638888 -302.88268) (xy 82.665191 -302.841084) (xy 82.697826 -302.804247)
			(xy 82.735947 -302.773122) (xy 82.778568 -302.748515) (xy 82.824584 -302.731063) (xy 82.872803 -302.721219)
			(xy 82.921978 -302.719238) (xy 82.970833 -302.72517) (xy 83.018104 -302.738862) (xy 83.062566 -302.75996)
			(xy 83.103069 -302.787916) (xy 83.138562 -302.822008) (xy 83.168127 -302.861352) (xy 83.190998 -302.904929)
			(xy 83.206582 -302.95161) (xy 83.214477 -303.000187) (xy 83.214972 -303.024794) (xy 83.214477 -303.049401)
			(xy 83.206582 -303.097978) (xy 83.190998 -303.144659) (xy 83.168127 -303.188236) (xy 83.138562 -303.22758)
			(xy 83.103069 -303.261672) (xy 83.062566 -303.289628) (xy 83.018104 -303.310726) (xy 82.970833 -303.324418)
			(xy 82.921978 -303.33035) (xy 82.872803 -303.328369) (xy 82.824584 -303.318525) (xy 82.778568 -303.301073)
			(xy 82.735947 -303.276466) (xy 82.697826 -303.245341) (xy 82.665191 -303.208504) (xy 82.638888 -303.166908)
			(xy 82.619597 -303.121632) (xy 82.60782 -303.073848) (xy 82.60386 -303.024794) (xy 82.280252 -303.024794)
			(xy 82.279757 -303.049401) (xy 82.271862 -303.097978) (xy 82.256278 -303.144659) (xy 82.233407 -303.188236)
			(xy 82.203842 -303.22758) (xy 82.168349 -303.261672) (xy 82.127846 -303.289628) (xy 82.083384 -303.310726)
			(xy 82.036113 -303.324418) (xy 81.987258 -303.33035) (xy 81.938083 -303.328369) (xy 81.889864 -303.318525)
			(xy 81.843848 -303.301073) (xy 81.801227 -303.276466) (xy 81.763106 -303.245341) (xy 81.730471 -303.208504)
			(xy 81.704168 -303.166908) (xy 81.684877 -303.121632) (xy 81.6731 -303.073848) (xy 81.66914 -303.024794)
			(xy 81.330292 -303.024794) (xy 81.329797 -303.049401) (xy 81.321902 -303.097978) (xy 81.306318 -303.144659)
			(xy 81.283447 -303.188236) (xy 81.253882 -303.22758) (xy 81.218389 -303.261672) (xy 81.177886 -303.289628)
			(xy 81.133424 -303.310726) (xy 81.086153 -303.324418) (xy 81.037298 -303.33035) (xy 80.988123 -303.328369)
			(xy 80.939904 -303.318525) (xy 80.893888 -303.301073) (xy 80.851267 -303.276466) (xy 80.813146 -303.245341)
			(xy 80.780511 -303.208504) (xy 80.754208 -303.166908) (xy 80.734917 -303.121632) (xy 80.72314 -303.073848)
			(xy 80.71918 -303.024794) (xy 80.380078 -303.024794) (xy 80.379583 -303.049401) (xy 80.371688 -303.097978)
			(xy 80.356104 -303.144659) (xy 80.333233 -303.188236) (xy 80.303668 -303.22758) (xy 80.268175 -303.261672)
			(xy 80.227672 -303.289628) (xy 80.18321 -303.310726) (xy 80.135939 -303.324418) (xy 80.087084 -303.33035)
			(xy 80.037909 -303.328369) (xy 79.98969 -303.318525) (xy 79.943674 -303.301073) (xy 79.901053 -303.276466)
			(xy 79.862932 -303.245341) (xy 79.830297 -303.208504) (xy 79.803994 -303.166908) (xy 79.784703 -303.121632)
			(xy 79.772926 -303.073848) (xy 79.768966 -303.024794) (xy 79.430118 -303.024794) (xy 79.429623 -303.049401)
			(xy 79.421728 -303.097978) (xy 79.406144 -303.144659) (xy 79.383273 -303.188236) (xy 79.353708 -303.22758)
			(xy 79.318215 -303.261672) (xy 79.277712 -303.289628) (xy 79.23325 -303.310726) (xy 79.185979 -303.324418)
			(xy 79.137124 -303.33035) (xy 79.087949 -303.328369) (xy 79.03973 -303.318525) (xy 78.993714 -303.301073)
			(xy 78.951093 -303.276466) (xy 78.912972 -303.245341) (xy 78.880337 -303.208504) (xy 78.854034 -303.166908)
			(xy 78.834743 -303.121632) (xy 78.822966 -303.073848) (xy 78.819006 -303.024794) (xy 78.480158 -303.024794)
			(xy 78.479663 -303.049401) (xy 78.471768 -303.097978) (xy 78.456184 -303.144659) (xy 78.433313 -303.188236)
			(xy 78.403748 -303.22758) (xy 78.368255 -303.261672) (xy 78.327752 -303.289628) (xy 78.28329 -303.310726)
			(xy 78.236019 -303.324418) (xy 78.187164 -303.33035) (xy 78.137989 -303.328369) (xy 78.08977 -303.318525)
			(xy 78.043754 -303.301073) (xy 78.001133 -303.276466) (xy 77.963012 -303.245341) (xy 77.930377 -303.208504)
			(xy 77.904074 -303.166908) (xy 77.884783 -303.121632) (xy 77.873006 -303.073848) (xy 77.869046 -303.024794)
			(xy 77.530198 -303.024794) (xy 77.529703 -303.049401) (xy 77.521808 -303.097978) (xy 77.506224 -303.144659)
			(xy 77.483353 -303.188236) (xy 77.453788 -303.22758) (xy 77.418295 -303.261672) (xy 77.377792 -303.289628)
			(xy 77.33333 -303.310726) (xy 77.286059 -303.324418) (xy 77.237204 -303.33035) (xy 77.188029 -303.328369)
			(xy 77.13981 -303.318525) (xy 77.093794 -303.301073) (xy 77.051173 -303.276466) (xy 77.013052 -303.245341)
			(xy 76.980417 -303.208504) (xy 76.954114 -303.166908) (xy 76.934823 -303.121632) (xy 76.923046 -303.073848)
			(xy 76.919086 -303.024794) (xy 72.780144 -303.024794) (xy 72.779649 -303.049401) (xy 72.771754 -303.097978)
			(xy 72.75617 -303.144659) (xy 72.733299 -303.188236) (xy 72.703734 -303.22758) (xy 72.668241 -303.261672)
			(xy 72.627738 -303.289628) (xy 72.583276 -303.310726) (xy 72.536005 -303.324418) (xy 72.48715 -303.33035)
			(xy 72.437975 -303.328369) (xy 72.389756 -303.318525) (xy 72.34374 -303.301073) (xy 72.301119 -303.276466)
			(xy 72.262998 -303.245341) (xy 72.230363 -303.208504) (xy 72.20406 -303.166908) (xy 72.184769 -303.121632)
			(xy 72.172992 -303.073848) (xy 72.169032 -303.024794) (xy 71.830184 -303.024794) (xy 71.829689 -303.049401)
			(xy 71.821794 -303.097978) (xy 71.80621 -303.144659) (xy 71.783339 -303.188236) (xy 71.753774 -303.22758)
			(xy 71.718281 -303.261672) (xy 71.677778 -303.289628) (xy 71.633316 -303.310726) (xy 71.586045 -303.324418)
			(xy 71.53719 -303.33035) (xy 71.488015 -303.328369) (xy 71.439796 -303.318525) (xy 71.39378 -303.301073)
			(xy 71.351159 -303.276466) (xy 71.313038 -303.245341) (xy 71.280403 -303.208504) (xy 71.2541 -303.166908)
			(xy 71.234809 -303.121632) (xy 71.223032 -303.073848) (xy 71.219072 -303.024794) (xy 70.880224 -303.024794)
			(xy 70.879729 -303.049401) (xy 70.871834 -303.097978) (xy 70.85625 -303.144659) (xy 70.833379 -303.188236)
			(xy 70.803814 -303.22758) (xy 70.768321 -303.261672) (xy 70.727818 -303.289628) (xy 70.683356 -303.310726)
			(xy 70.636085 -303.324418) (xy 70.58723 -303.33035) (xy 70.538055 -303.328369) (xy 70.489836 -303.318525)
			(xy 70.44382 -303.301073) (xy 70.401199 -303.276466) (xy 70.363078 -303.245341) (xy 70.330443 -303.208504)
			(xy 70.30414 -303.166908) (xy 70.284849 -303.121632) (xy 70.273072 -303.073848) (xy 70.269112 -303.024794)
			(xy 69.930264 -303.024794) (xy 69.929769 -303.049401) (xy 69.921874 -303.097978) (xy 69.90629 -303.144659)
			(xy 69.883419 -303.188236) (xy 69.853854 -303.22758) (xy 69.818361 -303.261672) (xy 69.777858 -303.289628)
			(xy 69.733396 -303.310726) (xy 69.686125 -303.324418) (xy 69.63727 -303.33035) (xy 69.588095 -303.328369)
			(xy 69.539876 -303.318525) (xy 69.49386 -303.301073) (xy 69.451239 -303.276466) (xy 69.413118 -303.245341)
			(xy 69.380483 -303.208504) (xy 69.35418 -303.166908) (xy 69.334889 -303.121632) (xy 69.323112 -303.073848)
			(xy 69.319152 -303.024794) (xy 68.98005 -303.024794) (xy 68.979555 -303.049401) (xy 68.97166 -303.097978)
			(xy 68.956076 -303.144659) (xy 68.933205 -303.188236) (xy 68.90364 -303.22758) (xy 68.868147 -303.261672)
			(xy 68.827644 -303.289628) (xy 68.783182 -303.310726) (xy 68.735911 -303.324418) (xy 68.687056 -303.33035)
			(xy 68.637881 -303.328369) (xy 68.589662 -303.318525) (xy 68.543646 -303.301073) (xy 68.501025 -303.276466)
			(xy 68.462904 -303.245341) (xy 68.430269 -303.208504) (xy 68.403966 -303.166908) (xy 68.384675 -303.121632)
			(xy 68.372898 -303.073848) (xy 68.368938 -303.024794) (xy 68.03009 -303.024794) (xy 68.029595 -303.049401)
			(xy 68.0217 -303.097978) (xy 68.006116 -303.144659) (xy 67.983245 -303.188236) (xy 67.95368 -303.22758)
			(xy 67.918187 -303.261672) (xy 67.877684 -303.289628) (xy 67.833222 -303.310726) (xy 67.785951 -303.324418)
			(xy 67.737096 -303.33035) (xy 67.687921 -303.328369) (xy 67.639702 -303.318525) (xy 67.593686 -303.301073)
			(xy 67.551065 -303.276466) (xy 67.512944 -303.245341) (xy 67.480309 -303.208504) (xy 67.454006 -303.166908)
			(xy 67.434715 -303.121632) (xy 67.422938 -303.073848) (xy 67.418978 -303.024794) (xy 67.08013 -303.024794)
			(xy 67.079635 -303.049401) (xy 67.07174 -303.097978) (xy 67.056156 -303.144659) (xy 67.033285 -303.188236)
			(xy 67.00372 -303.22758) (xy 66.968227 -303.261672) (xy 66.927724 -303.289628) (xy 66.883262 -303.310726)
			(xy 66.835991 -303.324418) (xy 66.787136 -303.33035) (xy 66.737961 -303.328369) (xy 66.689742 -303.318525)
			(xy 66.643726 -303.301073) (xy 66.601105 -303.276466) (xy 66.562984 -303.245341) (xy 66.530349 -303.208504)
			(xy 66.504046 -303.166908) (xy 66.484755 -303.121632) (xy 66.472978 -303.073848) (xy 66.469018 -303.024794)
			(xy 66.13017 -303.024794) (xy 66.129675 -303.049401) (xy 66.12178 -303.097978) (xy 66.106196 -303.144659)
			(xy 66.083325 -303.188236) (xy 66.05376 -303.22758) (xy 66.018267 -303.261672) (xy 65.977764 -303.289628)
			(xy 65.933302 -303.310726) (xy 65.886031 -303.324418) (xy 65.837176 -303.33035) (xy 65.788001 -303.328369)
			(xy 65.739782 -303.318525) (xy 65.693766 -303.301073) (xy 65.651145 -303.276466) (xy 65.613024 -303.245341)
			(xy 65.580389 -303.208504) (xy 65.554086 -303.166908) (xy 65.534795 -303.121632) (xy 65.523018 -303.073848)
			(xy 65.519058 -303.024794) (xy 65.18021 -303.024794) (xy 65.179715 -303.049401) (xy 65.17182 -303.097978)
			(xy 65.156236 -303.144659) (xy 65.133365 -303.188236) (xy 65.1038 -303.22758) (xy 65.068307 -303.261672)
			(xy 65.027804 -303.289628) (xy 64.983342 -303.310726) (xy 64.936071 -303.324418) (xy 64.887216 -303.33035)
			(xy 64.838041 -303.328369) (xy 64.789822 -303.318525) (xy 64.743806 -303.301073) (xy 64.701185 -303.276466)
			(xy 64.663064 -303.245341) (xy 64.630429 -303.208504) (xy 64.604126 -303.166908) (xy 64.584835 -303.121632)
			(xy 64.573058 -303.073848) (xy 64.569098 -303.024794) (xy 64.23025 -303.024794) (xy 64.229755 -303.049401)
			(xy 64.22186 -303.097978) (xy 64.206276 -303.144659) (xy 64.183405 -303.188236) (xy 64.15384 -303.22758)
			(xy 64.118347 -303.261672) (xy 64.077844 -303.289628) (xy 64.033382 -303.310726) (xy 63.986111 -303.324418)
			(xy 63.937256 -303.33035) (xy 63.888081 -303.328369) (xy 63.839862 -303.318525) (xy 63.793846 -303.301073)
			(xy 63.751225 -303.276466) (xy 63.713104 -303.245341) (xy 63.680469 -303.208504) (xy 63.654166 -303.166908)
			(xy 63.634875 -303.121632) (xy 63.623098 -303.073848) (xy 63.619138 -303.024794) (xy 63.28029 -303.024794)
			(xy 63.279795 -303.049401) (xy 63.2719 -303.097978) (xy 63.256316 -303.144659) (xy 63.233445 -303.188236)
			(xy 63.20388 -303.22758) (xy 63.168387 -303.261672) (xy 63.127884 -303.289628) (xy 63.083422 -303.310726)
			(xy 63.036151 -303.324418) (xy 62.987296 -303.33035) (xy 62.938121 -303.328369) (xy 62.889902 -303.318525)
			(xy 62.843886 -303.301073) (xy 62.801265 -303.276466) (xy 62.763144 -303.245341) (xy 62.730509 -303.208504)
			(xy 62.704206 -303.166908) (xy 62.684915 -303.121632) (xy 62.673138 -303.073848) (xy 62.669178 -303.024794)
			(xy 62.330076 -303.024794) (xy 62.329581 -303.049401) (xy 62.321686 -303.097978) (xy 62.306102 -303.144659)
			(xy 62.283231 -303.188236) (xy 62.253666 -303.22758) (xy 62.218173 -303.261672) (xy 62.17767 -303.289628)
			(xy 62.133208 -303.310726) (xy 62.085937 -303.324418) (xy 62.037082 -303.33035) (xy 61.987907 -303.328369)
			(xy 61.939688 -303.318525) (xy 61.893672 -303.301073) (xy 61.851051 -303.276466) (xy 61.81293 -303.245341)
			(xy 61.780295 -303.208504) (xy 61.753992 -303.166908) (xy 61.734701 -303.121632) (xy 61.722924 -303.073848)
			(xy 61.718964 -303.024794) (xy 61.380116 -303.024794) (xy 61.379621 -303.049401) (xy 61.371726 -303.097978)
			(xy 61.356142 -303.144659) (xy 61.333271 -303.188236) (xy 61.303706 -303.22758) (xy 61.268213 -303.261672)
			(xy 61.22771 -303.289628) (xy 61.183248 -303.310726) (xy 61.135977 -303.324418) (xy 61.087122 -303.33035)
			(xy 61.037947 -303.328369) (xy 60.989728 -303.318525) (xy 60.943712 -303.301073) (xy 60.901091 -303.276466)
			(xy 60.86297 -303.245341) (xy 60.830335 -303.208504) (xy 60.804032 -303.166908) (xy 60.784741 -303.121632)
			(xy 60.772964 -303.073848) (xy 60.769004 -303.024794) (xy 60.430156 -303.024794) (xy 60.429661 -303.049401)
			(xy 60.421766 -303.097978) (xy 60.406182 -303.144659) (xy 60.383311 -303.188236) (xy 60.353746 -303.22758)
			(xy 60.318253 -303.261672) (xy 60.27775 -303.289628) (xy 60.233288 -303.310726) (xy 60.186017 -303.324418)
			(xy 60.137162 -303.33035) (xy 60.087987 -303.328369) (xy 60.039768 -303.318525) (xy 59.993752 -303.301073)
			(xy 59.951131 -303.276466) (xy 59.91301 -303.245341) (xy 59.880375 -303.208504) (xy 59.854072 -303.166908)
			(xy 59.834781 -303.121632) (xy 59.823004 -303.073848) (xy 59.819044 -303.024794) (xy 58.530236 -303.024794)
			(xy 58.529741 -303.049401) (xy 58.521846 -303.097978) (xy 58.506262 -303.144659) (xy 58.483391 -303.188236)
			(xy 58.453826 -303.22758) (xy 58.418333 -303.261672) (xy 58.37783 -303.289628) (xy 58.333368 -303.310726)
			(xy 58.286097 -303.324418) (xy 58.237242 -303.33035) (xy 58.188067 -303.328369) (xy 58.139848 -303.318525)
			(xy 58.093832 -303.301073) (xy 58.051211 -303.276466) (xy 58.01309 -303.245341) (xy 57.980455 -303.208504)
			(xy 57.954152 -303.166908) (xy 57.934861 -303.121632) (xy 57.923084 -303.073848) (xy 57.919124 -303.024794)
			(xy 57.580276 -303.024794) (xy 57.579781 -303.049401) (xy 57.571886 -303.097978) (xy 57.556302 -303.144659)
			(xy 57.533431 -303.188236) (xy 57.503866 -303.22758) (xy 57.468373 -303.261672) (xy 57.42787 -303.289628)
			(xy 57.383408 -303.310726) (xy 57.336137 -303.324418) (xy 57.287282 -303.33035) (xy 57.238107 -303.328369)
			(xy 57.189888 -303.318525) (xy 57.143872 -303.301073) (xy 57.101251 -303.276466) (xy 57.06313 -303.245341)
			(xy 57.030495 -303.208504) (xy 57.004192 -303.166908) (xy 56.984901 -303.121632) (xy 56.973124 -303.073848)
			(xy 56.969164 -303.024794) (xy 56.630062 -303.024794) (xy 56.629567 -303.049401) (xy 56.621672 -303.097978)
			(xy 56.606088 -303.144659) (xy 56.583217 -303.188236) (xy 56.553652 -303.22758) (xy 56.518159 -303.261672)
			(xy 56.477656 -303.289628) (xy 56.433194 -303.310726) (xy 56.385923 -303.324418) (xy 56.337068 -303.33035)
			(xy 56.287893 -303.328369) (xy 56.239674 -303.318525) (xy 56.193658 -303.301073) (xy 56.151037 -303.276466)
			(xy 56.112916 -303.245341) (xy 56.080281 -303.208504) (xy 56.053978 -303.166908) (xy 56.034687 -303.121632)
			(xy 56.02291 -303.073848) (xy 56.01895 -303.024794) (xy 55.680102 -303.024794) (xy 55.679607 -303.049401)
			(xy 55.671712 -303.097978) (xy 55.656128 -303.144659) (xy 55.633257 -303.188236) (xy 55.603692 -303.22758)
			(xy 55.568199 -303.261672) (xy 55.527696 -303.289628) (xy 55.483234 -303.310726) (xy 55.435963 -303.324418)
			(xy 55.387108 -303.33035) (xy 55.337933 -303.328369) (xy 55.289714 -303.318525) (xy 55.243698 -303.301073)
			(xy 55.201077 -303.276466) (xy 55.162956 -303.245341) (xy 55.130321 -303.208504) (xy 55.104018 -303.166908)
			(xy 55.084727 -303.121632) (xy 55.07295 -303.073848) (xy 55.06899 -303.024794) (xy 54.730142 -303.024794)
			(xy 54.729647 -303.049401) (xy 54.721752 -303.097978) (xy 54.706168 -303.144659) (xy 54.683297 -303.188236)
			(xy 54.653732 -303.22758) (xy 54.618239 -303.261672) (xy 54.577736 -303.289628) (xy 54.533274 -303.310726)
			(xy 54.486003 -303.324418) (xy 54.437148 -303.33035) (xy 54.387973 -303.328369) (xy 54.339754 -303.318525)
			(xy 54.293738 -303.301073) (xy 54.251117 -303.276466) (xy 54.212996 -303.245341) (xy 54.180361 -303.208504)
			(xy 54.154058 -303.166908) (xy 54.134767 -303.121632) (xy 54.12299 -303.073848) (xy 54.11903 -303.024794)
			(xy 53.780182 -303.024794) (xy 53.779687 -303.049401) (xy 53.771792 -303.097978) (xy 53.756208 -303.144659)
			(xy 53.733337 -303.188236) (xy 53.703772 -303.22758) (xy 53.668279 -303.261672) (xy 53.627776 -303.289628)
			(xy 53.583314 -303.310726) (xy 53.536043 -303.324418) (xy 53.487188 -303.33035) (xy 53.438013 -303.328369)
			(xy 53.389794 -303.318525) (xy 53.343778 -303.301073) (xy 53.301157 -303.276466) (xy 53.263036 -303.245341)
			(xy 53.230401 -303.208504) (xy 53.204098 -303.166908) (xy 53.184807 -303.121632) (xy 53.17303 -303.073848)
			(xy 53.16907 -303.024794) (xy 52.830222 -303.024794) (xy 52.829727 -303.049401) (xy 52.821832 -303.097978)
			(xy 52.806248 -303.144659) (xy 52.783377 -303.188236) (xy 52.753812 -303.22758) (xy 52.718319 -303.261672)
			(xy 52.677816 -303.289628) (xy 52.633354 -303.310726) (xy 52.586083 -303.324418) (xy 52.537228 -303.33035)
			(xy 52.488053 -303.328369) (xy 52.439834 -303.318525) (xy 52.393818 -303.301073) (xy 52.351197 -303.276466)
			(xy 52.313076 -303.245341) (xy 52.280441 -303.208504) (xy 52.254138 -303.166908) (xy 52.234847 -303.121632)
			(xy 52.22307 -303.073848) (xy 52.21911 -303.024794) (xy 51.880262 -303.024794) (xy 51.879767 -303.049401)
			(xy 51.871872 -303.097978) (xy 51.856288 -303.144659) (xy 51.833417 -303.188236) (xy 51.803852 -303.22758)
			(xy 51.768359 -303.261672) (xy 51.727856 -303.289628) (xy 51.683394 -303.310726) (xy 51.636123 -303.324418)
			(xy 51.587268 -303.33035) (xy 51.538093 -303.328369) (xy 51.489874 -303.318525) (xy 51.443858 -303.301073)
			(xy 51.401237 -303.276466) (xy 51.363116 -303.245341) (xy 51.330481 -303.208504) (xy 51.304178 -303.166908)
			(xy 51.284887 -303.121632) (xy 51.27311 -303.073848) (xy 51.26915 -303.024794) (xy 50.930302 -303.024794)
			(xy 50.929807 -303.049401) (xy 50.921912 -303.097978) (xy 50.906328 -303.144659) (xy 50.883457 -303.188236)
			(xy 50.853892 -303.22758) (xy 50.818399 -303.261672) (xy 50.777896 -303.289628) (xy 50.733434 -303.310726)
			(xy 50.686163 -303.324418) (xy 50.637308 -303.33035) (xy 50.588133 -303.328369) (xy 50.539914 -303.318525)
			(xy 50.493898 -303.301073) (xy 50.451277 -303.276466) (xy 50.413156 -303.245341) (xy 50.380521 -303.208504)
			(xy 50.354218 -303.166908) (xy 50.334927 -303.121632) (xy 50.32315 -303.073848) (xy 50.31919 -303.024794)
			(xy 49.980088 -303.024794) (xy 49.979593 -303.049401) (xy 49.971698 -303.097978) (xy 49.956114 -303.144659)
			(xy 49.933243 -303.188236) (xy 49.903678 -303.22758) (xy 49.868185 -303.261672) (xy 49.827682 -303.289628)
			(xy 49.78322 -303.310726) (xy 49.735949 -303.324418) (xy 49.687094 -303.33035) (xy 49.637919 -303.328369)
			(xy 49.5897 -303.318525) (xy 49.543684 -303.301073) (xy 49.501063 -303.276466) (xy 49.462942 -303.245341)
			(xy 49.430307 -303.208504) (xy 49.404004 -303.166908) (xy 49.384713 -303.121632) (xy 49.372936 -303.073848)
			(xy 49.368976 -303.024794) (xy 49.030128 -303.024794) (xy 49.029633 -303.049401) (xy 49.021738 -303.097978)
			(xy 49.006154 -303.144659) (xy 48.983283 -303.188236) (xy 48.953718 -303.22758) (xy 48.918225 -303.261672)
			(xy 48.877722 -303.289628) (xy 48.83326 -303.310726) (xy 48.785989 -303.324418) (xy 48.737134 -303.33035)
			(xy 48.687959 -303.328369) (xy 48.63974 -303.318525) (xy 48.593724 -303.301073) (xy 48.551103 -303.276466)
			(xy 48.512982 -303.245341) (xy 48.480347 -303.208504) (xy 48.454044 -303.166908) (xy 48.434753 -303.121632)
			(xy 48.422976 -303.073848) (xy 48.419016 -303.024794) (xy 48.080168 -303.024794) (xy 48.079673 -303.049401)
			(xy 48.071778 -303.097978) (xy 48.056194 -303.144659) (xy 48.033323 -303.188236) (xy 48.003758 -303.22758)
			(xy 47.968265 -303.261672) (xy 47.927762 -303.289628) (xy 47.8833 -303.310726) (xy 47.836029 -303.324418)
			(xy 47.787174 -303.33035) (xy 47.737999 -303.328369) (xy 47.68978 -303.318525) (xy 47.643764 -303.301073)
			(xy 47.601143 -303.276466) (xy 47.563022 -303.245341) (xy 47.530387 -303.208504) (xy 47.504084 -303.166908)
			(xy 47.484793 -303.121632) (xy 47.473016 -303.073848) (xy 47.469056 -303.024794) (xy 47.13017 -303.024794)
			(xy 47.127931 -303.066089) (xy 47.117259 -303.114571) (xy 47.098884 -303.160687) (xy 47.073291 -303.203222)
			(xy 47.041153 -303.241057) (xy 47.003318 -303.273194) (xy 46.960781 -303.298787) (xy 46.914665 -303.317161)
			(xy 46.866183 -303.327832) (xy 46.816614 -303.330519) (xy 46.767263 -303.325151) (xy 46.719431 -303.31187)
			(xy 46.674378 -303.291025) (xy 46.63329 -303.263166) (xy 46.597251 -303.229026) (xy 46.567209 -303.189506)
			(xy 46.543958 -303.145647) (xy 46.528108 -303.098603) (xy 46.520077 -303.049615) (xy 46.519592 -303.024794)
			(xy 46.519768 -303.010611) (xy 46.52244 -302.982371) (xy 46.524926 -302.968406) (xy 46.527073 -302.954438)
			(xy 46.524495 -302.926309) (xy 46.514308 -302.899963) (xy 46.497291 -302.877417) (xy 46.474747 -302.860398)
			(xy 46.448402 -302.850207) (xy 46.420273 -302.847627) (xy 46.406308 -302.849788) (xy 46.392341 -302.852259)
			(xy 46.364102 -302.854935) (xy 46.34992 -302.855122) (xy 46.325097 -302.854644) (xy 46.276104 -302.846615)
			(xy 46.229056 -302.830765) (xy 46.185192 -302.807513) (xy 46.145667 -302.777471) (xy 46.111524 -302.741429)
			(xy 46.083662 -302.700339) (xy 46.062814 -302.655282) (xy 46.049531 -302.607446) (xy 46.044161 -302.558091)
			(xy 45.705101 -302.558091) (xy 45.704773 -302.574421) (xy 45.696878 -302.622998) (xy 45.681294 -302.669679)
			(xy 45.658423 -302.713256) (xy 45.628858 -302.7526) (xy 45.593365 -302.786692) (xy 45.552862 -302.814648)
			(xy 45.5084 -302.835746) (xy 45.461129 -302.849438) (xy 45.412274 -302.85537) (xy 45.363099 -302.853389)
			(xy 45.31488 -302.843545) (xy 45.268864 -302.826093) (xy 45.226243 -302.801486) (xy 45.188122 -302.770361)
			(xy 45.155487 -302.733524) (xy 45.129184 -302.691928) (xy 45.109893 -302.646652) (xy 45.098116 -302.598868)
			(xy 45.094156 -302.549814) (xy 44.776898 -302.549814) (xy 44.776394 -302.575522) (xy 44.768351 -302.626304)
			(xy 44.752463 -302.675203) (xy 44.72912 -302.721015) (xy 44.698899 -302.762611) (xy 44.662543 -302.798967)
			(xy 44.620947 -302.829188) (xy 44.575135 -302.852531) (xy 44.526236 -302.868419) (xy 44.475454 -302.876462)
			(xy 44.424038 -302.876462) (xy 44.373256 -302.868419) (xy 44.324357 -302.852531) (xy 44.278545 -302.829188)
			(xy 44.236949 -302.798967) (xy 44.200593 -302.762611) (xy 44.170372 -302.721015) (xy 44.147029 -302.675203)
			(xy 44.131141 -302.626304) (xy 44.123098 -302.575522) (xy 43.826434 -302.575522) (xy 43.818391 -302.626304)
			(xy 43.802503 -302.675203) (xy 43.77916 -302.721015) (xy 43.748939 -302.762611) (xy 43.712583 -302.798967)
			(xy 43.670987 -302.829188) (xy 43.625175 -302.852531) (xy 43.576276 -302.868419) (xy 43.525494 -302.876462)
			(xy 43.474078 -302.876462) (xy 43.423296 -302.868419) (xy 43.374397 -302.852531) (xy 43.328585 -302.829188)
			(xy 43.286989 -302.798967) (xy 43.250633 -302.762611) (xy 43.220412 -302.721015) (xy 43.197069 -302.675203)
			(xy 43.181181 -302.626304) (xy 43.173138 -302.575522) (xy 42.85446 -302.575522) (xy 42.846744 -302.622998)
			(xy 42.83116 -302.669679) (xy 42.808289 -302.713256) (xy 42.778724 -302.7526) (xy 42.743231 -302.786692)
			(xy 42.702728 -302.814648) (xy 42.658266 -302.835746) (xy 42.610995 -302.849438) (xy 42.56214 -302.85537)
			(xy 42.512965 -302.853389) (xy 42.464746 -302.843545) (xy 42.41873 -302.826093) (xy 42.376109 -302.801486)
			(xy 42.337988 -302.770361) (xy 42.305353 -302.733524) (xy 42.27905 -302.691928) (xy 42.259759 -302.646652)
			(xy 42.247982 -302.598868) (xy 42.244022 -302.549814) (xy 41.905174 -302.549814) (xy 41.904679 -302.574421)
			(xy 41.896784 -302.622998) (xy 41.8812 -302.669679) (xy 41.858329 -302.713256) (xy 41.828764 -302.7526)
			(xy 41.793271 -302.786692) (xy 41.752768 -302.814648) (xy 41.708306 -302.835746) (xy 41.661035 -302.849438)
			(xy 41.61218 -302.85537) (xy 41.563005 -302.853389) (xy 41.514786 -302.843545) (xy 41.46877 -302.826093)
			(xy 41.426149 -302.801486) (xy 41.388028 -302.770361) (xy 41.355393 -302.733524) (xy 41.32909 -302.691928)
			(xy 41.309799 -302.646652) (xy 41.298022 -302.598868) (xy 41.294062 -302.549814) (xy 40.955214 -302.549814)
			(xy 40.954719 -302.574421) (xy 40.946824 -302.622998) (xy 40.93124 -302.669679) (xy 40.908369 -302.713256)
			(xy 40.878804 -302.7526) (xy 40.843311 -302.786692) (xy 40.802808 -302.814648) (xy 40.758346 -302.835746)
			(xy 40.711075 -302.849438) (xy 40.66222 -302.85537) (xy 40.613045 -302.853389) (xy 40.564826 -302.843545)
			(xy 40.51881 -302.826093) (xy 40.476189 -302.801486) (xy 40.438068 -302.770361) (xy 40.405433 -302.733524)
			(xy 40.37913 -302.691928) (xy 40.359839 -302.646652) (xy 40.348062 -302.598868) (xy 40.344102 -302.549814)
			(xy 40.005254 -302.549814) (xy 40.004759 -302.574421) (xy 39.996864 -302.622998) (xy 39.98128 -302.669679)
			(xy 39.958409 -302.713256) (xy 39.928844 -302.7526) (xy 39.893351 -302.786692) (xy 39.852848 -302.814648)
			(xy 39.808386 -302.835746) (xy 39.761115 -302.849438) (xy 39.71226 -302.85537) (xy 39.663085 -302.853389)
			(xy 39.614866 -302.843545) (xy 39.56885 -302.826093) (xy 39.526229 -302.801486) (xy 39.488108 -302.770361)
			(xy 39.455473 -302.733524) (xy 39.42917 -302.691928) (xy 39.409879 -302.646652) (xy 39.398102 -302.598868)
			(xy 39.394142 -302.549814) (xy 39.055294 -302.549814) (xy 39.054799 -302.574421) (xy 39.046904 -302.622998)
			(xy 39.03132 -302.669679) (xy 39.008449 -302.713256) (xy 38.978884 -302.7526) (xy 38.943391 -302.786692)
			(xy 38.902888 -302.814648) (xy 38.858426 -302.835746) (xy 38.811155 -302.849438) (xy 38.7623 -302.85537)
			(xy 38.713125 -302.853389) (xy 38.664906 -302.843545) (xy 38.61889 -302.826093) (xy 38.576269 -302.801486)
			(xy 38.538148 -302.770361) (xy 38.505513 -302.733524) (xy 38.47921 -302.691928) (xy 38.459919 -302.646652)
			(xy 38.448142 -302.598868) (xy 38.444182 -302.549814) (xy 38.126924 -302.549814) (xy 38.12642 -302.575522)
			(xy 38.118377 -302.626304) (xy 38.102489 -302.675203) (xy 38.079146 -302.721015) (xy 38.048925 -302.762611)
			(xy 38.012569 -302.798967) (xy 37.970973 -302.829188) (xy 37.925161 -302.852531) (xy 37.876262 -302.868419)
			(xy 37.82548 -302.876462) (xy 37.774064 -302.876462) (xy 37.723282 -302.868419) (xy 37.674383 -302.852531)
			(xy 37.628571 -302.829188) (xy 37.586975 -302.798967) (xy 37.550619 -302.762611) (xy 37.520398 -302.721015)
			(xy 37.497055 -302.675203) (xy 37.481167 -302.626304) (xy 37.473124 -302.575522) (xy 37.17646 -302.575522)
			(xy 37.168417 -302.626304) (xy 37.152529 -302.675203) (xy 37.129186 -302.721015) (xy 37.098965 -302.762611)
			(xy 37.062609 -302.798967) (xy 37.021013 -302.829188) (xy 36.975201 -302.852531) (xy 36.926302 -302.868419)
			(xy 36.87552 -302.876462) (xy 36.824104 -302.876462) (xy 36.773322 -302.868419) (xy 36.724423 -302.852531)
			(xy 36.678611 -302.829188) (xy 36.637015 -302.798967) (xy 36.600659 -302.762611) (xy 36.570438 -302.721015)
			(xy 36.547095 -302.675203) (xy 36.531207 -302.626304) (xy 36.523164 -302.575522) (xy 36.204273 -302.575522)
			(xy 36.196516 -302.623252) (xy 36.180932 -302.669933) (xy 36.158061 -302.71351) (xy 36.128496 -302.752854)
			(xy 36.093003 -302.786946) (xy 36.0525 -302.814902) (xy 36.008038 -302.836) (xy 35.960767 -302.849692)
			(xy 35.911912 -302.855624) (xy 35.862737 -302.853643) (xy 35.814518 -302.843799) (xy 35.768502 -302.826347)
			(xy 35.725881 -302.80174) (xy 35.68776 -302.770615) (xy 35.655125 -302.733778) (xy 35.628822 -302.692182)
			(xy 35.609531 -302.646906) (xy 35.597754 -302.599122) (xy 35.593794 -302.550068) (xy 23.347047 -302.550068)
			(xy 23.293922 -302.690148) (xy 23.228408 -302.840543) (xy 23.155705 -302.987597) (xy 23.075981 -303.130967)
			(xy 22.989425 -303.270318) (xy 22.896237 -303.405325) (xy 22.824065 -303.499774) (xy 36.544008 -303.499774)
			(xy 36.547968 -303.45072) (xy 36.559745 -303.402936) (xy 36.579036 -303.35766) (xy 36.605339 -303.316064)
			(xy 36.637974 -303.279227) (xy 36.676095 -303.248102) (xy 36.718716 -303.223495) (xy 36.764732 -303.206043)
			(xy 36.812951 -303.196199) (xy 36.862126 -303.194218) (xy 36.910981 -303.20015) (xy 36.958252 -303.213842)
			(xy 37.002714 -303.23494) (xy 37.043217 -303.262896) (xy 37.07871 -303.296988) (xy 37.108275 -303.336332)
			(xy 37.131146 -303.379909) (xy 37.14673 -303.42659) (xy 37.154625 -303.475167) (xy 37.15512 -303.499774)
			(xy 37.493968 -303.499774) (xy 37.497928 -303.45072) (xy 37.509705 -303.402936) (xy 37.528996 -303.35766)
			(xy 37.555299 -303.316064) (xy 37.587934 -303.279227) (xy 37.626055 -303.248102) (xy 37.668676 -303.223495)
			(xy 37.714692 -303.206043) (xy 37.762911 -303.196199) (xy 37.812086 -303.194218) (xy 37.860941 -303.20015)
			(xy 37.908212 -303.213842) (xy 37.952674 -303.23494) (xy 37.993177 -303.262896) (xy 38.02867 -303.296988)
			(xy 38.058235 -303.336332) (xy 38.081106 -303.379909) (xy 38.09669 -303.42659) (xy 38.104585 -303.475167)
			(xy 38.10508 -303.499774) (xy 38.104585 -303.524381) (xy 38.104406 -303.525482) (xy 38.423338 -303.525482)
			(xy 38.423338 -303.474066) (xy 38.431381 -303.423284) (xy 38.447269 -303.374385) (xy 38.470612 -303.328573)
			(xy 38.500833 -303.286977) (xy 38.537189 -303.250621) (xy 38.578785 -303.2204) (xy 38.624597 -303.197057)
			(xy 38.673496 -303.181169) (xy 38.724278 -303.173126) (xy 38.775694 -303.173126) (xy 38.826476 -303.181169)
			(xy 38.875375 -303.197057) (xy 38.921187 -303.2204) (xy 38.962783 -303.250621) (xy 38.999139 -303.286977)
			(xy 39.02936 -303.328573) (xy 39.052703 -303.374385) (xy 39.068591 -303.423284) (xy 39.076634 -303.474066)
			(xy 39.077138 -303.499774) (xy 39.076634 -303.525482) (xy 39.373298 -303.525482) (xy 39.373298 -303.474066)
			(xy 39.381341 -303.423284) (xy 39.397229 -303.374385) (xy 39.420572 -303.328573) (xy 39.450793 -303.286977)
			(xy 39.487149 -303.250621) (xy 39.528745 -303.2204) (xy 39.574557 -303.197057) (xy 39.623456 -303.181169)
			(xy 39.674238 -303.173126) (xy 39.725654 -303.173126) (xy 39.776436 -303.181169) (xy 39.825335 -303.197057)
			(xy 39.871147 -303.2204) (xy 39.912743 -303.250621) (xy 39.949099 -303.286977) (xy 39.97932 -303.328573)
			(xy 40.002663 -303.374385) (xy 40.018551 -303.423284) (xy 40.026594 -303.474066) (xy 40.027098 -303.499774)
			(xy 40.344102 -303.499774) (xy 40.348062 -303.45072) (xy 40.359839 -303.402936) (xy 40.37913 -303.35766)
			(xy 40.405433 -303.316064) (xy 40.438068 -303.279227) (xy 40.476189 -303.248102) (xy 40.51881 -303.223495)
			(xy 40.564826 -303.206043) (xy 40.613045 -303.196199) (xy 40.66222 -303.194218) (xy 40.711075 -303.20015)
			(xy 40.758346 -303.213842) (xy 40.802808 -303.23494) (xy 40.843311 -303.262896) (xy 40.878804 -303.296988)
			(xy 40.908369 -303.336332) (xy 40.93124 -303.379909) (xy 40.946824 -303.42659) (xy 40.954719 -303.475167)
			(xy 40.955214 -303.499774) (xy 40.954719 -303.524381) (xy 40.95454 -303.525482) (xy 41.273218 -303.525482)
			(xy 41.273218 -303.474066) (xy 41.281261 -303.423284) (xy 41.297149 -303.374385) (xy 41.320492 -303.328573)
			(xy 41.350713 -303.286977) (xy 41.387069 -303.250621) (xy 41.428665 -303.2204) (xy 41.474477 -303.197057)
			(xy 41.523376 -303.181169) (xy 41.574158 -303.173126) (xy 41.625574 -303.173126) (xy 41.676356 -303.181169)
			(xy 41.725255 -303.197057) (xy 41.771067 -303.2204) (xy 41.812663 -303.250621) (xy 41.849019 -303.286977)
			(xy 41.87924 -303.328573) (xy 41.902583 -303.374385) (xy 41.918471 -303.423284) (xy 41.926514 -303.474066)
			(xy 41.927018 -303.499774) (xy 41.926514 -303.525482) (xy 42.223178 -303.525482) (xy 42.223178 -303.474066)
			(xy 42.231221 -303.423284) (xy 42.247109 -303.374385) (xy 42.270452 -303.328573) (xy 42.300673 -303.286977)
			(xy 42.337029 -303.250621) (xy 42.378625 -303.2204) (xy 42.424437 -303.197057) (xy 42.473336 -303.181169)
			(xy 42.524118 -303.173126) (xy 42.575534 -303.173126) (xy 42.626316 -303.181169) (xy 42.675215 -303.197057)
			(xy 42.721027 -303.2204) (xy 42.762623 -303.250621) (xy 42.798979 -303.286977) (xy 42.8292 -303.328573)
			(xy 42.852543 -303.374385) (xy 42.868431 -303.423284) (xy 42.876474 -303.474066) (xy 42.876978 -303.499774)
			(xy 43.193982 -303.499774) (xy 43.197942 -303.45072) (xy 43.209719 -303.402936) (xy 43.22901 -303.35766)
			(xy 43.255313 -303.316064) (xy 43.287948 -303.279227) (xy 43.326069 -303.248102) (xy 43.36869 -303.223495)
			(xy 43.414706 -303.206043) (xy 43.462925 -303.196199) (xy 43.5121 -303.194218) (xy 43.560955 -303.20015)
			(xy 43.608226 -303.213842) (xy 43.652688 -303.23494) (xy 43.693191 -303.262896) (xy 43.728684 -303.296988)
			(xy 43.758249 -303.336332) (xy 43.78112 -303.379909) (xy 43.796704 -303.42659) (xy 43.804599 -303.475167)
			(xy 43.805094 -303.499774) (xy 44.143942 -303.499774) (xy 44.147902 -303.45072) (xy 44.159679 -303.402936)
			(xy 44.17897 -303.35766) (xy 44.205273 -303.316064) (xy 44.237908 -303.279227) (xy 44.276029 -303.248102)
			(xy 44.31865 -303.223495) (xy 44.364666 -303.206043) (xy 44.412885 -303.196199) (xy 44.46206 -303.194218)
			(xy 44.510915 -303.20015) (xy 44.558186 -303.213842) (xy 44.602648 -303.23494) (xy 44.643151 -303.262896)
			(xy 44.678644 -303.296988) (xy 44.708209 -303.336332) (xy 44.73108 -303.379909) (xy 44.746664 -303.42659)
			(xy 44.754559 -303.475167) (xy 44.755054 -303.499774) (xy 45.094156 -303.499774) (xy 45.098116 -303.45072)
			(xy 45.109893 -303.402936) (xy 45.129184 -303.35766) (xy 45.155487 -303.316064) (xy 45.188122 -303.279227)
			(xy 45.226243 -303.248102) (xy 45.268864 -303.223495) (xy 45.31488 -303.206043) (xy 45.363099 -303.196199)
			(xy 45.412274 -303.194218) (xy 45.461129 -303.20015) (xy 45.5084 -303.213842) (xy 45.552862 -303.23494)
			(xy 45.593365 -303.262896) (xy 45.628858 -303.296988) (xy 45.658423 -303.336332) (xy 45.681294 -303.379909)
			(xy 45.696878 -303.42659) (xy 45.704773 -303.475167) (xy 45.705268 -303.499774) (xy 45.704773 -303.524381)
			(xy 45.696878 -303.572958) (xy 45.681294 -303.619639) (xy 45.658423 -303.663216) (xy 45.628858 -303.70256)
			(xy 45.593365 -303.736652) (xy 45.552862 -303.764608) (xy 45.5084 -303.785706) (xy 45.461129 -303.799398)
			(xy 45.412274 -303.80533) (xy 45.363099 -303.803349) (xy 45.31488 -303.793505) (xy 45.268864 -303.776053)
			(xy 45.226243 -303.751446) (xy 45.188122 -303.720321) (xy 45.155487 -303.683484) (xy 45.129184 -303.641888)
			(xy 45.109893 -303.596612) (xy 45.098116 -303.548828) (xy 45.094156 -303.499774) (xy 44.755054 -303.499774)
			(xy 44.754559 -303.524381) (xy 44.746664 -303.572958) (xy 44.73108 -303.619639) (xy 44.708209 -303.663216)
			(xy 44.678644 -303.70256) (xy 44.643151 -303.736652) (xy 44.602648 -303.764608) (xy 44.558186 -303.785706)
			(xy 44.510915 -303.799398) (xy 44.46206 -303.80533) (xy 44.412885 -303.803349) (xy 44.364666 -303.793505)
			(xy 44.31865 -303.776053) (xy 44.276029 -303.751446) (xy 44.237908 -303.720321) (xy 44.205273 -303.683484)
			(xy 44.17897 -303.641888) (xy 44.159679 -303.596612) (xy 44.147902 -303.548828) (xy 44.143942 -303.499774)
			(xy 43.805094 -303.499774) (xy 43.804599 -303.524381) (xy 43.796704 -303.572958) (xy 43.78112 -303.619639)
			(xy 43.758249 -303.663216) (xy 43.728684 -303.70256) (xy 43.693191 -303.736652) (xy 43.652688 -303.764608)
			(xy 43.608226 -303.785706) (xy 43.560955 -303.799398) (xy 43.5121 -303.80533) (xy 43.462925 -303.803349)
			(xy 43.414706 -303.793505) (xy 43.36869 -303.776053) (xy 43.326069 -303.751446) (xy 43.287948 -303.720321)
			(xy 43.255313 -303.683484) (xy 43.22901 -303.641888) (xy 43.209719 -303.596612) (xy 43.197942 -303.548828)
			(xy 43.193982 -303.499774) (xy 42.876978 -303.499774) (xy 42.876474 -303.525482) (xy 42.868431 -303.576264)
			(xy 42.852543 -303.625163) (xy 42.8292 -303.670975) (xy 42.798979 -303.712571) (xy 42.762623 -303.748927)
			(xy 42.721027 -303.779148) (xy 42.675215 -303.802491) (xy 42.626316 -303.818379) (xy 42.575534 -303.826422)
			(xy 42.524118 -303.826422) (xy 42.473336 -303.818379) (xy 42.424437 -303.802491) (xy 42.378625 -303.779148)
			(xy 42.337029 -303.748927) (xy 42.300673 -303.712571) (xy 42.270452 -303.670975) (xy 42.247109 -303.625163)
			(xy 42.231221 -303.576264) (xy 42.223178 -303.525482) (xy 41.926514 -303.525482) (xy 41.918471 -303.576264)
			(xy 41.902583 -303.625163) (xy 41.87924 -303.670975) (xy 41.849019 -303.712571) (xy 41.812663 -303.748927)
			(xy 41.771067 -303.779148) (xy 41.725255 -303.802491) (xy 41.676356 -303.818379) (xy 41.625574 -303.826422)
			(xy 41.574158 -303.826422) (xy 41.523376 -303.818379) (xy 41.474477 -303.802491) (xy 41.428665 -303.779148)
			(xy 41.387069 -303.748927) (xy 41.350713 -303.712571) (xy 41.320492 -303.670975) (xy 41.297149 -303.625163)
			(xy 41.281261 -303.576264) (xy 41.273218 -303.525482) (xy 40.95454 -303.525482) (xy 40.946824 -303.572958)
			(xy 40.93124 -303.619639) (xy 40.908369 -303.663216) (xy 40.878804 -303.70256) (xy 40.843311 -303.736652)
			(xy 40.802808 -303.764608) (xy 40.758346 -303.785706) (xy 40.711075 -303.799398) (xy 40.66222 -303.80533)
			(xy 40.613045 -303.803349) (xy 40.564826 -303.793505) (xy 40.51881 -303.776053) (xy 40.476189 -303.751446)
			(xy 40.438068 -303.720321) (xy 40.405433 -303.683484) (xy 40.37913 -303.641888) (xy 40.359839 -303.596612)
			(xy 40.348062 -303.548828) (xy 40.344102 -303.499774) (xy 40.027098 -303.499774) (xy 40.026594 -303.525482)
			(xy 40.018551 -303.576264) (xy 40.002663 -303.625163) (xy 39.97932 -303.670975) (xy 39.949099 -303.712571)
			(xy 39.912743 -303.748927) (xy 39.871147 -303.779148) (xy 39.825335 -303.802491) (xy 39.776436 -303.818379)
			(xy 39.725654 -303.826422) (xy 39.674238 -303.826422) (xy 39.623456 -303.818379) (xy 39.574557 -303.802491)
			(xy 39.528745 -303.779148) (xy 39.487149 -303.748927) (xy 39.450793 -303.712571) (xy 39.420572 -303.670975)
			(xy 39.397229 -303.625163) (xy 39.381341 -303.576264) (xy 39.373298 -303.525482) (xy 39.076634 -303.525482)
			(xy 39.068591 -303.576264) (xy 39.052703 -303.625163) (xy 39.02936 -303.670975) (xy 38.999139 -303.712571)
			(xy 38.962783 -303.748927) (xy 38.921187 -303.779148) (xy 38.875375 -303.802491) (xy 38.826476 -303.818379)
			(xy 38.775694 -303.826422) (xy 38.724278 -303.826422) (xy 38.673496 -303.818379) (xy 38.624597 -303.802491)
			(xy 38.578785 -303.779148) (xy 38.537189 -303.748927) (xy 38.500833 -303.712571) (xy 38.470612 -303.670975)
			(xy 38.447269 -303.625163) (xy 38.431381 -303.576264) (xy 38.423338 -303.525482) (xy 38.104406 -303.525482)
			(xy 38.09669 -303.572958) (xy 38.081106 -303.619639) (xy 38.058235 -303.663216) (xy 38.02867 -303.70256)
			(xy 37.993177 -303.736652) (xy 37.952674 -303.764608) (xy 37.908212 -303.785706) (xy 37.860941 -303.799398)
			(xy 37.812086 -303.80533) (xy 37.762911 -303.803349) (xy 37.714692 -303.793505) (xy 37.668676 -303.776053)
			(xy 37.626055 -303.751446) (xy 37.587934 -303.720321) (xy 37.555299 -303.683484) (xy 37.528996 -303.641888)
			(xy 37.509705 -303.596612) (xy 37.497928 -303.548828) (xy 37.493968 -303.499774) (xy 37.15512 -303.499774)
			(xy 37.154625 -303.524381) (xy 37.14673 -303.572958) (xy 37.131146 -303.619639) (xy 37.108275 -303.663216)
			(xy 37.07871 -303.70256) (xy 37.043217 -303.736652) (xy 37.002714 -303.764608) (xy 36.958252 -303.785706)
			(xy 36.910981 -303.799398) (xy 36.862126 -303.80533) (xy 36.812951 -303.803349) (xy 36.764732 -303.793505)
			(xy 36.718716 -303.776053) (xy 36.676095 -303.751446) (xy 36.637974 -303.720321) (xy 36.605339 -303.683484)
			(xy 36.579036 -303.641888) (xy 36.559745 -303.596612) (xy 36.547968 -303.548828) (xy 36.544008 -303.499774)
			(xy 22.824065 -303.499774) (xy 22.796635 -303.535671) (xy 22.690852 -303.661054) (xy 22.579134 -303.781179)
			(xy 22.461744 -303.895766) (xy 22.338955 -304.004548) (xy 22.211053 -304.107271) (xy 22.078338 -304.203694)
			(xy 21.941119 -304.293593) (xy 21.799718 -304.376757) (xy 21.660189 -304.449988) (xy 35.593794 -304.449988)
			(xy 35.597754 -304.400934) (xy 35.609531 -304.35315) (xy 35.628822 -304.307874) (xy 35.655125 -304.266278)
			(xy 35.68776 -304.229441) (xy 35.725881 -304.198316) (xy 35.768502 -304.173709) (xy 35.814518 -304.156257)
			(xy 35.862737 -304.146413) (xy 35.911912 -304.144432) (xy 35.960767 -304.150364) (xy 36.008038 -304.164056)
			(xy 36.0525 -304.185154) (xy 36.093003 -304.21311) (xy 36.128496 -304.247202) (xy 36.158061 -304.286546)
			(xy 36.180932 -304.330123) (xy 36.196516 -304.376804) (xy 36.204411 -304.425381) (xy 36.204906 -304.449988)
			(xy 36.204411 -304.474595) (xy 36.204273 -304.475442) (xy 36.523164 -304.475442) (xy 36.523164 -304.424026)
			(xy 36.531207 -304.373244) (xy 36.547095 -304.324345) (xy 36.570438 -304.278533) (xy 36.600659 -304.236937)
			(xy 36.637015 -304.200581) (xy 36.678611 -304.17036) (xy 36.724423 -304.147017) (xy 36.773322 -304.131129)
			(xy 36.824104 -304.123086) (xy 36.87552 -304.123086) (xy 36.926302 -304.131129) (xy 36.975201 -304.147017)
			(xy 37.021013 -304.17036) (xy 37.062609 -304.200581) (xy 37.098965 -304.236937) (xy 37.129186 -304.278533)
			(xy 37.152529 -304.324345) (xy 37.168417 -304.373244) (xy 37.17646 -304.424026) (xy 37.176964 -304.449734)
			(xy 37.17646 -304.475442) (xy 37.473124 -304.475442) (xy 37.473124 -304.424026) (xy 37.481167 -304.373244)
			(xy 37.497055 -304.324345) (xy 37.520398 -304.278533) (xy 37.550619 -304.236937) (xy 37.586975 -304.200581)
			(xy 37.628571 -304.17036) (xy 37.674383 -304.147017) (xy 37.723282 -304.131129) (xy 37.774064 -304.123086)
			(xy 37.82548 -304.123086) (xy 37.876262 -304.131129) (xy 37.925161 -304.147017) (xy 37.970973 -304.17036)
			(xy 38.012569 -304.200581) (xy 38.048925 -304.236937) (xy 38.079146 -304.278533) (xy 38.102489 -304.324345)
			(xy 38.118377 -304.373244) (xy 38.12642 -304.424026) (xy 38.126924 -304.449734) (xy 38.444182 -304.449734)
			(xy 38.448142 -304.40068) (xy 38.459919 -304.352896) (xy 38.47921 -304.30762) (xy 38.505513 -304.266024)
			(xy 38.538148 -304.229187) (xy 38.576269 -304.198062) (xy 38.61889 -304.173455) (xy 38.664906 -304.156003)
			(xy 38.713125 -304.146159) (xy 38.7623 -304.144178) (xy 38.811155 -304.15011) (xy 38.858426 -304.163802)
			(xy 38.902888 -304.1849) (xy 38.943391 -304.212856) (xy 38.978884 -304.246948) (xy 39.008449 -304.286292)
			(xy 39.03132 -304.329869) (xy 39.046904 -304.37655) (xy 39.054799 -304.425127) (xy 39.055294 -304.449734)
			(xy 39.394142 -304.449734) (xy 39.398102 -304.40068) (xy 39.409879 -304.352896) (xy 39.42917 -304.30762)
			(xy 39.455473 -304.266024) (xy 39.488108 -304.229187) (xy 39.526229 -304.198062) (xy 39.56885 -304.173455)
			(xy 39.614866 -304.156003) (xy 39.663085 -304.146159) (xy 39.71226 -304.144178) (xy 39.761115 -304.15011)
			(xy 39.808386 -304.163802) (xy 39.852848 -304.1849) (xy 39.893351 -304.212856) (xy 39.928844 -304.246948)
			(xy 39.958409 -304.286292) (xy 39.98128 -304.329869) (xy 39.996864 -304.37655) (xy 40.004759 -304.425127)
			(xy 40.005254 -304.449734) (xy 40.344102 -304.449734) (xy 40.348062 -304.40068) (xy 40.359839 -304.352896)
			(xy 40.37913 -304.30762) (xy 40.405433 -304.266024) (xy 40.438068 -304.229187) (xy 40.476189 -304.198062)
			(xy 40.51881 -304.173455) (xy 40.564826 -304.156003) (xy 40.613045 -304.146159) (xy 40.66222 -304.144178)
			(xy 40.711075 -304.15011) (xy 40.758346 -304.163802) (xy 40.802808 -304.1849) (xy 40.843311 -304.212856)
			(xy 40.878804 -304.246948) (xy 40.908369 -304.286292) (xy 40.93124 -304.329869) (xy 40.946824 -304.37655)
			(xy 40.954719 -304.425127) (xy 40.955214 -304.449734) (xy 41.294062 -304.449734) (xy 41.298022 -304.40068)
			(xy 41.309799 -304.352896) (xy 41.32909 -304.30762) (xy 41.355393 -304.266024) (xy 41.388028 -304.229187)
			(xy 41.426149 -304.198062) (xy 41.46877 -304.173455) (xy 41.514786 -304.156003) (xy 41.563005 -304.146159)
			(xy 41.61218 -304.144178) (xy 41.661035 -304.15011) (xy 41.708306 -304.163802) (xy 41.752768 -304.1849)
			(xy 41.793271 -304.212856) (xy 41.828764 -304.246948) (xy 41.858329 -304.286292) (xy 41.8812 -304.329869)
			(xy 41.896784 -304.37655) (xy 41.904679 -304.425127) (xy 41.905174 -304.449734) (xy 42.244022 -304.449734)
			(xy 42.247982 -304.40068) (xy 42.259759 -304.352896) (xy 42.27905 -304.30762) (xy 42.305353 -304.266024)
			(xy 42.337988 -304.229187) (xy 42.376109 -304.198062) (xy 42.41873 -304.173455) (xy 42.464746 -304.156003)
			(xy 42.512965 -304.146159) (xy 42.56214 -304.144178) (xy 42.610995 -304.15011) (xy 42.658266 -304.163802)
			(xy 42.702728 -304.1849) (xy 42.743231 -304.212856) (xy 42.778724 -304.246948) (xy 42.808289 -304.286292)
			(xy 42.83116 -304.329869) (xy 42.846744 -304.37655) (xy 42.854639 -304.425127) (xy 42.855134 -304.449734)
			(xy 42.854639 -304.474341) (xy 42.85446 -304.475442) (xy 43.173138 -304.475442) (xy 43.173138 -304.424026)
			(xy 43.181181 -304.373244) (xy 43.197069 -304.324345) (xy 43.220412 -304.278533) (xy 43.250633 -304.236937)
			(xy 43.286989 -304.200581) (xy 43.328585 -304.17036) (xy 43.374397 -304.147017) (xy 43.423296 -304.131129)
			(xy 43.474078 -304.123086) (xy 43.525494 -304.123086) (xy 43.576276 -304.131129) (xy 43.625175 -304.147017)
			(xy 43.670987 -304.17036) (xy 43.712583 -304.200581) (xy 43.748939 -304.236937) (xy 43.77916 -304.278533)
			(xy 43.802503 -304.324345) (xy 43.818391 -304.373244) (xy 43.826434 -304.424026) (xy 43.826938 -304.449734)
			(xy 43.826434 -304.475442) (xy 44.123098 -304.475442) (xy 44.123098 -304.424026) (xy 44.131141 -304.373244)
			(xy 44.147029 -304.324345) (xy 44.170372 -304.278533) (xy 44.200593 -304.236937) (xy 44.236949 -304.200581)
			(xy 44.278545 -304.17036) (xy 44.324357 -304.147017) (xy 44.373256 -304.131129) (xy 44.424038 -304.123086)
			(xy 44.475454 -304.123086) (xy 44.526236 -304.131129) (xy 44.575135 -304.147017) (xy 44.620947 -304.17036)
			(xy 44.662543 -304.200581) (xy 44.698899 -304.236937) (xy 44.72912 -304.278533) (xy 44.752463 -304.324345)
			(xy 44.768351 -304.373244) (xy 44.776394 -304.424026) (xy 44.776898 -304.449734) (xy 45.094156 -304.449734)
			(xy 45.098116 -304.40068) (xy 45.109893 -304.352896) (xy 45.129184 -304.30762) (xy 45.155487 -304.266024)
			(xy 45.188122 -304.229187) (xy 45.226243 -304.198062) (xy 45.268864 -304.173455) (xy 45.31488 -304.156003)
			(xy 45.363099 -304.146159) (xy 45.412274 -304.144178) (xy 45.461129 -304.15011) (xy 45.5084 -304.163802)
			(xy 45.552862 -304.1849) (xy 45.593365 -304.212856) (xy 45.628858 -304.246948) (xy 45.658423 -304.286292)
			(xy 45.681294 -304.329869) (xy 45.696878 -304.37655) (xy 45.704773 -304.425127) (xy 45.7051 -304.441395)
			(xy 46.044216 -304.441395) (xy 46.049586 -304.39205) (xy 46.062869 -304.344225) (xy 46.083714 -304.299178)
			(xy 46.111572 -304.258097) (xy 46.145709 -304.222065) (xy 46.185226 -304.192029) (xy 46.229081 -304.168783)
			(xy 46.27612 -304.152937) (xy 46.325102 -304.14491) (xy 46.34992 -304.144426) (xy 46.364103 -304.144599)
			(xy 46.392343 -304.147274) (xy 46.406308 -304.14976) (xy 46.418754 -304.152046) (xy 46.442376 -304.14468)
			(xy 46.519846 -304.06721) (xy 46.527212 -304.043588) (xy 46.524926 -304.031142) (xy 46.522446 -304.017177)
			(xy 46.519776 -303.988937) (xy 46.519592 -303.974754) (xy 46.520114 -303.949499) (xy 46.528427 -303.899677)
			(xy 46.544828 -303.851903) (xy 46.568869 -303.80748) (xy 46.599893 -303.76762) (xy 46.637055 -303.73341)
			(xy 46.679341 -303.705784) (xy 46.725597 -303.685494) (xy 46.774562 -303.673094) (xy 46.8249 -303.668923)
			(xy 46.875238 -303.673094) (xy 46.924203 -303.685494) (xy 46.970459 -303.705784) (xy 47.012745 -303.73341)
			(xy 47.049907 -303.76762) (xy 47.080931 -303.80748) (xy 47.104972 -303.851903) (xy 47.121373 -303.899677)
			(xy 47.129686 -303.949499) (xy 47.130208 -303.974754) (xy 47.130025 -303.988937) (xy 47.127357 -304.017177)
			(xy 47.124874 -304.031142) (xy 47.122588 -304.043588) (xy 47.129954 -304.06721) (xy 47.207424 -304.14468)
			(xy 47.231046 -304.152046) (xy 47.243492 -304.14976) (xy 47.257459 -304.147289) (xy 47.285698 -304.144614)
			(xy 47.29988 -304.144426) (xy 47.314063 -304.144605) (xy 47.342303 -304.147275) (xy 47.356268 -304.14976)
			(xy 47.368714 -304.152046) (xy 47.392336 -304.14468) (xy 47.469806 -304.06721) (xy 47.477172 -304.043588)
			(xy 47.474886 -304.031142) (xy 47.472405 -304.017177) (xy 47.469736 -303.988937) (xy 47.469552 -303.974754)
			(xy 47.470127 -303.949937) (xy 47.478165 -303.900958) (xy 47.49402 -303.853925) (xy 47.517275 -303.810076)
			(xy 47.547319 -303.770567) (xy 47.583358 -303.736439) (xy 47.624443 -303.708591) (xy 47.669493 -303.687757)
			(xy 47.71732 -303.674485) (xy 47.766664 -303.669126) (xy 47.816224 -303.67182) (xy 47.864697 -303.682497)
			(xy 47.910803 -303.700875) (xy 47.953328 -303.72647) (xy 47.991153 -303.758608) (xy 48.02328 -303.796441)
			(xy 48.048863 -303.838974) (xy 48.067228 -303.885086) (xy 48.077891 -303.933561) (xy 48.080119 -303.974754)
			(xy 48.419016 -303.974754) (xy 48.422976 -303.9257) (xy 48.434753 -303.877916) (xy 48.454044 -303.83264)
			(xy 48.480347 -303.791044) (xy 48.512982 -303.754207) (xy 48.551103 -303.723082) (xy 48.593724 -303.698475)
			(xy 48.63974 -303.681023) (xy 48.687959 -303.671179) (xy 48.737134 -303.669198) (xy 48.785989 -303.67513)
			(xy 48.83326 -303.688822) (xy 48.877722 -303.70992) (xy 48.918225 -303.737876) (xy 48.953718 -303.771968)
			(xy 48.983283 -303.811312) (xy 49.006154 -303.854889) (xy 49.021738 -303.90157) (xy 49.029633 -303.950147)
			(xy 49.030128 -303.974754) (xy 49.368976 -303.974754) (xy 49.372936 -303.9257) (xy 49.384713 -303.877916)
			(xy 49.404004 -303.83264) (xy 49.430307 -303.791044) (xy 49.462942 -303.754207) (xy 49.501063 -303.723082)
			(xy 49.543684 -303.698475) (xy 49.5897 -303.681023) (xy 49.637919 -303.671179) (xy 49.687094 -303.669198)
			(xy 49.735949 -303.67513) (xy 49.78322 -303.688822) (xy 49.827682 -303.70992) (xy 49.868185 -303.737876)
			(xy 49.903678 -303.771968) (xy 49.933243 -303.811312) (xy 49.956114 -303.854889) (xy 49.971698 -303.90157)
			(xy 49.979593 -303.950147) (xy 49.980088 -303.974754) (xy 50.31919 -303.974754) (xy 50.32315 -303.9257)
			(xy 50.334927 -303.877916) (xy 50.354218 -303.83264) (xy 50.380521 -303.791044) (xy 50.413156 -303.754207)
			(xy 50.451277 -303.723082) (xy 50.493898 -303.698475) (xy 50.539914 -303.681023) (xy 50.588133 -303.671179)
			(xy 50.637308 -303.669198) (xy 50.686163 -303.67513) (xy 50.733434 -303.688822) (xy 50.777896 -303.70992)
			(xy 50.818399 -303.737876) (xy 50.853892 -303.771968) (xy 50.883457 -303.811312) (xy 50.906328 -303.854889)
			(xy 50.921912 -303.90157) (xy 50.929807 -303.950147) (xy 50.930302 -303.974754) (xy 51.26915 -303.974754)
			(xy 51.27311 -303.9257) (xy 51.284887 -303.877916) (xy 51.304178 -303.83264) (xy 51.330481 -303.791044)
			(xy 51.363116 -303.754207) (xy 51.401237 -303.723082) (xy 51.443858 -303.698475) (xy 51.489874 -303.681023)
			(xy 51.538093 -303.671179) (xy 51.587268 -303.669198) (xy 51.636123 -303.67513) (xy 51.683394 -303.688822)
			(xy 51.727856 -303.70992) (xy 51.768359 -303.737876) (xy 51.803852 -303.771968) (xy 51.833417 -303.811312)
			(xy 51.856288 -303.854889) (xy 51.871872 -303.90157) (xy 51.879767 -303.950147) (xy 51.880262 -303.974754)
			(xy 52.21911 -303.974754) (xy 52.22307 -303.9257) (xy 52.234847 -303.877916) (xy 52.254138 -303.83264)
			(xy 52.280441 -303.791044) (xy 52.313076 -303.754207) (xy 52.351197 -303.723082) (xy 52.393818 -303.698475)
			(xy 52.439834 -303.681023) (xy 52.488053 -303.671179) (xy 52.537228 -303.669198) (xy 52.586083 -303.67513)
			(xy 52.633354 -303.688822) (xy 52.677816 -303.70992) (xy 52.718319 -303.737876) (xy 52.753812 -303.771968)
			(xy 52.783377 -303.811312) (xy 52.806248 -303.854889) (xy 52.821832 -303.90157) (xy 52.829727 -303.950147)
			(xy 52.830222 -303.974754) (xy 53.16907 -303.974754) (xy 53.17303 -303.9257) (xy 53.184807 -303.877916)
			(xy 53.204098 -303.83264) (xy 53.230401 -303.791044) (xy 53.263036 -303.754207) (xy 53.301157 -303.723082)
			(xy 53.343778 -303.698475) (xy 53.389794 -303.681023) (xy 53.438013 -303.671179) (xy 53.487188 -303.669198)
			(xy 53.536043 -303.67513) (xy 53.583314 -303.688822) (xy 53.627776 -303.70992) (xy 53.668279 -303.737876)
			(xy 53.703772 -303.771968) (xy 53.733337 -303.811312) (xy 53.756208 -303.854889) (xy 53.771792 -303.90157)
			(xy 53.779687 -303.950147) (xy 53.780182 -303.974754) (xy 54.11903 -303.974754) (xy 54.12299 -303.9257)
			(xy 54.134767 -303.877916) (xy 54.154058 -303.83264) (xy 54.180361 -303.791044) (xy 54.212996 -303.754207)
			(xy 54.251117 -303.723082) (xy 54.293738 -303.698475) (xy 54.339754 -303.681023) (xy 54.387973 -303.671179)
			(xy 54.437148 -303.669198) (xy 54.486003 -303.67513) (xy 54.533274 -303.688822) (xy 54.577736 -303.70992)
			(xy 54.618239 -303.737876) (xy 54.653732 -303.771968) (xy 54.683297 -303.811312) (xy 54.706168 -303.854889)
			(xy 54.721752 -303.90157) (xy 54.729647 -303.950147) (xy 54.730142 -303.974754) (xy 55.06899 -303.974754)
			(xy 55.07295 -303.9257) (xy 55.084727 -303.877916) (xy 55.104018 -303.83264) (xy 55.130321 -303.791044)
			(xy 55.162956 -303.754207) (xy 55.201077 -303.723082) (xy 55.243698 -303.698475) (xy 55.289714 -303.681023)
			(xy 55.337933 -303.671179) (xy 55.387108 -303.669198) (xy 55.435963 -303.67513) (xy 55.483234 -303.688822)
			(xy 55.527696 -303.70992) (xy 55.568199 -303.737876) (xy 55.603692 -303.771968) (xy 55.633257 -303.811312)
			(xy 55.656128 -303.854889) (xy 55.671712 -303.90157) (xy 55.679607 -303.950147) (xy 55.680102 -303.974754)
			(xy 56.01895 -303.974754) (xy 56.02291 -303.9257) (xy 56.034687 -303.877916) (xy 56.053978 -303.83264)
			(xy 56.080281 -303.791044) (xy 56.112916 -303.754207) (xy 56.151037 -303.723082) (xy 56.193658 -303.698475)
			(xy 56.239674 -303.681023) (xy 56.287893 -303.671179) (xy 56.337068 -303.669198) (xy 56.385923 -303.67513)
			(xy 56.433194 -303.688822) (xy 56.477656 -303.70992) (xy 56.518159 -303.737876) (xy 56.553652 -303.771968)
			(xy 56.583217 -303.811312) (xy 56.606088 -303.854889) (xy 56.621672 -303.90157) (xy 56.629567 -303.950147)
			(xy 56.630062 -303.974754) (xy 56.969164 -303.974754) (xy 56.973124 -303.9257) (xy 56.984901 -303.877916)
			(xy 57.004192 -303.83264) (xy 57.030495 -303.791044) (xy 57.06313 -303.754207) (xy 57.101251 -303.723082)
			(xy 57.143872 -303.698475) (xy 57.189888 -303.681023) (xy 57.238107 -303.671179) (xy 57.287282 -303.669198)
			(xy 57.336137 -303.67513) (xy 57.383408 -303.688822) (xy 57.42787 -303.70992) (xy 57.468373 -303.737876)
			(xy 57.503866 -303.771968) (xy 57.533431 -303.811312) (xy 57.556302 -303.854889) (xy 57.571886 -303.90157)
			(xy 57.579781 -303.950147) (xy 57.580276 -303.974754) (xy 57.919124 -303.974754) (xy 57.923084 -303.9257)
			(xy 57.934861 -303.877916) (xy 57.954152 -303.83264) (xy 57.980455 -303.791044) (xy 58.01309 -303.754207)
			(xy 58.051211 -303.723082) (xy 58.093832 -303.698475) (xy 58.139848 -303.681023) (xy 58.188067 -303.671179)
			(xy 58.237242 -303.669198) (xy 58.286097 -303.67513) (xy 58.333368 -303.688822) (xy 58.37783 -303.70992)
			(xy 58.418333 -303.737876) (xy 58.453826 -303.771968) (xy 58.483391 -303.811312) (xy 58.506262 -303.854889)
			(xy 58.521846 -303.90157) (xy 58.529741 -303.950147) (xy 58.530236 -303.974754) (xy 59.819044 -303.974754)
			(xy 59.823004 -303.9257) (xy 59.834781 -303.877916) (xy 59.854072 -303.83264) (xy 59.880375 -303.791044)
			(xy 59.91301 -303.754207) (xy 59.951131 -303.723082) (xy 59.993752 -303.698475) (xy 60.039768 -303.681023)
			(xy 60.087987 -303.671179) (xy 60.137162 -303.669198) (xy 60.186017 -303.67513) (xy 60.233288 -303.688822)
			(xy 60.27775 -303.70992) (xy 60.318253 -303.737876) (xy 60.353746 -303.771968) (xy 60.383311 -303.811312)
			(xy 60.406182 -303.854889) (xy 60.421766 -303.90157) (xy 60.429661 -303.950147) (xy 60.430156 -303.974754)
			(xy 60.769004 -303.974754) (xy 60.772964 -303.9257) (xy 60.784741 -303.877916) (xy 60.804032 -303.83264)
			(xy 60.830335 -303.791044) (xy 60.86297 -303.754207) (xy 60.901091 -303.723082) (xy 60.943712 -303.698475)
			(xy 60.989728 -303.681023) (xy 61.037947 -303.671179) (xy 61.087122 -303.669198) (xy 61.135977 -303.67513)
			(xy 61.183248 -303.688822) (xy 61.22771 -303.70992) (xy 61.268213 -303.737876) (xy 61.303706 -303.771968)
			(xy 61.333271 -303.811312) (xy 61.356142 -303.854889) (xy 61.371726 -303.90157) (xy 61.379621 -303.950147)
			(xy 61.380116 -303.974754) (xy 61.718964 -303.974754) (xy 61.722924 -303.9257) (xy 61.734701 -303.877916)
			(xy 61.753992 -303.83264) (xy 61.780295 -303.791044) (xy 61.81293 -303.754207) (xy 61.851051 -303.723082)
			(xy 61.893672 -303.698475) (xy 61.939688 -303.681023) (xy 61.987907 -303.671179) (xy 62.037082 -303.669198)
			(xy 62.085937 -303.67513) (xy 62.133208 -303.688822) (xy 62.17767 -303.70992) (xy 62.218173 -303.737876)
			(xy 62.253666 -303.771968) (xy 62.283231 -303.811312) (xy 62.306102 -303.854889) (xy 62.321686 -303.90157)
			(xy 62.329581 -303.950147) (xy 62.330076 -303.974754) (xy 62.669178 -303.974754) (xy 62.673138 -303.9257)
			(xy 62.684915 -303.877916) (xy 62.704206 -303.83264) (xy 62.730509 -303.791044) (xy 62.763144 -303.754207)
			(xy 62.801265 -303.723082) (xy 62.843886 -303.698475) (xy 62.889902 -303.681023) (xy 62.938121 -303.671179)
			(xy 62.987296 -303.669198) (xy 63.036151 -303.67513) (xy 63.083422 -303.688822) (xy 63.127884 -303.70992)
			(xy 63.168387 -303.737876) (xy 63.20388 -303.771968) (xy 63.233445 -303.811312) (xy 63.256316 -303.854889)
			(xy 63.2719 -303.90157) (xy 63.279795 -303.950147) (xy 63.28029 -303.974754) (xy 63.619138 -303.974754)
			(xy 63.623098 -303.9257) (xy 63.634875 -303.877916) (xy 63.654166 -303.83264) (xy 63.680469 -303.791044)
			(xy 63.713104 -303.754207) (xy 63.751225 -303.723082) (xy 63.793846 -303.698475) (xy 63.839862 -303.681023)
			(xy 63.888081 -303.671179) (xy 63.937256 -303.669198) (xy 63.986111 -303.67513) (xy 64.033382 -303.688822)
			(xy 64.077844 -303.70992) (xy 64.118347 -303.737876) (xy 64.15384 -303.771968) (xy 64.183405 -303.811312)
			(xy 64.206276 -303.854889) (xy 64.22186 -303.90157) (xy 64.229755 -303.950147) (xy 64.23025 -303.974754)
			(xy 64.569098 -303.974754) (xy 64.573058 -303.9257) (xy 64.584835 -303.877916) (xy 64.604126 -303.83264)
			(xy 64.630429 -303.791044) (xy 64.663064 -303.754207) (xy 64.701185 -303.723082) (xy 64.743806 -303.698475)
			(xy 64.789822 -303.681023) (xy 64.838041 -303.671179) (xy 64.887216 -303.669198) (xy 64.936071 -303.67513)
			(xy 64.983342 -303.688822) (xy 65.027804 -303.70992) (xy 65.068307 -303.737876) (xy 65.1038 -303.771968)
			(xy 65.133365 -303.811312) (xy 65.156236 -303.854889) (xy 65.17182 -303.90157) (xy 65.179715 -303.950147)
			(xy 65.18021 -303.974754) (xy 65.519058 -303.974754) (xy 65.523018 -303.9257) (xy 65.534795 -303.877916)
			(xy 65.554086 -303.83264) (xy 65.580389 -303.791044) (xy 65.613024 -303.754207) (xy 65.651145 -303.723082)
			(xy 65.693766 -303.698475) (xy 65.739782 -303.681023) (xy 65.788001 -303.671179) (xy 65.837176 -303.669198)
			(xy 65.886031 -303.67513) (xy 65.933302 -303.688822) (xy 65.977764 -303.70992) (xy 66.018267 -303.737876)
			(xy 66.05376 -303.771968) (xy 66.083325 -303.811312) (xy 66.106196 -303.854889) (xy 66.12178 -303.90157)
			(xy 66.129675 -303.950147) (xy 66.13017 -303.974754) (xy 66.469018 -303.974754) (xy 66.472978 -303.9257)
			(xy 66.484755 -303.877916) (xy 66.504046 -303.83264) (xy 66.530349 -303.791044) (xy 66.562984 -303.754207)
			(xy 66.601105 -303.723082) (xy 66.643726 -303.698475) (xy 66.689742 -303.681023) (xy 66.737961 -303.671179)
			(xy 66.787136 -303.669198) (xy 66.835991 -303.67513) (xy 66.883262 -303.688822) (xy 66.927724 -303.70992)
			(xy 66.968227 -303.737876) (xy 67.00372 -303.771968) (xy 67.033285 -303.811312) (xy 67.056156 -303.854889)
			(xy 67.07174 -303.90157) (xy 67.079635 -303.950147) (xy 67.08013 -303.974754) (xy 67.418978 -303.974754)
			(xy 67.422938 -303.9257) (xy 67.434715 -303.877916) (xy 67.454006 -303.83264) (xy 67.480309 -303.791044)
			(xy 67.512944 -303.754207) (xy 67.551065 -303.723082) (xy 67.593686 -303.698475) (xy 67.639702 -303.681023)
			(xy 67.687921 -303.671179) (xy 67.737096 -303.669198) (xy 67.785951 -303.67513) (xy 67.833222 -303.688822)
			(xy 67.877684 -303.70992) (xy 67.918187 -303.737876) (xy 67.95368 -303.771968) (xy 67.983245 -303.811312)
			(xy 68.006116 -303.854889) (xy 68.0217 -303.90157) (xy 68.029595 -303.950147) (xy 68.029993 -303.969928)
			(xy 68.374018 -303.969928) (xy 68.377978 -303.920874) (xy 68.389755 -303.87309) (xy 68.409046 -303.827814)
			(xy 68.435349 -303.786218) (xy 68.467984 -303.749381) (xy 68.506105 -303.718256) (xy 68.548726 -303.693649)
			(xy 68.594742 -303.676197) (xy 68.642961 -303.666353) (xy 68.692136 -303.664372) (xy 68.740991 -303.670304)
			(xy 68.788262 -303.683996) (xy 68.832724 -303.705094) (xy 68.873227 -303.73305) (xy 68.90872 -303.767142)
			(xy 68.938285 -303.806486) (xy 68.961156 -303.850063) (xy 68.97674 -303.896744) (xy 68.984635 -303.945321)
			(xy 68.98513 -303.969928) (xy 68.985033 -303.974754) (xy 69.319152 -303.974754) (xy 69.323112 -303.9257)
			(xy 69.334889 -303.877916) (xy 69.35418 -303.83264) (xy 69.380483 -303.791044) (xy 69.413118 -303.754207)
			(xy 69.451239 -303.723082) (xy 69.49386 -303.698475) (xy 69.539876 -303.681023) (xy 69.588095 -303.671179)
			(xy 69.63727 -303.669198) (xy 69.686125 -303.67513) (xy 69.733396 -303.688822) (xy 69.777858 -303.70992)
			(xy 69.818361 -303.737876) (xy 69.853854 -303.771968) (xy 69.883419 -303.811312) (xy 69.90629 -303.854889)
			(xy 69.921874 -303.90157) (xy 69.929769 -303.950147) (xy 69.930264 -303.974754) (xy 70.269112 -303.974754)
			(xy 70.273072 -303.9257) (xy 70.284849 -303.877916) (xy 70.30414 -303.83264) (xy 70.330443 -303.791044)
			(xy 70.363078 -303.754207) (xy 70.401199 -303.723082) (xy 70.44382 -303.698475) (xy 70.489836 -303.681023)
			(xy 70.538055 -303.671179) (xy 70.58723 -303.669198) (xy 70.636085 -303.67513) (xy 70.683356 -303.688822)
			(xy 70.727818 -303.70992) (xy 70.768321 -303.737876) (xy 70.803814 -303.771968) (xy 70.833379 -303.811312)
			(xy 70.85625 -303.854889) (xy 70.871834 -303.90157) (xy 70.879729 -303.950147) (xy 70.880224 -303.974754)
			(xy 71.219072 -303.974754) (xy 71.223032 -303.9257) (xy 71.234809 -303.877916) (xy 71.2541 -303.83264)
			(xy 71.280403 -303.791044) (xy 71.313038 -303.754207) (xy 71.351159 -303.723082) (xy 71.39378 -303.698475)
			(xy 71.439796 -303.681023) (xy 71.488015 -303.671179) (xy 71.53719 -303.669198) (xy 71.586045 -303.67513)
			(xy 71.633316 -303.688822) (xy 71.677778 -303.70992) (xy 71.718281 -303.737876) (xy 71.753774 -303.771968)
			(xy 71.783339 -303.811312) (xy 71.80621 -303.854889) (xy 71.821794 -303.90157) (xy 71.829689 -303.950147)
			(xy 71.830184 -303.974754) (xy 72.169032 -303.974754) (xy 72.172992 -303.9257) (xy 72.184769 -303.877916)
			(xy 72.20406 -303.83264) (xy 72.230363 -303.791044) (xy 72.262998 -303.754207) (xy 72.301119 -303.723082)
			(xy 72.34374 -303.698475) (xy 72.389756 -303.681023) (xy 72.437975 -303.671179) (xy 72.48715 -303.669198)
			(xy 72.536005 -303.67513) (xy 72.583276 -303.688822) (xy 72.627738 -303.70992) (xy 72.668241 -303.737876)
			(xy 72.703734 -303.771968) (xy 72.733299 -303.811312) (xy 72.75617 -303.854889) (xy 72.771754 -303.90157)
			(xy 72.779649 -303.950147) (xy 72.780144 -303.974754) (xy 72.779649 -303.999361) (xy 72.771754 -304.047938)
			(xy 72.75617 -304.094619) (xy 72.733299 -304.138196) (xy 72.703734 -304.17754) (xy 72.668241 -304.211632)
			(xy 72.627738 -304.239588) (xy 72.583276 -304.260686) (xy 72.536005 -304.274378) (xy 72.48715 -304.28031)
			(xy 72.437975 -304.278329) (xy 72.389756 -304.268485) (xy 72.34374 -304.251033) (xy 72.301119 -304.226426)
			(xy 72.262998 -304.195301) (xy 72.230363 -304.158464) (xy 72.20406 -304.116868) (xy 72.184769 -304.071592)
			(xy 72.172992 -304.023808) (xy 72.169032 -303.974754) (xy 71.830184 -303.974754) (xy 71.829689 -303.999361)
			(xy 71.821794 -304.047938) (xy 71.80621 -304.094619) (xy 71.783339 -304.138196) (xy 71.753774 -304.17754)
			(xy 71.718281 -304.211632) (xy 71.677778 -304.239588) (xy 71.633316 -304.260686) (xy 71.586045 -304.274378)
			(xy 71.53719 -304.28031) (xy 71.488015 -304.278329) (xy 71.439796 -304.268485) (xy 71.39378 -304.251033)
			(xy 71.351159 -304.226426) (xy 71.313038 -304.195301) (xy 71.280403 -304.158464) (xy 71.2541 -304.116868)
			(xy 71.234809 -304.071592) (xy 71.223032 -304.023808) (xy 71.219072 -303.974754) (xy 70.880224 -303.974754)
			(xy 70.879729 -303.999361) (xy 70.871834 -304.047938) (xy 70.85625 -304.094619) (xy 70.833379 -304.138196)
			(xy 70.803814 -304.17754) (xy 70.768321 -304.211632) (xy 70.727818 -304.239588) (xy 70.683356 -304.260686)
			(xy 70.636085 -304.274378) (xy 70.58723 -304.28031) (xy 70.538055 -304.278329) (xy 70.489836 -304.268485)
			(xy 70.44382 -304.251033) (xy 70.401199 -304.226426) (xy 70.363078 -304.195301) (xy 70.330443 -304.158464)
			(xy 70.30414 -304.116868) (xy 70.284849 -304.071592) (xy 70.273072 -304.023808) (xy 70.269112 -303.974754)
			(xy 69.930264 -303.974754) (xy 69.929769 -303.999361) (xy 69.921874 -304.047938) (xy 69.90629 -304.094619)
			(xy 69.883419 -304.138196) (xy 69.853854 -304.17754) (xy 69.818361 -304.211632) (xy 69.777858 -304.239588)
			(xy 69.733396 -304.260686) (xy 69.686125 -304.274378) (xy 69.63727 -304.28031) (xy 69.588095 -304.278329)
			(xy 69.539876 -304.268485) (xy 69.49386 -304.251033) (xy 69.451239 -304.226426) (xy 69.413118 -304.195301)
			(xy 69.380483 -304.158464) (xy 69.35418 -304.116868) (xy 69.334889 -304.071592) (xy 69.323112 -304.023808)
			(xy 69.319152 -303.974754) (xy 68.985033 -303.974754) (xy 68.984635 -303.994535) (xy 68.97674 -304.043112)
			(xy 68.961156 -304.089793) (xy 68.938285 -304.13337) (xy 68.90872 -304.172714) (xy 68.873227 -304.206806)
			(xy 68.832724 -304.234762) (xy 68.788262 -304.25586) (xy 68.740991 -304.269552) (xy 68.692136 -304.275484)
			(xy 68.642961 -304.273503) (xy 68.594742 -304.263659) (xy 68.548726 -304.246207) (xy 68.506105 -304.2216)
			(xy 68.467984 -304.190475) (xy 68.435349 -304.153638) (xy 68.409046 -304.112042) (xy 68.389755 -304.066766)
			(xy 68.377978 -304.018982) (xy 68.374018 -303.969928) (xy 68.029993 -303.969928) (xy 68.03009 -303.974754)
			(xy 68.029595 -303.999361) (xy 68.0217 -304.047938) (xy 68.006116 -304.094619) (xy 67.983245 -304.138196)
			(xy 67.95368 -304.17754) (xy 67.918187 -304.211632) (xy 67.877684 -304.239588) (xy 67.833222 -304.260686)
			(xy 67.785951 -304.274378) (xy 67.737096 -304.28031) (xy 67.687921 -304.278329) (xy 67.639702 -304.268485)
			(xy 67.593686 -304.251033) (xy 67.551065 -304.226426) (xy 67.512944 -304.195301) (xy 67.480309 -304.158464)
			(xy 67.454006 -304.116868) (xy 67.434715 -304.071592) (xy 67.422938 -304.023808) (xy 67.418978 -303.974754)
			(xy 67.08013 -303.974754) (xy 67.079635 -303.999361) (xy 67.07174 -304.047938) (xy 67.056156 -304.094619)
			(xy 67.033285 -304.138196) (xy 67.00372 -304.17754) (xy 66.968227 -304.211632) (xy 66.927724 -304.239588)
			(xy 66.883262 -304.260686) (xy 66.835991 -304.274378) (xy 66.787136 -304.28031) (xy 66.737961 -304.278329)
			(xy 66.689742 -304.268485) (xy 66.643726 -304.251033) (xy 66.601105 -304.226426) (xy 66.562984 -304.195301)
			(xy 66.530349 -304.158464) (xy 66.504046 -304.116868) (xy 66.484755 -304.071592) (xy 66.472978 -304.023808)
			(xy 66.469018 -303.974754) (xy 66.13017 -303.974754) (xy 66.129675 -303.999361) (xy 66.12178 -304.047938)
			(xy 66.106196 -304.094619) (xy 66.083325 -304.138196) (xy 66.05376 -304.17754) (xy 66.018267 -304.211632)
			(xy 65.977764 -304.239588) (xy 65.933302 -304.260686) (xy 65.886031 -304.274378) (xy 65.837176 -304.28031)
			(xy 65.788001 -304.278329) (xy 65.739782 -304.268485) (xy 65.693766 -304.251033) (xy 65.651145 -304.226426)
			(xy 65.613024 -304.195301) (xy 65.580389 -304.158464) (xy 65.554086 -304.116868) (xy 65.534795 -304.071592)
			(xy 65.523018 -304.023808) (xy 65.519058 -303.974754) (xy 65.18021 -303.974754) (xy 65.179715 -303.999361)
			(xy 65.17182 -304.047938) (xy 65.156236 -304.094619) (xy 65.133365 -304.138196) (xy 65.1038 -304.17754)
			(xy 65.068307 -304.211632) (xy 65.027804 -304.239588) (xy 64.983342 -304.260686) (xy 64.936071 -304.274378)
			(xy 64.887216 -304.28031) (xy 64.838041 -304.278329) (xy 64.789822 -304.268485) (xy 64.743806 -304.251033)
			(xy 64.701185 -304.226426) (xy 64.663064 -304.195301) (xy 64.630429 -304.158464) (xy 64.604126 -304.116868)
			(xy 64.584835 -304.071592) (xy 64.573058 -304.023808) (xy 64.569098 -303.974754) (xy 64.23025 -303.974754)
			(xy 64.229755 -303.999361) (xy 64.22186 -304.047938) (xy 64.206276 -304.094619) (xy 64.183405 -304.138196)
			(xy 64.15384 -304.17754) (xy 64.118347 -304.211632) (xy 64.077844 -304.239588) (xy 64.033382 -304.260686)
			(xy 63.986111 -304.274378) (xy 63.937256 -304.28031) (xy 63.888081 -304.278329) (xy 63.839862 -304.268485)
			(xy 63.793846 -304.251033) (xy 63.751225 -304.226426) (xy 63.713104 -304.195301) (xy 63.680469 -304.158464)
			(xy 63.654166 -304.116868) (xy 63.634875 -304.071592) (xy 63.623098 -304.023808) (xy 63.619138 -303.974754)
			(xy 63.28029 -303.974754) (xy 63.279795 -303.999361) (xy 63.2719 -304.047938) (xy 63.256316 -304.094619)
			(xy 63.233445 -304.138196) (xy 63.20388 -304.17754) (xy 63.168387 -304.211632) (xy 63.127884 -304.239588)
			(xy 63.083422 -304.260686) (xy 63.036151 -304.274378) (xy 62.987296 -304.28031) (xy 62.938121 -304.278329)
			(xy 62.889902 -304.268485) (xy 62.843886 -304.251033) (xy 62.801265 -304.226426) (xy 62.763144 -304.195301)
			(xy 62.730509 -304.158464) (xy 62.704206 -304.116868) (xy 62.684915 -304.071592) (xy 62.673138 -304.023808)
			(xy 62.669178 -303.974754) (xy 62.330076 -303.974754) (xy 62.329581 -303.999361) (xy 62.321686 -304.047938)
			(xy 62.306102 -304.094619) (xy 62.283231 -304.138196) (xy 62.253666 -304.17754) (xy 62.218173 -304.211632)
			(xy 62.17767 -304.239588) (xy 62.133208 -304.260686) (xy 62.085937 -304.274378) (xy 62.037082 -304.28031)
			(xy 61.987907 -304.278329) (xy 61.939688 -304.268485) (xy 61.893672 -304.251033) (xy 61.851051 -304.226426)
			(xy 61.81293 -304.195301) (xy 61.780295 -304.158464) (xy 61.753992 -304.116868) (xy 61.734701 -304.071592)
			(xy 61.722924 -304.023808) (xy 61.718964 -303.974754) (xy 61.380116 -303.974754) (xy 61.379621 -303.999361)
			(xy 61.371726 -304.047938) (xy 61.356142 -304.094619) (xy 61.333271 -304.138196) (xy 61.303706 -304.17754)
			(xy 61.268213 -304.211632) (xy 61.22771 -304.239588) (xy 61.183248 -304.260686) (xy 61.135977 -304.274378)
			(xy 61.087122 -304.28031) (xy 61.037947 -304.278329) (xy 60.989728 -304.268485) (xy 60.943712 -304.251033)
			(xy 60.901091 -304.226426) (xy 60.86297 -304.195301) (xy 60.830335 -304.158464) (xy 60.804032 -304.116868)
			(xy 60.784741 -304.071592) (xy 60.772964 -304.023808) (xy 60.769004 -303.974754) (xy 60.430156 -303.974754)
			(xy 60.429661 -303.999361) (xy 60.421766 -304.047938) (xy 60.406182 -304.094619) (xy 60.383311 -304.138196)
			(xy 60.353746 -304.17754) (xy 60.318253 -304.211632) (xy 60.27775 -304.239588) (xy 60.233288 -304.260686)
			(xy 60.186017 -304.274378) (xy 60.137162 -304.28031) (xy 60.087987 -304.278329) (xy 60.039768 -304.268485)
			(xy 59.993752 -304.251033) (xy 59.951131 -304.226426) (xy 59.91301 -304.195301) (xy 59.880375 -304.158464)
			(xy 59.854072 -304.116868) (xy 59.834781 -304.071592) (xy 59.823004 -304.023808) (xy 59.819044 -303.974754)
			(xy 58.530236 -303.974754) (xy 58.529741 -303.999361) (xy 58.521846 -304.047938) (xy 58.506262 -304.094619)
			(xy 58.483391 -304.138196) (xy 58.453826 -304.17754) (xy 58.418333 -304.211632) (xy 58.37783 -304.239588)
			(xy 58.333368 -304.260686) (xy 58.286097 -304.274378) (xy 58.237242 -304.28031) (xy 58.188067 -304.278329)
			(xy 58.139848 -304.268485) (xy 58.093832 -304.251033) (xy 58.051211 -304.226426) (xy 58.01309 -304.195301)
			(xy 57.980455 -304.158464) (xy 57.954152 -304.116868) (xy 57.934861 -304.071592) (xy 57.923084 -304.023808)
			(xy 57.919124 -303.974754) (xy 57.580276 -303.974754) (xy 57.579781 -303.999361) (xy 57.571886 -304.047938)
			(xy 57.556302 -304.094619) (xy 57.533431 -304.138196) (xy 57.503866 -304.17754) (xy 57.468373 -304.211632)
			(xy 57.42787 -304.239588) (xy 57.383408 -304.260686) (xy 57.336137 -304.274378) (xy 57.287282 -304.28031)
			(xy 57.238107 -304.278329) (xy 57.189888 -304.268485) (xy 57.143872 -304.251033) (xy 57.101251 -304.226426)
			(xy 57.06313 -304.195301) (xy 57.030495 -304.158464) (xy 57.004192 -304.116868) (xy 56.984901 -304.071592)
			(xy 56.973124 -304.023808) (xy 56.969164 -303.974754) (xy 56.630062 -303.974754) (xy 56.629567 -303.999361)
			(xy 56.621672 -304.047938) (xy 56.606088 -304.094619) (xy 56.583217 -304.138196) (xy 56.553652 -304.17754)
			(xy 56.518159 -304.211632) (xy 56.477656 -304.239588) (xy 56.433194 -304.260686) (xy 56.385923 -304.274378)
			(xy 56.337068 -304.28031) (xy 56.287893 -304.278329) (xy 56.239674 -304.268485) (xy 56.193658 -304.251033)
			(xy 56.151037 -304.226426) (xy 56.112916 -304.195301) (xy 56.080281 -304.158464) (xy 56.053978 -304.116868)
			(xy 56.034687 -304.071592) (xy 56.02291 -304.023808) (xy 56.01895 -303.974754) (xy 55.680102 -303.974754)
			(xy 55.679607 -303.999361) (xy 55.671712 -304.047938) (xy 55.656128 -304.094619) (xy 55.633257 -304.138196)
			(xy 55.603692 -304.17754) (xy 55.568199 -304.211632) (xy 55.527696 -304.239588) (xy 55.483234 -304.260686)
			(xy 55.435963 -304.274378) (xy 55.387108 -304.28031) (xy 55.337933 -304.278329) (xy 55.289714 -304.268485)
			(xy 55.243698 -304.251033) (xy 55.201077 -304.226426) (xy 55.162956 -304.195301) (xy 55.130321 -304.158464)
			(xy 55.104018 -304.116868) (xy 55.084727 -304.071592) (xy 55.07295 -304.023808) (xy 55.06899 -303.974754)
			(xy 54.730142 -303.974754) (xy 54.729647 -303.999361) (xy 54.721752 -304.047938) (xy 54.706168 -304.094619)
			(xy 54.683297 -304.138196) (xy 54.653732 -304.17754) (xy 54.618239 -304.211632) (xy 54.577736 -304.239588)
			(xy 54.533274 -304.260686) (xy 54.486003 -304.274378) (xy 54.437148 -304.28031) (xy 54.387973 -304.278329)
			(xy 54.339754 -304.268485) (xy 54.293738 -304.251033) (xy 54.251117 -304.226426) (xy 54.212996 -304.195301)
			(xy 54.180361 -304.158464) (xy 54.154058 -304.116868) (xy 54.134767 -304.071592) (xy 54.12299 -304.023808)
			(xy 54.11903 -303.974754) (xy 53.780182 -303.974754) (xy 53.779687 -303.999361) (xy 53.771792 -304.047938)
			(xy 53.756208 -304.094619) (xy 53.733337 -304.138196) (xy 53.703772 -304.17754) (xy 53.668279 -304.211632)
			(xy 53.627776 -304.239588) (xy 53.583314 -304.260686) (xy 53.536043 -304.274378) (xy 53.487188 -304.28031)
			(xy 53.438013 -304.278329) (xy 53.389794 -304.268485) (xy 53.343778 -304.251033) (xy 53.301157 -304.226426)
			(xy 53.263036 -304.195301) (xy 53.230401 -304.158464) (xy 53.204098 -304.116868) (xy 53.184807 -304.071592)
			(xy 53.17303 -304.023808) (xy 53.16907 -303.974754) (xy 52.830222 -303.974754) (xy 52.829727 -303.999361)
			(xy 52.821832 -304.047938) (xy 52.806248 -304.094619) (xy 52.783377 -304.138196) (xy 52.753812 -304.17754)
			(xy 52.718319 -304.211632) (xy 52.677816 -304.239588) (xy 52.633354 -304.260686) (xy 52.586083 -304.274378)
			(xy 52.537228 -304.28031) (xy 52.488053 -304.278329) (xy 52.439834 -304.268485) (xy 52.393818 -304.251033)
			(xy 52.351197 -304.226426) (xy 52.313076 -304.195301) (xy 52.280441 -304.158464) (xy 52.254138 -304.116868)
			(xy 52.234847 -304.071592) (xy 52.22307 -304.023808) (xy 52.21911 -303.974754) (xy 51.880262 -303.974754)
			(xy 51.879767 -303.999361) (xy 51.871872 -304.047938) (xy 51.856288 -304.094619) (xy 51.833417 -304.138196)
			(xy 51.803852 -304.17754) (xy 51.768359 -304.211632) (xy 51.727856 -304.239588) (xy 51.683394 -304.260686)
			(xy 51.636123 -304.274378) (xy 51.587268 -304.28031) (xy 51.538093 -304.278329) (xy 51.489874 -304.268485)
			(xy 51.443858 -304.251033) (xy 51.401237 -304.226426) (xy 51.363116 -304.195301) (xy 51.330481 -304.158464)
			(xy 51.304178 -304.116868) (xy 51.284887 -304.071592) (xy 51.27311 -304.023808) (xy 51.26915 -303.974754)
			(xy 50.930302 -303.974754) (xy 50.929807 -303.999361) (xy 50.921912 -304.047938) (xy 50.906328 -304.094619)
			(xy 50.883457 -304.138196) (xy 50.853892 -304.17754) (xy 50.818399 -304.211632) (xy 50.777896 -304.239588)
			(xy 50.733434 -304.260686) (xy 50.686163 -304.274378) (xy 50.637308 -304.28031) (xy 50.588133 -304.278329)
			(xy 50.539914 -304.268485) (xy 50.493898 -304.251033) (xy 50.451277 -304.226426) (xy 50.413156 -304.195301)
			(xy 50.380521 -304.158464) (xy 50.354218 -304.116868) (xy 50.334927 -304.071592) (xy 50.32315 -304.023808)
			(xy 50.31919 -303.974754) (xy 49.980088 -303.974754) (xy 49.979593 -303.999361) (xy 49.971698 -304.047938)
			(xy 49.956114 -304.094619) (xy 49.933243 -304.138196) (xy 49.903678 -304.17754) (xy 49.868185 -304.211632)
			(xy 49.827682 -304.239588) (xy 49.78322 -304.260686) (xy 49.735949 -304.274378) (xy 49.687094 -304.28031)
			(xy 49.637919 -304.278329) (xy 49.5897 -304.268485) (xy 49.543684 -304.251033) (xy 49.501063 -304.226426)
			(xy 49.462942 -304.195301) (xy 49.430307 -304.158464) (xy 49.404004 -304.116868) (xy 49.384713 -304.071592)
			(xy 49.372936 -304.023808) (xy 49.368976 -303.974754) (xy 49.030128 -303.974754) (xy 49.029633 -303.999361)
			(xy 49.021738 -304.047938) (xy 49.006154 -304.094619) (xy 48.983283 -304.138196) (xy 48.953718 -304.17754)
			(xy 48.918225 -304.211632) (xy 48.877722 -304.239588) (xy 48.83326 -304.260686) (xy 48.785989 -304.274378)
			(xy 48.737134 -304.28031) (xy 48.687959 -304.278329) (xy 48.63974 -304.268485) (xy 48.593724 -304.251033)
			(xy 48.551103 -304.226426) (xy 48.512982 -304.195301) (xy 48.480347 -304.158464) (xy 48.454044 -304.116868)
			(xy 48.434753 -304.071592) (xy 48.422976 -304.023808) (xy 48.419016 -303.974754) (xy 48.080119 -303.974754)
			(xy 48.080572 -303.983122) (xy 48.075199 -304.032465) (xy 48.061914 -304.080288) (xy 48.041067 -304.125332)
			(xy 48.013207 -304.166409) (xy 47.979069 -304.202439) (xy 47.939552 -304.232471) (xy 47.895696 -304.255714)
			(xy 47.848658 -304.271556) (xy 47.799677 -304.27958) (xy 47.77486 -304.280062) (xy 47.760677 -304.279892)
			(xy 47.732437 -304.277215) (xy 47.718472 -304.274728) (xy 47.706026 -304.272442) (xy 47.682404 -304.279808)
			(xy 47.604934 -304.357278) (xy 47.597568 -304.3809) (xy 47.599854 -304.393346) (xy 47.602332 -304.407312)
			(xy 47.605003 -304.435551) (xy 47.605188 -304.449734) (xy 47.605016 -304.463917) (xy 47.602341 -304.492157)
			(xy 47.599854 -304.506122) (xy 47.597568 -304.518568) (xy 47.604934 -304.54219) (xy 47.682404 -304.61966)
			(xy 47.706026 -304.627026) (xy 47.718472 -304.62474) (xy 47.732437 -304.622258) (xy 47.760677 -304.61959)
			(xy 47.77486 -304.619406) (xy 47.799685 -304.619835) (xy 47.848681 -304.627861) (xy 47.895733 -304.643708)
			(xy 47.939601 -304.666959) (xy 47.97913 -304.697) (xy 48.013278 -304.733041) (xy 48.041145 -304.774132)
			(xy 48.061997 -304.81919) (xy 48.075285 -304.867028) (xy 48.080658 -304.916386) (xy 48.080207 -304.924714)
			(xy 48.419016 -304.924714) (xy 48.422976 -304.87566) (xy 48.434753 -304.827876) (xy 48.454044 -304.7826)
			(xy 48.480347 -304.741004) (xy 48.512982 -304.704167) (xy 48.551103 -304.673042) (xy 48.593724 -304.648435)
			(xy 48.63974 -304.630983) (xy 48.687959 -304.621139) (xy 48.737134 -304.619158) (xy 48.785989 -304.62509)
			(xy 48.83326 -304.638782) (xy 48.877722 -304.65988) (xy 48.918225 -304.687836) (xy 48.953718 -304.721928)
			(xy 48.983283 -304.761272) (xy 49.006154 -304.804849) (xy 49.021738 -304.85153) (xy 49.029633 -304.900107)
			(xy 49.030128 -304.924714) (xy 49.368976 -304.924714) (xy 49.372936 -304.87566) (xy 49.384713 -304.827876)
			(xy 49.404004 -304.7826) (xy 49.430307 -304.741004) (xy 49.462942 -304.704167) (xy 49.501063 -304.673042)
			(xy 49.543684 -304.648435) (xy 49.5897 -304.630983) (xy 49.637919 -304.621139) (xy 49.687094 -304.619158)
			(xy 49.735949 -304.62509) (xy 49.78322 -304.638782) (xy 49.827682 -304.65988) (xy 49.868185 -304.687836)
			(xy 49.903678 -304.721928) (xy 49.933243 -304.761272) (xy 49.956114 -304.804849) (xy 49.971698 -304.85153)
			(xy 49.979593 -304.900107) (xy 49.980088 -304.924714) (xy 68.368938 -304.924714) (xy 68.372898 -304.87566)
			(xy 68.384675 -304.827876) (xy 68.403966 -304.7826) (xy 68.430269 -304.741004) (xy 68.462904 -304.704167)
			(xy 68.501025 -304.673042) (xy 68.543646 -304.648435) (xy 68.589662 -304.630983) (xy 68.637881 -304.621139)
			(xy 68.687056 -304.619158) (xy 68.735911 -304.62509) (xy 68.783182 -304.638782) (xy 68.827644 -304.65988)
			(xy 68.868147 -304.687836) (xy 68.90364 -304.721928) (xy 68.933205 -304.761272) (xy 68.956076 -304.804849)
			(xy 68.97166 -304.85153) (xy 68.979555 -304.900107) (xy 68.98005 -304.924714) (xy 69.319152 -304.924714)
			(xy 69.323112 -304.87566) (xy 69.334889 -304.827876) (xy 69.35418 -304.7826) (xy 69.380483 -304.741004)
			(xy 69.413118 -304.704167) (xy 69.451239 -304.673042) (xy 69.49386 -304.648435) (xy 69.539876 -304.630983)
			(xy 69.588095 -304.621139) (xy 69.63727 -304.619158) (xy 69.686125 -304.62509) (xy 69.733396 -304.638782)
			(xy 69.777858 -304.65988) (xy 69.818361 -304.687836) (xy 69.853854 -304.721928) (xy 69.883419 -304.761272)
			(xy 69.90629 -304.804849) (xy 69.921874 -304.85153) (xy 69.929769 -304.900107) (xy 69.930264 -304.924714)
			(xy 70.269112 -304.924714) (xy 70.273072 -304.87566) (xy 70.284849 -304.827876) (xy 70.30414 -304.7826)
			(xy 70.330443 -304.741004) (xy 70.363078 -304.704167) (xy 70.401199 -304.673042) (xy 70.44382 -304.648435)
			(xy 70.489836 -304.630983) (xy 70.538055 -304.621139) (xy 70.58723 -304.619158) (xy 70.636085 -304.62509)
			(xy 70.683356 -304.638782) (xy 70.727818 -304.65988) (xy 70.768321 -304.687836) (xy 70.803814 -304.721928)
			(xy 70.833379 -304.761272) (xy 70.85625 -304.804849) (xy 70.871834 -304.85153) (xy 70.879729 -304.900107)
			(xy 70.880224 -304.924714) (xy 71.219072 -304.924714) (xy 71.223032 -304.87566) (xy 71.234809 -304.827876)
			(xy 71.2541 -304.7826) (xy 71.280403 -304.741004) (xy 71.313038 -304.704167) (xy 71.351159 -304.673042)
			(xy 71.39378 -304.648435) (xy 71.439796 -304.630983) (xy 71.488015 -304.621139) (xy 71.53719 -304.619158)
			(xy 71.586045 -304.62509) (xy 71.633316 -304.638782) (xy 71.677778 -304.65988) (xy 71.718281 -304.687836)
			(xy 71.753774 -304.721928) (xy 71.783339 -304.761272) (xy 71.80621 -304.804849) (xy 71.821794 -304.85153)
			(xy 71.829689 -304.900107) (xy 71.830184 -304.924714) (xy 71.829689 -304.949321) (xy 71.821794 -304.997898)
			(xy 71.80621 -305.044579) (xy 71.783339 -305.088156) (xy 71.753774 -305.1275) (xy 71.718281 -305.161592)
			(xy 71.677778 -305.189548) (xy 71.633316 -305.210646) (xy 71.586045 -305.224338) (xy 71.53719 -305.23027)
			(xy 71.488015 -305.228289) (xy 71.439796 -305.218445) (xy 71.39378 -305.200993) (xy 71.351159 -305.176386)
			(xy 71.313038 -305.145261) (xy 71.280403 -305.108424) (xy 71.2541 -305.066828) (xy 71.234809 -305.021552)
			(xy 71.223032 -304.973768) (xy 71.219072 -304.924714) (xy 70.880224 -304.924714) (xy 70.879729 -304.949321)
			(xy 70.871834 -304.997898) (xy 70.85625 -305.044579) (xy 70.833379 -305.088156) (xy 70.803814 -305.1275)
			(xy 70.768321 -305.161592) (xy 70.727818 -305.189548) (xy 70.683356 -305.210646) (xy 70.636085 -305.224338)
			(xy 70.58723 -305.23027) (xy 70.538055 -305.228289) (xy 70.489836 -305.218445) (xy 70.44382 -305.200993)
			(xy 70.401199 -305.176386) (xy 70.363078 -305.145261) (xy 70.330443 -305.108424) (xy 70.30414 -305.066828)
			(xy 70.284849 -305.021552) (xy 70.273072 -304.973768) (xy 70.269112 -304.924714) (xy 69.930264 -304.924714)
			(xy 69.929769 -304.949321) (xy 69.921874 -304.997898) (xy 69.90629 -305.044579) (xy 69.883419 -305.088156)
			(xy 69.853854 -305.1275) (xy 69.818361 -305.161592) (xy 69.777858 -305.189548) (xy 69.733396 -305.210646)
			(xy 69.686125 -305.224338) (xy 69.63727 -305.23027) (xy 69.588095 -305.228289) (xy 69.539876 -305.218445)
			(xy 69.49386 -305.200993) (xy 69.451239 -305.176386) (xy 69.413118 -305.145261) (xy 69.380483 -305.108424)
			(xy 69.35418 -305.066828) (xy 69.334889 -305.021552) (xy 69.323112 -304.973768) (xy 69.319152 -304.924714)
			(xy 68.98005 -304.924714) (xy 68.979555 -304.949321) (xy 68.97166 -304.997898) (xy 68.956076 -305.044579)
			(xy 68.933205 -305.088156) (xy 68.90364 -305.1275) (xy 68.868147 -305.161592) (xy 68.827644 -305.189548)
			(xy 68.783182 -305.210646) (xy 68.735911 -305.224338) (xy 68.687056 -305.23027) (xy 68.637881 -305.228289)
			(xy 68.589662 -305.218445) (xy 68.543646 -305.200993) (xy 68.501025 -305.176386) (xy 68.462904 -305.145261)
			(xy 68.430269 -305.108424) (xy 68.403966 -305.066828) (xy 68.384675 -305.021552) (xy 68.372898 -304.973768)
			(xy 68.368938 -304.924714) (xy 49.980088 -304.924714) (xy 49.979593 -304.949321) (xy 49.971698 -304.997898)
			(xy 49.956114 -305.044579) (xy 49.933243 -305.088156) (xy 49.903678 -305.1275) (xy 49.868185 -305.161592)
			(xy 49.827682 -305.189548) (xy 49.78322 -305.210646) (xy 49.735949 -305.224338) (xy 49.687094 -305.23027)
			(xy 49.637919 -305.228289) (xy 49.5897 -305.218445) (xy 49.543684 -305.200993) (xy 49.501063 -305.176386)
			(xy 49.462942 -305.145261) (xy 49.430307 -305.108424) (xy 49.404004 -305.066828) (xy 49.384713 -305.021552)
			(xy 49.372936 -304.973768) (xy 49.368976 -304.924714) (xy 49.030128 -304.924714) (xy 49.029633 -304.949321)
			(xy 49.021738 -304.997898) (xy 49.006154 -305.044579) (xy 48.983283 -305.088156) (xy 48.953718 -305.1275)
			(xy 48.918225 -305.161592) (xy 48.877722 -305.189548) (xy 48.83326 -305.210646) (xy 48.785989 -305.224338)
			(xy 48.737134 -305.23027) (xy 48.687959 -305.228289) (xy 48.63974 -305.218445) (xy 48.593724 -305.200993)
			(xy 48.551103 -305.176386) (xy 48.512982 -305.145261) (xy 48.480347 -305.108424) (xy 48.454044 -305.066828)
			(xy 48.434753 -305.021552) (xy 48.422976 -304.973768) (xy 48.419016 -304.924714) (xy 48.080207 -304.924714)
			(xy 48.077975 -304.965962) (xy 48.067307 -305.014452) (xy 48.048934 -305.060576) (xy 48.023341 -305.103121)
			(xy 47.991203 -305.140964) (xy 47.953365 -305.17311) (xy 47.910825 -305.19871) (xy 47.864703 -305.217091)
			(xy 47.816216 -305.227768) (xy 47.76664 -305.230459) (xy 47.717281 -305.225095) (xy 47.669441 -305.211816)
			(xy 47.624379 -305.190972) (xy 47.583284 -305.163112) (xy 47.547236 -305.12897) (xy 47.517188 -305.089447)
			(xy 47.493929 -305.045582) (xy 47.478074 -304.998533) (xy 47.470039 -304.949539) (xy 47.469552 -304.924714)
			(xy 47.469731 -304.910531) (xy 47.472402 -304.882291) (xy 47.474886 -304.868326) (xy 47.477172 -304.85588)
			(xy 47.469806 -304.832258) (xy 47.392336 -304.754788) (xy 47.368714 -304.747422) (xy 47.356268 -304.749708)
			(xy 47.342302 -304.752185) (xy 47.314063 -304.754856) (xy 47.29988 -304.755042) (xy 47.27589 -304.754556)
			(xy 47.228501 -304.747048) (xy 47.182869 -304.73222) (xy 47.140119 -304.710437) (xy 47.101302 -304.682235)
			(xy 47.067374 -304.648309) (xy 47.039171 -304.609493) (xy 47.017385 -304.566744) (xy 47.002555 -304.521113)
			(xy 46.995045 -304.473724) (xy 46.994572 -304.449734) (xy 46.994754 -304.435551) (xy 46.997422 -304.407311)
			(xy 46.999906 -304.393346) (xy 47.002192 -304.3809) (xy 46.994826 -304.357278) (xy 46.917356 -304.279808)
			(xy 46.893734 -304.272442) (xy 46.881288 -304.274728) (xy 46.867322 -304.277202) (xy 46.839082 -304.279876)
			(xy 46.8249 -304.280062) (xy 46.810717 -304.279886) (xy 46.782477 -304.277214) (xy 46.768512 -304.274728)
			(xy 46.756066 -304.272442) (xy 46.732444 -304.279808) (xy 46.654974 -304.357278) (xy 46.647608 -304.3809)
			(xy 46.649894 -304.393346) (xy 46.652373 -304.407312) (xy 46.655043 -304.435551) (xy 46.655228 -304.449734)
			(xy 46.654685 -304.474552) (xy 46.64665 -304.523533) (xy 46.630796 -304.570568) (xy 46.607542 -304.61442)
			(xy 46.577499 -304.653931) (xy 46.54146 -304.688062) (xy 46.500375 -304.715913) (xy 46.455324 -304.73675)
			(xy 46.407497 -304.750024) (xy 46.358151 -304.755386) (xy 46.308589 -304.752694) (xy 46.260114 -304.742019)
			(xy 46.214006 -304.723643) (xy 46.171477 -304.698049) (xy 46.13365 -304.665912) (xy 46.10152 -304.628079)
			(xy 46.075933 -304.585546) (xy 46.057565 -304.539434) (xy 46.046899 -304.490958) (xy 46.044216 -304.441395)
			(xy 45.7051 -304.441395) (xy 45.705268 -304.449734) (xy 45.704773 -304.474341) (xy 45.696878 -304.522918)
			(xy 45.681294 -304.569599) (xy 45.658423 -304.613176) (xy 45.628858 -304.65252) (xy 45.593365 -304.686612)
			(xy 45.552862 -304.714568) (xy 45.5084 -304.735666) (xy 45.461129 -304.749358) (xy 45.412274 -304.75529)
			(xy 45.363099 -304.753309) (xy 45.31488 -304.743465) (xy 45.268864 -304.726013) (xy 45.226243 -304.701406)
			(xy 45.188122 -304.670281) (xy 45.155487 -304.633444) (xy 45.129184 -304.591848) (xy 45.109893 -304.546572)
			(xy 45.098116 -304.498788) (xy 45.094156 -304.449734) (xy 44.776898 -304.449734) (xy 44.776394 -304.475442)
			(xy 44.768351 -304.526224) (xy 44.752463 -304.575123) (xy 44.72912 -304.620935) (xy 44.698899 -304.662531)
			(xy 44.662543 -304.698887) (xy 44.620947 -304.729108) (xy 44.575135 -304.752451) (xy 44.526236 -304.768339)
			(xy 44.475454 -304.776382) (xy 44.424038 -304.776382) (xy 44.373256 -304.768339) (xy 44.324357 -304.752451)
			(xy 44.278545 -304.729108) (xy 44.236949 -304.698887) (xy 44.200593 -304.662531) (xy 44.170372 -304.620935)
			(xy 44.147029 -304.575123) (xy 44.131141 -304.526224) (xy 44.123098 -304.475442) (xy 43.826434 -304.475442)
			(xy 43.818391 -304.526224) (xy 43.802503 -304.575123) (xy 43.77916 -304.620935) (xy 43.748939 -304.662531)
			(xy 43.712583 -304.698887) (xy 43.670987 -304.729108) (xy 43.625175 -304.752451) (xy 43.576276 -304.768339)
			(xy 43.525494 -304.776382) (xy 43.474078 -304.776382) (xy 43.423296 -304.768339) (xy 43.374397 -304.752451)
			(xy 43.328585 -304.729108) (xy 43.286989 -304.698887) (xy 43.250633 -304.662531) (xy 43.220412 -304.620935)
			(xy 43.197069 -304.575123) (xy 43.181181 -304.526224) (xy 43.173138 -304.475442) (xy 42.85446 -304.475442)
			(xy 42.846744 -304.522918) (xy 42.83116 -304.569599) (xy 42.808289 -304.613176) (xy 42.778724 -304.65252)
			(xy 42.743231 -304.686612) (xy 42.702728 -304.714568) (xy 42.658266 -304.735666) (xy 42.610995 -304.749358)
			(xy 42.56214 -304.75529) (xy 42.512965 -304.753309) (xy 42.464746 -304.743465) (xy 42.41873 -304.726013)
			(xy 42.376109 -304.701406) (xy 42.337988 -304.670281) (xy 42.305353 -304.633444) (xy 42.27905 -304.591848)
			(xy 42.259759 -304.546572) (xy 42.247982 -304.498788) (xy 42.244022 -304.449734) (xy 41.905174 -304.449734)
			(xy 41.904679 -304.474341) (xy 41.896784 -304.522918) (xy 41.8812 -304.569599) (xy 41.858329 -304.613176)
			(xy 41.828764 -304.65252) (xy 41.793271 -304.686612) (xy 41.752768 -304.714568) (xy 41.708306 -304.735666)
			(xy 41.661035 -304.749358) (xy 41.61218 -304.75529) (xy 41.563005 -304.753309) (xy 41.514786 -304.743465)
			(xy 41.46877 -304.726013) (xy 41.426149 -304.701406) (xy 41.388028 -304.670281) (xy 41.355393 -304.633444)
			(xy 41.32909 -304.591848) (xy 41.309799 -304.546572) (xy 41.298022 -304.498788) (xy 41.294062 -304.449734)
			(xy 40.955214 -304.449734) (xy 40.954719 -304.474341) (xy 40.946824 -304.522918) (xy 40.93124 -304.569599)
			(xy 40.908369 -304.613176) (xy 40.878804 -304.65252) (xy 40.843311 -304.686612) (xy 40.802808 -304.714568)
			(xy 40.758346 -304.735666) (xy 40.711075 -304.749358) (xy 40.66222 -304.75529) (xy 40.613045 -304.753309)
			(xy 40.564826 -304.743465) (xy 40.51881 -304.726013) (xy 40.476189 -304.701406) (xy 40.438068 -304.670281)
			(xy 40.405433 -304.633444) (xy 40.37913 -304.591848) (xy 40.359839 -304.546572) (xy 40.348062 -304.498788)
			(xy 40.344102 -304.449734) (xy 40.005254 -304.449734) (xy 40.004759 -304.474341) (xy 39.996864 -304.522918)
			(xy 39.98128 -304.569599) (xy 39.958409 -304.613176) (xy 39.928844 -304.65252) (xy 39.893351 -304.686612)
			(xy 39.852848 -304.714568) (xy 39.808386 -304.735666) (xy 39.761115 -304.749358) (xy 39.71226 -304.75529)
			(xy 39.663085 -304.753309) (xy 39.614866 -304.743465) (xy 39.56885 -304.726013) (xy 39.526229 -304.701406)
			(xy 39.488108 -304.670281) (xy 39.455473 -304.633444) (xy 39.42917 -304.591848) (xy 39.409879 -304.546572)
			(xy 39.398102 -304.498788) (xy 39.394142 -304.449734) (xy 39.055294 -304.449734) (xy 39.054799 -304.474341)
			(xy 39.046904 -304.522918) (xy 39.03132 -304.569599) (xy 39.008449 -304.613176) (xy 38.978884 -304.65252)
			(xy 38.943391 -304.686612) (xy 38.902888 -304.714568) (xy 38.858426 -304.735666) (xy 38.811155 -304.749358)
			(xy 38.7623 -304.75529) (xy 38.713125 -304.753309) (xy 38.664906 -304.743465) (xy 38.61889 -304.726013)
			(xy 38.576269 -304.701406) (xy 38.538148 -304.670281) (xy 38.505513 -304.633444) (xy 38.47921 -304.591848)
			(xy 38.459919 -304.546572) (xy 38.448142 -304.498788) (xy 38.444182 -304.449734) (xy 38.126924 -304.449734)
			(xy 38.12642 -304.475442) (xy 38.118377 -304.526224) (xy 38.102489 -304.575123) (xy 38.079146 -304.620935)
			(xy 38.048925 -304.662531) (xy 38.012569 -304.698887) (xy 37.970973 -304.729108) (xy 37.925161 -304.752451)
			(xy 37.876262 -304.768339) (xy 37.82548 -304.776382) (xy 37.774064 -304.776382) (xy 37.723282 -304.768339)
			(xy 37.674383 -304.752451) (xy 37.628571 -304.729108) (xy 37.586975 -304.698887) (xy 37.550619 -304.662531)
			(xy 37.520398 -304.620935) (xy 37.497055 -304.575123) (xy 37.481167 -304.526224) (xy 37.473124 -304.475442)
			(xy 37.17646 -304.475442) (xy 37.168417 -304.526224) (xy 37.152529 -304.575123) (xy 37.129186 -304.620935)
			(xy 37.098965 -304.662531) (xy 37.062609 -304.698887) (xy 37.021013 -304.729108) (xy 36.975201 -304.752451)
			(xy 36.926302 -304.768339) (xy 36.87552 -304.776382) (xy 36.824104 -304.776382) (xy 36.773322 -304.768339)
			(xy 36.724423 -304.752451) (xy 36.678611 -304.729108) (xy 36.637015 -304.698887) (xy 36.600659 -304.662531)
			(xy 36.570438 -304.620935) (xy 36.547095 -304.575123) (xy 36.531207 -304.526224) (xy 36.523164 -304.475442)
			(xy 36.204273 -304.475442) (xy 36.196516 -304.523172) (xy 36.180932 -304.569853) (xy 36.158061 -304.61343)
			(xy 36.128496 -304.652774) (xy 36.093003 -304.686866) (xy 36.0525 -304.714822) (xy 36.008038 -304.73592)
			(xy 35.960767 -304.749612) (xy 35.911912 -304.755544) (xy 35.862737 -304.753563) (xy 35.814518 -304.743719)
			(xy 35.768502 -304.726267) (xy 35.725881 -304.70166) (xy 35.68776 -304.670535) (xy 35.655125 -304.633698)
			(xy 35.628822 -304.592102) (xy 35.609531 -304.546826) (xy 35.597754 -304.499042) (xy 35.593794 -304.449988)
			(xy 21.660189 -304.449988) (xy 21.654463 -304.452993) (xy 21.505695 -304.522122) (xy 21.353761 -304.583982)
			(xy 21.199015 -304.63843) (xy 21.04182 -304.685339) (xy 20.882541 -304.724597) (xy 20.721553 -304.756115)
			(xy 20.559229 -304.779818) (xy 20.39595 -304.795651) (xy 20.232097 -304.803576) (xy 20.150074 -304.804064)
			(xy 20.14982 -304.804064) (xy 20.068368 -304.803581) (xy 19.905652 -304.795764) (xy 19.743498 -304.78015)
			(xy 19.58228 -304.756774) (xy 19.422369 -304.725691) (xy 19.264134 -304.686971) (xy 19.107938 -304.640706)
			(xy 18.954141 -304.587) (xy 18.803099 -304.525977) (xy 18.655157 -304.457778) (xy 18.510658 -304.382561)
			(xy 18.369934 -304.300498) (xy 18.233309 -304.211778) (xy 18.101097 -304.116606) (xy 17.973604 -304.0152)
			(xy 17.851122 -303.907795) (xy 17.792192 -303.851564) (xy 17.770602 -303.830736) (xy 17.765968 -303.830952)
			(xy 17.756892 -303.832865) (xy 17.752568 -303.834546) (xy 17.663414 -303.872646) (xy 17.655552 -303.876991)
			(xy 17.64328 -303.890092) (xy 17.636284 -303.906625) (xy 17.635474 -303.915572) (xy 17.635474 -304.80635)
			(xy 17.63607 -304.818675) (xy 17.647521 -304.840503) (xy 17.657318 -304.848006) (xy 17.66316 -304.851562)
			(xy 17.743678 -304.892456) (xy 17.748179 -304.894594) (xy 17.757772 -304.897282) (xy 17.762728 -304.89779)
			(xy 17.770856 -304.89779) (xy 17.776916 -304.897137) (xy 17.788473 -304.893279) (xy 17.793716 -304.89017)
			(xy 17.796764 -304.888138) (xy 17.821337 -304.871093) (xy 17.87467 -304.844045) (xy 17.931568 -304.82564)
			(xy 17.990638 -304.816326) (xy 18.020538 -304.815748) (xy 18.047809 -304.816211) (xy 18.101796 -304.823973)
			(xy 18.154129 -304.839339) (xy 18.203743 -304.861997) (xy 18.249626 -304.891484) (xy 18.290847 -304.927202)
			(xy 18.326564 -304.968422) (xy 18.356052 -305.014306) (xy 18.37871 -305.063919) (xy 18.394076 -305.116252)
			(xy 18.401839 -305.170239) (xy 18.401839 -305.224781) (xy 18.394076 -305.278768) (xy 18.37871 -305.331101)
			(xy 18.377312 -305.334162) (xy 27.409392 -305.334162) (xy 27.413463 -305.27854) (xy 27.425589 -305.224103)
			(xy 27.445512 -305.172012) (xy 27.472808 -305.123377) (xy 27.506894 -305.079234) (xy 27.547043 -305.040525)
			(xy 27.592401 -305.008074) (xy 27.642001 -304.982573) (xy 27.694785 -304.964566) (xy 27.749628 -304.954436)
			(xy 27.805362 -304.952399) (xy 27.860799 -304.958499) (xy 27.914756 -304.972605) (xy 27.966085 -304.994417)
			(xy 28.013691 -305.023471) (xy 28.056559 -305.059146) (xy 28.093776 -305.100683) (xy 28.124549 -305.147196)
			(xy 28.148221 -305.197693) (xy 28.164289 -305.2511) (xy 28.172409 -305.306276) (xy 28.172918 -305.334162)
			(xy 28.172409 -305.362048) (xy 28.166831 -305.399948) (xy 36.544008 -305.399948) (xy 36.547968 -305.350894)
			(xy 36.559745 -305.30311) (xy 36.579036 -305.257834) (xy 36.605339 -305.216238) (xy 36.637974 -305.179401)
			(xy 36.676095 -305.148276) (xy 36.718716 -305.123669) (xy 36.764732 -305.106217) (xy 36.812951 -305.096373)
			(xy 36.862126 -305.094392) (xy 36.910981 -305.100324) (xy 36.958252 -305.114016) (xy 37.002714 -305.135114)
			(xy 37.043217 -305.16307) (xy 37.07871 -305.197162) (xy 37.108275 -305.236506) (xy 37.131146 -305.280083)
			(xy 37.14673 -305.326764) (xy 37.154625 -305.375341) (xy 37.15512 -305.399948) (xy 37.493968 -305.399948)
			(xy 37.497928 -305.350894) (xy 37.509705 -305.30311) (xy 37.528996 -305.257834) (xy 37.555299 -305.216238)
			(xy 37.587934 -305.179401) (xy 37.626055 -305.148276) (xy 37.668676 -305.123669) (xy 37.714692 -305.106217)
			(xy 37.762911 -305.096373) (xy 37.812086 -305.094392) (xy 37.860941 -305.100324) (xy 37.908212 -305.114016)
			(xy 37.952674 -305.135114) (xy 37.993177 -305.16307) (xy 38.02867 -305.197162) (xy 38.058235 -305.236506)
			(xy 38.081106 -305.280083) (xy 38.09669 -305.326764) (xy 38.104585 -305.375341) (xy 38.10508 -305.399948)
			(xy 38.104585 -305.424555) (xy 38.104406 -305.425656) (xy 38.423338 -305.425656) (xy 38.423338 -305.37424)
			(xy 38.431381 -305.323458) (xy 38.447269 -305.274559) (xy 38.470612 -305.228747) (xy 38.500833 -305.187151)
			(xy 38.537189 -305.150795) (xy 38.578785 -305.120574) (xy 38.624597 -305.097231) (xy 38.673496 -305.081343)
			(xy 38.724278 -305.0733) (xy 38.775694 -305.0733) (xy 38.826476 -305.081343) (xy 38.875375 -305.097231)
			(xy 38.921187 -305.120574) (xy 38.962783 -305.150795) (xy 38.999139 -305.187151) (xy 39.02936 -305.228747)
			(xy 39.052703 -305.274559) (xy 39.068591 -305.323458) (xy 39.076634 -305.37424) (xy 39.077138 -305.399948)
			(xy 39.076634 -305.425656) (xy 39.373298 -305.425656) (xy 39.373298 -305.37424) (xy 39.381341 -305.323458)
			(xy 39.397229 -305.274559) (xy 39.420572 -305.228747) (xy 39.450793 -305.187151) (xy 39.487149 -305.150795)
			(xy 39.528745 -305.120574) (xy 39.574557 -305.097231) (xy 39.623456 -305.081343) (xy 39.674238 -305.0733)
			(xy 39.725654 -305.0733) (xy 39.776436 -305.081343) (xy 39.825335 -305.097231) (xy 39.871147 -305.120574)
			(xy 39.912743 -305.150795) (xy 39.949099 -305.187151) (xy 39.97932 -305.228747) (xy 40.002663 -305.274559)
			(xy 40.018551 -305.323458) (xy 40.026594 -305.37424) (xy 40.027098 -305.399948) (xy 40.344102 -305.399948)
			(xy 40.348062 -305.350894) (xy 40.359839 -305.30311) (xy 40.37913 -305.257834) (xy 40.405433 -305.216238)
			(xy 40.438068 -305.179401) (xy 40.476189 -305.148276) (xy 40.51881 -305.123669) (xy 40.564826 -305.106217)
			(xy 40.613045 -305.096373) (xy 40.66222 -305.094392) (xy 40.711075 -305.100324) (xy 40.758346 -305.114016)
			(xy 40.802808 -305.135114) (xy 40.843311 -305.16307) (xy 40.878804 -305.197162) (xy 40.908369 -305.236506)
			(xy 40.93124 -305.280083) (xy 40.946824 -305.326764) (xy 40.954719 -305.375341) (xy 40.955214 -305.399948)
			(xy 40.954719 -305.424555) (xy 40.95454 -305.425656) (xy 41.273218 -305.425656) (xy 41.273218 -305.37424)
			(xy 41.281261 -305.323458) (xy 41.297149 -305.274559) (xy 41.320492 -305.228747) (xy 41.350713 -305.187151)
			(xy 41.387069 -305.150795) (xy 41.428665 -305.120574) (xy 41.474477 -305.097231) (xy 41.523376 -305.081343)
			(xy 41.574158 -305.0733) (xy 41.625574 -305.0733) (xy 41.676356 -305.081343) (xy 41.725255 -305.097231)
			(xy 41.771067 -305.120574) (xy 41.812663 -305.150795) (xy 41.849019 -305.187151) (xy 41.87924 -305.228747)
			(xy 41.902583 -305.274559) (xy 41.918471 -305.323458) (xy 41.926514 -305.37424) (xy 41.927018 -305.399948)
			(xy 41.926514 -305.425656) (xy 42.223178 -305.425656) (xy 42.223178 -305.37424) (xy 42.231221 -305.323458)
			(xy 42.247109 -305.274559) (xy 42.270452 -305.228747) (xy 42.300673 -305.187151) (xy 42.337029 -305.150795)
			(xy 42.378625 -305.120574) (xy 42.424437 -305.097231) (xy 42.473336 -305.081343) (xy 42.524118 -305.0733)
			(xy 42.575534 -305.0733) (xy 42.626316 -305.081343) (xy 42.675215 -305.097231) (xy 42.721027 -305.120574)
			(xy 42.762623 -305.150795) (xy 42.798979 -305.187151) (xy 42.8292 -305.228747) (xy 42.852543 -305.274559)
			(xy 42.868431 -305.323458) (xy 42.876474 -305.37424) (xy 42.876978 -305.399948) (xy 43.193982 -305.399948)
			(xy 43.197942 -305.350894) (xy 43.209719 -305.30311) (xy 43.22901 -305.257834) (xy 43.255313 -305.216238)
			(xy 43.287948 -305.179401) (xy 43.326069 -305.148276) (xy 43.36869 -305.123669) (xy 43.414706 -305.106217)
			(xy 43.462925 -305.096373) (xy 43.5121 -305.094392) (xy 43.560955 -305.100324) (xy 43.608226 -305.114016)
			(xy 43.652688 -305.135114) (xy 43.693191 -305.16307) (xy 43.728684 -305.197162) (xy 43.758249 -305.236506)
			(xy 43.78112 -305.280083) (xy 43.796704 -305.326764) (xy 43.804599 -305.375341) (xy 43.805094 -305.399948)
			(xy 44.143942 -305.399948) (xy 44.147902 -305.350894) (xy 44.159679 -305.30311) (xy 44.17897 -305.257834)
			(xy 44.205273 -305.216238) (xy 44.237908 -305.179401) (xy 44.276029 -305.148276) (xy 44.31865 -305.123669)
			(xy 44.364666 -305.106217) (xy 44.412885 -305.096373) (xy 44.46206 -305.094392) (xy 44.510915 -305.100324)
			(xy 44.558186 -305.114016) (xy 44.602648 -305.135114) (xy 44.643151 -305.16307) (xy 44.678644 -305.197162)
			(xy 44.708209 -305.236506) (xy 44.73108 -305.280083) (xy 44.746664 -305.326764) (xy 44.754559 -305.375341)
			(xy 44.755054 -305.399948) (xy 45.094156 -305.399948) (xy 45.098116 -305.350894) (xy 45.109893 -305.30311)
			(xy 45.129184 -305.257834) (xy 45.155487 -305.216238) (xy 45.188122 -305.179401) (xy 45.226243 -305.148276)
			(xy 45.268864 -305.123669) (xy 45.31488 -305.106217) (xy 45.363099 -305.096373) (xy 45.412274 -305.094392)
			(xy 45.461129 -305.100324) (xy 45.5084 -305.114016) (xy 45.552862 -305.135114) (xy 45.593365 -305.16307)
			(xy 45.628858 -305.197162) (xy 45.658423 -305.236506) (xy 45.681294 -305.280083) (xy 45.696878 -305.326764)
			(xy 45.704773 -305.375341) (xy 45.705268 -305.399948) (xy 46.044116 -305.399948) (xy 46.048076 -305.350894)
			(xy 46.059853 -305.30311) (xy 46.079144 -305.257834) (xy 46.105447 -305.216238) (xy 46.138082 -305.179401)
			(xy 46.176203 -305.148276) (xy 46.218824 -305.123669) (xy 46.26484 -305.106217) (xy 46.313059 -305.096373)
			(xy 46.362234 -305.094392) (xy 46.411089 -305.100324) (xy 46.45836 -305.114016) (xy 46.502822 -305.135114)
			(xy 46.543325 -305.16307) (xy 46.578818 -305.197162) (xy 46.608383 -305.236506) (xy 46.631254 -305.280083)
			(xy 46.646838 -305.326764) (xy 46.654733 -305.375341) (xy 46.655228 -305.399948) (xy 46.654733 -305.424555)
			(xy 46.646838 -305.473132) (xy 46.631254 -305.519813) (xy 46.608383 -305.56339) (xy 46.578818 -305.602734)
			(xy 46.543325 -305.636826) (xy 46.502822 -305.664782) (xy 46.45836 -305.68588) (xy 46.411089 -305.699572)
			(xy 46.362234 -305.705504) (xy 46.313059 -305.703523) (xy 46.26484 -305.693679) (xy 46.218824 -305.676227)
			(xy 46.176203 -305.65162) (xy 46.138082 -305.620495) (xy 46.105447 -305.583658) (xy 46.079144 -305.542062)
			(xy 46.059853 -305.496786) (xy 46.048076 -305.449002) (xy 46.044116 -305.399948) (xy 45.705268 -305.399948)
			(xy 45.704773 -305.424555) (xy 45.696878 -305.473132) (xy 45.681294 -305.519813) (xy 45.658423 -305.56339)
			(xy 45.628858 -305.602734) (xy 45.593365 -305.636826) (xy 45.552862 -305.664782) (xy 45.5084 -305.68588)
			(xy 45.461129 -305.699572) (xy 45.412274 -305.705504) (xy 45.363099 -305.703523) (xy 45.31488 -305.693679)
			(xy 45.268864 -305.676227) (xy 45.226243 -305.65162) (xy 45.188122 -305.620495) (xy 45.155487 -305.583658)
			(xy 45.129184 -305.542062) (xy 45.109893 -305.496786) (xy 45.098116 -305.449002) (xy 45.094156 -305.399948)
			(xy 44.755054 -305.399948) (xy 44.754559 -305.424555) (xy 44.746664 -305.473132) (xy 44.73108 -305.519813)
			(xy 44.708209 -305.56339) (xy 44.678644 -305.602734) (xy 44.643151 -305.636826) (xy 44.602648 -305.664782)
			(xy 44.558186 -305.68588) (xy 44.510915 -305.699572) (xy 44.46206 -305.705504) (xy 44.412885 -305.703523)
			(xy 44.364666 -305.693679) (xy 44.31865 -305.676227) (xy 44.276029 -305.65162) (xy 44.237908 -305.620495)
			(xy 44.205273 -305.583658) (xy 44.17897 -305.542062) (xy 44.159679 -305.496786) (xy 44.147902 -305.449002)
			(xy 44.143942 -305.399948) (xy 43.805094 -305.399948) (xy 43.804599 -305.424555) (xy 43.796704 -305.473132)
			(xy 43.78112 -305.519813) (xy 43.758249 -305.56339) (xy 43.728684 -305.602734) (xy 43.693191 -305.636826)
			(xy 43.652688 -305.664782) (xy 43.608226 -305.68588) (xy 43.560955 -305.699572) (xy 43.5121 -305.705504)
			(xy 43.462925 -305.703523) (xy 43.414706 -305.693679) (xy 43.36869 -305.676227) (xy 43.326069 -305.65162)
			(xy 43.287948 -305.620495) (xy 43.255313 -305.583658) (xy 43.22901 -305.542062) (xy 43.209719 -305.496786)
			(xy 43.197942 -305.449002) (xy 43.193982 -305.399948) (xy 42.876978 -305.399948) (xy 42.876474 -305.425656)
			(xy 42.868431 -305.476438) (xy 42.852543 -305.525337) (xy 42.8292 -305.571149) (xy 42.798979 -305.612745)
			(xy 42.762623 -305.649101) (xy 42.721027 -305.679322) (xy 42.675215 -305.702665) (xy 42.626316 -305.718553)
			(xy 42.575534 -305.726596) (xy 42.524118 -305.726596) (xy 42.473336 -305.718553) (xy 42.424437 -305.702665)
			(xy 42.378625 -305.679322) (xy 42.337029 -305.649101) (xy 42.300673 -305.612745) (xy 42.270452 -305.571149)
			(xy 42.247109 -305.525337) (xy 42.231221 -305.476438) (xy 42.223178 -305.425656) (xy 41.926514 -305.425656)
			(xy 41.918471 -305.476438) (xy 41.902583 -305.525337) (xy 41.87924 -305.571149) (xy 41.849019 -305.612745)
			(xy 41.812663 -305.649101) (xy 41.771067 -305.679322) (xy 41.725255 -305.702665) (xy 41.676356 -305.718553)
			(xy 41.625574 -305.726596) (xy 41.574158 -305.726596) (xy 41.523376 -305.718553) (xy 41.474477 -305.702665)
			(xy 41.428665 -305.679322) (xy 41.387069 -305.649101) (xy 41.350713 -305.612745) (xy 41.320492 -305.571149)
			(xy 41.297149 -305.525337) (xy 41.281261 -305.476438) (xy 41.273218 -305.425656) (xy 40.95454 -305.425656)
			(xy 40.946824 -305.473132) (xy 40.93124 -305.519813) (xy 40.908369 -305.56339) (xy 40.878804 -305.602734)
			(xy 40.843311 -305.636826) (xy 40.802808 -305.664782) (xy 40.758346 -305.68588) (xy 40.711075 -305.699572)
			(xy 40.66222 -305.705504) (xy 40.613045 -305.703523) (xy 40.564826 -305.693679) (xy 40.51881 -305.676227)
			(xy 40.476189 -305.65162) (xy 40.438068 -305.620495) (xy 40.405433 -305.583658) (xy 40.37913 -305.542062)
			(xy 40.359839 -305.496786) (xy 40.348062 -305.449002) (xy 40.344102 -305.399948) (xy 40.027098 -305.399948)
			(xy 40.026594 -305.425656) (xy 40.018551 -305.476438) (xy 40.002663 -305.525337) (xy 39.97932 -305.571149)
			(xy 39.949099 -305.612745) (xy 39.912743 -305.649101) (xy 39.871147 -305.679322) (xy 39.825335 -305.702665)
			(xy 39.776436 -305.718553) (xy 39.725654 -305.726596) (xy 39.674238 -305.726596) (xy 39.623456 -305.718553)
			(xy 39.574557 -305.702665) (xy 39.528745 -305.679322) (xy 39.487149 -305.649101) (xy 39.450793 -305.612745)
			(xy 39.420572 -305.571149) (xy 39.397229 -305.525337) (xy 39.381341 -305.476438) (xy 39.373298 -305.425656)
			(xy 39.076634 -305.425656) (xy 39.068591 -305.476438) (xy 39.052703 -305.525337) (xy 39.02936 -305.571149)
			(xy 38.999139 -305.612745) (xy 38.962783 -305.649101) (xy 38.921187 -305.679322) (xy 38.875375 -305.702665)
			(xy 38.826476 -305.718553) (xy 38.775694 -305.726596) (xy 38.724278 -305.726596) (xy 38.673496 -305.718553)
			(xy 38.624597 -305.702665) (xy 38.578785 -305.679322) (xy 38.537189 -305.649101) (xy 38.500833 -305.612745)
			(xy 38.470612 -305.571149) (xy 38.447269 -305.525337) (xy 38.431381 -305.476438) (xy 38.423338 -305.425656)
			(xy 38.104406 -305.425656) (xy 38.09669 -305.473132) (xy 38.081106 -305.519813) (xy 38.058235 -305.56339)
			(xy 38.02867 -305.602734) (xy 37.993177 -305.636826) (xy 37.952674 -305.664782) (xy 37.908212 -305.68588)
			(xy 37.860941 -305.699572) (xy 37.812086 -305.705504) (xy 37.762911 -305.703523) (xy 37.714692 -305.693679)
			(xy 37.668676 -305.676227) (xy 37.626055 -305.65162) (xy 37.587934 -305.620495) (xy 37.555299 -305.583658)
			(xy 37.528996 -305.542062) (xy 37.509705 -305.496786) (xy 37.497928 -305.449002) (xy 37.493968 -305.399948)
			(xy 37.15512 -305.399948) (xy 37.154625 -305.424555) (xy 37.14673 -305.473132) (xy 37.131146 -305.519813)
			(xy 37.108275 -305.56339) (xy 37.07871 -305.602734) (xy 37.043217 -305.636826) (xy 37.002714 -305.664782)
			(xy 36.958252 -305.68588) (xy 36.910981 -305.699572) (xy 36.862126 -305.705504) (xy 36.812951 -305.703523)
			(xy 36.764732 -305.693679) (xy 36.718716 -305.676227) (xy 36.676095 -305.65162) (xy 36.637974 -305.620495)
			(xy 36.605339 -305.583658) (xy 36.579036 -305.542062) (xy 36.559745 -305.496786) (xy 36.547968 -305.449002)
			(xy 36.544008 -305.399948) (xy 28.166831 -305.399948) (xy 28.164289 -305.417224) (xy 28.148221 -305.470631)
			(xy 28.124549 -305.521128) (xy 28.093776 -305.567641) (xy 28.056559 -305.609178) (xy 28.013691 -305.644853)
			(xy 27.966085 -305.673907) (xy 27.914756 -305.695719) (xy 27.860799 -305.709825) (xy 27.805362 -305.715925)
			(xy 27.749628 -305.713888) (xy 27.694785 -305.703758) (xy 27.642001 -305.685751) (xy 27.592401 -305.66025)
			(xy 27.547043 -305.627799) (xy 27.506894 -305.58909) (xy 27.472808 -305.544947) (xy 27.445512 -305.496312)
			(xy 27.425589 -305.444221) (xy 27.413463 -305.389784) (xy 27.409392 -305.334162) (xy 18.377312 -305.334162)
			(xy 18.356052 -305.380714) (xy 18.326564 -305.426598) (xy 18.290847 -305.467818) (xy 18.249626 -305.503536)
			(xy 18.203743 -305.533023) (xy 18.154129 -305.555681) (xy 18.101796 -305.571047) (xy 18.047809 -305.578809)
			(xy 18.020538 -305.579272) (xy 17.991217 -305.578711) (xy 17.933269 -305.569702) (xy 17.877377 -305.551952)
			(xy 17.82485 -305.525876) (xy 17.800574 -305.509422) (xy 17.794478 -305.505358) (xy 17.770602 -305.49723)
			(xy 17.764559 -305.4969) (xy 17.752612 -305.498825) (xy 17.74698 -305.50104) (xy 17.685766 -305.532028)
			(xy 17.66316 -305.543458) (xy 17.657318 -305.547014) (xy 17.647644 -305.554625) (xy 17.636221 -305.576385)
			(xy 17.635474 -305.58867) (xy 17.635474 -305.891438) (xy 17.636024 -305.906605) (xy 17.644919 -305.935606)
			(xy 17.661942 -305.960714) (xy 17.68559 -305.979712) (xy 17.713776 -305.990923) (xy 17.744012 -305.993358)
			(xy 17.77363 -305.986803) (xy 17.787112 -305.97983) (xy 17.788382 -305.979068) (xy 17.820132 -305.957224)
			(xy 17.84977 -305.939799) (xy 17.913791 -305.914751) (xy 17.947386 -305.90744) (xy 17.96549 -305.904109)
			(xy 18.002131 -305.900551) (xy 18.020538 -305.900328) (xy 18.047809 -305.900791) (xy 18.101796 -305.908553)
			(xy 18.154129 -305.923919) (xy 18.203743 -305.946577) (xy 18.249626 -305.976064) (xy 18.290847 -306.011782)
			(xy 18.326327 -306.052728) (xy 26.690826 -306.052728) (xy 26.694897 -305.997106) (xy 26.707023 -305.942669)
			(xy 26.726946 -305.890578) (xy 26.754242 -305.841943) (xy 26.788328 -305.7978) (xy 26.828477 -305.759091)
			(xy 26.873835 -305.72664) (xy 26.923435 -305.701139) (xy 26.976219 -305.683132) (xy 27.031062 -305.673002)
			(xy 27.086796 -305.670965) (xy 27.142233 -305.677065) (xy 27.19619 -305.691171) (xy 27.247519 -305.712983)
			(xy 27.295125 -305.742037) (xy 27.337993 -305.777712) (xy 27.37521 -305.819249) (xy 27.405983 -305.865762)
			(xy 27.429655 -305.916259) (xy 27.445723 -305.969666) (xy 27.453843 -306.024842) (xy 27.454352 -306.052728)
			(xy 27.453843 -306.080614) (xy 27.445723 -306.13579) (xy 27.429655 -306.189197) (xy 27.405983 -306.239694)
			(xy 27.37521 -306.286207) (xy 27.337993 -306.327744) (xy 27.311055 -306.350162) (xy 35.593794 -306.350162)
			(xy 35.597754 -306.301108) (xy 35.609531 -306.253324) (xy 35.628822 -306.208048) (xy 35.655125 -306.166452)
			(xy 35.68776 -306.129615) (xy 35.725881 -306.09849) (xy 35.768502 -306.073883) (xy 35.814518 -306.056431)
			(xy 35.862737 -306.046587) (xy 35.911912 -306.044606) (xy 35.960767 -306.050538) (xy 36.008038 -306.06423)
			(xy 36.0525 -306.085328) (xy 36.093003 -306.113284) (xy 36.128496 -306.147376) (xy 36.158061 -306.18672)
			(xy 36.180932 -306.230297) (xy 36.196516 -306.276978) (xy 36.204411 -306.325555) (xy 36.204906 -306.350162)
			(xy 36.204411 -306.374769) (xy 36.204273 -306.375616) (xy 36.523164 -306.375616) (xy 36.523164 -306.3242)
			(xy 36.531207 -306.273418) (xy 36.547095 -306.224519) (xy 36.570438 -306.178707) (xy 36.600659 -306.137111)
			(xy 36.637015 -306.100755) (xy 36.678611 -306.070534) (xy 36.724423 -306.047191) (xy 36.773322 -306.031303)
			(xy 36.824104 -306.02326) (xy 36.87552 -306.02326) (xy 36.926302 -306.031303) (xy 36.975201 -306.047191)
			(xy 37.021013 -306.070534) (xy 37.062609 -306.100755) (xy 37.098965 -306.137111) (xy 37.129186 -306.178707)
			(xy 37.152529 -306.224519) (xy 37.168417 -306.273418) (xy 37.17646 -306.3242) (xy 37.176964 -306.349908)
			(xy 37.17646 -306.375616) (xy 37.473124 -306.375616) (xy 37.473124 -306.3242) (xy 37.481167 -306.273418)
			(xy 37.497055 -306.224519) (xy 37.520398 -306.178707) (xy 37.550619 -306.137111) (xy 37.586975 -306.100755)
			(xy 37.628571 -306.070534) (xy 37.674383 -306.047191) (xy 37.723282 -306.031303) (xy 37.774064 -306.02326)
			(xy 37.82548 -306.02326) (xy 37.876262 -306.031303) (xy 37.925161 -306.047191) (xy 37.970973 -306.070534)
			(xy 38.012569 -306.100755) (xy 38.048925 -306.137111) (xy 38.079146 -306.178707) (xy 38.102489 -306.224519)
			(xy 38.118377 -306.273418) (xy 38.12642 -306.3242) (xy 38.126924 -306.349908) (xy 38.444182 -306.349908)
			(xy 38.448142 -306.300854) (xy 38.459919 -306.25307) (xy 38.47921 -306.207794) (xy 38.505513 -306.166198)
			(xy 38.538148 -306.129361) (xy 38.576269 -306.098236) (xy 38.61889 -306.073629) (xy 38.664906 -306.056177)
			(xy 38.713125 -306.046333) (xy 38.7623 -306.044352) (xy 38.811155 -306.050284) (xy 38.858426 -306.063976)
			(xy 38.902888 -306.085074) (xy 38.943391 -306.11303) (xy 38.978884 -306.147122) (xy 39.008449 -306.186466)
			(xy 39.03132 -306.230043) (xy 39.046904 -306.276724) (xy 39.054799 -306.325301) (xy 39.055294 -306.349908)
			(xy 39.394142 -306.349908) (xy 39.398102 -306.300854) (xy 39.409879 -306.25307) (xy 39.42917 -306.207794)
			(xy 39.455473 -306.166198) (xy 39.488108 -306.129361) (xy 39.526229 -306.098236) (xy 39.56885 -306.073629)
			(xy 39.614866 -306.056177) (xy 39.663085 -306.046333) (xy 39.71226 -306.044352) (xy 39.761115 -306.050284)
			(xy 39.808386 -306.063976) (xy 39.852848 -306.085074) (xy 39.893351 -306.11303) (xy 39.928844 -306.147122)
			(xy 39.958409 -306.186466) (xy 39.98128 -306.230043) (xy 39.996864 -306.276724) (xy 40.004759 -306.325301)
			(xy 40.005254 -306.349908) (xy 40.344102 -306.349908) (xy 40.348062 -306.300854) (xy 40.359839 -306.25307)
			(xy 40.37913 -306.207794) (xy 40.405433 -306.166198) (xy 40.438068 -306.129361) (xy 40.476189 -306.098236)
			(xy 40.51881 -306.073629) (xy 40.564826 -306.056177) (xy 40.613045 -306.046333) (xy 40.66222 -306.044352)
			(xy 40.711075 -306.050284) (xy 40.758346 -306.063976) (xy 40.802808 -306.085074) (xy 40.843311 -306.11303)
			(xy 40.878804 -306.147122) (xy 40.908369 -306.186466) (xy 40.93124 -306.230043) (xy 40.946824 -306.276724)
			(xy 40.954719 -306.325301) (xy 40.955214 -306.349908) (xy 41.294062 -306.349908) (xy 41.298022 -306.300854)
			(xy 41.309799 -306.25307) (xy 41.32909 -306.207794) (xy 41.355393 -306.166198) (xy 41.388028 -306.129361)
			(xy 41.426149 -306.098236) (xy 41.46877 -306.073629) (xy 41.514786 -306.056177) (xy 41.563005 -306.046333)
			(xy 41.61218 -306.044352) (xy 41.661035 -306.050284) (xy 41.708306 -306.063976) (xy 41.752768 -306.085074)
			(xy 41.793271 -306.11303) (xy 41.828764 -306.147122) (xy 41.858329 -306.186466) (xy 41.8812 -306.230043)
			(xy 41.896784 -306.276724) (xy 41.904679 -306.325301) (xy 41.905174 -306.349908) (xy 42.244022 -306.349908)
			(xy 42.247982 -306.300854) (xy 42.259759 -306.25307) (xy 42.27905 -306.207794) (xy 42.305353 -306.166198)
			(xy 42.337988 -306.129361) (xy 42.376109 -306.098236) (xy 42.41873 -306.073629) (xy 42.464746 -306.056177)
			(xy 42.512965 -306.046333) (xy 42.56214 -306.044352) (xy 42.610995 -306.050284) (xy 42.658266 -306.063976)
			(xy 42.702728 -306.085074) (xy 42.743231 -306.11303) (xy 42.778724 -306.147122) (xy 42.808289 -306.186466)
			(xy 42.83116 -306.230043) (xy 42.846744 -306.276724) (xy 42.854639 -306.325301) (xy 42.855134 -306.349908)
			(xy 42.854639 -306.374515) (xy 42.85446 -306.375616) (xy 43.173138 -306.375616) (xy 43.173138 -306.3242)
			(xy 43.181181 -306.273418) (xy 43.197069 -306.224519) (xy 43.220412 -306.178707) (xy 43.250633 -306.137111)
			(xy 43.286989 -306.100755) (xy 43.328585 -306.070534) (xy 43.374397 -306.047191) (xy 43.423296 -306.031303)
			(xy 43.474078 -306.02326) (xy 43.525494 -306.02326) (xy 43.576276 -306.031303) (xy 43.625175 -306.047191)
			(xy 43.670987 -306.070534) (xy 43.712583 -306.100755) (xy 43.748939 -306.137111) (xy 43.77916 -306.178707)
			(xy 43.802503 -306.224519) (xy 43.818391 -306.273418) (xy 43.826434 -306.3242) (xy 43.826938 -306.349908)
			(xy 43.826434 -306.375616) (xy 44.123098 -306.375616) (xy 44.123098 -306.3242) (xy 44.131141 -306.273418)
			(xy 44.147029 -306.224519) (xy 44.170372 -306.178707) (xy 44.200593 -306.137111) (xy 44.236949 -306.100755)
			(xy 44.278545 -306.070534) (xy 44.324357 -306.047191) (xy 44.373256 -306.031303) (xy 44.424038 -306.02326)
			(xy 44.475454 -306.02326) (xy 44.526236 -306.031303) (xy 44.575135 -306.047191) (xy 44.620947 -306.070534)
			(xy 44.662543 -306.100755) (xy 44.698899 -306.137111) (xy 44.72912 -306.178707) (xy 44.752463 -306.224519)
			(xy 44.768351 -306.273418) (xy 44.776394 -306.3242) (xy 44.776898 -306.349908) (xy 45.094156 -306.349908)
			(xy 45.098116 -306.300854) (xy 45.109893 -306.25307) (xy 45.129184 -306.207794) (xy 45.155487 -306.166198)
			(xy 45.188122 -306.129361) (xy 45.226243 -306.098236) (xy 45.268864 -306.073629) (xy 45.31488 -306.056177)
			(xy 45.363099 -306.046333) (xy 45.412274 -306.044352) (xy 45.461129 -306.050284) (xy 45.5084 -306.063976)
			(xy 45.552862 -306.085074) (xy 45.593365 -306.11303) (xy 45.628858 -306.147122) (xy 45.658423 -306.186466)
			(xy 45.681294 -306.230043) (xy 45.696878 -306.276724) (xy 45.704773 -306.325301) (xy 45.705268 -306.349908)
			(xy 46.044116 -306.349908) (xy 46.048076 -306.300854) (xy 46.059853 -306.25307) (xy 46.079144 -306.207794)
			(xy 46.105447 -306.166198) (xy 46.138082 -306.129361) (xy 46.176203 -306.098236) (xy 46.218824 -306.073629)
			(xy 46.26484 -306.056177) (xy 46.313059 -306.046333) (xy 46.362234 -306.044352) (xy 46.411089 -306.050284)
			(xy 46.45836 -306.063976) (xy 46.502822 -306.085074) (xy 46.543325 -306.11303) (xy 46.578818 -306.147122)
			(xy 46.608383 -306.186466) (xy 46.631254 -306.230043) (xy 46.646838 -306.276724) (xy 46.654733 -306.325301)
			(xy 46.655061 -306.341629) (xy 46.994189 -306.341629) (xy 46.999554 -306.292281) (xy 47.012832 -306.24445)
			(xy 47.033673 -306.199398) (xy 47.061528 -306.15831) (xy 47.095663 -306.122271) (xy 47.13518 -306.092228)
			(xy 47.179035 -306.068974) (xy 47.226075 -306.053121) (xy 47.27506 -306.045087) (xy 47.29988 -306.0446)
			(xy 47.314063 -306.044779) (xy 47.342303 -306.04745) (xy 47.356268 -306.049934) (xy 47.37024 -306.052045)
			(xy 47.398366 -306.049473) (xy 47.424709 -306.039292) (xy 47.447254 -306.022281) (xy 47.464274 -305.999743)
			(xy 47.474465 -305.973403) (xy 47.477047 -305.945279) (xy 47.474886 -305.931316) (xy 47.472402 -305.917351)
			(xy 47.469735 -305.889111) (xy 47.469552 -305.874928) (xy 47.470048 -305.850104) (xy 47.478076 -305.801108)
			(xy 47.493925 -305.754058) (xy 47.517178 -305.710191) (xy 47.547222 -305.670664) (xy 47.583264 -305.636519)
			(xy 47.624357 -305.608655) (xy 47.669416 -305.587806) (xy 47.717254 -305.574522) (xy 47.766612 -305.569153)
			(xy 47.816188 -305.57184) (xy 47.864676 -305.582513) (xy 47.910798 -305.60089) (xy 47.953339 -305.626487)
			(xy 47.991179 -305.658629) (xy 48.02332 -305.69647) (xy 48.048915 -305.739013) (xy 48.06729 -305.785136)
			(xy 48.077961 -305.833624) (xy 48.080198 -305.874928) (xy 48.419016 -305.874928) (xy 48.422976 -305.825874)
			(xy 48.434753 -305.77809) (xy 48.454044 -305.732814) (xy 48.480347 -305.691218) (xy 48.512982 -305.654381)
			(xy 48.551103 -305.623256) (xy 48.593724 -305.598649) (xy 48.63974 -305.581197) (xy 48.687959 -305.571353)
			(xy 48.737134 -305.569372) (xy 48.785989 -305.575304) (xy 48.83326 -305.588996) (xy 48.877722 -305.610094)
			(xy 48.918225 -305.63805) (xy 48.953718 -305.672142) (xy 48.983283 -305.711486) (xy 49.006154 -305.755063)
			(xy 49.021738 -305.801744) (xy 49.029633 -305.850321) (xy 49.030128 -305.874928) (xy 49.368976 -305.874928)
			(xy 49.372936 -305.825874) (xy 49.384713 -305.77809) (xy 49.404004 -305.732814) (xy 49.430307 -305.691218)
			(xy 49.462942 -305.654381) (xy 49.501063 -305.623256) (xy 49.543684 -305.598649) (xy 49.5897 -305.581197)
			(xy 49.637919 -305.571353) (xy 49.687094 -305.569372) (xy 49.735949 -305.575304) (xy 49.78322 -305.588996)
			(xy 49.827682 -305.610094) (xy 49.868185 -305.63805) (xy 49.903678 -305.672142) (xy 49.933243 -305.711486)
			(xy 49.956114 -305.755063) (xy 49.971698 -305.801744) (xy 49.979593 -305.850321) (xy 49.980088 -305.874928)
			(xy 50.31919 -305.874928) (xy 50.32315 -305.825874) (xy 50.334927 -305.77809) (xy 50.354218 -305.732814)
			(xy 50.380521 -305.691218) (xy 50.413156 -305.654381) (xy 50.451277 -305.623256) (xy 50.493898 -305.598649)
			(xy 50.539914 -305.581197) (xy 50.588133 -305.571353) (xy 50.637308 -305.569372) (xy 50.686163 -305.575304)
			(xy 50.733434 -305.588996) (xy 50.777896 -305.610094) (xy 50.818399 -305.63805) (xy 50.853892 -305.672142)
			(xy 50.883457 -305.711486) (xy 50.906328 -305.755063) (xy 50.921912 -305.801744) (xy 50.929807 -305.850321)
			(xy 50.930302 -305.874928) (xy 51.26915 -305.874928) (xy 51.27311 -305.825874) (xy 51.284887 -305.77809)
			(xy 51.304178 -305.732814) (xy 51.330481 -305.691218) (xy 51.363116 -305.654381) (xy 51.401237 -305.623256)
			(xy 51.443858 -305.598649) (xy 51.489874 -305.581197) (xy 51.538093 -305.571353) (xy 51.587268 -305.569372)
			(xy 51.636123 -305.575304) (xy 51.683394 -305.588996) (xy 51.727856 -305.610094) (xy 51.768359 -305.63805)
			(xy 51.803852 -305.672142) (xy 51.833417 -305.711486) (xy 51.856288 -305.755063) (xy 51.871872 -305.801744)
			(xy 51.879767 -305.850321) (xy 51.880262 -305.874928) (xy 52.21911 -305.874928) (xy 52.22307 -305.825874)
			(xy 52.234847 -305.77809) (xy 52.254138 -305.732814) (xy 52.280441 -305.691218) (xy 52.313076 -305.654381)
			(xy 52.351197 -305.623256) (xy 52.393818 -305.598649) (xy 52.439834 -305.581197) (xy 52.488053 -305.571353)
			(xy 52.537228 -305.569372) (xy 52.586083 -305.575304) (xy 52.633354 -305.588996) (xy 52.677816 -305.610094)
			(xy 52.718319 -305.63805) (xy 52.753812 -305.672142) (xy 52.783377 -305.711486) (xy 52.806248 -305.755063)
			(xy 52.821832 -305.801744) (xy 52.829727 -305.850321) (xy 52.830222 -305.874928) (xy 53.16907 -305.874928)
			(xy 53.17303 -305.825874) (xy 53.184807 -305.77809) (xy 53.204098 -305.732814) (xy 53.230401 -305.691218)
			(xy 53.263036 -305.654381) (xy 53.301157 -305.623256) (xy 53.343778 -305.598649) (xy 53.389794 -305.581197)
			(xy 53.438013 -305.571353) (xy 53.487188 -305.569372) (xy 53.536043 -305.575304) (xy 53.583314 -305.588996)
			(xy 53.627776 -305.610094) (xy 53.668279 -305.63805) (xy 53.703772 -305.672142) (xy 53.733337 -305.711486)
			(xy 53.756208 -305.755063) (xy 53.771792 -305.801744) (xy 53.779687 -305.850321) (xy 53.780182 -305.874928)
			(xy 54.11903 -305.874928) (xy 54.12299 -305.825874) (xy 54.134767 -305.77809) (xy 54.154058 -305.732814)
			(xy 54.180361 -305.691218) (xy 54.212996 -305.654381) (xy 54.251117 -305.623256) (xy 54.293738 -305.598649)
			(xy 54.339754 -305.581197) (xy 54.387973 -305.571353) (xy 54.437148 -305.569372) (xy 54.486003 -305.575304)
			(xy 54.533274 -305.588996) (xy 54.577736 -305.610094) (xy 54.618239 -305.63805) (xy 54.653732 -305.672142)
			(xy 54.683297 -305.711486) (xy 54.706168 -305.755063) (xy 54.721752 -305.801744) (xy 54.729647 -305.850321)
			(xy 54.730142 -305.874928) (xy 55.06899 -305.874928) (xy 55.07295 -305.825874) (xy 55.084727 -305.77809)
			(xy 55.104018 -305.732814) (xy 55.130321 -305.691218) (xy 55.162956 -305.654381) (xy 55.201077 -305.623256)
			(xy 55.243698 -305.598649) (xy 55.289714 -305.581197) (xy 55.337933 -305.571353) (xy 55.387108 -305.569372)
			(xy 55.435963 -305.575304) (xy 55.483234 -305.588996) (xy 55.527696 -305.610094) (xy 55.568199 -305.63805)
			(xy 55.603692 -305.672142) (xy 55.633257 -305.711486) (xy 55.656128 -305.755063) (xy 55.671712 -305.801744)
			(xy 55.679607 -305.850321) (xy 55.680102 -305.874928) (xy 56.01895 -305.874928) (xy 56.02291 -305.825874)
			(xy 56.034687 -305.77809) (xy 56.053978 -305.732814) (xy 56.080281 -305.691218) (xy 56.112916 -305.654381)
			(xy 56.151037 -305.623256) (xy 56.193658 -305.598649) (xy 56.239674 -305.581197) (xy 56.287893 -305.571353)
			(xy 56.337068 -305.569372) (xy 56.385923 -305.575304) (xy 56.433194 -305.588996) (xy 56.477656 -305.610094)
			(xy 56.518159 -305.63805) (xy 56.553652 -305.672142) (xy 56.583217 -305.711486) (xy 56.606088 -305.755063)
			(xy 56.621672 -305.801744) (xy 56.629567 -305.850321) (xy 56.630062 -305.874928) (xy 56.969164 -305.874928)
			(xy 56.973124 -305.825874) (xy 56.984901 -305.77809) (xy 57.004192 -305.732814) (xy 57.030495 -305.691218)
			(xy 57.06313 -305.654381) (xy 57.101251 -305.623256) (xy 57.143872 -305.598649) (xy 57.189888 -305.581197)
			(xy 57.238107 -305.571353) (xy 57.287282 -305.569372) (xy 57.336137 -305.575304) (xy 57.383408 -305.588996)
			(xy 57.42787 -305.610094) (xy 57.468373 -305.63805) (xy 57.503866 -305.672142) (xy 57.533431 -305.711486)
			(xy 57.556302 -305.755063) (xy 57.571886 -305.801744) (xy 57.579781 -305.850321) (xy 57.580276 -305.874928)
			(xy 57.919124 -305.874928) (xy 57.923084 -305.825874) (xy 57.934861 -305.77809) (xy 57.954152 -305.732814)
			(xy 57.980455 -305.691218) (xy 58.01309 -305.654381) (xy 58.051211 -305.623256) (xy 58.093832 -305.598649)
			(xy 58.139848 -305.581197) (xy 58.188067 -305.571353) (xy 58.237242 -305.569372) (xy 58.286097 -305.575304)
			(xy 58.333368 -305.588996) (xy 58.37783 -305.610094) (xy 58.418333 -305.63805) (xy 58.453826 -305.672142)
			(xy 58.483391 -305.711486) (xy 58.506262 -305.755063) (xy 58.521846 -305.801744) (xy 58.529741 -305.850321)
			(xy 58.530236 -305.874928) (xy 59.819044 -305.874928) (xy 59.823004 -305.825874) (xy 59.834781 -305.77809)
			(xy 59.854072 -305.732814) (xy 59.880375 -305.691218) (xy 59.91301 -305.654381) (xy 59.951131 -305.623256)
			(xy 59.993752 -305.598649) (xy 60.039768 -305.581197) (xy 60.087987 -305.571353) (xy 60.137162 -305.569372)
			(xy 60.186017 -305.575304) (xy 60.233288 -305.588996) (xy 60.27775 -305.610094) (xy 60.318253 -305.63805)
			(xy 60.353746 -305.672142) (xy 60.383311 -305.711486) (xy 60.406182 -305.755063) (xy 60.421766 -305.801744)
			(xy 60.429661 -305.850321) (xy 60.430156 -305.874928) (xy 60.769004 -305.874928) (xy 60.772964 -305.825874)
			(xy 60.784741 -305.77809) (xy 60.804032 -305.732814) (xy 60.830335 -305.691218) (xy 60.86297 -305.654381)
			(xy 60.901091 -305.623256) (xy 60.943712 -305.598649) (xy 60.989728 -305.581197) (xy 61.037947 -305.571353)
			(xy 61.087122 -305.569372) (xy 61.135977 -305.575304) (xy 61.183248 -305.588996) (xy 61.22771 -305.610094)
			(xy 61.268213 -305.63805) (xy 61.303706 -305.672142) (xy 61.333271 -305.711486) (xy 61.356142 -305.755063)
			(xy 61.371726 -305.801744) (xy 61.379621 -305.850321) (xy 61.380116 -305.874928) (xy 61.718964 -305.874928)
			(xy 61.722924 -305.825874) (xy 61.734701 -305.77809) (xy 61.753992 -305.732814) (xy 61.780295 -305.691218)
			(xy 61.81293 -305.654381) (xy 61.851051 -305.623256) (xy 61.893672 -305.598649) (xy 61.939688 -305.581197)
			(xy 61.987907 -305.571353) (xy 62.037082 -305.569372) (xy 62.085937 -305.575304) (xy 62.133208 -305.588996)
			(xy 62.17767 -305.610094) (xy 62.218173 -305.63805) (xy 62.253666 -305.672142) (xy 62.283231 -305.711486)
			(xy 62.306102 -305.755063) (xy 62.321686 -305.801744) (xy 62.329581 -305.850321) (xy 62.330076 -305.874928)
			(xy 62.669178 -305.874928) (xy 62.673138 -305.825874) (xy 62.684915 -305.77809) (xy 62.704206 -305.732814)
			(xy 62.730509 -305.691218) (xy 62.763144 -305.654381) (xy 62.801265 -305.623256) (xy 62.843886 -305.598649)
			(xy 62.889902 -305.581197) (xy 62.938121 -305.571353) (xy 62.987296 -305.569372) (xy 63.036151 -305.575304)
			(xy 63.083422 -305.588996) (xy 63.127884 -305.610094) (xy 63.168387 -305.63805) (xy 63.20388 -305.672142)
			(xy 63.233445 -305.711486) (xy 63.256316 -305.755063) (xy 63.2719 -305.801744) (xy 63.279795 -305.850321)
			(xy 63.28029 -305.874928) (xy 63.619138 -305.874928) (xy 63.623098 -305.825874) (xy 63.634875 -305.77809)
			(xy 63.654166 -305.732814) (xy 63.680469 -305.691218) (xy 63.713104 -305.654381) (xy 63.751225 -305.623256)
			(xy 63.793846 -305.598649) (xy 63.839862 -305.581197) (xy 63.888081 -305.571353) (xy 63.937256 -305.569372)
			(xy 63.986111 -305.575304) (xy 64.033382 -305.588996) (xy 64.077844 -305.610094) (xy 64.118347 -305.63805)
			(xy 64.15384 -305.672142) (xy 64.183405 -305.711486) (xy 64.206276 -305.755063) (xy 64.22186 -305.801744)
			(xy 64.229755 -305.850321) (xy 64.23025 -305.874928) (xy 64.569098 -305.874928) (xy 64.573058 -305.825874)
			(xy 64.584835 -305.77809) (xy 64.604126 -305.732814) (xy 64.630429 -305.691218) (xy 64.663064 -305.654381)
			(xy 64.701185 -305.623256) (xy 64.743806 -305.598649) (xy 64.789822 -305.581197) (xy 64.838041 -305.571353)
			(xy 64.887216 -305.569372) (xy 64.936071 -305.575304) (xy 64.983342 -305.588996) (xy 65.027804 -305.610094)
			(xy 65.068307 -305.63805) (xy 65.1038 -305.672142) (xy 65.133365 -305.711486) (xy 65.156236 -305.755063)
			(xy 65.17182 -305.801744) (xy 65.179715 -305.850321) (xy 65.18021 -305.874928) (xy 65.519058 -305.874928)
			(xy 65.523018 -305.825874) (xy 65.534795 -305.77809) (xy 65.554086 -305.732814) (xy 65.580389 -305.691218)
			(xy 65.613024 -305.654381) (xy 65.651145 -305.623256) (xy 65.693766 -305.598649) (xy 65.739782 -305.581197)
			(xy 65.788001 -305.571353) (xy 65.837176 -305.569372) (xy 65.886031 -305.575304) (xy 65.933302 -305.588996)
			(xy 65.977764 -305.610094) (xy 66.018267 -305.63805) (xy 66.05376 -305.672142) (xy 66.083325 -305.711486)
			(xy 66.106196 -305.755063) (xy 66.12178 -305.801744) (xy 66.129675 -305.850321) (xy 66.13017 -305.874928)
			(xy 66.469018 -305.874928) (xy 66.472978 -305.825874) (xy 66.484755 -305.77809) (xy 66.504046 -305.732814)
			(xy 66.530349 -305.691218) (xy 66.562984 -305.654381) (xy 66.601105 -305.623256) (xy 66.643726 -305.598649)
			(xy 66.689742 -305.581197) (xy 66.737961 -305.571353) (xy 66.787136 -305.569372) (xy 66.835991 -305.575304)
			(xy 66.883262 -305.588996) (xy 66.927724 -305.610094) (xy 66.968227 -305.63805) (xy 67.00372 -305.672142)
			(xy 67.033285 -305.711486) (xy 67.056156 -305.755063) (xy 67.07174 -305.801744) (xy 67.079635 -305.850321)
			(xy 67.08013 -305.874928) (xy 67.418978 -305.874928) (xy 67.422938 -305.825874) (xy 67.434715 -305.77809)
			(xy 67.454006 -305.732814) (xy 67.480309 -305.691218) (xy 67.512944 -305.654381) (xy 67.551065 -305.623256)
			(xy 67.593686 -305.598649) (xy 67.639702 -305.581197) (xy 67.687921 -305.571353) (xy 67.737096 -305.569372)
			(xy 67.785951 -305.575304) (xy 67.833222 -305.588996) (xy 67.877684 -305.610094) (xy 67.918187 -305.63805)
			(xy 67.95368 -305.672142) (xy 67.983245 -305.711486) (xy 68.006116 -305.755063) (xy 68.0217 -305.801744)
			(xy 68.029595 -305.850321) (xy 68.03009 -305.874928) (xy 68.368938 -305.874928) (xy 68.372898 -305.825874)
			(xy 68.384675 -305.77809) (xy 68.403966 -305.732814) (xy 68.430269 -305.691218) (xy 68.462904 -305.654381)
			(xy 68.501025 -305.623256) (xy 68.543646 -305.598649) (xy 68.589662 -305.581197) (xy 68.637881 -305.571353)
			(xy 68.687056 -305.569372) (xy 68.735911 -305.575304) (xy 68.783182 -305.588996) (xy 68.827644 -305.610094)
			(xy 68.868147 -305.63805) (xy 68.90364 -305.672142) (xy 68.933205 -305.711486) (xy 68.956076 -305.755063)
			(xy 68.97166 -305.801744) (xy 68.979555 -305.850321) (xy 68.98005 -305.874928) (xy 69.319152 -305.874928)
			(xy 69.323112 -305.825874) (xy 69.334889 -305.77809) (xy 69.35418 -305.732814) (xy 69.380483 -305.691218)
			(xy 69.413118 -305.654381) (xy 69.451239 -305.623256) (xy 69.49386 -305.598649) (xy 69.539876 -305.581197)
			(xy 69.588095 -305.571353) (xy 69.63727 -305.569372) (xy 69.686125 -305.575304) (xy 69.733396 -305.588996)
			(xy 69.777858 -305.610094) (xy 69.818361 -305.63805) (xy 69.853854 -305.672142) (xy 69.883419 -305.711486)
			(xy 69.90629 -305.755063) (xy 69.921874 -305.801744) (xy 69.929769 -305.850321) (xy 69.930264 -305.874928)
			(xy 70.269112 -305.874928) (xy 70.273072 -305.825874) (xy 70.284849 -305.77809) (xy 70.30414 -305.732814)
			(xy 70.330443 -305.691218) (xy 70.363078 -305.654381) (xy 70.401199 -305.623256) (xy 70.44382 -305.598649)
			(xy 70.489836 -305.581197) (xy 70.538055 -305.571353) (xy 70.58723 -305.569372) (xy 70.636085 -305.575304)
			(xy 70.683356 -305.588996) (xy 70.727818 -305.610094) (xy 70.768321 -305.63805) (xy 70.803814 -305.672142)
			(xy 70.833379 -305.711486) (xy 70.85625 -305.755063) (xy 70.871834 -305.801744) (xy 70.879729 -305.850321)
			(xy 70.880224 -305.874928) (xy 71.219072 -305.874928) (xy 71.223032 -305.825874) (xy 71.234809 -305.77809)
			(xy 71.2541 -305.732814) (xy 71.280403 -305.691218) (xy 71.313038 -305.654381) (xy 71.351159 -305.623256)
			(xy 71.39378 -305.598649) (xy 71.439796 -305.581197) (xy 71.488015 -305.571353) (xy 71.53719 -305.569372)
			(xy 71.586045 -305.575304) (xy 71.633316 -305.588996) (xy 71.677778 -305.610094) (xy 71.718281 -305.63805)
			(xy 71.753774 -305.672142) (xy 71.783339 -305.711486) (xy 71.80621 -305.755063) (xy 71.821794 -305.801744)
			(xy 71.829689 -305.850321) (xy 71.830184 -305.874928) (xy 71.829689 -305.899535) (xy 71.821794 -305.948112)
			(xy 71.80621 -305.994793) (xy 71.783339 -306.03837) (xy 71.753774 -306.077714) (xy 71.718281 -306.111806)
			(xy 71.677778 -306.139762) (xy 71.633316 -306.16086) (xy 71.586045 -306.174552) (xy 71.53719 -306.180484)
			(xy 71.488015 -306.178503) (xy 71.439796 -306.168659) (xy 71.39378 -306.151207) (xy 71.351159 -306.1266)
			(xy 71.313038 -306.095475) (xy 71.280403 -306.058638) (xy 71.2541 -306.017042) (xy 71.234809 -305.971766)
			(xy 71.223032 -305.923982) (xy 71.219072 -305.874928) (xy 70.880224 -305.874928) (xy 70.879729 -305.899535)
			(xy 70.871834 -305.948112) (xy 70.85625 -305.994793) (xy 70.833379 -306.03837) (xy 70.803814 -306.077714)
			(xy 70.768321 -306.111806) (xy 70.727818 -306.139762) (xy 70.683356 -306.16086) (xy 70.636085 -306.174552)
			(xy 70.58723 -306.180484) (xy 70.538055 -306.178503) (xy 70.489836 -306.168659) (xy 70.44382 -306.151207)
			(xy 70.401199 -306.1266) (xy 70.363078 -306.095475) (xy 70.330443 -306.058638) (xy 70.30414 -306.017042)
			(xy 70.284849 -305.971766) (xy 70.273072 -305.923982) (xy 70.269112 -305.874928) (xy 69.930264 -305.874928)
			(xy 69.929769 -305.899535) (xy 69.921874 -305.948112) (xy 69.90629 -305.994793) (xy 69.883419 -306.03837)
			(xy 69.853854 -306.077714) (xy 69.818361 -306.111806) (xy 69.777858 -306.139762) (xy 69.733396 -306.16086)
			(xy 69.686125 -306.174552) (xy 69.63727 -306.180484) (xy 69.588095 -306.178503) (xy 69.539876 -306.168659)
			(xy 69.49386 -306.151207) (xy 69.451239 -306.1266) (xy 69.413118 -306.095475) (xy 69.380483 -306.058638)
			(xy 69.35418 -306.017042) (xy 69.334889 -305.971766) (xy 69.323112 -305.923982) (xy 69.319152 -305.874928)
			(xy 68.98005 -305.874928) (xy 68.979555 -305.899535) (xy 68.97166 -305.948112) (xy 68.956076 -305.994793)
			(xy 68.933205 -306.03837) (xy 68.90364 -306.077714) (xy 68.868147 -306.111806) (xy 68.827644 -306.139762)
			(xy 68.783182 -306.16086) (xy 68.735911 -306.174552) (xy 68.687056 -306.180484) (xy 68.637881 -306.178503)
			(xy 68.589662 -306.168659) (xy 68.543646 -306.151207) (xy 68.501025 -306.1266) (xy 68.462904 -306.095475)
			(xy 68.430269 -306.058638) (xy 68.403966 -306.017042) (xy 68.384675 -305.971766) (xy 68.372898 -305.923982)
			(xy 68.368938 -305.874928) (xy 68.03009 -305.874928) (xy 68.029595 -305.899535) (xy 68.0217 -305.948112)
			(xy 68.006116 -305.994793) (xy 67.983245 -306.03837) (xy 67.95368 -306.077714) (xy 67.918187 -306.111806)
			(xy 67.877684 -306.139762) (xy 67.833222 -306.16086) (xy 67.785951 -306.174552) (xy 67.737096 -306.180484)
			(xy 67.687921 -306.178503) (xy 67.639702 -306.168659) (xy 67.593686 -306.151207) (xy 67.551065 -306.1266)
			(xy 67.512944 -306.095475) (xy 67.480309 -306.058638) (xy 67.454006 -306.017042) (xy 67.434715 -305.971766)
			(xy 67.422938 -305.923982) (xy 67.418978 -305.874928) (xy 67.08013 -305.874928) (xy 67.079635 -305.899535)
			(xy 67.07174 -305.948112) (xy 67.056156 -305.994793) (xy 67.033285 -306.03837) (xy 67.00372 -306.077714)
			(xy 66.968227 -306.111806) (xy 66.927724 -306.139762) (xy 66.883262 -306.16086) (xy 66.835991 -306.174552)
			(xy 66.787136 -306.180484) (xy 66.737961 -306.178503) (xy 66.689742 -306.168659) (xy 66.643726 -306.151207)
			(xy 66.601105 -306.1266) (xy 66.562984 -306.095475) (xy 66.530349 -306.058638) (xy 66.504046 -306.017042)
			(xy 66.484755 -305.971766) (xy 66.472978 -305.923982) (xy 66.469018 -305.874928) (xy 66.13017 -305.874928)
			(xy 66.129675 -305.899535) (xy 66.12178 -305.948112) (xy 66.106196 -305.994793) (xy 66.083325 -306.03837)
			(xy 66.05376 -306.077714) (xy 66.018267 -306.111806) (xy 65.977764 -306.139762) (xy 65.933302 -306.16086)
			(xy 65.886031 -306.174552) (xy 65.837176 -306.180484) (xy 65.788001 -306.178503) (xy 65.739782 -306.168659)
			(xy 65.693766 -306.151207) (xy 65.651145 -306.1266) (xy 65.613024 -306.095475) (xy 65.580389 -306.058638)
			(xy 65.554086 -306.017042) (xy 65.534795 -305.971766) (xy 65.523018 -305.923982) (xy 65.519058 -305.874928)
			(xy 65.18021 -305.874928) (xy 65.179715 -305.899535) (xy 65.17182 -305.948112) (xy 65.156236 -305.994793)
			(xy 65.133365 -306.03837) (xy 65.1038 -306.077714) (xy 65.068307 -306.111806) (xy 65.027804 -306.139762)
			(xy 64.983342 -306.16086) (xy 64.936071 -306.174552) (xy 64.887216 -306.180484) (xy 64.838041 -306.178503)
			(xy 64.789822 -306.168659) (xy 64.743806 -306.151207) (xy 64.701185 -306.1266) (xy 64.663064 -306.095475)
			(xy 64.630429 -306.058638) (xy 64.604126 -306.017042) (xy 64.584835 -305.971766) (xy 64.573058 -305.923982)
			(xy 64.569098 -305.874928) (xy 64.23025 -305.874928) (xy 64.229755 -305.899535) (xy 64.22186 -305.948112)
			(xy 64.206276 -305.994793) (xy 64.183405 -306.03837) (xy 64.15384 -306.077714) (xy 64.118347 -306.111806)
			(xy 64.077844 -306.139762) (xy 64.033382 -306.16086) (xy 63.986111 -306.174552) (xy 63.937256 -306.180484)
			(xy 63.888081 -306.178503) (xy 63.839862 -306.168659) (xy 63.793846 -306.151207) (xy 63.751225 -306.1266)
			(xy 63.713104 -306.095475) (xy 63.680469 -306.058638) (xy 63.654166 -306.017042) (xy 63.634875 -305.971766)
			(xy 63.623098 -305.923982) (xy 63.619138 -305.874928) (xy 63.28029 -305.874928) (xy 63.279795 -305.899535)
			(xy 63.2719 -305.948112) (xy 63.256316 -305.994793) (xy 63.233445 -306.03837) (xy 63.20388 -306.077714)
			(xy 63.168387 -306.111806) (xy 63.127884 -306.139762) (xy 63.083422 -306.16086) (xy 63.036151 -306.174552)
			(xy 62.987296 -306.180484) (xy 62.938121 -306.178503) (xy 62.889902 -306.168659) (xy 62.843886 -306.151207)
			(xy 62.801265 -306.1266) (xy 62.763144 -306.095475) (xy 62.730509 -306.058638) (xy 62.704206 -306.017042)
			(xy 62.684915 -305.971766) (xy 62.673138 -305.923982) (xy 62.669178 -305.874928) (xy 62.330076 -305.874928)
			(xy 62.329581 -305.899535) (xy 62.321686 -305.948112) (xy 62.306102 -305.994793) (xy 62.283231 -306.03837)
			(xy 62.253666 -306.077714) (xy 62.218173 -306.111806) (xy 62.17767 -306.139762) (xy 62.133208 -306.16086)
			(xy 62.085937 -306.174552) (xy 62.037082 -306.180484) (xy 61.987907 -306.178503) (xy 61.939688 -306.168659)
			(xy 61.893672 -306.151207) (xy 61.851051 -306.1266) (xy 61.81293 -306.095475) (xy 61.780295 -306.058638)
			(xy 61.753992 -306.017042) (xy 61.734701 -305.971766) (xy 61.722924 -305.923982) (xy 61.718964 -305.874928)
			(xy 61.380116 -305.874928) (xy 61.379621 -305.899535) (xy 61.371726 -305.948112) (xy 61.356142 -305.994793)
			(xy 61.333271 -306.03837) (xy 61.303706 -306.077714) (xy 61.268213 -306.111806) (xy 61.22771 -306.139762)
			(xy 61.183248 -306.16086) (xy 61.135977 -306.174552) (xy 61.087122 -306.180484) (xy 61.037947 -306.178503)
			(xy 60.989728 -306.168659) (xy 60.943712 -306.151207) (xy 60.901091 -306.1266) (xy 60.86297 -306.095475)
			(xy 60.830335 -306.058638) (xy 60.804032 -306.017042) (xy 60.784741 -305.971766) (xy 60.772964 -305.923982)
			(xy 60.769004 -305.874928) (xy 60.430156 -305.874928) (xy 60.429661 -305.899535) (xy 60.421766 -305.948112)
			(xy 60.406182 -305.994793) (xy 60.383311 -306.03837) (xy 60.353746 -306.077714) (xy 60.318253 -306.111806)
			(xy 60.27775 -306.139762) (xy 60.233288 -306.16086) (xy 60.186017 -306.174552) (xy 60.137162 -306.180484)
			(xy 60.087987 -306.178503) (xy 60.039768 -306.168659) (xy 59.993752 -306.151207) (xy 59.951131 -306.1266)
			(xy 59.91301 -306.095475) (xy 59.880375 -306.058638) (xy 59.854072 -306.017042) (xy 59.834781 -305.971766)
			(xy 59.823004 -305.923982) (xy 59.819044 -305.874928) (xy 58.530236 -305.874928) (xy 58.529741 -305.899535)
			(xy 58.521846 -305.948112) (xy 58.506262 -305.994793) (xy 58.483391 -306.03837) (xy 58.453826 -306.077714)
			(xy 58.418333 -306.111806) (xy 58.37783 -306.139762) (xy 58.333368 -306.16086) (xy 58.286097 -306.174552)
			(xy 58.237242 -306.180484) (xy 58.188067 -306.178503) (xy 58.139848 -306.168659) (xy 58.093832 -306.151207)
			(xy 58.051211 -306.1266) (xy 58.01309 -306.095475) (xy 57.980455 -306.058638) (xy 57.954152 -306.017042)
			(xy 57.934861 -305.971766) (xy 57.923084 -305.923982) (xy 57.919124 -305.874928) (xy 57.580276 -305.874928)
			(xy 57.579781 -305.899535) (xy 57.571886 -305.948112) (xy 57.556302 -305.994793) (xy 57.533431 -306.03837)
			(xy 57.503866 -306.077714) (xy 57.468373 -306.111806) (xy 57.42787 -306.139762) (xy 57.383408 -306.16086)
			(xy 57.336137 -306.174552) (xy 57.287282 -306.180484) (xy 57.238107 -306.178503) (xy 57.189888 -306.168659)
			(xy 57.143872 -306.151207) (xy 57.101251 -306.1266) (xy 57.06313 -306.095475) (xy 57.030495 -306.058638)
			(xy 57.004192 -306.017042) (xy 56.984901 -305.971766) (xy 56.973124 -305.923982) (xy 56.969164 -305.874928)
			(xy 56.630062 -305.874928) (xy 56.629567 -305.899535) (xy 56.621672 -305.948112) (xy 56.606088 -305.994793)
			(xy 56.583217 -306.03837) (xy 56.553652 -306.077714) (xy 56.518159 -306.111806) (xy 56.477656 -306.139762)
			(xy 56.433194 -306.16086) (xy 56.385923 -306.174552) (xy 56.337068 -306.180484) (xy 56.287893 -306.178503)
			(xy 56.239674 -306.168659) (xy 56.193658 -306.151207) (xy 56.151037 -306.1266) (xy 56.112916 -306.095475)
			(xy 56.080281 -306.058638) (xy 56.053978 -306.017042) (xy 56.034687 -305.971766) (xy 56.02291 -305.923982)
			(xy 56.01895 -305.874928) (xy 55.680102 -305.874928) (xy 55.679607 -305.899535) (xy 55.671712 -305.948112)
			(xy 55.656128 -305.994793) (xy 55.633257 -306.03837) (xy 55.603692 -306.077714) (xy 55.568199 -306.111806)
			(xy 55.527696 -306.139762) (xy 55.483234 -306.16086) (xy 55.435963 -306.174552) (xy 55.387108 -306.180484)
			(xy 55.337933 -306.178503) (xy 55.289714 -306.168659) (xy 55.243698 -306.151207) (xy 55.201077 -306.1266)
			(xy 55.162956 -306.095475) (xy 55.130321 -306.058638) (xy 55.104018 -306.017042) (xy 55.084727 -305.971766)
			(xy 55.07295 -305.923982) (xy 55.06899 -305.874928) (xy 54.730142 -305.874928) (xy 54.729647 -305.899535)
			(xy 54.721752 -305.948112) (xy 54.706168 -305.994793) (xy 54.683297 -306.03837) (xy 54.653732 -306.077714)
			(xy 54.618239 -306.111806) (xy 54.577736 -306.139762) (xy 54.533274 -306.16086) (xy 54.486003 -306.174552)
			(xy 54.437148 -306.180484) (xy 54.387973 -306.178503) (xy 54.339754 -306.168659) (xy 54.293738 -306.151207)
			(xy 54.251117 -306.1266) (xy 54.212996 -306.095475) (xy 54.180361 -306.058638) (xy 54.154058 -306.017042)
			(xy 54.134767 -305.971766) (xy 54.12299 -305.923982) (xy 54.11903 -305.874928) (xy 53.780182 -305.874928)
			(xy 53.779687 -305.899535) (xy 53.771792 -305.948112) (xy 53.756208 -305.994793) (xy 53.733337 -306.03837)
			(xy 53.703772 -306.077714) (xy 53.668279 -306.111806) (xy 53.627776 -306.139762) (xy 53.583314 -306.16086)
			(xy 53.536043 -306.174552) (xy 53.487188 -306.180484) (xy 53.438013 -306.178503) (xy 53.389794 -306.168659)
			(xy 53.343778 -306.151207) (xy 53.301157 -306.1266) (xy 53.263036 -306.095475) (xy 53.230401 -306.058638)
			(xy 53.204098 -306.017042) (xy 53.184807 -305.971766) (xy 53.17303 -305.923982) (xy 53.16907 -305.874928)
			(xy 52.830222 -305.874928) (xy 52.829727 -305.899535) (xy 52.821832 -305.948112) (xy 52.806248 -305.994793)
			(xy 52.783377 -306.03837) (xy 52.753812 -306.077714) (xy 52.718319 -306.111806) (xy 52.677816 -306.139762)
			(xy 52.633354 -306.16086) (xy 52.586083 -306.174552) (xy 52.537228 -306.180484) (xy 52.488053 -306.178503)
			(xy 52.439834 -306.168659) (xy 52.393818 -306.151207) (xy 52.351197 -306.1266) (xy 52.313076 -306.095475)
			(xy 52.280441 -306.058638) (xy 52.254138 -306.017042) (xy 52.234847 -305.971766) (xy 52.22307 -305.923982)
			(xy 52.21911 -305.874928) (xy 51.880262 -305.874928) (xy 51.879767 -305.899535) (xy 51.871872 -305.948112)
			(xy 51.856288 -305.994793) (xy 51.833417 -306.03837) (xy 51.803852 -306.077714) (xy 51.768359 -306.111806)
			(xy 51.727856 -306.139762) (xy 51.683394 -306.16086) (xy 51.636123 -306.174552) (xy 51.587268 -306.180484)
			(xy 51.538093 -306.178503) (xy 51.489874 -306.168659) (xy 51.443858 -306.151207) (xy 51.401237 -306.1266)
			(xy 51.363116 -306.095475) (xy 51.330481 -306.058638) (xy 51.304178 -306.017042) (xy 51.284887 -305.971766)
			(xy 51.27311 -305.923982) (xy 51.26915 -305.874928) (xy 50.930302 -305.874928) (xy 50.929807 -305.899535)
			(xy 50.921912 -305.948112) (xy 50.906328 -305.994793) (xy 50.883457 -306.03837) (xy 50.853892 -306.077714)
			(xy 50.818399 -306.111806) (xy 50.777896 -306.139762) (xy 50.733434 -306.16086) (xy 50.686163 -306.174552)
			(xy 50.637308 -306.180484) (xy 50.588133 -306.178503) (xy 50.539914 -306.168659) (xy 50.493898 -306.151207)
			(xy 50.451277 -306.1266) (xy 50.413156 -306.095475) (xy 50.380521 -306.058638) (xy 50.354218 -306.017042)
			(xy 50.334927 -305.971766) (xy 50.32315 -305.923982) (xy 50.31919 -305.874928) (xy 49.980088 -305.874928)
			(xy 49.979593 -305.899535) (xy 49.971698 -305.948112) (xy 49.956114 -305.994793) (xy 49.933243 -306.03837)
			(xy 49.903678 -306.077714) (xy 49.868185 -306.111806) (xy 49.827682 -306.139762) (xy 49.78322 -306.16086)
			(xy 49.735949 -306.174552) (xy 49.687094 -306.180484) (xy 49.637919 -306.178503) (xy 49.5897 -306.168659)
			(xy 49.543684 -306.151207) (xy 49.501063 -306.1266) (xy 49.462942 -306.095475) (xy 49.430307 -306.058638)
			(xy 49.404004 -306.017042) (xy 49.384713 -305.971766) (xy 49.372936 -305.923982) (xy 49.368976 -305.874928)
			(xy 49.030128 -305.874928) (xy 49.029633 -305.899535) (xy 49.021738 -305.948112) (xy 49.006154 -305.994793)
			(xy 48.983283 -306.03837) (xy 48.953718 -306.077714) (xy 48.918225 -306.111806) (xy 48.877722 -306.139762)
			(xy 48.83326 -306.16086) (xy 48.785989 -306.174552) (xy 48.737134 -306.180484) (xy 48.687959 -306.178503)
			(xy 48.63974 -306.168659) (xy 48.593724 -306.151207) (xy 48.551103 -306.1266) (xy 48.512982 -306.095475)
			(xy 48.480347 -306.058638) (xy 48.454044 -306.017042) (xy 48.434753 -305.971766) (xy 48.422976 -305.923982)
			(xy 48.419016 -305.874928) (xy 48.080198 -305.874928) (xy 48.080646 -305.8832) (xy 48.075275 -305.932557)
			(xy 48.06199 -305.980395) (xy 48.041139 -306.025454) (xy 48.013274 -306.066545) (xy 47.979127 -306.102586)
			(xy 47.939599 -306.132628) (xy 47.895731 -306.15588) (xy 47.84868 -306.171727) (xy 47.799684 -306.179753)
			(xy 47.77486 -306.180236) (xy 47.760677 -306.180064) (xy 47.732437 -306.177389) (xy 47.718472 -306.174902)
			(xy 47.704512 -306.172687) (xy 47.676374 -306.175273) (xy 47.650021 -306.18547) (xy 47.627472 -306.202499)
			(xy 47.610452 -306.225055) (xy 47.600264 -306.251412) (xy 47.597689 -306.279551) (xy 47.599854 -306.29352)
			(xy 47.602329 -306.307486) (xy 47.605002 -306.335726) (xy 47.605188 -306.349908) (xy 47.604714 -306.374728)
			(xy 47.596682 -306.423713) (xy 47.580831 -306.470754) (xy 47.557578 -306.51461) (xy 47.527537 -306.554128)
			(xy 47.491499 -306.588264) (xy 47.450413 -306.616121) (xy 47.405361 -306.636964) (xy 47.357531 -306.650244)
			(xy 47.308183 -306.655611) (xy 47.258616 -306.652924) (xy 47.210137 -306.642253) (xy 47.164023 -306.62388)
			(xy 47.121489 -306.598289) (xy 47.083655 -306.566154) (xy 47.051518 -306.528321) (xy 47.025925 -306.485788)
			(xy 47.00755 -306.439674) (xy 46.996878 -306.391196) (xy 46.994189 -306.341629) (xy 46.655061 -306.341629)
			(xy 46.655228 -306.349908) (xy 46.654733 -306.374515) (xy 46.646838 -306.423092) (xy 46.631254 -306.469773)
			(xy 46.608383 -306.51335) (xy 46.578818 -306.552694) (xy 46.543325 -306.586786) (xy 46.502822 -306.614742)
			(xy 46.45836 -306.63584) (xy 46.411089 -306.649532) (xy 46.362234 -306.655464) (xy 46.313059 -306.653483)
			(xy 46.26484 -306.643639) (xy 46.218824 -306.626187) (xy 46.176203 -306.60158) (xy 46.138082 -306.570455)
			(xy 46.105447 -306.533618) (xy 46.079144 -306.492022) (xy 46.059853 -306.446746) (xy 46.048076 -306.398962)
			(xy 46.044116 -306.349908) (xy 45.705268 -306.349908) (xy 45.704773 -306.374515) (xy 45.696878 -306.423092)
			(xy 45.681294 -306.469773) (xy 45.658423 -306.51335) (xy 45.628858 -306.552694) (xy 45.593365 -306.586786)
			(xy 45.552862 -306.614742) (xy 45.5084 -306.63584) (xy 45.461129 -306.649532) (xy 45.412274 -306.655464)
			(xy 45.363099 -306.653483) (xy 45.31488 -306.643639) (xy 45.268864 -306.626187) (xy 45.226243 -306.60158)
			(xy 45.188122 -306.570455) (xy 45.155487 -306.533618) (xy 45.129184 -306.492022) (xy 45.109893 -306.446746)
			(xy 45.098116 -306.398962) (xy 45.094156 -306.349908) (xy 44.776898 -306.349908) (xy 44.776394 -306.375616)
			(xy 44.768351 -306.426398) (xy 44.752463 -306.475297) (xy 44.72912 -306.521109) (xy 44.698899 -306.562705)
			(xy 44.662543 -306.599061) (xy 44.620947 -306.629282) (xy 44.575135 -306.652625) (xy 44.526236 -306.668513)
			(xy 44.475454 -306.676556) (xy 44.424038 -306.676556) (xy 44.373256 -306.668513) (xy 44.324357 -306.652625)
			(xy 44.278545 -306.629282) (xy 44.236949 -306.599061) (xy 44.200593 -306.562705) (xy 44.170372 -306.521109)
			(xy 44.147029 -306.475297) (xy 44.131141 -306.426398) (xy 44.123098 -306.375616) (xy 43.826434 -306.375616)
			(xy 43.818391 -306.426398) (xy 43.802503 -306.475297) (xy 43.77916 -306.521109) (xy 43.748939 -306.562705)
			(xy 43.712583 -306.599061) (xy 43.670987 -306.629282) (xy 43.625175 -306.652625) (xy 43.576276 -306.668513)
			(xy 43.525494 -306.676556) (xy 43.474078 -306.676556) (xy 43.423296 -306.668513) (xy 43.374397 -306.652625)
			(xy 43.328585 -306.629282) (xy 43.286989 -306.599061) (xy 43.250633 -306.562705) (xy 43.220412 -306.521109)
			(xy 43.197069 -306.475297) (xy 43.181181 -306.426398) (xy 43.173138 -306.375616) (xy 42.85446 -306.375616)
			(xy 42.846744 -306.423092) (xy 42.83116 -306.469773) (xy 42.808289 -306.51335) (xy 42.778724 -306.552694)
			(xy 42.743231 -306.586786) (xy 42.702728 -306.614742) (xy 42.658266 -306.63584) (xy 42.610995 -306.649532)
			(xy 42.56214 -306.655464) (xy 42.512965 -306.653483) (xy 42.464746 -306.643639) (xy 42.41873 -306.626187)
			(xy 42.376109 -306.60158) (xy 42.337988 -306.570455) (xy 42.305353 -306.533618) (xy 42.27905 -306.492022)
			(xy 42.259759 -306.446746) (xy 42.247982 -306.398962) (xy 42.244022 -306.349908) (xy 41.905174 -306.349908)
			(xy 41.904679 -306.374515) (xy 41.896784 -306.423092) (xy 41.8812 -306.469773) (xy 41.858329 -306.51335)
			(xy 41.828764 -306.552694) (xy 41.793271 -306.586786) (xy 41.752768 -306.614742) (xy 41.708306 -306.63584)
			(xy 41.661035 -306.649532) (xy 41.61218 -306.655464) (xy 41.563005 -306.653483) (xy 41.514786 -306.643639)
			(xy 41.46877 -306.626187) (xy 41.426149 -306.60158) (xy 41.388028 -306.570455) (xy 41.355393 -306.533618)
			(xy 41.32909 -306.492022) (xy 41.309799 -306.446746) (xy 41.298022 -306.398962) (xy 41.294062 -306.349908)
			(xy 40.955214 -306.349908) (xy 40.954719 -306.374515) (xy 40.946824 -306.423092) (xy 40.93124 -306.469773)
			(xy 40.908369 -306.51335) (xy 40.878804 -306.552694) (xy 40.843311 -306.586786) (xy 40.802808 -306.614742)
			(xy 40.758346 -306.63584) (xy 40.711075 -306.649532) (xy 40.66222 -306.655464) (xy 40.613045 -306.653483)
			(xy 40.564826 -306.643639) (xy 40.51881 -306.626187) (xy 40.476189 -306.60158) (xy 40.438068 -306.570455)
			(xy 40.405433 -306.533618) (xy 40.37913 -306.492022) (xy 40.359839 -306.446746) (xy 40.348062 -306.398962)
			(xy 40.344102 -306.349908) (xy 40.005254 -306.349908) (xy 40.004759 -306.374515) (xy 39.996864 -306.423092)
			(xy 39.98128 -306.469773) (xy 39.958409 -306.51335) (xy 39.928844 -306.552694) (xy 39.893351 -306.586786)
			(xy 39.852848 -306.614742) (xy 39.808386 -306.63584) (xy 39.761115 -306.649532) (xy 39.71226 -306.655464)
			(xy 39.663085 -306.653483) (xy 39.614866 -306.643639) (xy 39.56885 -306.626187) (xy 39.526229 -306.60158)
			(xy 39.488108 -306.570455) (xy 39.455473 -306.533618) (xy 39.42917 -306.492022) (xy 39.409879 -306.446746)
			(xy 39.398102 -306.398962) (xy 39.394142 -306.349908) (xy 39.055294 -306.349908) (xy 39.054799 -306.374515)
			(xy 39.046904 -306.423092) (xy 39.03132 -306.469773) (xy 39.008449 -306.51335) (xy 38.978884 -306.552694)
			(xy 38.943391 -306.586786) (xy 38.902888 -306.614742) (xy 38.858426 -306.63584) (xy 38.811155 -306.649532)
			(xy 38.7623 -306.655464) (xy 38.713125 -306.653483) (xy 38.664906 -306.643639) (xy 38.61889 -306.626187)
			(xy 38.576269 -306.60158) (xy 38.538148 -306.570455) (xy 38.505513 -306.533618) (xy 38.47921 -306.492022)
			(xy 38.459919 -306.446746) (xy 38.448142 -306.398962) (xy 38.444182 -306.349908) (xy 38.126924 -306.349908)
			(xy 38.12642 -306.375616) (xy 38.118377 -306.426398) (xy 38.102489 -306.475297) (xy 38.079146 -306.521109)
			(xy 38.048925 -306.562705) (xy 38.012569 -306.599061) (xy 37.970973 -306.629282) (xy 37.925161 -306.652625)
			(xy 37.876262 -306.668513) (xy 37.82548 -306.676556) (xy 37.774064 -306.676556) (xy 37.723282 -306.668513)
			(xy 37.674383 -306.652625) (xy 37.628571 -306.629282) (xy 37.586975 -306.599061) (xy 37.550619 -306.562705)
			(xy 37.520398 -306.521109) (xy 37.497055 -306.475297) (xy 37.481167 -306.426398) (xy 37.473124 -306.375616)
			(xy 37.17646 -306.375616) (xy 37.168417 -306.426398) (xy 37.152529 -306.475297) (xy 37.129186 -306.521109)
			(xy 37.098965 -306.562705) (xy 37.062609 -306.599061) (xy 37.021013 -306.629282) (xy 36.975201 -306.652625)
			(xy 36.926302 -306.668513) (xy 36.87552 -306.676556) (xy 36.824104 -306.676556) (xy 36.773322 -306.668513)
			(xy 36.724423 -306.652625) (xy 36.678611 -306.629282) (xy 36.637015 -306.599061) (xy 36.600659 -306.562705)
			(xy 36.570438 -306.521109) (xy 36.547095 -306.475297) (xy 36.531207 -306.426398) (xy 36.523164 -306.375616)
			(xy 36.204273 -306.375616) (xy 36.196516 -306.423346) (xy 36.180932 -306.470027) (xy 36.158061 -306.513604)
			(xy 36.128496 -306.552948) (xy 36.093003 -306.58704) (xy 36.0525 -306.614996) (xy 36.008038 -306.636094)
			(xy 35.960767 -306.649786) (xy 35.911912 -306.655718) (xy 35.862737 -306.653737) (xy 35.814518 -306.643893)
			(xy 35.768502 -306.626441) (xy 35.725881 -306.601834) (xy 35.68776 -306.570709) (xy 35.655125 -306.533872)
			(xy 35.628822 -306.492276) (xy 35.609531 -306.447) (xy 35.597754 -306.399216) (xy 35.593794 -306.350162)
			(xy 27.311055 -306.350162) (xy 27.295125 -306.363419) (xy 27.247519 -306.392473) (xy 27.19619 -306.414285)
			(xy 27.142233 -306.428391) (xy 27.086796 -306.434491) (xy 27.031062 -306.432454) (xy 26.976219 -306.422324)
			(xy 26.923435 -306.404317) (xy 26.873835 -306.378816) (xy 26.828477 -306.346365) (xy 26.788328 -306.307656)
			(xy 26.754242 -306.263513) (xy 26.726946 -306.214878) (xy 26.707023 -306.162787) (xy 26.694897 -306.10835)
			(xy 26.690826 -306.052728) (xy 18.326327 -306.052728) (xy 18.326564 -306.053002) (xy 18.356052 -306.098886)
			(xy 18.37871 -306.148499) (xy 18.394076 -306.200832) (xy 18.401839 -306.254819) (xy 18.401839 -306.309361)
			(xy 18.394076 -306.363348) (xy 18.37871 -306.415681) (xy 18.356052 -306.465294) (xy 18.326564 -306.511178)
			(xy 18.290847 -306.552398) (xy 18.249626 -306.588116) (xy 18.203743 -306.617603) (xy 18.154129 -306.640261)
			(xy 18.101796 -306.655627) (xy 18.047809 -306.663389) (xy 18.020538 -306.663852) (xy 18.002132 -306.663617)
			(xy 17.965493 -306.660051) (xy 17.947386 -306.65674) (xy 17.913789 -306.649437) (xy 17.849767 -306.624388)
			(xy 17.820132 -306.606956) (xy 17.788382 -306.585112) (xy 17.787112 -306.58435) (xy 17.773641 -306.577373)
			(xy 17.744029 -306.570851) (xy 17.713807 -306.573306) (xy 17.685636 -306.584522) (xy 17.661996 -306.60351)
			(xy 17.64497 -306.6286) (xy 17.636056 -306.657582) (xy 17.635474 -306.672742) (xy 17.635474 -306.765198)
			(xy 29.725364 -306.765198) (xy 29.729435 -306.709576) (xy 29.741561 -306.655139) (xy 29.761484 -306.603048)
			(xy 29.78878 -306.554413) (xy 29.822866 -306.51027) (xy 29.863015 -306.471561) (xy 29.908373 -306.43911)
			(xy 29.957973 -306.413609) (xy 30.010757 -306.395602) (xy 30.0656 -306.385472) (xy 30.121334 -306.383435)
			(xy 30.176771 -306.389535) (xy 30.230728 -306.403641) (xy 30.282057 -306.425453) (xy 30.329663 -306.454507)
			(xy 30.372531 -306.490182) (xy 30.409748 -306.531719) (xy 30.440521 -306.578232) (xy 30.464193 -306.628729)
			(xy 30.480261 -306.682136) (xy 30.488381 -306.737312) (xy 30.48889 -306.765198) (xy 30.488381 -306.793084)
			(xy 30.480261 -306.84826) (xy 30.464193 -306.901667) (xy 30.440521 -306.952164) (xy 30.409748 -306.998677)
			(xy 30.372531 -307.040214) (xy 30.329663 -307.075889) (xy 30.282057 -307.104943) (xy 30.230728 -307.126755)
			(xy 30.176771 -307.140861) (xy 30.121334 -307.146961) (xy 30.0656 -307.144924) (xy 30.010757 -307.134794)
			(xy 29.957973 -307.116787) (xy 29.908373 -307.091286) (xy 29.863015 -307.058835) (xy 29.822866 -307.020126)
			(xy 29.78878 -306.975983) (xy 29.761484 -306.927348) (xy 29.741561 -306.875257) (xy 29.729435 -306.82082)
			(xy 29.725364 -306.765198) (xy 17.635474 -306.765198) (xy 17.635474 -307.240178) (xy 31.85998 -307.240178)
			(xy 31.864051 -307.184556) (xy 31.876177 -307.130119) (xy 31.8961 -307.078028) (xy 31.923396 -307.029393)
			(xy 31.957482 -306.98525) (xy 31.997631 -306.946541) (xy 32.042989 -306.91409) (xy 32.092589 -306.888589)
			(xy 32.145373 -306.870582) (xy 32.200216 -306.860452) (xy 32.25595 -306.858415) (xy 32.311387 -306.864515)
			(xy 32.365344 -306.878621) (xy 32.416673 -306.900433) (xy 32.464279 -306.929487) (xy 32.507147 -306.965162)
			(xy 32.544364 -307.006699) (xy 32.575137 -307.053212) (xy 32.598809 -307.103709) (xy 32.614877 -307.157116)
			(xy 32.622997 -307.212292) (xy 32.623506 -307.240178) (xy 32.622997 -307.268064) (xy 32.618317 -307.299868)
			(xy 36.544008 -307.299868) (xy 36.547968 -307.250814) (xy 36.559745 -307.20303) (xy 36.579036 -307.157754)
			(xy 36.605339 -307.116158) (xy 36.637974 -307.079321) (xy 36.676095 -307.048196) (xy 36.718716 -307.023589)
			(xy 36.764732 -307.006137) (xy 36.812951 -306.996293) (xy 36.862126 -306.994312) (xy 36.910981 -307.000244)
			(xy 36.958252 -307.013936) (xy 37.002714 -307.035034) (xy 37.043217 -307.06299) (xy 37.07871 -307.097082)
			(xy 37.108275 -307.136426) (xy 37.131146 -307.180003) (xy 37.14673 -307.226684) (xy 37.154625 -307.275261)
			(xy 37.15512 -307.299868) (xy 37.493968 -307.299868) (xy 37.497928 -307.250814) (xy 37.509705 -307.20303)
			(xy 37.528996 -307.157754) (xy 37.555299 -307.116158) (xy 37.587934 -307.079321) (xy 37.626055 -307.048196)
			(xy 37.668676 -307.023589) (xy 37.714692 -307.006137) (xy 37.762911 -306.996293) (xy 37.812086 -306.994312)
			(xy 37.860941 -307.000244) (xy 37.908212 -307.013936) (xy 37.952674 -307.035034) (xy 37.993177 -307.06299)
			(xy 38.02867 -307.097082) (xy 38.058235 -307.136426) (xy 38.081106 -307.180003) (xy 38.09669 -307.226684)
			(xy 38.104585 -307.275261) (xy 38.10508 -307.299868) (xy 38.104585 -307.324475) (xy 38.104406 -307.325576)
			(xy 38.423338 -307.325576) (xy 38.423338 -307.27416) (xy 38.431381 -307.223378) (xy 38.447269 -307.174479)
			(xy 38.470612 -307.128667) (xy 38.500833 -307.087071) (xy 38.537189 -307.050715) (xy 38.578785 -307.020494)
			(xy 38.624597 -306.997151) (xy 38.673496 -306.981263) (xy 38.724278 -306.97322) (xy 38.775694 -306.97322)
			(xy 38.826476 -306.981263) (xy 38.875375 -306.997151) (xy 38.921187 -307.020494) (xy 38.962783 -307.050715)
			(xy 38.999139 -307.087071) (xy 39.02936 -307.128667) (xy 39.052703 -307.174479) (xy 39.068591 -307.223378)
			(xy 39.076634 -307.27416) (xy 39.077138 -307.299868) (xy 39.076634 -307.325576) (xy 39.373298 -307.325576)
			(xy 39.373298 -307.27416) (xy 39.381341 -307.223378) (xy 39.397229 -307.174479) (xy 39.420572 -307.128667)
			(xy 39.450793 -307.087071) (xy 39.487149 -307.050715) (xy 39.528745 -307.020494) (xy 39.574557 -306.997151)
			(xy 39.623456 -306.981263) (xy 39.674238 -306.97322) (xy 39.725654 -306.97322) (xy 39.776436 -306.981263)
			(xy 39.825335 -306.997151) (xy 39.871147 -307.020494) (xy 39.912743 -307.050715) (xy 39.949099 -307.087071)
			(xy 39.97932 -307.128667) (xy 40.002663 -307.174479) (xy 40.018551 -307.223378) (xy 40.026594 -307.27416)
			(xy 40.027098 -307.299868) (xy 40.344102 -307.299868) (xy 40.348062 -307.250814) (xy 40.359839 -307.20303)
			(xy 40.37913 -307.157754) (xy 40.405433 -307.116158) (xy 40.438068 -307.079321) (xy 40.476189 -307.048196)
			(xy 40.51881 -307.023589) (xy 40.564826 -307.006137) (xy 40.613045 -306.996293) (xy 40.66222 -306.994312)
			(xy 40.711075 -307.000244) (xy 40.758346 -307.013936) (xy 40.802808 -307.035034) (xy 40.843311 -307.06299)
			(xy 40.878804 -307.097082) (xy 40.908369 -307.136426) (xy 40.93124 -307.180003) (xy 40.946824 -307.226684)
			(xy 40.954719 -307.275261) (xy 40.955214 -307.299868) (xy 40.954719 -307.324475) (xy 40.95454 -307.325576)
			(xy 41.273218 -307.325576) (xy 41.273218 -307.27416) (xy 41.281261 -307.223378) (xy 41.297149 -307.174479)
			(xy 41.320492 -307.128667) (xy 41.350713 -307.087071) (xy 41.387069 -307.050715) (xy 41.428665 -307.020494)
			(xy 41.474477 -306.997151) (xy 41.523376 -306.981263) (xy 41.574158 -306.97322) (xy 41.625574 -306.97322)
			(xy 41.676356 -306.981263) (xy 41.725255 -306.997151) (xy 41.771067 -307.020494) (xy 41.812663 -307.050715)
			(xy 41.849019 -307.087071) (xy 41.87924 -307.128667) (xy 41.902583 -307.174479) (xy 41.918471 -307.223378)
			(xy 41.926514 -307.27416) (xy 41.927018 -307.299868) (xy 41.926514 -307.325576) (xy 42.223178 -307.325576)
			(xy 42.223178 -307.27416) (xy 42.231221 -307.223378) (xy 42.247109 -307.174479) (xy 42.270452 -307.128667)
			(xy 42.300673 -307.087071) (xy 42.337029 -307.050715) (xy 42.378625 -307.020494) (xy 42.424437 -306.997151)
			(xy 42.473336 -306.981263) (xy 42.524118 -306.97322) (xy 42.575534 -306.97322) (xy 42.626316 -306.981263)
			(xy 42.675215 -306.997151) (xy 42.721027 -307.020494) (xy 42.762623 -307.050715) (xy 42.798979 -307.087071)
			(xy 42.8292 -307.128667) (xy 42.852543 -307.174479) (xy 42.868431 -307.223378) (xy 42.876474 -307.27416)
			(xy 42.876978 -307.299868) (xy 43.193982 -307.299868) (xy 43.197942 -307.250814) (xy 43.209719 -307.20303)
			(xy 43.22901 -307.157754) (xy 43.255313 -307.116158) (xy 43.287948 -307.079321) (xy 43.326069 -307.048196)
			(xy 43.36869 -307.023589) (xy 43.414706 -307.006137) (xy 43.462925 -306.996293) (xy 43.5121 -306.994312)
			(xy 43.560955 -307.000244) (xy 43.608226 -307.013936) (xy 43.652688 -307.035034) (xy 43.693191 -307.06299)
			(xy 43.728684 -307.097082) (xy 43.758249 -307.136426) (xy 43.78112 -307.180003) (xy 43.796704 -307.226684)
			(xy 43.804599 -307.275261) (xy 43.805094 -307.299868) (xy 44.143942 -307.299868) (xy 44.147902 -307.250814)
			(xy 44.159679 -307.20303) (xy 44.17897 -307.157754) (xy 44.205273 -307.116158) (xy 44.237908 -307.079321)
			(xy 44.276029 -307.048196) (xy 44.31865 -307.023589) (xy 44.364666 -307.006137) (xy 44.412885 -306.996293)
			(xy 44.46206 -306.994312) (xy 44.510915 -307.000244) (xy 44.558186 -307.013936) (xy 44.602648 -307.035034)
			(xy 44.643151 -307.06299) (xy 44.678644 -307.097082) (xy 44.708209 -307.136426) (xy 44.73108 -307.180003)
			(xy 44.746664 -307.226684) (xy 44.754559 -307.275261) (xy 44.755054 -307.299868) (xy 45.094156 -307.299868)
			(xy 45.098116 -307.250814) (xy 45.109893 -307.20303) (xy 45.129184 -307.157754) (xy 45.155487 -307.116158)
			(xy 45.188122 -307.079321) (xy 45.226243 -307.048196) (xy 45.268864 -307.023589) (xy 45.31488 -307.006137)
			(xy 45.363099 -306.996293) (xy 45.412274 -306.994312) (xy 45.461129 -307.000244) (xy 45.5084 -307.013936)
			(xy 45.552862 -307.035034) (xy 45.593365 -307.06299) (xy 45.628858 -307.097082) (xy 45.658423 -307.136426)
			(xy 45.681294 -307.180003) (xy 45.696878 -307.226684) (xy 45.704773 -307.275261) (xy 45.705268 -307.299868)
			(xy 46.044116 -307.299868) (xy 46.048076 -307.250814) (xy 46.059853 -307.20303) (xy 46.079144 -307.157754)
			(xy 46.105447 -307.116158) (xy 46.138082 -307.079321) (xy 46.176203 -307.048196) (xy 46.218824 -307.023589)
			(xy 46.26484 -307.006137) (xy 46.313059 -306.996293) (xy 46.362234 -306.994312) (xy 46.411089 -307.000244)
			(xy 46.45836 -307.013936) (xy 46.502822 -307.035034) (xy 46.543325 -307.06299) (xy 46.578818 -307.097082)
			(xy 46.608383 -307.136426) (xy 46.631254 -307.180003) (xy 46.646838 -307.226684) (xy 46.654733 -307.275261)
			(xy 46.655228 -307.299868) (xy 46.994076 -307.299868) (xy 46.998036 -307.250814) (xy 47.009813 -307.20303)
			(xy 47.029104 -307.157754) (xy 47.055407 -307.116158) (xy 47.088042 -307.079321) (xy 47.126163 -307.048196)
			(xy 47.168784 -307.023589) (xy 47.2148 -307.006137) (xy 47.263019 -306.996293) (xy 47.312194 -306.994312)
			(xy 47.361049 -307.000244) (xy 47.40832 -307.013936) (xy 47.452782 -307.035034) (xy 47.493285 -307.06299)
			(xy 47.528778 -307.097082) (xy 47.558343 -307.136426) (xy 47.581214 -307.180003) (xy 47.596798 -307.226684)
			(xy 47.604693 -307.275261) (xy 47.605022 -307.291601) (xy 47.94405 -307.291601) (xy 47.949421 -307.242243)
			(xy 47.962706 -307.194404) (xy 47.983557 -307.149345) (xy 48.011423 -307.108253) (xy 48.04557 -307.072211)
			(xy 48.085098 -307.042168) (xy 48.128967 -307.018917) (xy 48.176019 -307.003069) (xy 48.225015 -306.995043)
			(xy 48.24984 -306.99456) (xy 48.264023 -306.994732) (xy 48.292263 -306.997407) (xy 48.306228 -306.999894)
			(xy 48.318674 -307.00218) (xy 48.342296 -306.994814) (xy 48.419766 -306.917344) (xy 48.427132 -306.893722)
			(xy 48.424846 -306.881276) (xy 48.422371 -306.86731) (xy 48.419698 -306.83907) (xy 48.419512 -306.824888)
			(xy 48.420034 -306.799633) (xy 48.428347 -306.749811) (xy 48.444748 -306.702037) (xy 48.468789 -306.657614)
			(xy 48.499813 -306.617754) (xy 48.536975 -306.583544) (xy 48.579261 -306.555918) (xy 48.625517 -306.535628)
			(xy 48.674482 -306.523228) (xy 48.72482 -306.519057) (xy 48.775158 -306.523228) (xy 48.824123 -306.535628)
			(xy 48.870379 -306.555918) (xy 48.912665 -306.583544) (xy 48.949827 -306.617754) (xy 48.980851 -306.657614)
			(xy 49.004892 -306.702037) (xy 49.021293 -306.749811) (xy 49.029606 -306.799633) (xy 49.030128 -306.824888)
			(xy 49.029949 -306.839071) (xy 49.027279 -306.867311) (xy 49.024794 -306.881276) (xy 49.022508 -306.893722)
			(xy 49.029874 -306.917344) (xy 49.107344 -306.994814) (xy 49.130966 -307.00218) (xy 49.143412 -306.999894)
			(xy 49.157378 -306.99742) (xy 49.185618 -306.994747) (xy 49.1998 -306.99456) (xy 49.213983 -306.994737)
			(xy 49.242223 -306.997409) (xy 49.256188 -306.999894) (xy 49.268634 -307.00218) (xy 49.292256 -306.994814)
			(xy 49.369726 -306.917344) (xy 49.377092 -306.893722) (xy 49.374806 -306.881276) (xy 49.37233 -306.86731)
			(xy 49.369658 -306.839071) (xy 49.369472 -306.824888) (xy 49.369994 -306.799633) (xy 49.378307 -306.749811)
			(xy 49.394708 -306.702037) (xy 49.418749 -306.657614) (xy 49.449773 -306.617754) (xy 49.486935 -306.583544)
			(xy 49.529221 -306.555918) (xy 49.575477 -306.535628) (xy 49.624442 -306.523228) (xy 49.67478 -306.519057)
			(xy 49.725118 -306.523228) (xy 49.774083 -306.535628) (xy 49.820339 -306.555918) (xy 49.862625 -306.583544)
			(xy 49.899787 -306.617754) (xy 49.930811 -306.657614) (xy 49.954852 -306.702037) (xy 49.971253 -306.749811)
			(xy 49.979566 -306.799633) (xy 49.980088 -306.824888) (xy 49.97991 -306.839071) (xy 49.977239 -306.867311)
			(xy 49.974754 -306.881276) (xy 49.972468 -306.893722) (xy 49.979834 -306.917344) (xy 50.057304 -306.994814)
			(xy 50.080926 -307.00218) (xy 50.093372 -306.999894) (xy 50.107337 -306.997412) (xy 50.135577 -306.994744)
			(xy 50.14976 -306.99456) (xy 50.164007 -306.99472) (xy 50.192375 -306.997394) (xy 50.206402 -306.999894)
			(xy 50.218848 -307.00218) (xy 50.24247 -306.994814) (xy 50.31105 -306.926488) (xy 50.319222 -306.917262)
			(xy 50.326524 -306.893763) (xy 50.32502 -306.88153) (xy 50.32502 -306.881022) (xy 50.322563 -306.867117)
			(xy 50.319888 -306.839006) (xy 50.319686 -306.824888) (xy 50.320191 -306.800068) (xy 50.328223 -306.751083)
			(xy 50.344075 -306.704042) (xy 50.367328 -306.660186) (xy 50.397371 -306.62067) (xy 50.43341 -306.586534)
			(xy 50.474497 -306.558678) (xy 50.519549 -306.537837) (xy 50.56738 -306.524558) (xy 50.616729 -306.519193)
			(xy 50.666295 -306.521882) (xy 50.714774 -306.532555) (xy 50.760887 -306.550929) (xy 50.803421 -306.576523)
			(xy 50.841253 -306.60866) (xy 50.873388 -306.646494) (xy 50.898979 -306.689029) (xy 50.917351 -306.735143)
			(xy 50.928021 -306.783623) (xy 50.930257 -306.824888) (xy 51.26915 -306.824888) (xy 51.27311 -306.775834)
			(xy 51.284887 -306.72805) (xy 51.304178 -306.682774) (xy 51.330481 -306.641178) (xy 51.363116 -306.604341)
			(xy 51.401237 -306.573216) (xy 51.443858 -306.548609) (xy 51.489874 -306.531157) (xy 51.538093 -306.521313)
			(xy 51.587268 -306.519332) (xy 51.636123 -306.525264) (xy 51.683394 -306.538956) (xy 51.727856 -306.560054)
			(xy 51.768359 -306.58801) (xy 51.803852 -306.622102) (xy 51.833417 -306.661446) (xy 51.856288 -306.705023)
			(xy 51.871872 -306.751704) (xy 51.879767 -306.800281) (xy 51.880262 -306.824888) (xy 52.21911 -306.824888)
			(xy 52.22307 -306.775834) (xy 52.234847 -306.72805) (xy 52.254138 -306.682774) (xy 52.280441 -306.641178)
			(xy 52.313076 -306.604341) (xy 52.351197 -306.573216) (xy 52.393818 -306.548609) (xy 52.439834 -306.531157)
			(xy 52.488053 -306.521313) (xy 52.537228 -306.519332) (xy 52.586083 -306.525264) (xy 52.633354 -306.538956)
			(xy 52.677816 -306.560054) (xy 52.718319 -306.58801) (xy 52.753812 -306.622102) (xy 52.783377 -306.661446)
			(xy 52.806248 -306.705023) (xy 52.821832 -306.751704) (xy 52.829727 -306.800281) (xy 52.830222 -306.824888)
			(xy 53.16907 -306.824888) (xy 53.17303 -306.775834) (xy 53.184807 -306.72805) (xy 53.204098 -306.682774)
			(xy 53.230401 -306.641178) (xy 53.263036 -306.604341) (xy 53.301157 -306.573216) (xy 53.343778 -306.548609)
			(xy 53.389794 -306.531157) (xy 53.438013 -306.521313) (xy 53.487188 -306.519332) (xy 53.536043 -306.525264)
			(xy 53.583314 -306.538956) (xy 53.627776 -306.560054) (xy 53.668279 -306.58801) (xy 53.703772 -306.622102)
			(xy 53.733337 -306.661446) (xy 53.756208 -306.705023) (xy 53.771792 -306.751704) (xy 53.779687 -306.800281)
			(xy 53.780182 -306.824888) (xy 54.11903 -306.824888) (xy 54.12299 -306.775834) (xy 54.134767 -306.72805)
			(xy 54.154058 -306.682774) (xy 54.180361 -306.641178) (xy 54.212996 -306.604341) (xy 54.251117 -306.573216)
			(xy 54.293738 -306.548609) (xy 54.339754 -306.531157) (xy 54.387973 -306.521313) (xy 54.437148 -306.519332)
			(xy 54.486003 -306.525264) (xy 54.533274 -306.538956) (xy 54.577736 -306.560054) (xy 54.618239 -306.58801)
			(xy 54.653732 -306.622102) (xy 54.683297 -306.661446) (xy 54.706168 -306.705023) (xy 54.721752 -306.751704)
			(xy 54.729647 -306.800281) (xy 54.730142 -306.824888) (xy 55.06899 -306.824888) (xy 55.07295 -306.775834)
			(xy 55.084727 -306.72805) (xy 55.104018 -306.682774) (xy 55.130321 -306.641178) (xy 55.162956 -306.604341)
			(xy 55.201077 -306.573216) (xy 55.243698 -306.548609) (xy 55.289714 -306.531157) (xy 55.337933 -306.521313)
			(xy 55.387108 -306.519332) (xy 55.435963 -306.525264) (xy 55.483234 -306.538956) (xy 55.527696 -306.560054)
			(xy 55.568199 -306.58801) (xy 55.603692 -306.622102) (xy 55.633257 -306.661446) (xy 55.656128 -306.705023)
			(xy 55.671712 -306.751704) (xy 55.679607 -306.800281) (xy 55.680102 -306.824888) (xy 56.01895 -306.824888)
			(xy 56.02291 -306.775834) (xy 56.034687 -306.72805) (xy 56.053978 -306.682774) (xy 56.080281 -306.641178)
			(xy 56.112916 -306.604341) (xy 56.151037 -306.573216) (xy 56.193658 -306.548609) (xy 56.239674 -306.531157)
			(xy 56.287893 -306.521313) (xy 56.337068 -306.519332) (xy 56.385923 -306.525264) (xy 56.433194 -306.538956)
			(xy 56.477656 -306.560054) (xy 56.518159 -306.58801) (xy 56.553652 -306.622102) (xy 56.583217 -306.661446)
			(xy 56.606088 -306.705023) (xy 56.621672 -306.751704) (xy 56.629567 -306.800281) (xy 56.630062 -306.824888)
			(xy 56.969164 -306.824888) (xy 56.973124 -306.775834) (xy 56.984901 -306.72805) (xy 57.004192 -306.682774)
			(xy 57.030495 -306.641178) (xy 57.06313 -306.604341) (xy 57.101251 -306.573216) (xy 57.143872 -306.548609)
			(xy 57.189888 -306.531157) (xy 57.238107 -306.521313) (xy 57.287282 -306.519332) (xy 57.336137 -306.525264)
			(xy 57.383408 -306.538956) (xy 57.42787 -306.560054) (xy 57.468373 -306.58801) (xy 57.503866 -306.622102)
			(xy 57.533431 -306.661446) (xy 57.556302 -306.705023) (xy 57.571886 -306.751704) (xy 57.579781 -306.800281)
			(xy 57.580276 -306.824888) (xy 57.919124 -306.824888) (xy 57.923084 -306.775834) (xy 57.934861 -306.72805)
			(xy 57.954152 -306.682774) (xy 57.980455 -306.641178) (xy 58.01309 -306.604341) (xy 58.051211 -306.573216)
			(xy 58.093832 -306.548609) (xy 58.139848 -306.531157) (xy 58.188067 -306.521313) (xy 58.237242 -306.519332)
			(xy 58.286097 -306.525264) (xy 58.333368 -306.538956) (xy 58.37783 -306.560054) (xy 58.418333 -306.58801)
			(xy 58.453826 -306.622102) (xy 58.483391 -306.661446) (xy 58.506262 -306.705023) (xy 58.521846 -306.751704)
			(xy 58.529741 -306.800281) (xy 58.530236 -306.824888) (xy 59.819044 -306.824888) (xy 59.823004 -306.775834)
			(xy 59.834781 -306.72805) (xy 59.854072 -306.682774) (xy 59.880375 -306.641178) (xy 59.91301 -306.604341)
			(xy 59.951131 -306.573216) (xy 59.993752 -306.548609) (xy 60.039768 -306.531157) (xy 60.087987 -306.521313)
			(xy 60.137162 -306.519332) (xy 60.186017 -306.525264) (xy 60.233288 -306.538956) (xy 60.27775 -306.560054)
			(xy 60.318253 -306.58801) (xy 60.353746 -306.622102) (xy 60.383311 -306.661446) (xy 60.406182 -306.705023)
			(xy 60.421766 -306.751704) (xy 60.429661 -306.800281) (xy 60.430156 -306.824888) (xy 60.769004 -306.824888)
			(xy 60.772964 -306.775834) (xy 60.784741 -306.72805) (xy 60.804032 -306.682774) (xy 60.830335 -306.641178)
			(xy 60.86297 -306.604341) (xy 60.901091 -306.573216) (xy 60.943712 -306.548609) (xy 60.989728 -306.531157)
			(xy 61.037947 -306.521313) (xy 61.087122 -306.519332) (xy 61.135977 -306.525264) (xy 61.183248 -306.538956)
			(xy 61.22771 -306.560054) (xy 61.268213 -306.58801) (xy 61.303706 -306.622102) (xy 61.333271 -306.661446)
			(xy 61.356142 -306.705023) (xy 61.371726 -306.751704) (xy 61.379621 -306.800281) (xy 61.380116 -306.824888)
			(xy 61.718964 -306.824888) (xy 61.722924 -306.775834) (xy 61.734701 -306.72805) (xy 61.753992 -306.682774)
			(xy 61.780295 -306.641178) (xy 61.81293 -306.604341) (xy 61.851051 -306.573216) (xy 61.893672 -306.548609)
			(xy 61.939688 -306.531157) (xy 61.987907 -306.521313) (xy 62.037082 -306.519332) (xy 62.085937 -306.525264)
			(xy 62.133208 -306.538956) (xy 62.17767 -306.560054) (xy 62.218173 -306.58801) (xy 62.253666 -306.622102)
			(xy 62.283231 -306.661446) (xy 62.306102 -306.705023) (xy 62.321686 -306.751704) (xy 62.329581 -306.800281)
			(xy 62.330076 -306.824888) (xy 62.669178 -306.824888) (xy 62.673138 -306.775834) (xy 62.684915 -306.72805)
			(xy 62.704206 -306.682774) (xy 62.730509 -306.641178) (xy 62.763144 -306.604341) (xy 62.801265 -306.573216)
			(xy 62.843886 -306.548609) (xy 62.889902 -306.531157) (xy 62.938121 -306.521313) (xy 62.987296 -306.519332)
			(xy 63.036151 -306.525264) (xy 63.083422 -306.538956) (xy 63.127884 -306.560054) (xy 63.168387 -306.58801)
			(xy 63.20388 -306.622102) (xy 63.233445 -306.661446) (xy 63.256316 -306.705023) (xy 63.2719 -306.751704)
			(xy 63.279795 -306.800281) (xy 63.28029 -306.824888) (xy 63.619138 -306.824888) (xy 63.623098 -306.775834)
			(xy 63.634875 -306.72805) (xy 63.654166 -306.682774) (xy 63.680469 -306.641178) (xy 63.713104 -306.604341)
			(xy 63.751225 -306.573216) (xy 63.793846 -306.548609) (xy 63.839862 -306.531157) (xy 63.888081 -306.521313)
			(xy 63.937256 -306.519332) (xy 63.986111 -306.525264) (xy 64.033382 -306.538956) (xy 64.077844 -306.560054)
			(xy 64.118347 -306.58801) (xy 64.15384 -306.622102) (xy 64.183405 -306.661446) (xy 64.206276 -306.705023)
			(xy 64.22186 -306.751704) (xy 64.229755 -306.800281) (xy 64.23025 -306.824888) (xy 64.569098 -306.824888)
			(xy 64.573058 -306.775834) (xy 64.584835 -306.72805) (xy 64.604126 -306.682774) (xy 64.630429 -306.641178)
			(xy 64.663064 -306.604341) (xy 64.701185 -306.573216) (xy 64.743806 -306.548609) (xy 64.789822 -306.531157)
			(xy 64.838041 -306.521313) (xy 64.887216 -306.519332) (xy 64.936071 -306.525264) (xy 64.983342 -306.538956)
			(xy 65.027804 -306.560054) (xy 65.068307 -306.58801) (xy 65.1038 -306.622102) (xy 65.133365 -306.661446)
			(xy 65.156236 -306.705023) (xy 65.17182 -306.751704) (xy 65.179715 -306.800281) (xy 65.18021 -306.824888)
			(xy 65.519058 -306.824888) (xy 65.523018 -306.775834) (xy 65.534795 -306.72805) (xy 65.554086 -306.682774)
			(xy 65.580389 -306.641178) (xy 65.613024 -306.604341) (xy 65.651145 -306.573216) (xy 65.693766 -306.548609)
			(xy 65.739782 -306.531157) (xy 65.788001 -306.521313) (xy 65.837176 -306.519332) (xy 65.886031 -306.525264)
			(xy 65.933302 -306.538956) (xy 65.977764 -306.560054) (xy 66.018267 -306.58801) (xy 66.05376 -306.622102)
			(xy 66.083325 -306.661446) (xy 66.106196 -306.705023) (xy 66.12178 -306.751704) (xy 66.129675 -306.800281)
			(xy 66.13017 -306.824888) (xy 66.469018 -306.824888) (xy 66.472978 -306.775834) (xy 66.484755 -306.72805)
			(xy 66.504046 -306.682774) (xy 66.530349 -306.641178) (xy 66.562984 -306.604341) (xy 66.601105 -306.573216)
			(xy 66.643726 -306.548609) (xy 66.689742 -306.531157) (xy 66.737961 -306.521313) (xy 66.787136 -306.519332)
			(xy 66.835991 -306.525264) (xy 66.883262 -306.538956) (xy 66.927724 -306.560054) (xy 66.968227 -306.58801)
			(xy 67.00372 -306.622102) (xy 67.033285 -306.661446) (xy 67.056156 -306.705023) (xy 67.07174 -306.751704)
			(xy 67.079635 -306.800281) (xy 67.08013 -306.824888) (xy 67.418978 -306.824888) (xy 67.422938 -306.775834)
			(xy 67.434715 -306.72805) (xy 67.454006 -306.682774) (xy 67.480309 -306.641178) (xy 67.512944 -306.604341)
			(xy 67.551065 -306.573216) (xy 67.593686 -306.548609) (xy 67.639702 -306.531157) (xy 67.687921 -306.521313)
			(xy 67.737096 -306.519332) (xy 67.785951 -306.525264) (xy 67.833222 -306.538956) (xy 67.877684 -306.560054)
			(xy 67.918187 -306.58801) (xy 67.95368 -306.622102) (xy 67.983245 -306.661446) (xy 68.006116 -306.705023)
			(xy 68.0217 -306.751704) (xy 68.029595 -306.800281) (xy 68.03009 -306.824888) (xy 68.368938 -306.824888)
			(xy 68.372898 -306.775834) (xy 68.384675 -306.72805) (xy 68.403966 -306.682774) (xy 68.430269 -306.641178)
			(xy 68.462904 -306.604341) (xy 68.501025 -306.573216) (xy 68.543646 -306.548609) (xy 68.589662 -306.531157)
			(xy 68.637881 -306.521313) (xy 68.687056 -306.519332) (xy 68.735911 -306.525264) (xy 68.783182 -306.538956)
			(xy 68.827644 -306.560054) (xy 68.868147 -306.58801) (xy 68.90364 -306.622102) (xy 68.933205 -306.661446)
			(xy 68.956076 -306.705023) (xy 68.97166 -306.751704) (xy 68.979555 -306.800281) (xy 68.98005 -306.824888)
			(xy 69.319152 -306.824888) (xy 69.323112 -306.775834) (xy 69.334889 -306.72805) (xy 69.35418 -306.682774)
			(xy 69.380483 -306.641178) (xy 69.413118 -306.604341) (xy 69.451239 -306.573216) (xy 69.49386 -306.548609)
			(xy 69.539876 -306.531157) (xy 69.588095 -306.521313) (xy 69.63727 -306.519332) (xy 69.686125 -306.525264)
			(xy 69.733396 -306.538956) (xy 69.777858 -306.560054) (xy 69.818361 -306.58801) (xy 69.853854 -306.622102)
			(xy 69.883419 -306.661446) (xy 69.90629 -306.705023) (xy 69.921874 -306.751704) (xy 69.929769 -306.800281)
			(xy 69.930264 -306.824888) (xy 70.269112 -306.824888) (xy 70.273072 -306.775834) (xy 70.284849 -306.72805)
			(xy 70.30414 -306.682774) (xy 70.330443 -306.641178) (xy 70.363078 -306.604341) (xy 70.401199 -306.573216)
			(xy 70.44382 -306.548609) (xy 70.489836 -306.531157) (xy 70.538055 -306.521313) (xy 70.58723 -306.519332)
			(xy 70.636085 -306.525264) (xy 70.683356 -306.538956) (xy 70.727818 -306.560054) (xy 70.768321 -306.58801)
			(xy 70.803814 -306.622102) (xy 70.833379 -306.661446) (xy 70.85625 -306.705023) (xy 70.871834 -306.751704)
			(xy 70.879729 -306.800281) (xy 70.880224 -306.824888) (xy 71.219072 -306.824888) (xy 71.223032 -306.775834)
			(xy 71.234809 -306.72805) (xy 71.2541 -306.682774) (xy 71.280403 -306.641178) (xy 71.313038 -306.604341)
			(xy 71.351159 -306.573216) (xy 71.39378 -306.548609) (xy 71.439796 -306.531157) (xy 71.488015 -306.521313)
			(xy 71.53719 -306.519332) (xy 71.586045 -306.525264) (xy 71.633316 -306.538956) (xy 71.677778 -306.560054)
			(xy 71.718281 -306.58801) (xy 71.753774 -306.622102) (xy 71.783339 -306.661446) (xy 71.80621 -306.705023)
			(xy 71.821794 -306.751704) (xy 71.829689 -306.800281) (xy 71.830184 -306.824888) (xy 71.829689 -306.849495)
			(xy 71.821794 -306.898072) (xy 71.80621 -306.944753) (xy 71.783339 -306.98833) (xy 71.753774 -307.027674)
			(xy 71.718281 -307.061766) (xy 71.677778 -307.089722) (xy 71.633316 -307.11082) (xy 71.586045 -307.124512)
			(xy 71.53719 -307.130444) (xy 71.488015 -307.128463) (xy 71.439796 -307.118619) (xy 71.39378 -307.101167)
			(xy 71.351159 -307.07656) (xy 71.313038 -307.045435) (xy 71.280403 -307.008598) (xy 71.2541 -306.967002)
			(xy 71.234809 -306.921726) (xy 71.223032 -306.873942) (xy 71.219072 -306.824888) (xy 70.880224 -306.824888)
			(xy 70.879729 -306.849495) (xy 70.871834 -306.898072) (xy 70.85625 -306.944753) (xy 70.833379 -306.98833)
			(xy 70.803814 -307.027674) (xy 70.768321 -307.061766) (xy 70.727818 -307.089722) (xy 70.683356 -307.11082)
			(xy 70.636085 -307.124512) (xy 70.58723 -307.130444) (xy 70.538055 -307.128463) (xy 70.489836 -307.118619)
			(xy 70.44382 -307.101167) (xy 70.401199 -307.07656) (xy 70.363078 -307.045435) (xy 70.330443 -307.008598)
			(xy 70.30414 -306.967002) (xy 70.284849 -306.921726) (xy 70.273072 -306.873942) (xy 70.269112 -306.824888)
			(xy 69.930264 -306.824888) (xy 69.929769 -306.849495) (xy 69.921874 -306.898072) (xy 69.90629 -306.944753)
			(xy 69.883419 -306.98833) (xy 69.853854 -307.027674) (xy 69.818361 -307.061766) (xy 69.777858 -307.089722)
			(xy 69.733396 -307.11082) (xy 69.686125 -307.124512) (xy 69.63727 -307.130444) (xy 69.588095 -307.128463)
			(xy 69.539876 -307.118619) (xy 69.49386 -307.101167) (xy 69.451239 -307.07656) (xy 69.413118 -307.045435)
			(xy 69.380483 -307.008598) (xy 69.35418 -306.967002) (xy 69.334889 -306.921726) (xy 69.323112 -306.873942)
			(xy 69.319152 -306.824888) (xy 68.98005 -306.824888) (xy 68.979555 -306.849495) (xy 68.97166 -306.898072)
			(xy 68.956076 -306.944753) (xy 68.933205 -306.98833) (xy 68.90364 -307.027674) (xy 68.868147 -307.061766)
			(xy 68.827644 -307.089722) (xy 68.783182 -307.11082) (xy 68.735911 -307.124512) (xy 68.687056 -307.130444)
			(xy 68.637881 -307.128463) (xy 68.589662 -307.118619) (xy 68.543646 -307.101167) (xy 68.501025 -307.07656)
			(xy 68.462904 -307.045435) (xy 68.430269 -307.008598) (xy 68.403966 -306.967002) (xy 68.384675 -306.921726)
			(xy 68.372898 -306.873942) (xy 68.368938 -306.824888) (xy 68.03009 -306.824888) (xy 68.029595 -306.849495)
			(xy 68.0217 -306.898072) (xy 68.006116 -306.944753) (xy 67.983245 -306.98833) (xy 67.95368 -307.027674)
			(xy 67.918187 -307.061766) (xy 67.877684 -307.089722) (xy 67.833222 -307.11082) (xy 67.785951 -307.124512)
			(xy 67.737096 -307.130444) (xy 67.687921 -307.128463) (xy 67.639702 -307.118619) (xy 67.593686 -307.101167)
			(xy 67.551065 -307.07656) (xy 67.512944 -307.045435) (xy 67.480309 -307.008598) (xy 67.454006 -306.967002)
			(xy 67.434715 -306.921726) (xy 67.422938 -306.873942) (xy 67.418978 -306.824888) (xy 67.08013 -306.824888)
			(xy 67.079635 -306.849495) (xy 67.07174 -306.898072) (xy 67.056156 -306.944753) (xy 67.033285 -306.98833)
			(xy 67.00372 -307.027674) (xy 66.968227 -307.061766) (xy 66.927724 -307.089722) (xy 66.883262 -307.11082)
			(xy 66.835991 -307.124512) (xy 66.787136 -307.130444) (xy 66.737961 -307.128463) (xy 66.689742 -307.118619)
			(xy 66.643726 -307.101167) (xy 66.601105 -307.07656) (xy 66.562984 -307.045435) (xy 66.530349 -307.008598)
			(xy 66.504046 -306.967002) (xy 66.484755 -306.921726) (xy 66.472978 -306.873942) (xy 66.469018 -306.824888)
			(xy 66.13017 -306.824888) (xy 66.129675 -306.849495) (xy 66.12178 -306.898072) (xy 66.106196 -306.944753)
			(xy 66.083325 -306.98833) (xy 66.05376 -307.027674) (xy 66.018267 -307.061766) (xy 65.977764 -307.089722)
			(xy 65.933302 -307.11082) (xy 65.886031 -307.124512) (xy 65.837176 -307.130444) (xy 65.788001 -307.128463)
			(xy 65.739782 -307.118619) (xy 65.693766 -307.101167) (xy 65.651145 -307.07656) (xy 65.613024 -307.045435)
			(xy 65.580389 -307.008598) (xy 65.554086 -306.967002) (xy 65.534795 -306.921726) (xy 65.523018 -306.873942)
			(xy 65.519058 -306.824888) (xy 65.18021 -306.824888) (xy 65.179715 -306.849495) (xy 65.17182 -306.898072)
			(xy 65.156236 -306.944753) (xy 65.133365 -306.98833) (xy 65.1038 -307.027674) (xy 65.068307 -307.061766)
			(xy 65.027804 -307.089722) (xy 64.983342 -307.11082) (xy 64.936071 -307.124512) (xy 64.887216 -307.130444)
			(xy 64.838041 -307.128463) (xy 64.789822 -307.118619) (xy 64.743806 -307.101167) (xy 64.701185 -307.07656)
			(xy 64.663064 -307.045435) (xy 64.630429 -307.008598) (xy 64.604126 -306.967002) (xy 64.584835 -306.921726)
			(xy 64.573058 -306.873942) (xy 64.569098 -306.824888) (xy 64.23025 -306.824888) (xy 64.229755 -306.849495)
			(xy 64.22186 -306.898072) (xy 64.206276 -306.944753) (xy 64.183405 -306.98833) (xy 64.15384 -307.027674)
			(xy 64.118347 -307.061766) (xy 64.077844 -307.089722) (xy 64.033382 -307.11082) (xy 63.986111 -307.124512)
			(xy 63.937256 -307.130444) (xy 63.888081 -307.128463) (xy 63.839862 -307.118619) (xy 63.793846 -307.101167)
			(xy 63.751225 -307.07656) (xy 63.713104 -307.045435) (xy 63.680469 -307.008598) (xy 63.654166 -306.967002)
			(xy 63.634875 -306.921726) (xy 63.623098 -306.873942) (xy 63.619138 -306.824888) (xy 63.28029 -306.824888)
			(xy 63.279795 -306.849495) (xy 63.2719 -306.898072) (xy 63.256316 -306.944753) (xy 63.233445 -306.98833)
			(xy 63.20388 -307.027674) (xy 63.168387 -307.061766) (xy 63.127884 -307.089722) (xy 63.083422 -307.11082)
			(xy 63.036151 -307.124512) (xy 62.987296 -307.130444) (xy 62.938121 -307.128463) (xy 62.889902 -307.118619)
			(xy 62.843886 -307.101167) (xy 62.801265 -307.07656) (xy 62.763144 -307.045435) (xy 62.730509 -307.008598)
			(xy 62.704206 -306.967002) (xy 62.684915 -306.921726) (xy 62.673138 -306.873942) (xy 62.669178 -306.824888)
			(xy 62.330076 -306.824888) (xy 62.329581 -306.849495) (xy 62.321686 -306.898072) (xy 62.306102 -306.944753)
			(xy 62.283231 -306.98833) (xy 62.253666 -307.027674) (xy 62.218173 -307.061766) (xy 62.17767 -307.089722)
			(xy 62.133208 -307.11082) (xy 62.085937 -307.124512) (xy 62.037082 -307.130444) (xy 61.987907 -307.128463)
			(xy 61.939688 -307.118619) (xy 61.893672 -307.101167) (xy 61.851051 -307.07656) (xy 61.81293 -307.045435)
			(xy 61.780295 -307.008598) (xy 61.753992 -306.967002) (xy 61.734701 -306.921726) (xy 61.722924 -306.873942)
			(xy 61.718964 -306.824888) (xy 61.380116 -306.824888) (xy 61.379621 -306.849495) (xy 61.371726 -306.898072)
			(xy 61.356142 -306.944753) (xy 61.333271 -306.98833) (xy 61.303706 -307.027674) (xy 61.268213 -307.061766)
			(xy 61.22771 -307.089722) (xy 61.183248 -307.11082) (xy 61.135977 -307.124512) (xy 61.087122 -307.130444)
			(xy 61.037947 -307.128463) (xy 60.989728 -307.118619) (xy 60.943712 -307.101167) (xy 60.901091 -307.07656)
			(xy 60.86297 -307.045435) (xy 60.830335 -307.008598) (xy 60.804032 -306.967002) (xy 60.784741 -306.921726)
			(xy 60.772964 -306.873942) (xy 60.769004 -306.824888) (xy 60.430156 -306.824888) (xy 60.429661 -306.849495)
			(xy 60.421766 -306.898072) (xy 60.406182 -306.944753) (xy 60.383311 -306.98833) (xy 60.353746 -307.027674)
			(xy 60.318253 -307.061766) (xy 60.27775 -307.089722) (xy 60.233288 -307.11082) (xy 60.186017 -307.124512)
			(xy 60.137162 -307.130444) (xy 60.087987 -307.128463) (xy 60.039768 -307.118619) (xy 59.993752 -307.101167)
			(xy 59.951131 -307.07656) (xy 59.91301 -307.045435) (xy 59.880375 -307.008598) (xy 59.854072 -306.967002)
			(xy 59.834781 -306.921726) (xy 59.823004 -306.873942) (xy 59.819044 -306.824888) (xy 58.530236 -306.824888)
			(xy 58.529741 -306.849495) (xy 58.521846 -306.898072) (xy 58.506262 -306.944753) (xy 58.483391 -306.98833)
			(xy 58.453826 -307.027674) (xy 58.418333 -307.061766) (xy 58.37783 -307.089722) (xy 58.333368 -307.11082)
			(xy 58.286097 -307.124512) (xy 58.237242 -307.130444) (xy 58.188067 -307.128463) (xy 58.139848 -307.118619)
			(xy 58.093832 -307.101167) (xy 58.051211 -307.07656) (xy 58.01309 -307.045435) (xy 57.980455 -307.008598)
			(xy 57.954152 -306.967002) (xy 57.934861 -306.921726) (xy 57.923084 -306.873942) (xy 57.919124 -306.824888)
			(xy 57.580276 -306.824888) (xy 57.579781 -306.849495) (xy 57.571886 -306.898072) (xy 57.556302 -306.944753)
			(xy 57.533431 -306.98833) (xy 57.503866 -307.027674) (xy 57.468373 -307.061766) (xy 57.42787 -307.089722)
			(xy 57.383408 -307.11082) (xy 57.336137 -307.124512) (xy 57.287282 -307.130444) (xy 57.238107 -307.128463)
			(xy 57.189888 -307.118619) (xy 57.143872 -307.101167) (xy 57.101251 -307.07656) (xy 57.06313 -307.045435)
			(xy 57.030495 -307.008598) (xy 57.004192 -306.967002) (xy 56.984901 -306.921726) (xy 56.973124 -306.873942)
			(xy 56.969164 -306.824888) (xy 56.630062 -306.824888) (xy 56.629567 -306.849495) (xy 56.621672 -306.898072)
			(xy 56.606088 -306.944753) (xy 56.583217 -306.98833) (xy 56.553652 -307.027674) (xy 56.518159 -307.061766)
			(xy 56.477656 -307.089722) (xy 56.433194 -307.11082) (xy 56.385923 -307.124512) (xy 56.337068 -307.130444)
			(xy 56.287893 -307.128463) (xy 56.239674 -307.118619) (xy 56.193658 -307.101167) (xy 56.151037 -307.07656)
			(xy 56.112916 -307.045435) (xy 56.080281 -307.008598) (xy 56.053978 -306.967002) (xy 56.034687 -306.921726)
			(xy 56.02291 -306.873942) (xy 56.01895 -306.824888) (xy 55.680102 -306.824888) (xy 55.679607 -306.849495)
			(xy 55.671712 -306.898072) (xy 55.656128 -306.944753) (xy 55.633257 -306.98833) (xy 55.603692 -307.027674)
			(xy 55.568199 -307.061766) (xy 55.527696 -307.089722) (xy 55.483234 -307.11082) (xy 55.435963 -307.124512)
			(xy 55.387108 -307.130444) (xy 55.337933 -307.128463) (xy 55.289714 -307.118619) (xy 55.243698 -307.101167)
			(xy 55.201077 -307.07656) (xy 55.162956 -307.045435) (xy 55.130321 -307.008598) (xy 55.104018 -306.967002)
			(xy 55.084727 -306.921726) (xy 55.07295 -306.873942) (xy 55.06899 -306.824888) (xy 54.730142 -306.824888)
			(xy 54.729647 -306.849495) (xy 54.721752 -306.898072) (xy 54.706168 -306.944753) (xy 54.683297 -306.98833)
			(xy 54.653732 -307.027674) (xy 54.618239 -307.061766) (xy 54.577736 -307.089722) (xy 54.533274 -307.11082)
			(xy 54.486003 -307.124512) (xy 54.437148 -307.130444) (xy 54.387973 -307.128463) (xy 54.339754 -307.118619)
			(xy 54.293738 -307.101167) (xy 54.251117 -307.07656) (xy 54.212996 -307.045435) (xy 54.180361 -307.008598)
			(xy 54.154058 -306.967002) (xy 54.134767 -306.921726) (xy 54.12299 -306.873942) (xy 54.11903 -306.824888)
			(xy 53.780182 -306.824888) (xy 53.779687 -306.849495) (xy 53.771792 -306.898072) (xy 53.756208 -306.944753)
			(xy 53.733337 -306.98833) (xy 53.703772 -307.027674) (xy 53.668279 -307.061766) (xy 53.627776 -307.089722)
			(xy 53.583314 -307.11082) (xy 53.536043 -307.124512) (xy 53.487188 -307.130444) (xy 53.438013 -307.128463)
			(xy 53.389794 -307.118619) (xy 53.343778 -307.101167) (xy 53.301157 -307.07656) (xy 53.263036 -307.045435)
			(xy 53.230401 -307.008598) (xy 53.204098 -306.967002) (xy 53.184807 -306.921726) (xy 53.17303 -306.873942)
			(xy 53.16907 -306.824888) (xy 52.830222 -306.824888) (xy 52.829727 -306.849495) (xy 52.821832 -306.898072)
			(xy 52.806248 -306.944753) (xy 52.783377 -306.98833) (xy 52.753812 -307.027674) (xy 52.718319 -307.061766)
			(xy 52.677816 -307.089722) (xy 52.633354 -307.11082) (xy 52.586083 -307.124512) (xy 52.537228 -307.130444)
			(xy 52.488053 -307.128463) (xy 52.439834 -307.118619) (xy 52.393818 -307.101167) (xy 52.351197 -307.07656)
			(xy 52.313076 -307.045435) (xy 52.280441 -307.008598) (xy 52.254138 -306.967002) (xy 52.234847 -306.921726)
			(xy 52.22307 -306.873942) (xy 52.21911 -306.824888) (xy 51.880262 -306.824888) (xy 51.879767 -306.849495)
			(xy 51.871872 -306.898072) (xy 51.856288 -306.944753) (xy 51.833417 -306.98833) (xy 51.803852 -307.027674)
			(xy 51.768359 -307.061766) (xy 51.727856 -307.089722) (xy 51.683394 -307.11082) (xy 51.636123 -307.124512)
			(xy 51.587268 -307.130444) (xy 51.538093 -307.128463) (xy 51.489874 -307.118619) (xy 51.443858 -307.101167)
			(xy 51.401237 -307.07656) (xy 51.363116 -307.045435) (xy 51.330481 -307.008598) (xy 51.304178 -306.967002)
			(xy 51.284887 -306.921726) (xy 51.27311 -306.873942) (xy 51.26915 -306.824888) (xy 50.930257 -306.824888)
			(xy 50.930707 -306.833189) (xy 50.925338 -306.882538) (xy 50.912057 -306.930368) (xy 50.891213 -306.975419)
			(xy 50.863355 -307.016504) (xy 50.829217 -307.052542) (xy 50.789699 -307.082581) (xy 50.745841 -307.105832)
			(xy 50.6988 -307.121681) (xy 50.649814 -307.129711) (xy 50.624994 -307.130196) (xy 50.610748 -307.130023)
			(xy 50.58238 -307.127354) (xy 50.568352 -307.124862) (xy 50.555906 -307.122576) (xy 50.532284 -307.129942)
			(xy 50.463704 -307.198268) (xy 50.455552 -307.207508) (xy 50.448241 -307.230996) (xy 50.449734 -307.243226)
			(xy 50.449734 -307.243734) (xy 50.452198 -307.257637) (xy 50.454869 -307.285749) (xy 50.455068 -307.299868)
			(xy 50.454546 -307.325123) (xy 50.446233 -307.374945) (xy 50.429832 -307.422719) (xy 50.405791 -307.467142)
			(xy 50.374767 -307.507002) (xy 50.337605 -307.541212) (xy 50.295319 -307.568838) (xy 50.249063 -307.589128)
			(xy 50.200098 -307.601528) (xy 50.14976 -307.605699) (xy 50.099422 -307.601528) (xy 50.050457 -307.589128)
			(xy 50.004201 -307.568838) (xy 49.961915 -307.541212) (xy 49.924753 -307.507002) (xy 49.893729 -307.467142)
			(xy 49.869688 -307.422719) (xy 49.853287 -307.374945) (xy 49.844974 -307.325123) (xy 49.844452 -307.299868)
			(xy 49.844625 -307.285685) (xy 49.8473 -307.257445) (xy 49.849786 -307.24348) (xy 49.852072 -307.231034)
			(xy 49.844706 -307.207412) (xy 49.767236 -307.129942) (xy 49.743614 -307.122576) (xy 49.731168 -307.124862)
			(xy 49.717202 -307.127339) (xy 49.688963 -307.13001) (xy 49.67478 -307.130196) (xy 49.660597 -307.130022)
			(xy 49.632357 -307.127348) (xy 49.618392 -307.124862) (xy 49.605946 -307.122576) (xy 49.582324 -307.129942)
			(xy 49.504854 -307.207412) (xy 49.497488 -307.231034) (xy 49.499774 -307.24348) (xy 49.502257 -307.257445)
			(xy 49.504925 -307.285685) (xy 49.505108 -307.299868) (xy 49.504586 -307.325123) (xy 49.496273 -307.374945)
			(xy 49.479872 -307.422719) (xy 49.455831 -307.467142) (xy 49.424807 -307.507002) (xy 49.387645 -307.541212)
			(xy 49.345359 -307.568838) (xy 49.299103 -307.589128) (xy 49.250138 -307.601528) (xy 49.1998 -307.605699)
			(xy 49.149462 -307.601528) (xy 49.100497 -307.589128) (xy 49.054241 -307.568838) (xy 49.011955 -307.541212)
			(xy 48.974793 -307.507002) (xy 48.943769 -307.467142) (xy 48.919728 -307.422719) (xy 48.903327 -307.374945)
			(xy 48.895014 -307.325123) (xy 48.894492 -307.299868) (xy 48.894664 -307.285685) (xy 48.897339 -307.257445)
			(xy 48.899826 -307.24348) (xy 48.902112 -307.231034) (xy 48.894746 -307.207412) (xy 48.817276 -307.129942)
			(xy 48.793654 -307.122576) (xy 48.781208 -307.124862) (xy 48.767241 -307.127333) (xy 48.739002 -307.130009)
			(xy 48.72482 -307.130196) (xy 48.710637 -307.130017) (xy 48.682397 -307.127346) (xy 48.668432 -307.124862)
			(xy 48.655986 -307.122576) (xy 48.632364 -307.129942) (xy 48.554894 -307.207412) (xy 48.547528 -307.231034)
			(xy 48.549814 -307.24348) (xy 48.552298 -307.257445) (xy 48.554965 -307.285685) (xy 48.555148 -307.299868)
			(xy 48.554657 -307.324693) (xy 48.546629 -307.373689) (xy 48.53078 -307.420741) (xy 48.507527 -307.464608)
			(xy 48.477484 -307.504136) (xy 48.441441 -307.538282) (xy 48.400348 -307.566147) (xy 48.355288 -307.586996)
			(xy 48.307449 -307.600281) (xy 48.258091 -307.605651) (xy 48.208514 -307.602964) (xy 48.160026 -307.592291)
			(xy 48.113902 -307.573915) (xy 48.07136 -307.548318) (xy 48.033519 -307.516175) (xy 48.001378 -307.478334)
			(xy 47.975782 -307.43579) (xy 47.957406 -307.389667) (xy 47.946735 -307.341178) (xy 47.94405 -307.291601)
			(xy 47.605022 -307.291601) (xy 47.605188 -307.299868) (xy 47.604693 -307.324475) (xy 47.596798 -307.373052)
			(xy 47.581214 -307.419733) (xy 47.558343 -307.46331) (xy 47.528778 -307.502654) (xy 47.493285 -307.536746)
			(xy 47.452782 -307.564702) (xy 47.40832 -307.5858) (xy 47.361049 -307.599492) (xy 47.312194 -307.605424)
			(xy 47.263019 -307.603443) (xy 47.2148 -307.593599) (xy 47.168784 -307.576147) (xy 47.126163 -307.55154)
			(xy 47.088042 -307.520415) (xy 47.055407 -307.483578) (xy 47.029104 -307.441982) (xy 47.009813 -307.396706)
			(xy 46.998036 -307.348922) (xy 46.994076 -307.299868) (xy 46.655228 -307.299868) (xy 46.654733 -307.324475)
			(xy 46.646838 -307.373052) (xy 46.631254 -307.419733) (xy 46.608383 -307.46331) (xy 46.578818 -307.502654)
			(xy 46.543325 -307.536746) (xy 46.502822 -307.564702) (xy 46.45836 -307.5858) (xy 46.411089 -307.599492)
			(xy 46.362234 -307.605424) (xy 46.313059 -307.603443) (xy 46.26484 -307.593599) (xy 46.218824 -307.576147)
			(xy 46.176203 -307.55154) (xy 46.138082 -307.520415) (xy 46.105447 -307.483578) (xy 46.079144 -307.441982)
			(xy 46.059853 -307.396706) (xy 46.048076 -307.348922) (xy 46.044116 -307.299868) (xy 45.705268 -307.299868)
			(xy 45.704773 -307.324475) (xy 45.696878 -307.373052) (xy 45.681294 -307.419733) (xy 45.658423 -307.46331)
			(xy 45.628858 -307.502654) (xy 45.593365 -307.536746) (xy 45.552862 -307.564702) (xy 45.5084 -307.5858)
			(xy 45.461129 -307.599492) (xy 45.412274 -307.605424) (xy 45.363099 -307.603443) (xy 45.31488 -307.593599)
			(xy 45.268864 -307.576147) (xy 45.226243 -307.55154) (xy 45.188122 -307.520415) (xy 45.155487 -307.483578)
			(xy 45.129184 -307.441982) (xy 45.109893 -307.396706) (xy 45.098116 -307.348922) (xy 45.094156 -307.299868)
			(xy 44.755054 -307.299868) (xy 44.754559 -307.324475) (xy 44.746664 -307.373052) (xy 44.73108 -307.419733)
			(xy 44.708209 -307.46331) (xy 44.678644 -307.502654) (xy 44.643151 -307.536746) (xy 44.602648 -307.564702)
			(xy 44.558186 -307.5858) (xy 44.510915 -307.599492) (xy 44.46206 -307.605424) (xy 44.412885 -307.603443)
			(xy 44.364666 -307.593599) (xy 44.31865 -307.576147) (xy 44.276029 -307.55154) (xy 44.237908 -307.520415)
			(xy 44.205273 -307.483578) (xy 44.17897 -307.441982) (xy 44.159679 -307.396706) (xy 44.147902 -307.348922)
			(xy 44.143942 -307.299868) (xy 43.805094 -307.299868) (xy 43.804599 -307.324475) (xy 43.796704 -307.373052)
			(xy 43.78112 -307.419733) (xy 43.758249 -307.46331) (xy 43.728684 -307.502654) (xy 43.693191 -307.536746)
			(xy 43.652688 -307.564702) (xy 43.608226 -307.5858) (xy 43.560955 -307.599492) (xy 43.5121 -307.605424)
			(xy 43.462925 -307.603443) (xy 43.414706 -307.593599) (xy 43.36869 -307.576147) (xy 43.326069 -307.55154)
			(xy 43.287948 -307.520415) (xy 43.255313 -307.483578) (xy 43.22901 -307.441982) (xy 43.209719 -307.396706)
			(xy 43.197942 -307.348922) (xy 43.193982 -307.299868) (xy 42.876978 -307.299868) (xy 42.876474 -307.325576)
			(xy 42.868431 -307.376358) (xy 42.852543 -307.425257) (xy 42.8292 -307.471069) (xy 42.798979 -307.512665)
			(xy 42.762623 -307.549021) (xy 42.721027 -307.579242) (xy 42.675215 -307.602585) (xy 42.626316 -307.618473)
			(xy 42.575534 -307.626516) (xy 42.524118 -307.626516) (xy 42.473336 -307.618473) (xy 42.424437 -307.602585)
			(xy 42.378625 -307.579242) (xy 42.337029 -307.549021) (xy 42.300673 -307.512665) (xy 42.270452 -307.471069)
			(xy 42.247109 -307.425257) (xy 42.231221 -307.376358) (xy 42.223178 -307.325576) (xy 41.926514 -307.325576)
			(xy 41.918471 -307.376358) (xy 41.902583 -307.425257) (xy 41.87924 -307.471069) (xy 41.849019 -307.512665)
			(xy 41.812663 -307.549021) (xy 41.771067 -307.579242) (xy 41.725255 -307.602585) (xy 41.676356 -307.618473)
			(xy 41.625574 -307.626516) (xy 41.574158 -307.626516) (xy 41.523376 -307.618473) (xy 41.474477 -307.602585)
			(xy 41.428665 -307.579242) (xy 41.387069 -307.549021) (xy 41.350713 -307.512665) (xy 41.320492 -307.471069)
			(xy 41.297149 -307.425257) (xy 41.281261 -307.376358) (xy 41.273218 -307.325576) (xy 40.95454 -307.325576)
			(xy 40.946824 -307.373052) (xy 40.93124 -307.419733) (xy 40.908369 -307.46331) (xy 40.878804 -307.502654)
			(xy 40.843311 -307.536746) (xy 40.802808 -307.564702) (xy 40.758346 -307.5858) (xy 40.711075 -307.599492)
			(xy 40.66222 -307.605424) (xy 40.613045 -307.603443) (xy 40.564826 -307.593599) (xy 40.51881 -307.576147)
			(xy 40.476189 -307.55154) (xy 40.438068 -307.520415) (xy 40.405433 -307.483578) (xy 40.37913 -307.441982)
			(xy 40.359839 -307.396706) (xy 40.348062 -307.348922) (xy 40.344102 -307.299868) (xy 40.027098 -307.299868)
			(xy 40.026594 -307.325576) (xy 40.018551 -307.376358) (xy 40.002663 -307.425257) (xy 39.97932 -307.471069)
			(xy 39.949099 -307.512665) (xy 39.912743 -307.549021) (xy 39.871147 -307.579242) (xy 39.825335 -307.602585)
			(xy 39.776436 -307.618473) (xy 39.725654 -307.626516) (xy 39.674238 -307.626516) (xy 39.623456 -307.618473)
			(xy 39.574557 -307.602585) (xy 39.528745 -307.579242) (xy 39.487149 -307.549021) (xy 39.450793 -307.512665)
			(xy 39.420572 -307.471069) (xy 39.397229 -307.425257) (xy 39.381341 -307.376358) (xy 39.373298 -307.325576)
			(xy 39.076634 -307.325576) (xy 39.068591 -307.376358) (xy 39.052703 -307.425257) (xy 39.02936 -307.471069)
			(xy 38.999139 -307.512665) (xy 38.962783 -307.549021) (xy 38.921187 -307.579242) (xy 38.875375 -307.602585)
			(xy 38.826476 -307.618473) (xy 38.775694 -307.626516) (xy 38.724278 -307.626516) (xy 38.673496 -307.618473)
			(xy 38.624597 -307.602585) (xy 38.578785 -307.579242) (xy 38.537189 -307.549021) (xy 38.500833 -307.512665)
			(xy 38.470612 -307.471069) (xy 38.447269 -307.425257) (xy 38.431381 -307.376358) (xy 38.423338 -307.325576)
			(xy 38.104406 -307.325576) (xy 38.09669 -307.373052) (xy 38.081106 -307.419733) (xy 38.058235 -307.46331)
			(xy 38.02867 -307.502654) (xy 37.993177 -307.536746) (xy 37.952674 -307.564702) (xy 37.908212 -307.5858)
			(xy 37.860941 -307.599492) (xy 37.812086 -307.605424) (xy 37.762911 -307.603443) (xy 37.714692 -307.593599)
			(xy 37.668676 -307.576147) (xy 37.626055 -307.55154) (xy 37.587934 -307.520415) (xy 37.555299 -307.483578)
			(xy 37.528996 -307.441982) (xy 37.509705 -307.396706) (xy 37.497928 -307.348922) (xy 37.493968 -307.299868)
			(xy 37.15512 -307.299868) (xy 37.154625 -307.324475) (xy 37.14673 -307.373052) (xy 37.131146 -307.419733)
			(xy 37.108275 -307.46331) (xy 37.07871 -307.502654) (xy 37.043217 -307.536746) (xy 37.002714 -307.564702)
			(xy 36.958252 -307.5858) (xy 36.910981 -307.599492) (xy 36.862126 -307.605424) (xy 36.812951 -307.603443)
			(xy 36.764732 -307.593599) (xy 36.718716 -307.576147) (xy 36.676095 -307.55154) (xy 36.637974 -307.520415)
			(xy 36.605339 -307.483578) (xy 36.579036 -307.441982) (xy 36.559745 -307.396706) (xy 36.547968 -307.348922)
			(xy 36.544008 -307.299868) (xy 32.618317 -307.299868) (xy 32.614877 -307.32324) (xy 32.598809 -307.376647)
			(xy 32.575137 -307.427144) (xy 32.544364 -307.473657) (xy 32.507147 -307.515194) (xy 32.464279 -307.550869)
			(xy 32.416673 -307.579923) (xy 32.365344 -307.601735) (xy 32.311387 -307.615841) (xy 32.25595 -307.621941)
			(xy 32.200216 -307.619904) (xy 32.145373 -307.609774) (xy 32.092589 -307.591767) (xy 32.042989 -307.566266)
			(xy 31.997631 -307.533815) (xy 31.957482 -307.495106) (xy 31.923396 -307.450963) (xy 31.8961 -307.402328)
			(xy 31.876177 -307.350237) (xy 31.864051 -307.2958) (xy 31.85998 -307.240178) (xy 17.635474 -307.240178)
			(xy 17.635474 -307.610764) (xy 17.635743 -307.61765) (xy 17.639484 -307.630907) (xy 17.64284 -307.636926)
			(xy 17.658218 -307.658782) (xy 17.683365 -307.705936) (xy 17.701686 -307.756137) (xy 17.712823 -307.808404)
			(xy 17.716559 -307.861713) (xy 17.71282 -307.915022) (xy 17.701679 -307.967288) (xy 17.683354 -308.017488)
			(xy 17.658204 -308.06464) (xy 17.64284 -308.086506) (xy 17.639434 -308.092503) (xy 17.635702 -308.105775)
			(xy 17.635474 -308.112668) (xy 17.635474 -308.450488) (xy 28.078174 -308.450488) (xy 28.082245 -308.394866)
			(xy 28.094371 -308.340429) (xy 28.114294 -308.288338) (xy 28.14159 -308.239703) (xy 28.175676 -308.19556)
			(xy 28.215825 -308.156851) (xy 28.261183 -308.1244) (xy 28.310783 -308.098899) (xy 28.363567 -308.080892)
			(xy 28.41841 -308.070762) (xy 28.474144 -308.068725) (xy 28.529581 -308.074825) (xy 28.583538 -308.088931)
			(xy 28.634867 -308.110743) (xy 28.682473 -308.139797) (xy 28.725341 -308.175472) (xy 28.762558 -308.217009)
			(xy 28.784439 -308.250082) (xy 35.593794 -308.250082) (xy 35.597754 -308.201028) (xy 35.609531 -308.153244)
			(xy 35.628822 -308.107968) (xy 35.655125 -308.066372) (xy 35.68776 -308.029535) (xy 35.725881 -307.99841)
			(xy 35.768502 -307.973803) (xy 35.814518 -307.956351) (xy 35.862737 -307.946507) (xy 35.911912 -307.944526)
			(xy 35.960767 -307.950458) (xy 36.008038 -307.96415) (xy 36.0525 -307.985248) (xy 36.093003 -308.013204)
			(xy 36.128496 -308.047296) (xy 36.158061 -308.08664) (xy 36.180932 -308.130217) (xy 36.196516 -308.176898)
			(xy 36.204411 -308.225475) (xy 36.204906 -308.250082) (xy 36.204411 -308.274689) (xy 36.204273 -308.275536)
			(xy 36.523164 -308.275536) (xy 36.523164 -308.22412) (xy 36.531207 -308.173338) (xy 36.547095 -308.124439)
			(xy 36.570438 -308.078627) (xy 36.600659 -308.037031) (xy 36.637015 -308.000675) (xy 36.678611 -307.970454)
			(xy 36.724423 -307.947111) (xy 36.773322 -307.931223) (xy 36.824104 -307.92318) (xy 36.87552 -307.92318)
			(xy 36.926302 -307.931223) (xy 36.975201 -307.947111) (xy 37.021013 -307.970454) (xy 37.062609 -308.000675)
			(xy 37.098965 -308.037031) (xy 37.129186 -308.078627) (xy 37.152529 -308.124439) (xy 37.168417 -308.173338)
			(xy 37.17646 -308.22412) (xy 37.176964 -308.249828) (xy 37.17646 -308.275536) (xy 37.473124 -308.275536)
			(xy 37.473124 -308.22412) (xy 37.481167 -308.173338) (xy 37.497055 -308.124439) (xy 37.520398 -308.078627)
			(xy 37.550619 -308.037031) (xy 37.586975 -308.000675) (xy 37.628571 -307.970454) (xy 37.674383 -307.947111)
			(xy 37.723282 -307.931223) (xy 37.774064 -307.92318) (xy 37.82548 -307.92318) (xy 37.876262 -307.931223)
			(xy 37.925161 -307.947111) (xy 37.970973 -307.970454) (xy 38.012569 -308.000675) (xy 38.048925 -308.037031)
			(xy 38.079146 -308.078627) (xy 38.102489 -308.124439) (xy 38.118377 -308.173338) (xy 38.12642 -308.22412)
			(xy 38.126924 -308.249828) (xy 38.444182 -308.249828) (xy 38.448142 -308.200774) (xy 38.459919 -308.15299)
			(xy 38.47921 -308.107714) (xy 38.505513 -308.066118) (xy 38.538148 -308.029281) (xy 38.576269 -307.998156)
			(xy 38.61889 -307.973549) (xy 38.664906 -307.956097) (xy 38.713125 -307.946253) (xy 38.7623 -307.944272)
			(xy 38.811155 -307.950204) (xy 38.858426 -307.963896) (xy 38.902888 -307.984994) (xy 38.943391 -308.01295)
			(xy 38.978884 -308.047042) (xy 39.008449 -308.086386) (xy 39.03132 -308.129963) (xy 39.046904 -308.176644)
			(xy 39.054799 -308.225221) (xy 39.055294 -308.249828) (xy 39.394142 -308.249828) (xy 39.398102 -308.200774)
			(xy 39.409879 -308.15299) (xy 39.42917 -308.107714) (xy 39.455473 -308.066118) (xy 39.488108 -308.029281)
			(xy 39.526229 -307.998156) (xy 39.56885 -307.973549) (xy 39.614866 -307.956097) (xy 39.663085 -307.946253)
			(xy 39.71226 -307.944272) (xy 39.761115 -307.950204) (xy 39.808386 -307.963896) (xy 39.852848 -307.984994)
			(xy 39.893351 -308.01295) (xy 39.928844 -308.047042) (xy 39.958409 -308.086386) (xy 39.98128 -308.129963)
			(xy 39.996864 -308.176644) (xy 40.004759 -308.225221) (xy 40.005254 -308.249828) (xy 40.344102 -308.249828)
			(xy 40.348062 -308.200774) (xy 40.359839 -308.15299) (xy 40.37913 -308.107714) (xy 40.405433 -308.066118)
			(xy 40.438068 -308.029281) (xy 40.476189 -307.998156) (xy 40.51881 -307.973549) (xy 40.564826 -307.956097)
			(xy 40.613045 -307.946253) (xy 40.66222 -307.944272) (xy 40.711075 -307.950204) (xy 40.758346 -307.963896)
			(xy 40.802808 -307.984994) (xy 40.843311 -308.01295) (xy 40.878804 -308.047042) (xy 40.908369 -308.086386)
			(xy 40.93124 -308.129963) (xy 40.946824 -308.176644) (xy 40.954719 -308.225221) (xy 40.955214 -308.249828)
			(xy 41.294062 -308.249828) (xy 41.298022 -308.200774) (xy 41.309799 -308.15299) (xy 41.32909 -308.107714)
			(xy 41.355393 -308.066118) (xy 41.388028 -308.029281) (xy 41.426149 -307.998156) (xy 41.46877 -307.973549)
			(xy 41.514786 -307.956097) (xy 41.563005 -307.946253) (xy 41.61218 -307.944272) (xy 41.661035 -307.950204)
			(xy 41.708306 -307.963896) (xy 41.752768 -307.984994) (xy 41.793271 -308.01295) (xy 41.828764 -308.047042)
			(xy 41.858329 -308.086386) (xy 41.8812 -308.129963) (xy 41.896784 -308.176644) (xy 41.904679 -308.225221)
			(xy 41.905174 -308.249828) (xy 42.244022 -308.249828) (xy 42.247982 -308.200774) (xy 42.259759 -308.15299)
			(xy 42.27905 -308.107714) (xy 42.305353 -308.066118) (xy 42.337988 -308.029281) (xy 42.376109 -307.998156)
			(xy 42.41873 -307.973549) (xy 42.464746 -307.956097) (xy 42.512965 -307.946253) (xy 42.56214 -307.944272)
			(xy 42.610995 -307.950204) (xy 42.658266 -307.963896) (xy 42.702728 -307.984994) (xy 42.743231 -308.01295)
			(xy 42.778724 -308.047042) (xy 42.808289 -308.086386) (xy 42.83116 -308.129963) (xy 42.846744 -308.176644)
			(xy 42.854639 -308.225221) (xy 42.855134 -308.249828) (xy 42.854639 -308.274435) (xy 42.85446 -308.275536)
			(xy 43.173138 -308.275536) (xy 43.173138 -308.22412) (xy 43.181181 -308.173338) (xy 43.197069 -308.124439)
			(xy 43.220412 -308.078627) (xy 43.250633 -308.037031) (xy 43.286989 -308.000675) (xy 43.328585 -307.970454)
			(xy 43.374397 -307.947111) (xy 43.423296 -307.931223) (xy 43.474078 -307.92318) (xy 43.525494 -307.92318)
			(xy 43.576276 -307.931223) (xy 43.625175 -307.947111) (xy 43.670987 -307.970454) (xy 43.712583 -308.000675)
			(xy 43.748939 -308.037031) (xy 43.77916 -308.078627) (xy 43.802503 -308.124439) (xy 43.818391 -308.173338)
			(xy 43.826434 -308.22412) (xy 43.826938 -308.249828) (xy 43.826434 -308.275536) (xy 44.123098 -308.275536)
			(xy 44.123098 -308.22412) (xy 44.131141 -308.173338) (xy 44.147029 -308.124439) (xy 44.170372 -308.078627)
			(xy 44.200593 -308.037031) (xy 44.236949 -308.000675) (xy 44.278545 -307.970454) (xy 44.324357 -307.947111)
			(xy 44.373256 -307.931223) (xy 44.424038 -307.92318) (xy 44.475454 -307.92318) (xy 44.526236 -307.931223)
			(xy 44.575135 -307.947111) (xy 44.620947 -307.970454) (xy 44.662543 -308.000675) (xy 44.698899 -308.037031)
			(xy 44.72912 -308.078627) (xy 44.752463 -308.124439) (xy 44.768351 -308.173338) (xy 44.776394 -308.22412)
			(xy 44.776898 -308.249828) (xy 45.094156 -308.249828) (xy 45.098116 -308.200774) (xy 45.109893 -308.15299)
			(xy 45.129184 -308.107714) (xy 45.155487 -308.066118) (xy 45.188122 -308.029281) (xy 45.226243 -307.998156)
			(xy 45.268864 -307.973549) (xy 45.31488 -307.956097) (xy 45.363099 -307.946253) (xy 45.412274 -307.944272)
			(xy 45.461129 -307.950204) (xy 45.5084 -307.963896) (xy 45.552862 -307.984994) (xy 45.593365 -308.01295)
			(xy 45.628858 -308.047042) (xy 45.658423 -308.086386) (xy 45.681294 -308.129963) (xy 45.696878 -308.176644)
			(xy 45.704773 -308.225221) (xy 45.705268 -308.249828) (xy 46.044116 -308.249828) (xy 46.048076 -308.200774)
			(xy 46.059853 -308.15299) (xy 46.079144 -308.107714) (xy 46.105447 -308.066118) (xy 46.138082 -308.029281)
			(xy 46.176203 -307.998156) (xy 46.218824 -307.973549) (xy 46.26484 -307.956097) (xy 46.313059 -307.946253)
			(xy 46.362234 -307.944272) (xy 46.411089 -307.950204) (xy 46.45836 -307.963896) (xy 46.502822 -307.984994)
			(xy 46.543325 -308.01295) (xy 46.578818 -308.047042) (xy 46.608383 -308.086386) (xy 46.631254 -308.129963)
			(xy 46.646838 -308.176644) (xy 46.654733 -308.225221) (xy 46.655228 -308.249828) (xy 46.994076 -308.249828)
			(xy 46.998036 -308.200774) (xy 47.009813 -308.15299) (xy 47.029104 -308.107714) (xy 47.055407 -308.066118)
			(xy 47.088042 -308.029281) (xy 47.126163 -307.998156) (xy 47.168784 -307.973549) (xy 47.2148 -307.956097)
			(xy 47.263019 -307.946253) (xy 47.312194 -307.944272) (xy 47.361049 -307.950204) (xy 47.40832 -307.963896)
			(xy 47.452782 -307.984994) (xy 47.493285 -308.01295) (xy 47.528778 -308.047042) (xy 47.558343 -308.086386)
			(xy 47.581214 -308.129963) (xy 47.596798 -308.176644) (xy 47.604693 -308.225221) (xy 47.605188 -308.249828)
			(xy 47.944036 -308.249828) (xy 47.947996 -308.200774) (xy 47.959773 -308.15299) (xy 47.979064 -308.107714)
			(xy 48.005367 -308.066118) (xy 48.038002 -308.029281) (xy 48.076123 -307.998156) (xy 48.118744 -307.973549)
			(xy 48.16476 -307.956097) (xy 48.212979 -307.946253) (xy 48.262154 -307.944272) (xy 48.311009 -307.950204)
			(xy 48.35828 -307.963896) (xy 48.402742 -307.984994) (xy 48.443245 -308.01295) (xy 48.478738 -308.047042)
			(xy 48.508303 -308.086386) (xy 48.531174 -308.129963) (xy 48.546758 -308.176644) (xy 48.554653 -308.225221)
			(xy 48.555148 -308.249828) (xy 48.554982 -308.258073) (xy 48.894081 -308.258073) (xy 48.89677 -308.208503)
			(xy 48.907443 -308.160021) (xy 48.92582 -308.113905) (xy 48.951415 -308.071369) (xy 48.983555 -308.033535)
			(xy 49.021392 -308.001399) (xy 49.06393 -307.975807) (xy 49.110048 -307.957435) (xy 49.158531 -307.946766)
			(xy 49.208101 -307.944082) (xy 49.257452 -307.949452) (xy 49.305284 -307.962736) (xy 49.350337 -307.983584)
			(xy 49.391424 -308.011445) (xy 49.427462 -308.045587) (xy 49.457501 -308.08511) (xy 49.48075 -308.128972)
			(xy 49.496597 -308.176017) (xy 49.504624 -308.225007) (xy 49.505108 -308.249828) (xy 49.504935 -308.264011)
			(xy 49.502261 -308.292251) (xy 49.499774 -308.306216) (xy 49.497488 -308.318662) (xy 49.504854 -308.342284)
			(xy 49.582324 -308.419754) (xy 49.605946 -308.42712) (xy 49.618392 -308.424834) (xy 49.632359 -308.422363)
			(xy 49.660598 -308.419687) (xy 49.67478 -308.4195) (xy 49.698773 -308.419957) (xy 49.746169 -308.427461)
			(xy 49.791807 -308.442287) (xy 49.834563 -308.464071) (xy 49.873386 -308.492275) (xy 49.907317 -308.526205)
			(xy 49.935523 -308.565027) (xy 49.957308 -308.607782) (xy 49.972137 -308.65342) (xy 49.979642 -308.700815)
			(xy 49.980088 -308.724808) (xy 49.979913 -308.738991) (xy 49.97724 -308.767231) (xy 49.974754 -308.781196)
			(xy 49.972468 -308.793642) (xy 49.979834 -308.817264) (xy 50.057304 -308.894734) (xy 50.080926 -308.9021)
			(xy 50.093372 -308.899814) (xy 50.107337 -308.897332) (xy 50.135577 -308.894664) (xy 50.14976 -308.89448)
			(xy 50.174585 -308.894935) (xy 50.223582 -308.902961) (xy 50.270635 -308.918809) (xy 50.314504 -308.94206)
			(xy 50.354033 -308.972103) (xy 50.388181 -309.008145) (xy 50.416048 -309.049237) (xy 50.436899 -309.094297)
			(xy 50.450186 -309.142136) (xy 50.455558 -309.191494) (xy 50.455556 -309.191539) (xy 50.794269 -309.191539)
			(xy 50.799632 -309.142187) (xy 50.81291 -309.094352) (xy 50.833751 -309.049296) (xy 50.861607 -309.008205)
			(xy 50.895744 -308.972161) (xy 50.935262 -308.942115) (xy 50.979121 -308.918858) (xy 51.026164 -308.903003)
			(xy 51.075152 -308.894968) (xy 51.099974 -308.89448) (xy 51.114157 -308.89466) (xy 51.142397 -308.89733)
			(xy 51.156362 -308.899814) (xy 51.168808 -308.9021) (xy 51.19243 -308.894734) (xy 51.2699 -308.817264)
			(xy 51.277266 -308.793642) (xy 51.27498 -308.781196) (xy 51.272507 -308.76723) (xy 51.269833 -308.73899)
			(xy 51.269646 -308.724808) (xy 51.269825 -308.710625) (xy 51.272495 -308.682385) (xy 51.27498 -308.66842)
			(xy 51.277266 -308.655974) (xy 51.2699 -308.632352) (xy 51.19243 -308.554882) (xy 51.168808 -308.547516)
			(xy 51.156362 -308.549802) (xy 51.142396 -308.55228) (xy 51.114157 -308.554951) (xy 51.099974 -308.555136)
			(xy 51.075155 -308.554594) (xy 51.026172 -308.546559) (xy 50.979134 -308.530706) (xy 50.935281 -308.507452)
			(xy 50.895768 -308.477409) (xy 50.861635 -308.441369) (xy 50.833783 -308.400282) (xy 50.812944 -308.355231)
			(xy 50.799669 -308.307401) (xy 50.794306 -308.258054) (xy 50.796998 -308.20849) (xy 50.807673 -308.160014)
			(xy 50.82605 -308.113903) (xy 50.851644 -308.071373) (xy 50.883782 -308.033544) (xy 50.921617 -308.001413)
			(xy 50.964152 -307.975826) (xy 51.010265 -307.957457) (xy 51.058743 -307.946791) (xy 51.108308 -307.944108)
			(xy 51.157654 -307.949479) (xy 51.205482 -307.962763) (xy 51.25053 -307.983609) (xy 51.291611 -308.011469)
			(xy 51.327645 -308.045608) (xy 51.357681 -308.085127) (xy 51.380927 -308.128984) (xy 51.396772 -308.176025)
			(xy 51.404798 -308.225009) (xy 51.405282 -308.249828) (xy 51.40511 -308.264011) (xy 51.402435 -308.292251)
			(xy 51.399948 -308.306216) (xy 51.397662 -308.318662) (xy 51.405028 -308.342284) (xy 51.482498 -308.419754)
			(xy 51.50612 -308.42712) (xy 51.518566 -308.424834) (xy 51.532531 -308.422353) (xy 51.560771 -308.419684)
			(xy 51.574954 -308.4195) (xy 51.589137 -308.419683) (xy 51.617377 -308.422351) (xy 51.631342 -308.424834)
			(xy 51.643788 -308.42712) (xy 51.66741 -308.419754) (xy 51.74488 -308.342284) (xy 51.752246 -308.318662)
			(xy 51.74996 -308.306216) (xy 51.747477 -308.292251) (xy 51.744809 -308.264011) (xy 51.744626 -308.249828)
			(xy 51.745048 -308.225005) (xy 51.753075 -308.176012) (xy 51.768923 -308.128963) (xy 51.792173 -308.085098)
			(xy 51.822214 -308.045573) (xy 51.858254 -308.011428) (xy 51.899342 -307.983563) (xy 51.944398 -307.962713)
			(xy 51.992233 -307.949426) (xy 52.041588 -307.944054) (xy 52.091161 -307.946737) (xy 52.139647 -307.957404)
			(xy 52.185769 -307.975776) (xy 52.228311 -308.001367) (xy 52.266153 -308.033503) (xy 52.298297 -308.071338)
			(xy 52.323897 -308.113875) (xy 52.342277 -308.159993) (xy 52.352955 -308.208477) (xy 52.3552 -308.2498)
			(xy 52.694097 -308.2498) (xy 52.698268 -308.199467) (xy 52.710666 -308.150507) (xy 52.730953 -308.104256)
			(xy 52.758577 -308.061974) (xy 52.792783 -308.024816) (xy 52.832638 -307.993794) (xy 52.877056 -307.969756)
			(xy 52.924825 -307.953356) (xy 52.974641 -307.945042) (xy 52.999894 -307.94452) (xy 53.014077 -307.944697)
			(xy 53.042317 -307.947369) (xy 53.056282 -307.949854) (xy 53.068728 -307.95214) (xy 53.09235 -307.944774)
			(xy 53.16982 -307.867304) (xy 53.177186 -307.843682) (xy 53.1749 -307.831236) (xy 53.172419 -307.817271)
			(xy 53.16975 -307.789031) (xy 53.169566 -307.774848) (xy 53.170026 -307.750022) (xy 53.178051 -307.701023)
			(xy 53.193899 -307.653967) (xy 53.21715 -307.610096) (xy 53.247194 -307.570565) (xy 53.283237 -307.536415)
			(xy 53.32433 -307.508546) (xy 53.369391 -307.487693) (xy 53.417233 -307.474406) (xy 53.466593 -307.469033)
			(xy 53.516173 -307.471718) (xy 53.564665 -307.482388) (xy 53.610791 -307.500764) (xy 53.653337 -307.52636)
			(xy 53.691182 -307.558503) (xy 53.723327 -307.596345) (xy 53.748926 -307.638889) (xy 53.767305 -307.685014)
			(xy 53.777979 -307.733505) (xy 53.78022 -307.774848) (xy 54.11903 -307.774848) (xy 54.12299 -307.725794)
			(xy 54.134767 -307.67801) (xy 54.154058 -307.632734) (xy 54.180361 -307.591138) (xy 54.212996 -307.554301)
			(xy 54.251117 -307.523176) (xy 54.293738 -307.498569) (xy 54.339754 -307.481117) (xy 54.387973 -307.471273)
			(xy 54.437148 -307.469292) (xy 54.486003 -307.475224) (xy 54.533274 -307.488916) (xy 54.577736 -307.510014)
			(xy 54.618239 -307.53797) (xy 54.653732 -307.572062) (xy 54.683297 -307.611406) (xy 54.706168 -307.654983)
			(xy 54.721752 -307.701664) (xy 54.729647 -307.750241) (xy 54.730142 -307.774848) (xy 55.06899 -307.774848)
			(xy 55.07295 -307.725794) (xy 55.084727 -307.67801) (xy 55.104018 -307.632734) (xy 55.130321 -307.591138)
			(xy 55.162956 -307.554301) (xy 55.201077 -307.523176) (xy 55.243698 -307.498569) (xy 55.289714 -307.481117)
			(xy 55.337933 -307.471273) (xy 55.387108 -307.469292) (xy 55.435963 -307.475224) (xy 55.483234 -307.488916)
			(xy 55.527696 -307.510014) (xy 55.568199 -307.53797) (xy 55.603692 -307.572062) (xy 55.633257 -307.611406)
			(xy 55.656128 -307.654983) (xy 55.671712 -307.701664) (xy 55.679607 -307.750241) (xy 55.680102 -307.774848)
			(xy 56.019204 -307.774848) (xy 56.023164 -307.725794) (xy 56.034941 -307.67801) (xy 56.054232 -307.632734)
			(xy 56.080535 -307.591138) (xy 56.11317 -307.554301) (xy 56.151291 -307.523176) (xy 56.193912 -307.498569)
			(xy 56.239928 -307.481117) (xy 56.288147 -307.471273) (xy 56.337322 -307.469292) (xy 56.386177 -307.475224)
			(xy 56.433448 -307.488916) (xy 56.47791 -307.510014) (xy 56.518413 -307.53797) (xy 56.553906 -307.572062)
			(xy 56.583471 -307.611406) (xy 56.606342 -307.654983) (xy 56.621926 -307.701664) (xy 56.629821 -307.750241)
			(xy 56.630316 -307.774848) (xy 56.969164 -307.774848) (xy 56.973124 -307.725794) (xy 56.984901 -307.67801)
			(xy 57.004192 -307.632734) (xy 57.030495 -307.591138) (xy 57.06313 -307.554301) (xy 57.101251 -307.523176)
			(xy 57.143872 -307.498569) (xy 57.189888 -307.481117) (xy 57.238107 -307.471273) (xy 57.287282 -307.469292)
			(xy 57.336137 -307.475224) (xy 57.383408 -307.488916) (xy 57.42787 -307.510014) (xy 57.468373 -307.53797)
			(xy 57.503866 -307.572062) (xy 57.533431 -307.611406) (xy 57.556302 -307.654983) (xy 57.571886 -307.701664)
			(xy 57.579781 -307.750241) (xy 57.580276 -307.774848) (xy 57.919124 -307.774848) (xy 57.923084 -307.725794)
			(xy 57.934861 -307.67801) (xy 57.954152 -307.632734) (xy 57.980455 -307.591138) (xy 58.01309 -307.554301)
			(xy 58.051211 -307.523176) (xy 58.093832 -307.498569) (xy 58.139848 -307.481117) (xy 58.188067 -307.471273)
			(xy 58.237242 -307.469292) (xy 58.286097 -307.475224) (xy 58.333368 -307.488916) (xy 58.37783 -307.510014)
			(xy 58.418333 -307.53797) (xy 58.453826 -307.572062) (xy 58.483391 -307.611406) (xy 58.506262 -307.654983)
			(xy 58.521846 -307.701664) (xy 58.529741 -307.750241) (xy 58.530236 -307.774848) (xy 59.819044 -307.774848)
			(xy 59.823004 -307.725794) (xy 59.834781 -307.67801) (xy 59.854072 -307.632734) (xy 59.880375 -307.591138)
			(xy 59.91301 -307.554301) (xy 59.951131 -307.523176) (xy 59.993752 -307.498569) (xy 60.039768 -307.481117)
			(xy 60.087987 -307.471273) (xy 60.137162 -307.469292) (xy 60.186017 -307.475224) (xy 60.233288 -307.488916)
			(xy 60.27775 -307.510014) (xy 60.318253 -307.53797) (xy 60.353746 -307.572062) (xy 60.383311 -307.611406)
			(xy 60.406182 -307.654983) (xy 60.421766 -307.701664) (xy 60.429661 -307.750241) (xy 60.430156 -307.774848)
			(xy 60.769004 -307.774848) (xy 60.772964 -307.725794) (xy 60.784741 -307.67801) (xy 60.804032 -307.632734)
			(xy 60.830335 -307.591138) (xy 60.86297 -307.554301) (xy 60.901091 -307.523176) (xy 60.943712 -307.498569)
			(xy 60.989728 -307.481117) (xy 61.037947 -307.471273) (xy 61.087122 -307.469292) (xy 61.135977 -307.475224)
			(xy 61.183248 -307.488916) (xy 61.22771 -307.510014) (xy 61.268213 -307.53797) (xy 61.303706 -307.572062)
			(xy 61.333271 -307.611406) (xy 61.356142 -307.654983) (xy 61.371726 -307.701664) (xy 61.379621 -307.750241)
			(xy 61.380116 -307.774848) (xy 61.718964 -307.774848) (xy 61.722924 -307.725794) (xy 61.734701 -307.67801)
			(xy 61.753992 -307.632734) (xy 61.780295 -307.591138) (xy 61.81293 -307.554301) (xy 61.851051 -307.523176)
			(xy 61.893672 -307.498569) (xy 61.939688 -307.481117) (xy 61.987907 -307.471273) (xy 62.037082 -307.469292)
			(xy 62.085937 -307.475224) (xy 62.133208 -307.488916) (xy 62.17767 -307.510014) (xy 62.218173 -307.53797)
			(xy 62.253666 -307.572062) (xy 62.283231 -307.611406) (xy 62.306102 -307.654983) (xy 62.321686 -307.701664)
			(xy 62.329581 -307.750241) (xy 62.330071 -307.774594) (xy 62.668924 -307.774594) (xy 62.672884 -307.72554)
			(xy 62.684661 -307.677756) (xy 62.703952 -307.63248) (xy 62.730255 -307.590884) (xy 62.76289 -307.554047)
			(xy 62.801011 -307.522922) (xy 62.843632 -307.498315) (xy 62.889648 -307.480863) (xy 62.937867 -307.471019)
			(xy 62.987042 -307.469038) (xy 63.035897 -307.47497) (xy 63.083168 -307.488662) (xy 63.12763 -307.50976)
			(xy 63.168133 -307.537716) (xy 63.203626 -307.571808) (xy 63.233191 -307.611152) (xy 63.256062 -307.654729)
			(xy 63.271646 -307.70141) (xy 63.279541 -307.749987) (xy 63.280036 -307.774594) (xy 63.619138 -307.774594)
			(xy 63.623098 -307.72554) (xy 63.634875 -307.677756) (xy 63.654166 -307.63248) (xy 63.680469 -307.590884)
			(xy 63.713104 -307.554047) (xy 63.751225 -307.522922) (xy 63.793846 -307.498315) (xy 63.839862 -307.480863)
			(xy 63.888081 -307.471019) (xy 63.937256 -307.469038) (xy 63.986111 -307.47497) (xy 64.033382 -307.488662)
			(xy 64.077844 -307.50976) (xy 64.118347 -307.537716) (xy 64.15384 -307.571808) (xy 64.183405 -307.611152)
			(xy 64.206276 -307.654729) (xy 64.22186 -307.70141) (xy 64.229755 -307.749987) (xy 64.23025 -307.774594)
			(xy 64.230245 -307.774848) (xy 64.569098 -307.774848) (xy 64.573058 -307.725794) (xy 64.584835 -307.67801)
			(xy 64.604126 -307.632734) (xy 64.630429 -307.591138) (xy 64.663064 -307.554301) (xy 64.701185 -307.523176)
			(xy 64.743806 -307.498569) (xy 64.789822 -307.481117) (xy 64.838041 -307.471273) (xy 64.887216 -307.469292)
			(xy 64.936071 -307.475224) (xy 64.983342 -307.488916) (xy 65.027804 -307.510014) (xy 65.068307 -307.53797)
			(xy 65.1038 -307.572062) (xy 65.133365 -307.611406) (xy 65.156236 -307.654983) (xy 65.17182 -307.701664)
			(xy 65.179715 -307.750241) (xy 65.18021 -307.774848) (xy 65.519058 -307.774848) (xy 65.523018 -307.725794)
			(xy 65.534795 -307.67801) (xy 65.554086 -307.632734) (xy 65.580389 -307.591138) (xy 65.613024 -307.554301)
			(xy 65.651145 -307.523176) (xy 65.693766 -307.498569) (xy 65.739782 -307.481117) (xy 65.788001 -307.471273)
			(xy 65.837176 -307.469292) (xy 65.886031 -307.475224) (xy 65.933302 -307.488916) (xy 65.977764 -307.510014)
			(xy 66.018267 -307.53797) (xy 66.05376 -307.572062) (xy 66.083325 -307.611406) (xy 66.106196 -307.654983)
			(xy 66.12178 -307.701664) (xy 66.129675 -307.750241) (xy 66.13017 -307.774848) (xy 66.469018 -307.774848)
			(xy 66.472978 -307.725794) (xy 66.484755 -307.67801) (xy 66.504046 -307.632734) (xy 66.530349 -307.591138)
			(xy 66.562984 -307.554301) (xy 66.601105 -307.523176) (xy 66.643726 -307.498569) (xy 66.689742 -307.481117)
			(xy 66.737961 -307.471273) (xy 66.787136 -307.469292) (xy 66.835991 -307.475224) (xy 66.883262 -307.488916)
			(xy 66.927724 -307.510014) (xy 66.968227 -307.53797) (xy 67.00372 -307.572062) (xy 67.033285 -307.611406)
			(xy 67.056156 -307.654983) (xy 67.07174 -307.701664) (xy 67.079635 -307.750241) (xy 67.08013 -307.774848)
			(xy 67.418978 -307.774848) (xy 67.422938 -307.725794) (xy 67.434715 -307.67801) (xy 67.454006 -307.632734)
			(xy 67.480309 -307.591138) (xy 67.512944 -307.554301) (xy 67.551065 -307.523176) (xy 67.593686 -307.498569)
			(xy 67.639702 -307.481117) (xy 67.687921 -307.471273) (xy 67.737096 -307.469292) (xy 67.785951 -307.475224)
			(xy 67.833222 -307.488916) (xy 67.877684 -307.510014) (xy 67.918187 -307.53797) (xy 67.95368 -307.572062)
			(xy 67.983245 -307.611406) (xy 68.006116 -307.654983) (xy 68.0217 -307.701664) (xy 68.029595 -307.750241)
			(xy 68.03009 -307.774848) (xy 68.368938 -307.774848) (xy 68.372898 -307.725794) (xy 68.384675 -307.67801)
			(xy 68.403966 -307.632734) (xy 68.430269 -307.591138) (xy 68.462904 -307.554301) (xy 68.501025 -307.523176)
			(xy 68.543646 -307.498569) (xy 68.589662 -307.481117) (xy 68.637881 -307.471273) (xy 68.687056 -307.469292)
			(xy 68.735911 -307.475224) (xy 68.783182 -307.488916) (xy 68.827644 -307.510014) (xy 68.868147 -307.53797)
			(xy 68.90364 -307.572062) (xy 68.933205 -307.611406) (xy 68.956076 -307.654983) (xy 68.97166 -307.701664)
			(xy 68.979555 -307.750241) (xy 68.98005 -307.774848) (xy 69.319152 -307.774848) (xy 69.323112 -307.725794)
			(xy 69.334889 -307.67801) (xy 69.35418 -307.632734) (xy 69.380483 -307.591138) (xy 69.413118 -307.554301)
			(xy 69.451239 -307.523176) (xy 69.49386 -307.498569) (xy 69.539876 -307.481117) (xy 69.588095 -307.471273)
			(xy 69.63727 -307.469292) (xy 69.686125 -307.475224) (xy 69.733396 -307.488916) (xy 69.777858 -307.510014)
			(xy 69.818361 -307.53797) (xy 69.853854 -307.572062) (xy 69.883419 -307.611406) (xy 69.90629 -307.654983)
			(xy 69.921874 -307.701664) (xy 69.929769 -307.750241) (xy 69.930264 -307.774848) (xy 70.269112 -307.774848)
			(xy 70.273072 -307.725794) (xy 70.284849 -307.67801) (xy 70.30414 -307.632734) (xy 70.330443 -307.591138)
			(xy 70.363078 -307.554301) (xy 70.401199 -307.523176) (xy 70.44382 -307.498569) (xy 70.489836 -307.481117)
			(xy 70.538055 -307.471273) (xy 70.58723 -307.469292) (xy 70.636085 -307.475224) (xy 70.683356 -307.488916)
			(xy 70.727818 -307.510014) (xy 70.768321 -307.53797) (xy 70.803814 -307.572062) (xy 70.833379 -307.611406)
			(xy 70.85625 -307.654983) (xy 70.871834 -307.701664) (xy 70.879729 -307.750241) (xy 70.880224 -307.774848)
			(xy 71.219072 -307.774848) (xy 71.223032 -307.725794) (xy 71.234809 -307.67801) (xy 71.2541 -307.632734)
			(xy 71.280403 -307.591138) (xy 71.313038 -307.554301) (xy 71.351159 -307.523176) (xy 71.39378 -307.498569)
			(xy 71.439796 -307.481117) (xy 71.488015 -307.471273) (xy 71.53719 -307.469292) (xy 71.586045 -307.475224)
			(xy 71.633316 -307.488916) (xy 71.677778 -307.510014) (xy 71.718281 -307.53797) (xy 71.753774 -307.572062)
			(xy 71.783339 -307.611406) (xy 71.80621 -307.654983) (xy 71.821794 -307.701664) (xy 71.829689 -307.750241)
			(xy 71.830184 -307.774848) (xy 71.829689 -307.799455) (xy 71.821794 -307.848032) (xy 71.80621 -307.894713)
			(xy 71.783339 -307.93829) (xy 71.753774 -307.977634) (xy 71.718281 -308.011726) (xy 71.677778 -308.039682)
			(xy 71.633316 -308.06078) (xy 71.586045 -308.074472) (xy 71.53719 -308.080404) (xy 71.488015 -308.078423)
			(xy 71.439796 -308.068579) (xy 71.39378 -308.051127) (xy 71.351159 -308.02652) (xy 71.313038 -307.995395)
			(xy 71.280403 -307.958558) (xy 71.2541 -307.916962) (xy 71.234809 -307.871686) (xy 71.223032 -307.823902)
			(xy 71.219072 -307.774848) (xy 70.880224 -307.774848) (xy 70.879729 -307.799455) (xy 70.871834 -307.848032)
			(xy 70.85625 -307.894713) (xy 70.833379 -307.93829) (xy 70.803814 -307.977634) (xy 70.768321 -308.011726)
			(xy 70.727818 -308.039682) (xy 70.683356 -308.06078) (xy 70.636085 -308.074472) (xy 70.58723 -308.080404)
			(xy 70.538055 -308.078423) (xy 70.489836 -308.068579) (xy 70.44382 -308.051127) (xy 70.401199 -308.02652)
			(xy 70.363078 -307.995395) (xy 70.330443 -307.958558) (xy 70.30414 -307.916962) (xy 70.284849 -307.871686)
			(xy 70.273072 -307.823902) (xy 70.269112 -307.774848) (xy 69.930264 -307.774848) (xy 69.929769 -307.799455)
			(xy 69.921874 -307.848032) (xy 69.90629 -307.894713) (xy 69.883419 -307.93829) (xy 69.853854 -307.977634)
			(xy 69.818361 -308.011726) (xy 69.777858 -308.039682) (xy 69.733396 -308.06078) (xy 69.686125 -308.074472)
			(xy 69.63727 -308.080404) (xy 69.588095 -308.078423) (xy 69.539876 -308.068579) (xy 69.49386 -308.051127)
			(xy 69.451239 -308.02652) (xy 69.413118 -307.995395) (xy 69.380483 -307.958558) (xy 69.35418 -307.916962)
			(xy 69.334889 -307.871686) (xy 69.323112 -307.823902) (xy 69.319152 -307.774848) (xy 68.98005 -307.774848)
			(xy 68.979555 -307.799455) (xy 68.97166 -307.848032) (xy 68.956076 -307.894713) (xy 68.933205 -307.93829)
			(xy 68.90364 -307.977634) (xy 68.868147 -308.011726) (xy 68.827644 -308.039682) (xy 68.783182 -308.06078)
			(xy 68.735911 -308.074472) (xy 68.687056 -308.080404) (xy 68.637881 -308.078423) (xy 68.589662 -308.068579)
			(xy 68.543646 -308.051127) (xy 68.501025 -308.02652) (xy 68.462904 -307.995395) (xy 68.430269 -307.958558)
			(xy 68.403966 -307.916962) (xy 68.384675 -307.871686) (xy 68.372898 -307.823902) (xy 68.368938 -307.774848)
			(xy 68.03009 -307.774848) (xy 68.029595 -307.799455) (xy 68.0217 -307.848032) (xy 68.006116 -307.894713)
			(xy 67.983245 -307.93829) (xy 67.95368 -307.977634) (xy 67.918187 -308.011726) (xy 67.877684 -308.039682)
			(xy 67.833222 -308.06078) (xy 67.785951 -308.074472) (xy 67.737096 -308.080404) (xy 67.687921 -308.078423)
			(xy 67.639702 -308.068579) (xy 67.593686 -308.051127) (xy 67.551065 -308.02652) (xy 67.512944 -307.995395)
			(xy 67.480309 -307.958558) (xy 67.454006 -307.916962) (xy 67.434715 -307.871686) (xy 67.422938 -307.823902)
			(xy 67.418978 -307.774848) (xy 67.08013 -307.774848) (xy 67.079635 -307.799455) (xy 67.07174 -307.848032)
			(xy 67.056156 -307.894713) (xy 67.033285 -307.93829) (xy 67.00372 -307.977634) (xy 66.968227 -308.011726)
			(xy 66.927724 -308.039682) (xy 66.883262 -308.06078) (xy 66.835991 -308.074472) (xy 66.787136 -308.080404)
			(xy 66.737961 -308.078423) (xy 66.689742 -308.068579) (xy 66.643726 -308.051127) (xy 66.601105 -308.02652)
			(xy 66.562984 -307.995395) (xy 66.530349 -307.958558) (xy 66.504046 -307.916962) (xy 66.484755 -307.871686)
			(xy 66.472978 -307.823902) (xy 66.469018 -307.774848) (xy 66.13017 -307.774848) (xy 66.129675 -307.799455)
			(xy 66.12178 -307.848032) (xy 66.106196 -307.894713) (xy 66.083325 -307.93829) (xy 66.05376 -307.977634)
			(xy 66.018267 -308.011726) (xy 65.977764 -308.039682) (xy 65.933302 -308.06078) (xy 65.886031 -308.074472)
			(xy 65.837176 -308.080404) (xy 65.788001 -308.078423) (xy 65.739782 -308.068579) (xy 65.693766 -308.051127)
			(xy 65.651145 -308.02652) (xy 65.613024 -307.995395) (xy 65.580389 -307.958558) (xy 65.554086 -307.916962)
			(xy 65.534795 -307.871686) (xy 65.523018 -307.823902) (xy 65.519058 -307.774848) (xy 65.18021 -307.774848)
			(xy 65.179715 -307.799455) (xy 65.17182 -307.848032) (xy 65.156236 -307.894713) (xy 65.133365 -307.93829)
			(xy 65.1038 -307.977634) (xy 65.068307 -308.011726) (xy 65.027804 -308.039682) (xy 64.983342 -308.06078)
			(xy 64.936071 -308.074472) (xy 64.887216 -308.080404) (xy 64.838041 -308.078423) (xy 64.789822 -308.068579)
			(xy 64.743806 -308.051127) (xy 64.701185 -308.02652) (xy 64.663064 -307.995395) (xy 64.630429 -307.958558)
			(xy 64.604126 -307.916962) (xy 64.584835 -307.871686) (xy 64.573058 -307.823902) (xy 64.569098 -307.774848)
			(xy 64.230245 -307.774848) (xy 64.229755 -307.799201) (xy 64.22186 -307.847778) (xy 64.206276 -307.894459)
			(xy 64.183405 -307.938036) (xy 64.15384 -307.97738) (xy 64.118347 -308.011472) (xy 64.077844 -308.039428)
			(xy 64.033382 -308.060526) (xy 63.986111 -308.074218) (xy 63.937256 -308.08015) (xy 63.888081 -308.078169)
			(xy 63.839862 -308.068325) (xy 63.793846 -308.050873) (xy 63.751225 -308.026266) (xy 63.713104 -307.995141)
			(xy 63.680469 -307.958304) (xy 63.654166 -307.916708) (xy 63.634875 -307.871432) (xy 63.623098 -307.823648)
			(xy 63.619138 -307.774594) (xy 63.280036 -307.774594) (xy 63.279541 -307.799201) (xy 63.271646 -307.847778)
			(xy 63.256062 -307.894459) (xy 63.233191 -307.938036) (xy 63.203626 -307.97738) (xy 63.168133 -308.011472)
			(xy 63.12763 -308.039428) (xy 63.083168 -308.060526) (xy 63.035897 -308.074218) (xy 62.987042 -308.08015)
			(xy 62.937867 -308.078169) (xy 62.889648 -308.068325) (xy 62.843632 -308.050873) (xy 62.801011 -308.026266)
			(xy 62.76289 -307.995141) (xy 62.730255 -307.958304) (xy 62.703952 -307.916708) (xy 62.684661 -307.871432)
			(xy 62.672884 -307.823648) (xy 62.668924 -307.774594) (xy 62.330071 -307.774594) (xy 62.330076 -307.774848)
			(xy 62.329581 -307.799455) (xy 62.321686 -307.848032) (xy 62.306102 -307.894713) (xy 62.283231 -307.93829)
			(xy 62.253666 -307.977634) (xy 62.218173 -308.011726) (xy 62.17767 -308.039682) (xy 62.133208 -308.06078)
			(xy 62.085937 -308.074472) (xy 62.037082 -308.080404) (xy 61.987907 -308.078423) (xy 61.939688 -308.068579)
			(xy 61.893672 -308.051127) (xy 61.851051 -308.02652) (xy 61.81293 -307.995395) (xy 61.780295 -307.958558)
			(xy 61.753992 -307.916962) (xy 61.734701 -307.871686) (xy 61.722924 -307.823902) (xy 61.718964 -307.774848)
			(xy 61.380116 -307.774848) (xy 61.379621 -307.799455) (xy 61.371726 -307.848032) (xy 61.356142 -307.894713)
			(xy 61.333271 -307.93829) (xy 61.303706 -307.977634) (xy 61.268213 -308.011726) (xy 61.22771 -308.039682)
			(xy 61.183248 -308.06078) (xy 61.135977 -308.074472) (xy 61.087122 -308.080404) (xy 61.037947 -308.078423)
			(xy 60.989728 -308.068579) (xy 60.943712 -308.051127) (xy 60.901091 -308.02652) (xy 60.86297 -307.995395)
			(xy 60.830335 -307.958558) (xy 60.804032 -307.916962) (xy 60.784741 -307.871686) (xy 60.772964 -307.823902)
			(xy 60.769004 -307.774848) (xy 60.430156 -307.774848) (xy 60.429661 -307.799455) (xy 60.421766 -307.848032)
			(xy 60.406182 -307.894713) (xy 60.383311 -307.93829) (xy 60.353746 -307.977634) (xy 60.318253 -308.011726)
			(xy 60.27775 -308.039682) (xy 60.233288 -308.06078) (xy 60.186017 -308.074472) (xy 60.137162 -308.080404)
			(xy 60.087987 -308.078423) (xy 60.039768 -308.068579) (xy 59.993752 -308.051127) (xy 59.951131 -308.02652)
			(xy 59.91301 -307.995395) (xy 59.880375 -307.958558) (xy 59.854072 -307.916962) (xy 59.834781 -307.871686)
			(xy 59.823004 -307.823902) (xy 59.819044 -307.774848) (xy 58.530236 -307.774848) (xy 58.529741 -307.799455)
			(xy 58.521846 -307.848032) (xy 58.506262 -307.894713) (xy 58.483391 -307.93829) (xy 58.453826 -307.977634)
			(xy 58.418333 -308.011726) (xy 58.37783 -308.039682) (xy 58.333368 -308.06078) (xy 58.286097 -308.074472)
			(xy 58.237242 -308.080404) (xy 58.188067 -308.078423) (xy 58.139848 -308.068579) (xy 58.093832 -308.051127)
			(xy 58.051211 -308.02652) (xy 58.01309 -307.995395) (xy 57.980455 -307.958558) (xy 57.954152 -307.916962)
			(xy 57.934861 -307.871686) (xy 57.923084 -307.823902) (xy 57.919124 -307.774848) (xy 57.580276 -307.774848)
			(xy 57.579781 -307.799455) (xy 57.571886 -307.848032) (xy 57.556302 -307.894713) (xy 57.533431 -307.93829)
			(xy 57.503866 -307.977634) (xy 57.468373 -308.011726) (xy 57.42787 -308.039682) (xy 57.383408 -308.06078)
			(xy 57.336137 -308.074472) (xy 57.287282 -308.080404) (xy 57.238107 -308.078423) (xy 57.189888 -308.068579)
			(xy 57.143872 -308.051127) (xy 57.101251 -308.02652) (xy 57.06313 -307.995395) (xy 57.030495 -307.958558)
			(xy 57.004192 -307.916962) (xy 56.984901 -307.871686) (xy 56.973124 -307.823902) (xy 56.969164 -307.774848)
			(xy 56.630316 -307.774848) (xy 56.629821 -307.799455) (xy 56.621926 -307.848032) (xy 56.606342 -307.894713)
			(xy 56.583471 -307.93829) (xy 56.553906 -307.977634) (xy 56.518413 -308.011726) (xy 56.47791 -308.039682)
			(xy 56.433448 -308.06078) (xy 56.386177 -308.074472) (xy 56.337322 -308.080404) (xy 56.288147 -308.078423)
			(xy 56.239928 -308.068579) (xy 56.193912 -308.051127) (xy 56.151291 -308.02652) (xy 56.11317 -307.995395)
			(xy 56.080535 -307.958558) (xy 56.054232 -307.916962) (xy 56.034941 -307.871686) (xy 56.023164 -307.823902)
			(xy 56.019204 -307.774848) (xy 55.680102 -307.774848) (xy 55.679607 -307.799455) (xy 55.671712 -307.848032)
			(xy 55.656128 -307.894713) (xy 55.633257 -307.93829) (xy 55.603692 -307.977634) (xy 55.568199 -308.011726)
			(xy 55.527696 -308.039682) (xy 55.483234 -308.06078) (xy 55.435963 -308.074472) (xy 55.387108 -308.080404)
			(xy 55.337933 -308.078423) (xy 55.289714 -308.068579) (xy 55.243698 -308.051127) (xy 55.201077 -308.02652)
			(xy 55.162956 -307.995395) (xy 55.130321 -307.958558) (xy 55.104018 -307.916962) (xy 55.084727 -307.871686)
			(xy 55.07295 -307.823902) (xy 55.06899 -307.774848) (xy 54.730142 -307.774848) (xy 54.729647 -307.799455)
			(xy 54.721752 -307.848032) (xy 54.706168 -307.894713) (xy 54.683297 -307.93829) (xy 54.653732 -307.977634)
			(xy 54.618239 -308.011726) (xy 54.577736 -308.039682) (xy 54.533274 -308.06078) (xy 54.486003 -308.074472)
			(xy 54.437148 -308.080404) (xy 54.387973 -308.078423) (xy 54.339754 -308.068579) (xy 54.293738 -308.051127)
			(xy 54.251117 -308.02652) (xy 54.212996 -307.995395) (xy 54.180361 -307.958558) (xy 54.154058 -307.916962)
			(xy 54.134767 -307.871686) (xy 54.12299 -307.823902) (xy 54.11903 -307.774848) (xy 53.78022 -307.774848)
			(xy 53.780667 -307.783085) (xy 53.775298 -307.832446) (xy 53.762014 -307.880288) (xy 53.741165 -307.92535)
			(xy 53.713299 -307.966446) (xy 53.679152 -308.002492) (xy 53.639622 -308.032538) (xy 53.595753 -308.055793)
			(xy 53.548699 -308.071643) (xy 53.4997 -308.079672) (xy 53.474874 -308.080156) (xy 53.460691 -308.079984)
			(xy 53.432451 -308.077309) (xy 53.418486 -308.074822) (xy 53.40604 -308.072536) (xy 53.382418 -308.079902)
			(xy 53.304948 -308.157372) (xy 53.297582 -308.180994) (xy 53.299868 -308.19344) (xy 53.302346 -308.207406)
			(xy 53.305017 -308.235645) (xy 53.305202 -308.249828) (xy 53.305029 -308.264011) (xy 53.302355 -308.292251)
			(xy 53.299868 -308.306216) (xy 53.297582 -308.318662) (xy 53.304948 -308.342284) (xy 53.382418 -308.419754)
			(xy 53.40604 -308.42712) (xy 53.418486 -308.424834) (xy 53.432453 -308.422364) (xy 53.460692 -308.419688)
			(xy 53.474874 -308.4195) (xy 53.500134 -308.419975) (xy 53.549965 -308.428286) (xy 53.597748 -308.444687)
			(xy 53.64218 -308.468729) (xy 53.682049 -308.499756) (xy 53.716266 -308.536923) (xy 53.743899 -308.579216)
			(xy 53.764193 -308.62548) (xy 53.776596 -308.674453) (xy 53.780768 -308.7248) (xy 53.780767 -308.724808)
			(xy 54.11903 -308.724808) (xy 54.12299 -308.675754) (xy 54.134767 -308.62797) (xy 54.154058 -308.582694)
			(xy 54.180361 -308.541098) (xy 54.212996 -308.504261) (xy 54.251117 -308.473136) (xy 54.293738 -308.448529)
			(xy 54.339754 -308.431077) (xy 54.387973 -308.421233) (xy 54.437148 -308.419252) (xy 54.486003 -308.425184)
			(xy 54.533274 -308.438876) (xy 54.577736 -308.459974) (xy 54.618239 -308.48793) (xy 54.653732 -308.522022)
			(xy 54.683297 -308.561366) (xy 54.706168 -308.604943) (xy 54.721752 -308.651624) (xy 54.729647 -308.700201)
			(xy 54.730142 -308.724808) (xy 54.729976 -308.733075) (xy 55.069087 -308.733075) (xy 55.071776 -308.683507)
			(xy 55.082448 -308.635027) (xy 55.100823 -308.588912) (xy 55.126416 -308.546378) (xy 55.158554 -308.508544)
			(xy 55.196389 -308.476408) (xy 55.238925 -308.450817) (xy 55.28504 -308.432444) (xy 55.333521 -308.421774)
			(xy 55.383089 -308.419087) (xy 55.432439 -308.424456) (xy 55.48027 -308.437737) (xy 55.525322 -308.458582)
			(xy 55.566408 -308.486441) (xy 55.602447 -308.52058) (xy 55.632487 -308.560099) (xy 55.655738 -308.603958)
			(xy 55.671587 -308.651001) (xy 55.679617 -308.699988) (xy 55.680102 -308.724808) (xy 55.679927 -308.738991)
			(xy 55.677254 -308.767231) (xy 55.674768 -308.781196) (xy 55.672482 -308.793642) (xy 55.679848 -308.817264)
			(xy 55.757318 -308.894734) (xy 55.78094 -308.9021) (xy 55.793386 -308.899814) (xy 55.807353 -308.897343)
			(xy 55.835592 -308.894668) (xy 55.849774 -308.89448) (xy 55.864021 -308.894637) (xy 55.892389 -308.897313)
			(xy 55.906416 -308.899814) (xy 55.918862 -308.9021) (xy 55.942484 -308.894734) (xy 56.011064 -308.826408)
			(xy 56.019226 -308.817175) (xy 56.026533 -308.793682) (xy 56.025034 -308.78145) (xy 56.025034 -308.780942)
			(xy 56.022566 -308.767039) (xy 56.019898 -308.738927) (xy 56.0197 -308.724808) (xy 56.020169 -308.699986)
			(xy 56.028199 -308.650997) (xy 56.044049 -308.603952) (xy 56.067301 -308.560092) (xy 56.097343 -308.52057)
			(xy 56.133383 -308.48643) (xy 56.174471 -308.45857) (xy 56.219525 -308.437724) (xy 56.267358 -308.424442)
			(xy 56.31671 -308.419073) (xy 56.36628 -308.42176) (xy 56.414763 -308.43243) (xy 56.460881 -308.450804)
			(xy 56.503418 -308.476396) (xy 56.541255 -308.508534) (xy 56.573394 -308.546369) (xy 56.598989 -308.588905)
			(xy 56.617365 -308.635022) (xy 56.628038 -308.683504) (xy 56.630279 -308.724808) (xy 57.919124 -308.724808)
			(xy 57.923084 -308.675754) (xy 57.934861 -308.62797) (xy 57.954152 -308.582694) (xy 57.980455 -308.541098)
			(xy 58.01309 -308.504261) (xy 58.051211 -308.473136) (xy 58.093832 -308.448529) (xy 58.139848 -308.431077)
			(xy 58.188067 -308.421233) (xy 58.237242 -308.419252) (xy 58.286097 -308.425184) (xy 58.333368 -308.438876)
			(xy 58.37783 -308.459974) (xy 58.418333 -308.48793) (xy 58.453826 -308.522022) (xy 58.483391 -308.561366)
			(xy 58.506262 -308.604943) (xy 58.521846 -308.651624) (xy 58.529741 -308.700201) (xy 58.530236 -308.724808)
			(xy 58.530069 -308.733113) (xy 59.819033 -308.733113) (xy 59.821717 -308.683534) (xy 59.832386 -308.635042)
			(xy 59.85076 -308.588916) (xy 59.876355 -308.546369) (xy 59.908496 -308.508525) (xy 59.946337 -308.476379)
			(xy 59.98888 -308.450778) (xy 60.035004 -308.432398) (xy 60.083494 -308.421722) (xy 60.133073 -308.419032)
			(xy 60.182433 -308.424399) (xy 60.230275 -308.437681) (xy 60.275338 -308.458528) (xy 60.316435 -308.486392)
			(xy 60.352481 -308.520537) (xy 60.382529 -308.560064) (xy 60.405786 -308.603932) (xy 60.421639 -308.650985)
			(xy 60.429671 -308.699982) (xy 60.430156 -308.724808) (xy 60.429981 -308.738991) (xy 60.427308 -308.767231)
			(xy 60.424822 -308.781196) (xy 60.422536 -308.793642) (xy 60.429902 -308.817264) (xy 60.507372 -308.894734)
			(xy 60.530994 -308.9021) (xy 60.54344 -308.899814) (xy 60.557406 -308.897336) (xy 60.585645 -308.894665)
			(xy 60.599828 -308.89448) (xy 60.614011 -308.894653) (xy 60.642251 -308.897328) (xy 60.656216 -308.899814)
			(xy 60.668662 -308.9021) (xy 60.692284 -308.894734) (xy 60.769754 -308.817264) (xy 60.77712 -308.793642)
			(xy 60.774834 -308.781196) (xy 60.772361 -308.76723) (xy 60.769687 -308.73899) (xy 60.7695 -308.724808)
			(xy 60.770022 -308.699553) (xy 60.778335 -308.649731) (xy 60.794736 -308.601957) (xy 60.818777 -308.557534)
			(xy 60.849801 -308.517674) (xy 60.886963 -308.483464) (xy 60.929249 -308.455838) (xy 60.975505 -308.435548)
			(xy 61.02447 -308.423148) (xy 61.074808 -308.418977) (xy 61.125146 -308.423148) (xy 61.174111 -308.435548)
			(xy 61.220367 -308.455838) (xy 61.262653 -308.483464) (xy 61.299815 -308.517674) (xy 61.330839 -308.557534)
			(xy 61.35488 -308.601957) (xy 61.371281 -308.649731) (xy 61.379594 -308.699553) (xy 61.380116 -308.724808)
			(xy 61.37994 -308.738991) (xy 61.377268 -308.767231) (xy 61.374782 -308.781196) (xy 61.372496 -308.793642)
			(xy 61.379862 -308.817264) (xy 61.457332 -308.894734) (xy 61.480954 -308.9021) (xy 61.4934 -308.899814)
			(xy 61.507367 -308.897342) (xy 61.535606 -308.894667) (xy 61.549788 -308.89448) (xy 61.563971 -308.894659)
			(xy 61.592211 -308.897329) (xy 61.606176 -308.899814) (xy 61.618622 -308.9021) (xy 61.642244 -308.894734)
			(xy 61.719714 -308.817264) (xy 61.72708 -308.793642) (xy 61.724794 -308.781196) (xy 61.722321 -308.76723)
			(xy 61.719647 -308.73899) (xy 61.71946 -308.724808) (xy 61.719969 -308.699986) (xy 61.728 -308.650995)
			(xy 61.743851 -308.603949) (xy 61.767104 -308.560088) (xy 61.797147 -308.520566) (xy 61.833188 -308.486425)
			(xy 61.874279 -308.458565) (xy 61.919335 -308.437721) (xy 61.96717 -308.42444) (xy 62.016523 -308.419073)
			(xy 62.066095 -308.421762) (xy 62.114578 -308.432435) (xy 62.160696 -308.450811) (xy 62.203233 -308.476407)
			(xy 62.241069 -308.508548) (xy 62.273207 -308.546386) (xy 62.298799 -308.588925) (xy 62.317172 -308.635045)
			(xy 62.327842 -308.683529) (xy 62.330063 -308.724554) (xy 62.668924 -308.724554) (xy 62.672884 -308.6755)
			(xy 62.684661 -308.627716) (xy 62.703952 -308.58244) (xy 62.730255 -308.540844) (xy 62.76289 -308.504007)
			(xy 62.801011 -308.472882) (xy 62.843632 -308.448275) (xy 62.889648 -308.430823) (xy 62.937867 -308.420979)
			(xy 62.987042 -308.418998) (xy 63.035897 -308.42493) (xy 63.083168 -308.438622) (xy 63.12763 -308.45972)
			(xy 63.168133 -308.487676) (xy 63.203626 -308.521768) (xy 63.233191 -308.561112) (xy 63.256062 -308.604689)
			(xy 63.271646 -308.65137) (xy 63.279541 -308.699947) (xy 63.280036 -308.724554) (xy 63.280031 -308.724808)
			(xy 63.619138 -308.724808) (xy 63.623098 -308.675754) (xy 63.634875 -308.62797) (xy 63.654166 -308.582694)
			(xy 63.680469 -308.541098) (xy 63.713104 -308.504261) (xy 63.751225 -308.473136) (xy 63.793846 -308.448529)
			(xy 63.839862 -308.431077) (xy 63.888081 -308.421233) (xy 63.937256 -308.419252) (xy 63.986111 -308.425184)
			(xy 64.033382 -308.438876) (xy 64.077844 -308.459974) (xy 64.118347 -308.48793) (xy 64.15384 -308.522022)
			(xy 64.183405 -308.561366) (xy 64.206276 -308.604943) (xy 64.22186 -308.651624) (xy 64.229755 -308.700201)
			(xy 64.23025 -308.724808) (xy 64.569098 -308.724808) (xy 64.573058 -308.675754) (xy 64.584835 -308.62797)
			(xy 64.604126 -308.582694) (xy 64.630429 -308.541098) (xy 64.663064 -308.504261) (xy 64.701185 -308.473136)
			(xy 64.743806 -308.448529) (xy 64.789822 -308.431077) (xy 64.838041 -308.421233) (xy 64.887216 -308.419252)
			(xy 64.936071 -308.425184) (xy 64.983342 -308.438876) (xy 65.027804 -308.459974) (xy 65.068307 -308.48793)
			(xy 65.1038 -308.522022) (xy 65.133365 -308.561366) (xy 65.156236 -308.604943) (xy 65.17182 -308.651624)
			(xy 65.179715 -308.700201) (xy 65.18021 -308.724808) (xy 65.519058 -308.724808) (xy 65.523018 -308.675754)
			(xy 65.534795 -308.62797) (xy 65.554086 -308.582694) (xy 65.580389 -308.541098) (xy 65.613024 -308.504261)
			(xy 65.651145 -308.473136) (xy 65.693766 -308.448529) (xy 65.739782 -308.431077) (xy 65.788001 -308.421233)
			(xy 65.837176 -308.419252) (xy 65.886031 -308.425184) (xy 65.933302 -308.438876) (xy 65.977764 -308.459974)
			(xy 66.018267 -308.48793) (xy 66.05376 -308.522022) (xy 66.083325 -308.561366) (xy 66.106196 -308.604943)
			(xy 66.12178 -308.651624) (xy 66.129675 -308.700201) (xy 66.13017 -308.724808) (xy 66.469018 -308.724808)
			(xy 66.472978 -308.675754) (xy 66.484755 -308.62797) (xy 66.504046 -308.582694) (xy 66.530349 -308.541098)
			(xy 66.562984 -308.504261) (xy 66.601105 -308.473136) (xy 66.643726 -308.448529) (xy 66.689742 -308.431077)
			(xy 66.737961 -308.421233) (xy 66.787136 -308.419252) (xy 66.835991 -308.425184) (xy 66.883262 -308.438876)
			(xy 66.927724 -308.459974) (xy 66.968227 -308.48793) (xy 67.00372 -308.522022) (xy 67.033285 -308.561366)
			(xy 67.056156 -308.604943) (xy 67.07174 -308.651624) (xy 67.079635 -308.700201) (xy 67.08013 -308.724808)
			(xy 67.418978 -308.724808) (xy 67.422938 -308.675754) (xy 67.434715 -308.62797) (xy 67.454006 -308.582694)
			(xy 67.480309 -308.541098) (xy 67.512944 -308.504261) (xy 67.551065 -308.473136) (xy 67.593686 -308.448529)
			(xy 67.639702 -308.431077) (xy 67.687921 -308.421233) (xy 67.737096 -308.419252) (xy 67.785951 -308.425184)
			(xy 67.833222 -308.438876) (xy 67.877684 -308.459974) (xy 67.918187 -308.48793) (xy 67.95368 -308.522022)
			(xy 67.983245 -308.561366) (xy 68.006116 -308.604943) (xy 68.0217 -308.651624) (xy 68.029595 -308.700201)
			(xy 68.03009 -308.724808) (xy 68.369192 -308.724808) (xy 68.373152 -308.675754) (xy 68.384929 -308.62797)
			(xy 68.40422 -308.582694) (xy 68.430523 -308.541098) (xy 68.463158 -308.504261) (xy 68.501279 -308.473136)
			(xy 68.5439 -308.448529) (xy 68.589916 -308.431077) (xy 68.638135 -308.421233) (xy 68.68731 -308.419252)
			(xy 68.736165 -308.425184) (xy 68.783436 -308.438876) (xy 68.827898 -308.459974) (xy 68.868401 -308.48793)
			(xy 68.903894 -308.522022) (xy 68.933459 -308.561366) (xy 68.95633 -308.604943) (xy 68.971914 -308.651624)
			(xy 68.979809 -308.700201) (xy 68.980304 -308.724808) (xy 69.319152 -308.724808) (xy 69.323112 -308.675754)
			(xy 69.334889 -308.62797) (xy 69.35418 -308.582694) (xy 69.380483 -308.541098) (xy 69.413118 -308.504261)
			(xy 69.451239 -308.473136) (xy 69.49386 -308.448529) (xy 69.539876 -308.431077) (xy 69.588095 -308.421233)
			(xy 69.63727 -308.419252) (xy 69.686125 -308.425184) (xy 69.733396 -308.438876) (xy 69.777858 -308.459974)
			(xy 69.818361 -308.48793) (xy 69.853854 -308.522022) (xy 69.883419 -308.561366) (xy 69.90629 -308.604943)
			(xy 69.921874 -308.651624) (xy 69.929769 -308.700201) (xy 69.930264 -308.724808) (xy 70.269112 -308.724808)
			(xy 70.273072 -308.675754) (xy 70.284849 -308.62797) (xy 70.30414 -308.582694) (xy 70.330443 -308.541098)
			(xy 70.363078 -308.504261) (xy 70.401199 -308.473136) (xy 70.44382 -308.448529) (xy 70.489836 -308.431077)
			(xy 70.538055 -308.421233) (xy 70.58723 -308.419252) (xy 70.636085 -308.425184) (xy 70.683356 -308.438876)
			(xy 70.727818 -308.459974) (xy 70.768321 -308.48793) (xy 70.803814 -308.522022) (xy 70.833379 -308.561366)
			(xy 70.85625 -308.604943) (xy 70.871834 -308.651624) (xy 70.879729 -308.700201) (xy 70.880224 -308.724808)
			(xy 71.219072 -308.724808) (xy 71.223032 -308.675754) (xy 71.234809 -308.62797) (xy 71.2541 -308.582694)
			(xy 71.280403 -308.541098) (xy 71.313038 -308.504261) (xy 71.351159 -308.473136) (xy 71.39378 -308.448529)
			(xy 71.439796 -308.431077) (xy 71.488015 -308.421233) (xy 71.53719 -308.419252) (xy 71.586045 -308.425184)
			(xy 71.633316 -308.438876) (xy 71.677778 -308.459974) (xy 71.718281 -308.48793) (xy 71.753774 -308.522022)
			(xy 71.783339 -308.561366) (xy 71.80621 -308.604943) (xy 71.821794 -308.651624) (xy 71.829689 -308.700201)
			(xy 71.830184 -308.724808) (xy 71.829689 -308.749415) (xy 71.821794 -308.797992) (xy 71.80621 -308.844673)
			(xy 71.783339 -308.88825) (xy 71.753774 -308.927594) (xy 71.718281 -308.961686) (xy 71.677778 -308.989642)
			(xy 71.633316 -309.01074) (xy 71.586045 -309.024432) (xy 71.53719 -309.030364) (xy 71.488015 -309.028383)
			(xy 71.439796 -309.018539) (xy 71.39378 -309.001087) (xy 71.351159 -308.97648) (xy 71.313038 -308.945355)
			(xy 71.280403 -308.908518) (xy 71.2541 -308.866922) (xy 71.234809 -308.821646) (xy 71.223032 -308.773862)
			(xy 71.219072 -308.724808) (xy 70.880224 -308.724808) (xy 70.879729 -308.749415) (xy 70.871834 -308.797992)
			(xy 70.85625 -308.844673) (xy 70.833379 -308.88825) (xy 70.803814 -308.927594) (xy 70.768321 -308.961686)
			(xy 70.727818 -308.989642) (xy 70.683356 -309.01074) (xy 70.636085 -309.024432) (xy 70.58723 -309.030364)
			(xy 70.538055 -309.028383) (xy 70.489836 -309.018539) (xy 70.44382 -309.001087) (xy 70.401199 -308.97648)
			(xy 70.363078 -308.945355) (xy 70.330443 -308.908518) (xy 70.30414 -308.866922) (xy 70.284849 -308.821646)
			(xy 70.273072 -308.773862) (xy 70.269112 -308.724808) (xy 69.930264 -308.724808) (xy 69.929769 -308.749415)
			(xy 69.921874 -308.797992) (xy 69.90629 -308.844673) (xy 69.883419 -308.88825) (xy 69.853854 -308.927594)
			(xy 69.818361 -308.961686) (xy 69.777858 -308.989642) (xy 69.733396 -309.01074) (xy 69.686125 -309.024432)
			(xy 69.63727 -309.030364) (xy 69.588095 -309.028383) (xy 69.539876 -309.018539) (xy 69.49386 -309.001087)
			(xy 69.451239 -308.97648) (xy 69.413118 -308.945355) (xy 69.380483 -308.908518) (xy 69.35418 -308.866922)
			(xy 69.334889 -308.821646) (xy 69.323112 -308.773862) (xy 69.319152 -308.724808) (xy 68.980304 -308.724808)
			(xy 68.979809 -308.749415) (xy 68.971914 -308.797992) (xy 68.95633 -308.844673) (xy 68.933459 -308.88825)
			(xy 68.903894 -308.927594) (xy 68.868401 -308.961686) (xy 68.827898 -308.989642) (xy 68.783436 -309.01074)
			(xy 68.736165 -309.024432) (xy 68.68731 -309.030364) (xy 68.638135 -309.028383) (xy 68.589916 -309.018539)
			(xy 68.5439 -309.001087) (xy 68.501279 -308.97648) (xy 68.463158 -308.945355) (xy 68.430523 -308.908518)
			(xy 68.40422 -308.866922) (xy 68.384929 -308.821646) (xy 68.373152 -308.773862) (xy 68.369192 -308.724808)
			(xy 68.03009 -308.724808) (xy 68.029595 -308.749415) (xy 68.0217 -308.797992) (xy 68.006116 -308.844673)
			(xy 67.983245 -308.88825) (xy 67.95368 -308.927594) (xy 67.918187 -308.961686) (xy 67.877684 -308.989642)
			(xy 67.833222 -309.01074) (xy 67.785951 -309.024432) (xy 67.737096 -309.030364) (xy 67.687921 -309.028383)
			(xy 67.639702 -309.018539) (xy 67.593686 -309.001087) (xy 67.551065 -308.97648) (xy 67.512944 -308.945355)
			(xy 67.480309 -308.908518) (xy 67.454006 -308.866922) (xy 67.434715 -308.821646) (xy 67.422938 -308.773862)
			(xy 67.418978 -308.724808) (xy 67.08013 -308.724808) (xy 67.079635 -308.749415) (xy 67.07174 -308.797992)
			(xy 67.056156 -308.844673) (xy 67.033285 -308.88825) (xy 67.00372 -308.927594) (xy 66.968227 -308.961686)
			(xy 66.927724 -308.989642) (xy 66.883262 -309.01074) (xy 66.835991 -309.024432) (xy 66.787136 -309.030364)
			(xy 66.737961 -309.028383) (xy 66.689742 -309.018539) (xy 66.643726 -309.001087) (xy 66.601105 -308.97648)
			(xy 66.562984 -308.945355) (xy 66.530349 -308.908518) (xy 66.504046 -308.866922) (xy 66.484755 -308.821646)
			(xy 66.472978 -308.773862) (xy 66.469018 -308.724808) (xy 66.13017 -308.724808) (xy 66.129675 -308.749415)
			(xy 66.12178 -308.797992) (xy 66.106196 -308.844673) (xy 66.083325 -308.88825) (xy 66.05376 -308.927594)
			(xy 66.018267 -308.961686) (xy 65.977764 -308.989642) (xy 65.933302 -309.01074) (xy 65.886031 -309.024432)
			(xy 65.837176 -309.030364) (xy 65.788001 -309.028383) (xy 65.739782 -309.018539) (xy 65.693766 -309.001087)
			(xy 65.651145 -308.97648) (xy 65.613024 -308.945355) (xy 65.580389 -308.908518) (xy 65.554086 -308.866922)
			(xy 65.534795 -308.821646) (xy 65.523018 -308.773862) (xy 65.519058 -308.724808) (xy 65.18021 -308.724808)
			(xy 65.179715 -308.749415) (xy 65.17182 -308.797992) (xy 65.156236 -308.844673) (xy 65.133365 -308.88825)
			(xy 65.1038 -308.927594) (xy 65.068307 -308.961686) (xy 65.027804 -308.989642) (xy 64.983342 -309.01074)
			(xy 64.936071 -309.024432) (xy 64.887216 -309.030364) (xy 64.838041 -309.028383) (xy 64.789822 -309.018539)
			(xy 64.743806 -309.001087) (xy 64.701185 -308.97648) (xy 64.663064 -308.945355) (xy 64.630429 -308.908518)
			(xy 64.604126 -308.866922) (xy 64.584835 -308.821646) (xy 64.573058 -308.773862) (xy 64.569098 -308.724808)
			(xy 64.23025 -308.724808) (xy 64.229755 -308.749415) (xy 64.22186 -308.797992) (xy 64.206276 -308.844673)
			(xy 64.183405 -308.88825) (xy 64.15384 -308.927594) (xy 64.118347 -308.961686) (xy 64.077844 -308.989642)
			(xy 64.033382 -309.01074) (xy 63.986111 -309.024432) (xy 63.937256 -309.030364) (xy 63.888081 -309.028383)
			(xy 63.839862 -309.018539) (xy 63.793846 -309.001087) (xy 63.751225 -308.97648) (xy 63.713104 -308.945355)
			(xy 63.680469 -308.908518) (xy 63.654166 -308.866922) (xy 63.634875 -308.821646) (xy 63.623098 -308.773862)
			(xy 63.619138 -308.724808) (xy 63.280031 -308.724808) (xy 63.279541 -308.749161) (xy 63.271646 -308.797738)
			(xy 63.256062 -308.844419) (xy 63.233191 -308.887996) (xy 63.203626 -308.92734) (xy 63.168133 -308.961432)
			(xy 63.12763 -308.989388) (xy 63.083168 -309.010486) (xy 63.035897 -309.024178) (xy 62.987042 -309.03011)
			(xy 62.937867 -309.028129) (xy 62.889648 -309.018285) (xy 62.843632 -309.000833) (xy 62.801011 -308.976226)
			(xy 62.76289 -308.945101) (xy 62.730255 -308.908264) (xy 62.703952 -308.866668) (xy 62.684661 -308.821392)
			(xy 62.672884 -308.773608) (xy 62.668924 -308.724554) (xy 62.330063 -308.724554) (xy 62.330526 -308.733101)
			(xy 62.325156 -308.782454) (xy 62.311871 -308.830288) (xy 62.291023 -308.875342) (xy 62.26316 -308.91643)
			(xy 62.229016 -308.952469) (xy 62.189492 -308.982509) (xy 62.145629 -309.005759) (xy 62.098581 -309.021606)
			(xy 62.04959 -309.029633) (xy 62.024768 -309.030116) (xy 62.010585 -309.029944) (xy 61.982345 -309.027269)
			(xy 61.96838 -309.024782) (xy 61.955934 -309.022496) (xy 61.932312 -309.029862) (xy 61.854842 -309.107332)
			(xy 61.847476 -309.130954) (xy 61.849762 -309.1434) (xy 61.852234 -309.157367) (xy 61.854909 -309.185606)
			(xy 61.855096 -309.199788) (xy 61.854574 -309.225043) (xy 61.846261 -309.274865) (xy 61.82986 -309.322639)
			(xy 61.805819 -309.367062) (xy 61.774795 -309.406922) (xy 61.737633 -309.441132) (xy 61.695347 -309.468758)
			(xy 61.649091 -309.489048) (xy 61.600126 -309.501448) (xy 61.549788 -309.505619) (xy 61.49945 -309.501448)
			(xy 61.450485 -309.489048) (xy 61.404229 -309.468758) (xy 61.361943 -309.441132) (xy 61.324781 -309.406922)
			(xy 61.293757 -309.367062) (xy 61.269716 -309.322639) (xy 61.253315 -309.274865) (xy 61.245002 -309.225043)
			(xy 61.24448 -309.199788) (xy 61.244655 -309.185605) (xy 61.247328 -309.157365) (xy 61.249814 -309.1434)
			(xy 61.2521 -309.130954) (xy 61.244734 -309.107332) (xy 61.167264 -309.029862) (xy 61.143642 -309.022496)
			(xy 61.131196 -309.024782) (xy 61.11723 -309.027255) (xy 61.08899 -309.029929) (xy 61.074808 -309.030116)
			(xy 61.060625 -309.029938) (xy 61.032385 -309.027267) (xy 61.01842 -309.024782) (xy 61.005974 -309.022496)
			(xy 60.982352 -309.029862) (xy 60.904882 -309.107332) (xy 60.897516 -309.130954) (xy 60.899802 -309.1434)
			(xy 60.902275 -309.157367) (xy 60.904949 -309.185606) (xy 60.905136 -309.199788) (xy 60.904614 -309.225043)
			(xy 60.896301 -309.274865) (xy 60.8799 -309.322639) (xy 60.855859 -309.367062) (xy 60.824835 -309.406922)
			(xy 60.787673 -309.441132) (xy 60.745387 -309.468758) (xy 60.699131 -309.489048) (xy 60.650166 -309.501448)
			(xy 60.599828 -309.505619) (xy 60.54949 -309.501448) (xy 60.500525 -309.489048) (xy 60.454269 -309.468758)
			(xy 60.411983 -309.441132) (xy 60.374821 -309.406922) (xy 60.343797 -309.367062) (xy 60.319756 -309.322639)
			(xy 60.303355 -309.274865) (xy 60.295042 -309.225043) (xy 60.29452 -309.199788) (xy 60.294695 -309.185605)
			(xy 60.297368 -309.157365) (xy 60.299854 -309.1434) (xy 60.30214 -309.130954) (xy 60.294774 -309.107332)
			(xy 60.217304 -309.029862) (xy 60.193682 -309.022496) (xy 60.181236 -309.024782) (xy 60.167271 -309.027263)
			(xy 60.139031 -309.029932) (xy 60.124848 -309.030116) (xy 60.100022 -309.029674) (xy 60.051024 -309.021649)
			(xy 60.003969 -309.005802) (xy 59.960098 -308.982551) (xy 59.920567 -308.952508) (xy 59.886417 -308.916466)
			(xy 59.858548 -308.875373) (xy 59.837695 -308.830313) (xy 59.824407 -308.782473) (xy 59.819033 -308.733113)
			(xy 58.530069 -308.733113) (xy 58.529741 -308.749415) (xy 58.521846 -308.797992) (xy 58.506262 -308.844673)
			(xy 58.483391 -308.88825) (xy 58.453826 -308.927594) (xy 58.418333 -308.961686) (xy 58.37783 -308.989642)
			(xy 58.333368 -309.01074) (xy 58.286097 -309.024432) (xy 58.237242 -309.030364) (xy 58.188067 -309.028383)
			(xy 58.139848 -309.018539) (xy 58.093832 -309.001087) (xy 58.051211 -308.97648) (xy 58.01309 -308.945355)
			(xy 57.980455 -308.908518) (xy 57.954152 -308.866922) (xy 57.934861 -308.821646) (xy 57.923084 -308.773862)
			(xy 57.919124 -308.724808) (xy 56.630279 -308.724808) (xy 56.630727 -308.733074) (xy 56.625361 -308.782426)
			(xy 56.612081 -308.83026) (xy 56.591238 -308.875315) (xy 56.56338 -308.916405) (xy 56.529242 -308.952446)
			(xy 56.489722 -308.98249) (xy 56.445862 -309.005744) (xy 56.398818 -309.021597) (xy 56.349829 -309.029629)
			(xy 56.325008 -309.030116) (xy 56.310762 -309.029941) (xy 56.282394 -309.027274) (xy 56.268366 -309.024782)
			(xy 56.25592 -309.022496) (xy 56.232298 -309.029862) (xy 56.163718 -309.098188) (xy 56.155556 -309.107421)
			(xy 56.14825 -309.130914) (xy 56.149748 -309.143146) (xy 56.149748 -309.143654) (xy 56.152215 -309.157557)
			(xy 56.154884 -309.185669) (xy 56.155082 -309.199788) (xy 56.15456 -309.225043) (xy 56.146247 -309.274865)
			(xy 56.129846 -309.322639) (xy 56.105805 -309.367062) (xy 56.074781 -309.406922) (xy 56.037619 -309.441132)
			(xy 55.995333 -309.468758) (xy 55.949077 -309.489048) (xy 55.900112 -309.501448) (xy 55.849774 -309.505619)
			(xy 55.799436 -309.501448) (xy 55.750471 -309.489048) (xy 55.704215 -309.468758) (xy 55.661929 -309.441132)
			(xy 55.624767 -309.406922) (xy 55.593743 -309.367062) (xy 55.569702 -309.322639) (xy 55.553301 -309.274865)
			(xy 55.544988 -309.225043) (xy 55.544466 -309.199788) (xy 55.544641 -309.185605) (xy 55.547314 -309.157365)
			(xy 55.5498 -309.1434) (xy 55.552086 -309.130954) (xy 55.54472 -309.107332) (xy 55.46725 -309.029862)
			(xy 55.443628 -309.022496) (xy 55.431182 -309.024782) (xy 55.417216 -309.027257) (xy 55.388976 -309.02993)
			(xy 55.374794 -309.030116) (xy 55.349974 -309.029616) (xy 55.300987 -309.021584) (xy 55.253945 -309.005732)
			(xy 55.210087 -308.982479) (xy 55.170569 -308.952437) (xy 55.136432 -308.916397) (xy 55.108575 -308.87531)
			(xy 55.087732 -308.830256) (xy 55.074453 -308.782425) (xy 55.069087 -308.733075) (xy 54.729976 -308.733075)
			(xy 54.729647 -308.749415) (xy 54.721752 -308.797992) (xy 54.706168 -308.844673) (xy 54.683297 -308.88825)
			(xy 54.653732 -308.927594) (xy 54.618239 -308.961686) (xy 54.577736 -308.989642) (xy 54.533274 -309.01074)
			(xy 54.486003 -309.024432) (xy 54.437148 -309.030364) (xy 54.387973 -309.028383) (xy 54.339754 -309.018539)
			(xy 54.293738 -309.001087) (xy 54.251117 -308.97648) (xy 54.212996 -308.945355) (xy 54.180361 -308.908518)
			(xy 54.154058 -308.866922) (xy 54.134767 -308.821646) (xy 54.12299 -308.773862) (xy 54.11903 -308.724808)
			(xy 53.780767 -308.724808) (xy 53.776596 -308.775147) (xy 53.764193 -308.82412) (xy 53.743899 -308.870384)
			(xy 53.716266 -308.912677) (xy 53.682049 -308.949844) (xy 53.64218 -308.980871) (xy 53.597748 -309.004913)
			(xy 53.549965 -309.021314) (xy 53.500134 -309.029625) (xy 53.474874 -309.030116) (xy 53.460691 -309.029943)
			(xy 53.432451 -309.027268) (xy 53.418486 -309.024782) (xy 53.40604 -309.022496) (xy 53.382418 -309.029862)
			(xy 53.304948 -309.107332) (xy 53.297582 -309.130954) (xy 53.299868 -309.1434) (xy 53.30234 -309.157367)
			(xy 53.305015 -309.185606) (xy 53.305202 -309.199788) (xy 53.304735 -309.22461) (xy 53.296705 -309.2736)
			(xy 53.280856 -309.320646) (xy 53.257604 -309.364508) (xy 53.227562 -309.40403) (xy 53.191522 -309.438171)
			(xy 53.150433 -309.466032) (xy 53.105379 -309.486879) (xy 53.057545 -309.500161) (xy 53.008192 -309.505531)
			(xy 52.958621 -309.502845) (xy 52.910137 -309.492174) (xy 52.864019 -309.4738) (xy 52.82148 -309.448208)
			(xy 52.783643 -309.41607) (xy 52.751503 -309.378234) (xy 52.725908 -309.335697) (xy 52.707531 -309.28958)
			(xy 52.696858 -309.241097) (xy 52.694169 -309.191526) (xy 52.699535 -309.142173) (xy 52.712815 -309.094338)
			(xy 52.733659 -309.049282) (xy 52.761517 -309.008192) (xy 52.795657 -308.97215) (xy 52.835177 -308.942106)
			(xy 52.879038 -308.918851) (xy 52.926082 -308.902999) (xy 52.975072 -308.894966) (xy 52.999894 -308.89448)
			(xy 53.014077 -308.894658) (xy 53.042317 -308.897329) (xy 53.056282 -308.899814) (xy 53.068728 -308.9021)
			(xy 53.09235 -308.894734) (xy 53.16982 -308.817264) (xy 53.177186 -308.793642) (xy 53.1749 -308.781196)
			(xy 53.172427 -308.76723) (xy 53.169753 -308.73899) (xy 53.169566 -308.724808) (xy 53.169744 -308.710625)
			(xy 53.172415 -308.682385) (xy 53.1749 -308.66842) (xy 53.177186 -308.655974) (xy 53.16982 -308.632352)
			(xy 53.09235 -308.554882) (xy 53.068728 -308.547516) (xy 53.056282 -308.549802) (xy 53.042316 -308.552277)
			(xy 53.014076 -308.55495) (xy 52.999894 -308.555136) (xy 52.974641 -308.554558) (xy 52.924825 -308.546244)
			(xy 52.877056 -308.529844) (xy 52.832638 -308.505806) (xy 52.792783 -308.474784) (xy 52.758577 -308.437626)
			(xy 52.730953 -308.395344) (xy 52.710666 -308.349093) (xy 52.698268 -308.300133) (xy 52.694097 -308.2498)
			(xy 52.3552 -308.2498) (xy 52.355648 -308.25805) (xy 52.350285 -308.307406) (xy 52.337009 -308.355244)
			(xy 52.316168 -308.400304) (xy 52.288311 -308.441398) (xy 52.254174 -308.477445) (xy 52.214654 -308.507493)
			(xy 52.170794 -308.530753) (xy 52.123748 -308.54661) (xy 52.074757 -308.554647) (xy 52.049934 -308.555136)
			(xy 52.035751 -308.554954) (xy 52.007511 -308.552285) (xy 51.993546 -308.549802) (xy 51.9811 -308.547516)
			(xy 51.957478 -308.554882) (xy 51.880008 -308.632352) (xy 51.872642 -308.655974) (xy 51.874928 -308.66842)
			(xy 51.877404 -308.682386) (xy 51.880076 -308.710626) (xy 51.880262 -308.724808) (xy 51.879869 -308.748804)
			(xy 51.87236 -308.796204) (xy 51.857527 -308.841846) (xy 51.835737 -308.884605) (xy 51.807525 -308.923428)
			(xy 51.773587 -308.95736) (xy 51.734759 -308.985565) (xy 51.691996 -309.007348) (xy 51.646351 -309.022172)
			(xy 51.59895 -309.029673) (xy 51.574954 -309.030116) (xy 51.560771 -309.029932) (xy 51.532531 -309.027265)
			(xy 51.518566 -309.024782) (xy 51.50612 -309.022496) (xy 51.482498 -309.029862) (xy 51.405028 -309.107332)
			(xy 51.397662 -309.130954) (xy 51.399948 -309.1434) (xy 51.40242 -309.157367) (xy 51.405095 -309.185606)
			(xy 51.405282 -309.199788) (xy 51.404835 -309.22461) (xy 51.396806 -309.273599) (xy 51.380957 -309.320644)
			(xy 51.357705 -309.364506) (xy 51.327664 -309.404028) (xy 51.291625 -309.438169) (xy 51.250537 -309.46603)
			(xy 51.205484 -309.486877) (xy 51.157651 -309.50016) (xy 51.108299 -309.50553) (xy 51.058728 -309.502845)
			(xy 51.010245 -309.492176) (xy 50.964127 -309.473804) (xy 50.921588 -309.448213) (xy 50.88375 -309.416077)
			(xy 50.851609 -309.378243) (xy 50.826013 -309.335708) (xy 50.807635 -309.289591) (xy 50.79696 -309.24111)
			(xy 50.794269 -309.191539) (xy 50.455556 -309.191539) (xy 50.452874 -309.241072) (xy 50.442204 -309.289561)
			(xy 50.423829 -309.335686) (xy 50.398234 -309.378231) (xy 50.366093 -309.416074) (xy 50.328253 -309.448218)
			(xy 50.285711 -309.473817) (xy 50.239588 -309.492196) (xy 50.191099 -309.50287) (xy 50.141522 -309.505559)
			(xy 50.092163 -309.500192) (xy 50.044323 -309.486909) (xy 49.999262 -309.466062) (xy 49.958167 -309.438199)
			(xy 49.922122 -309.404054) (xy 49.892075 -309.364527) (xy 49.86882 -309.320661) (xy 49.852968 -309.273609)
			(xy 49.844937 -309.224613) (xy 49.844452 -309.199788) (xy 49.844628 -309.185605) (xy 49.8473 -309.157365)
			(xy 49.849786 -309.1434) (xy 49.852072 -309.130954) (xy 49.844706 -309.107332) (xy 49.767236 -309.029862)
			(xy 49.743614 -309.022496) (xy 49.731168 -309.024782) (xy 49.717202 -309.027259) (xy 49.688963 -309.02993)
			(xy 49.67478 -309.030116) (xy 49.650789 -309.029656) (xy 49.603397 -309.022147) (xy 49.557763 -309.007317)
			(xy 49.515011 -308.985532) (xy 49.476193 -308.957327) (xy 49.442265 -308.923398) (xy 49.414062 -308.884579)
			(xy 49.392278 -308.841826) (xy 49.37745 -308.796191) (xy 49.369943 -308.748799) (xy 49.369472 -308.724808)
			(xy 49.36965 -308.710625) (xy 49.372321 -308.682385) (xy 49.374806 -308.66842) (xy 49.377092 -308.655974)
			(xy 49.369726 -308.632352) (xy 49.292256 -308.554882) (xy 49.268634 -308.547516) (xy 49.256188 -308.549802)
			(xy 49.242222 -308.552276) (xy 49.213982 -308.554949) (xy 49.1998 -308.555136) (xy 49.174979 -308.554622)
			(xy 49.12599 -308.546591) (xy 49.078946 -308.530739) (xy 49.035086 -308.507486) (xy 48.995567 -308.477443)
			(xy 48.961428 -308.441402) (xy 48.93357 -308.400313) (xy 48.912726 -308.355258) (xy 48.899447 -308.307424)
			(xy 48.894081 -308.258073) (xy 48.554982 -308.258073) (xy 48.554653 -308.274435) (xy 48.546758 -308.323012)
			(xy 48.531174 -308.369693) (xy 48.508303 -308.41327) (xy 48.478738 -308.452614) (xy 48.443245 -308.486706)
			(xy 48.402742 -308.514662) (xy 48.35828 -308.53576) (xy 48.311009 -308.549452) (xy 48.262154 -308.555384)
			(xy 48.212979 -308.553403) (xy 48.16476 -308.543559) (xy 48.118744 -308.526107) (xy 48.076123 -308.5015)
			(xy 48.038002 -308.470375) (xy 48.005367 -308.433538) (xy 47.979064 -308.391942) (xy 47.959773 -308.346666)
			(xy 47.947996 -308.298882) (xy 47.944036 -308.249828) (xy 47.605188 -308.249828) (xy 47.604693 -308.274435)
			(xy 47.596798 -308.323012) (xy 47.581214 -308.369693) (xy 47.558343 -308.41327) (xy 47.528778 -308.452614)
			(xy 47.493285 -308.486706) (xy 47.452782 -308.514662) (xy 47.40832 -308.53576) (xy 47.361049 -308.549452)
			(xy 47.312194 -308.555384) (xy 47.263019 -308.553403) (xy 47.2148 -308.543559) (xy 47.168784 -308.526107)
			(xy 47.126163 -308.5015) (xy 47.088042 -308.470375) (xy 47.055407 -308.433538) (xy 47.029104 -308.391942)
			(xy 47.009813 -308.346666) (xy 46.998036 -308.298882) (xy 46.994076 -308.249828) (xy 46.655228 -308.249828)
			(xy 46.654733 -308.274435) (xy 46.646838 -308.323012) (xy 46.631254 -308.369693) (xy 46.608383 -308.41327)
			(xy 46.578818 -308.452614) (xy 46.543325 -308.486706) (xy 46.502822 -308.514662) (xy 46.45836 -308.53576)
			(xy 46.411089 -308.549452) (xy 46.362234 -308.555384) (xy 46.313059 -308.553403) (xy 46.26484 -308.543559)
			(xy 46.218824 -308.526107) (xy 46.176203 -308.5015) (xy 46.138082 -308.470375) (xy 46.105447 -308.433538)
			(xy 46.079144 -308.391942) (xy 46.059853 -308.346666) (xy 46.048076 -308.298882) (xy 46.044116 -308.249828)
			(xy 45.705268 -308.249828) (xy 45.704773 -308.274435) (xy 45.696878 -308.323012) (xy 45.681294 -308.369693)
			(xy 45.658423 -308.41327) (xy 45.628858 -308.452614) (xy 45.593365 -308.486706) (xy 45.552862 -308.514662)
			(xy 45.5084 -308.53576) (xy 45.461129 -308.549452) (xy 45.412274 -308.555384) (xy 45.363099 -308.553403)
			(xy 45.31488 -308.543559) (xy 45.268864 -308.526107) (xy 45.226243 -308.5015) (xy 45.188122 -308.470375)
			(xy 45.155487 -308.433538) (xy 45.129184 -308.391942) (xy 45.109893 -308.346666) (xy 45.098116 -308.298882)
			(xy 45.094156 -308.249828) (xy 44.776898 -308.249828) (xy 44.776394 -308.275536) (xy 44.768351 -308.326318)
			(xy 44.752463 -308.375217) (xy 44.72912 -308.421029) (xy 44.698899 -308.462625) (xy 44.662543 -308.498981)
			(xy 44.620947 -308.529202) (xy 44.575135 -308.552545) (xy 44.526236 -308.568433) (xy 44.475454 -308.576476)
			(xy 44.424038 -308.576476) (xy 44.373256 -308.568433) (xy 44.324357 -308.552545) (xy 44.278545 -308.529202)
			(xy 44.236949 -308.498981) (xy 44.200593 -308.462625) (xy 44.170372 -308.421029) (xy 44.147029 -308.375217)
			(xy 44.131141 -308.326318) (xy 44.123098 -308.275536) (xy 43.826434 -308.275536) (xy 43.818391 -308.326318)
			(xy 43.802503 -308.375217) (xy 43.77916 -308.421029) (xy 43.748939 -308.462625) (xy 43.712583 -308.498981)
			(xy 43.670987 -308.529202) (xy 43.625175 -308.552545) (xy 43.576276 -308.568433) (xy 43.525494 -308.576476)
			(xy 43.474078 -308.576476) (xy 43.423296 -308.568433) (xy 43.374397 -308.552545) (xy 43.328585 -308.529202)
			(xy 43.286989 -308.498981) (xy 43.250633 -308.462625) (xy 43.220412 -308.421029) (xy 43.197069 -308.375217)
			(xy 43.181181 -308.326318) (xy 43.173138 -308.275536) (xy 42.85446 -308.275536) (xy 42.846744 -308.323012)
			(xy 42.83116 -308.369693) (xy 42.808289 -308.41327) (xy 42.778724 -308.452614) (xy 42.743231 -308.486706)
			(xy 42.702728 -308.514662) (xy 42.658266 -308.53576) (xy 42.610995 -308.549452) (xy 42.56214 -308.555384)
			(xy 42.512965 -308.553403) (xy 42.464746 -308.543559) (xy 42.41873 -308.526107) (xy 42.376109 -308.5015)
			(xy 42.337988 -308.470375) (xy 42.305353 -308.433538) (xy 42.27905 -308.391942) (xy 42.259759 -308.346666)
			(xy 42.247982 -308.298882) (xy 42.244022 -308.249828) (xy 41.905174 -308.249828) (xy 41.904679 -308.274435)
			(xy 41.896784 -308.323012) (xy 41.8812 -308.369693) (xy 41.858329 -308.41327) (xy 41.828764 -308.452614)
			(xy 41.793271 -308.486706) (xy 41.752768 -308.514662) (xy 41.708306 -308.53576) (xy 41.661035 -308.549452)
			(xy 41.61218 -308.555384) (xy 41.563005 -308.553403) (xy 41.514786 -308.543559) (xy 41.46877 -308.526107)
			(xy 41.426149 -308.5015) (xy 41.388028 -308.470375) (xy 41.355393 -308.433538) (xy 41.32909 -308.391942)
			(xy 41.309799 -308.346666) (xy 41.298022 -308.298882) (xy 41.294062 -308.249828) (xy 40.955214 -308.249828)
			(xy 40.954719 -308.274435) (xy 40.946824 -308.323012) (xy 40.93124 -308.369693) (xy 40.908369 -308.41327)
			(xy 40.878804 -308.452614) (xy 40.843311 -308.486706) (xy 40.802808 -308.514662) (xy 40.758346 -308.53576)
			(xy 40.711075 -308.549452) (xy 40.66222 -308.555384) (xy 40.613045 -308.553403) (xy 40.564826 -308.543559)
			(xy 40.51881 -308.526107) (xy 40.476189 -308.5015) (xy 40.438068 -308.470375) (xy 40.405433 -308.433538)
			(xy 40.37913 -308.391942) (xy 40.359839 -308.346666) (xy 40.348062 -308.298882) (xy 40.344102 -308.249828)
			(xy 40.005254 -308.249828) (xy 40.004759 -308.274435) (xy 39.996864 -308.323012) (xy 39.98128 -308.369693)
			(xy 39.958409 -308.41327) (xy 39.928844 -308.452614) (xy 39.893351 -308.486706) (xy 39.852848 -308.514662)
			(xy 39.808386 -308.53576) (xy 39.761115 -308.549452) (xy 39.71226 -308.555384) (xy 39.663085 -308.553403)
			(xy 39.614866 -308.543559) (xy 39.56885 -308.526107) (xy 39.526229 -308.5015) (xy 39.488108 -308.470375)
			(xy 39.455473 -308.433538) (xy 39.42917 -308.391942) (xy 39.409879 -308.346666) (xy 39.398102 -308.298882)
			(xy 39.394142 -308.249828) (xy 39.055294 -308.249828) (xy 39.054799 -308.274435) (xy 39.046904 -308.323012)
			(xy 39.03132 -308.369693) (xy 39.008449 -308.41327) (xy 38.978884 -308.452614) (xy 38.943391 -308.486706)
			(xy 38.902888 -308.514662) (xy 38.858426 -308.53576) (xy 38.811155 -308.549452) (xy 38.7623 -308.555384)
			(xy 38.713125 -308.553403) (xy 38.664906 -308.543559) (xy 38.61889 -308.526107) (xy 38.576269 -308.5015)
			(xy 38.538148 -308.470375) (xy 38.505513 -308.433538) (xy 38.47921 -308.391942) (xy 38.459919 -308.346666)
			(xy 38.448142 -308.298882) (xy 38.444182 -308.249828) (xy 38.126924 -308.249828) (xy 38.12642 -308.275536)
			(xy 38.118377 -308.326318) (xy 38.102489 -308.375217) (xy 38.079146 -308.421029) (xy 38.048925 -308.462625)
			(xy 38.012569 -308.498981) (xy 37.970973 -308.529202) (xy 37.925161 -308.552545) (xy 37.876262 -308.568433)
			(xy 37.82548 -308.576476) (xy 37.774064 -308.576476) (xy 37.723282 -308.568433) (xy 37.674383 -308.552545)
			(xy 37.628571 -308.529202) (xy 37.586975 -308.498981) (xy 37.550619 -308.462625) (xy 37.520398 -308.421029)
			(xy 37.497055 -308.375217) (xy 37.481167 -308.326318) (xy 37.473124 -308.275536) (xy 37.17646 -308.275536)
			(xy 37.168417 -308.326318) (xy 37.152529 -308.375217) (xy 37.129186 -308.421029) (xy 37.098965 -308.462625)
			(xy 37.062609 -308.498981) (xy 37.021013 -308.529202) (xy 36.975201 -308.552545) (xy 36.926302 -308.568433)
			(xy 36.87552 -308.576476) (xy 36.824104 -308.576476) (xy 36.773322 -308.568433) (xy 36.724423 -308.552545)
			(xy 36.678611 -308.529202) (xy 36.637015 -308.498981) (xy 36.600659 -308.462625) (xy 36.570438 -308.421029)
			(xy 36.547095 -308.375217) (xy 36.531207 -308.326318) (xy 36.523164 -308.275536) (xy 36.204273 -308.275536)
			(xy 36.196516 -308.323266) (xy 36.180932 -308.369947) (xy 36.158061 -308.413524) (xy 36.128496 -308.452868)
			(xy 36.093003 -308.48696) (xy 36.0525 -308.514916) (xy 36.008038 -308.536014) (xy 35.960767 -308.549706)
			(xy 35.911912 -308.555638) (xy 35.862737 -308.553657) (xy 35.814518 -308.543813) (xy 35.768502 -308.526361)
			(xy 35.725881 -308.501754) (xy 35.68776 -308.470629) (xy 35.655125 -308.433792) (xy 35.628822 -308.392196)
			(xy 35.609531 -308.34692) (xy 35.597754 -308.299136) (xy 35.593794 -308.250082) (xy 28.784439 -308.250082)
			(xy 28.793331 -308.263522) (xy 28.817003 -308.314019) (xy 28.833071 -308.367426) (xy 28.841191 -308.422602)
			(xy 28.8417 -308.450488) (xy 28.841191 -308.478374) (xy 28.833071 -308.53355) (xy 28.817003 -308.586957)
			(xy 28.793331 -308.637454) (xy 28.778726 -308.65953) (xy 30.405576 -308.65953) (xy 30.409647 -308.603908)
			(xy 30.421773 -308.549471) (xy 30.441696 -308.49738) (xy 30.468992 -308.448745) (xy 30.503078 -308.404602)
			(xy 30.543227 -308.365893) (xy 30.588585 -308.333442) (xy 30.638185 -308.307941) (xy 30.690969 -308.289934)
			(xy 30.745812 -308.279804) (xy 30.801546 -308.277767) (xy 30.856983 -308.283867) (xy 30.91094 -308.297973)
			(xy 30.962269 -308.319785) (xy 31.009875 -308.348839) (xy 31.052743 -308.384514) (xy 31.08996 -308.426051)
			(xy 31.120733 -308.472564) (xy 31.144405 -308.523061) (xy 31.160473 -308.576468) (xy 31.168593 -308.631644)
			(xy 31.169102 -308.65953) (xy 31.168593 -308.687416) (xy 31.160473 -308.742592) (xy 31.144405 -308.795999)
			(xy 31.120733 -308.846496) (xy 31.08996 -308.893009) (xy 31.052743 -308.934546) (xy 31.009875 -308.970221)
			(xy 30.962269 -308.999275) (xy 30.91094 -309.021087) (xy 30.856983 -309.035193) (xy 30.801546 -309.041293)
			(xy 30.745812 -309.039256) (xy 30.690969 -309.029126) (xy 30.638185 -309.011119) (xy 30.588585 -308.985618)
			(xy 30.543227 -308.953167) (xy 30.503078 -308.914458) (xy 30.468992 -308.870315) (xy 30.441696 -308.82168)
			(xy 30.421773 -308.769589) (xy 30.409647 -308.715152) (xy 30.405576 -308.65953) (xy 28.778726 -308.65953)
			(xy 28.762558 -308.683967) (xy 28.725341 -308.725504) (xy 28.682473 -308.761179) (xy 28.634867 -308.790233)
			(xy 28.583538 -308.812045) (xy 28.529581 -308.826151) (xy 28.474144 -308.832251) (xy 28.41841 -308.830214)
			(xy 28.363567 -308.820084) (xy 28.310783 -308.802077) (xy 28.261183 -308.776576) (xy 28.215825 -308.744125)
			(xy 28.175676 -308.705416) (xy 28.14159 -308.661273) (xy 28.114294 -308.612638) (xy 28.094371 -308.560547)
			(xy 28.082245 -308.50611) (xy 28.078174 -308.450488) (xy 17.635474 -308.450488) (xy 17.635474 -308.456584)
			(xy 17.635982 -308.457092) (xy 17.635982 -309.414926) (xy 26.999944 -309.414926) (xy 27.004015 -309.359304)
			(xy 27.016141 -309.304867) (xy 27.036064 -309.252776) (xy 27.06336 -309.204141) (xy 27.097446 -309.159998)
			(xy 27.137595 -309.121289) (xy 27.182953 -309.088838) (xy 27.232553 -309.063337) (xy 27.285337 -309.04533)
			(xy 27.34018 -309.0352) (xy 27.395914 -309.033163) (xy 27.451351 -309.039263) (xy 27.505308 -309.053369)
			(xy 27.556637 -309.075181) (xy 27.604243 -309.104235) (xy 27.647111 -309.13991) (xy 27.684328 -309.181447)
			(xy 27.696462 -309.199788) (xy 36.544008 -309.199788) (xy 36.547968 -309.150734) (xy 36.559745 -309.10295)
			(xy 36.579036 -309.057674) (xy 36.605339 -309.016078) (xy 36.637974 -308.979241) (xy 36.676095 -308.948116)
			(xy 36.718716 -308.923509) (xy 36.764732 -308.906057) (xy 36.812951 -308.896213) (xy 36.862126 -308.894232)
			(xy 36.910981 -308.900164) (xy 36.958252 -308.913856) (xy 37.002714 -308.934954) (xy 37.043217 -308.96291)
			(xy 37.07871 -308.997002) (xy 37.108275 -309.036346) (xy 37.131146 -309.079923) (xy 37.14673 -309.126604)
			(xy 37.154625 -309.175181) (xy 37.15512 -309.199788) (xy 37.493968 -309.199788) (xy 37.497928 -309.150734)
			(xy 37.509705 -309.10295) (xy 37.528996 -309.057674) (xy 37.555299 -309.016078) (xy 37.587934 -308.979241)
			(xy 37.626055 -308.948116) (xy 37.668676 -308.923509) (xy 37.714692 -308.906057) (xy 37.762911 -308.896213)
			(xy 37.812086 -308.894232) (xy 37.860941 -308.900164) (xy 37.908212 -308.913856) (xy 37.952674 -308.934954)
			(xy 37.993177 -308.96291) (xy 38.02867 -308.997002) (xy 38.058235 -309.036346) (xy 38.081106 -309.079923)
			(xy 38.09669 -309.126604) (xy 38.104585 -309.175181) (xy 38.10508 -309.199788) (xy 38.104585 -309.224395)
			(xy 38.104406 -309.225496) (xy 38.423338 -309.225496) (xy 38.423338 -309.17408) (xy 38.431381 -309.123298)
			(xy 38.447269 -309.074399) (xy 38.470612 -309.028587) (xy 38.500833 -308.986991) (xy 38.537189 -308.950635)
			(xy 38.578785 -308.920414) (xy 38.624597 -308.897071) (xy 38.673496 -308.881183) (xy 38.724278 -308.87314)
			(xy 38.775694 -308.87314) (xy 38.826476 -308.881183) (xy 38.875375 -308.897071) (xy 38.921187 -308.920414)
			(xy 38.962783 -308.950635) (xy 38.999139 -308.986991) (xy 39.02936 -309.028587) (xy 39.052703 -309.074399)
			(xy 39.068591 -309.123298) (xy 39.076634 -309.17408) (xy 39.077138 -309.199788) (xy 39.076634 -309.225496)
			(xy 39.373298 -309.225496) (xy 39.373298 -309.17408) (xy 39.381341 -309.123298) (xy 39.397229 -309.074399)
			(xy 39.420572 -309.028587) (xy 39.450793 -308.986991) (xy 39.487149 -308.950635) (xy 39.528745 -308.920414)
			(xy 39.574557 -308.897071) (xy 39.623456 -308.881183) (xy 39.674238 -308.87314) (xy 39.725654 -308.87314)
			(xy 39.776436 -308.881183) (xy 39.825335 -308.897071) (xy 39.871147 -308.920414) (xy 39.912743 -308.950635)
			(xy 39.949099 -308.986991) (xy 39.97932 -309.028587) (xy 40.002663 -309.074399) (xy 40.018551 -309.123298)
			(xy 40.026594 -309.17408) (xy 40.027098 -309.199788) (xy 40.344102 -309.199788) (xy 40.348062 -309.150734)
			(xy 40.359839 -309.10295) (xy 40.37913 -309.057674) (xy 40.405433 -309.016078) (xy 40.438068 -308.979241)
			(xy 40.476189 -308.948116) (xy 40.51881 -308.923509) (xy 40.564826 -308.906057) (xy 40.613045 -308.896213)
			(xy 40.66222 -308.894232) (xy 40.711075 -308.900164) (xy 40.758346 -308.913856) (xy 40.802808 -308.934954)
			(xy 40.843311 -308.96291) (xy 40.878804 -308.997002) (xy 40.908369 -309.036346) (xy 40.93124 -309.079923)
			(xy 40.946824 -309.126604) (xy 40.954719 -309.175181) (xy 40.955214 -309.199788) (xy 40.954719 -309.224395)
			(xy 40.95454 -309.225496) (xy 41.273218 -309.225496) (xy 41.273218 -309.17408) (xy 41.281261 -309.123298)
			(xy 41.297149 -309.074399) (xy 41.320492 -309.028587) (xy 41.350713 -308.986991) (xy 41.387069 -308.950635)
			(xy 41.428665 -308.920414) (xy 41.474477 -308.897071) (xy 41.523376 -308.881183) (xy 41.574158 -308.87314)
			(xy 41.625574 -308.87314) (xy 41.676356 -308.881183) (xy 41.725255 -308.897071) (xy 41.771067 -308.920414)
			(xy 41.812663 -308.950635) (xy 41.849019 -308.986991) (xy 41.87924 -309.028587) (xy 41.902583 -309.074399)
			(xy 41.918471 -309.123298) (xy 41.926514 -309.17408) (xy 41.927018 -309.199788) (xy 41.926514 -309.225496)
			(xy 42.223178 -309.225496) (xy 42.223178 -309.17408) (xy 42.231221 -309.123298) (xy 42.247109 -309.074399)
			(xy 42.270452 -309.028587) (xy 42.300673 -308.986991) (xy 42.337029 -308.950635) (xy 42.378625 -308.920414)
			(xy 42.424437 -308.897071) (xy 42.473336 -308.881183) (xy 42.524118 -308.87314) (xy 42.575534 -308.87314)
			(xy 42.626316 -308.881183) (xy 42.675215 -308.897071) (xy 42.721027 -308.920414) (xy 42.762623 -308.950635)
			(xy 42.798979 -308.986991) (xy 42.8292 -309.028587) (xy 42.852543 -309.074399) (xy 42.868431 -309.123298)
			(xy 42.876474 -309.17408) (xy 42.876978 -309.199788) (xy 43.193982 -309.199788) (xy 43.197942 -309.150734)
			(xy 43.209719 -309.10295) (xy 43.22901 -309.057674) (xy 43.255313 -309.016078) (xy 43.287948 -308.979241)
			(xy 43.326069 -308.948116) (xy 43.36869 -308.923509) (xy 43.414706 -308.906057) (xy 43.462925 -308.896213)
			(xy 43.5121 -308.894232) (xy 43.560955 -308.900164) (xy 43.608226 -308.913856) (xy 43.652688 -308.934954)
			(xy 43.693191 -308.96291) (xy 43.728684 -308.997002) (xy 43.758249 -309.036346) (xy 43.78112 -309.079923)
			(xy 43.796704 -309.126604) (xy 43.804599 -309.175181) (xy 43.805094 -309.199788) (xy 44.143942 -309.199788)
			(xy 44.147902 -309.150734) (xy 44.159679 -309.10295) (xy 44.17897 -309.057674) (xy 44.205273 -309.016078)
			(xy 44.237908 -308.979241) (xy 44.276029 -308.948116) (xy 44.31865 -308.923509) (xy 44.364666 -308.906057)
			(xy 44.412885 -308.896213) (xy 44.46206 -308.894232) (xy 44.510915 -308.900164) (xy 44.558186 -308.913856)
			(xy 44.602648 -308.934954) (xy 44.643151 -308.96291) (xy 44.678644 -308.997002) (xy 44.708209 -309.036346)
			(xy 44.73108 -309.079923) (xy 44.746664 -309.126604) (xy 44.754559 -309.175181) (xy 44.755054 -309.199788)
			(xy 45.094156 -309.199788) (xy 45.098116 -309.150734) (xy 45.109893 -309.10295) (xy 45.129184 -309.057674)
			(xy 45.155487 -309.016078) (xy 45.188122 -308.979241) (xy 45.226243 -308.948116) (xy 45.268864 -308.923509)
			(xy 45.31488 -308.906057) (xy 45.363099 -308.896213) (xy 45.412274 -308.894232) (xy 45.461129 -308.900164)
			(xy 45.5084 -308.913856) (xy 45.552862 -308.934954) (xy 45.593365 -308.96291) (xy 45.628858 -308.997002)
			(xy 45.658423 -309.036346) (xy 45.681294 -309.079923) (xy 45.696878 -309.126604) (xy 45.704773 -309.175181)
			(xy 45.705268 -309.199788) (xy 46.044116 -309.199788) (xy 46.048076 -309.150734) (xy 46.059853 -309.10295)
			(xy 46.079144 -309.057674) (xy 46.105447 -309.016078) (xy 46.138082 -308.979241) (xy 46.176203 -308.948116)
			(xy 46.218824 -308.923509) (xy 46.26484 -308.906057) (xy 46.313059 -308.896213) (xy 46.362234 -308.894232)
			(xy 46.411089 -308.900164) (xy 46.45836 -308.913856) (xy 46.502822 -308.934954) (xy 46.543325 -308.96291)
			(xy 46.578818 -308.997002) (xy 46.608383 -309.036346) (xy 46.631254 -309.079923) (xy 46.646838 -309.126604)
			(xy 46.654733 -309.175181) (xy 46.655228 -309.199788) (xy 46.994076 -309.199788) (xy 46.998036 -309.150734)
			(xy 47.009813 -309.10295) (xy 47.029104 -309.057674) (xy 47.055407 -309.016078) (xy 47.088042 -308.979241)
			(xy 47.126163 -308.948116) (xy 47.168784 -308.923509) (xy 47.2148 -308.906057) (xy 47.263019 -308.896213)
			(xy 47.312194 -308.894232) (xy 47.361049 -308.900164) (xy 47.40832 -308.913856) (xy 47.452782 -308.934954)
			(xy 47.493285 -308.96291) (xy 47.528778 -308.997002) (xy 47.558343 -309.036346) (xy 47.581214 -309.079923)
			(xy 47.596798 -309.126604) (xy 47.604693 -309.175181) (xy 47.605188 -309.199788) (xy 47.605021 -309.208114)
			(xy 47.944042 -309.208114) (xy 47.946725 -309.158537) (xy 47.957393 -309.110048) (xy 47.975766 -309.063923)
			(xy 48.001359 -309.021378) (xy 48.033498 -308.983535) (xy 48.071336 -308.95139) (xy 48.113876 -308.925789)
			(xy 48.159998 -308.907409) (xy 48.208485 -308.896732) (xy 48.258062 -308.894041) (xy 48.30742 -308.899405)
			(xy 48.35526 -308.912685) (xy 48.400322 -308.933529) (xy 48.441418 -308.961389) (xy 48.477465 -308.995531)
			(xy 48.507513 -309.035055) (xy 48.530771 -309.078919) (xy 48.546627 -309.125969) (xy 48.554661 -309.174963)
			(xy 48.555148 -309.199788) (xy 48.554969 -309.213971) (xy 48.552298 -309.242211) (xy 48.549814 -309.256176)
			(xy 48.547528 -309.268622) (xy 48.554894 -309.292244) (xy 48.632364 -309.369714) (xy 48.655986 -309.37708)
			(xy 48.668432 -309.374794) (xy 48.682398 -309.372317) (xy 48.710637 -309.369646) (xy 48.72482 -309.36946)
			(xy 48.74881 -309.369944) (xy 48.796199 -309.377452) (xy 48.841831 -309.39228) (xy 48.884582 -309.414064)
			(xy 48.923399 -309.442266) (xy 48.957327 -309.476192) (xy 48.98553 -309.515008) (xy 49.007315 -309.557758)
			(xy 49.022145 -309.603389) (xy 49.029655 -309.650778) (xy 49.030128 -309.674768) (xy 49.029947 -309.688951)
			(xy 49.027278 -309.717191) (xy 49.024794 -309.731156) (xy 49.022508 -309.743602) (xy 49.029874 -309.767224)
			(xy 49.107344 -309.844694) (xy 49.130966 -309.85206) (xy 49.143412 -309.849774) (xy 49.157378 -309.8473)
			(xy 49.185618 -309.844626) (xy 49.1998 -309.84444) (xy 49.22462 -309.844878) (xy 49.273606 -309.852908)
			(xy 49.320648 -309.868758) (xy 49.364506 -309.892009) (xy 49.404025 -309.922049) (xy 49.438163 -309.958087)
			(xy 49.466022 -309.999172) (xy 49.486867 -310.044224) (xy 49.500149 -310.092054) (xy 49.505518 -310.141403)
			(xy 49.505066 -310.149748) (xy 49.843956 -310.149748) (xy 49.847916 -310.100694) (xy 49.859693 -310.05291)
			(xy 49.878984 -310.007634) (xy 49.905287 -309.966038) (xy 49.937922 -309.929201) (xy 49.976043 -309.898076)
			(xy 50.018664 -309.873469) (xy 50.06468 -309.856017) (xy 50.112899 -309.846173) (xy 50.162074 -309.844192)
			(xy 50.210929 -309.850124) (xy 50.2582 -309.863816) (xy 50.302662 -309.884914) (xy 50.343165 -309.91287)
			(xy 50.378658 -309.946962) (xy 50.408223 -309.986306) (xy 50.431094 -310.029883) (xy 50.446678 -310.076564)
			(xy 50.454573 -310.125141) (xy 50.455068 -310.149748) (xy 50.79417 -310.149748) (xy 50.79813 -310.100694)
			(xy 50.809907 -310.05291) (xy 50.829198 -310.007634) (xy 50.855501 -309.966038) (xy 50.888136 -309.929201)
			(xy 50.926257 -309.898076) (xy 50.968878 -309.873469) (xy 51.014894 -309.856017) (xy 51.063113 -309.846173)
			(xy 51.112288 -309.844192) (xy 51.161143 -309.850124) (xy 51.208414 -309.863816) (xy 51.252876 -309.884914)
			(xy 51.293379 -309.91287) (xy 51.328872 -309.946962) (xy 51.358437 -309.986306) (xy 51.381308 -310.029883)
			(xy 51.396892 -310.076564) (xy 51.404787 -310.125141) (xy 51.405282 -310.149748) (xy 51.74413 -310.149748)
			(xy 51.74809 -310.100694) (xy 51.759867 -310.05291) (xy 51.779158 -310.007634) (xy 51.805461 -309.966038)
			(xy 51.838096 -309.929201) (xy 51.876217 -309.898076) (xy 51.918838 -309.873469) (xy 51.964854 -309.856017)
			(xy 52.013073 -309.846173) (xy 52.062248 -309.844192) (xy 52.111103 -309.850124) (xy 52.158374 -309.863816)
			(xy 52.202836 -309.884914) (xy 52.243339 -309.91287) (xy 52.278832 -309.946962) (xy 52.308397 -309.986306)
			(xy 52.331268 -310.029883) (xy 52.346852 -310.076564) (xy 52.354747 -310.125141) (xy 52.355242 -310.149748)
			(xy 52.69409 -310.149748) (xy 52.69805 -310.100694) (xy 52.709827 -310.05291) (xy 52.729118 -310.007634)
			(xy 52.755421 -309.966038) (xy 52.788056 -309.929201) (xy 52.826177 -309.898076) (xy 52.868798 -309.873469)
			(xy 52.914814 -309.856017) (xy 52.963033 -309.846173) (xy 53.012208 -309.844192) (xy 53.061063 -309.850124)
			(xy 53.108334 -309.863816) (xy 53.152796 -309.884914) (xy 53.193299 -309.91287) (xy 53.228792 -309.946962)
			(xy 53.258357 -309.986306) (xy 53.281228 -310.029883) (xy 53.296812 -310.076564) (xy 53.304707 -310.125141)
			(xy 53.305202 -310.149748) (xy 53.64405 -310.149748) (xy 53.64801 -310.100694) (xy 53.659787 -310.05291)
			(xy 53.679078 -310.007634) (xy 53.705381 -309.966038) (xy 53.738016 -309.929201) (xy 53.776137 -309.898076)
			(xy 53.818758 -309.873469) (xy 53.864774 -309.856017) (xy 53.912993 -309.846173) (xy 53.962168 -309.844192)
			(xy 54.011023 -309.850124) (xy 54.058294 -309.863816) (xy 54.102756 -309.884914) (xy 54.143259 -309.91287)
			(xy 54.178752 -309.946962) (xy 54.208317 -309.986306) (xy 54.231188 -310.029883) (xy 54.246772 -310.076564)
			(xy 54.254667 -310.125141) (xy 54.255162 -310.149748) (xy 54.59401 -310.149748) (xy 54.59797 -310.100694)
			(xy 54.609747 -310.05291) (xy 54.629038 -310.007634) (xy 54.655341 -309.966038) (xy 54.687976 -309.929201)
			(xy 54.726097 -309.898076) (xy 54.768718 -309.873469) (xy 54.814734 -309.856017) (xy 54.862953 -309.846173)
			(xy 54.912128 -309.844192) (xy 54.960983 -309.850124) (xy 55.008254 -309.863816) (xy 55.052716 -309.884914)
			(xy 55.093219 -309.91287) (xy 55.128712 -309.946962) (xy 55.158277 -309.986306) (xy 55.181148 -310.029883)
			(xy 55.196732 -310.076564) (xy 55.204627 -310.125141) (xy 55.205122 -310.149748) (xy 55.54397 -310.149748)
			(xy 55.54793 -310.100694) (xy 55.559707 -310.05291) (xy 55.578998 -310.007634) (xy 55.605301 -309.966038)
			(xy 55.637936 -309.929201) (xy 55.676057 -309.898076) (xy 55.718678 -309.873469) (xy 55.764694 -309.856017)
			(xy 55.812913 -309.846173) (xy 55.862088 -309.844192) (xy 55.910943 -309.850124) (xy 55.958214 -309.863816)
			(xy 56.002676 -309.884914) (xy 56.043179 -309.91287) (xy 56.078672 -309.946962) (xy 56.108237 -309.986306)
			(xy 56.131108 -310.029883) (xy 56.146692 -310.076564) (xy 56.154587 -310.125141) (xy 56.155082 -310.149748)
			(xy 56.494184 -310.149748) (xy 56.498144 -310.100694) (xy 56.509921 -310.05291) (xy 56.529212 -310.007634)
			(xy 56.555515 -309.966038) (xy 56.58815 -309.929201) (xy 56.626271 -309.898076) (xy 56.668892 -309.873469)
			(xy 56.714908 -309.856017) (xy 56.763127 -309.846173) (xy 56.812302 -309.844192) (xy 56.861157 -309.850124)
			(xy 56.908428 -309.863816) (xy 56.95289 -309.884914) (xy 56.993393 -309.91287) (xy 57.028886 -309.946962)
			(xy 57.058451 -309.986306) (xy 57.081322 -310.029883) (xy 57.096906 -310.076564) (xy 57.104801 -310.125141)
			(xy 57.105296 -310.149748) (xy 57.444144 -310.149748) (xy 57.448104 -310.100694) (xy 57.459881 -310.05291)
			(xy 57.479172 -310.007634) (xy 57.505475 -309.966038) (xy 57.53811 -309.929201) (xy 57.576231 -309.898076)
			(xy 57.618852 -309.873469) (xy 57.664868 -309.856017) (xy 57.713087 -309.846173) (xy 57.762262 -309.844192)
			(xy 57.811117 -309.850124) (xy 57.858388 -309.863816) (xy 57.90285 -309.884914) (xy 57.943353 -309.91287)
			(xy 57.978846 -309.946962) (xy 58.008411 -309.986306) (xy 58.031282 -310.029883) (xy 58.046866 -310.076564)
			(xy 58.054761 -310.125141) (xy 58.055256 -310.149748) (xy 58.394104 -310.149748) (xy 58.398064 -310.100694)
			(xy 58.409841 -310.05291) (xy 58.429132 -310.007634) (xy 58.455435 -309.966038) (xy 58.48807 -309.929201)
			(xy 58.526191 -309.898076) (xy 58.568812 -309.873469) (xy 58.614828 -309.856017) (xy 58.663047 -309.846173)
			(xy 58.712222 -309.844192) (xy 58.761077 -309.850124) (xy 58.808348 -309.863816) (xy 58.85281 -309.884914)
			(xy 58.893313 -309.91287) (xy 58.928806 -309.946962) (xy 58.958371 -309.986306) (xy 58.981242 -310.029883)
			(xy 58.996826 -310.076564) (xy 59.004721 -310.125141) (xy 59.005216 -310.149748) (xy 59.344064 -310.149748)
			(xy 59.348024 -310.100694) (xy 59.359801 -310.05291) (xy 59.379092 -310.007634) (xy 59.405395 -309.966038)
			(xy 59.43803 -309.929201) (xy 59.476151 -309.898076) (xy 59.518772 -309.873469) (xy 59.564788 -309.856017)
			(xy 59.613007 -309.846173) (xy 59.662182 -309.844192) (xy 59.711037 -309.850124) (xy 59.758308 -309.863816)
			(xy 59.80277 -309.884914) (xy 59.843273 -309.91287) (xy 59.878766 -309.946962) (xy 59.908331 -309.986306)
			(xy 59.931202 -310.029883) (xy 59.946786 -310.076564) (xy 59.954681 -310.125141) (xy 59.955176 -310.149748)
			(xy 60.294024 -310.149748) (xy 60.297984 -310.100694) (xy 60.309761 -310.05291) (xy 60.329052 -310.007634)
			(xy 60.355355 -309.966038) (xy 60.38799 -309.929201) (xy 60.426111 -309.898076) (xy 60.468732 -309.873469)
			(xy 60.514748 -309.856017) (xy 60.562967 -309.846173) (xy 60.612142 -309.844192) (xy 60.660997 -309.850124)
			(xy 60.708268 -309.863816) (xy 60.75273 -309.884914) (xy 60.793233 -309.91287) (xy 60.828726 -309.946962)
			(xy 60.858291 -309.986306) (xy 60.881162 -310.029883) (xy 60.896746 -310.076564) (xy 60.904641 -310.125141)
			(xy 60.905136 -310.149748) (xy 61.243984 -310.149748) (xy 61.247944 -310.100694) (xy 61.259721 -310.05291)
			(xy 61.279012 -310.007634) (xy 61.305315 -309.966038) (xy 61.33795 -309.929201) (xy 61.376071 -309.898076)
			(xy 61.418692 -309.873469) (xy 61.464708 -309.856017) (xy 61.512927 -309.846173) (xy 61.562102 -309.844192)
			(xy 61.610957 -309.850124) (xy 61.658228 -309.863816) (xy 61.70269 -309.884914) (xy 61.743193 -309.91287)
			(xy 61.778686 -309.946962) (xy 61.808251 -309.986306) (xy 61.831122 -310.029883) (xy 61.846706 -310.076564)
			(xy 61.854601 -310.125141) (xy 61.855096 -310.149748) (xy 62.193944 -310.149748) (xy 62.197904 -310.100694)
			(xy 62.209681 -310.05291) (xy 62.228972 -310.007634) (xy 62.255275 -309.966038) (xy 62.28791 -309.929201)
			(xy 62.326031 -309.898076) (xy 62.368652 -309.873469) (xy 62.414668 -309.856017) (xy 62.462887 -309.846173)
			(xy 62.512062 -309.844192) (xy 62.560917 -309.850124) (xy 62.608188 -309.863816) (xy 62.65265 -309.884914)
			(xy 62.693153 -309.91287) (xy 62.728646 -309.946962) (xy 62.758211 -309.986306) (xy 62.781082 -310.029883)
			(xy 62.796666 -310.076564) (xy 62.804561 -310.125141) (xy 62.805056 -310.149748) (xy 63.144158 -310.149748)
			(xy 63.148118 -310.100694) (xy 63.159895 -310.05291) (xy 63.179186 -310.007634) (xy 63.205489 -309.966038)
			(xy 63.238124 -309.929201) (xy 63.276245 -309.898076) (xy 63.318866 -309.873469) (xy 63.364882 -309.856017)
			(xy 63.413101 -309.846173) (xy 63.462276 -309.844192) (xy 63.511131 -309.850124) (xy 63.558402 -309.863816)
			(xy 63.602864 -309.884914) (xy 63.643367 -309.91287) (xy 63.67886 -309.946962) (xy 63.708425 -309.986306)
			(xy 63.731296 -310.029883) (xy 63.74688 -310.076564) (xy 63.754775 -310.125141) (xy 63.75527 -310.149748)
			(xy 64.094118 -310.149748) (xy 64.098078 -310.100694) (xy 64.109855 -310.05291) (xy 64.129146 -310.007634)
			(xy 64.155449 -309.966038) (xy 64.188084 -309.929201) (xy 64.226205 -309.898076) (xy 64.268826 -309.873469)
			(xy 64.314842 -309.856017) (xy 64.363061 -309.846173) (xy 64.412236 -309.844192) (xy 64.461091 -309.850124)
			(xy 64.508362 -309.863816) (xy 64.552824 -309.884914) (xy 64.593327 -309.91287) (xy 64.62882 -309.946962)
			(xy 64.658385 -309.986306) (xy 64.681256 -310.029883) (xy 64.69684 -310.076564) (xy 64.704735 -310.125141)
			(xy 64.70523 -310.149748) (xy 65.044078 -310.149748) (xy 65.048038 -310.100694) (xy 65.059815 -310.05291)
			(xy 65.079106 -310.007634) (xy 65.105409 -309.966038) (xy 65.138044 -309.929201) (xy 65.176165 -309.898076)
			(xy 65.218786 -309.873469) (xy 65.264802 -309.856017) (xy 65.313021 -309.846173) (xy 65.362196 -309.844192)
			(xy 65.411051 -309.850124) (xy 65.458322 -309.863816) (xy 65.502784 -309.884914) (xy 65.543287 -309.91287)
			(xy 65.57878 -309.946962) (xy 65.608345 -309.986306) (xy 65.631216 -310.029883) (xy 65.6468 -310.076564)
			(xy 65.654695 -310.125141) (xy 65.65519 -310.149748) (xy 65.994038 -310.149748) (xy 65.997998 -310.100694)
			(xy 66.009775 -310.05291) (xy 66.029066 -310.007634) (xy 66.055369 -309.966038) (xy 66.088004 -309.929201)
			(xy 66.126125 -309.898076) (xy 66.168746 -309.873469) (xy 66.214762 -309.856017) (xy 66.262981 -309.846173)
			(xy 66.312156 -309.844192) (xy 66.361011 -309.850124) (xy 66.408282 -309.863816) (xy 66.452744 -309.884914)
			(xy 66.493247 -309.91287) (xy 66.52874 -309.946962) (xy 66.558305 -309.986306) (xy 66.581176 -310.029883)
			(xy 66.59676 -310.076564) (xy 66.604655 -310.125141) (xy 66.60515 -310.149748) (xy 66.943998 -310.149748)
			(xy 66.947958 -310.100694) (xy 66.959735 -310.05291) (xy 66.979026 -310.007634) (xy 67.005329 -309.966038)
			(xy 67.037964 -309.929201) (xy 67.076085 -309.898076) (xy 67.118706 -309.873469) (xy 67.164722 -309.856017)
			(xy 67.212941 -309.846173) (xy 67.262116 -309.844192) (xy 67.310971 -309.850124) (xy 67.358242 -309.863816)
			(xy 67.402704 -309.884914) (xy 67.443207 -309.91287) (xy 67.4787 -309.946962) (xy 67.508265 -309.986306)
			(xy 67.531136 -310.029883) (xy 67.54672 -310.076564) (xy 67.554615 -310.125141) (xy 67.55511 -310.149748)
			(xy 67.893958 -310.149748) (xy 67.897918 -310.100694) (xy 67.909695 -310.05291) (xy 67.928986 -310.007634)
			(xy 67.955289 -309.966038) (xy 67.987924 -309.929201) (xy 68.026045 -309.898076) (xy 68.068666 -309.873469)
			(xy 68.114682 -309.856017) (xy 68.162901 -309.846173) (xy 68.212076 -309.844192) (xy 68.260931 -309.850124)
			(xy 68.308202 -309.863816) (xy 68.352664 -309.884914) (xy 68.393167 -309.91287) (xy 68.42866 -309.946962)
			(xy 68.458225 -309.986306) (xy 68.481096 -310.029883) (xy 68.49668 -310.076564) (xy 68.504575 -310.125141)
			(xy 68.50507 -310.149748) (xy 68.844172 -310.149748) (xy 68.848132 -310.100694) (xy 68.859909 -310.05291)
			(xy 68.8792 -310.007634) (xy 68.905503 -309.966038) (xy 68.938138 -309.929201) (xy 68.976259 -309.898076)
			(xy 69.01888 -309.873469) (xy 69.064896 -309.856017) (xy 69.113115 -309.846173) (xy 69.16229 -309.844192)
			(xy 69.211145 -309.850124) (xy 69.258416 -309.863816) (xy 69.302878 -309.884914) (xy 69.343381 -309.91287)
			(xy 69.378874 -309.946962) (xy 69.408439 -309.986306) (xy 69.43131 -310.029883) (xy 69.446894 -310.076564)
			(xy 69.454789 -310.125141) (xy 69.455284 -310.149748) (xy 69.794132 -310.149748) (xy 69.798092 -310.100694)
			(xy 69.809869 -310.05291) (xy 69.82916 -310.007634) (xy 69.855463 -309.966038) (xy 69.888098 -309.929201)
			(xy 69.926219 -309.898076) (xy 69.96884 -309.873469) (xy 70.014856 -309.856017) (xy 70.063075 -309.846173)
			(xy 70.11225 -309.844192) (xy 70.161105 -309.850124) (xy 70.208376 -309.863816) (xy 70.252838 -309.884914)
			(xy 70.293341 -309.91287) (xy 70.328834 -309.946962) (xy 70.358399 -309.986306) (xy 70.38127 -310.029883)
			(xy 70.396854 -310.076564) (xy 70.404749 -310.125141) (xy 70.405244 -310.149748) (xy 70.744092 -310.149748)
			(xy 70.748052 -310.100694) (xy 70.759829 -310.05291) (xy 70.77912 -310.007634) (xy 70.805423 -309.966038)
			(xy 70.838058 -309.929201) (xy 70.876179 -309.898076) (xy 70.9188 -309.873469) (xy 70.964816 -309.856017)
			(xy 71.013035 -309.846173) (xy 71.06221 -309.844192) (xy 71.111065 -309.850124) (xy 71.158336 -309.863816)
			(xy 71.202798 -309.884914) (xy 71.243301 -309.91287) (xy 71.278794 -309.946962) (xy 71.308359 -309.986306)
			(xy 71.33123 -310.029883) (xy 71.346814 -310.076564) (xy 71.354709 -310.125141) (xy 71.355204 -310.149748)
			(xy 71.354709 -310.174355) (xy 71.346814 -310.222932) (xy 71.33123 -310.269613) (xy 71.308359 -310.31319)
			(xy 71.278794 -310.352534) (xy 71.243301 -310.386626) (xy 71.202798 -310.414582) (xy 71.158336 -310.43568)
			(xy 71.111065 -310.449372) (xy 71.06221 -310.455304) (xy 71.013035 -310.453323) (xy 70.964816 -310.443479)
			(xy 70.9188 -310.426027) (xy 70.876179 -310.40142) (xy 70.838058 -310.370295) (xy 70.805423 -310.333458)
			(xy 70.77912 -310.291862) (xy 70.759829 -310.246586) (xy 70.748052 -310.198802) (xy 70.744092 -310.149748)
			(xy 70.405244 -310.149748) (xy 70.404749 -310.174355) (xy 70.396854 -310.222932) (xy 70.38127 -310.269613)
			(xy 70.358399 -310.31319) (xy 70.328834 -310.352534) (xy 70.293341 -310.386626) (xy 70.252838 -310.414582)
			(xy 70.208376 -310.43568) (xy 70.161105 -310.449372) (xy 70.11225 -310.455304) (xy 70.063075 -310.453323)
			(xy 70.014856 -310.443479) (xy 69.96884 -310.426027) (xy 69.926219 -310.40142) (xy 69.888098 -310.370295)
			(xy 69.855463 -310.333458) (xy 69.82916 -310.291862) (xy 69.809869 -310.246586) (xy 69.798092 -310.198802)
			(xy 69.794132 -310.149748) (xy 69.455284 -310.149748) (xy 69.454789 -310.174355) (xy 69.446894 -310.222932)
			(xy 69.43131 -310.269613) (xy 69.408439 -310.31319) (xy 69.378874 -310.352534) (xy 69.343381 -310.386626)
			(xy 69.302878 -310.414582) (xy 69.258416 -310.43568) (xy 69.211145 -310.449372) (xy 69.16229 -310.455304)
			(xy 69.113115 -310.453323) (xy 69.064896 -310.443479) (xy 69.01888 -310.426027) (xy 68.976259 -310.40142)
			(xy 68.938138 -310.370295) (xy 68.905503 -310.333458) (xy 68.8792 -310.291862) (xy 68.859909 -310.246586)
			(xy 68.848132 -310.198802) (xy 68.844172 -310.149748) (xy 68.50507 -310.149748) (xy 68.504575 -310.174355)
			(xy 68.49668 -310.222932) (xy 68.481096 -310.269613) (xy 68.458225 -310.31319) (xy 68.42866 -310.352534)
			(xy 68.393167 -310.386626) (xy 68.352664 -310.414582) (xy 68.308202 -310.43568) (xy 68.260931 -310.449372)
			(xy 68.212076 -310.455304) (xy 68.162901 -310.453323) (xy 68.114682 -310.443479) (xy 68.068666 -310.426027)
			(xy 68.026045 -310.40142) (xy 67.987924 -310.370295) (xy 67.955289 -310.333458) (xy 67.928986 -310.291862)
			(xy 67.909695 -310.246586) (xy 67.897918 -310.198802) (xy 67.893958 -310.149748) (xy 67.55511 -310.149748)
			(xy 67.554615 -310.174355) (xy 67.54672 -310.222932) (xy 67.531136 -310.269613) (xy 67.508265 -310.31319)
			(xy 67.4787 -310.352534) (xy 67.443207 -310.386626) (xy 67.402704 -310.414582) (xy 67.358242 -310.43568)
			(xy 67.310971 -310.449372) (xy 67.262116 -310.455304) (xy 67.212941 -310.453323) (xy 67.164722 -310.443479)
			(xy 67.118706 -310.426027) (xy 67.076085 -310.40142) (xy 67.037964 -310.370295) (xy 67.005329 -310.333458)
			(xy 66.979026 -310.291862) (xy 66.959735 -310.246586) (xy 66.947958 -310.198802) (xy 66.943998 -310.149748)
			(xy 66.60515 -310.149748) (xy 66.604655 -310.174355) (xy 66.59676 -310.222932) (xy 66.581176 -310.269613)
			(xy 66.558305 -310.31319) (xy 66.52874 -310.352534) (xy 66.493247 -310.386626) (xy 66.452744 -310.414582)
			(xy 66.408282 -310.43568) (xy 66.361011 -310.449372) (xy 66.312156 -310.455304) (xy 66.262981 -310.453323)
			(xy 66.214762 -310.443479) (xy 66.168746 -310.426027) (xy 66.126125 -310.40142) (xy 66.088004 -310.370295)
			(xy 66.055369 -310.333458) (xy 66.029066 -310.291862) (xy 66.009775 -310.246586) (xy 65.997998 -310.198802)
			(xy 65.994038 -310.149748) (xy 65.65519 -310.149748) (xy 65.654695 -310.174355) (xy 65.6468 -310.222932)
			(xy 65.631216 -310.269613) (xy 65.608345 -310.31319) (xy 65.57878 -310.352534) (xy 65.543287 -310.386626)
			(xy 65.502784 -310.414582) (xy 65.458322 -310.43568) (xy 65.411051 -310.449372) (xy 65.362196 -310.455304)
			(xy 65.313021 -310.453323) (xy 65.264802 -310.443479) (xy 65.218786 -310.426027) (xy 65.176165 -310.40142)
			(xy 65.138044 -310.370295) (xy 65.105409 -310.333458) (xy 65.079106 -310.291862) (xy 65.059815 -310.246586)
			(xy 65.048038 -310.198802) (xy 65.044078 -310.149748) (xy 64.70523 -310.149748) (xy 64.704735 -310.174355)
			(xy 64.69684 -310.222932) (xy 64.681256 -310.269613) (xy 64.658385 -310.31319) (xy 64.62882 -310.352534)
			(xy 64.593327 -310.386626) (xy 64.552824 -310.414582) (xy 64.508362 -310.43568) (xy 64.461091 -310.449372)
			(xy 64.412236 -310.455304) (xy 64.363061 -310.453323) (xy 64.314842 -310.443479) (xy 64.268826 -310.426027)
			(xy 64.226205 -310.40142) (xy 64.188084 -310.370295) (xy 64.155449 -310.333458) (xy 64.129146 -310.291862)
			(xy 64.109855 -310.246586) (xy 64.098078 -310.198802) (xy 64.094118 -310.149748) (xy 63.75527 -310.149748)
			(xy 63.754775 -310.174355) (xy 63.74688 -310.222932) (xy 63.731296 -310.269613) (xy 63.708425 -310.31319)
			(xy 63.67886 -310.352534) (xy 63.643367 -310.386626) (xy 63.602864 -310.414582) (xy 63.558402 -310.43568)
			(xy 63.511131 -310.449372) (xy 63.462276 -310.455304) (xy 63.413101 -310.453323) (xy 63.364882 -310.443479)
			(xy 63.318866 -310.426027) (xy 63.276245 -310.40142) (xy 63.238124 -310.370295) (xy 63.205489 -310.333458)
			(xy 63.179186 -310.291862) (xy 63.159895 -310.246586) (xy 63.148118 -310.198802) (xy 63.144158 -310.149748)
			(xy 62.805056 -310.149748) (xy 62.804561 -310.174355) (xy 62.796666 -310.222932) (xy 62.781082 -310.269613)
			(xy 62.758211 -310.31319) (xy 62.728646 -310.352534) (xy 62.693153 -310.386626) (xy 62.65265 -310.414582)
			(xy 62.608188 -310.43568) (xy 62.560917 -310.449372) (xy 62.512062 -310.455304) (xy 62.462887 -310.453323)
			(xy 62.414668 -310.443479) (xy 62.368652 -310.426027) (xy 62.326031 -310.40142) (xy 62.28791 -310.370295)
			(xy 62.255275 -310.333458) (xy 62.228972 -310.291862) (xy 62.209681 -310.246586) (xy 62.197904 -310.198802)
			(xy 62.193944 -310.149748) (xy 61.855096 -310.149748) (xy 61.854601 -310.174355) (xy 61.846706 -310.222932)
			(xy 61.831122 -310.269613) (xy 61.808251 -310.31319) (xy 61.778686 -310.352534) (xy 61.743193 -310.386626)
			(xy 61.70269 -310.414582) (xy 61.658228 -310.43568) (xy 61.610957 -310.449372) (xy 61.562102 -310.455304)
			(xy 61.512927 -310.453323) (xy 61.464708 -310.443479) (xy 61.418692 -310.426027) (xy 61.376071 -310.40142)
			(xy 61.33795 -310.370295) (xy 61.305315 -310.333458) (xy 61.279012 -310.291862) (xy 61.259721 -310.246586)
			(xy 61.247944 -310.198802) (xy 61.243984 -310.149748) (xy 60.905136 -310.149748) (xy 60.904641 -310.174355)
			(xy 60.896746 -310.222932) (xy 60.881162 -310.269613) (xy 60.858291 -310.31319) (xy 60.828726 -310.352534)
			(xy 60.793233 -310.386626) (xy 60.75273 -310.414582) (xy 60.708268 -310.43568) (xy 60.660997 -310.449372)
			(xy 60.612142 -310.455304) (xy 60.562967 -310.453323) (xy 60.514748 -310.443479) (xy 60.468732 -310.426027)
			(xy 60.426111 -310.40142) (xy 60.38799 -310.370295) (xy 60.355355 -310.333458) (xy 60.329052 -310.291862)
			(xy 60.309761 -310.246586) (xy 60.297984 -310.198802) (xy 60.294024 -310.149748) (xy 59.955176 -310.149748)
			(xy 59.954681 -310.174355) (xy 59.946786 -310.222932) (xy 59.931202 -310.269613) (xy 59.908331 -310.31319)
			(xy 59.878766 -310.352534) (xy 59.843273 -310.386626) (xy 59.80277 -310.414582) (xy 59.758308 -310.43568)
			(xy 59.711037 -310.449372) (xy 59.662182 -310.455304) (xy 59.613007 -310.453323) (xy 59.564788 -310.443479)
			(xy 59.518772 -310.426027) (xy 59.476151 -310.40142) (xy 59.43803 -310.370295) (xy 59.405395 -310.333458)
			(xy 59.379092 -310.291862) (xy 59.359801 -310.246586) (xy 59.348024 -310.198802) (xy 59.344064 -310.149748)
			(xy 59.005216 -310.149748) (xy 59.004721 -310.174355) (xy 58.996826 -310.222932) (xy 58.981242 -310.269613)
			(xy 58.958371 -310.31319) (xy 58.928806 -310.352534) (xy 58.893313 -310.386626) (xy 58.85281 -310.414582)
			(xy 58.808348 -310.43568) (xy 58.761077 -310.449372) (xy 58.712222 -310.455304) (xy 58.663047 -310.453323)
			(xy 58.614828 -310.443479) (xy 58.568812 -310.426027) (xy 58.526191 -310.40142) (xy 58.48807 -310.370295)
			(xy 58.455435 -310.333458) (xy 58.429132 -310.291862) (xy 58.409841 -310.246586) (xy 58.398064 -310.198802)
			(xy 58.394104 -310.149748) (xy 58.055256 -310.149748) (xy 58.054761 -310.174355) (xy 58.046866 -310.222932)
			(xy 58.031282 -310.269613) (xy 58.008411 -310.31319) (xy 57.978846 -310.352534) (xy 57.943353 -310.386626)
			(xy 57.90285 -310.414582) (xy 57.858388 -310.43568) (xy 57.811117 -310.449372) (xy 57.762262 -310.455304)
			(xy 57.713087 -310.453323) (xy 57.664868 -310.443479) (xy 57.618852 -310.426027) (xy 57.576231 -310.40142)
			(xy 57.53811 -310.370295) (xy 57.505475 -310.333458) (xy 57.479172 -310.291862) (xy 57.459881 -310.246586)
			(xy 57.448104 -310.198802) (xy 57.444144 -310.149748) (xy 57.105296 -310.149748) (xy 57.104801 -310.174355)
			(xy 57.096906 -310.222932) (xy 57.081322 -310.269613) (xy 57.058451 -310.31319) (xy 57.028886 -310.352534)
			(xy 56.993393 -310.386626) (xy 56.95289 -310.414582) (xy 56.908428 -310.43568) (xy 56.861157 -310.449372)
			(xy 56.812302 -310.455304) (xy 56.763127 -310.453323) (xy 56.714908 -310.443479) (xy 56.668892 -310.426027)
			(xy 56.626271 -310.40142) (xy 56.58815 -310.370295) (xy 56.555515 -310.333458) (xy 56.529212 -310.291862)
			(xy 56.509921 -310.246586) (xy 56.498144 -310.198802) (xy 56.494184 -310.149748) (xy 56.155082 -310.149748)
			(xy 56.154587 -310.174355) (xy 56.146692 -310.222932) (xy 56.131108 -310.269613) (xy 56.108237 -310.31319)
			(xy 56.078672 -310.352534) (xy 56.043179 -310.386626) (xy 56.002676 -310.414582) (xy 55.958214 -310.43568)
			(xy 55.910943 -310.449372) (xy 55.862088 -310.455304) (xy 55.812913 -310.453323) (xy 55.764694 -310.443479)
			(xy 55.718678 -310.426027) (xy 55.676057 -310.40142) (xy 55.637936 -310.370295) (xy 55.605301 -310.333458)
			(xy 55.578998 -310.291862) (xy 55.559707 -310.246586) (xy 55.54793 -310.198802) (xy 55.54397 -310.149748)
			(xy 55.205122 -310.149748) (xy 55.204627 -310.174355) (xy 55.196732 -310.222932) (xy 55.181148 -310.269613)
			(xy 55.158277 -310.31319) (xy 55.128712 -310.352534) (xy 55.093219 -310.386626) (xy 55.052716 -310.414582)
			(xy 55.008254 -310.43568) (xy 54.960983 -310.449372) (xy 54.912128 -310.455304) (xy 54.862953 -310.453323)
			(xy 54.814734 -310.443479) (xy 54.768718 -310.426027) (xy 54.726097 -310.40142) (xy 54.687976 -310.370295)
			(xy 54.655341 -310.333458) (xy 54.629038 -310.291862) (xy 54.609747 -310.246586) (xy 54.59797 -310.198802)
			(xy 54.59401 -310.149748) (xy 54.255162 -310.149748) (xy 54.254667 -310.174355) (xy 54.246772 -310.222932)
			(xy 54.231188 -310.269613) (xy 54.208317 -310.31319) (xy 54.178752 -310.352534) (xy 54.143259 -310.386626)
			(xy 54.102756 -310.414582) (xy 54.058294 -310.43568) (xy 54.011023 -310.449372) (xy 53.962168 -310.455304)
			(xy 53.912993 -310.453323) (xy 53.864774 -310.443479) (xy 53.818758 -310.426027) (xy 53.776137 -310.40142)
			(xy 53.738016 -310.370295) (xy 53.705381 -310.333458) (xy 53.679078 -310.291862) (xy 53.659787 -310.246586)
			(xy 53.64801 -310.198802) (xy 53.64405 -310.149748) (xy 53.305202 -310.149748) (xy 53.304707 -310.174355)
			(xy 53.296812 -310.222932) (xy 53.281228 -310.269613) (xy 53.258357 -310.31319) (xy 53.228792 -310.352534)
			(xy 53.193299 -310.386626) (xy 53.152796 -310.414582) (xy 53.108334 -310.43568) (xy 53.061063 -310.449372)
			(xy 53.012208 -310.455304) (xy 52.963033 -310.453323) (xy 52.914814 -310.443479) (xy 52.868798 -310.426027)
			(xy 52.826177 -310.40142) (xy 52.788056 -310.370295) (xy 52.755421 -310.333458) (xy 52.729118 -310.291862)
			(xy 52.709827 -310.246586) (xy 52.69805 -310.198802) (xy 52.69409 -310.149748) (xy 52.355242 -310.149748)
			(xy 52.354747 -310.174355) (xy 52.346852 -310.222932) (xy 52.331268 -310.269613) (xy 52.308397 -310.31319)
			(xy 52.278832 -310.352534) (xy 52.243339 -310.386626) (xy 52.202836 -310.414582) (xy 52.158374 -310.43568)
			(xy 52.111103 -310.449372) (xy 52.062248 -310.455304) (xy 52.013073 -310.453323) (xy 51.964854 -310.443479)
			(xy 51.918838 -310.426027) (xy 51.876217 -310.40142) (xy 51.838096 -310.370295) (xy 51.805461 -310.333458)
			(xy 51.779158 -310.291862) (xy 51.759867 -310.246586) (xy 51.74809 -310.198802) (xy 51.74413 -310.149748)
			(xy 51.405282 -310.149748) (xy 51.404787 -310.174355) (xy 51.396892 -310.222932) (xy 51.381308 -310.269613)
			(xy 51.358437 -310.31319) (xy 51.328872 -310.352534) (xy 51.293379 -310.386626) (xy 51.252876 -310.414582)
			(xy 51.208414 -310.43568) (xy 51.161143 -310.449372) (xy 51.112288 -310.455304) (xy 51.063113 -310.453323)
			(xy 51.014894 -310.443479) (xy 50.968878 -310.426027) (xy 50.926257 -310.40142) (xy 50.888136 -310.370295)
			(xy 50.855501 -310.333458) (xy 50.829198 -310.291862) (xy 50.809907 -310.246586) (xy 50.79813 -310.198802)
			(xy 50.79417 -310.149748) (xy 50.455068 -310.149748) (xy 50.454573 -310.174355) (xy 50.446678 -310.222932)
			(xy 50.431094 -310.269613) (xy 50.408223 -310.31319) (xy 50.378658 -310.352534) (xy 50.343165 -310.386626)
			(xy 50.302662 -310.414582) (xy 50.2582 -310.43568) (xy 50.210929 -310.449372) (xy 50.162074 -310.455304)
			(xy 50.112899 -310.453323) (xy 50.06468 -310.443479) (xy 50.018664 -310.426027) (xy 49.976043 -310.40142)
			(xy 49.937922 -310.370295) (xy 49.905287 -310.333458) (xy 49.878984 -310.291862) (xy 49.859693 -310.246586)
			(xy 49.847916 -310.198802) (xy 49.843956 -310.149748) (xy 49.505066 -310.149748) (xy 49.502834 -310.19097)
			(xy 49.492165 -310.23945) (xy 49.473795 -310.285566) (xy 49.448206 -310.328102) (xy 49.416072 -310.365938)
			(xy 49.378241 -310.398078) (xy 49.335709 -310.423673) (xy 49.289596 -310.442051) (xy 49.241118 -310.452727)
			(xy 49.191551 -310.45542) (xy 49.142201 -310.450058) (xy 49.094369 -310.436783) (xy 49.049314 -310.415945)
			(xy 49.008224 -310.388093) (xy 48.972181 -310.35396) (xy 48.942135 -310.314446) (xy 48.918877 -310.270592)
			(xy 48.90302 -310.223553) (xy 48.894982 -310.174568) (xy 48.894492 -310.149748) (xy 48.894675 -310.135565)
			(xy 48.897343 -310.107325) (xy 48.899826 -310.09336) (xy 48.902112 -310.080914) (xy 48.894746 -310.057292)
			(xy 48.817276 -309.979822) (xy 48.793654 -309.972456) (xy 48.781208 -309.974742) (xy 48.767241 -309.977213)
			(xy 48.739002 -309.979889) (xy 48.72482 -309.980076) (xy 48.710637 -309.979897) (xy 48.682397 -309.977227)
			(xy 48.668432 -309.974742) (xy 48.655986 -309.972456) (xy 48.632364 -309.979822) (xy 48.554894 -310.057292)
			(xy 48.547528 -310.080914) (xy 48.549814 -310.09336) (xy 48.552295 -310.107325) (xy 48.554964 -310.135565)
			(xy 48.555148 -310.149748) (xy 48.55457 -310.174565) (xy 48.546533 -310.223543) (xy 48.530677 -310.270576)
			(xy 48.507422 -310.314425) (xy 48.477379 -310.353933) (xy 48.44134 -310.388061) (xy 48.400254 -310.415908)
			(xy 48.355205 -310.436742) (xy 48.307378 -310.450013) (xy 48.258035 -310.455372) (xy 48.208475 -310.452678)
			(xy 48.160003 -310.442001) (xy 48.113897 -310.423623) (xy 48.071372 -310.398028) (xy 48.033548 -310.36589)
			(xy 48.001421 -310.328057) (xy 47.975838 -310.285524) (xy 47.957473 -310.239413) (xy 47.94681 -310.190938)
			(xy 47.94413 -310.141377) (xy 47.949503 -310.092035) (xy 47.962789 -310.044212) (xy 47.983635 -309.999169)
			(xy 48.011495 -309.958091) (xy 48.045633 -309.922062) (xy 48.08515 -309.892031) (xy 48.129005 -309.868788)
			(xy 48.176042 -309.852946) (xy 48.225023 -309.844922) (xy 48.24984 -309.84444) (xy 48.264023 -309.84461)
			(xy 48.292263 -309.847287) (xy 48.306228 -309.849774) (xy 48.318674 -309.85206) (xy 48.342296 -309.844694)
			(xy 48.419766 -309.767224) (xy 48.427132 -309.743602) (xy 48.424846 -309.731156) (xy 48.422368 -309.71719)
			(xy 48.419697 -309.688951) (xy 48.419512 -309.674768) (xy 48.419684 -309.660585) (xy 48.422359 -309.632345)
			(xy 48.424846 -309.61838) (xy 48.427132 -309.605934) (xy 48.419766 -309.582312) (xy 48.342296 -309.504842)
			(xy 48.318674 -309.497476) (xy 48.306228 -309.499762) (xy 48.292263 -309.502244) (xy 48.264023 -309.504912)
			(xy 48.24984 -309.505096) (xy 48.225015 -309.504665) (xy 48.176019 -309.496639) (xy 48.128967 -309.480792)
			(xy 48.085099 -309.457541) (xy 48.04557 -309.427499) (xy 48.011422 -309.391458) (xy 47.983555 -309.350367)
			(xy 47.962703 -309.305309) (xy 47.949415 -309.257471) (xy 47.944042 -309.208114) (xy 47.605021 -309.208114)
			(xy 47.604693 -309.224395) (xy 47.596798 -309.272972) (xy 47.581214 -309.319653) (xy 47.558343 -309.36323)
			(xy 47.528778 -309.402574) (xy 47.493285 -309.436666) (xy 47.452782 -309.464622) (xy 47.40832 -309.48572)
			(xy 47.361049 -309.499412) (xy 47.312194 -309.505344) (xy 47.263019 -309.503363) (xy 47.2148 -309.493519)
			(xy 47.168784 -309.476067) (xy 47.126163 -309.45146) (xy 47.088042 -309.420335) (xy 47.055407 -309.383498)
			(xy 47.029104 -309.341902) (xy 47.009813 -309.296626) (xy 46.998036 -309.248842) (xy 46.994076 -309.199788)
			(xy 46.655228 -309.199788) (xy 46.654733 -309.224395) (xy 46.646838 -309.272972) (xy 46.631254 -309.319653)
			(xy 46.608383 -309.36323) (xy 46.578818 -309.402574) (xy 46.543325 -309.436666) (xy 46.502822 -309.464622)
			(xy 46.45836 -309.48572) (xy 46.411089 -309.499412) (xy 46.362234 -309.505344) (xy 46.313059 -309.503363)
			(xy 46.26484 -309.493519) (xy 46.218824 -309.476067) (xy 46.176203 -309.45146) (xy 46.138082 -309.420335)
			(xy 46.105447 -309.383498) (xy 46.079144 -309.341902) (xy 46.059853 -309.296626) (xy 46.048076 -309.248842)
			(xy 46.044116 -309.199788) (xy 45.705268 -309.199788) (xy 45.704773 -309.224395) (xy 45.696878 -309.272972)
			(xy 45.681294 -309.319653) (xy 45.658423 -309.36323) (xy 45.628858 -309.402574) (xy 45.593365 -309.436666)
			(xy 45.552862 -309.464622) (xy 45.5084 -309.48572) (xy 45.461129 -309.499412) (xy 45.412274 -309.505344)
			(xy 45.363099 -309.503363) (xy 45.31488 -309.493519) (xy 45.268864 -309.476067) (xy 45.226243 -309.45146)
			(xy 45.188122 -309.420335) (xy 45.155487 -309.383498) (xy 45.129184 -309.341902) (xy 45.109893 -309.296626)
			(xy 45.098116 -309.248842) (xy 45.094156 -309.199788) (xy 44.755054 -309.199788) (xy 44.754559 -309.224395)
			(xy 44.746664 -309.272972) (xy 44.73108 -309.319653) (xy 44.708209 -309.36323) (xy 44.678644 -309.402574)
			(xy 44.643151 -309.436666) (xy 44.602648 -309.464622) (xy 44.558186 -309.48572) (xy 44.510915 -309.499412)
			(xy 44.46206 -309.505344) (xy 44.412885 -309.503363) (xy 44.364666 -309.493519) (xy 44.31865 -309.476067)
			(xy 44.276029 -309.45146) (xy 44.237908 -309.420335) (xy 44.205273 -309.383498) (xy 44.17897 -309.341902)
			(xy 44.159679 -309.296626) (xy 44.147902 -309.248842) (xy 44.143942 -309.199788) (xy 43.805094 -309.199788)
			(xy 43.804599 -309.224395) (xy 43.796704 -309.272972) (xy 43.78112 -309.319653) (xy 43.758249 -309.36323)
			(xy 43.728684 -309.402574) (xy 43.693191 -309.436666) (xy 43.652688 -309.464622) (xy 43.608226 -309.48572)
			(xy 43.560955 -309.499412) (xy 43.5121 -309.505344) (xy 43.462925 -309.503363) (xy 43.414706 -309.493519)
			(xy 43.36869 -309.476067) (xy 43.326069 -309.45146) (xy 43.287948 -309.420335) (xy 43.255313 -309.383498)
			(xy 43.22901 -309.341902) (xy 43.209719 -309.296626) (xy 43.197942 -309.248842) (xy 43.193982 -309.199788)
			(xy 42.876978 -309.199788) (xy 42.876474 -309.225496) (xy 42.868431 -309.276278) (xy 42.852543 -309.325177)
			(xy 42.8292 -309.370989) (xy 42.798979 -309.412585) (xy 42.762623 -309.448941) (xy 42.721027 -309.479162)
			(xy 42.675215 -309.502505) (xy 42.626316 -309.518393) (xy 42.575534 -309.526436) (xy 42.524118 -309.526436)
			(xy 42.473336 -309.518393) (xy 42.424437 -309.502505) (xy 42.378625 -309.479162) (xy 42.337029 -309.448941)
			(xy 42.300673 -309.412585) (xy 42.270452 -309.370989) (xy 42.247109 -309.325177) (xy 42.231221 -309.276278)
			(xy 42.223178 -309.225496) (xy 41.926514 -309.225496) (xy 41.918471 -309.276278) (xy 41.902583 -309.325177)
			(xy 41.87924 -309.370989) (xy 41.849019 -309.412585) (xy 41.812663 -309.448941) (xy 41.771067 -309.479162)
			(xy 41.725255 -309.502505) (xy 41.676356 -309.518393) (xy 41.625574 -309.526436) (xy 41.574158 -309.526436)
			(xy 41.523376 -309.518393) (xy 41.474477 -309.502505) (xy 41.428665 -309.479162) (xy 41.387069 -309.448941)
			(xy 41.350713 -309.412585) (xy 41.320492 -309.370989) (xy 41.297149 -309.325177) (xy 41.281261 -309.276278)
			(xy 41.273218 -309.225496) (xy 40.95454 -309.225496) (xy 40.946824 -309.272972) (xy 40.93124 -309.319653)
			(xy 40.908369 -309.36323) (xy 40.878804 -309.402574) (xy 40.843311 -309.436666) (xy 40.802808 -309.464622)
			(xy 40.758346 -309.48572) (xy 40.711075 -309.499412) (xy 40.66222 -309.505344) (xy 40.613045 -309.503363)
			(xy 40.564826 -309.493519) (xy 40.51881 -309.476067) (xy 40.476189 -309.45146) (xy 40.438068 -309.420335)
			(xy 40.405433 -309.383498) (xy 40.37913 -309.341902) (xy 40.359839 -309.296626) (xy 40.348062 -309.248842)
			(xy 40.344102 -309.199788) (xy 40.027098 -309.199788) (xy 40.026594 -309.225496) (xy 40.018551 -309.276278)
			(xy 40.002663 -309.325177) (xy 39.97932 -309.370989) (xy 39.949099 -309.412585) (xy 39.912743 -309.448941)
			(xy 39.871147 -309.479162) (xy 39.825335 -309.502505) (xy 39.776436 -309.518393) (xy 39.725654 -309.526436)
			(xy 39.674238 -309.526436) (xy 39.623456 -309.518393) (xy 39.574557 -309.502505) (xy 39.528745 -309.479162)
			(xy 39.487149 -309.448941) (xy 39.450793 -309.412585) (xy 39.420572 -309.370989) (xy 39.397229 -309.325177)
			(xy 39.381341 -309.276278) (xy 39.373298 -309.225496) (xy 39.076634 -309.225496) (xy 39.068591 -309.276278)
			(xy 39.052703 -309.325177) (xy 39.02936 -309.370989) (xy 38.999139 -309.412585) (xy 38.962783 -309.448941)
			(xy 38.921187 -309.479162) (xy 38.875375 -309.502505) (xy 38.826476 -309.518393) (xy 38.775694 -309.526436)
			(xy 38.724278 -309.526436) (xy 38.673496 -309.518393) (xy 38.624597 -309.502505) (xy 38.578785 -309.479162)
			(xy 38.537189 -309.448941) (xy 38.500833 -309.412585) (xy 38.470612 -309.370989) (xy 38.447269 -309.325177)
			(xy 38.431381 -309.276278) (xy 38.423338 -309.225496) (xy 38.104406 -309.225496) (xy 38.09669 -309.272972)
			(xy 38.081106 -309.319653) (xy 38.058235 -309.36323) (xy 38.02867 -309.402574) (xy 37.993177 -309.436666)
			(xy 37.952674 -309.464622) (xy 37.908212 -309.48572) (xy 37.860941 -309.499412) (xy 37.812086 -309.505344)
			(xy 37.762911 -309.503363) (xy 37.714692 -309.493519) (xy 37.668676 -309.476067) (xy 37.626055 -309.45146)
			(xy 37.587934 -309.420335) (xy 37.555299 -309.383498) (xy 37.528996 -309.341902) (xy 37.509705 -309.296626)
			(xy 37.497928 -309.248842) (xy 37.493968 -309.199788) (xy 37.15512 -309.199788) (xy 37.154625 -309.224395)
			(xy 37.14673 -309.272972) (xy 37.131146 -309.319653) (xy 37.108275 -309.36323) (xy 37.07871 -309.402574)
			(xy 37.043217 -309.436666) (xy 37.002714 -309.464622) (xy 36.958252 -309.48572) (xy 36.910981 -309.499412)
			(xy 36.862126 -309.505344) (xy 36.812951 -309.503363) (xy 36.764732 -309.493519) (xy 36.718716 -309.476067)
			(xy 36.676095 -309.45146) (xy 36.637974 -309.420335) (xy 36.605339 -309.383498) (xy 36.579036 -309.341902)
			(xy 36.559745 -309.296626) (xy 36.547968 -309.248842) (xy 36.544008 -309.199788) (xy 27.696462 -309.199788)
			(xy 27.715101 -309.22796) (xy 27.738773 -309.278457) (xy 27.754841 -309.331864) (xy 27.762961 -309.38704)
			(xy 27.76347 -309.414926) (xy 27.762961 -309.442812) (xy 27.754841 -309.497988) (xy 27.738773 -309.551395)
			(xy 27.715101 -309.601892) (xy 27.684328 -309.648405) (xy 27.647111 -309.689942) (xy 27.604243 -309.725617)
			(xy 27.556637 -309.754671) (xy 27.505308 -309.776483) (xy 27.451351 -309.790589) (xy 27.395914 -309.796689)
			(xy 27.34018 -309.794652) (xy 27.285337 -309.784522) (xy 27.232553 -309.766515) (xy 27.182953 -309.741014)
			(xy 27.137595 -309.708563) (xy 27.097446 -309.669854) (xy 27.06336 -309.625711) (xy 27.036064 -309.577076)
			(xy 27.016141 -309.524985) (xy 27.004015 -309.470548) (xy 26.999944 -309.414926) (xy 17.635982 -309.414926)
			(xy 17.635982 -310.237378) (xy 34.10077 -310.237378) (xy 34.101256 -310.210127) (xy 34.109012 -310.156179)
			(xy 34.124367 -310.103884) (xy 34.147009 -310.054307) (xy 34.176475 -310.008457) (xy 34.212166 -309.967266)
			(xy 34.253357 -309.931575) (xy 34.299207 -309.902109) (xy 34.348784 -309.879467) (xy 34.401079 -309.864112)
			(xy 34.455027 -309.856356) (xy 34.509529 -309.856356) (xy 34.563477 -309.864112) (xy 34.615772 -309.879467)
			(xy 34.665349 -309.902109) (xy 34.711199 -309.931575) (xy 34.75239 -309.967266) (xy 34.788081 -310.008457)
			(xy 34.817547 -310.054307) (xy 34.840189 -310.103884) (xy 34.85373 -310.150002) (xy 35.593794 -310.150002)
			(xy 35.597754 -310.100948) (xy 35.609531 -310.053164) (xy 35.628822 -310.007888) (xy 35.655125 -309.966292)
			(xy 35.68776 -309.929455) (xy 35.725881 -309.89833) (xy 35.768502 -309.873723) (xy 35.814518 -309.856271)
			(xy 35.862737 -309.846427) (xy 35.911912 -309.844446) (xy 35.960767 -309.850378) (xy 36.008038 -309.86407)
			(xy 36.0525 -309.885168) (xy 36.093003 -309.913124) (xy 36.128496 -309.947216) (xy 36.158061 -309.98656)
			(xy 36.180932 -310.030137) (xy 36.196516 -310.076818) (xy 36.204411 -310.125395) (xy 36.204906 -310.150002)
			(xy 36.204411 -310.174609) (xy 36.204273 -310.175456) (xy 36.523164 -310.175456) (xy 36.523164 -310.12404)
			(xy 36.531207 -310.073258) (xy 36.547095 -310.024359) (xy 36.570438 -309.978547) (xy 36.600659 -309.936951)
			(xy 36.637015 -309.900595) (xy 36.678611 -309.870374) (xy 36.724423 -309.847031) (xy 36.773322 -309.831143)
			(xy 36.824104 -309.8231) (xy 36.87552 -309.8231) (xy 36.926302 -309.831143) (xy 36.975201 -309.847031)
			(xy 37.021013 -309.870374) (xy 37.062609 -309.900595) (xy 37.098965 -309.936951) (xy 37.129186 -309.978547)
			(xy 37.152529 -310.024359) (xy 37.168417 -310.073258) (xy 37.17646 -310.12404) (xy 37.176964 -310.149748)
			(xy 37.17646 -310.175456) (xy 37.473124 -310.175456) (xy 37.473124 -310.12404) (xy 37.481167 -310.073258)
			(xy 37.497055 -310.024359) (xy 37.520398 -309.978547) (xy 37.550619 -309.936951) (xy 37.586975 -309.900595)
			(xy 37.628571 -309.870374) (xy 37.674383 -309.847031) (xy 37.723282 -309.831143) (xy 37.774064 -309.8231)
			(xy 37.82548 -309.8231) (xy 37.876262 -309.831143) (xy 37.925161 -309.847031) (xy 37.970973 -309.870374)
			(xy 38.012569 -309.900595) (xy 38.048925 -309.936951) (xy 38.079146 -309.978547) (xy 38.102489 -310.024359)
			(xy 38.118377 -310.073258) (xy 38.12642 -310.12404) (xy 38.126924 -310.149748) (xy 38.444182 -310.149748)
			(xy 38.448142 -310.100694) (xy 38.459919 -310.05291) (xy 38.47921 -310.007634) (xy 38.505513 -309.966038)
			(xy 38.538148 -309.929201) (xy 38.576269 -309.898076) (xy 38.61889 -309.873469) (xy 38.664906 -309.856017)
			(xy 38.713125 -309.846173) (xy 38.7623 -309.844192) (xy 38.811155 -309.850124) (xy 38.858426 -309.863816)
			(xy 38.902888 -309.884914) (xy 38.943391 -309.91287) (xy 38.978884 -309.946962) (xy 39.008449 -309.986306)
			(xy 39.03132 -310.029883) (xy 39.046904 -310.076564) (xy 39.054799 -310.125141) (xy 39.055294 -310.149748)
			(xy 39.394142 -310.149748) (xy 39.398102 -310.100694) (xy 39.409879 -310.05291) (xy 39.42917 -310.007634)
			(xy 39.455473 -309.966038) (xy 39.488108 -309.929201) (xy 39.526229 -309.898076) (xy 39.56885 -309.873469)
			(xy 39.614866 -309.856017) (xy 39.663085 -309.846173) (xy 39.71226 -309.844192) (xy 39.761115 -309.850124)
			(xy 39.808386 -309.863816) (xy 39.852848 -309.884914) (xy 39.893351 -309.91287) (xy 39.928844 -309.946962)
			(xy 39.958409 -309.986306) (xy 39.98128 -310.029883) (xy 39.996864 -310.076564) (xy 40.004759 -310.125141)
			(xy 40.005254 -310.149748) (xy 40.344102 -310.149748) (xy 40.348062 -310.100694) (xy 40.359839 -310.05291)
			(xy 40.37913 -310.007634) (xy 40.405433 -309.966038) (xy 40.438068 -309.929201) (xy 40.476189 -309.898076)
			(xy 40.51881 -309.873469) (xy 40.564826 -309.856017) (xy 40.613045 -309.846173) (xy 40.66222 -309.844192)
			(xy 40.711075 -309.850124) (xy 40.758346 -309.863816) (xy 40.802808 -309.884914) (xy 40.843311 -309.91287)
			(xy 40.878804 -309.946962) (xy 40.908369 -309.986306) (xy 40.93124 -310.029883) (xy 40.946824 -310.076564)
			(xy 40.954719 -310.125141) (xy 40.955214 -310.149748) (xy 41.294062 -310.149748) (xy 41.298022 -310.100694)
			(xy 41.309799 -310.05291) (xy 41.32909 -310.007634) (xy 41.355393 -309.966038) (xy 41.388028 -309.929201)
			(xy 41.426149 -309.898076) (xy 41.46877 -309.873469) (xy 41.514786 -309.856017) (xy 41.563005 -309.846173)
			(xy 41.61218 -309.844192) (xy 41.661035 -309.850124) (xy 41.708306 -309.863816) (xy 41.752768 -309.884914)
			(xy 41.793271 -309.91287) (xy 41.828764 -309.946962) (xy 41.858329 -309.986306) (xy 41.8812 -310.029883)
			(xy 41.896784 -310.076564) (xy 41.904679 -310.125141) (xy 41.905174 -310.149748) (xy 42.244022 -310.149748)
			(xy 42.247982 -310.100694) (xy 42.259759 -310.05291) (xy 42.27905 -310.007634) (xy 42.305353 -309.966038)
			(xy 42.337988 -309.929201) (xy 42.376109 -309.898076) (xy 42.41873 -309.873469) (xy 42.464746 -309.856017)
			(xy 42.512965 -309.846173) (xy 42.56214 -309.844192) (xy 42.610995 -309.850124) (xy 42.658266 -309.863816)
			(xy 42.702728 -309.884914) (xy 42.743231 -309.91287) (xy 42.778724 -309.946962) (xy 42.808289 -309.986306)
			(xy 42.83116 -310.029883) (xy 42.846744 -310.076564) (xy 42.854639 -310.125141) (xy 42.855134 -310.149748)
			(xy 43.193982 -310.149748) (xy 43.197942 -310.100694) (xy 43.209719 -310.05291) (xy 43.22901 -310.007634)
			(xy 43.255313 -309.966038) (xy 43.287948 -309.929201) (xy 43.326069 -309.898076) (xy 43.36869 -309.873469)
			(xy 43.414706 -309.856017) (xy 43.462925 -309.846173) (xy 43.5121 -309.844192) (xy 43.560955 -309.850124)
			(xy 43.608226 -309.863816) (xy 43.652688 -309.884914) (xy 43.693191 -309.91287) (xy 43.728684 -309.946962)
			(xy 43.758249 -309.986306) (xy 43.78112 -310.029883) (xy 43.796704 -310.076564) (xy 43.804599 -310.125141)
			(xy 43.805094 -310.149748) (xy 44.143942 -310.149748) (xy 44.147902 -310.100694) (xy 44.159679 -310.05291)
			(xy 44.17897 -310.007634) (xy 44.205273 -309.966038) (xy 44.237908 -309.929201) (xy 44.276029 -309.898076)
			(xy 44.31865 -309.873469) (xy 44.364666 -309.856017) (xy 44.412885 -309.846173) (xy 44.46206 -309.844192)
			(xy 44.510915 -309.850124) (xy 44.558186 -309.863816) (xy 44.602648 -309.884914) (xy 44.643151 -309.91287)
			(xy 44.678644 -309.946962) (xy 44.708209 -309.986306) (xy 44.73108 -310.029883) (xy 44.746664 -310.076564)
			(xy 44.754559 -310.125141) (xy 44.755054 -310.149748) (xy 45.094156 -310.149748) (xy 45.098116 -310.100694)
			(xy 45.109893 -310.05291) (xy 45.129184 -310.007634) (xy 45.155487 -309.966038) (xy 45.188122 -309.929201)
			(xy 45.226243 -309.898076) (xy 45.268864 -309.873469) (xy 45.31488 -309.856017) (xy 45.363099 -309.846173)
			(xy 45.412274 -309.844192) (xy 45.461129 -309.850124) (xy 45.5084 -309.863816) (xy 45.552862 -309.884914)
			(xy 45.593365 -309.91287) (xy 45.628858 -309.946962) (xy 45.658423 -309.986306) (xy 45.681294 -310.029883)
			(xy 45.696878 -310.076564) (xy 45.704773 -310.125141) (xy 45.705268 -310.149748) (xy 46.044116 -310.149748)
			(xy 46.048076 -310.100694) (xy 46.059853 -310.05291) (xy 46.079144 -310.007634) (xy 46.105447 -309.966038)
			(xy 46.138082 -309.929201) (xy 46.176203 -309.898076) (xy 46.218824 -309.873469) (xy 46.26484 -309.856017)
			(xy 46.313059 -309.846173) (xy 46.362234 -309.844192) (xy 46.411089 -309.850124) (xy 46.45836 -309.863816)
			(xy 46.502822 -309.884914) (xy 46.543325 -309.91287) (xy 46.578818 -309.946962) (xy 46.608383 -309.986306)
			(xy 46.631254 -310.029883) (xy 46.646838 -310.076564) (xy 46.654733 -310.125141) (xy 46.655228 -310.149748)
			(xy 46.994076 -310.149748) (xy 46.998036 -310.100694) (xy 47.009813 -310.05291) (xy 47.029104 -310.007634)
			(xy 47.055407 -309.966038) (xy 47.088042 -309.929201) (xy 47.126163 -309.898076) (xy 47.168784 -309.873469)
			(xy 47.2148 -309.856017) (xy 47.263019 -309.846173) (xy 47.312194 -309.844192) (xy 47.361049 -309.850124)
			(xy 47.40832 -309.863816) (xy 47.452782 -309.884914) (xy 47.493285 -309.91287) (xy 47.528778 -309.946962)
			(xy 47.558343 -309.986306) (xy 47.581214 -310.029883) (xy 47.596798 -310.076564) (xy 47.604693 -310.125141)
			(xy 47.605188 -310.149748) (xy 47.604693 -310.174355) (xy 47.596798 -310.222932) (xy 47.581214 -310.269613)
			(xy 47.558343 -310.31319) (xy 47.528778 -310.352534) (xy 47.493285 -310.386626) (xy 47.452782 -310.414582)
			(xy 47.40832 -310.43568) (xy 47.361049 -310.449372) (xy 47.312194 -310.455304) (xy 47.263019 -310.453323)
			(xy 47.2148 -310.443479) (xy 47.168784 -310.426027) (xy 47.126163 -310.40142) (xy 47.088042 -310.370295)
			(xy 47.055407 -310.333458) (xy 47.029104 -310.291862) (xy 47.009813 -310.246586) (xy 46.998036 -310.198802)
			(xy 46.994076 -310.149748) (xy 46.655228 -310.149748) (xy 46.654733 -310.174355) (xy 46.646838 -310.222932)
			(xy 46.631254 -310.269613) (xy 46.608383 -310.31319) (xy 46.578818 -310.352534) (xy 46.543325 -310.386626)
			(xy 46.502822 -310.414582) (xy 46.45836 -310.43568) (xy 46.411089 -310.449372) (xy 46.362234 -310.455304)
			(xy 46.313059 -310.453323) (xy 46.26484 -310.443479) (xy 46.218824 -310.426027) (xy 46.176203 -310.40142)
			(xy 46.138082 -310.370295) (xy 46.105447 -310.333458) (xy 46.079144 -310.291862) (xy 46.059853 -310.246586)
			(xy 46.048076 -310.198802) (xy 46.044116 -310.149748) (xy 45.705268 -310.149748) (xy 45.704773 -310.174355)
			(xy 45.696878 -310.222932) (xy 45.681294 -310.269613) (xy 45.658423 -310.31319) (xy 45.628858 -310.352534)
			(xy 45.593365 -310.386626) (xy 45.552862 -310.414582) (xy 45.5084 -310.43568) (xy 45.461129 -310.449372)
			(xy 45.412274 -310.455304) (xy 45.363099 -310.453323) (xy 45.31488 -310.443479) (xy 45.268864 -310.426027)
			(xy 45.226243 -310.40142) (xy 45.188122 -310.370295) (xy 45.155487 -310.333458) (xy 45.129184 -310.291862)
			(xy 45.109893 -310.246586) (xy 45.098116 -310.198802) (xy 45.094156 -310.149748) (xy 44.755054 -310.149748)
			(xy 44.754559 -310.174355) (xy 44.746664 -310.222932) (xy 44.73108 -310.269613) (xy 44.708209 -310.31319)
			(xy 44.678644 -310.352534) (xy 44.643151 -310.386626) (xy 44.602648 -310.414582) (xy 44.558186 -310.43568)
			(xy 44.510915 -310.449372) (xy 44.46206 -310.455304) (xy 44.412885 -310.453323) (xy 44.364666 -310.443479)
			(xy 44.31865 -310.426027) (xy 44.276029 -310.40142) (xy 44.237908 -310.370295) (xy 44.205273 -310.333458)
			(xy 44.17897 -310.291862) (xy 44.159679 -310.246586) (xy 44.147902 -310.198802) (xy 44.143942 -310.149748)
			(xy 43.805094 -310.149748) (xy 43.804599 -310.174355) (xy 43.796704 -310.222932) (xy 43.78112 -310.269613)
			(xy 43.758249 -310.31319) (xy 43.728684 -310.352534) (xy 43.693191 -310.386626) (xy 43.652688 -310.414582)
			(xy 43.608226 -310.43568) (xy 43.560955 -310.449372) (xy 43.5121 -310.455304) (xy 43.462925 -310.453323)
			(xy 43.414706 -310.443479) (xy 43.36869 -310.426027) (xy 43.326069 -310.40142) (xy 43.287948 -310.370295)
			(xy 43.255313 -310.333458) (xy 43.22901 -310.291862) (xy 43.209719 -310.246586) (xy 43.197942 -310.198802)
			(xy 43.193982 -310.149748) (xy 42.855134 -310.149748) (xy 42.854639 -310.174355) (xy 42.846744 -310.222932)
			(xy 42.83116 -310.269613) (xy 42.808289 -310.31319) (xy 42.778724 -310.352534) (xy 42.743231 -310.386626)
			(xy 42.702728 -310.414582) (xy 42.658266 -310.43568) (xy 42.610995 -310.449372) (xy 42.56214 -310.455304)
			(xy 42.512965 -310.453323) (xy 42.464746 -310.443479) (xy 42.41873 -310.426027) (xy 42.376109 -310.40142)
			(xy 42.337988 -310.370295) (xy 42.305353 -310.333458) (xy 42.27905 -310.291862) (xy 42.259759 -310.246586)
			(xy 42.247982 -310.198802) (xy 42.244022 -310.149748) (xy 41.905174 -310.149748) (xy 41.904679 -310.174355)
			(xy 41.896784 -310.222932) (xy 41.8812 -310.269613) (xy 41.858329 -310.31319) (xy 41.828764 -310.352534)
			(xy 41.793271 -310.386626) (xy 41.752768 -310.414582) (xy 41.708306 -310.43568) (xy 41.661035 -310.449372)
			(xy 41.61218 -310.455304) (xy 41.563005 -310.453323) (xy 41.514786 -310.443479) (xy 41.46877 -310.426027)
			(xy 41.426149 -310.40142) (xy 41.388028 -310.370295) (xy 41.355393 -310.333458) (xy 41.32909 -310.291862)
			(xy 41.309799 -310.246586) (xy 41.298022 -310.198802) (xy 41.294062 -310.149748) (xy 40.955214 -310.149748)
			(xy 40.954719 -310.174355) (xy 40.946824 -310.222932) (xy 40.93124 -310.269613) (xy 40.908369 -310.31319)
			(xy 40.878804 -310.352534) (xy 40.843311 -310.386626) (xy 40.802808 -310.414582) (xy 40.758346 -310.43568)
			(xy 40.711075 -310.449372) (xy 40.66222 -310.455304) (xy 40.613045 -310.453323) (xy 40.564826 -310.443479)
			(xy 40.51881 -310.426027) (xy 40.476189 -310.40142) (xy 40.438068 -310.370295) (xy 40.405433 -310.333458)
			(xy 40.37913 -310.291862) (xy 40.359839 -310.246586) (xy 40.348062 -310.198802) (xy 40.344102 -310.149748)
			(xy 40.005254 -310.149748) (xy 40.004759 -310.174355) (xy 39.996864 -310.222932) (xy 39.98128 -310.269613)
			(xy 39.958409 -310.31319) (xy 39.928844 -310.352534) (xy 39.893351 -310.386626) (xy 39.852848 -310.414582)
			(xy 39.808386 -310.43568) (xy 39.761115 -310.449372) (xy 39.71226 -310.455304) (xy 39.663085 -310.453323)
			(xy 39.614866 -310.443479) (xy 39.56885 -310.426027) (xy 39.526229 -310.40142) (xy 39.488108 -310.370295)
			(xy 39.455473 -310.333458) (xy 39.42917 -310.291862) (xy 39.409879 -310.246586) (xy 39.398102 -310.198802)
			(xy 39.394142 -310.149748) (xy 39.055294 -310.149748) (xy 39.054799 -310.174355) (xy 39.046904 -310.222932)
			(xy 39.03132 -310.269613) (xy 39.008449 -310.31319) (xy 38.978884 -310.352534) (xy 38.943391 -310.386626)
			(xy 38.902888 -310.414582) (xy 38.858426 -310.43568) (xy 38.811155 -310.449372) (xy 38.7623 -310.455304)
			(xy 38.713125 -310.453323) (xy 38.664906 -310.443479) (xy 38.61889 -310.426027) (xy 38.576269 -310.40142)
			(xy 38.538148 -310.370295) (xy 38.505513 -310.333458) (xy 38.47921 -310.291862) (xy 38.459919 -310.246586)
			(xy 38.448142 -310.198802) (xy 38.444182 -310.149748) (xy 38.126924 -310.149748) (xy 38.12642 -310.175456)
			(xy 38.118377 -310.226238) (xy 38.102489 -310.275137) (xy 38.079146 -310.320949) (xy 38.048925 -310.362545)
			(xy 38.012569 -310.398901) (xy 37.970973 -310.429122) (xy 37.925161 -310.452465) (xy 37.876262 -310.468353)
			(xy 37.82548 -310.476396) (xy 37.774064 -310.476396) (xy 37.723282 -310.468353) (xy 37.674383 -310.452465)
			(xy 37.628571 -310.429122) (xy 37.586975 -310.398901) (xy 37.550619 -310.362545) (xy 37.520398 -310.320949)
			(xy 37.497055 -310.275137) (xy 37.481167 -310.226238) (xy 37.473124 -310.175456) (xy 37.17646 -310.175456)
			(xy 37.168417 -310.226238) (xy 37.152529 -310.275137) (xy 37.129186 -310.320949) (xy 37.098965 -310.362545)
			(xy 37.062609 -310.398901) (xy 37.021013 -310.429122) (xy 36.975201 -310.452465) (xy 36.926302 -310.468353)
			(xy 36.87552 -310.476396) (xy 36.824104 -310.476396) (xy 36.773322 -310.468353) (xy 36.724423 -310.452465)
			(xy 36.678611 -310.429122) (xy 36.637015 -310.398901) (xy 36.600659 -310.362545) (xy 36.570438 -310.320949)
			(xy 36.547095 -310.275137) (xy 36.531207 -310.226238) (xy 36.523164 -310.175456) (xy 36.204273 -310.175456)
			(xy 36.196516 -310.223186) (xy 36.180932 -310.269867) (xy 36.158061 -310.313444) (xy 36.128496 -310.352788)
			(xy 36.093003 -310.38688) (xy 36.0525 -310.414836) (xy 36.008038 -310.435934) (xy 35.960767 -310.449626)
			(xy 35.911912 -310.455558) (xy 35.862737 -310.453577) (xy 35.814518 -310.443733) (xy 35.768502 -310.426281)
			(xy 35.725881 -310.401674) (xy 35.68776 -310.370549) (xy 35.655125 -310.333712) (xy 35.628822 -310.292116)
			(xy 35.609531 -310.24684) (xy 35.597754 -310.199056) (xy 35.593794 -310.150002) (xy 34.85373 -310.150002)
			(xy 34.855544 -310.156179) (xy 34.8633 -310.210127) (xy 34.863786 -310.237378) (xy 34.863273 -310.266153)
			(xy 34.854619 -310.323048) (xy 34.837521 -310.377998) (xy 34.812365 -310.429758) (xy 34.779721 -310.477154)
			(xy 34.760408 -310.49849) (xy 34.751082 -310.509071) (xy 34.73817 -310.534137) (xy 34.732608 -310.56178)
			(xy 34.734821 -310.589889) (xy 34.74464 -310.61632) (xy 34.761315 -310.639057) (xy 34.783574 -310.656364)
			(xy 34.796476 -310.662066) (xy 34.822543 -310.67316) (xy 34.871364 -310.701893) (xy 34.915401 -310.737528)
			(xy 34.953685 -310.779283) (xy 34.985374 -310.82624) (xy 35.009771 -310.877366) (xy 35.026341 -310.931537)
			(xy 35.034719 -310.987564) (xy 35.035236 -311.015888) (xy 35.03475 -311.043139) (xy 35.026994 -311.097087)
			(xy 35.02615 -311.099962) (xy 36.544008 -311.099962) (xy 36.547968 -311.050908) (xy 36.559745 -311.003124)
			(xy 36.579036 -310.957848) (xy 36.605339 -310.916252) (xy 36.637974 -310.879415) (xy 36.676095 -310.84829)
			(xy 36.718716 -310.823683) (xy 36.764732 -310.806231) (xy 36.812951 -310.796387) (xy 36.862126 -310.794406)
			(xy 36.910981 -310.800338) (xy 36.958252 -310.81403) (xy 37.002714 -310.835128) (xy 37.043217 -310.863084)
			(xy 37.07871 -310.897176) (xy 37.108275 -310.93652) (xy 37.131146 -310.980097) (xy 37.14673 -311.026778)
			(xy 37.154625 -311.075355) (xy 37.15512 -311.099962) (xy 37.493968 -311.099962) (xy 37.497928 -311.050908)
			(xy 37.509705 -311.003124) (xy 37.528996 -310.957848) (xy 37.555299 -310.916252) (xy 37.587934 -310.879415)
			(xy 37.626055 -310.84829) (xy 37.668676 -310.823683) (xy 37.714692 -310.806231) (xy 37.762911 -310.796387)
			(xy 37.812086 -310.794406) (xy 37.860941 -310.800338) (xy 37.908212 -310.81403) (xy 37.952674 -310.835128)
			(xy 37.993177 -310.863084) (xy 38.02867 -310.897176) (xy 38.058235 -310.93652) (xy 38.081106 -310.980097)
			(xy 38.09669 -311.026778) (xy 38.104585 -311.075355) (xy 38.10508 -311.099962) (xy 38.444182 -311.099962)
			(xy 38.448142 -311.050908) (xy 38.459919 -311.003124) (xy 38.47921 -310.957848) (xy 38.505513 -310.916252)
			(xy 38.538148 -310.879415) (xy 38.576269 -310.84829) (xy 38.61889 -310.823683) (xy 38.664906 -310.806231)
			(xy 38.713125 -310.796387) (xy 38.7623 -310.794406) (xy 38.811155 -310.800338) (xy 38.858426 -310.81403)
			(xy 38.902888 -310.835128) (xy 38.943391 -310.863084) (xy 38.978884 -310.897176) (xy 39.008449 -310.93652)
			(xy 39.03132 -310.980097) (xy 39.046904 -311.026778) (xy 39.054799 -311.075355) (xy 39.055294 -311.099962)
			(xy 39.054799 -311.124569) (xy 39.05462 -311.12567) (xy 39.373298 -311.12567) (xy 39.373298 -311.074254)
			(xy 39.381341 -311.023472) (xy 39.397229 -310.974573) (xy 39.420572 -310.928761) (xy 39.450793 -310.887165)
			(xy 39.487149 -310.850809) (xy 39.528745 -310.820588) (xy 39.574557 -310.797245) (xy 39.623456 -310.781357)
			(xy 39.674238 -310.773314) (xy 39.725654 -310.773314) (xy 39.776436 -310.781357) (xy 39.825335 -310.797245)
			(xy 39.871147 -310.820588) (xy 39.912743 -310.850809) (xy 39.949099 -310.887165) (xy 39.97932 -310.928761)
			(xy 40.002663 -310.974573) (xy 40.018551 -311.023472) (xy 40.026594 -311.074254) (xy 40.027098 -311.099962)
			(xy 40.344102 -311.099962) (xy 40.348062 -311.050908) (xy 40.359839 -311.003124) (xy 40.37913 -310.957848)
			(xy 40.405433 -310.916252) (xy 40.438068 -310.879415) (xy 40.476189 -310.84829) (xy 40.51881 -310.823683)
			(xy 40.564826 -310.806231) (xy 40.613045 -310.796387) (xy 40.66222 -310.794406) (xy 40.711075 -310.800338)
			(xy 40.758346 -310.81403) (xy 40.802808 -310.835128) (xy 40.843311 -310.863084) (xy 40.878804 -310.897176)
			(xy 40.908369 -310.93652) (xy 40.93124 -310.980097) (xy 40.946824 -311.026778) (xy 40.954719 -311.075355)
			(xy 40.955214 -311.099962) (xy 40.954719 -311.124569) (xy 40.95454 -311.12567) (xy 41.273218 -311.12567)
			(xy 41.273218 -311.074254) (xy 41.281261 -311.023472) (xy 41.297149 -310.974573) (xy 41.320492 -310.928761)
			(xy 41.350713 -310.887165) (xy 41.387069 -310.850809) (xy 41.428665 -310.820588) (xy 41.474477 -310.797245)
			(xy 41.523376 -310.781357) (xy 41.574158 -310.773314) (xy 41.625574 -310.773314) (xy 41.676356 -310.781357)
			(xy 41.725255 -310.797245) (xy 41.771067 -310.820588) (xy 41.812663 -310.850809) (xy 41.849019 -310.887165)
			(xy 41.87924 -310.928761) (xy 41.902583 -310.974573) (xy 41.918471 -311.023472) (xy 41.926514 -311.074254)
			(xy 41.927018 -311.099962) (xy 42.244022 -311.099962) (xy 42.247982 -311.050908) (xy 42.259759 -311.003124)
			(xy 42.27905 -310.957848) (xy 42.305353 -310.916252) (xy 42.337988 -310.879415) (xy 42.376109 -310.84829)
			(xy 42.41873 -310.823683) (xy 42.464746 -310.806231) (xy 42.512965 -310.796387) (xy 42.56214 -310.794406)
			(xy 42.610995 -310.800338) (xy 42.658266 -310.81403) (xy 42.702728 -310.835128) (xy 42.743231 -310.863084)
			(xy 42.778724 -310.897176) (xy 42.808289 -310.93652) (xy 42.83116 -310.980097) (xy 42.846744 -311.026778)
			(xy 42.854639 -311.075355) (xy 42.855134 -311.099962) (xy 43.193982 -311.099962) (xy 43.197942 -311.050908)
			(xy 43.209719 -311.003124) (xy 43.22901 -310.957848) (xy 43.255313 -310.916252) (xy 43.287948 -310.879415)
			(xy 43.326069 -310.84829) (xy 43.36869 -310.823683) (xy 43.414706 -310.806231) (xy 43.462925 -310.796387)
			(xy 43.5121 -310.794406) (xy 43.560955 -310.800338) (xy 43.608226 -310.81403) (xy 43.652688 -310.835128)
			(xy 43.693191 -310.863084) (xy 43.728684 -310.897176) (xy 43.758249 -310.93652) (xy 43.78112 -310.980097)
			(xy 43.796704 -311.026778) (xy 43.804599 -311.075355) (xy 43.805094 -311.099962) (xy 44.143942 -311.099962)
			(xy 44.147902 -311.050908) (xy 44.159679 -311.003124) (xy 44.17897 -310.957848) (xy 44.205273 -310.916252)
			(xy 44.237908 -310.879415) (xy 44.276029 -310.84829) (xy 44.31865 -310.823683) (xy 44.364666 -310.806231)
			(xy 44.412885 -310.796387) (xy 44.46206 -310.794406) (xy 44.510915 -310.800338) (xy 44.558186 -310.81403)
			(xy 44.602648 -310.835128) (xy 44.643151 -310.863084) (xy 44.678644 -310.897176) (xy 44.708209 -310.93652)
			(xy 44.73108 -310.980097) (xy 44.746664 -311.026778) (xy 44.754559 -311.075355) (xy 44.755054 -311.099962)
			(xy 45.094156 -311.099962) (xy 45.098116 -311.050908) (xy 45.109893 -311.003124) (xy 45.129184 -310.957848)
			(xy 45.155487 -310.916252) (xy 45.188122 -310.879415) (xy 45.226243 -310.84829) (xy 45.268864 -310.823683)
			(xy 45.31488 -310.806231) (xy 45.363099 -310.796387) (xy 45.412274 -310.794406) (xy 45.461129 -310.800338)
			(xy 45.5084 -310.81403) (xy 45.552862 -310.835128) (xy 45.593365 -310.863084) (xy 45.628858 -310.897176)
			(xy 45.658423 -310.93652) (xy 45.681294 -310.980097) (xy 45.696878 -311.026778) (xy 45.704773 -311.075355)
			(xy 45.705268 -311.099962) (xy 46.044116 -311.099962) (xy 46.048076 -311.050908) (xy 46.059853 -311.003124)
			(xy 46.079144 -310.957848) (xy 46.105447 -310.916252) (xy 46.138082 -310.879415) (xy 46.176203 -310.84829)
			(xy 46.218824 -310.823683) (xy 46.26484 -310.806231) (xy 46.313059 -310.796387) (xy 46.362234 -310.794406)
			(xy 46.411089 -310.800338) (xy 46.45836 -310.81403) (xy 46.502822 -310.835128) (xy 46.543325 -310.863084)
			(xy 46.578818 -310.897176) (xy 46.608383 -310.93652) (xy 46.631254 -310.980097) (xy 46.646838 -311.026778)
			(xy 46.654733 -311.075355) (xy 46.655228 -311.099962) (xy 46.994076 -311.099962) (xy 46.998036 -311.050908)
			(xy 47.009813 -311.003124) (xy 47.029104 -310.957848) (xy 47.055407 -310.916252) (xy 47.088042 -310.879415)
			(xy 47.126163 -310.84829) (xy 47.168784 -310.823683) (xy 47.2148 -310.806231) (xy 47.263019 -310.796387)
			(xy 47.312194 -310.794406) (xy 47.361049 -310.800338) (xy 47.40832 -310.81403) (xy 47.452782 -310.835128)
			(xy 47.493285 -310.863084) (xy 47.528778 -310.897176) (xy 47.558343 -310.93652) (xy 47.581214 -310.980097)
			(xy 47.596798 -311.026778) (xy 47.604693 -311.075355) (xy 47.605188 -311.099962) (xy 47.944036 -311.099962)
			(xy 47.947996 -311.050908) (xy 47.959773 -311.003124) (xy 47.979064 -310.957848) (xy 48.005367 -310.916252)
			(xy 48.038002 -310.879415) (xy 48.076123 -310.84829) (xy 48.118744 -310.823683) (xy 48.16476 -310.806231)
			(xy 48.212979 -310.796387) (xy 48.262154 -310.794406) (xy 48.311009 -310.800338) (xy 48.35828 -310.81403)
			(xy 48.402742 -310.835128) (xy 48.443245 -310.863084) (xy 48.478738 -310.897176) (xy 48.508303 -310.93652)
			(xy 48.531174 -310.980097) (xy 48.546758 -311.026778) (xy 48.554653 -311.075355) (xy 48.555148 -311.099962)
			(xy 48.893996 -311.099962) (xy 48.897956 -311.050908) (xy 48.909733 -311.003124) (xy 48.929024 -310.957848)
			(xy 48.955327 -310.916252) (xy 48.987962 -310.879415) (xy 49.026083 -310.84829) (xy 49.068704 -310.823683)
			(xy 49.11472 -310.806231) (xy 49.162939 -310.796387) (xy 49.212114 -310.794406) (xy 49.260969 -310.800338)
			(xy 49.30824 -310.81403) (xy 49.352702 -310.835128) (xy 49.393205 -310.863084) (xy 49.428698 -310.897176)
			(xy 49.458263 -310.93652) (xy 49.481134 -310.980097) (xy 49.496718 -311.026778) (xy 49.504613 -311.075355)
			(xy 49.505108 -311.099962) (xy 49.843956 -311.099962) (xy 49.847916 -311.050908) (xy 49.859693 -311.003124)
			(xy 49.878984 -310.957848) (xy 49.905287 -310.916252) (xy 49.937922 -310.879415) (xy 49.976043 -310.84829)
			(xy 50.018664 -310.823683) (xy 50.06468 -310.806231) (xy 50.112899 -310.796387) (xy 50.162074 -310.794406)
			(xy 50.210929 -310.800338) (xy 50.2582 -310.81403) (xy 50.302662 -310.835128) (xy 50.343165 -310.863084)
			(xy 50.378658 -310.897176) (xy 50.408223 -310.93652) (xy 50.431094 -310.980097) (xy 50.446678 -311.026778)
			(xy 50.454573 -311.075355) (xy 50.455068 -311.099962) (xy 50.79417 -311.099962) (xy 50.79813 -311.050908)
			(xy 50.809907 -311.003124) (xy 50.829198 -310.957848) (xy 50.855501 -310.916252) (xy 50.888136 -310.879415)
			(xy 50.926257 -310.84829) (xy 50.968878 -310.823683) (xy 51.014894 -310.806231) (xy 51.063113 -310.796387)
			(xy 51.112288 -310.794406) (xy 51.161143 -310.800338) (xy 51.208414 -310.81403) (xy 51.252876 -310.835128)
			(xy 51.293379 -310.863084) (xy 51.328872 -310.897176) (xy 51.358437 -310.93652) (xy 51.381308 -310.980097)
			(xy 51.396892 -311.026778) (xy 51.404787 -311.075355) (xy 51.405282 -311.099962) (xy 51.74413 -311.099962)
			(xy 51.74809 -311.050908) (xy 51.759867 -311.003124) (xy 51.779158 -310.957848) (xy 51.805461 -310.916252)
			(xy 51.838096 -310.879415) (xy 51.876217 -310.84829) (xy 51.918838 -310.823683) (xy 51.964854 -310.806231)
			(xy 52.013073 -310.796387) (xy 52.062248 -310.794406) (xy 52.111103 -310.800338) (xy 52.158374 -310.81403)
			(xy 52.202836 -310.835128) (xy 52.243339 -310.863084) (xy 52.278832 -310.897176) (xy 52.308397 -310.93652)
			(xy 52.331268 -310.980097) (xy 52.346852 -311.026778) (xy 52.354747 -311.075355) (xy 52.355242 -311.099962)
			(xy 52.69409 -311.099962) (xy 52.69805 -311.050908) (xy 52.709827 -311.003124) (xy 52.729118 -310.957848)
			(xy 52.755421 -310.916252) (xy 52.788056 -310.879415) (xy 52.826177 -310.84829) (xy 52.868798 -310.823683)
			(xy 52.914814 -310.806231) (xy 52.963033 -310.796387) (xy 53.012208 -310.794406) (xy 53.061063 -310.800338)
			(xy 53.108334 -310.81403) (xy 53.152796 -310.835128) (xy 53.193299 -310.863084) (xy 53.228792 -310.897176)
			(xy 53.258357 -310.93652) (xy 53.281228 -310.980097) (xy 53.296812 -311.026778) (xy 53.304707 -311.075355)
			(xy 53.305202 -311.099962) (xy 53.64405 -311.099962) (xy 53.64801 -311.050908) (xy 53.659787 -311.003124)
			(xy 53.679078 -310.957848) (xy 53.705381 -310.916252) (xy 53.738016 -310.879415) (xy 53.776137 -310.84829)
			(xy 53.818758 -310.823683) (xy 53.864774 -310.806231) (xy 53.912993 -310.796387) (xy 53.962168 -310.794406)
			(xy 54.011023 -310.800338) (xy 54.058294 -310.81403) (xy 54.102756 -310.835128) (xy 54.143259 -310.863084)
			(xy 54.178752 -310.897176) (xy 54.208317 -310.93652) (xy 54.231188 -310.980097) (xy 54.246772 -311.026778)
			(xy 54.254667 -311.075355) (xy 54.255162 -311.099962) (xy 54.59401 -311.099962) (xy 54.59797 -311.050908)
			(xy 54.609747 -311.003124) (xy 54.629038 -310.957848) (xy 54.655341 -310.916252) (xy 54.687976 -310.879415)
			(xy 54.726097 -310.84829) (xy 54.768718 -310.823683) (xy 54.814734 -310.806231) (xy 54.862953 -310.796387)
			(xy 54.912128 -310.794406) (xy 54.960983 -310.800338) (xy 55.008254 -310.81403) (xy 55.052716 -310.835128)
			(xy 55.093219 -310.863084) (xy 55.128712 -310.897176) (xy 55.158277 -310.93652) (xy 55.181148 -310.980097)
			(xy 55.196732 -311.026778) (xy 55.204627 -311.075355) (xy 55.205122 -311.099962) (xy 55.54397 -311.099962)
			(xy 55.54793 -311.050908) (xy 55.559707 -311.003124) (xy 55.578998 -310.957848) (xy 55.605301 -310.916252)
			(xy 55.637936 -310.879415) (xy 55.676057 -310.84829) (xy 55.718678 -310.823683) (xy 55.764694 -310.806231)
			(xy 55.812913 -310.796387) (xy 55.862088 -310.794406) (xy 55.910943 -310.800338) (xy 55.958214 -310.81403)
			(xy 56.002676 -310.835128) (xy 56.043179 -310.863084) (xy 56.078672 -310.897176) (xy 56.108237 -310.93652)
			(xy 56.131108 -310.980097) (xy 56.146692 -311.026778) (xy 56.154587 -311.075355) (xy 56.155082 -311.099962)
			(xy 56.494184 -311.099962) (xy 56.498144 -311.050908) (xy 56.509921 -311.003124) (xy 56.529212 -310.957848)
			(xy 56.555515 -310.916252) (xy 56.58815 -310.879415) (xy 56.626271 -310.84829) (xy 56.668892 -310.823683)
			(xy 56.714908 -310.806231) (xy 56.763127 -310.796387) (xy 56.812302 -310.794406) (xy 56.861157 -310.800338)
			(xy 56.908428 -310.81403) (xy 56.95289 -310.835128) (xy 56.993393 -310.863084) (xy 57.028886 -310.897176)
			(xy 57.058451 -310.93652) (xy 57.081322 -310.980097) (xy 57.096906 -311.026778) (xy 57.104801 -311.075355)
			(xy 57.105296 -311.099962) (xy 57.444144 -311.099962) (xy 57.448104 -311.050908) (xy 57.459881 -311.003124)
			(xy 57.479172 -310.957848) (xy 57.505475 -310.916252) (xy 57.53811 -310.879415) (xy 57.576231 -310.84829)
			(xy 57.618852 -310.823683) (xy 57.664868 -310.806231) (xy 57.713087 -310.796387) (xy 57.762262 -310.794406)
			(xy 57.811117 -310.800338) (xy 57.858388 -310.81403) (xy 57.90285 -310.835128) (xy 57.943353 -310.863084)
			(xy 57.978846 -310.897176) (xy 58.008411 -310.93652) (xy 58.031282 -310.980097) (xy 58.046866 -311.026778)
			(xy 58.054761 -311.075355) (xy 58.055256 -311.099962) (xy 58.054761 -311.124569) (xy 58.054582 -311.12567)
			(xy 58.37326 -311.12567) (xy 58.37326 -311.074254) (xy 58.381303 -311.023472) (xy 58.397191 -310.974573)
			(xy 58.420534 -310.928761) (xy 58.450755 -310.887165) (xy 58.487111 -310.850809) (xy 58.528707 -310.820588)
			(xy 58.574519 -310.797245) (xy 58.623418 -310.781357) (xy 58.6742 -310.773314) (xy 58.725616 -310.773314)
			(xy 58.776398 -310.781357) (xy 58.825297 -310.797245) (xy 58.871109 -310.820588) (xy 58.912705 -310.850809)
			(xy 58.949061 -310.887165) (xy 58.979282 -310.928761) (xy 59.002625 -310.974573) (xy 59.018513 -311.023472)
			(xy 59.026556 -311.074254) (xy 59.02706 -311.099962) (xy 59.344064 -311.099962) (xy 59.348024 -311.050908)
			(xy 59.359801 -311.003124) (xy 59.379092 -310.957848) (xy 59.405395 -310.916252) (xy 59.43803 -310.879415)
			(xy 59.476151 -310.84829) (xy 59.518772 -310.823683) (xy 59.564788 -310.806231) (xy 59.613007 -310.796387)
			(xy 59.662182 -310.794406) (xy 59.711037 -310.800338) (xy 59.758308 -310.81403) (xy 59.80277 -310.835128)
			(xy 59.843273 -310.863084) (xy 59.878766 -310.897176) (xy 59.908331 -310.93652) (xy 59.931202 -310.980097)
			(xy 59.946786 -311.026778) (xy 59.954681 -311.075355) (xy 59.955176 -311.099962) (xy 59.954681 -311.124569)
			(xy 59.954502 -311.12567) (xy 60.27318 -311.12567) (xy 60.27318 -311.074254) (xy 60.281223 -311.023472)
			(xy 60.297111 -310.974573) (xy 60.320454 -310.928761) (xy 60.350675 -310.887165) (xy 60.387031 -310.850809)
			(xy 60.428627 -310.820588) (xy 60.474439 -310.797245) (xy 60.523338 -310.781357) (xy 60.57412 -310.773314)
			(xy 60.625536 -310.773314) (xy 60.676318 -310.781357) (xy 60.725217 -310.797245) (xy 60.771029 -310.820588)
			(xy 60.812625 -310.850809) (xy 60.848981 -310.887165) (xy 60.879202 -310.928761) (xy 60.902545 -310.974573)
			(xy 60.918433 -311.023472) (xy 60.926476 -311.074254) (xy 60.92698 -311.099962) (xy 61.243984 -311.099962)
			(xy 61.247944 -311.050908) (xy 61.259721 -311.003124) (xy 61.279012 -310.957848) (xy 61.305315 -310.916252)
			(xy 61.33795 -310.879415) (xy 61.376071 -310.84829) (xy 61.418692 -310.823683) (xy 61.464708 -310.806231)
			(xy 61.512927 -310.796387) (xy 61.562102 -310.794406) (xy 61.610957 -310.800338) (xy 61.658228 -310.81403)
			(xy 61.70269 -310.835128) (xy 61.743193 -310.863084) (xy 61.778686 -310.897176) (xy 61.808251 -310.93652)
			(xy 61.831122 -310.980097) (xy 61.846706 -311.026778) (xy 61.854601 -311.075355) (xy 61.855096 -311.099962)
			(xy 61.854601 -311.124569) (xy 61.854422 -311.12567) (xy 62.1731 -311.12567) (xy 62.1731 -311.074254)
			(xy 62.181143 -311.023472) (xy 62.197031 -310.974573) (xy 62.220374 -310.928761) (xy 62.250595 -310.887165)
			(xy 62.286951 -310.850809) (xy 62.328547 -310.820588) (xy 62.374359 -310.797245) (xy 62.423258 -310.781357)
			(xy 62.47404 -310.773314) (xy 62.525456 -310.773314) (xy 62.576238 -310.781357) (xy 62.625137 -310.797245)
			(xy 62.670949 -310.820588) (xy 62.712545 -310.850809) (xy 62.748901 -310.887165) (xy 62.779122 -310.928761)
			(xy 62.802465 -310.974573) (xy 62.818353 -311.023472) (xy 62.826396 -311.074254) (xy 62.8269 -311.099962)
			(xy 63.144158 -311.099962) (xy 63.148118 -311.050908) (xy 63.159895 -311.003124) (xy 63.179186 -310.957848)
			(xy 63.205489 -310.916252) (xy 63.238124 -310.879415) (xy 63.276245 -310.84829) (xy 63.318866 -310.823683)
			(xy 63.364882 -310.806231) (xy 63.413101 -310.796387) (xy 63.462276 -310.794406) (xy 63.511131 -310.800338)
			(xy 63.558402 -310.81403) (xy 63.602864 -310.835128) (xy 63.643367 -310.863084) (xy 63.67886 -310.897176)
			(xy 63.708425 -310.93652) (xy 63.731296 -310.980097) (xy 63.74688 -311.026778) (xy 63.754775 -311.075355)
			(xy 63.75527 -311.099962) (xy 63.754775 -311.124569) (xy 63.754596 -311.12567) (xy 64.073274 -311.12567)
			(xy 64.073274 -311.074254) (xy 64.081317 -311.023472) (xy 64.097205 -310.974573) (xy 64.120548 -310.928761)
			(xy 64.150769 -310.887165) (xy 64.187125 -310.850809) (xy 64.228721 -310.820588) (xy 64.274533 -310.797245)
			(xy 64.323432 -310.781357) (xy 64.374214 -310.773314) (xy 64.42563 -310.773314) (xy 64.476412 -310.781357)
			(xy 64.525311 -310.797245) (xy 64.571123 -310.820588) (xy 64.612719 -310.850809) (xy 64.649075 -310.887165)
			(xy 64.679296 -310.928761) (xy 64.702639 -310.974573) (xy 64.718527 -311.023472) (xy 64.72657 -311.074254)
			(xy 64.727074 -311.099962) (xy 65.044078 -311.099962) (xy 65.048038 -311.050908) (xy 65.059815 -311.003124)
			(xy 65.079106 -310.957848) (xy 65.105409 -310.916252) (xy 65.138044 -310.879415) (xy 65.176165 -310.84829)
			(xy 65.218786 -310.823683) (xy 65.264802 -310.806231) (xy 65.313021 -310.796387) (xy 65.362196 -310.794406)
			(xy 65.411051 -310.800338) (xy 65.458322 -310.81403) (xy 65.502784 -310.835128) (xy 65.543287 -310.863084)
			(xy 65.57878 -310.897176) (xy 65.608345 -310.93652) (xy 65.631216 -310.980097) (xy 65.6468 -311.026778)
			(xy 65.654695 -311.075355) (xy 65.65519 -311.099962) (xy 65.654695 -311.124569) (xy 65.654516 -311.12567)
			(xy 65.973194 -311.12567) (xy 65.973194 -311.074254) (xy 65.981237 -311.023472) (xy 65.997125 -310.974573)
			(xy 66.020468 -310.928761) (xy 66.050689 -310.887165) (xy 66.087045 -310.850809) (xy 66.128641 -310.820588)
			(xy 66.174453 -310.797245) (xy 66.223352 -310.781357) (xy 66.274134 -310.773314) (xy 66.32555 -310.773314)
			(xy 66.376332 -310.781357) (xy 66.425231 -310.797245) (xy 66.471043 -310.820588) (xy 66.512639 -310.850809)
			(xy 66.548995 -310.887165) (xy 66.579216 -310.928761) (xy 66.602559 -310.974573) (xy 66.618447 -311.023472)
			(xy 66.62649 -311.074254) (xy 66.626994 -311.099962) (xy 66.943998 -311.099962) (xy 66.947958 -311.050908)
			(xy 66.959735 -311.003124) (xy 66.979026 -310.957848) (xy 67.005329 -310.916252) (xy 67.037964 -310.879415)
			(xy 67.076085 -310.84829) (xy 67.118706 -310.823683) (xy 67.164722 -310.806231) (xy 67.212941 -310.796387)
			(xy 67.262116 -310.794406) (xy 67.310971 -310.800338) (xy 67.358242 -310.81403) (xy 67.402704 -310.835128)
			(xy 67.443207 -310.863084) (xy 67.4787 -310.897176) (xy 67.508265 -310.93652) (xy 67.531136 -310.980097)
			(xy 67.54672 -311.026778) (xy 67.554615 -311.075355) (xy 67.55511 -311.099962) (xy 67.554615 -311.124569)
			(xy 67.554436 -311.12567) (xy 67.873114 -311.12567) (xy 67.873114 -311.074254) (xy 67.881157 -311.023472)
			(xy 67.897045 -310.974573) (xy 67.920388 -310.928761) (xy 67.950609 -310.887165) (xy 67.986965 -310.850809)
			(xy 68.028561 -310.820588) (xy 68.074373 -310.797245) (xy 68.123272 -310.781357) (xy 68.174054 -310.773314)
			(xy 68.22547 -310.773314) (xy 68.276252 -310.781357) (xy 68.325151 -310.797245) (xy 68.370963 -310.820588)
			(xy 68.412559 -310.850809) (xy 68.448915 -310.887165) (xy 68.479136 -310.928761) (xy 68.502479 -310.974573)
			(xy 68.518367 -311.023472) (xy 68.52641 -311.074254) (xy 68.526914 -311.099962) (xy 68.844172 -311.099962)
			(xy 68.848132 -311.050908) (xy 68.859909 -311.003124) (xy 68.8792 -310.957848) (xy 68.905503 -310.916252)
			(xy 68.938138 -310.879415) (xy 68.976259 -310.84829) (xy 69.01888 -310.823683) (xy 69.064896 -310.806231)
			(xy 69.113115 -310.796387) (xy 69.16229 -310.794406) (xy 69.211145 -310.800338) (xy 69.258416 -310.81403)
			(xy 69.302878 -310.835128) (xy 69.343381 -310.863084) (xy 69.378874 -310.897176) (xy 69.408439 -310.93652)
			(xy 69.43131 -310.980097) (xy 69.446894 -311.026778) (xy 69.454789 -311.075355) (xy 69.455284 -311.099962)
			(xy 69.454789 -311.124569) (xy 69.45461 -311.12567) (xy 69.773288 -311.12567) (xy 69.773288 -311.074254)
			(xy 69.781331 -311.023472) (xy 69.797219 -310.974573) (xy 69.820562 -310.928761) (xy 69.850783 -310.887165)
			(xy 69.887139 -310.850809) (xy 69.928735 -310.820588) (xy 69.974547 -310.797245) (xy 70.023446 -310.781357)
			(xy 70.074228 -310.773314) (xy 70.125644 -310.773314) (xy 70.176426 -310.781357) (xy 70.225325 -310.797245)
			(xy 70.271137 -310.820588) (xy 70.312733 -310.850809) (xy 70.349089 -310.887165) (xy 70.37931 -310.928761)
			(xy 70.402653 -310.974573) (xy 70.418541 -311.023472) (xy 70.426584 -311.074254) (xy 70.427088 -311.099962)
			(xy 70.744092 -311.099962) (xy 70.748052 -311.050908) (xy 70.759829 -311.003124) (xy 70.77912 -310.957848)
			(xy 70.805423 -310.916252) (xy 70.838058 -310.879415) (xy 70.876179 -310.84829) (xy 70.9188 -310.823683)
			(xy 70.964816 -310.806231) (xy 71.013035 -310.796387) (xy 71.06221 -310.794406) (xy 71.111065 -310.800338)
			(xy 71.158336 -310.81403) (xy 71.202798 -310.835128) (xy 71.243301 -310.863084) (xy 71.278794 -310.897176)
			(xy 71.308359 -310.93652) (xy 71.33123 -310.980097) (xy 71.346814 -311.026778) (xy 71.354709 -311.075355)
			(xy 71.355204 -311.099962) (xy 71.354709 -311.124569) (xy 71.346814 -311.173146) (xy 71.33123 -311.219827)
			(xy 71.308359 -311.263404) (xy 71.278794 -311.302748) (xy 71.243301 -311.33684) (xy 71.202798 -311.364796)
			(xy 71.158336 -311.385894) (xy 71.111065 -311.399586) (xy 71.06221 -311.405518) (xy 71.013035 -311.403537)
			(xy 70.964816 -311.393693) (xy 70.9188 -311.376241) (xy 70.876179 -311.351634) (xy 70.838058 -311.320509)
			(xy 70.805423 -311.283672) (xy 70.77912 -311.242076) (xy 70.759829 -311.1968) (xy 70.748052 -311.149016)
			(xy 70.744092 -311.099962) (xy 70.427088 -311.099962) (xy 70.426584 -311.12567) (xy 70.418541 -311.176452)
			(xy 70.402653 -311.225351) (xy 70.37931 -311.271163) (xy 70.349089 -311.312759) (xy 70.312733 -311.349115)
			(xy 70.271137 -311.379336) (xy 70.225325 -311.402679) (xy 70.176426 -311.418567) (xy 70.125644 -311.42661)
			(xy 70.074228 -311.42661) (xy 70.023446 -311.418567) (xy 69.974547 -311.402679) (xy 69.928735 -311.379336)
			(xy 69.887139 -311.349115) (xy 69.850783 -311.312759) (xy 69.820562 -311.271163) (xy 69.797219 -311.225351)
			(xy 69.781331 -311.176452) (xy 69.773288 -311.12567) (xy 69.45461 -311.12567) (xy 69.446894 -311.173146)
			(xy 69.43131 -311.219827) (xy 69.408439 -311.263404) (xy 69.378874 -311.302748) (xy 69.343381 -311.33684)
			(xy 69.302878 -311.364796) (xy 69.258416 -311.385894) (xy 69.211145 -311.399586) (xy 69.16229 -311.405518)
			(xy 69.113115 -311.403537) (xy 69.064896 -311.393693) (xy 69.01888 -311.376241) (xy 68.976259 -311.351634)
			(xy 68.938138 -311.320509) (xy 68.905503 -311.283672) (xy 68.8792 -311.242076) (xy 68.859909 -311.1968)
			(xy 68.848132 -311.149016) (xy 68.844172 -311.099962) (xy 68.526914 -311.099962) (xy 68.52641 -311.12567)
			(xy 68.518367 -311.176452) (xy 68.502479 -311.225351) (xy 68.479136 -311.271163) (xy 68.448915 -311.312759)
			(xy 68.412559 -311.349115) (xy 68.370963 -311.379336) (xy 68.325151 -311.402679) (xy 68.276252 -311.418567)
			(xy 68.22547 -311.42661) (xy 68.174054 -311.42661) (xy 68.123272 -311.418567) (xy 68.074373 -311.402679)
			(xy 68.028561 -311.379336) (xy 67.986965 -311.349115) (xy 67.950609 -311.312759) (xy 67.920388 -311.271163)
			(xy 67.897045 -311.225351) (xy 67.881157 -311.176452) (xy 67.873114 -311.12567) (xy 67.554436 -311.12567)
			(xy 67.54672 -311.173146) (xy 67.531136 -311.219827) (xy 67.508265 -311.263404) (xy 67.4787 -311.302748)
			(xy 67.443207 -311.33684) (xy 67.402704 -311.364796) (xy 67.358242 -311.385894) (xy 67.310971 -311.399586)
			(xy 67.262116 -311.405518) (xy 67.212941 -311.403537) (xy 67.164722 -311.393693) (xy 67.118706 -311.376241)
			(xy 67.076085 -311.351634) (xy 67.037964 -311.320509) (xy 67.005329 -311.283672) (xy 66.979026 -311.242076)
			(xy 66.959735 -311.1968) (xy 66.947958 -311.149016) (xy 66.943998 -311.099962) (xy 66.626994 -311.099962)
			(xy 66.62649 -311.12567) (xy 66.618447 -311.176452) (xy 66.602559 -311.225351) (xy 66.579216 -311.271163)
			(xy 66.548995 -311.312759) (xy 66.512639 -311.349115) (xy 66.471043 -311.379336) (xy 66.425231 -311.402679)
			(xy 66.376332 -311.418567) (xy 66.32555 -311.42661) (xy 66.274134 -311.42661) (xy 66.223352 -311.418567)
			(xy 66.174453 -311.402679) (xy 66.128641 -311.379336) (xy 66.087045 -311.349115) (xy 66.050689 -311.312759)
			(xy 66.020468 -311.271163) (xy 65.997125 -311.225351) (xy 65.981237 -311.176452) (xy 65.973194 -311.12567)
			(xy 65.654516 -311.12567) (xy 65.6468 -311.173146) (xy 65.631216 -311.219827) (xy 65.608345 -311.263404)
			(xy 65.57878 -311.302748) (xy 65.543287 -311.33684) (xy 65.502784 -311.364796) (xy 65.458322 -311.385894)
			(xy 65.411051 -311.399586) (xy 65.362196 -311.405518) (xy 65.313021 -311.403537) (xy 65.264802 -311.393693)
			(xy 65.218786 -311.376241) (xy 65.176165 -311.351634) (xy 65.138044 -311.320509) (xy 65.105409 -311.283672)
			(xy 65.079106 -311.242076) (xy 65.059815 -311.1968) (xy 65.048038 -311.149016) (xy 65.044078 -311.099962)
			(xy 64.727074 -311.099962) (xy 64.72657 -311.12567) (xy 64.718527 -311.176452) (xy 64.702639 -311.225351)
			(xy 64.679296 -311.271163) (xy 64.649075 -311.312759) (xy 64.612719 -311.349115) (xy 64.571123 -311.379336)
			(xy 64.525311 -311.402679) (xy 64.476412 -311.418567) (xy 64.42563 -311.42661) (xy 64.374214 -311.42661)
			(xy 64.323432 -311.418567) (xy 64.274533 -311.402679) (xy 64.228721 -311.379336) (xy 64.187125 -311.349115)
			(xy 64.150769 -311.312759) (xy 64.120548 -311.271163) (xy 64.097205 -311.225351) (xy 64.081317 -311.176452)
			(xy 64.073274 -311.12567) (xy 63.754596 -311.12567) (xy 63.74688 -311.173146) (xy 63.731296 -311.219827)
			(xy 63.708425 -311.263404) (xy 63.67886 -311.302748) (xy 63.643367 -311.33684) (xy 63.602864 -311.364796)
			(xy 63.558402 -311.385894) (xy 63.511131 -311.399586) (xy 63.462276 -311.405518) (xy 63.413101 -311.403537)
			(xy 63.364882 -311.393693) (xy 63.318866 -311.376241) (xy 63.276245 -311.351634) (xy 63.238124 -311.320509)
			(xy 63.205489 -311.283672) (xy 63.179186 -311.242076) (xy 63.159895 -311.1968) (xy 63.148118 -311.149016)
			(xy 63.144158 -311.099962) (xy 62.8269 -311.099962) (xy 62.826396 -311.12567) (xy 62.818353 -311.176452)
			(xy 62.802465 -311.225351) (xy 62.779122 -311.271163) (xy 62.748901 -311.312759) (xy 62.712545 -311.349115)
			(xy 62.670949 -311.379336) (xy 62.625137 -311.402679) (xy 62.576238 -311.418567) (xy 62.525456 -311.42661)
			(xy 62.47404 -311.42661) (xy 62.423258 -311.418567) (xy 62.374359 -311.402679) (xy 62.328547 -311.379336)
			(xy 62.286951 -311.349115) (xy 62.250595 -311.312759) (xy 62.220374 -311.271163) (xy 62.197031 -311.225351)
			(xy 62.181143 -311.176452) (xy 62.1731 -311.12567) (xy 61.854422 -311.12567) (xy 61.846706 -311.173146)
			(xy 61.831122 -311.219827) (xy 61.808251 -311.263404) (xy 61.778686 -311.302748) (xy 61.743193 -311.33684)
			(xy 61.70269 -311.364796) (xy 61.658228 -311.385894) (xy 61.610957 -311.399586) (xy 61.562102 -311.405518)
			(xy 61.512927 -311.403537) (xy 61.464708 -311.393693) (xy 61.418692 -311.376241) (xy 61.376071 -311.351634)
			(xy 61.33795 -311.320509) (xy 61.305315 -311.283672) (xy 61.279012 -311.242076) (xy 61.259721 -311.1968)
			(xy 61.247944 -311.149016) (xy 61.243984 -311.099962) (xy 60.92698 -311.099962) (xy 60.926476 -311.12567)
			(xy 60.918433 -311.176452) (xy 60.902545 -311.225351) (xy 60.879202 -311.271163) (xy 60.848981 -311.312759)
			(xy 60.812625 -311.349115) (xy 60.771029 -311.379336) (xy 60.725217 -311.402679) (xy 60.676318 -311.418567)
			(xy 60.625536 -311.42661) (xy 60.57412 -311.42661) (xy 60.523338 -311.418567) (xy 60.474439 -311.402679)
			(xy 60.428627 -311.379336) (xy 60.387031 -311.349115) (xy 60.350675 -311.312759) (xy 60.320454 -311.271163)
			(xy 60.297111 -311.225351) (xy 60.281223 -311.176452) (xy 60.27318 -311.12567) (xy 59.954502 -311.12567)
			(xy 59.946786 -311.173146) (xy 59.931202 -311.219827) (xy 59.908331 -311.263404) (xy 59.878766 -311.302748)
			(xy 59.843273 -311.33684) (xy 59.80277 -311.364796) (xy 59.758308 -311.385894) (xy 59.711037 -311.399586)
			(xy 59.662182 -311.405518) (xy 59.613007 -311.403537) (xy 59.564788 -311.393693) (xy 59.518772 -311.376241)
			(xy 59.476151 -311.351634) (xy 59.43803 -311.320509) (xy 59.405395 -311.283672) (xy 59.379092 -311.242076)
			(xy 59.359801 -311.1968) (xy 59.348024 -311.149016) (xy 59.344064 -311.099962) (xy 59.02706 -311.099962)
			(xy 59.026556 -311.12567) (xy 59.018513 -311.176452) (xy 59.002625 -311.225351) (xy 58.979282 -311.271163)
			(xy 58.949061 -311.312759) (xy 58.912705 -311.349115) (xy 58.871109 -311.379336) (xy 58.825297 -311.402679)
			(xy 58.776398 -311.418567) (xy 58.725616 -311.42661) (xy 58.6742 -311.42661) (xy 58.623418 -311.418567)
			(xy 58.574519 -311.402679) (xy 58.528707 -311.379336) (xy 58.487111 -311.349115) (xy 58.450755 -311.312759)
			(xy 58.420534 -311.271163) (xy 58.397191 -311.225351) (xy 58.381303 -311.176452) (xy 58.37326 -311.12567)
			(xy 58.054582 -311.12567) (xy 58.046866 -311.173146) (xy 58.031282 -311.219827) (xy 58.008411 -311.263404)
			(xy 57.978846 -311.302748) (xy 57.943353 -311.33684) (xy 57.90285 -311.364796) (xy 57.858388 -311.385894)
			(xy 57.811117 -311.399586) (xy 57.762262 -311.405518) (xy 57.713087 -311.403537) (xy 57.664868 -311.393693)
			(xy 57.618852 -311.376241) (xy 57.576231 -311.351634) (xy 57.53811 -311.320509) (xy 57.505475 -311.283672)
			(xy 57.479172 -311.242076) (xy 57.459881 -311.1968) (xy 57.448104 -311.149016) (xy 57.444144 -311.099962)
			(xy 57.105296 -311.099962) (xy 57.104801 -311.124569) (xy 57.096906 -311.173146) (xy 57.081322 -311.219827)
			(xy 57.058451 -311.263404) (xy 57.028886 -311.302748) (xy 56.993393 -311.33684) (xy 56.95289 -311.364796)
			(xy 56.908428 -311.385894) (xy 56.861157 -311.399586) (xy 56.812302 -311.405518) (xy 56.763127 -311.403537)
			(xy 56.714908 -311.393693) (xy 56.668892 -311.376241) (xy 56.626271 -311.351634) (xy 56.58815 -311.320509)
			(xy 56.555515 -311.283672) (xy 56.529212 -311.242076) (xy 56.509921 -311.1968) (xy 56.498144 -311.149016)
			(xy 56.494184 -311.099962) (xy 56.155082 -311.099962) (xy 56.154587 -311.124569) (xy 56.146692 -311.173146)
			(xy 56.131108 -311.219827) (xy 56.108237 -311.263404) (xy 56.078672 -311.302748) (xy 56.043179 -311.33684)
			(xy 56.002676 -311.364796) (xy 55.958214 -311.385894) (xy 55.910943 -311.399586) (xy 55.862088 -311.405518)
			(xy 55.812913 -311.403537) (xy 55.764694 -311.393693) (xy 55.718678 -311.376241) (xy 55.676057 -311.351634)
			(xy 55.637936 -311.320509) (xy 55.605301 -311.283672) (xy 55.578998 -311.242076) (xy 55.559707 -311.1968)
			(xy 55.54793 -311.149016) (xy 55.54397 -311.099962) (xy 55.205122 -311.099962) (xy 55.204627 -311.124569)
			(xy 55.196732 -311.173146) (xy 55.181148 -311.219827) (xy 55.158277 -311.263404) (xy 55.128712 -311.302748)
			(xy 55.093219 -311.33684) (xy 55.052716 -311.364796) (xy 55.008254 -311.385894) (xy 54.960983 -311.399586)
			(xy 54.912128 -311.405518) (xy 54.862953 -311.403537) (xy 54.814734 -311.393693) (xy 54.768718 -311.376241)
			(xy 54.726097 -311.351634) (xy 54.687976 -311.320509) (xy 54.655341 -311.283672) (xy 54.629038 -311.242076)
			(xy 54.609747 -311.1968) (xy 54.59797 -311.149016) (xy 54.59401 -311.099962) (xy 54.255162 -311.099962)
			(xy 54.254667 -311.124569) (xy 54.246772 -311.173146) (xy 54.231188 -311.219827) (xy 54.208317 -311.263404)
			(xy 54.178752 -311.302748) (xy 54.143259 -311.33684) (xy 54.102756 -311.364796) (xy 54.058294 -311.385894)
			(xy 54.011023 -311.399586) (xy 53.962168 -311.405518) (xy 53.912993 -311.403537) (xy 53.864774 -311.393693)
			(xy 53.818758 -311.376241) (xy 53.776137 -311.351634) (xy 53.738016 -311.320509) (xy 53.705381 -311.283672)
			(xy 53.679078 -311.242076) (xy 53.659787 -311.1968) (xy 53.64801 -311.149016) (xy 53.64405 -311.099962)
			(xy 53.305202 -311.099962) (xy 53.304707 -311.124569) (xy 53.296812 -311.173146) (xy 53.281228 -311.219827)
			(xy 53.258357 -311.263404) (xy 53.228792 -311.302748) (xy 53.193299 -311.33684) (xy 53.152796 -311.364796)
			(xy 53.108334 -311.385894) (xy 53.061063 -311.399586) (xy 53.012208 -311.405518) (xy 52.963033 -311.403537)
			(xy 52.914814 -311.393693) (xy 52.868798 -311.376241) (xy 52.826177 -311.351634) (xy 52.788056 -311.320509)
			(xy 52.755421 -311.283672) (xy 52.729118 -311.242076) (xy 52.709827 -311.1968) (xy 52.69805 -311.149016)
			(xy 52.69409 -311.099962) (xy 52.355242 -311.099962) (xy 52.354747 -311.124569) (xy 52.346852 -311.173146)
			(xy 52.331268 -311.219827) (xy 52.308397 -311.263404) (xy 52.278832 -311.302748) (xy 52.243339 -311.33684)
			(xy 52.202836 -311.364796) (xy 52.158374 -311.385894) (xy 52.111103 -311.399586) (xy 52.062248 -311.405518)
			(xy 52.013073 -311.403537) (xy 51.964854 -311.393693) (xy 51.918838 -311.376241) (xy 51.876217 -311.351634)
			(xy 51.838096 -311.320509) (xy 51.805461 -311.283672) (xy 51.779158 -311.242076) (xy 51.759867 -311.1968)
			(xy 51.74809 -311.149016) (xy 51.74413 -311.099962) (xy 51.405282 -311.099962) (xy 51.404787 -311.124569)
			(xy 51.396892 -311.173146) (xy 51.381308 -311.219827) (xy 51.358437 -311.263404) (xy 51.328872 -311.302748)
			(xy 51.293379 -311.33684) (xy 51.252876 -311.364796) (xy 51.208414 -311.385894) (xy 51.161143 -311.399586)
			(xy 51.112288 -311.405518) (xy 51.063113 -311.403537) (xy 51.014894 -311.393693) (xy 50.968878 -311.376241)
			(xy 50.926257 -311.351634) (xy 50.888136 -311.320509) (xy 50.855501 -311.283672) (xy 50.829198 -311.242076)
			(xy 50.809907 -311.1968) (xy 50.79813 -311.149016) (xy 50.79417 -311.099962) (xy 50.455068 -311.099962)
			(xy 50.454573 -311.124569) (xy 50.446678 -311.173146) (xy 50.431094 -311.219827) (xy 50.408223 -311.263404)
			(xy 50.378658 -311.302748) (xy 50.343165 -311.33684) (xy 50.302662 -311.364796) (xy 50.2582 -311.385894)
			(xy 50.210929 -311.399586) (xy 50.162074 -311.405518) (xy 50.112899 -311.403537) (xy 50.06468 -311.393693)
			(xy 50.018664 -311.376241) (xy 49.976043 -311.351634) (xy 49.937922 -311.320509) (xy 49.905287 -311.283672)
			(xy 49.878984 -311.242076) (xy 49.859693 -311.1968) (xy 49.847916 -311.149016) (xy 49.843956 -311.099962)
			(xy 49.505108 -311.099962) (xy 49.504613 -311.124569) (xy 49.496718 -311.173146) (xy 49.481134 -311.219827)
			(xy 49.458263 -311.263404) (xy 49.428698 -311.302748) (xy 49.393205 -311.33684) (xy 49.352702 -311.364796)
			(xy 49.30824 -311.385894) (xy 49.260969 -311.399586) (xy 49.212114 -311.405518) (xy 49.162939 -311.403537)
			(xy 49.11472 -311.393693) (xy 49.068704 -311.376241) (xy 49.026083 -311.351634) (xy 48.987962 -311.320509)
			(xy 48.955327 -311.283672) (xy 48.929024 -311.242076) (xy 48.909733 -311.1968) (xy 48.897956 -311.149016)
			(xy 48.893996 -311.099962) (xy 48.555148 -311.099962) (xy 48.554653 -311.124569) (xy 48.546758 -311.173146)
			(xy 48.531174 -311.219827) (xy 48.508303 -311.263404) (xy 48.478738 -311.302748) (xy 48.443245 -311.33684)
			(xy 48.402742 -311.364796) (xy 48.35828 -311.385894) (xy 48.311009 -311.399586) (xy 48.262154 -311.405518)
			(xy 48.212979 -311.403537) (xy 48.16476 -311.393693) (xy 48.118744 -311.376241) (xy 48.076123 -311.351634)
			(xy 48.038002 -311.320509) (xy 48.005367 -311.283672) (xy 47.979064 -311.242076) (xy 47.959773 -311.1968)
			(xy 47.947996 -311.149016) (xy 47.944036 -311.099962) (xy 47.605188 -311.099962) (xy 47.604693 -311.124569)
			(xy 47.596798 -311.173146) (xy 47.581214 -311.219827) (xy 47.558343 -311.263404) (xy 47.528778 -311.302748)
			(xy 47.493285 -311.33684) (xy 47.452782 -311.364796) (xy 47.40832 -311.385894) (xy 47.361049 -311.399586)
			(xy 47.312194 -311.405518) (xy 47.263019 -311.403537) (xy 47.2148 -311.393693) (xy 47.168784 -311.376241)
			(xy 47.126163 -311.351634) (xy 47.088042 -311.320509) (xy 47.055407 -311.283672) (xy 47.029104 -311.242076)
			(xy 47.009813 -311.1968) (xy 46.998036 -311.149016) (xy 46.994076 -311.099962) (xy 46.655228 -311.099962)
			(xy 46.654733 -311.124569) (xy 46.646838 -311.173146) (xy 46.631254 -311.219827) (xy 46.608383 -311.263404)
			(xy 46.578818 -311.302748) (xy 46.543325 -311.33684) (xy 46.502822 -311.364796) (xy 46.45836 -311.385894)
			(xy 46.411089 -311.399586) (xy 46.362234 -311.405518) (xy 46.313059 -311.403537) (xy 46.26484 -311.393693)
			(xy 46.218824 -311.376241) (xy 46.176203 -311.351634) (xy 46.138082 -311.320509) (xy 46.105447 -311.283672)
			(xy 46.079144 -311.242076) (xy 46.059853 -311.1968) (xy 46.048076 -311.149016) (xy 46.044116 -311.099962)
			(xy 45.705268 -311.099962) (xy 45.704773 -311.124569) (xy 45.696878 -311.173146) (xy 45.681294 -311.219827)
			(xy 45.658423 -311.263404) (xy 45.628858 -311.302748) (xy 45.593365 -311.33684) (xy 45.552862 -311.364796)
			(xy 45.5084 -311.385894) (xy 45.461129 -311.399586) (xy 45.412274 -311.405518) (xy 45.363099 -311.403537)
			(xy 45.31488 -311.393693) (xy 45.268864 -311.376241) (xy 45.226243 -311.351634) (xy 45.188122 -311.320509)
			(xy 45.155487 -311.283672) (xy 45.129184 -311.242076) (xy 45.109893 -311.1968) (xy 45.098116 -311.149016)
			(xy 45.094156 -311.099962) (xy 44.755054 -311.099962) (xy 44.754559 -311.124569) (xy 44.746664 -311.173146)
			(xy 44.73108 -311.219827) (xy 44.708209 -311.263404) (xy 44.678644 -311.302748) (xy 44.643151 -311.33684)
			(xy 44.602648 -311.364796) (xy 44.558186 -311.385894) (xy 44.510915 -311.399586) (xy 44.46206 -311.405518)
			(xy 44.412885 -311.403537) (xy 44.364666 -311.393693) (xy 44.31865 -311.376241) (xy 44.276029 -311.351634)
			(xy 44.237908 -311.320509) (xy 44.205273 -311.283672) (xy 44.17897 -311.242076) (xy 44.159679 -311.1968)
			(xy 44.147902 -311.149016) (xy 44.143942 -311.099962) (xy 43.805094 -311.099962) (xy 43.804599 -311.124569)
			(xy 43.796704 -311.173146) (xy 43.78112 -311.219827) (xy 43.758249 -311.263404) (xy 43.728684 -311.302748)
			(xy 43.693191 -311.33684) (xy 43.652688 -311.364796) (xy 43.608226 -311.385894) (xy 43.560955 -311.399586)
			(xy 43.5121 -311.405518) (xy 43.462925 -311.403537) (xy 43.414706 -311.393693) (xy 43.36869 -311.376241)
			(xy 43.326069 -311.351634) (xy 43.287948 -311.320509) (xy 43.255313 -311.283672) (xy 43.22901 -311.242076)
			(xy 43.209719 -311.1968) (xy 43.197942 -311.149016) (xy 43.193982 -311.099962) (xy 42.855134 -311.099962)
			(xy 42.854639 -311.124569) (xy 42.846744 -311.173146) (xy 42.83116 -311.219827) (xy 42.808289 -311.263404)
			(xy 42.778724 -311.302748) (xy 42.743231 -311.33684) (xy 42.702728 -311.364796) (xy 42.658266 -311.385894)
			(xy 42.610995 -311.399586) (xy 42.56214 -311.405518) (xy 42.512965 -311.403537) (xy 42.464746 -311.393693)
			(xy 42.41873 -311.376241) (xy 42.376109 -311.351634) (xy 42.337988 -311.320509) (xy 42.305353 -311.283672)
			(xy 42.27905 -311.242076) (xy 42.259759 -311.1968) (xy 42.247982 -311.149016) (xy 42.244022 -311.099962)
			(xy 41.927018 -311.099962) (xy 41.926514 -311.12567) (xy 41.918471 -311.176452) (xy 41.902583 -311.225351)
			(xy 41.87924 -311.271163) (xy 41.849019 -311.312759) (xy 41.812663 -311.349115) (xy 41.771067 -311.379336)
			(xy 41.725255 -311.402679) (xy 41.676356 -311.418567) (xy 41.625574 -311.42661) (xy 41.574158 -311.42661)
			(xy 41.523376 -311.418567) (xy 41.474477 -311.402679) (xy 41.428665 -311.379336) (xy 41.387069 -311.349115)
			(xy 41.350713 -311.312759) (xy 41.320492 -311.271163) (xy 41.297149 -311.225351) (xy 41.281261 -311.176452)
			(xy 41.273218 -311.12567) (xy 40.95454 -311.12567) (xy 40.946824 -311.173146) (xy 40.93124 -311.219827)
			(xy 40.908369 -311.263404) (xy 40.878804 -311.302748) (xy 40.843311 -311.33684) (xy 40.802808 -311.364796)
			(xy 40.758346 -311.385894) (xy 40.711075 -311.399586) (xy 40.66222 -311.405518) (xy 40.613045 -311.403537)
			(xy 40.564826 -311.393693) (xy 40.51881 -311.376241) (xy 40.476189 -311.351634) (xy 40.438068 -311.320509)
			(xy 40.405433 -311.283672) (xy 40.37913 -311.242076) (xy 40.359839 -311.1968) (xy 40.348062 -311.149016)
			(xy 40.344102 -311.099962) (xy 40.027098 -311.099962) (xy 40.026594 -311.12567) (xy 40.018551 -311.176452)
			(xy 40.002663 -311.225351) (xy 39.97932 -311.271163) (xy 39.949099 -311.312759) (xy 39.912743 -311.349115)
			(xy 39.871147 -311.379336) (xy 39.825335 -311.402679) (xy 39.776436 -311.418567) (xy 39.725654 -311.42661)
			(xy 39.674238 -311.42661) (xy 39.623456 -311.418567) (xy 39.574557 -311.402679) (xy 39.528745 -311.379336)
			(xy 39.487149 -311.349115) (xy 39.450793 -311.312759) (xy 39.420572 -311.271163) (xy 39.397229 -311.225351)
			(xy 39.381341 -311.176452) (xy 39.373298 -311.12567) (xy 39.05462 -311.12567) (xy 39.046904 -311.173146)
			(xy 39.03132 -311.219827) (xy 39.008449 -311.263404) (xy 38.978884 -311.302748) (xy 38.943391 -311.33684)
			(xy 38.902888 -311.364796) (xy 38.858426 -311.385894) (xy 38.811155 -311.399586) (xy 38.7623 -311.405518)
			(xy 38.713125 -311.403537) (xy 38.664906 -311.393693) (xy 38.61889 -311.376241) (xy 38.576269 -311.351634)
			(xy 38.538148 -311.320509) (xy 38.505513 -311.283672) (xy 38.47921 -311.242076) (xy 38.459919 -311.1968)
			(xy 38.448142 -311.149016) (xy 38.444182 -311.099962) (xy 38.10508 -311.099962) (xy 38.104585 -311.124569)
			(xy 38.09669 -311.173146) (xy 38.081106 -311.219827) (xy 38.058235 -311.263404) (xy 38.02867 -311.302748)
			(xy 37.993177 -311.33684) (xy 37.952674 -311.364796) (xy 37.908212 -311.385894) (xy 37.860941 -311.399586)
			(xy 37.812086 -311.405518) (xy 37.762911 -311.403537) (xy 37.714692 -311.393693) (xy 37.668676 -311.376241)
			(xy 37.626055 -311.351634) (xy 37.587934 -311.320509) (xy 37.555299 -311.283672) (xy 37.528996 -311.242076)
			(xy 37.509705 -311.1968) (xy 37.497928 -311.149016) (xy 37.493968 -311.099962) (xy 37.15512 -311.099962)
			(xy 37.154625 -311.124569) (xy 37.14673 -311.173146) (xy 37.131146 -311.219827) (xy 37.108275 -311.263404)
			(xy 37.07871 -311.302748) (xy 37.043217 -311.33684) (xy 37.002714 -311.364796) (xy 36.958252 -311.385894)
			(xy 36.910981 -311.399586) (xy 36.862126 -311.405518) (xy 36.812951 -311.403537) (xy 36.764732 -311.393693)
			(xy 36.718716 -311.376241) (xy 36.676095 -311.351634) (xy 36.637974 -311.320509) (xy 36.605339 -311.283672)
			(xy 36.579036 -311.242076) (xy 36.559745 -311.1968) (xy 36.547968 -311.149016) (xy 36.544008 -311.099962)
			(xy 35.02615 -311.099962) (xy 35.011639 -311.149382) (xy 34.988997 -311.198959) (xy 34.959531 -311.244809)
			(xy 34.92384 -311.286) (xy 34.882649 -311.321691) (xy 34.836799 -311.351157) (xy 34.787222 -311.373799)
			(xy 34.734927 -311.389154) (xy 34.680979 -311.39691) (xy 34.626477 -311.39691) (xy 34.572529 -311.389154)
			(xy 34.520234 -311.373799) (xy 34.470657 -311.351157) (xy 34.424807 -311.321691) (xy 34.383616 -311.286)
			(xy 34.347925 -311.244809) (xy 34.318459 -311.198959) (xy 34.295817 -311.149382) (xy 34.280462 -311.097087)
			(xy 34.272706 -311.043139) (xy 34.27222 -311.015888) (xy 34.272711 -310.987113) (xy 34.28137 -310.930217)
			(xy 34.298473 -310.875266) (xy 34.323634 -310.823506) (xy 34.356282 -310.776112) (xy 34.375598 -310.754776)
			(xy 34.384845 -310.74413) (xy 34.397761 -310.719082) (xy 34.40333 -310.691456) (xy 34.401129 -310.66336)
			(xy 34.391325 -310.636939) (xy 34.374666 -310.614208) (xy 34.352424 -310.596902) (xy 34.33953 -310.5912)
			(xy 34.31343 -310.580181) (xy 34.26461 -310.551434) (xy 34.220577 -310.515786) (xy 34.182297 -310.474019)
			(xy 34.150614 -310.427052) (xy 34.126222 -310.375917) (xy 34.109657 -310.321738) (xy 34.101285 -310.265705)
			(xy 34.10077 -310.237378) (xy 17.635982 -310.237378) (xy 17.635982 -310.503824) (xy 17.636641 -310.512555)
			(xy 17.643136 -310.528799) (xy 17.648682 -310.535574) (xy 17.64919 -310.536082) (xy 17.654016 -310.540908)
			(xy 17.713452 -310.590692) (xy 17.717816 -310.594139) (xy 17.72768 -310.599266) (xy 17.73301 -310.600852)
			(xy 17.743932 -310.6039) (xy 17.755108 -310.601868) (xy 17.771426 -310.599227) (xy 17.804365 -310.596426)
			(xy 17.820894 -310.59628) (xy 17.84517 -310.596711) (xy 17.893321 -310.602958) (xy 17.916906 -310.608726)
			(xy 17.923301 -310.610198) (xy 17.936419 -310.610198) (xy 17.942814 -310.608726) (xy 17.966458 -310.602927)
			(xy 18.014739 -310.596688) (xy 18.03908 -310.59628) (xy 18.066349 -310.596766) (xy 18.120333 -310.604528)
			(xy 18.172662 -310.619893) (xy 18.222272 -310.642549) (xy 18.268152 -310.672035) (xy 18.30937 -310.70775)
			(xy 18.345085 -310.748968) (xy 18.374571 -310.794848) (xy 18.39165 -310.832246) (xy 28.267912 -310.832246)
			(xy 28.271983 -310.776624) (xy 28.284109 -310.722187) (xy 28.304032 -310.670096) (xy 28.331328 -310.621461)
			(xy 28.365414 -310.577318) (xy 28.405563 -310.538609) (xy 28.450921 -310.506158) (xy 28.500521 -310.480657)
			(xy 28.553305 -310.46265) (xy 28.608148 -310.45252) (xy 28.663882 -310.450483) (xy 28.719319 -310.456583)
			(xy 28.773276 -310.470689) (xy 28.824605 -310.492501) (xy 28.872211 -310.521555) (xy 28.915079 -310.55723)
			(xy 28.952296 -310.598767) (xy 28.983069 -310.64528) (xy 29.006741 -310.695777) (xy 29.022809 -310.749184)
			(xy 29.030929 -310.80436) (xy 29.031438 -310.832246) (xy 29.030929 -310.860132) (xy 29.022809 -310.915308)
			(xy 29.006741 -310.968715) (xy 28.983069 -311.019212) (xy 28.952296 -311.065725) (xy 28.915079 -311.107262)
			(xy 28.872211 -311.142937) (xy 28.824605 -311.171991) (xy 28.773276 -311.193803) (xy 28.719319 -311.207909)
			(xy 28.663882 -311.214009) (xy 28.608148 -311.211972) (xy 28.553305 -311.201842) (xy 28.500521 -311.183835)
			(xy 28.450921 -311.158334) (xy 28.405563 -311.125883) (xy 28.365414 -311.087174) (xy 28.331328 -311.043031)
			(xy 28.304032 -310.994396) (xy 28.284109 -310.942305) (xy 28.271983 -310.887868) (xy 28.267912 -310.832246)
			(xy 18.39165 -310.832246) (xy 18.397227 -310.844458) (xy 18.412592 -310.896787) (xy 18.420354 -310.950771)
			(xy 18.420354 -311.005309) (xy 18.412592 -311.059293) (xy 18.397227 -311.111622) (xy 18.374571 -311.161232)
			(xy 18.345085 -311.207112) (xy 18.30937 -311.24833) (xy 18.268152 -311.284045) (xy 18.222272 -311.313531)
			(xy 18.172662 -311.336187) (xy 18.120333 -311.351552) (xy 18.066349 -311.359314) (xy 18.03908 -311.359804)
			(xy 18.01474 -311.359386) (xy 17.966461 -311.353141) (xy 17.942814 -311.347358) (xy 17.936419 -311.345886)
			(xy 17.923301 -311.345886) (xy 17.916906 -311.347358) (xy 17.893325 -311.353147) (xy 17.845172 -311.359388)
			(xy 17.820894 -311.359804) (xy 17.804365 -311.35966) (xy 17.771426 -311.356858) (xy 17.755108 -311.354216)
			(xy 17.743932 -311.352184) (xy 17.73301 -311.355232) (xy 17.727668 -311.35679) (xy 17.717795 -311.361915)
			(xy 17.713452 -311.365392) (xy 17.654016 -311.415176) (xy 17.64919 -311.420002) (xy 17.648682 -311.42051)
			(xy 17.643185 -311.427313) (xy 17.636697 -311.443543) (xy 17.635982 -311.45226) (xy 17.635982 -311.7088)
			(xy 17.637253 -311.719859) (xy 17.647921 -311.739368) (xy 17.656556 -311.746392) (xy 17.664684 -311.751218)
			(xy 17.746726 -311.791096) (xy 17.755418 -311.794808) (xy 17.774241 -311.796326) (xy 17.792346 -311.790958)
			(xy 17.800066 -311.785508) (xy 17.80032 -311.785508) (xy 17.820529 -311.770183) (xy 17.864232 -311.744445)
			(xy 17.910963 -311.72473) (xy 17.959895 -311.711387) (xy 18.010165 -311.70465) (xy 18.035524 -311.704228)
			(xy 18.062775 -311.704714) (xy 18.116723 -311.712471) (xy 18.169018 -311.727827) (xy 18.218595 -311.750468)
			(xy 18.264446 -311.779935) (xy 18.305636 -311.815627) (xy 18.312111 -311.8231) (xy 32.447482 -311.8231)
			(xy 32.451553 -311.767478) (xy 32.463679 -311.713041) (xy 32.483602 -311.66095) (xy 32.510898 -311.612315)
			(xy 32.544984 -311.568172) (xy 32.585133 -311.529463) (xy 32.630491 -311.497012) (xy 32.680091 -311.471511)
			(xy 32.732875 -311.453504) (xy 32.787718 -311.443374) (xy 32.843452 -311.441337) (xy 32.898889 -311.447437)
			(xy 32.952846 -311.461543) (xy 33.004175 -311.483355) (xy 33.051781 -311.512409) (xy 33.094649 -311.548084)
			(xy 33.131866 -311.589621) (xy 33.162639 -311.636134) (xy 33.186311 -311.686631) (xy 33.202379 -311.740038)
			(xy 33.210499 -311.795214) (xy 33.211008 -311.8231) (xy 33.210499 -311.850986) (xy 33.202379 -311.906162)
			(xy 33.186311 -311.959569) (xy 33.162639 -312.010066) (xy 33.131866 -312.056579) (xy 33.094649 -312.098116)
			(xy 33.051781 -312.133791) (xy 33.004175 -312.162845) (xy 32.952846 -312.184657) (xy 32.898889 -312.198763)
			(xy 32.843452 -312.204863) (xy 32.787718 -312.202826) (xy 32.732875 -312.192696) (xy 32.680091 -312.174689)
			(xy 32.630491 -312.149188) (xy 32.585133 -312.116737) (xy 32.544984 -312.078028) (xy 32.510898 -312.033885)
			(xy 32.483602 -311.98525) (xy 32.463679 -311.933159) (xy 32.451553 -311.878722) (xy 32.447482 -311.8231)
			(xy 18.312111 -311.8231) (xy 18.341327 -311.856818) (xy 18.370794 -311.902668) (xy 18.393435 -311.952246)
			(xy 18.40879 -312.004541) (xy 18.416546 -312.058489) (xy 18.416546 -312.112991) (xy 18.40879 -312.166939)
			(xy 18.393435 -312.219234) (xy 18.370794 -312.268812) (xy 18.341327 -312.314662) (xy 18.305636 -312.355853)
			(xy 18.264446 -312.391545) (xy 18.218595 -312.421012) (xy 18.169018 -312.443653) (xy 18.116723 -312.459009)
			(xy 18.062775 -312.466766) (xy 18.035524 -312.467244) (xy 18.010166 -312.466811) (xy 17.9599 -312.460061)
			(xy 17.91097 -312.446716) (xy 17.864238 -312.427011) (xy 17.820525 -312.401293) (xy 17.80032 -312.385964)
			(xy 17.800066 -312.385964) (xy 17.792374 -312.38044) (xy 17.774247 -312.375006) (xy 17.755386 -312.376546)
			(xy 17.746726 -312.380376) (xy 17.664684 -312.420254) (xy 17.656556 -312.42508) (xy 17.647951 -312.432132)
			(xy 17.637271 -312.451622) (xy 17.635982 -312.462672) (xy 17.635982 -312.523378) (xy 31.731964 -312.523378)
			(xy 31.736035 -312.467756) (xy 31.748161 -312.413319) (xy 31.768084 -312.361228) (xy 31.79538 -312.312593)
			(xy 31.829466 -312.26845) (xy 31.869615 -312.229741) (xy 31.914973 -312.19729) (xy 31.964573 -312.171789)
			(xy 32.017357 -312.153782) (xy 32.0722 -312.143652) (xy 32.127934 -312.141615) (xy 32.183371 -312.147715)
			(xy 32.237328 -312.161821) (xy 32.288657 -312.183633) (xy 32.336263 -312.212687) (xy 32.379131 -312.248362)
			(xy 32.396823 -312.268108) (xy 34.021774 -312.268108) (xy 34.025845 -312.212486) (xy 34.037971 -312.158049)
			(xy 34.057894 -312.105958) (xy 34.08519 -312.057323) (xy 34.119276 -312.01318) (xy 34.159425 -311.974471)
			(xy 34.204783 -311.94202) (xy 34.254383 -311.916519) (xy 34.307167 -311.898512) (xy 34.36201 -311.888382)
			(xy 34.417744 -311.886345) (xy 34.473181 -311.892445) (xy 34.527138 -311.906551) (xy 34.578467 -311.928363)
			(xy 34.626073 -311.957417) (xy 34.668941 -311.993092) (xy 34.706158 -312.034629) (xy 34.716108 -312.049668)
			(xy 35.593794 -312.049668) (xy 35.597754 -312.000614) (xy 35.609531 -311.95283) (xy 35.628822 -311.907554)
			(xy 35.655125 -311.865958) (xy 35.68776 -311.829121) (xy 35.725881 -311.797996) (xy 35.768502 -311.773389)
			(xy 35.814518 -311.755937) (xy 35.862737 -311.746093) (xy 35.911912 -311.744112) (xy 35.960767 -311.750044)
			(xy 36.008038 -311.763736) (xy 36.0525 -311.784834) (xy 36.093003 -311.81279) (xy 36.128496 -311.846882)
			(xy 36.158061 -311.886226) (xy 36.180932 -311.929803) (xy 36.196516 -311.976484) (xy 36.204411 -312.025061)
			(xy 36.204906 -312.049668) (xy 36.204411 -312.074275) (xy 36.204191 -312.07563) (xy 36.523164 -312.07563)
			(xy 36.523164 -312.024214) (xy 36.531207 -311.973432) (xy 36.547095 -311.924533) (xy 36.570438 -311.878721)
			(xy 36.600659 -311.837125) (xy 36.637015 -311.800769) (xy 36.678611 -311.770548) (xy 36.724423 -311.747205)
			(xy 36.773322 -311.731317) (xy 36.824104 -311.723274) (xy 36.87552 -311.723274) (xy 36.926302 -311.731317)
			(xy 36.975201 -311.747205) (xy 37.021013 -311.770548) (xy 37.062609 -311.800769) (xy 37.098965 -311.837125)
			(xy 37.129186 -311.878721) (xy 37.152529 -311.924533) (xy 37.168417 -311.973432) (xy 37.17646 -312.024214)
			(xy 37.176964 -312.049922) (xy 37.17646 -312.07563) (xy 37.473124 -312.07563) (xy 37.473124 -312.024214)
			(xy 37.481167 -311.973432) (xy 37.497055 -311.924533) (xy 37.520398 -311.878721) (xy 37.550619 -311.837125)
			(xy 37.586975 -311.800769) (xy 37.628571 -311.770548) (xy 37.674383 -311.747205) (xy 37.723282 -311.731317)
			(xy 37.774064 -311.723274) (xy 37.82548 -311.723274) (xy 37.876262 -311.731317) (xy 37.925161 -311.747205)
			(xy 37.970973 -311.770548) (xy 38.012569 -311.800769) (xy 38.048925 -311.837125) (xy 38.079146 -311.878721)
			(xy 38.102489 -311.924533) (xy 38.118377 -311.973432) (xy 38.12642 -312.024214) (xy 38.126924 -312.049922)
			(xy 38.444182 -312.049922) (xy 38.448142 -312.000868) (xy 38.459919 -311.953084) (xy 38.47921 -311.907808)
			(xy 38.505513 -311.866212) (xy 38.538148 -311.829375) (xy 38.576269 -311.79825) (xy 38.61889 -311.773643)
			(xy 38.664906 -311.756191) (xy 38.713125 -311.746347) (xy 38.7623 -311.744366) (xy 38.811155 -311.750298)
			(xy 38.858426 -311.76399) (xy 38.902888 -311.785088) (xy 38.943391 -311.813044) (xy 38.978884 -311.847136)
			(xy 39.008449 -311.88648) (xy 39.03132 -311.930057) (xy 39.046904 -311.976738) (xy 39.054799 -312.025315)
			(xy 39.055294 -312.049922) (xy 39.054799 -312.074529) (xy 39.05462 -312.07563) (xy 39.373298 -312.07563)
			(xy 39.373298 -312.024214) (xy 39.381341 -311.973432) (xy 39.397229 -311.924533) (xy 39.420572 -311.878721)
			(xy 39.450793 -311.837125) (xy 39.487149 -311.800769) (xy 39.528745 -311.770548) (xy 39.574557 -311.747205)
			(xy 39.623456 -311.731317) (xy 39.674238 -311.723274) (xy 39.725654 -311.723274) (xy 39.776436 -311.731317)
			(xy 39.825335 -311.747205) (xy 39.871147 -311.770548) (xy 39.912743 -311.800769) (xy 39.949099 -311.837125)
			(xy 39.97932 -311.878721) (xy 40.002663 -311.924533) (xy 40.018551 -311.973432) (xy 40.026594 -312.024214)
			(xy 40.027098 -312.049922) (xy 40.344102 -312.049922) (xy 40.348062 -312.000868) (xy 40.359839 -311.953084)
			(xy 40.37913 -311.907808) (xy 40.405433 -311.866212) (xy 40.438068 -311.829375) (xy 40.476189 -311.79825)
			(xy 40.51881 -311.773643) (xy 40.564826 -311.756191) (xy 40.613045 -311.746347) (xy 40.66222 -311.744366)
			(xy 40.711075 -311.750298) (xy 40.758346 -311.76399) (xy 40.802808 -311.785088) (xy 40.843311 -311.813044)
			(xy 40.878804 -311.847136) (xy 40.908369 -311.88648) (xy 40.93124 -311.930057) (xy 40.946824 -311.976738)
			(xy 40.954719 -312.025315) (xy 40.955214 -312.049922) (xy 40.954719 -312.074529) (xy 40.95454 -312.07563)
			(xy 41.273218 -312.07563) (xy 41.273218 -312.024214) (xy 41.281261 -311.973432) (xy 41.297149 -311.924533)
			(xy 41.320492 -311.878721) (xy 41.350713 -311.837125) (xy 41.387069 -311.800769) (xy 41.428665 -311.770548)
			(xy 41.474477 -311.747205) (xy 41.523376 -311.731317) (xy 41.574158 -311.723274) (xy 41.625574 -311.723274)
			(xy 41.676356 -311.731317) (xy 41.725255 -311.747205) (xy 41.771067 -311.770548) (xy 41.812663 -311.800769)
			(xy 41.849019 -311.837125) (xy 41.87924 -311.878721) (xy 41.902583 -311.924533) (xy 41.918471 -311.973432)
			(xy 41.926514 -312.024214) (xy 41.927018 -312.049922) (xy 42.244022 -312.049922) (xy 42.247982 -312.000868)
			(xy 42.259759 -311.953084) (xy 42.27905 -311.907808) (xy 42.305353 -311.866212) (xy 42.337988 -311.829375)
			(xy 42.376109 -311.79825) (xy 42.41873 -311.773643) (xy 42.464746 -311.756191) (xy 42.512965 -311.746347)
			(xy 42.56214 -311.744366) (xy 42.610995 -311.750298) (xy 42.658266 -311.76399) (xy 42.702728 -311.785088)
			(xy 42.743231 -311.813044) (xy 42.778724 -311.847136) (xy 42.808289 -311.88648) (xy 42.83116 -311.930057)
			(xy 42.846744 -311.976738) (xy 42.854639 -312.025315) (xy 42.855134 -312.049922) (xy 43.193982 -312.049922)
			(xy 43.197942 -312.000868) (xy 43.209719 -311.953084) (xy 43.22901 -311.907808) (xy 43.255313 -311.866212)
			(xy 43.287948 -311.829375) (xy 43.326069 -311.79825) (xy 43.36869 -311.773643) (xy 43.414706 -311.756191)
			(xy 43.462925 -311.746347) (xy 43.5121 -311.744366) (xy 43.560955 -311.750298) (xy 43.608226 -311.76399)
			(xy 43.652688 -311.785088) (xy 43.693191 -311.813044) (xy 43.728684 -311.847136) (xy 43.758249 -311.88648)
			(xy 43.78112 -311.930057) (xy 43.796704 -311.976738) (xy 43.804599 -312.025315) (xy 43.805094 -312.049922)
			(xy 44.143942 -312.049922) (xy 44.147902 -312.000868) (xy 44.159679 -311.953084) (xy 44.17897 -311.907808)
			(xy 44.205273 -311.866212) (xy 44.237908 -311.829375) (xy 44.276029 -311.79825) (xy 44.31865 -311.773643)
			(xy 44.364666 -311.756191) (xy 44.412885 -311.746347) (xy 44.46206 -311.744366) (xy 44.510915 -311.750298)
			(xy 44.558186 -311.76399) (xy 44.602648 -311.785088) (xy 44.643151 -311.813044) (xy 44.678644 -311.847136)
			(xy 44.708209 -311.88648) (xy 44.73108 -311.930057) (xy 44.746664 -311.976738) (xy 44.754559 -312.025315)
			(xy 44.755054 -312.049922) (xy 45.094156 -312.049922) (xy 45.098116 -312.000868) (xy 45.109893 -311.953084)
			(xy 45.129184 -311.907808) (xy 45.155487 -311.866212) (xy 45.188122 -311.829375) (xy 45.226243 -311.79825)
			(xy 45.268864 -311.773643) (xy 45.31488 -311.756191) (xy 45.363099 -311.746347) (xy 45.412274 -311.744366)
			(xy 45.461129 -311.750298) (xy 45.5084 -311.76399) (xy 45.552862 -311.785088) (xy 45.593365 -311.813044)
			(xy 45.628858 -311.847136) (xy 45.658423 -311.88648) (xy 45.681294 -311.930057) (xy 45.696878 -311.976738)
			(xy 45.704773 -312.025315) (xy 45.705268 -312.049922) (xy 46.044116 -312.049922) (xy 46.048076 -312.000868)
			(xy 46.059853 -311.953084) (xy 46.079144 -311.907808) (xy 46.105447 -311.866212) (xy 46.138082 -311.829375)
			(xy 46.176203 -311.79825) (xy 46.218824 -311.773643) (xy 46.26484 -311.756191) (xy 46.313059 -311.746347)
			(xy 46.362234 -311.744366) (xy 46.411089 -311.750298) (xy 46.45836 -311.76399) (xy 46.502822 -311.785088)
			(xy 46.543325 -311.813044) (xy 46.578818 -311.847136) (xy 46.608383 -311.88648) (xy 46.631254 -311.930057)
			(xy 46.646838 -311.976738) (xy 46.654733 -312.025315) (xy 46.655228 -312.049922) (xy 46.994076 -312.049922)
			(xy 46.998036 -312.000868) (xy 47.009813 -311.953084) (xy 47.029104 -311.907808) (xy 47.055407 -311.866212)
			(xy 47.088042 -311.829375) (xy 47.126163 -311.79825) (xy 47.168784 -311.773643) (xy 47.2148 -311.756191)
			(xy 47.263019 -311.746347) (xy 47.312194 -311.744366) (xy 47.361049 -311.750298) (xy 47.40832 -311.76399)
			(xy 47.452782 -311.785088) (xy 47.493285 -311.813044) (xy 47.528778 -311.847136) (xy 47.558343 -311.88648)
			(xy 47.581214 -311.930057) (xy 47.596798 -311.976738) (xy 47.604693 -312.025315) (xy 47.605188 -312.049922)
			(xy 47.944036 -312.049922) (xy 47.947996 -312.000868) (xy 47.959773 -311.953084) (xy 47.979064 -311.907808)
			(xy 48.005367 -311.866212) (xy 48.038002 -311.829375) (xy 48.076123 -311.79825) (xy 48.118744 -311.773643)
			(xy 48.16476 -311.756191) (xy 48.212979 -311.746347) (xy 48.262154 -311.744366) (xy 48.311009 -311.750298)
			(xy 48.35828 -311.76399) (xy 48.402742 -311.785088) (xy 48.443245 -311.813044) (xy 48.478738 -311.847136)
			(xy 48.508303 -311.88648) (xy 48.531174 -311.930057) (xy 48.546758 -311.976738) (xy 48.554653 -312.025315)
			(xy 48.555148 -312.049922) (xy 48.893996 -312.049922) (xy 48.897956 -312.000868) (xy 48.909733 -311.953084)
			(xy 48.929024 -311.907808) (xy 48.955327 -311.866212) (xy 48.987962 -311.829375) (xy 49.026083 -311.79825)
			(xy 49.068704 -311.773643) (xy 49.11472 -311.756191) (xy 49.162939 -311.746347) (xy 49.212114 -311.744366)
			(xy 49.260969 -311.750298) (xy 49.30824 -311.76399) (xy 49.352702 -311.785088) (xy 49.393205 -311.813044)
			(xy 49.428698 -311.847136) (xy 49.458263 -311.88648) (xy 49.481134 -311.930057) (xy 49.496718 -311.976738)
			(xy 49.504613 -312.025315) (xy 49.505108 -312.049922) (xy 49.843956 -312.049922) (xy 49.847916 -312.000868)
			(xy 49.859693 -311.953084) (xy 49.878984 -311.907808) (xy 49.905287 -311.866212) (xy 49.937922 -311.829375)
			(xy 49.976043 -311.79825) (xy 50.018664 -311.773643) (xy 50.06468 -311.756191) (xy 50.112899 -311.746347)
			(xy 50.162074 -311.744366) (xy 50.210929 -311.750298) (xy 50.2582 -311.76399) (xy 50.302662 -311.785088)
			(xy 50.343165 -311.813044) (xy 50.378658 -311.847136) (xy 50.408223 -311.88648) (xy 50.431094 -311.930057)
			(xy 50.446678 -311.976738) (xy 50.454573 -312.025315) (xy 50.455068 -312.049922) (xy 50.79417 -312.049922)
			(xy 50.79813 -312.000868) (xy 50.809907 -311.953084) (xy 50.829198 -311.907808) (xy 50.855501 -311.866212)
			(xy 50.888136 -311.829375) (xy 50.926257 -311.79825) (xy 50.968878 -311.773643) (xy 51.014894 -311.756191)
			(xy 51.063113 -311.746347) (xy 51.112288 -311.744366) (xy 51.161143 -311.750298) (xy 51.208414 -311.76399)
			(xy 51.252876 -311.785088) (xy 51.293379 -311.813044) (xy 51.328872 -311.847136) (xy 51.358437 -311.88648)
			(xy 51.381308 -311.930057) (xy 51.396892 -311.976738) (xy 51.404787 -312.025315) (xy 51.405282 -312.049922)
			(xy 51.74413 -312.049922) (xy 51.74809 -312.000868) (xy 51.759867 -311.953084) (xy 51.779158 -311.907808)
			(xy 51.805461 -311.866212) (xy 51.838096 -311.829375) (xy 51.876217 -311.79825) (xy 51.918838 -311.773643)
			(xy 51.964854 -311.756191) (xy 52.013073 -311.746347) (xy 52.062248 -311.744366) (xy 52.111103 -311.750298)
			(xy 52.158374 -311.76399) (xy 52.202836 -311.785088) (xy 52.243339 -311.813044) (xy 52.278832 -311.847136)
			(xy 52.308397 -311.88648) (xy 52.331268 -311.930057) (xy 52.346852 -311.976738) (xy 52.354747 -312.025315)
			(xy 52.355242 -312.049922) (xy 52.69409 -312.049922) (xy 52.69805 -312.000868) (xy 52.709827 -311.953084)
			(xy 52.729118 -311.907808) (xy 52.755421 -311.866212) (xy 52.788056 -311.829375) (xy 52.826177 -311.79825)
			(xy 52.868798 -311.773643) (xy 52.914814 -311.756191) (xy 52.963033 -311.746347) (xy 53.012208 -311.744366)
			(xy 53.061063 -311.750298) (xy 53.108334 -311.76399) (xy 53.152796 -311.785088) (xy 53.193299 -311.813044)
			(xy 53.228792 -311.847136) (xy 53.258357 -311.88648) (xy 53.281228 -311.930057) (xy 53.296812 -311.976738)
			(xy 53.304707 -312.025315) (xy 53.305202 -312.049922) (xy 53.64405 -312.049922) (xy 53.64801 -312.000868)
			(xy 53.659787 -311.953084) (xy 53.679078 -311.907808) (xy 53.705381 -311.866212) (xy 53.738016 -311.829375)
			(xy 53.776137 -311.79825) (xy 53.818758 -311.773643) (xy 53.864774 -311.756191) (xy 53.912993 -311.746347)
			(xy 53.962168 -311.744366) (xy 54.011023 -311.750298) (xy 54.058294 -311.76399) (xy 54.102756 -311.785088)
			(xy 54.143259 -311.813044) (xy 54.178752 -311.847136) (xy 54.208317 -311.88648) (xy 54.231188 -311.930057)
			(xy 54.246772 -311.976738) (xy 54.254667 -312.025315) (xy 54.255162 -312.049922) (xy 54.59401 -312.049922)
			(xy 54.59797 -312.000868) (xy 54.609747 -311.953084) (xy 54.629038 -311.907808) (xy 54.655341 -311.866212)
			(xy 54.687976 -311.829375) (xy 54.726097 -311.79825) (xy 54.768718 -311.773643) (xy 54.814734 -311.756191)
			(xy 54.862953 -311.746347) (xy 54.912128 -311.744366) (xy 54.960983 -311.750298) (xy 55.008254 -311.76399)
			(xy 55.052716 -311.785088) (xy 55.093219 -311.813044) (xy 55.128712 -311.847136) (xy 55.158277 -311.88648)
			(xy 55.181148 -311.930057) (xy 55.196732 -311.976738) (xy 55.204627 -312.025315) (xy 55.205122 -312.049922)
			(xy 55.54397 -312.049922) (xy 55.54793 -312.000868) (xy 55.559707 -311.953084) (xy 55.578998 -311.907808)
			(xy 55.605301 -311.866212) (xy 55.637936 -311.829375) (xy 55.676057 -311.79825) (xy 55.718678 -311.773643)
			(xy 55.764694 -311.756191) (xy 55.812913 -311.746347) (xy 55.862088 -311.744366) (xy 55.910943 -311.750298)
			(xy 55.958214 -311.76399) (xy 56.002676 -311.785088) (xy 56.043179 -311.813044) (xy 56.078672 -311.847136)
			(xy 56.108237 -311.88648) (xy 56.131108 -311.930057) (xy 56.146692 -311.976738) (xy 56.154587 -312.025315)
			(xy 56.155082 -312.049922) (xy 56.494184 -312.049922) (xy 56.498144 -312.000868) (xy 56.509921 -311.953084)
			(xy 56.529212 -311.907808) (xy 56.555515 -311.866212) (xy 56.58815 -311.829375) (xy 56.626271 -311.79825)
			(xy 56.668892 -311.773643) (xy 56.714908 -311.756191) (xy 56.763127 -311.746347) (xy 56.812302 -311.744366)
			(xy 56.861157 -311.750298) (xy 56.908428 -311.76399) (xy 56.95289 -311.785088) (xy 56.993393 -311.813044)
			(xy 57.028886 -311.847136) (xy 57.058451 -311.88648) (xy 57.081322 -311.930057) (xy 57.096906 -311.976738)
			(xy 57.104801 -312.025315) (xy 57.105296 -312.049922) (xy 57.444144 -312.049922) (xy 57.448104 -312.000868)
			(xy 57.459881 -311.953084) (xy 57.479172 -311.907808) (xy 57.505475 -311.866212) (xy 57.53811 -311.829375)
			(xy 57.576231 -311.79825) (xy 57.618852 -311.773643) (xy 57.664868 -311.756191) (xy 57.713087 -311.746347)
			(xy 57.762262 -311.744366) (xy 57.811117 -311.750298) (xy 57.858388 -311.76399) (xy 57.90285 -311.785088)
			(xy 57.943353 -311.813044) (xy 57.978846 -311.847136) (xy 58.008411 -311.88648) (xy 58.031282 -311.930057)
			(xy 58.046866 -311.976738) (xy 58.054761 -312.025315) (xy 58.055256 -312.049922) (xy 58.054761 -312.074529)
			(xy 58.054582 -312.07563) (xy 58.37326 -312.07563) (xy 58.37326 -312.024214) (xy 58.381303 -311.973432)
			(xy 58.397191 -311.924533) (xy 58.420534 -311.878721) (xy 58.450755 -311.837125) (xy 58.487111 -311.800769)
			(xy 58.528707 -311.770548) (xy 58.574519 -311.747205) (xy 58.623418 -311.731317) (xy 58.6742 -311.723274)
			(xy 58.725616 -311.723274) (xy 58.776398 -311.731317) (xy 58.825297 -311.747205) (xy 58.871109 -311.770548)
			(xy 58.912705 -311.800769) (xy 58.949061 -311.837125) (xy 58.979282 -311.878721) (xy 59.002625 -311.924533)
			(xy 59.018513 -311.973432) (xy 59.026556 -312.024214) (xy 59.02706 -312.049922) (xy 59.344064 -312.049922)
			(xy 59.348024 -312.000868) (xy 59.359801 -311.953084) (xy 59.379092 -311.907808) (xy 59.405395 -311.866212)
			(xy 59.43803 -311.829375) (xy 59.476151 -311.79825) (xy 59.518772 -311.773643) (xy 59.564788 -311.756191)
			(xy 59.613007 -311.746347) (xy 59.662182 -311.744366) (xy 59.711037 -311.750298) (xy 59.758308 -311.76399)
			(xy 59.80277 -311.785088) (xy 59.843273 -311.813044) (xy 59.878766 -311.847136) (xy 59.908331 -311.88648)
			(xy 59.931202 -311.930057) (xy 59.946786 -311.976738) (xy 59.954681 -312.025315) (xy 59.955176 -312.049922)
			(xy 59.954681 -312.074529) (xy 59.954502 -312.07563) (xy 60.27318 -312.07563) (xy 60.27318 -312.024214)
			(xy 60.281223 -311.973432) (xy 60.297111 -311.924533) (xy 60.320454 -311.878721) (xy 60.350675 -311.837125)
			(xy 60.387031 -311.800769) (xy 60.428627 -311.770548) (xy 60.474439 -311.747205) (xy 60.523338 -311.731317)
			(xy 60.57412 -311.723274) (xy 60.625536 -311.723274) (xy 60.676318 -311.731317) (xy 60.725217 -311.747205)
			(xy 60.771029 -311.770548) (xy 60.812625 -311.800769) (xy 60.848981 -311.837125) (xy 60.879202 -311.878721)
			(xy 60.902545 -311.924533) (xy 60.918433 -311.973432) (xy 60.926476 -312.024214) (xy 60.92698 -312.049922)
			(xy 61.243984 -312.049922) (xy 61.247944 -312.000868) (xy 61.259721 -311.953084) (xy 61.279012 -311.907808)
			(xy 61.305315 -311.866212) (xy 61.33795 -311.829375) (xy 61.376071 -311.79825) (xy 61.418692 -311.773643)
			(xy 61.464708 -311.756191) (xy 61.512927 -311.746347) (xy 61.562102 -311.744366) (xy 61.610957 -311.750298)
			(xy 61.658228 -311.76399) (xy 61.70269 -311.785088) (xy 61.743193 -311.813044) (xy 61.778686 -311.847136)
			(xy 61.808251 -311.88648) (xy 61.831122 -311.930057) (xy 61.846706 -311.976738) (xy 61.854601 -312.025315)
			(xy 61.855096 -312.049922) (xy 61.854601 -312.074529) (xy 61.854422 -312.07563) (xy 62.1731 -312.07563)
			(xy 62.1731 -312.024214) (xy 62.181143 -311.973432) (xy 62.197031 -311.924533) (xy 62.220374 -311.878721)
			(xy 62.250595 -311.837125) (xy 62.286951 -311.800769) (xy 62.328547 -311.770548) (xy 62.374359 -311.747205)
			(xy 62.423258 -311.731317) (xy 62.47404 -311.723274) (xy 62.525456 -311.723274) (xy 62.576238 -311.731317)
			(xy 62.625137 -311.747205) (xy 62.670949 -311.770548) (xy 62.712545 -311.800769) (xy 62.748901 -311.837125)
			(xy 62.779122 -311.878721) (xy 62.802465 -311.924533) (xy 62.818353 -311.973432) (xy 62.826396 -312.024214)
			(xy 62.8269 -312.049922) (xy 63.144158 -312.049922) (xy 63.148118 -312.000868) (xy 63.159895 -311.953084)
			(xy 63.179186 -311.907808) (xy 63.205489 -311.866212) (xy 63.238124 -311.829375) (xy 63.276245 -311.79825)
			(xy 63.318866 -311.773643) (xy 63.364882 -311.756191) (xy 63.413101 -311.746347) (xy 63.462276 -311.744366)
			(xy 63.511131 -311.750298) (xy 63.558402 -311.76399) (xy 63.602864 -311.785088) (xy 63.643367 -311.813044)
			(xy 63.67886 -311.847136) (xy 63.708425 -311.88648) (xy 63.731296 -311.930057) (xy 63.74688 -311.976738)
			(xy 63.754775 -312.025315) (xy 63.75527 -312.049922) (xy 63.754775 -312.074529) (xy 63.754596 -312.07563)
			(xy 64.073274 -312.07563) (xy 64.073274 -312.024214) (xy 64.081317 -311.973432) (xy 64.097205 -311.924533)
			(xy 64.120548 -311.878721) (xy 64.150769 -311.837125) (xy 64.187125 -311.800769) (xy 64.228721 -311.770548)
			(xy 64.274533 -311.747205) (xy 64.323432 -311.731317) (xy 64.374214 -311.723274) (xy 64.42563 -311.723274)
			(xy 64.476412 -311.731317) (xy 64.525311 -311.747205) (xy 64.571123 -311.770548) (xy 64.612719 -311.800769)
			(xy 64.649075 -311.837125) (xy 64.679296 -311.878721) (xy 64.702639 -311.924533) (xy 64.718527 -311.973432)
			(xy 64.72657 -312.024214) (xy 64.727074 -312.049922) (xy 65.044078 -312.049922) (xy 65.048038 -312.000868)
			(xy 65.059815 -311.953084) (xy 65.079106 -311.907808) (xy 65.105409 -311.866212) (xy 65.138044 -311.829375)
			(xy 65.176165 -311.79825) (xy 65.218786 -311.773643) (xy 65.264802 -311.756191) (xy 65.313021 -311.746347)
			(xy 65.362196 -311.744366) (xy 65.411051 -311.750298) (xy 65.458322 -311.76399) (xy 65.502784 -311.785088)
			(xy 65.543287 -311.813044) (xy 65.57878 -311.847136) (xy 65.608345 -311.88648) (xy 65.631216 -311.930057)
			(xy 65.6468 -311.976738) (xy 65.654695 -312.025315) (xy 65.65519 -312.049922) (xy 65.654695 -312.074529)
			(xy 65.654516 -312.07563) (xy 65.973194 -312.07563) (xy 65.973194 -312.024214) (xy 65.981237 -311.973432)
			(xy 65.997125 -311.924533) (xy 66.020468 -311.878721) (xy 66.050689 -311.837125) (xy 66.087045 -311.800769)
			(xy 66.128641 -311.770548) (xy 66.174453 -311.747205) (xy 66.223352 -311.731317) (xy 66.274134 -311.723274)
			(xy 66.32555 -311.723274) (xy 66.376332 -311.731317) (xy 66.425231 -311.747205) (xy 66.471043 -311.770548)
			(xy 66.512639 -311.800769) (xy 66.548995 -311.837125) (xy 66.579216 -311.878721) (xy 66.602559 -311.924533)
			(xy 66.618447 -311.973432) (xy 66.62649 -312.024214) (xy 66.626994 -312.049922) (xy 66.943998 -312.049922)
			(xy 66.947958 -312.000868) (xy 66.959735 -311.953084) (xy 66.979026 -311.907808) (xy 67.005329 -311.866212)
			(xy 67.037964 -311.829375) (xy 67.076085 -311.79825) (xy 67.118706 -311.773643) (xy 67.164722 -311.756191)
			(xy 67.212941 -311.746347) (xy 67.262116 -311.744366) (xy 67.310971 -311.750298) (xy 67.358242 -311.76399)
			(xy 67.402704 -311.785088) (xy 67.443207 -311.813044) (xy 67.4787 -311.847136) (xy 67.508265 -311.88648)
			(xy 67.531136 -311.930057) (xy 67.54672 -311.976738) (xy 67.554615 -312.025315) (xy 67.55511 -312.049922)
			(xy 67.554615 -312.074529) (xy 67.554436 -312.07563) (xy 67.873114 -312.07563) (xy 67.873114 -312.024214)
			(xy 67.881157 -311.973432) (xy 67.897045 -311.924533) (xy 67.920388 -311.878721) (xy 67.950609 -311.837125)
			(xy 67.986965 -311.800769) (xy 68.028561 -311.770548) (xy 68.074373 -311.747205) (xy 68.123272 -311.731317)
			(xy 68.174054 -311.723274) (xy 68.22547 -311.723274) (xy 68.276252 -311.731317) (xy 68.325151 -311.747205)
			(xy 68.370963 -311.770548) (xy 68.412559 -311.800769) (xy 68.448915 -311.837125) (xy 68.479136 -311.878721)
			(xy 68.502479 -311.924533) (xy 68.518367 -311.973432) (xy 68.52641 -312.024214) (xy 68.526914 -312.049922)
			(xy 68.844172 -312.049922) (xy 68.848132 -312.000868) (xy 68.859909 -311.953084) (xy 68.8792 -311.907808)
			(xy 68.905503 -311.866212) (xy 68.938138 -311.829375) (xy 68.976259 -311.79825) (xy 69.01888 -311.773643)
			(xy 69.064896 -311.756191) (xy 69.113115 -311.746347) (xy 69.16229 -311.744366) (xy 69.211145 -311.750298)
			(xy 69.258416 -311.76399) (xy 69.302878 -311.785088) (xy 69.343381 -311.813044) (xy 69.378874 -311.847136)
			(xy 69.408439 -311.88648) (xy 69.43131 -311.930057) (xy 69.446894 -311.976738) (xy 69.454789 -312.025315)
			(xy 69.455284 -312.049922) (xy 69.454789 -312.074529) (xy 69.45461 -312.07563) (xy 69.773288 -312.07563)
			(xy 69.773288 -312.024214) (xy 69.781331 -311.973432) (xy 69.797219 -311.924533) (xy 69.820562 -311.878721)
			(xy 69.850783 -311.837125) (xy 69.887139 -311.800769) (xy 69.928735 -311.770548) (xy 69.974547 -311.747205)
			(xy 70.023446 -311.731317) (xy 70.074228 -311.723274) (xy 70.125644 -311.723274) (xy 70.176426 -311.731317)
			(xy 70.225325 -311.747205) (xy 70.271137 -311.770548) (xy 70.312733 -311.800769) (xy 70.349089 -311.837125)
			(xy 70.37931 -311.878721) (xy 70.402653 -311.924533) (xy 70.418541 -311.973432) (xy 70.426584 -312.024214)
			(xy 70.427088 -312.049922) (xy 70.744092 -312.049922) (xy 70.748052 -312.000868) (xy 70.759829 -311.953084)
			(xy 70.77912 -311.907808) (xy 70.805423 -311.866212) (xy 70.838058 -311.829375) (xy 70.876179 -311.79825)
			(xy 70.9188 -311.773643) (xy 70.964816 -311.756191) (xy 71.013035 -311.746347) (xy 71.06221 -311.744366)
			(xy 71.111065 -311.750298) (xy 71.158336 -311.76399) (xy 71.202798 -311.785088) (xy 71.243301 -311.813044)
			(xy 71.278794 -311.847136) (xy 71.308359 -311.88648) (xy 71.33123 -311.930057) (xy 71.346814 -311.976738)
			(xy 71.354709 -312.025315) (xy 71.355204 -312.049922) (xy 71.354709 -312.074529) (xy 71.346814 -312.123106)
			(xy 71.33123 -312.169787) (xy 71.308359 -312.213364) (xy 71.278794 -312.252708) (xy 71.243301 -312.2868)
			(xy 71.202798 -312.314756) (xy 71.158336 -312.335854) (xy 71.111065 -312.349546) (xy 71.06221 -312.355478)
			(xy 71.013035 -312.353497) (xy 70.964816 -312.343653) (xy 70.9188 -312.326201) (xy 70.876179 -312.301594)
			(xy 70.838058 -312.270469) (xy 70.805423 -312.233632) (xy 70.77912 -312.192036) (xy 70.759829 -312.14676)
			(xy 70.748052 -312.098976) (xy 70.744092 -312.049922) (xy 70.427088 -312.049922) (xy 70.426584 -312.07563)
			(xy 70.418541 -312.126412) (xy 70.402653 -312.175311) (xy 70.37931 -312.221123) (xy 70.349089 -312.262719)
			(xy 70.312733 -312.299075) (xy 70.271137 -312.329296) (xy 70.225325 -312.352639) (xy 70.176426 -312.368527)
			(xy 70.125644 -312.37657) (xy 70.074228 -312.37657) (xy 70.023446 -312.368527) (xy 69.974547 -312.352639)
			(xy 69.928735 -312.329296) (xy 69.887139 -312.299075) (xy 69.850783 -312.262719) (xy 69.820562 -312.221123)
			(xy 69.797219 -312.175311) (xy 69.781331 -312.126412) (xy 69.773288 -312.07563) (xy 69.45461 -312.07563)
			(xy 69.446894 -312.123106) (xy 69.43131 -312.169787) (xy 69.408439 -312.213364) (xy 69.378874 -312.252708)
			(xy 69.343381 -312.2868) (xy 69.302878 -312.314756) (xy 69.258416 -312.335854) (xy 69.211145 -312.349546)
			(xy 69.16229 -312.355478) (xy 69.113115 -312.353497) (xy 69.064896 -312.343653) (xy 69.01888 -312.326201)
			(xy 68.976259 -312.301594) (xy 68.938138 -312.270469) (xy 68.905503 -312.233632) (xy 68.8792 -312.192036)
			(xy 68.859909 -312.14676) (xy 68.848132 -312.098976) (xy 68.844172 -312.049922) (xy 68.526914 -312.049922)
			(xy 68.52641 -312.07563) (xy 68.518367 -312.126412) (xy 68.502479 -312.175311) (xy 68.479136 -312.221123)
			(xy 68.448915 -312.262719) (xy 68.412559 -312.299075) (xy 68.370963 -312.329296) (xy 68.325151 -312.352639)
			(xy 68.276252 -312.368527) (xy 68.22547 -312.37657) (xy 68.174054 -312.37657) (xy 68.123272 -312.368527)
			(xy 68.074373 -312.352639) (xy 68.028561 -312.329296) (xy 67.986965 -312.299075) (xy 67.950609 -312.262719)
			(xy 67.920388 -312.221123) (xy 67.897045 -312.175311) (xy 67.881157 -312.126412) (xy 67.873114 -312.07563)
			(xy 67.554436 -312.07563) (xy 67.54672 -312.123106) (xy 67.531136 -312.169787) (xy 67.508265 -312.213364)
			(xy 67.4787 -312.252708) (xy 67.443207 -312.2868) (xy 67.402704 -312.314756) (xy 67.358242 -312.335854)
			(xy 67.310971 -312.349546) (xy 67.262116 -312.355478) (xy 67.212941 -312.353497) (xy 67.164722 -312.343653)
			(xy 67.118706 -312.326201) (xy 67.076085 -312.301594) (xy 67.037964 -312.270469) (xy 67.005329 -312.233632)
			(xy 66.979026 -312.192036) (xy 66.959735 -312.14676) (xy 66.947958 -312.098976) (xy 66.943998 -312.049922)
			(xy 66.626994 -312.049922) (xy 66.62649 -312.07563) (xy 66.618447 -312.126412) (xy 66.602559 -312.175311)
			(xy 66.579216 -312.221123) (xy 66.548995 -312.262719) (xy 66.512639 -312.299075) (xy 66.471043 -312.329296)
			(xy 66.425231 -312.352639) (xy 66.376332 -312.368527) (xy 66.32555 -312.37657) (xy 66.274134 -312.37657)
			(xy 66.223352 -312.368527) (xy 66.174453 -312.352639) (xy 66.128641 -312.329296) (xy 66.087045 -312.299075)
			(xy 66.050689 -312.262719) (xy 66.020468 -312.221123) (xy 65.997125 -312.175311) (xy 65.981237 -312.126412)
			(xy 65.973194 -312.07563) (xy 65.654516 -312.07563) (xy 65.6468 -312.123106) (xy 65.631216 -312.169787)
			(xy 65.608345 -312.213364) (xy 65.57878 -312.252708) (xy 65.543287 -312.2868) (xy 65.502784 -312.314756)
			(xy 65.458322 -312.335854) (xy 65.411051 -312.349546) (xy 65.362196 -312.355478) (xy 65.313021 -312.353497)
			(xy 65.264802 -312.343653) (xy 65.218786 -312.326201) (xy 65.176165 -312.301594) (xy 65.138044 -312.270469)
			(xy 65.105409 -312.233632) (xy 65.079106 -312.192036) (xy 65.059815 -312.14676) (xy 65.048038 -312.098976)
			(xy 65.044078 -312.049922) (xy 64.727074 -312.049922) (xy 64.72657 -312.07563) (xy 64.718527 -312.126412)
			(xy 64.702639 -312.175311) (xy 64.679296 -312.221123) (xy 64.649075 -312.262719) (xy 64.612719 -312.299075)
			(xy 64.571123 -312.329296) (xy 64.525311 -312.352639) (xy 64.476412 -312.368527) (xy 64.42563 -312.37657)
			(xy 64.374214 -312.37657) (xy 64.323432 -312.368527) (xy 64.274533 -312.352639) (xy 64.228721 -312.329296)
			(xy 64.187125 -312.299075) (xy 64.150769 -312.262719) (xy 64.120548 -312.221123) (xy 64.097205 -312.175311)
			(xy 64.081317 -312.126412) (xy 64.073274 -312.07563) (xy 63.754596 -312.07563) (xy 63.74688 -312.123106)
			(xy 63.731296 -312.169787) (xy 63.708425 -312.213364) (xy 63.67886 -312.252708) (xy 63.643367 -312.2868)
			(xy 63.602864 -312.314756) (xy 63.558402 -312.335854) (xy 63.511131 -312.349546) (xy 63.462276 -312.355478)
			(xy 63.413101 -312.353497) (xy 63.364882 -312.343653) (xy 63.318866 -312.326201) (xy 63.276245 -312.301594)
			(xy 63.238124 -312.270469) (xy 63.205489 -312.233632) (xy 63.179186 -312.192036) (xy 63.159895 -312.14676)
			(xy 63.148118 -312.098976) (xy 63.144158 -312.049922) (xy 62.8269 -312.049922) (xy 62.826396 -312.07563)
			(xy 62.818353 -312.126412) (xy 62.802465 -312.175311) (xy 62.779122 -312.221123) (xy 62.748901 -312.262719)
			(xy 62.712545 -312.299075) (xy 62.670949 -312.329296) (xy 62.625137 -312.352639) (xy 62.576238 -312.368527)
			(xy 62.525456 -312.37657) (xy 62.47404 -312.37657) (xy 62.423258 -312.368527) (xy 62.374359 -312.352639)
			(xy 62.328547 -312.329296) (xy 62.286951 -312.299075) (xy 62.250595 -312.262719) (xy 62.220374 -312.221123)
			(xy 62.197031 -312.175311) (xy 62.181143 -312.126412) (xy 62.1731 -312.07563) (xy 61.854422 -312.07563)
			(xy 61.846706 -312.123106) (xy 61.831122 -312.169787) (xy 61.808251 -312.213364) (xy 61.778686 -312.252708)
			(xy 61.743193 -312.2868) (xy 61.70269 -312.314756) (xy 61.658228 -312.335854) (xy 61.610957 -312.349546)
			(xy 61.562102 -312.355478) (xy 61.512927 -312.353497) (xy 61.464708 -312.343653) (xy 61.418692 -312.326201)
			(xy 61.376071 -312.301594) (xy 61.33795 -312.270469) (xy 61.305315 -312.233632) (xy 61.279012 -312.192036)
			(xy 61.259721 -312.14676) (xy 61.247944 -312.098976) (xy 61.243984 -312.049922) (xy 60.92698 -312.049922)
			(xy 60.926476 -312.07563) (xy 60.918433 -312.126412) (xy 60.902545 -312.175311) (xy 60.879202 -312.221123)
			(xy 60.848981 -312.262719) (xy 60.812625 -312.299075) (xy 60.771029 -312.329296) (xy 60.725217 -312.352639)
			(xy 60.676318 -312.368527) (xy 60.625536 -312.37657) (xy 60.57412 -312.37657) (xy 60.523338 -312.368527)
			(xy 60.474439 -312.352639) (xy 60.428627 -312.329296) (xy 60.387031 -312.299075) (xy 60.350675 -312.262719)
			(xy 60.320454 -312.221123) (xy 60.297111 -312.175311) (xy 60.281223 -312.126412) (xy 60.27318 -312.07563)
			(xy 59.954502 -312.07563) (xy 59.946786 -312.123106) (xy 59.931202 -312.169787) (xy 59.908331 -312.213364)
			(xy 59.878766 -312.252708) (xy 59.843273 -312.2868) (xy 59.80277 -312.314756) (xy 59.758308 -312.335854)
			(xy 59.711037 -312.349546) (xy 59.662182 -312.355478) (xy 59.613007 -312.353497) (xy 59.564788 -312.343653)
			(xy 59.518772 -312.326201) (xy 59.476151 -312.301594) (xy 59.43803 -312.270469) (xy 59.405395 -312.233632)
			(xy 59.379092 -312.192036) (xy 59.359801 -312.14676) (xy 59.348024 -312.098976) (xy 59.344064 -312.049922)
			(xy 59.02706 -312.049922) (xy 59.026556 -312.07563) (xy 59.018513 -312.126412) (xy 59.002625 -312.175311)
			(xy 58.979282 -312.221123) (xy 58.949061 -312.262719) (xy 58.912705 -312.299075) (xy 58.871109 -312.329296)
			(xy 58.825297 -312.352639) (xy 58.776398 -312.368527) (xy 58.725616 -312.37657) (xy 58.6742 -312.37657)
			(xy 58.623418 -312.368527) (xy 58.574519 -312.352639) (xy 58.528707 -312.329296) (xy 58.487111 -312.299075)
			(xy 58.450755 -312.262719) (xy 58.420534 -312.221123) (xy 58.397191 -312.175311) (xy 58.381303 -312.126412)
			(xy 58.37326 -312.07563) (xy 58.054582 -312.07563) (xy 58.046866 -312.123106) (xy 58.031282 -312.169787)
			(xy 58.008411 -312.213364) (xy 57.978846 -312.252708) (xy 57.943353 -312.2868) (xy 57.90285 -312.314756)
			(xy 57.858388 -312.335854) (xy 57.811117 -312.349546) (xy 57.762262 -312.355478) (xy 57.713087 -312.353497)
			(xy 57.664868 -312.343653) (xy 57.618852 -312.326201) (xy 57.576231 -312.301594) (xy 57.53811 -312.270469)
			(xy 57.505475 -312.233632) (xy 57.479172 -312.192036) (xy 57.459881 -312.14676) (xy 57.448104 -312.098976)
			(xy 57.444144 -312.049922) (xy 57.105296 -312.049922) (xy 57.104801 -312.074529) (xy 57.096906 -312.123106)
			(xy 57.081322 -312.169787) (xy 57.058451 -312.213364) (xy 57.028886 -312.252708) (xy 56.993393 -312.2868)
			(xy 56.95289 -312.314756) (xy 56.908428 -312.335854) (xy 56.861157 -312.349546) (xy 56.812302 -312.355478)
			(xy 56.763127 -312.353497) (xy 56.714908 -312.343653) (xy 56.668892 -312.326201) (xy 56.626271 -312.301594)
			(xy 56.58815 -312.270469) (xy 56.555515 -312.233632) (xy 56.529212 -312.192036) (xy 56.509921 -312.14676)
			(xy 56.498144 -312.098976) (xy 56.494184 -312.049922) (xy 56.155082 -312.049922) (xy 56.154587 -312.074529)
			(xy 56.146692 -312.123106) (xy 56.131108 -312.169787) (xy 56.108237 -312.213364) (xy 56.078672 -312.252708)
			(xy 56.043179 -312.2868) (xy 56.002676 -312.314756) (xy 55.958214 -312.335854) (xy 55.910943 -312.349546)
			(xy 55.862088 -312.355478) (xy 55.812913 -312.353497) (xy 55.764694 -312.343653) (xy 55.718678 -312.326201)
			(xy 55.676057 -312.301594) (xy 55.637936 -312.270469) (xy 55.605301 -312.233632) (xy 55.578998 -312.192036)
			(xy 55.559707 -312.14676) (xy 55.54793 -312.098976) (xy 55.54397 -312.049922) (xy 55.205122 -312.049922)
			(xy 55.204627 -312.074529) (xy 55.196732 -312.123106) (xy 55.181148 -312.169787) (xy 55.158277 -312.213364)
			(xy 55.128712 -312.252708) (xy 55.093219 -312.2868) (xy 55.052716 -312.314756) (xy 55.008254 -312.335854)
			(xy 54.960983 -312.349546) (xy 54.912128 -312.355478) (xy 54.862953 -312.353497) (xy 54.814734 -312.343653)
			(xy 54.768718 -312.326201) (xy 54.726097 -312.301594) (xy 54.687976 -312.270469) (xy 54.655341 -312.233632)
			(xy 54.629038 -312.192036) (xy 54.609747 -312.14676) (xy 54.59797 -312.098976) (xy 54.59401 -312.049922)
			(xy 54.255162 -312.049922) (xy 54.254667 -312.074529) (xy 54.246772 -312.123106) (xy 54.231188 -312.169787)
			(xy 54.208317 -312.213364) (xy 54.178752 -312.252708) (xy 54.143259 -312.2868) (xy 54.102756 -312.314756)
			(xy 54.058294 -312.335854) (xy 54.011023 -312.349546) (xy 53.962168 -312.355478) (xy 53.912993 -312.353497)
			(xy 53.864774 -312.343653) (xy 53.818758 -312.326201) (xy 53.776137 -312.301594) (xy 53.738016 -312.270469)
			(xy 53.705381 -312.233632) (xy 53.679078 -312.192036) (xy 53.659787 -312.14676) (xy 53.64801 -312.098976)
			(xy 53.64405 -312.049922) (xy 53.305202 -312.049922) (xy 53.304707 -312.074529) (xy 53.296812 -312.123106)
			(xy 53.281228 -312.169787) (xy 53.258357 -312.213364) (xy 53.228792 -312.252708) (xy 53.193299 -312.2868)
			(xy 53.152796 -312.314756) (xy 53.108334 -312.335854) (xy 53.061063 -312.349546) (xy 53.012208 -312.355478)
			(xy 52.963033 -312.353497) (xy 52.914814 -312.343653) (xy 52.868798 -312.326201) (xy 52.826177 -312.301594)
			(xy 52.788056 -312.270469) (xy 52.755421 -312.233632) (xy 52.729118 -312.192036) (xy 52.709827 -312.14676)
			(xy 52.69805 -312.098976) (xy 52.69409 -312.049922) (xy 52.355242 -312.049922) (xy 52.354747 -312.074529)
			(xy 52.346852 -312.123106) (xy 52.331268 -312.169787) (xy 52.308397 -312.213364) (xy 52.278832 -312.252708)
			(xy 52.243339 -312.2868) (xy 52.202836 -312.314756) (xy 52.158374 -312.335854) (xy 52.111103 -312.349546)
			(xy 52.062248 -312.355478) (xy 52.013073 -312.353497) (xy 51.964854 -312.343653) (xy 51.918838 -312.326201)
			(xy 51.876217 -312.301594) (xy 51.838096 -312.270469) (xy 51.805461 -312.233632) (xy 51.779158 -312.192036)
			(xy 51.759867 -312.14676) (xy 51.74809 -312.098976) (xy 51.74413 -312.049922) (xy 51.405282 -312.049922)
			(xy 51.404787 -312.074529) (xy 51.396892 -312.123106) (xy 51.381308 -312.169787) (xy 51.358437 -312.213364)
			(xy 51.328872 -312.252708) (xy 51.293379 -312.2868) (xy 51.252876 -312.314756) (xy 51.208414 -312.335854)
			(xy 51.161143 -312.349546) (xy 51.112288 -312.355478) (xy 51.063113 -312.353497) (xy 51.014894 -312.343653)
			(xy 50.968878 -312.326201) (xy 50.926257 -312.301594) (xy 50.888136 -312.270469) (xy 50.855501 -312.233632)
			(xy 50.829198 -312.192036) (xy 50.809907 -312.14676) (xy 50.79813 -312.098976) (xy 50.79417 -312.049922)
			(xy 50.455068 -312.049922) (xy 50.454573 -312.074529) (xy 50.446678 -312.123106) (xy 50.431094 -312.169787)
			(xy 50.408223 -312.213364) (xy 50.378658 -312.252708) (xy 50.343165 -312.2868) (xy 50.302662 -312.314756)
			(xy 50.2582 -312.335854) (xy 50.210929 -312.349546) (xy 50.162074 -312.355478) (xy 50.112899 -312.353497)
			(xy 50.06468 -312.343653) (xy 50.018664 -312.326201) (xy 49.976043 -312.301594) (xy 49.937922 -312.270469)
			(xy 49.905287 -312.233632) (xy 49.878984 -312.192036) (xy 49.859693 -312.14676) (xy 49.847916 -312.098976)
			(xy 49.843956 -312.049922) (xy 49.505108 -312.049922) (xy 49.504613 -312.074529) (xy 49.496718 -312.123106)
			(xy 49.481134 -312.169787) (xy 49.458263 -312.213364) (xy 49.428698 -312.252708) (xy 49.393205 -312.2868)
			(xy 49.352702 -312.314756) (xy 49.30824 -312.335854) (xy 49.260969 -312.349546) (xy 49.212114 -312.355478)
			(xy 49.162939 -312.353497) (xy 49.11472 -312.343653) (xy 49.068704 -312.326201) (xy 49.026083 -312.301594)
			(xy 48.987962 -312.270469) (xy 48.955327 -312.233632) (xy 48.929024 -312.192036) (xy 48.909733 -312.14676)
			(xy 48.897956 -312.098976) (xy 48.893996 -312.049922) (xy 48.555148 -312.049922) (xy 48.554653 -312.074529)
			(xy 48.546758 -312.123106) (xy 48.531174 -312.169787) (xy 48.508303 -312.213364) (xy 48.478738 -312.252708)
			(xy 48.443245 -312.2868) (xy 48.402742 -312.314756) (xy 48.35828 -312.335854) (xy 48.311009 -312.349546)
			(xy 48.262154 -312.355478) (xy 48.212979 -312.353497) (xy 48.16476 -312.343653) (xy 48.118744 -312.326201)
			(xy 48.076123 -312.301594) (xy 48.038002 -312.270469) (xy 48.005367 -312.233632) (xy 47.979064 -312.192036)
			(xy 47.959773 -312.14676) (xy 47.947996 -312.098976) (xy 47.944036 -312.049922) (xy 47.605188 -312.049922)
			(xy 47.604693 -312.074529) (xy 47.596798 -312.123106) (xy 47.581214 -312.169787) (xy 47.558343 -312.213364)
			(xy 47.528778 -312.252708) (xy 47.493285 -312.2868) (xy 47.452782 -312.314756) (xy 47.40832 -312.335854)
			(xy 47.361049 -312.349546) (xy 47.312194 -312.355478) (xy 47.263019 -312.353497) (xy 47.2148 -312.343653)
			(xy 47.168784 -312.326201) (xy 47.126163 -312.301594) (xy 47.088042 -312.270469) (xy 47.055407 -312.233632)
			(xy 47.029104 -312.192036) (xy 47.009813 -312.14676) (xy 46.998036 -312.098976) (xy 46.994076 -312.049922)
			(xy 46.655228 -312.049922) (xy 46.654733 -312.074529) (xy 46.646838 -312.123106) (xy 46.631254 -312.169787)
			(xy 46.608383 -312.213364) (xy 46.578818 -312.252708) (xy 46.543325 -312.2868) (xy 46.502822 -312.314756)
			(xy 46.45836 -312.335854) (xy 46.411089 -312.349546) (xy 46.362234 -312.355478) (xy 46.313059 -312.353497)
			(xy 46.26484 -312.343653) (xy 46.218824 -312.326201) (xy 46.176203 -312.301594) (xy 46.138082 -312.270469)
			(xy 46.105447 -312.233632) (xy 46.079144 -312.192036) (xy 46.059853 -312.14676) (xy 46.048076 -312.098976)
			(xy 46.044116 -312.049922) (xy 45.705268 -312.049922) (xy 45.704773 -312.074529) (xy 45.696878 -312.123106)
			(xy 45.681294 -312.169787) (xy 45.658423 -312.213364) (xy 45.628858 -312.252708) (xy 45.593365 -312.2868)
			(xy 45.552862 -312.314756) (xy 45.5084 -312.335854) (xy 45.461129 -312.349546) (xy 45.412274 -312.355478)
			(xy 45.363099 -312.353497) (xy 45.31488 -312.343653) (xy 45.268864 -312.326201) (xy 45.226243 -312.301594)
			(xy 45.188122 -312.270469) (xy 45.155487 -312.233632) (xy 45.129184 -312.192036) (xy 45.109893 -312.14676)
			(xy 45.098116 -312.098976) (xy 45.094156 -312.049922) (xy 44.755054 -312.049922) (xy 44.754559 -312.074529)
			(xy 44.746664 -312.123106) (xy 44.73108 -312.169787) (xy 44.708209 -312.213364) (xy 44.678644 -312.252708)
			(xy 44.643151 -312.2868) (xy 44.602648 -312.314756) (xy 44.558186 -312.335854) (xy 44.510915 -312.349546)
			(xy 44.46206 -312.355478) (xy 44.412885 -312.353497) (xy 44.364666 -312.343653) (xy 44.31865 -312.326201)
			(xy 44.276029 -312.301594) (xy 44.237908 -312.270469) (xy 44.205273 -312.233632) (xy 44.17897 -312.192036)
			(xy 44.159679 -312.14676) (xy 44.147902 -312.098976) (xy 44.143942 -312.049922) (xy 43.805094 -312.049922)
			(xy 43.804599 -312.074529) (xy 43.796704 -312.123106) (xy 43.78112 -312.169787) (xy 43.758249 -312.213364)
			(xy 43.728684 -312.252708) (xy 43.693191 -312.2868) (xy 43.652688 -312.314756) (xy 43.608226 -312.335854)
			(xy 43.560955 -312.349546) (xy 43.5121 -312.355478) (xy 43.462925 -312.353497) (xy 43.414706 -312.343653)
			(xy 43.36869 -312.326201) (xy 43.326069 -312.301594) (xy 43.287948 -312.270469) (xy 43.255313 -312.233632)
			(xy 43.22901 -312.192036) (xy 43.209719 -312.14676) (xy 43.197942 -312.098976) (xy 43.193982 -312.049922)
			(xy 42.855134 -312.049922) (xy 42.854639 -312.074529) (xy 42.846744 -312.123106) (xy 42.83116 -312.169787)
			(xy 42.808289 -312.213364) (xy 42.778724 -312.252708) (xy 42.743231 -312.2868) (xy 42.702728 -312.314756)
			(xy 42.658266 -312.335854) (xy 42.610995 -312.349546) (xy 42.56214 -312.355478) (xy 42.512965 -312.353497)
			(xy 42.464746 -312.343653) (xy 42.41873 -312.326201) (xy 42.376109 -312.301594) (xy 42.337988 -312.270469)
			(xy 42.305353 -312.233632) (xy 42.27905 -312.192036) (xy 42.259759 -312.14676) (xy 42.247982 -312.098976)
			(xy 42.244022 -312.049922) (xy 41.927018 -312.049922) (xy 41.926514 -312.07563) (xy 41.918471 -312.126412)
			(xy 41.902583 -312.175311) (xy 41.87924 -312.221123) (xy 41.849019 -312.262719) (xy 41.812663 -312.299075)
			(xy 41.771067 -312.329296) (xy 41.725255 -312.352639) (xy 41.676356 -312.368527) (xy 41.625574 -312.37657)
			(xy 41.574158 -312.37657) (xy 41.523376 -312.368527) (xy 41.474477 -312.352639) (xy 41.428665 -312.329296)
			(xy 41.387069 -312.299075) (xy 41.350713 -312.262719) (xy 41.320492 -312.221123) (xy 41.297149 -312.175311)
			(xy 41.281261 -312.126412) (xy 41.273218 -312.07563) (xy 40.95454 -312.07563) (xy 40.946824 -312.123106)
			(xy 40.93124 -312.169787) (xy 40.908369 -312.213364) (xy 40.878804 -312.252708) (xy 40.843311 -312.2868)
			(xy 40.802808 -312.314756) (xy 40.758346 -312.335854) (xy 40.711075 -312.349546) (xy 40.66222 -312.355478)
			(xy 40.613045 -312.353497) (xy 40.564826 -312.343653) (xy 40.51881 -312.326201) (xy 40.476189 -312.301594)
			(xy 40.438068 -312.270469) (xy 40.405433 -312.233632) (xy 40.37913 -312.192036) (xy 40.359839 -312.14676)
			(xy 40.348062 -312.098976) (xy 40.344102 -312.049922) (xy 40.027098 -312.049922) (xy 40.026594 -312.07563)
			(xy 40.018551 -312.126412) (xy 40.002663 -312.175311) (xy 39.97932 -312.221123) (xy 39.949099 -312.262719)
			(xy 39.912743 -312.299075) (xy 39.871147 -312.329296) (xy 39.825335 -312.352639) (xy 39.776436 -312.368527)
			(xy 39.725654 -312.37657) (xy 39.674238 -312.37657) (xy 39.623456 -312.368527) (xy 39.574557 -312.352639)
			(xy 39.528745 -312.329296) (xy 39.487149 -312.299075) (xy 39.450793 -312.262719) (xy 39.420572 -312.221123)
			(xy 39.397229 -312.175311) (xy 39.381341 -312.126412) (xy 39.373298 -312.07563) (xy 39.05462 -312.07563)
			(xy 39.046904 -312.123106) (xy 39.03132 -312.169787) (xy 39.008449 -312.213364) (xy 38.978884 -312.252708)
			(xy 38.943391 -312.2868) (xy 38.902888 -312.314756) (xy 38.858426 -312.335854) (xy 38.811155 -312.349546)
			(xy 38.7623 -312.355478) (xy 38.713125 -312.353497) (xy 38.664906 -312.343653) (xy 38.61889 -312.326201)
			(xy 38.576269 -312.301594) (xy 38.538148 -312.270469) (xy 38.505513 -312.233632) (xy 38.47921 -312.192036)
			(xy 38.459919 -312.14676) (xy 38.448142 -312.098976) (xy 38.444182 -312.049922) (xy 38.126924 -312.049922)
			(xy 38.12642 -312.07563) (xy 38.118377 -312.126412) (xy 38.102489 -312.175311) (xy 38.079146 -312.221123)
			(xy 38.048925 -312.262719) (xy 38.012569 -312.299075) (xy 37.970973 -312.329296) (xy 37.925161 -312.352639)
			(xy 37.876262 -312.368527) (xy 37.82548 -312.37657) (xy 37.774064 -312.37657) (xy 37.723282 -312.368527)
			(xy 37.674383 -312.352639) (xy 37.628571 -312.329296) (xy 37.586975 -312.299075) (xy 37.550619 -312.262719)
			(xy 37.520398 -312.221123) (xy 37.497055 -312.175311) (xy 37.481167 -312.126412) (xy 37.473124 -312.07563)
			(xy 37.17646 -312.07563) (xy 37.168417 -312.126412) (xy 37.152529 -312.175311) (xy 37.129186 -312.221123)
			(xy 37.098965 -312.262719) (xy 37.062609 -312.299075) (xy 37.021013 -312.329296) (xy 36.975201 -312.352639)
			(xy 36.926302 -312.368527) (xy 36.87552 -312.37657) (xy 36.824104 -312.37657) (xy 36.773322 -312.368527)
			(xy 36.724423 -312.352639) (xy 36.678611 -312.329296) (xy 36.637015 -312.299075) (xy 36.600659 -312.262719)
			(xy 36.570438 -312.221123) (xy 36.547095 -312.175311) (xy 36.531207 -312.126412) (xy 36.523164 -312.07563)
			(xy 36.204191 -312.07563) (xy 36.196516 -312.122852) (xy 36.180932 -312.169533) (xy 36.158061 -312.21311)
			(xy 36.128496 -312.252454) (xy 36.093003 -312.286546) (xy 36.0525 -312.314502) (xy 36.008038 -312.3356)
			(xy 35.960767 -312.349292) (xy 35.911912 -312.355224) (xy 35.862737 -312.353243) (xy 35.814518 -312.343399)
			(xy 35.768502 -312.325947) (xy 35.725881 -312.30134) (xy 35.68776 -312.270215) (xy 35.655125 -312.233378)
			(xy 35.628822 -312.191782) (xy 35.609531 -312.146506) (xy 35.597754 -312.098722) (xy 35.593794 -312.049668)
			(xy 34.716108 -312.049668) (xy 34.736931 -312.081142) (xy 34.760603 -312.131639) (xy 34.776671 -312.185046)
			(xy 34.784791 -312.240222) (xy 34.7853 -312.268108) (xy 34.784791 -312.295994) (xy 34.776671 -312.35117)
			(xy 34.760603 -312.404577) (xy 34.736931 -312.455074) (xy 34.706158 -312.501587) (xy 34.668941 -312.543124)
			(xy 34.626073 -312.578799) (xy 34.578467 -312.607853) (xy 34.527138 -312.629665) (xy 34.473181 -312.643771)
			(xy 34.417744 -312.649871) (xy 34.36201 -312.647834) (xy 34.307167 -312.637704) (xy 34.254383 -312.619697)
			(xy 34.204783 -312.594196) (xy 34.159425 -312.561745) (xy 34.119276 -312.523036) (xy 34.08519 -312.478893)
			(xy 34.057894 -312.430258) (xy 34.037971 -312.378167) (xy 34.025845 -312.32373) (xy 34.021774 -312.268108)
			(xy 32.396823 -312.268108) (xy 32.416348 -312.289899) (xy 32.447121 -312.336412) (xy 32.470793 -312.386909)
			(xy 32.486861 -312.440316) (xy 32.494981 -312.495492) (xy 32.49549 -312.523378) (xy 32.494981 -312.551264)
			(xy 32.486861 -312.60644) (xy 32.470793 -312.659847) (xy 32.447121 -312.710344) (xy 32.416348 -312.756857)
			(xy 32.379131 -312.798394) (xy 32.336263 -312.834069) (xy 32.288657 -312.863123) (xy 32.237328 -312.884935)
			(xy 32.183371 -312.899041) (xy 32.127934 -312.905141) (xy 32.0722 -312.903104) (xy 32.017357 -312.892974)
			(xy 31.964573 -312.874967) (xy 31.914973 -312.849466) (xy 31.869615 -312.817015) (xy 31.829466 -312.778306)
			(xy 31.79538 -312.734163) (xy 31.768084 -312.685528) (xy 31.748161 -312.633437) (xy 31.736035 -312.579)
			(xy 31.731964 -312.523378) (xy 17.635982 -312.523378) (xy 17.635982 -312.999882) (xy 36.544008 -312.999882)
			(xy 36.547968 -312.950828) (xy 36.559745 -312.903044) (xy 36.579036 -312.857768) (xy 36.605339 -312.816172)
			(xy 36.637974 -312.779335) (xy 36.676095 -312.74821) (xy 36.718716 -312.723603) (xy 36.764732 -312.706151)
			(xy 36.812951 -312.696307) (xy 36.862126 -312.694326) (xy 36.910981 -312.700258) (xy 36.958252 -312.71395)
			(xy 37.002714 -312.735048) (xy 37.043217 -312.763004) (xy 37.07871 -312.797096) (xy 37.108275 -312.83644)
			(xy 37.131146 -312.880017) (xy 37.14673 -312.926698) (xy 37.154625 -312.975275) (xy 37.15512 -312.999882)
			(xy 37.493968 -312.999882) (xy 37.497928 -312.950828) (xy 37.509705 -312.903044) (xy 37.528996 -312.857768)
			(xy 37.555299 -312.816172) (xy 37.587934 -312.779335) (xy 37.626055 -312.74821) (xy 37.668676 -312.723603)
			(xy 37.714692 -312.706151) (xy 37.762911 -312.696307) (xy 37.812086 -312.694326) (xy 37.860941 -312.700258)
			(xy 37.908212 -312.71395) (xy 37.952674 -312.735048) (xy 37.993177 -312.763004) (xy 38.02867 -312.797096)
			(xy 38.058235 -312.83644) (xy 38.081106 -312.880017) (xy 38.09669 -312.926698) (xy 38.104585 -312.975275)
			(xy 38.10508 -312.999882) (xy 38.104585 -313.024489) (xy 38.104406 -313.02559) (xy 38.423338 -313.02559)
			(xy 38.423338 -312.974174) (xy 38.431381 -312.923392) (xy 38.447269 -312.874493) (xy 38.470612 -312.828681)
			(xy 38.500833 -312.787085) (xy 38.537189 -312.750729) (xy 38.578785 -312.720508) (xy 38.624597 -312.697165)
			(xy 38.673496 -312.681277) (xy 38.724278 -312.673234) (xy 38.775694 -312.673234) (xy 38.826476 -312.681277)
			(xy 38.875375 -312.697165) (xy 38.921187 -312.720508) (xy 38.962783 -312.750729) (xy 38.999139 -312.787085)
			(xy 39.02936 -312.828681) (xy 39.052703 -312.874493) (xy 39.068591 -312.923392) (xy 39.076634 -312.974174)
			(xy 39.077138 -312.999882) (xy 39.394142 -312.999882) (xy 39.398102 -312.950828) (xy 39.409879 -312.903044)
			(xy 39.42917 -312.857768) (xy 39.455473 -312.816172) (xy 39.488108 -312.779335) (xy 39.526229 -312.74821)
			(xy 39.56885 -312.723603) (xy 39.614866 -312.706151) (xy 39.663085 -312.696307) (xy 39.71226 -312.694326)
			(xy 39.761115 -312.700258) (xy 39.808386 -312.71395) (xy 39.852848 -312.735048) (xy 39.893351 -312.763004)
			(xy 39.928844 -312.797096) (xy 39.958409 -312.83644) (xy 39.98128 -312.880017) (xy 39.996864 -312.926698)
			(xy 40.004759 -312.975275) (xy 40.005254 -312.999882) (xy 40.004759 -313.024489) (xy 40.00458 -313.02559)
			(xy 40.323258 -313.02559) (xy 40.323258 -312.974174) (xy 40.331301 -312.923392) (xy 40.347189 -312.874493)
			(xy 40.370532 -312.828681) (xy 40.400753 -312.787085) (xy 40.437109 -312.750729) (xy 40.478705 -312.720508)
			(xy 40.524517 -312.697165) (xy 40.573416 -312.681277) (xy 40.624198 -312.673234) (xy 40.675614 -312.673234)
			(xy 40.726396 -312.681277) (xy 40.775295 -312.697165) (xy 40.821107 -312.720508) (xy 40.862703 -312.750729)
			(xy 40.899059 -312.787085) (xy 40.92928 -312.828681) (xy 40.952623 -312.874493) (xy 40.968511 -312.923392)
			(xy 40.976554 -312.974174) (xy 40.977058 -312.999882) (xy 41.294062 -312.999882) (xy 41.298022 -312.950828)
			(xy 41.309799 -312.903044) (xy 41.32909 -312.857768) (xy 41.355393 -312.816172) (xy 41.388028 -312.779335)
			(xy 41.426149 -312.74821) (xy 41.46877 -312.723603) (xy 41.514786 -312.706151) (xy 41.563005 -312.696307)
			(xy 41.61218 -312.694326) (xy 41.661035 -312.700258) (xy 41.708306 -312.71395) (xy 41.752768 -312.735048)
			(xy 41.793271 -312.763004) (xy 41.828764 -312.797096) (xy 41.858329 -312.83644) (xy 41.8812 -312.880017)
			(xy 41.896784 -312.926698) (xy 41.904679 -312.975275) (xy 41.905174 -312.999882) (xy 41.904679 -313.024489)
			(xy 41.9045 -313.02559) (xy 42.223178 -313.02559) (xy 42.223178 -312.974174) (xy 42.231221 -312.923392)
			(xy 42.247109 -312.874493) (xy 42.270452 -312.828681) (xy 42.300673 -312.787085) (xy 42.337029 -312.750729)
			(xy 42.378625 -312.720508) (xy 42.424437 -312.697165) (xy 42.473336 -312.681277) (xy 42.524118 -312.673234)
			(xy 42.575534 -312.673234) (xy 42.626316 -312.681277) (xy 42.675215 -312.697165) (xy 42.721027 -312.720508)
			(xy 42.762623 -312.750729) (xy 42.798979 -312.787085) (xy 42.8292 -312.828681) (xy 42.852543 -312.874493)
			(xy 42.868431 -312.923392) (xy 42.876474 -312.974174) (xy 42.876978 -312.999882) (xy 43.193982 -312.999882)
			(xy 43.197942 -312.950828) (xy 43.209719 -312.903044) (xy 43.22901 -312.857768) (xy 43.255313 -312.816172)
			(xy 43.287948 -312.779335) (xy 43.326069 -312.74821) (xy 43.36869 -312.723603) (xy 43.414706 -312.706151)
			(xy 43.462925 -312.696307) (xy 43.5121 -312.694326) (xy 43.560955 -312.700258) (xy 43.608226 -312.71395)
			(xy 43.652688 -312.735048) (xy 43.693191 -312.763004) (xy 43.728684 -312.797096) (xy 43.758249 -312.83644)
			(xy 43.78112 -312.880017) (xy 43.796704 -312.926698) (xy 43.804599 -312.975275) (xy 43.805094 -312.999882)
			(xy 44.143942 -312.999882) (xy 44.147902 -312.950828) (xy 44.159679 -312.903044) (xy 44.17897 -312.857768)
			(xy 44.205273 -312.816172) (xy 44.237908 -312.779335) (xy 44.276029 -312.74821) (xy 44.31865 -312.723603)
			(xy 44.364666 -312.706151) (xy 44.412885 -312.696307) (xy 44.46206 -312.694326) (xy 44.510915 -312.700258)
			(xy 44.558186 -312.71395) (xy 44.602648 -312.735048) (xy 44.643151 -312.763004) (xy 44.678644 -312.797096)
			(xy 44.708209 -312.83644) (xy 44.73108 -312.880017) (xy 44.746664 -312.926698) (xy 44.754559 -312.975275)
			(xy 44.755054 -312.999882) (xy 45.094156 -312.999882) (xy 45.098116 -312.950828) (xy 45.109893 -312.903044)
			(xy 45.129184 -312.857768) (xy 45.155487 -312.816172) (xy 45.188122 -312.779335) (xy 45.226243 -312.74821)
			(xy 45.268864 -312.723603) (xy 45.31488 -312.706151) (xy 45.363099 -312.696307) (xy 45.412274 -312.694326)
			(xy 45.461129 -312.700258) (xy 45.5084 -312.71395) (xy 45.552862 -312.735048) (xy 45.593365 -312.763004)
			(xy 45.628858 -312.797096) (xy 45.658423 -312.83644) (xy 45.681294 -312.880017) (xy 45.696878 -312.926698)
			(xy 45.704773 -312.975275) (xy 45.705268 -312.999882) (xy 46.044116 -312.999882) (xy 46.048076 -312.950828)
			(xy 46.059853 -312.903044) (xy 46.079144 -312.857768) (xy 46.105447 -312.816172) (xy 46.138082 -312.779335)
			(xy 46.176203 -312.74821) (xy 46.218824 -312.723603) (xy 46.26484 -312.706151) (xy 46.313059 -312.696307)
			(xy 46.362234 -312.694326) (xy 46.411089 -312.700258) (xy 46.45836 -312.71395) (xy 46.502822 -312.735048)
			(xy 46.543325 -312.763004) (xy 46.578818 -312.797096) (xy 46.608383 -312.83644) (xy 46.631254 -312.880017)
			(xy 46.646838 -312.926698) (xy 46.654733 -312.975275) (xy 46.655228 -312.999882) (xy 46.994076 -312.999882)
			(xy 46.998036 -312.950828) (xy 47.009813 -312.903044) (xy 47.029104 -312.857768) (xy 47.055407 -312.816172)
			(xy 47.088042 -312.779335) (xy 47.126163 -312.74821) (xy 47.168784 -312.723603) (xy 47.2148 -312.706151)
			(xy 47.263019 -312.696307) (xy 47.312194 -312.694326) (xy 47.361049 -312.700258) (xy 47.40832 -312.71395)
			(xy 47.452782 -312.735048) (xy 47.493285 -312.763004) (xy 47.528778 -312.797096) (xy 47.558343 -312.83644)
			(xy 47.581214 -312.880017) (xy 47.596798 -312.926698) (xy 47.604693 -312.975275) (xy 47.605188 -312.999882)
			(xy 47.944036 -312.999882) (xy 47.947996 -312.950828) (xy 47.959773 -312.903044) (xy 47.979064 -312.857768)
			(xy 48.005367 -312.816172) (xy 48.038002 -312.779335) (xy 48.076123 -312.74821) (xy 48.118744 -312.723603)
			(xy 48.16476 -312.706151) (xy 48.212979 -312.696307) (xy 48.262154 -312.694326) (xy 48.311009 -312.700258)
			(xy 48.35828 -312.71395) (xy 48.402742 -312.735048) (xy 48.443245 -312.763004) (xy 48.478738 -312.797096)
			(xy 48.508303 -312.83644) (xy 48.531174 -312.880017) (xy 48.546758 -312.926698) (xy 48.554653 -312.975275)
			(xy 48.555148 -312.999882) (xy 48.893996 -312.999882) (xy 48.897956 -312.950828) (xy 48.909733 -312.903044)
			(xy 48.929024 -312.857768) (xy 48.955327 -312.816172) (xy 48.987962 -312.779335) (xy 49.026083 -312.74821)
			(xy 49.068704 -312.723603) (xy 49.11472 -312.706151) (xy 49.162939 -312.696307) (xy 49.212114 -312.694326)
			(xy 49.260969 -312.700258) (xy 49.30824 -312.71395) (xy 49.352702 -312.735048) (xy 49.393205 -312.763004)
			(xy 49.428698 -312.797096) (xy 49.458263 -312.83644) (xy 49.481134 -312.880017) (xy 49.496718 -312.926698)
			(xy 49.504613 -312.975275) (xy 49.505108 -312.999882) (xy 49.843956 -312.999882) (xy 49.847916 -312.950828)
			(xy 49.859693 -312.903044) (xy 49.878984 -312.857768) (xy 49.905287 -312.816172) (xy 49.937922 -312.779335)
			(xy 49.976043 -312.74821) (xy 50.018664 -312.723603) (xy 50.06468 -312.706151) (xy 50.112899 -312.696307)
			(xy 50.162074 -312.694326) (xy 50.210929 -312.700258) (xy 50.2582 -312.71395) (xy 50.302662 -312.735048)
			(xy 50.343165 -312.763004) (xy 50.378658 -312.797096) (xy 50.408223 -312.83644) (xy 50.431094 -312.880017)
			(xy 50.446678 -312.926698) (xy 50.454573 -312.975275) (xy 50.455068 -312.999882) (xy 50.79417 -312.999882)
			(xy 50.79813 -312.950828) (xy 50.809907 -312.903044) (xy 50.829198 -312.857768) (xy 50.855501 -312.816172)
			(xy 50.888136 -312.779335) (xy 50.926257 -312.74821) (xy 50.968878 -312.723603) (xy 51.014894 -312.706151)
			(xy 51.063113 -312.696307) (xy 51.112288 -312.694326) (xy 51.161143 -312.700258) (xy 51.208414 -312.71395)
			(xy 51.252876 -312.735048) (xy 51.293379 -312.763004) (xy 51.328872 -312.797096) (xy 51.358437 -312.83644)
			(xy 51.381308 -312.880017) (xy 51.396892 -312.926698) (xy 51.404787 -312.975275) (xy 51.405282 -312.999882)
			(xy 51.74413 -312.999882) (xy 51.74809 -312.950828) (xy 51.759867 -312.903044) (xy 51.779158 -312.857768)
			(xy 51.805461 -312.816172) (xy 51.838096 -312.779335) (xy 51.876217 -312.74821) (xy 51.918838 -312.723603)
			(xy 51.964854 -312.706151) (xy 52.013073 -312.696307) (xy 52.062248 -312.694326) (xy 52.111103 -312.700258)
			(xy 52.158374 -312.71395) (xy 52.202836 -312.735048) (xy 52.243339 -312.763004) (xy 52.278832 -312.797096)
			(xy 52.308397 -312.83644) (xy 52.331268 -312.880017) (xy 52.346852 -312.926698) (xy 52.354747 -312.975275)
			(xy 52.355242 -312.999882) (xy 52.69409 -312.999882) (xy 52.69805 -312.950828) (xy 52.709827 -312.903044)
			(xy 52.729118 -312.857768) (xy 52.755421 -312.816172) (xy 52.788056 -312.779335) (xy 52.826177 -312.74821)
			(xy 52.868798 -312.723603) (xy 52.914814 -312.706151) (xy 52.963033 -312.696307) (xy 53.012208 -312.694326)
			(xy 53.061063 -312.700258) (xy 53.108334 -312.71395) (xy 53.152796 -312.735048) (xy 53.193299 -312.763004)
			(xy 53.228792 -312.797096) (xy 53.258357 -312.83644) (xy 53.281228 -312.880017) (xy 53.296812 -312.926698)
			(xy 53.304707 -312.975275) (xy 53.305202 -312.999882) (xy 53.64405 -312.999882) (xy 53.64801 -312.950828)
			(xy 53.659787 -312.903044) (xy 53.679078 -312.857768) (xy 53.705381 -312.816172) (xy 53.738016 -312.779335)
			(xy 53.776137 -312.74821) (xy 53.818758 -312.723603) (xy 53.864774 -312.706151) (xy 53.912993 -312.696307)
			(xy 53.962168 -312.694326) (xy 54.011023 -312.700258) (xy 54.058294 -312.71395) (xy 54.102756 -312.735048)
			(xy 54.143259 -312.763004) (xy 54.178752 -312.797096) (xy 54.208317 -312.83644) (xy 54.231188 -312.880017)
			(xy 54.246772 -312.926698) (xy 54.254667 -312.975275) (xy 54.255162 -312.999882) (xy 54.59401 -312.999882)
			(xy 54.59797 -312.950828) (xy 54.609747 -312.903044) (xy 54.629038 -312.857768) (xy 54.655341 -312.816172)
			(xy 54.687976 -312.779335) (xy 54.726097 -312.74821) (xy 54.768718 -312.723603) (xy 54.814734 -312.706151)
			(xy 54.862953 -312.696307) (xy 54.912128 -312.694326) (xy 54.960983 -312.700258) (xy 55.008254 -312.71395)
			(xy 55.052716 -312.735048) (xy 55.093219 -312.763004) (xy 55.128712 -312.797096) (xy 55.158277 -312.83644)
			(xy 55.181148 -312.880017) (xy 55.196732 -312.926698) (xy 55.204627 -312.975275) (xy 55.205122 -312.999882)
			(xy 55.54397 -312.999882) (xy 55.54793 -312.950828) (xy 55.559707 -312.903044) (xy 55.578998 -312.857768)
			(xy 55.605301 -312.816172) (xy 55.637936 -312.779335) (xy 55.676057 -312.74821) (xy 55.718678 -312.723603)
			(xy 55.764694 -312.706151) (xy 55.812913 -312.696307) (xy 55.862088 -312.694326) (xy 55.910943 -312.700258)
			(xy 55.958214 -312.71395) (xy 56.002676 -312.735048) (xy 56.043179 -312.763004) (xy 56.078672 -312.797096)
			(xy 56.108237 -312.83644) (xy 56.131108 -312.880017) (xy 56.146692 -312.926698) (xy 56.154587 -312.975275)
			(xy 56.155082 -312.999882) (xy 56.494184 -312.999882) (xy 56.498144 -312.950828) (xy 56.509921 -312.903044)
			(xy 56.529212 -312.857768) (xy 56.555515 -312.816172) (xy 56.58815 -312.779335) (xy 56.626271 -312.74821)
			(xy 56.668892 -312.723603) (xy 56.714908 -312.706151) (xy 56.763127 -312.696307) (xy 56.812302 -312.694326)
			(xy 56.861157 -312.700258) (xy 56.908428 -312.71395) (xy 56.95289 -312.735048) (xy 56.993393 -312.763004)
			(xy 57.028886 -312.797096) (xy 57.058451 -312.83644) (xy 57.081322 -312.880017) (xy 57.096906 -312.926698)
			(xy 57.104801 -312.975275) (xy 57.105296 -312.999882) (xy 57.444144 -312.999882) (xy 57.448104 -312.950828)
			(xy 57.459881 -312.903044) (xy 57.479172 -312.857768) (xy 57.505475 -312.816172) (xy 57.53811 -312.779335)
			(xy 57.576231 -312.74821) (xy 57.618852 -312.723603) (xy 57.664868 -312.706151) (xy 57.713087 -312.696307)
			(xy 57.762262 -312.694326) (xy 57.811117 -312.700258) (xy 57.858388 -312.71395) (xy 57.90285 -312.735048)
			(xy 57.943353 -312.763004) (xy 57.978846 -312.797096) (xy 58.008411 -312.83644) (xy 58.031282 -312.880017)
			(xy 58.046866 -312.926698) (xy 58.054761 -312.975275) (xy 58.055256 -312.999882) (xy 58.394104 -312.999882)
			(xy 58.398064 -312.950828) (xy 58.409841 -312.903044) (xy 58.429132 -312.857768) (xy 58.455435 -312.816172)
			(xy 58.48807 -312.779335) (xy 58.526191 -312.74821) (xy 58.568812 -312.723603) (xy 58.614828 -312.706151)
			(xy 58.663047 -312.696307) (xy 58.712222 -312.694326) (xy 58.761077 -312.700258) (xy 58.808348 -312.71395)
			(xy 58.85281 -312.735048) (xy 58.893313 -312.763004) (xy 58.928806 -312.797096) (xy 58.958371 -312.83644)
			(xy 58.981242 -312.880017) (xy 58.996826 -312.926698) (xy 59.004721 -312.975275) (xy 59.005216 -312.999882)
			(xy 59.004721 -313.024489) (xy 59.004542 -313.02559) (xy 59.32322 -313.02559) (xy 59.32322 -312.974174)
			(xy 59.331263 -312.923392) (xy 59.347151 -312.874493) (xy 59.370494 -312.828681) (xy 59.400715 -312.787085)
			(xy 59.437071 -312.750729) (xy 59.478667 -312.720508) (xy 59.524479 -312.697165) (xy 59.573378 -312.681277)
			(xy 59.62416 -312.673234) (xy 59.675576 -312.673234) (xy 59.726358 -312.681277) (xy 59.775257 -312.697165)
			(xy 59.821069 -312.720508) (xy 59.862665 -312.750729) (xy 59.899021 -312.787085) (xy 59.929242 -312.828681)
			(xy 59.952585 -312.874493) (xy 59.968473 -312.923392) (xy 59.976516 -312.974174) (xy 59.97702 -312.999882)
			(xy 60.294024 -312.999882) (xy 60.297984 -312.950828) (xy 60.309761 -312.903044) (xy 60.329052 -312.857768)
			(xy 60.355355 -312.816172) (xy 60.38799 -312.779335) (xy 60.426111 -312.74821) (xy 60.468732 -312.723603)
			(xy 60.514748 -312.706151) (xy 60.562967 -312.696307) (xy 60.612142 -312.694326) (xy 60.660997 -312.700258)
			(xy 60.708268 -312.71395) (xy 60.75273 -312.735048) (xy 60.793233 -312.763004) (xy 60.828726 -312.797096)
			(xy 60.858291 -312.83644) (xy 60.881162 -312.880017) (xy 60.896746 -312.926698) (xy 60.904641 -312.975275)
			(xy 60.905136 -312.999882) (xy 60.904641 -313.024489) (xy 60.904462 -313.02559) (xy 61.22314 -313.02559)
			(xy 61.22314 -312.974174) (xy 61.231183 -312.923392) (xy 61.247071 -312.874493) (xy 61.270414 -312.828681)
			(xy 61.300635 -312.787085) (xy 61.336991 -312.750729) (xy 61.378587 -312.720508) (xy 61.424399 -312.697165)
			(xy 61.473298 -312.681277) (xy 61.52408 -312.673234) (xy 61.575496 -312.673234) (xy 61.626278 -312.681277)
			(xy 61.675177 -312.697165) (xy 61.720989 -312.720508) (xy 61.762585 -312.750729) (xy 61.798941 -312.787085)
			(xy 61.829162 -312.828681) (xy 61.852505 -312.874493) (xy 61.868393 -312.923392) (xy 61.876436 -312.974174)
			(xy 61.87694 -312.999882) (xy 62.193944 -312.999882) (xy 62.197904 -312.950828) (xy 62.209681 -312.903044)
			(xy 62.228972 -312.857768) (xy 62.255275 -312.816172) (xy 62.28791 -312.779335) (xy 62.326031 -312.74821)
			(xy 62.368652 -312.723603) (xy 62.414668 -312.706151) (xy 62.462887 -312.696307) (xy 62.512062 -312.694326)
			(xy 62.560917 -312.700258) (xy 62.608188 -312.71395) (xy 62.65265 -312.735048) (xy 62.693153 -312.763004)
			(xy 62.728646 -312.797096) (xy 62.758211 -312.83644) (xy 62.781082 -312.880017) (xy 62.796666 -312.926698)
			(xy 62.804561 -312.975275) (xy 62.805056 -312.999882) (xy 62.804561 -313.024489) (xy 62.804382 -313.02559)
			(xy 63.123314 -313.02559) (xy 63.123314 -312.974174) (xy 63.131357 -312.923392) (xy 63.147245 -312.874493)
			(xy 63.170588 -312.828681) (xy 63.200809 -312.787085) (xy 63.237165 -312.750729) (xy 63.278761 -312.720508)
			(xy 63.324573 -312.697165) (xy 63.373472 -312.681277) (xy 63.424254 -312.673234) (xy 63.47567 -312.673234)
			(xy 63.526452 -312.681277) (xy 63.575351 -312.697165) (xy 63.621163 -312.720508) (xy 63.662759 -312.750729)
			(xy 63.699115 -312.787085) (xy 63.729336 -312.828681) (xy 63.752679 -312.874493) (xy 63.768567 -312.923392)
			(xy 63.77661 -312.974174) (xy 63.777114 -312.999882) (xy 64.094118 -312.999882) (xy 64.098078 -312.950828)
			(xy 64.109855 -312.903044) (xy 64.129146 -312.857768) (xy 64.155449 -312.816172) (xy 64.188084 -312.779335)
			(xy 64.226205 -312.74821) (xy 64.268826 -312.723603) (xy 64.314842 -312.706151) (xy 64.363061 -312.696307)
			(xy 64.412236 -312.694326) (xy 64.461091 -312.700258) (xy 64.508362 -312.71395) (xy 64.552824 -312.735048)
			(xy 64.593327 -312.763004) (xy 64.62882 -312.797096) (xy 64.658385 -312.83644) (xy 64.681256 -312.880017)
			(xy 64.69684 -312.926698) (xy 64.704735 -312.975275) (xy 64.70523 -312.999882) (xy 64.704735 -313.024489)
			(xy 64.704556 -313.02559) (xy 65.023234 -313.02559) (xy 65.023234 -312.974174) (xy 65.031277 -312.923392)
			(xy 65.047165 -312.874493) (xy 65.070508 -312.828681) (xy 65.100729 -312.787085) (xy 65.137085 -312.750729)
			(xy 65.178681 -312.720508) (xy 65.224493 -312.697165) (xy 65.273392 -312.681277) (xy 65.324174 -312.673234)
			(xy 65.37559 -312.673234) (xy 65.426372 -312.681277) (xy 65.475271 -312.697165) (xy 65.521083 -312.720508)
			(xy 65.562679 -312.750729) (xy 65.599035 -312.787085) (xy 65.629256 -312.828681) (xy 65.652599 -312.874493)
			(xy 65.668487 -312.923392) (xy 65.67653 -312.974174) (xy 65.677034 -312.999882) (xy 65.994038 -312.999882)
			(xy 65.997998 -312.950828) (xy 66.009775 -312.903044) (xy 66.029066 -312.857768) (xy 66.055369 -312.816172)
			(xy 66.088004 -312.779335) (xy 66.126125 -312.74821) (xy 66.168746 -312.723603) (xy 66.214762 -312.706151)
			(xy 66.262981 -312.696307) (xy 66.312156 -312.694326) (xy 66.361011 -312.700258) (xy 66.408282 -312.71395)
			(xy 66.452744 -312.735048) (xy 66.493247 -312.763004) (xy 66.52874 -312.797096) (xy 66.558305 -312.83644)
			(xy 66.581176 -312.880017) (xy 66.59676 -312.926698) (xy 66.604655 -312.975275) (xy 66.60515 -312.999882)
			(xy 66.604655 -313.024489) (xy 66.604476 -313.02559) (xy 66.923154 -313.02559) (xy 66.923154 -312.974174)
			(xy 66.931197 -312.923392) (xy 66.947085 -312.874493) (xy 66.970428 -312.828681) (xy 67.000649 -312.787085)
			(xy 67.037005 -312.750729) (xy 67.078601 -312.720508) (xy 67.124413 -312.697165) (xy 67.173312 -312.681277)
			(xy 67.224094 -312.673234) (xy 67.27551 -312.673234) (xy 67.326292 -312.681277) (xy 67.375191 -312.697165)
			(xy 67.421003 -312.720508) (xy 67.462599 -312.750729) (xy 67.498955 -312.787085) (xy 67.529176 -312.828681)
			(xy 67.552519 -312.874493) (xy 67.568407 -312.923392) (xy 67.57645 -312.974174) (xy 67.576954 -312.999882)
			(xy 67.893958 -312.999882) (xy 67.897918 -312.950828) (xy 67.909695 -312.903044) (xy 67.928986 -312.857768)
			(xy 67.955289 -312.816172) (xy 67.987924 -312.779335) (xy 68.026045 -312.74821) (xy 68.068666 -312.723603)
			(xy 68.114682 -312.706151) (xy 68.162901 -312.696307) (xy 68.212076 -312.694326) (xy 68.260931 -312.700258)
			(xy 68.308202 -312.71395) (xy 68.352664 -312.735048) (xy 68.393167 -312.763004) (xy 68.42866 -312.797096)
			(xy 68.458225 -312.83644) (xy 68.481096 -312.880017) (xy 68.49668 -312.926698) (xy 68.504575 -312.975275)
			(xy 68.50507 -312.999882) (xy 68.504575 -313.024489) (xy 68.504396 -313.02559) (xy 68.823328 -313.02559)
			(xy 68.823328 -312.974174) (xy 68.831371 -312.923392) (xy 68.847259 -312.874493) (xy 68.870602 -312.828681)
			(xy 68.900823 -312.787085) (xy 68.937179 -312.750729) (xy 68.978775 -312.720508) (xy 69.024587 -312.697165)
			(xy 69.073486 -312.681277) (xy 69.124268 -312.673234) (xy 69.175684 -312.673234) (xy 69.226466 -312.681277)
			(xy 69.275365 -312.697165) (xy 69.321177 -312.720508) (xy 69.362773 -312.750729) (xy 69.399129 -312.787085)
			(xy 69.42935 -312.828681) (xy 69.452693 -312.874493) (xy 69.468581 -312.923392) (xy 69.476624 -312.974174)
			(xy 69.477128 -312.999882) (xy 69.794132 -312.999882) (xy 69.798092 -312.950828) (xy 69.809869 -312.903044)
			(xy 69.82916 -312.857768) (xy 69.855463 -312.816172) (xy 69.888098 -312.779335) (xy 69.926219 -312.74821)
			(xy 69.96884 -312.723603) (xy 70.014856 -312.706151) (xy 70.063075 -312.696307) (xy 70.11225 -312.694326)
			(xy 70.161105 -312.700258) (xy 70.208376 -312.71395) (xy 70.252838 -312.735048) (xy 70.293341 -312.763004)
			(xy 70.328834 -312.797096) (xy 70.358399 -312.83644) (xy 70.38127 -312.880017) (xy 70.396854 -312.926698)
			(xy 70.404749 -312.975275) (xy 70.405244 -312.999882) (xy 70.404749 -313.024489) (xy 70.40457 -313.02559)
			(xy 70.723248 -313.02559) (xy 70.723248 -312.974174) (xy 70.731291 -312.923392) (xy 70.747179 -312.874493)
			(xy 70.770522 -312.828681) (xy 70.800743 -312.787085) (xy 70.837099 -312.750729) (xy 70.878695 -312.720508)
			(xy 70.924507 -312.697165) (xy 70.973406 -312.681277) (xy 71.024188 -312.673234) (xy 71.075604 -312.673234)
			(xy 71.126386 -312.681277) (xy 71.175285 -312.697165) (xy 71.221097 -312.720508) (xy 71.262693 -312.750729)
			(xy 71.299049 -312.787085) (xy 71.32927 -312.828681) (xy 71.352613 -312.874493) (xy 71.368501 -312.923392)
			(xy 71.376544 -312.974174) (xy 71.377048 -312.999882) (xy 71.376544 -313.02559) (xy 71.368501 -313.076372)
			(xy 71.352613 -313.125271) (xy 71.32927 -313.171083) (xy 71.299049 -313.212679) (xy 71.262693 -313.249035)
			(xy 71.221097 -313.279256) (xy 71.175285 -313.302599) (xy 71.126386 -313.318487) (xy 71.075604 -313.32653)
			(xy 71.024188 -313.32653) (xy 70.973406 -313.318487) (xy 70.924507 -313.302599) (xy 70.878695 -313.279256)
			(xy 70.837099 -313.249035) (xy 70.800743 -313.212679) (xy 70.770522 -313.171083) (xy 70.747179 -313.125271)
			(xy 70.731291 -313.076372) (xy 70.723248 -313.02559) (xy 70.40457 -313.02559) (xy 70.396854 -313.073066)
			(xy 70.38127 -313.119747) (xy 70.358399 -313.163324) (xy 70.328834 -313.202668) (xy 70.293341 -313.23676)
			(xy 70.252838 -313.264716) (xy 70.208376 -313.285814) (xy 70.161105 -313.299506) (xy 70.11225 -313.305438)
			(xy 70.063075 -313.303457) (xy 70.014856 -313.293613) (xy 69.96884 -313.276161) (xy 69.926219 -313.251554)
			(xy 69.888098 -313.220429) (xy 69.855463 -313.183592) (xy 69.82916 -313.141996) (xy 69.809869 -313.09672)
			(xy 69.798092 -313.048936) (xy 69.794132 -312.999882) (xy 69.477128 -312.999882) (xy 69.476624 -313.02559)
			(xy 69.468581 -313.076372) (xy 69.452693 -313.125271) (xy 69.42935 -313.171083) (xy 69.399129 -313.212679)
			(xy 69.362773 -313.249035) (xy 69.321177 -313.279256) (xy 69.275365 -313.302599) (xy 69.226466 -313.318487)
			(xy 69.175684 -313.32653) (xy 69.124268 -313.32653) (xy 69.073486 -313.318487) (xy 69.024587 -313.302599)
			(xy 68.978775 -313.279256) (xy 68.937179 -313.249035) (xy 68.900823 -313.212679) (xy 68.870602 -313.171083)
			(xy 68.847259 -313.125271) (xy 68.831371 -313.076372) (xy 68.823328 -313.02559) (xy 68.504396 -313.02559)
			(xy 68.49668 -313.073066) (xy 68.481096 -313.119747) (xy 68.458225 -313.163324) (xy 68.42866 -313.202668)
			(xy 68.393167 -313.23676) (xy 68.352664 -313.264716) (xy 68.308202 -313.285814) (xy 68.260931 -313.299506)
			(xy 68.212076 -313.305438) (xy 68.162901 -313.303457) (xy 68.114682 -313.293613) (xy 68.068666 -313.276161)
			(xy 68.026045 -313.251554) (xy 67.987924 -313.220429) (xy 67.955289 -313.183592) (xy 67.928986 -313.141996)
			(xy 67.909695 -313.09672) (xy 67.897918 -313.048936) (xy 67.893958 -312.999882) (xy 67.576954 -312.999882)
			(xy 67.57645 -313.02559) (xy 67.568407 -313.076372) (xy 67.552519 -313.125271) (xy 67.529176 -313.171083)
			(xy 67.498955 -313.212679) (xy 67.462599 -313.249035) (xy 67.421003 -313.279256) (xy 67.375191 -313.302599)
			(xy 67.326292 -313.318487) (xy 67.27551 -313.32653) (xy 67.224094 -313.32653) (xy 67.173312 -313.318487)
			(xy 67.124413 -313.302599) (xy 67.078601 -313.279256) (xy 67.037005 -313.249035) (xy 67.000649 -313.212679)
			(xy 66.970428 -313.171083) (xy 66.947085 -313.125271) (xy 66.931197 -313.076372) (xy 66.923154 -313.02559)
			(xy 66.604476 -313.02559) (xy 66.59676 -313.073066) (xy 66.581176 -313.119747) (xy 66.558305 -313.163324)
			(xy 66.52874 -313.202668) (xy 66.493247 -313.23676) (xy 66.452744 -313.264716) (xy 66.408282 -313.285814)
			(xy 66.361011 -313.299506) (xy 66.312156 -313.305438) (xy 66.262981 -313.303457) (xy 66.214762 -313.293613)
			(xy 66.168746 -313.276161) (xy 66.126125 -313.251554) (xy 66.088004 -313.220429) (xy 66.055369 -313.183592)
			(xy 66.029066 -313.141996) (xy 66.009775 -313.09672) (xy 65.997998 -313.048936) (xy 65.994038 -312.999882)
			(xy 65.677034 -312.999882) (xy 65.67653 -313.02559) (xy 65.668487 -313.076372) (xy 65.652599 -313.125271)
			(xy 65.629256 -313.171083) (xy 65.599035 -313.212679) (xy 65.562679 -313.249035) (xy 65.521083 -313.279256)
			(xy 65.475271 -313.302599) (xy 65.426372 -313.318487) (xy 65.37559 -313.32653) (xy 65.324174 -313.32653)
			(xy 65.273392 -313.318487) (xy 65.224493 -313.302599) (xy 65.178681 -313.279256) (xy 65.137085 -313.249035)
			(xy 65.100729 -313.212679) (xy 65.070508 -313.171083) (xy 65.047165 -313.125271) (xy 65.031277 -313.076372)
			(xy 65.023234 -313.02559) (xy 64.704556 -313.02559) (xy 64.69684 -313.073066) (xy 64.681256 -313.119747)
			(xy 64.658385 -313.163324) (xy 64.62882 -313.202668) (xy 64.593327 -313.23676) (xy 64.552824 -313.264716)
			(xy 64.508362 -313.285814) (xy 64.461091 -313.299506) (xy 64.412236 -313.305438) (xy 64.363061 -313.303457)
			(xy 64.314842 -313.293613) (xy 64.268826 -313.276161) (xy 64.226205 -313.251554) (xy 64.188084 -313.220429)
			(xy 64.155449 -313.183592) (xy 64.129146 -313.141996) (xy 64.109855 -313.09672) (xy 64.098078 -313.048936)
			(xy 64.094118 -312.999882) (xy 63.777114 -312.999882) (xy 63.77661 -313.02559) (xy 63.768567 -313.076372)
			(xy 63.752679 -313.125271) (xy 63.729336 -313.171083) (xy 63.699115 -313.212679) (xy 63.662759 -313.249035)
			(xy 63.621163 -313.279256) (xy 63.575351 -313.302599) (xy 63.526452 -313.318487) (xy 63.47567 -313.32653)
			(xy 63.424254 -313.32653) (xy 63.373472 -313.318487) (xy 63.324573 -313.302599) (xy 63.278761 -313.279256)
			(xy 63.237165 -313.249035) (xy 63.200809 -313.212679) (xy 63.170588 -313.171083) (xy 63.147245 -313.125271)
			(xy 63.131357 -313.076372) (xy 63.123314 -313.02559) (xy 62.804382 -313.02559) (xy 62.796666 -313.073066)
			(xy 62.781082 -313.119747) (xy 62.758211 -313.163324) (xy 62.728646 -313.202668) (xy 62.693153 -313.23676)
			(xy 62.65265 -313.264716) (xy 62.608188 -313.285814) (xy 62.560917 -313.299506) (xy 62.512062 -313.305438)
			(xy 62.462887 -313.303457) (xy 62.414668 -313.293613) (xy 62.368652 -313.276161) (xy 62.326031 -313.251554)
			(xy 62.28791 -313.220429) (xy 62.255275 -313.183592) (xy 62.228972 -313.141996) (xy 62.209681 -313.09672)
			(xy 62.197904 -313.048936) (xy 62.193944 -312.999882) (xy 61.87694 -312.999882) (xy 61.876436 -313.02559)
			(xy 61.868393 -313.076372) (xy 61.852505 -313.125271) (xy 61.829162 -313.171083) (xy 61.798941 -313.212679)
			(xy 61.762585 -313.249035) (xy 61.720989 -313.279256) (xy 61.675177 -313.302599) (xy 61.626278 -313.318487)
			(xy 61.575496 -313.32653) (xy 61.52408 -313.32653) (xy 61.473298 -313.318487) (xy 61.424399 -313.302599)
			(xy 61.378587 -313.279256) (xy 61.336991 -313.249035) (xy 61.300635 -313.212679) (xy 61.270414 -313.171083)
			(xy 61.247071 -313.125271) (xy 61.231183 -313.076372) (xy 61.22314 -313.02559) (xy 60.904462 -313.02559)
			(xy 60.896746 -313.073066) (xy 60.881162 -313.119747) (xy 60.858291 -313.163324) (xy 60.828726 -313.202668)
			(xy 60.793233 -313.23676) (xy 60.75273 -313.264716) (xy 60.708268 -313.285814) (xy 60.660997 -313.299506)
			(xy 60.612142 -313.305438) (xy 60.562967 -313.303457) (xy 60.514748 -313.293613) (xy 60.468732 -313.276161)
			(xy 60.426111 -313.251554) (xy 60.38799 -313.220429) (xy 60.355355 -313.183592) (xy 60.329052 -313.141996)
			(xy 60.309761 -313.09672) (xy 60.297984 -313.048936) (xy 60.294024 -312.999882) (xy 59.97702 -312.999882)
			(xy 59.976516 -313.02559) (xy 59.968473 -313.076372) (xy 59.952585 -313.125271) (xy 59.929242 -313.171083)
			(xy 59.899021 -313.212679) (xy 59.862665 -313.249035) (xy 59.821069 -313.279256) (xy 59.775257 -313.302599)
			(xy 59.726358 -313.318487) (xy 59.675576 -313.32653) (xy 59.62416 -313.32653) (xy 59.573378 -313.318487)
			(xy 59.524479 -313.302599) (xy 59.478667 -313.279256) (xy 59.437071 -313.249035) (xy 59.400715 -313.212679)
			(xy 59.370494 -313.171083) (xy 59.347151 -313.125271) (xy 59.331263 -313.076372) (xy 59.32322 -313.02559)
			(xy 59.004542 -313.02559) (xy 58.996826 -313.073066) (xy 58.981242 -313.119747) (xy 58.958371 -313.163324)
			(xy 58.928806 -313.202668) (xy 58.893313 -313.23676) (xy 58.85281 -313.264716) (xy 58.808348 -313.285814)
			(xy 58.761077 -313.299506) (xy 58.712222 -313.305438) (xy 58.663047 -313.303457) (xy 58.614828 -313.293613)
			(xy 58.568812 -313.276161) (xy 58.526191 -313.251554) (xy 58.48807 -313.220429) (xy 58.455435 -313.183592)
			(xy 58.429132 -313.141996) (xy 58.409841 -313.09672) (xy 58.398064 -313.048936) (xy 58.394104 -312.999882)
			(xy 58.055256 -312.999882) (xy 58.054761 -313.024489) (xy 58.046866 -313.073066) (xy 58.031282 -313.119747)
			(xy 58.008411 -313.163324) (xy 57.978846 -313.202668) (xy 57.943353 -313.23676) (xy 57.90285 -313.264716)
			(xy 57.858388 -313.285814) (xy 57.811117 -313.299506) (xy 57.762262 -313.305438) (xy 57.713087 -313.303457)
			(xy 57.664868 -313.293613) (xy 57.618852 -313.276161) (xy 57.576231 -313.251554) (xy 57.53811 -313.220429)
			(xy 57.505475 -313.183592) (xy 57.479172 -313.141996) (xy 57.459881 -313.09672) (xy 57.448104 -313.048936)
			(xy 57.444144 -312.999882) (xy 57.105296 -312.999882) (xy 57.104801 -313.024489) (xy 57.096906 -313.073066)
			(xy 57.081322 -313.119747) (xy 57.058451 -313.163324) (xy 57.028886 -313.202668) (xy 56.993393 -313.23676)
			(xy 56.95289 -313.264716) (xy 56.908428 -313.285814) (xy 56.861157 -313.299506) (xy 56.812302 -313.305438)
			(xy 56.763127 -313.303457) (xy 56.714908 -313.293613) (xy 56.668892 -313.276161) (xy 56.626271 -313.251554)
			(xy 56.58815 -313.220429) (xy 56.555515 -313.183592) (xy 56.529212 -313.141996) (xy 56.509921 -313.09672)
			(xy 56.498144 -313.048936) (xy 56.494184 -312.999882) (xy 56.155082 -312.999882) (xy 56.154587 -313.024489)
			(xy 56.146692 -313.073066) (xy 56.131108 -313.119747) (xy 56.108237 -313.163324) (xy 56.078672 -313.202668)
			(xy 56.043179 -313.23676) (xy 56.002676 -313.264716) (xy 55.958214 -313.285814) (xy 55.910943 -313.299506)
			(xy 55.862088 -313.305438) (xy 55.812913 -313.303457) (xy 55.764694 -313.293613) (xy 55.718678 -313.276161)
			(xy 55.676057 -313.251554) (xy 55.637936 -313.220429) (xy 55.605301 -313.183592) (xy 55.578998 -313.141996)
			(xy 55.559707 -313.09672) (xy 55.54793 -313.048936) (xy 55.54397 -312.999882) (xy 55.205122 -312.999882)
			(xy 55.204627 -313.024489) (xy 55.196732 -313.073066) (xy 55.181148 -313.119747) (xy 55.158277 -313.163324)
			(xy 55.128712 -313.202668) (xy 55.093219 -313.23676) (xy 55.052716 -313.264716) (xy 55.008254 -313.285814)
			(xy 54.960983 -313.299506) (xy 54.912128 -313.305438) (xy 54.862953 -313.303457) (xy 54.814734 -313.293613)
			(xy 54.768718 -313.276161) (xy 54.726097 -313.251554) (xy 54.687976 -313.220429) (xy 54.655341 -313.183592)
			(xy 54.629038 -313.141996) (xy 54.609747 -313.09672) (xy 54.59797 -313.048936) (xy 54.59401 -312.999882)
			(xy 54.255162 -312.999882) (xy 54.254667 -313.024489) (xy 54.246772 -313.073066) (xy 54.231188 -313.119747)
			(xy 54.208317 -313.163324) (xy 54.178752 -313.202668) (xy 54.143259 -313.23676) (xy 54.102756 -313.264716)
			(xy 54.058294 -313.285814) (xy 54.011023 -313.299506) (xy 53.962168 -313.305438) (xy 53.912993 -313.303457)
			(xy 53.864774 -313.293613) (xy 53.818758 -313.276161) (xy 53.776137 -313.251554) (xy 53.738016 -313.220429)
			(xy 53.705381 -313.183592) (xy 53.679078 -313.141996) (xy 53.659787 -313.09672) (xy 53.64801 -313.048936)
			(xy 53.64405 -312.999882) (xy 53.305202 -312.999882) (xy 53.304707 -313.024489) (xy 53.296812 -313.073066)
			(xy 53.281228 -313.119747) (xy 53.258357 -313.163324) (xy 53.228792 -313.202668) (xy 53.193299 -313.23676)
			(xy 53.152796 -313.264716) (xy 53.108334 -313.285814) (xy 53.061063 -313.299506) (xy 53.012208 -313.305438)
			(xy 52.963033 -313.303457) (xy 52.914814 -313.293613) (xy 52.868798 -313.276161) (xy 52.826177 -313.251554)
			(xy 52.788056 -313.220429) (xy 52.755421 -313.183592) (xy 52.729118 -313.141996) (xy 52.709827 -313.09672)
			(xy 52.69805 -313.048936) (xy 52.69409 -312.999882) (xy 52.355242 -312.999882) (xy 52.354747 -313.024489)
			(xy 52.346852 -313.073066) (xy 52.331268 -313.119747) (xy 52.308397 -313.163324) (xy 52.278832 -313.202668)
			(xy 52.243339 -313.23676) (xy 52.202836 -313.264716) (xy 52.158374 -313.285814) (xy 52.111103 -313.299506)
			(xy 52.062248 -313.305438) (xy 52.013073 -313.303457) (xy 51.964854 -313.293613) (xy 51.918838 -313.276161)
			(xy 51.876217 -313.251554) (xy 51.838096 -313.220429) (xy 51.805461 -313.183592) (xy 51.779158 -313.141996)
			(xy 51.759867 -313.09672) (xy 51.74809 -313.048936) (xy 51.74413 -312.999882) (xy 51.405282 -312.999882)
			(xy 51.404787 -313.024489) (xy 51.396892 -313.073066) (xy 51.381308 -313.119747) (xy 51.358437 -313.163324)
			(xy 51.328872 -313.202668) (xy 51.293379 -313.23676) (xy 51.252876 -313.264716) (xy 51.208414 -313.285814)
			(xy 51.161143 -313.299506) (xy 51.112288 -313.305438) (xy 51.063113 -313.303457) (xy 51.014894 -313.293613)
			(xy 50.968878 -313.276161) (xy 50.926257 -313.251554) (xy 50.888136 -313.220429) (xy 50.855501 -313.183592)
			(xy 50.829198 -313.141996) (xy 50.809907 -313.09672) (xy 50.79813 -313.048936) (xy 50.79417 -312.999882)
			(xy 50.455068 -312.999882) (xy 50.454573 -313.024489) (xy 50.446678 -313.073066) (xy 50.431094 -313.119747)
			(xy 50.408223 -313.163324) (xy 50.378658 -313.202668) (xy 50.343165 -313.23676) (xy 50.302662 -313.264716)
			(xy 50.2582 -313.285814) (xy 50.210929 -313.299506) (xy 50.162074 -313.305438) (xy 50.112899 -313.303457)
			(xy 50.06468 -313.293613) (xy 50.018664 -313.276161) (xy 49.976043 -313.251554) (xy 49.937922 -313.220429)
			(xy 49.905287 -313.183592) (xy 49.878984 -313.141996) (xy 49.859693 -313.09672) (xy 49.847916 -313.048936)
			(xy 49.843956 -312.999882) (xy 49.505108 -312.999882) (xy 49.504613 -313.024489) (xy 49.496718 -313.073066)
			(xy 49.481134 -313.119747) (xy 49.458263 -313.163324) (xy 49.428698 -313.202668) (xy 49.393205 -313.23676)
			(xy 49.352702 -313.264716) (xy 49.30824 -313.285814) (xy 49.260969 -313.299506) (xy 49.212114 -313.305438)
			(xy 49.162939 -313.303457) (xy 49.11472 -313.293613) (xy 49.068704 -313.276161) (xy 49.026083 -313.251554)
			(xy 48.987962 -313.220429) (xy 48.955327 -313.183592) (xy 48.929024 -313.141996) (xy 48.909733 -313.09672)
			(xy 48.897956 -313.048936) (xy 48.893996 -312.999882) (xy 48.555148 -312.999882) (xy 48.554653 -313.024489)
			(xy 48.546758 -313.073066) (xy 48.531174 -313.119747) (xy 48.508303 -313.163324) (xy 48.478738 -313.202668)
			(xy 48.443245 -313.23676) (xy 48.402742 -313.264716) (xy 48.35828 -313.285814) (xy 48.311009 -313.299506)
			(xy 48.262154 -313.305438) (xy 48.212979 -313.303457) (xy 48.16476 -313.293613) (xy 48.118744 -313.276161)
			(xy 48.076123 -313.251554) (xy 48.038002 -313.220429) (xy 48.005367 -313.183592) (xy 47.979064 -313.141996)
			(xy 47.959773 -313.09672) (xy 47.947996 -313.048936) (xy 47.944036 -312.999882) (xy 47.605188 -312.999882)
			(xy 47.604693 -313.024489) (xy 47.596798 -313.073066) (xy 47.581214 -313.119747) (xy 47.558343 -313.163324)
			(xy 47.528778 -313.202668) (xy 47.493285 -313.23676) (xy 47.452782 -313.264716) (xy 47.40832 -313.285814)
			(xy 47.361049 -313.299506) (xy 47.312194 -313.305438) (xy 47.263019 -313.303457) (xy 47.2148 -313.293613)
			(xy 47.168784 -313.276161) (xy 47.126163 -313.251554) (xy 47.088042 -313.220429) (xy 47.055407 -313.183592)
			(xy 47.029104 -313.141996) (xy 47.009813 -313.09672) (xy 46.998036 -313.048936) (xy 46.994076 -312.999882)
			(xy 46.655228 -312.999882) (xy 46.654733 -313.024489) (xy 46.646838 -313.073066) (xy 46.631254 -313.119747)
			(xy 46.608383 -313.163324) (xy 46.578818 -313.202668) (xy 46.543325 -313.23676) (xy 46.502822 -313.264716)
			(xy 46.45836 -313.285814) (xy 46.411089 -313.299506) (xy 46.362234 -313.305438) (xy 46.313059 -313.303457)
			(xy 46.26484 -313.293613) (xy 46.218824 -313.276161) (xy 46.176203 -313.251554) (xy 46.138082 -313.220429)
			(xy 46.105447 -313.183592) (xy 46.079144 -313.141996) (xy 46.059853 -313.09672) (xy 46.048076 -313.048936)
			(xy 46.044116 -312.999882) (xy 45.705268 -312.999882) (xy 45.704773 -313.024489) (xy 45.696878 -313.073066)
			(xy 45.681294 -313.119747) (xy 45.658423 -313.163324) (xy 45.628858 -313.202668) (xy 45.593365 -313.23676)
			(xy 45.552862 -313.264716) (xy 45.5084 -313.285814) (xy 45.461129 -313.299506) (xy 45.412274 -313.305438)
			(xy 45.363099 -313.303457) (xy 45.31488 -313.293613) (xy 45.268864 -313.276161) (xy 45.226243 -313.251554)
			(xy 45.188122 -313.220429) (xy 45.155487 -313.183592) (xy 45.129184 -313.141996) (xy 45.109893 -313.09672)
			(xy 45.098116 -313.048936) (xy 45.094156 -312.999882) (xy 44.755054 -312.999882) (xy 44.754559 -313.024489)
			(xy 44.746664 -313.073066) (xy 44.73108 -313.119747) (xy 44.708209 -313.163324) (xy 44.678644 -313.202668)
			(xy 44.643151 -313.23676) (xy 44.602648 -313.264716) (xy 44.558186 -313.285814) (xy 44.510915 -313.299506)
			(xy 44.46206 -313.305438) (xy 44.412885 -313.303457) (xy 44.364666 -313.293613) (xy 44.31865 -313.276161)
			(xy 44.276029 -313.251554) (xy 44.237908 -313.220429) (xy 44.205273 -313.183592) (xy 44.17897 -313.141996)
			(xy 44.159679 -313.09672) (xy 44.147902 -313.048936) (xy 44.143942 -312.999882) (xy 43.805094 -312.999882)
			(xy 43.804599 -313.024489) (xy 43.796704 -313.073066) (xy 43.78112 -313.119747) (xy 43.758249 -313.163324)
			(xy 43.728684 -313.202668) (xy 43.693191 -313.23676) (xy 43.652688 -313.264716) (xy 43.608226 -313.285814)
			(xy 43.560955 -313.299506) (xy 43.5121 -313.305438) (xy 43.462925 -313.303457) (xy 43.414706 -313.293613)
			(xy 43.36869 -313.276161) (xy 43.326069 -313.251554) (xy 43.287948 -313.220429) (xy 43.255313 -313.183592)
			(xy 43.22901 -313.141996) (xy 43.209719 -313.09672) (xy 43.197942 -313.048936) (xy 43.193982 -312.999882)
			(xy 42.876978 -312.999882) (xy 42.876474 -313.02559) (xy 42.868431 -313.076372) (xy 42.852543 -313.125271)
			(xy 42.8292 -313.171083) (xy 42.798979 -313.212679) (xy 42.762623 -313.249035) (xy 42.721027 -313.279256)
			(xy 42.675215 -313.302599) (xy 42.626316 -313.318487) (xy 42.575534 -313.32653) (xy 42.524118 -313.32653)
			(xy 42.473336 -313.318487) (xy 42.424437 -313.302599) (xy 42.378625 -313.279256) (xy 42.337029 -313.249035)
			(xy 42.300673 -313.212679) (xy 42.270452 -313.171083) (xy 42.247109 -313.125271) (xy 42.231221 -313.076372)
			(xy 42.223178 -313.02559) (xy 41.9045 -313.02559) (xy 41.896784 -313.073066) (xy 41.8812 -313.119747)
			(xy 41.858329 -313.163324) (xy 41.828764 -313.202668) (xy 41.793271 -313.23676) (xy 41.752768 -313.264716)
			(xy 41.708306 -313.285814) (xy 41.661035 -313.299506) (xy 41.61218 -313.305438) (xy 41.563005 -313.303457)
			(xy 41.514786 -313.293613) (xy 41.46877 -313.276161) (xy 41.426149 -313.251554) (xy 41.388028 -313.220429)
			(xy 41.355393 -313.183592) (xy 41.32909 -313.141996) (xy 41.309799 -313.09672) (xy 41.298022 -313.048936)
			(xy 41.294062 -312.999882) (xy 40.977058 -312.999882) (xy 40.976554 -313.02559) (xy 40.968511 -313.076372)
			(xy 40.952623 -313.125271) (xy 40.92928 -313.171083) (xy 40.899059 -313.212679) (xy 40.862703 -313.249035)
			(xy 40.821107 -313.279256) (xy 40.775295 -313.302599) (xy 40.726396 -313.318487) (xy 40.675614 -313.32653)
			(xy 40.624198 -313.32653) (xy 40.573416 -313.318487) (xy 40.524517 -313.302599) (xy 40.478705 -313.279256)
			(xy 40.437109 -313.249035) (xy 40.400753 -313.212679) (xy 40.370532 -313.171083) (xy 40.347189 -313.125271)
			(xy 40.331301 -313.076372) (xy 40.323258 -313.02559) (xy 40.00458 -313.02559) (xy 39.996864 -313.073066)
			(xy 39.98128 -313.119747) (xy 39.958409 -313.163324) (xy 39.928844 -313.202668) (xy 39.893351 -313.23676)
			(xy 39.852848 -313.264716) (xy 39.808386 -313.285814) (xy 39.761115 -313.299506) (xy 39.71226 -313.305438)
			(xy 39.663085 -313.303457) (xy 39.614866 -313.293613) (xy 39.56885 -313.276161) (xy 39.526229 -313.251554)
			(xy 39.488108 -313.220429) (xy 39.455473 -313.183592) (xy 39.42917 -313.141996) (xy 39.409879 -313.09672)
			(xy 39.398102 -313.048936) (xy 39.394142 -312.999882) (xy 39.077138 -312.999882) (xy 39.076634 -313.02559)
			(xy 39.068591 -313.076372) (xy 39.052703 -313.125271) (xy 39.02936 -313.171083) (xy 38.999139 -313.212679)
			(xy 38.962783 -313.249035) (xy 38.921187 -313.279256) (xy 38.875375 -313.302599) (xy 38.826476 -313.318487)
			(xy 38.775694 -313.32653) (xy 38.724278 -313.32653) (xy 38.673496 -313.318487) (xy 38.624597 -313.302599)
			(xy 38.578785 -313.279256) (xy 38.537189 -313.249035) (xy 38.500833 -313.212679) (xy 38.470612 -313.171083)
			(xy 38.447269 -313.125271) (xy 38.431381 -313.076372) (xy 38.423338 -313.02559) (xy 38.104406 -313.02559)
			(xy 38.09669 -313.073066) (xy 38.081106 -313.119747) (xy 38.058235 -313.163324) (xy 38.02867 -313.202668)
			(xy 37.993177 -313.23676) (xy 37.952674 -313.264716) (xy 37.908212 -313.285814) (xy 37.860941 -313.299506)
			(xy 37.812086 -313.305438) (xy 37.762911 -313.303457) (xy 37.714692 -313.293613) (xy 37.668676 -313.276161)
			(xy 37.626055 -313.251554) (xy 37.587934 -313.220429) (xy 37.555299 -313.183592) (xy 37.528996 -313.141996)
			(xy 37.509705 -313.09672) (xy 37.497928 -313.048936) (xy 37.493968 -312.999882) (xy 37.15512 -312.999882)
			(xy 37.154625 -313.024489) (xy 37.14673 -313.073066) (xy 37.131146 -313.119747) (xy 37.108275 -313.163324)
			(xy 37.07871 -313.202668) (xy 37.043217 -313.23676) (xy 37.002714 -313.264716) (xy 36.958252 -313.285814)
			(xy 36.910981 -313.299506) (xy 36.862126 -313.305438) (xy 36.812951 -313.303457) (xy 36.764732 -313.293613)
			(xy 36.718716 -313.276161) (xy 36.676095 -313.251554) (xy 36.637974 -313.220429) (xy 36.605339 -313.183592)
			(xy 36.579036 -313.141996) (xy 36.559745 -313.09672) (xy 36.547968 -313.048936) (xy 36.544008 -312.999882)
			(xy 17.635982 -312.999882) (xy 17.635982 -313.669934) (xy 34.021774 -313.669934) (xy 34.025845 -313.614312)
			(xy 34.037971 -313.559875) (xy 34.057894 -313.507784) (xy 34.08519 -313.459149) (xy 34.119276 -313.415006)
			(xy 34.159425 -313.376297) (xy 34.204783 -313.343846) (xy 34.254383 -313.318345) (xy 34.307167 -313.300338)
			(xy 34.36201 -313.290208) (xy 34.417744 -313.288171) (xy 34.473181 -313.294271) (xy 34.527138 -313.308377)
			(xy 34.578467 -313.330189) (xy 34.626073 -313.359243) (xy 34.668941 -313.394918) (xy 34.706158 -313.436455)
			(xy 34.736931 -313.482968) (xy 34.760603 -313.533465) (xy 34.776671 -313.586872) (xy 34.784791 -313.642048)
			(xy 34.7853 -313.669934) (xy 34.784791 -313.69782) (xy 34.776671 -313.752996) (xy 34.760603 -313.806403)
			(xy 34.736931 -313.8569) (xy 34.706158 -313.903413) (xy 34.668941 -313.94495) (xy 34.663063 -313.949842)
			(xy 36.544008 -313.949842) (xy 36.547968 -313.900788) (xy 36.559745 -313.853004) (xy 36.579036 -313.807728)
			(xy 36.605339 -313.766132) (xy 36.637974 -313.729295) (xy 36.676095 -313.69817) (xy 36.718716 -313.673563)
			(xy 36.764732 -313.656111) (xy 36.812951 -313.646267) (xy 36.862126 -313.644286) (xy 36.910981 -313.650218)
			(xy 36.958252 -313.66391) (xy 37.002714 -313.685008) (xy 37.043217 -313.712964) (xy 37.07871 -313.747056)
			(xy 37.108275 -313.7864) (xy 37.131146 -313.829977) (xy 37.14673 -313.876658) (xy 37.154625 -313.925235)
			(xy 37.15512 -313.949842) (xy 37.493968 -313.949842) (xy 37.497928 -313.900788) (xy 37.509705 -313.853004)
			(xy 37.528996 -313.807728) (xy 37.555299 -313.766132) (xy 37.587934 -313.729295) (xy 37.626055 -313.69817)
			(xy 37.668676 -313.673563) (xy 37.714692 -313.656111) (xy 37.762911 -313.646267) (xy 37.812086 -313.644286)
			(xy 37.860941 -313.650218) (xy 37.908212 -313.66391) (xy 37.952674 -313.685008) (xy 37.993177 -313.712964)
			(xy 38.02867 -313.747056) (xy 38.058235 -313.7864) (xy 38.081106 -313.829977) (xy 38.09669 -313.876658)
			(xy 38.104585 -313.925235) (xy 38.10508 -313.949842) (xy 38.104585 -313.974449) (xy 38.104406 -313.97555)
			(xy 38.423338 -313.97555) (xy 38.423338 -313.924134) (xy 38.431381 -313.873352) (xy 38.447269 -313.824453)
			(xy 38.470612 -313.778641) (xy 38.500833 -313.737045) (xy 38.537189 -313.700689) (xy 38.578785 -313.670468)
			(xy 38.624597 -313.647125) (xy 38.673496 -313.631237) (xy 38.724278 -313.623194) (xy 38.775694 -313.623194)
			(xy 38.826476 -313.631237) (xy 38.875375 -313.647125) (xy 38.921187 -313.670468) (xy 38.962783 -313.700689)
			(xy 38.999139 -313.737045) (xy 39.02936 -313.778641) (xy 39.052703 -313.824453) (xy 39.068591 -313.873352)
			(xy 39.076634 -313.924134) (xy 39.077138 -313.949842) (xy 39.394142 -313.949842) (xy 39.398102 -313.900788)
			(xy 39.409879 -313.853004) (xy 39.42917 -313.807728) (xy 39.455473 -313.766132) (xy 39.488108 -313.729295)
			(xy 39.526229 -313.69817) (xy 39.56885 -313.673563) (xy 39.614866 -313.656111) (xy 39.663085 -313.646267)
			(xy 39.71226 -313.644286) (xy 39.761115 -313.650218) (xy 39.808386 -313.66391) (xy 39.852848 -313.685008)
			(xy 39.893351 -313.712964) (xy 39.928844 -313.747056) (xy 39.958409 -313.7864) (xy 39.98128 -313.829977)
			(xy 39.996864 -313.876658) (xy 40.004759 -313.925235) (xy 40.005254 -313.949842) (xy 40.004759 -313.974449)
			(xy 40.00458 -313.97555) (xy 40.323258 -313.97555) (xy 40.323258 -313.924134) (xy 40.331301 -313.873352)
			(xy 40.347189 -313.824453) (xy 40.370532 -313.778641) (xy 40.400753 -313.737045) (xy 40.437109 -313.700689)
			(xy 40.478705 -313.670468) (xy 40.524517 -313.647125) (xy 40.573416 -313.631237) (xy 40.624198 -313.623194)
			(xy 40.675614 -313.623194) (xy 40.726396 -313.631237) (xy 40.775295 -313.647125) (xy 40.821107 -313.670468)
			(xy 40.862703 -313.700689) (xy 40.899059 -313.737045) (xy 40.92928 -313.778641) (xy 40.952623 -313.824453)
			(xy 40.968511 -313.873352) (xy 40.976554 -313.924134) (xy 40.977058 -313.949842) (xy 41.294062 -313.949842)
			(xy 41.298022 -313.900788) (xy 41.309799 -313.853004) (xy 41.32909 -313.807728) (xy 41.355393 -313.766132)
			(xy 41.388028 -313.729295) (xy 41.426149 -313.69817) (xy 41.46877 -313.673563) (xy 41.514786 -313.656111)
			(xy 41.563005 -313.646267) (xy 41.61218 -313.644286) (xy 41.661035 -313.650218) (xy 41.708306 -313.66391)
			(xy 41.752768 -313.685008) (xy 41.793271 -313.712964) (xy 41.828764 -313.747056) (xy 41.858329 -313.7864)
			(xy 41.8812 -313.829977) (xy 41.896784 -313.876658) (xy 41.904679 -313.925235) (xy 41.905174 -313.949842)
			(xy 41.904679 -313.974449) (xy 41.9045 -313.97555) (xy 42.223178 -313.97555) (xy 42.223178 -313.924134)
			(xy 42.231221 -313.873352) (xy 42.247109 -313.824453) (xy 42.270452 -313.778641) (xy 42.300673 -313.737045)
			(xy 42.337029 -313.700689) (xy 42.378625 -313.670468) (xy 42.424437 -313.647125) (xy 42.473336 -313.631237)
			(xy 42.524118 -313.623194) (xy 42.575534 -313.623194) (xy 42.626316 -313.631237) (xy 42.675215 -313.647125)
			(xy 42.721027 -313.670468) (xy 42.762623 -313.700689) (xy 42.798979 -313.737045) (xy 42.8292 -313.778641)
			(xy 42.852543 -313.824453) (xy 42.868431 -313.873352) (xy 42.876474 -313.924134) (xy 42.876978 -313.949842)
			(xy 43.193982 -313.949842) (xy 43.197942 -313.900788) (xy 43.209719 -313.853004) (xy 43.22901 -313.807728)
			(xy 43.255313 -313.766132) (xy 43.287948 -313.729295) (xy 43.326069 -313.69817) (xy 43.36869 -313.673563)
			(xy 43.414706 -313.656111) (xy 43.462925 -313.646267) (xy 43.5121 -313.644286) (xy 43.560955 -313.650218)
			(xy 43.608226 -313.66391) (xy 43.652688 -313.685008) (xy 43.693191 -313.712964) (xy 43.728684 -313.747056)
			(xy 43.758249 -313.7864) (xy 43.78112 -313.829977) (xy 43.796704 -313.876658) (xy 43.804599 -313.925235)
			(xy 43.805094 -313.949842) (xy 44.143942 -313.949842) (xy 44.147902 -313.900788) (xy 44.159679 -313.853004)
			(xy 44.17897 -313.807728) (xy 44.205273 -313.766132) (xy 44.237908 -313.729295) (xy 44.276029 -313.69817)
			(xy 44.31865 -313.673563) (xy 44.364666 -313.656111) (xy 44.412885 -313.646267) (xy 44.46206 -313.644286)
			(xy 44.510915 -313.650218) (xy 44.558186 -313.66391) (xy 44.602648 -313.685008) (xy 44.643151 -313.712964)
			(xy 44.678644 -313.747056) (xy 44.708209 -313.7864) (xy 44.73108 -313.829977) (xy 44.746664 -313.876658)
			(xy 44.754559 -313.925235) (xy 44.755054 -313.949842) (xy 45.094156 -313.949842) (xy 45.098116 -313.900788)
			(xy 45.109893 -313.853004) (xy 45.129184 -313.807728) (xy 45.155487 -313.766132) (xy 45.188122 -313.729295)
			(xy 45.226243 -313.69817) (xy 45.268864 -313.673563) (xy 45.31488 -313.656111) (xy 45.363099 -313.646267)
			(xy 45.412274 -313.644286) (xy 45.461129 -313.650218) (xy 45.5084 -313.66391) (xy 45.552862 -313.685008)
			(xy 45.593365 -313.712964) (xy 45.628858 -313.747056) (xy 45.658423 -313.7864) (xy 45.681294 -313.829977)
			(xy 45.696878 -313.876658) (xy 45.704773 -313.925235) (xy 45.705268 -313.949842) (xy 46.044116 -313.949842)
			(xy 46.048076 -313.900788) (xy 46.059853 -313.853004) (xy 46.079144 -313.807728) (xy 46.105447 -313.766132)
			(xy 46.138082 -313.729295) (xy 46.176203 -313.69817) (xy 46.218824 -313.673563) (xy 46.26484 -313.656111)
			(xy 46.313059 -313.646267) (xy 46.362234 -313.644286) (xy 46.411089 -313.650218) (xy 46.45836 -313.66391)
			(xy 46.502822 -313.685008) (xy 46.543325 -313.712964) (xy 46.578818 -313.747056) (xy 46.608383 -313.7864)
			(xy 46.631254 -313.829977) (xy 46.646838 -313.876658) (xy 46.654733 -313.925235) (xy 46.655228 -313.949842)
			(xy 46.994076 -313.949842) (xy 46.998036 -313.900788) (xy 47.009813 -313.853004) (xy 47.029104 -313.807728)
			(xy 47.055407 -313.766132) (xy 47.088042 -313.729295) (xy 47.126163 -313.69817) (xy 47.168784 -313.673563)
			(xy 47.2148 -313.656111) (xy 47.263019 -313.646267) (xy 47.312194 -313.644286) (xy 47.361049 -313.650218)
			(xy 47.40832 -313.66391) (xy 47.452782 -313.685008) (xy 47.493285 -313.712964) (xy 47.528778 -313.747056)
			(xy 47.558343 -313.7864) (xy 47.581214 -313.829977) (xy 47.596798 -313.876658) (xy 47.604693 -313.925235)
			(xy 47.605188 -313.949842) (xy 47.944036 -313.949842) (xy 47.947996 -313.900788) (xy 47.959773 -313.853004)
			(xy 47.979064 -313.807728) (xy 48.005367 -313.766132) (xy 48.038002 -313.729295) (xy 48.076123 -313.69817)
			(xy 48.118744 -313.673563) (xy 48.16476 -313.656111) (xy 48.212979 -313.646267) (xy 48.262154 -313.644286)
			(xy 48.311009 -313.650218) (xy 48.35828 -313.66391) (xy 48.402742 -313.685008) (xy 48.443245 -313.712964)
			(xy 48.478738 -313.747056) (xy 48.508303 -313.7864) (xy 48.531174 -313.829977) (xy 48.546758 -313.876658)
			(xy 48.554653 -313.925235) (xy 48.555148 -313.949842) (xy 48.893996 -313.949842) (xy 48.897956 -313.900788)
			(xy 48.909733 -313.853004) (xy 48.929024 -313.807728) (xy 48.955327 -313.766132) (xy 48.987962 -313.729295)
			(xy 49.026083 -313.69817) (xy 49.068704 -313.673563) (xy 49.11472 -313.656111) (xy 49.162939 -313.646267)
			(xy 49.212114 -313.644286) (xy 49.260969 -313.650218) (xy 49.30824 -313.66391) (xy 49.352702 -313.685008)
			(xy 49.393205 -313.712964) (xy 49.428698 -313.747056) (xy 49.458263 -313.7864) (xy 49.481134 -313.829977)
			(xy 49.496718 -313.876658) (xy 49.504613 -313.925235) (xy 49.505108 -313.949842) (xy 49.843956 -313.949842)
			(xy 49.847916 -313.900788) (xy 49.859693 -313.853004) (xy 49.878984 -313.807728) (xy 49.905287 -313.766132)
			(xy 49.937922 -313.729295) (xy 49.976043 -313.69817) (xy 50.018664 -313.673563) (xy 50.06468 -313.656111)
			(xy 50.112899 -313.646267) (xy 50.162074 -313.644286) (xy 50.210929 -313.650218) (xy 50.2582 -313.66391)
			(xy 50.302662 -313.685008) (xy 50.343165 -313.712964) (xy 50.378658 -313.747056) (xy 50.408223 -313.7864)
			(xy 50.431094 -313.829977) (xy 50.446678 -313.876658) (xy 50.454573 -313.925235) (xy 50.455068 -313.949842)
			(xy 50.79417 -313.949842) (xy 50.79813 -313.900788) (xy 50.809907 -313.853004) (xy 50.829198 -313.807728)
			(xy 50.855501 -313.766132) (xy 50.888136 -313.729295) (xy 50.926257 -313.69817) (xy 50.968878 -313.673563)
			(xy 51.014894 -313.656111) (xy 51.063113 -313.646267) (xy 51.112288 -313.644286) (xy 51.161143 -313.650218)
			(xy 51.208414 -313.66391) (xy 51.252876 -313.685008) (xy 51.293379 -313.712964) (xy 51.328872 -313.747056)
			(xy 51.358437 -313.7864) (xy 51.381308 -313.829977) (xy 51.396892 -313.876658) (xy 51.404787 -313.925235)
			(xy 51.405282 -313.949842) (xy 51.74413 -313.949842) (xy 51.74809 -313.900788) (xy 51.759867 -313.853004)
			(xy 51.779158 -313.807728) (xy 51.805461 -313.766132) (xy 51.838096 -313.729295) (xy 51.876217 -313.69817)
			(xy 51.918838 -313.673563) (xy 51.964854 -313.656111) (xy 52.013073 -313.646267) (xy 52.062248 -313.644286)
			(xy 52.111103 -313.650218) (xy 52.158374 -313.66391) (xy 52.202836 -313.685008) (xy 52.243339 -313.712964)
			(xy 52.278832 -313.747056) (xy 52.308397 -313.7864) (xy 52.331268 -313.829977) (xy 52.346852 -313.876658)
			(xy 52.354747 -313.925235) (xy 52.355242 -313.949842) (xy 52.69409 -313.949842) (xy 52.69805 -313.900788)
			(xy 52.709827 -313.853004) (xy 52.729118 -313.807728) (xy 52.755421 -313.766132) (xy 52.788056 -313.729295)
			(xy 52.826177 -313.69817) (xy 52.868798 -313.673563) (xy 52.914814 -313.656111) (xy 52.963033 -313.646267)
			(xy 53.012208 -313.644286) (xy 53.061063 -313.650218) (xy 53.108334 -313.66391) (xy 53.152796 -313.685008)
			(xy 53.193299 -313.712964) (xy 53.228792 -313.747056) (xy 53.258357 -313.7864) (xy 53.281228 -313.829977)
			(xy 53.296812 -313.876658) (xy 53.304707 -313.925235) (xy 53.305202 -313.949842) (xy 53.64405 -313.949842)
			(xy 53.64801 -313.900788) (xy 53.659787 -313.853004) (xy 53.679078 -313.807728) (xy 53.705381 -313.766132)
			(xy 53.738016 -313.729295) (xy 53.776137 -313.69817) (xy 53.818758 -313.673563) (xy 53.864774 -313.656111)
			(xy 53.912993 -313.646267) (xy 53.962168 -313.644286) (xy 54.011023 -313.650218) (xy 54.058294 -313.66391)
			(xy 54.102756 -313.685008) (xy 54.143259 -313.712964) (xy 54.178752 -313.747056) (xy 54.208317 -313.7864)
			(xy 54.231188 -313.829977) (xy 54.246772 -313.876658) (xy 54.254667 -313.925235) (xy 54.255162 -313.949842)
			(xy 54.59401 -313.949842) (xy 54.59797 -313.900788) (xy 54.609747 -313.853004) (xy 54.629038 -313.807728)
			(xy 54.655341 -313.766132) (xy 54.687976 -313.729295) (xy 54.726097 -313.69817) (xy 54.768718 -313.673563)
			(xy 54.814734 -313.656111) (xy 54.862953 -313.646267) (xy 54.912128 -313.644286) (xy 54.960983 -313.650218)
			(xy 55.008254 -313.66391) (xy 55.052716 -313.685008) (xy 55.093219 -313.712964) (xy 55.128712 -313.747056)
			(xy 55.158277 -313.7864) (xy 55.181148 -313.829977) (xy 55.196732 -313.876658) (xy 55.204627 -313.925235)
			(xy 55.205122 -313.949842) (xy 55.54397 -313.949842) (xy 55.54793 -313.900788) (xy 55.559707 -313.853004)
			(xy 55.578998 -313.807728) (xy 55.605301 -313.766132) (xy 55.637936 -313.729295) (xy 55.676057 -313.69817)
			(xy 55.718678 -313.673563) (xy 55.764694 -313.656111) (xy 55.812913 -313.646267) (xy 55.862088 -313.644286)
			(xy 55.910943 -313.650218) (xy 55.958214 -313.66391) (xy 56.002676 -313.685008) (xy 56.043179 -313.712964)
			(xy 56.078672 -313.747056) (xy 56.108237 -313.7864) (xy 56.131108 -313.829977) (xy 56.146692 -313.876658)
			(xy 56.154587 -313.925235) (xy 56.155082 -313.949842) (xy 56.494184 -313.949842) (xy 56.498144 -313.900788)
			(xy 56.509921 -313.853004) (xy 56.529212 -313.807728) (xy 56.555515 -313.766132) (xy 56.58815 -313.729295)
			(xy 56.626271 -313.69817) (xy 56.668892 -313.673563) (xy 56.714908 -313.656111) (xy 56.763127 -313.646267)
			(xy 56.812302 -313.644286) (xy 56.861157 -313.650218) (xy 56.908428 -313.66391) (xy 56.95289 -313.685008)
			(xy 56.993393 -313.712964) (xy 57.028886 -313.747056) (xy 57.058451 -313.7864) (xy 57.081322 -313.829977)
			(xy 57.096906 -313.876658) (xy 57.104801 -313.925235) (xy 57.105296 -313.949842) (xy 57.444144 -313.949842)
			(xy 57.448104 -313.900788) (xy 57.459881 -313.853004) (xy 57.479172 -313.807728) (xy 57.505475 -313.766132)
			(xy 57.53811 -313.729295) (xy 57.576231 -313.69817) (xy 57.618852 -313.673563) (xy 57.664868 -313.656111)
			(xy 57.713087 -313.646267) (xy 57.762262 -313.644286) (xy 57.811117 -313.650218) (xy 57.858388 -313.66391)
			(xy 57.90285 -313.685008) (xy 57.943353 -313.712964) (xy 57.978846 -313.747056) (xy 58.008411 -313.7864)
			(xy 58.031282 -313.829977) (xy 58.046866 -313.876658) (xy 58.054761 -313.925235) (xy 58.055256 -313.949842)
			(xy 58.394104 -313.949842) (xy 58.398064 -313.900788) (xy 58.409841 -313.853004) (xy 58.429132 -313.807728)
			(xy 58.455435 -313.766132) (xy 58.48807 -313.729295) (xy 58.526191 -313.69817) (xy 58.568812 -313.673563)
			(xy 58.614828 -313.656111) (xy 58.663047 -313.646267) (xy 58.712222 -313.644286) (xy 58.761077 -313.650218)
			(xy 58.808348 -313.66391) (xy 58.85281 -313.685008) (xy 58.893313 -313.712964) (xy 58.928806 -313.747056)
			(xy 58.958371 -313.7864) (xy 58.981242 -313.829977) (xy 58.996826 -313.876658) (xy 59.004721 -313.925235)
			(xy 59.005216 -313.949842) (xy 59.004721 -313.974449) (xy 59.004542 -313.97555) (xy 59.32322 -313.97555)
			(xy 59.32322 -313.924134) (xy 59.331263 -313.873352) (xy 59.347151 -313.824453) (xy 59.370494 -313.778641)
			(xy 59.400715 -313.737045) (xy 59.437071 -313.700689) (xy 59.478667 -313.670468) (xy 59.524479 -313.647125)
			(xy 59.573378 -313.631237) (xy 59.62416 -313.623194) (xy 59.675576 -313.623194) (xy 59.726358 -313.631237)
			(xy 59.775257 -313.647125) (xy 59.821069 -313.670468) (xy 59.862665 -313.700689) (xy 59.899021 -313.737045)
			(xy 59.929242 -313.778641) (xy 59.952585 -313.824453) (xy 59.968473 -313.873352) (xy 59.976516 -313.924134)
			(xy 59.97702 -313.949842) (xy 60.294024 -313.949842) (xy 60.297984 -313.900788) (xy 60.309761 -313.853004)
			(xy 60.329052 -313.807728) (xy 60.355355 -313.766132) (xy 60.38799 -313.729295) (xy 60.426111 -313.69817)
			(xy 60.468732 -313.673563) (xy 60.514748 -313.656111) (xy 60.562967 -313.646267) (xy 60.612142 -313.644286)
			(xy 60.660997 -313.650218) (xy 60.708268 -313.66391) (xy 60.75273 -313.685008) (xy 60.793233 -313.712964)
			(xy 60.828726 -313.747056) (xy 60.858291 -313.7864) (xy 60.881162 -313.829977) (xy 60.896746 -313.876658)
			(xy 60.904641 -313.925235) (xy 60.905136 -313.949842) (xy 60.904641 -313.974449) (xy 60.904462 -313.97555)
			(xy 61.22314 -313.97555) (xy 61.22314 -313.924134) (xy 61.231183 -313.873352) (xy 61.247071 -313.824453)
			(xy 61.270414 -313.778641) (xy 61.300635 -313.737045) (xy 61.336991 -313.700689) (xy 61.378587 -313.670468)
			(xy 61.424399 -313.647125) (xy 61.473298 -313.631237) (xy 61.52408 -313.623194) (xy 61.575496 -313.623194)
			(xy 61.626278 -313.631237) (xy 61.675177 -313.647125) (xy 61.720989 -313.670468) (xy 61.762585 -313.700689)
			(xy 61.798941 -313.737045) (xy 61.829162 -313.778641) (xy 61.852505 -313.824453) (xy 61.868393 -313.873352)
			(xy 61.876436 -313.924134) (xy 61.87694 -313.949842) (xy 62.193944 -313.949842) (xy 62.197904 -313.900788)
			(xy 62.209681 -313.853004) (xy 62.228972 -313.807728) (xy 62.255275 -313.766132) (xy 62.28791 -313.729295)
			(xy 62.326031 -313.69817) (xy 62.368652 -313.673563) (xy 62.414668 -313.656111) (xy 62.462887 -313.646267)
			(xy 62.512062 -313.644286) (xy 62.560917 -313.650218) (xy 62.608188 -313.66391) (xy 62.65265 -313.685008)
			(xy 62.693153 -313.712964) (xy 62.728646 -313.747056) (xy 62.758211 -313.7864) (xy 62.781082 -313.829977)
			(xy 62.796666 -313.876658) (xy 62.804561 -313.925235) (xy 62.805056 -313.949842) (xy 62.804561 -313.974449)
			(xy 62.804382 -313.97555) (xy 63.123314 -313.97555) (xy 63.123314 -313.924134) (xy 63.131357 -313.873352)
			(xy 63.147245 -313.824453) (xy 63.170588 -313.778641) (xy 63.200809 -313.737045) (xy 63.237165 -313.700689)
			(xy 63.278761 -313.670468) (xy 63.324573 -313.647125) (xy 63.373472 -313.631237) (xy 63.424254 -313.623194)
			(xy 63.47567 -313.623194) (xy 63.526452 -313.631237) (xy 63.575351 -313.647125) (xy 63.621163 -313.670468)
			(xy 63.662759 -313.700689) (xy 63.699115 -313.737045) (xy 63.729336 -313.778641) (xy 63.752679 -313.824453)
			(xy 63.768567 -313.873352) (xy 63.77661 -313.924134) (xy 63.777114 -313.949842) (xy 64.094118 -313.949842)
			(xy 64.098078 -313.900788) (xy 64.109855 -313.853004) (xy 64.129146 -313.807728) (xy 64.155449 -313.766132)
			(xy 64.188084 -313.729295) (xy 64.226205 -313.69817) (xy 64.268826 -313.673563) (xy 64.314842 -313.656111)
			(xy 64.363061 -313.646267) (xy 64.412236 -313.644286) (xy 64.461091 -313.650218) (xy 64.508362 -313.66391)
			(xy 64.552824 -313.685008) (xy 64.593327 -313.712964) (xy 64.62882 -313.747056) (xy 64.658385 -313.7864)
			(xy 64.681256 -313.829977) (xy 64.69684 -313.876658) (xy 64.704735 -313.925235) (xy 64.70523 -313.949842)
			(xy 64.704735 -313.974449) (xy 64.704556 -313.97555) (xy 65.023234 -313.97555) (xy 65.023234 -313.924134)
			(xy 65.031277 -313.873352) (xy 65.047165 -313.824453) (xy 65.070508 -313.778641) (xy 65.100729 -313.737045)
			(xy 65.137085 -313.700689) (xy 65.178681 -313.670468) (xy 65.224493 -313.647125) (xy 65.273392 -313.631237)
			(xy 65.324174 -313.623194) (xy 65.37559 -313.623194) (xy 65.426372 -313.631237) (xy 65.475271 -313.647125)
			(xy 65.521083 -313.670468) (xy 65.562679 -313.700689) (xy 65.599035 -313.737045) (xy 65.629256 -313.778641)
			(xy 65.652599 -313.824453) (xy 65.668487 -313.873352) (xy 65.67653 -313.924134) (xy 65.677034 -313.949842)
			(xy 65.994038 -313.949842) (xy 65.997998 -313.900788) (xy 66.009775 -313.853004) (xy 66.029066 -313.807728)
			(xy 66.055369 -313.766132) (xy 66.088004 -313.729295) (xy 66.126125 -313.69817) (xy 66.168746 -313.673563)
			(xy 66.214762 -313.656111) (xy 66.262981 -313.646267) (xy 66.312156 -313.644286) (xy 66.361011 -313.650218)
			(xy 66.408282 -313.66391) (xy 66.452744 -313.685008) (xy 66.493247 -313.712964) (xy 66.52874 -313.747056)
			(xy 66.558305 -313.7864) (xy 66.581176 -313.829977) (xy 66.59676 -313.876658) (xy 66.604655 -313.925235)
			(xy 66.60515 -313.949842) (xy 66.604655 -313.974449) (xy 66.604476 -313.97555) (xy 66.923154 -313.97555)
			(xy 66.923154 -313.924134) (xy 66.931197 -313.873352) (xy 66.947085 -313.824453) (xy 66.970428 -313.778641)
			(xy 67.000649 -313.737045) (xy 67.037005 -313.700689) (xy 67.078601 -313.670468) (xy 67.124413 -313.647125)
			(xy 67.173312 -313.631237) (xy 67.224094 -313.623194) (xy 67.27551 -313.623194) (xy 67.326292 -313.631237)
			(xy 67.375191 -313.647125) (xy 67.421003 -313.670468) (xy 67.462599 -313.700689) (xy 67.498955 -313.737045)
			(xy 67.529176 -313.778641) (xy 67.552519 -313.824453) (xy 67.568407 -313.873352) (xy 67.57645 -313.924134)
			(xy 67.576954 -313.949842) (xy 67.893958 -313.949842) (xy 67.897918 -313.900788) (xy 67.909695 -313.853004)
			(xy 67.928986 -313.807728) (xy 67.955289 -313.766132) (xy 67.987924 -313.729295) (xy 68.026045 -313.69817)
			(xy 68.068666 -313.673563) (xy 68.114682 -313.656111) (xy 68.162901 -313.646267) (xy 68.212076 -313.644286)
			(xy 68.260931 -313.650218) (xy 68.308202 -313.66391) (xy 68.352664 -313.685008) (xy 68.393167 -313.712964)
			(xy 68.42866 -313.747056) (xy 68.458225 -313.7864) (xy 68.481096 -313.829977) (xy 68.49668 -313.876658)
			(xy 68.504575 -313.925235) (xy 68.50507 -313.949842) (xy 68.504575 -313.974449) (xy 68.504396 -313.97555)
			(xy 68.823328 -313.97555) (xy 68.823328 -313.924134) (xy 68.831371 -313.873352) (xy 68.847259 -313.824453)
			(xy 68.870602 -313.778641) (xy 68.900823 -313.737045) (xy 68.937179 -313.700689) (xy 68.978775 -313.670468)
			(xy 69.024587 -313.647125) (xy 69.073486 -313.631237) (xy 69.124268 -313.623194) (xy 69.175684 -313.623194)
			(xy 69.226466 -313.631237) (xy 69.275365 -313.647125) (xy 69.321177 -313.670468) (xy 69.362773 -313.700689)
			(xy 69.399129 -313.737045) (xy 69.42935 -313.778641) (xy 69.452693 -313.824453) (xy 69.468581 -313.873352)
			(xy 69.476624 -313.924134) (xy 69.477128 -313.949842) (xy 69.794132 -313.949842) (xy 69.798092 -313.900788)
			(xy 69.809869 -313.853004) (xy 69.82916 -313.807728) (xy 69.855463 -313.766132) (xy 69.888098 -313.729295)
			(xy 69.926219 -313.69817) (xy 69.96884 -313.673563) (xy 70.014856 -313.656111) (xy 70.063075 -313.646267)
			(xy 70.11225 -313.644286) (xy 70.161105 -313.650218) (xy 70.208376 -313.66391) (xy 70.252838 -313.685008)
			(xy 70.293341 -313.712964) (xy 70.328834 -313.747056) (xy 70.358399 -313.7864) (xy 70.38127 -313.829977)
			(xy 70.396854 -313.876658) (xy 70.404749 -313.925235) (xy 70.405244 -313.949842) (xy 70.404749 -313.974449)
			(xy 70.40457 -313.97555) (xy 70.723248 -313.97555) (xy 70.723248 -313.924134) (xy 70.731291 -313.873352)
			(xy 70.747179 -313.824453) (xy 70.770522 -313.778641) (xy 70.800743 -313.737045) (xy 70.837099 -313.700689)
			(xy 70.878695 -313.670468) (xy 70.924507 -313.647125) (xy 70.973406 -313.631237) (xy 71.024188 -313.623194)
			(xy 71.075604 -313.623194) (xy 71.126386 -313.631237) (xy 71.175285 -313.647125) (xy 71.221097 -313.670468)
			(xy 71.262693 -313.700689) (xy 71.299049 -313.737045) (xy 71.32927 -313.778641) (xy 71.352613 -313.824453)
			(xy 71.368501 -313.873352) (xy 71.376544 -313.924134) (xy 71.377048 -313.949842) (xy 71.376544 -313.97555)
			(xy 71.368501 -314.026332) (xy 71.352613 -314.075231) (xy 71.32927 -314.121043) (xy 71.299049 -314.162639)
			(xy 71.262693 -314.198995) (xy 71.221097 -314.229216) (xy 71.175285 -314.252559) (xy 71.126386 -314.268447)
			(xy 71.075604 -314.27649) (xy 71.024188 -314.27649) (xy 70.973406 -314.268447) (xy 70.924507 -314.252559)
			(xy 70.878695 -314.229216) (xy 70.837099 -314.198995) (xy 70.800743 -314.162639) (xy 70.770522 -314.121043)
			(xy 70.747179 -314.075231) (xy 70.731291 -314.026332) (xy 70.723248 -313.97555) (xy 70.40457 -313.97555)
			(xy 70.396854 -314.023026) (xy 70.38127 -314.069707) (xy 70.358399 -314.113284) (xy 70.328834 -314.152628)
			(xy 70.293341 -314.18672) (xy 70.252838 -314.214676) (xy 70.208376 -314.235774) (xy 70.161105 -314.249466)
			(xy 70.11225 -314.255398) (xy 70.063075 -314.253417) (xy 70.014856 -314.243573) (xy 69.96884 -314.226121)
			(xy 69.926219 -314.201514) (xy 69.888098 -314.170389) (xy 69.855463 -314.133552) (xy 69.82916 -314.091956)
			(xy 69.809869 -314.04668) (xy 69.798092 -313.998896) (xy 69.794132 -313.949842) (xy 69.477128 -313.949842)
			(xy 69.476624 -313.97555) (xy 69.468581 -314.026332) (xy 69.452693 -314.075231) (xy 69.42935 -314.121043)
			(xy 69.399129 -314.162639) (xy 69.362773 -314.198995) (xy 69.321177 -314.229216) (xy 69.275365 -314.252559)
			(xy 69.226466 -314.268447) (xy 69.175684 -314.27649) (xy 69.124268 -314.27649) (xy 69.073486 -314.268447)
			(xy 69.024587 -314.252559) (xy 68.978775 -314.229216) (xy 68.937179 -314.198995) (xy 68.900823 -314.162639)
			(xy 68.870602 -314.121043) (xy 68.847259 -314.075231) (xy 68.831371 -314.026332) (xy 68.823328 -313.97555)
			(xy 68.504396 -313.97555) (xy 68.49668 -314.023026) (xy 68.481096 -314.069707) (xy 68.458225 -314.113284)
			(xy 68.42866 -314.152628) (xy 68.393167 -314.18672) (xy 68.352664 -314.214676) (xy 68.308202 -314.235774)
			(xy 68.260931 -314.249466) (xy 68.212076 -314.255398) (xy 68.162901 -314.253417) (xy 68.114682 -314.243573)
			(xy 68.068666 -314.226121) (xy 68.026045 -314.201514) (xy 67.987924 -314.170389) (xy 67.955289 -314.133552)
			(xy 67.928986 -314.091956) (xy 67.909695 -314.04668) (xy 67.897918 -313.998896) (xy 67.893958 -313.949842)
			(xy 67.576954 -313.949842) (xy 67.57645 -313.97555) (xy 67.568407 -314.026332) (xy 67.552519 -314.075231)
			(xy 67.529176 -314.121043) (xy 67.498955 -314.162639) (xy 67.462599 -314.198995) (xy 67.421003 -314.229216)
			(xy 67.375191 -314.252559) (xy 67.326292 -314.268447) (xy 67.27551 -314.27649) (xy 67.224094 -314.27649)
			(xy 67.173312 -314.268447) (xy 67.124413 -314.252559) (xy 67.078601 -314.229216) (xy 67.037005 -314.198995)
			(xy 67.000649 -314.162639) (xy 66.970428 -314.121043) (xy 66.947085 -314.075231) (xy 66.931197 -314.026332)
			(xy 66.923154 -313.97555) (xy 66.604476 -313.97555) (xy 66.59676 -314.023026) (xy 66.581176 -314.069707)
			(xy 66.558305 -314.113284) (xy 66.52874 -314.152628) (xy 66.493247 -314.18672) (xy 66.452744 -314.214676)
			(xy 66.408282 -314.235774) (xy 66.361011 -314.249466) (xy 66.312156 -314.255398) (xy 66.262981 -314.253417)
			(xy 66.214762 -314.243573) (xy 66.168746 -314.226121) (xy 66.126125 -314.201514) (xy 66.088004 -314.170389)
			(xy 66.055369 -314.133552) (xy 66.029066 -314.091956) (xy 66.009775 -314.04668) (xy 65.997998 -313.998896)
			(xy 65.994038 -313.949842) (xy 65.677034 -313.949842) (xy 65.67653 -313.97555) (xy 65.668487 -314.026332)
			(xy 65.652599 -314.075231) (xy 65.629256 -314.121043) (xy 65.599035 -314.162639) (xy 65.562679 -314.198995)
			(xy 65.521083 -314.229216) (xy 65.475271 -314.252559) (xy 65.426372 -314.268447) (xy 65.37559 -314.27649)
			(xy 65.324174 -314.27649) (xy 65.273392 -314.268447) (xy 65.224493 -314.252559) (xy 65.178681 -314.229216)
			(xy 65.137085 -314.198995) (xy 65.100729 -314.162639) (xy 65.070508 -314.121043) (xy 65.047165 -314.075231)
			(xy 65.031277 -314.026332) (xy 65.023234 -313.97555) (xy 64.704556 -313.97555) (xy 64.69684 -314.023026)
			(xy 64.681256 -314.069707) (xy 64.658385 -314.113284) (xy 64.62882 -314.152628) (xy 64.593327 -314.18672)
			(xy 64.552824 -314.214676) (xy 64.508362 -314.235774) (xy 64.461091 -314.249466) (xy 64.412236 -314.255398)
			(xy 64.363061 -314.253417) (xy 64.314842 -314.243573) (xy 64.268826 -314.226121) (xy 64.226205 -314.201514)
			(xy 64.188084 -314.170389) (xy 64.155449 -314.133552) (xy 64.129146 -314.091956) (xy 64.109855 -314.04668)
			(xy 64.098078 -313.998896) (xy 64.094118 -313.949842) (xy 63.777114 -313.949842) (xy 63.77661 -313.97555)
			(xy 63.768567 -314.026332) (xy 63.752679 -314.075231) (xy 63.729336 -314.121043) (xy 63.699115 -314.162639)
			(xy 63.662759 -314.198995) (xy 63.621163 -314.229216) (xy 63.575351 -314.252559) (xy 63.526452 -314.268447)
			(xy 63.47567 -314.27649) (xy 63.424254 -314.27649) (xy 63.373472 -314.268447) (xy 63.324573 -314.252559)
			(xy 63.278761 -314.229216) (xy 63.237165 -314.198995) (xy 63.200809 -314.162639) (xy 63.170588 -314.121043)
			(xy 63.147245 -314.075231) (xy 63.131357 -314.026332) (xy 63.123314 -313.97555) (xy 62.804382 -313.97555)
			(xy 62.796666 -314.023026) (xy 62.781082 -314.069707) (xy 62.758211 -314.113284) (xy 62.728646 -314.152628)
			(xy 62.693153 -314.18672) (xy 62.65265 -314.214676) (xy 62.608188 -314.235774) (xy 62.560917 -314.249466)
			(xy 62.512062 -314.255398) (xy 62.462887 -314.253417) (xy 62.414668 -314.243573) (xy 62.368652 -314.226121)
			(xy 62.326031 -314.201514) (xy 62.28791 -314.170389) (xy 62.255275 -314.133552) (xy 62.228972 -314.091956)
			(xy 62.209681 -314.04668) (xy 62.197904 -313.998896) (xy 62.193944 -313.949842) (xy 61.87694 -313.949842)
			(xy 61.876436 -313.97555) (xy 61.868393 -314.026332) (xy 61.852505 -314.075231) (xy 61.829162 -314.121043)
			(xy 61.798941 -314.162639) (xy 61.762585 -314.198995) (xy 61.720989 -314.229216) (xy 61.675177 -314.252559)
			(xy 61.626278 -314.268447) (xy 61.575496 -314.27649) (xy 61.52408 -314.27649) (xy 61.473298 -314.268447)
			(xy 61.424399 -314.252559) (xy 61.378587 -314.229216) (xy 61.336991 -314.198995) (xy 61.300635 -314.162639)
			(xy 61.270414 -314.121043) (xy 61.247071 -314.075231) (xy 61.231183 -314.026332) (xy 61.22314 -313.97555)
			(xy 60.904462 -313.97555) (xy 60.896746 -314.023026) (xy 60.881162 -314.069707) (xy 60.858291 -314.113284)
			(xy 60.828726 -314.152628) (xy 60.793233 -314.18672) (xy 60.75273 -314.214676) (xy 60.708268 -314.235774)
			(xy 60.660997 -314.249466) (xy 60.612142 -314.255398) (xy 60.562967 -314.253417) (xy 60.514748 -314.243573)
			(xy 60.468732 -314.226121) (xy 60.426111 -314.201514) (xy 60.38799 -314.170389) (xy 60.355355 -314.133552)
			(xy 60.329052 -314.091956) (xy 60.309761 -314.04668) (xy 60.297984 -313.998896) (xy 60.294024 -313.949842)
			(xy 59.97702 -313.949842) (xy 59.976516 -313.97555) (xy 59.968473 -314.026332) (xy 59.952585 -314.075231)
			(xy 59.929242 -314.121043) (xy 59.899021 -314.162639) (xy 59.862665 -314.198995) (xy 59.821069 -314.229216)
			(xy 59.775257 -314.252559) (xy 59.726358 -314.268447) (xy 59.675576 -314.27649) (xy 59.62416 -314.27649)
			(xy 59.573378 -314.268447) (xy 59.524479 -314.252559) (xy 59.478667 -314.229216) (xy 59.437071 -314.198995)
			(xy 59.400715 -314.162639) (xy 59.370494 -314.121043) (xy 59.347151 -314.075231) (xy 59.331263 -314.026332)
			(xy 59.32322 -313.97555) (xy 59.004542 -313.97555) (xy 58.996826 -314.023026) (xy 58.981242 -314.069707)
			(xy 58.958371 -314.113284) (xy 58.928806 -314.152628) (xy 58.893313 -314.18672) (xy 58.85281 -314.214676)
			(xy 58.808348 -314.235774) (xy 58.761077 -314.249466) (xy 58.712222 -314.255398) (xy 58.663047 -314.253417)
			(xy 58.614828 -314.243573) (xy 58.568812 -314.226121) (xy 58.526191 -314.201514) (xy 58.48807 -314.170389)
			(xy 58.455435 -314.133552) (xy 58.429132 -314.091956) (xy 58.409841 -314.04668) (xy 58.398064 -313.998896)
			(xy 58.394104 -313.949842) (xy 58.055256 -313.949842) (xy 58.054761 -313.974449) (xy 58.046866 -314.023026)
			(xy 58.031282 -314.069707) (xy 58.008411 -314.113284) (xy 57.978846 -314.152628) (xy 57.943353 -314.18672)
			(xy 57.90285 -314.214676) (xy 57.858388 -314.235774) (xy 57.811117 -314.249466) (xy 57.762262 -314.255398)
			(xy 57.713087 -314.253417) (xy 57.664868 -314.243573) (xy 57.618852 -314.226121) (xy 57.576231 -314.201514)
			(xy 57.53811 -314.170389) (xy 57.505475 -314.133552) (xy 57.479172 -314.091956) (xy 57.459881 -314.04668)
			(xy 57.448104 -313.998896) (xy 57.444144 -313.949842) (xy 57.105296 -313.949842) (xy 57.104801 -313.974449)
			(xy 57.096906 -314.023026) (xy 57.081322 -314.069707) (xy 57.058451 -314.113284) (xy 57.028886 -314.152628)
			(xy 56.993393 -314.18672) (xy 56.95289 -314.214676) (xy 56.908428 -314.235774) (xy 56.861157 -314.249466)
			(xy 56.812302 -314.255398) (xy 56.763127 -314.253417) (xy 56.714908 -314.243573) (xy 56.668892 -314.226121)
			(xy 56.626271 -314.201514) (xy 56.58815 -314.170389) (xy 56.555515 -314.133552) (xy 56.529212 -314.091956)
			(xy 56.509921 -314.04668) (xy 56.498144 -313.998896) (xy 56.494184 -313.949842) (xy 56.155082 -313.949842)
			(xy 56.154587 -313.974449) (xy 56.146692 -314.023026) (xy 56.131108 -314.069707) (xy 56.108237 -314.113284)
			(xy 56.078672 -314.152628) (xy 56.043179 -314.18672) (xy 56.002676 -314.214676) (xy 55.958214 -314.235774)
			(xy 55.910943 -314.249466) (xy 55.862088 -314.255398) (xy 55.812913 -314.253417) (xy 55.764694 -314.243573)
			(xy 55.718678 -314.226121) (xy 55.676057 -314.201514) (xy 55.637936 -314.170389) (xy 55.605301 -314.133552)
			(xy 55.578998 -314.091956) (xy 55.559707 -314.04668) (xy 55.54793 -313.998896) (xy 55.54397 -313.949842)
			(xy 55.205122 -313.949842) (xy 55.204627 -313.974449) (xy 55.196732 -314.023026) (xy 55.181148 -314.069707)
			(xy 55.158277 -314.113284) (xy 55.128712 -314.152628) (xy 55.093219 -314.18672) (xy 55.052716 -314.214676)
			(xy 55.008254 -314.235774) (xy 54.960983 -314.249466) (xy 54.912128 -314.255398) (xy 54.862953 -314.253417)
			(xy 54.814734 -314.243573) (xy 54.768718 -314.226121) (xy 54.726097 -314.201514) (xy 54.687976 -314.170389)
			(xy 54.655341 -314.133552) (xy 54.629038 -314.091956) (xy 54.609747 -314.04668) (xy 54.59797 -313.998896)
			(xy 54.59401 -313.949842) (xy 54.255162 -313.949842) (xy 54.254667 -313.974449) (xy 54.246772 -314.023026)
			(xy 54.231188 -314.069707) (xy 54.208317 -314.113284) (xy 54.178752 -314.152628) (xy 54.143259 -314.18672)
			(xy 54.102756 -314.214676) (xy 54.058294 -314.235774) (xy 54.011023 -314.249466) (xy 53.962168 -314.255398)
			(xy 53.912993 -314.253417) (xy 53.864774 -314.243573) (xy 53.818758 -314.226121) (xy 53.776137 -314.201514)
			(xy 53.738016 -314.170389) (xy 53.705381 -314.133552) (xy 53.679078 -314.091956) (xy 53.659787 -314.04668)
			(xy 53.64801 -313.998896) (xy 53.64405 -313.949842) (xy 53.305202 -313.949842) (xy 53.304707 -313.974449)
			(xy 53.296812 -314.023026) (xy 53.281228 -314.069707) (xy 53.258357 -314.113284) (xy 53.228792 -314.152628)
			(xy 53.193299 -314.18672) (xy 53.152796 -314.214676) (xy 53.108334 -314.235774) (xy 53.061063 -314.249466)
			(xy 53.012208 -314.255398) (xy 52.963033 -314.253417) (xy 52.914814 -314.243573) (xy 52.868798 -314.226121)
			(xy 52.826177 -314.201514) (xy 52.788056 -314.170389) (xy 52.755421 -314.133552) (xy 52.729118 -314.091956)
			(xy 52.709827 -314.04668) (xy 52.69805 -313.998896) (xy 52.69409 -313.949842) (xy 52.355242 -313.949842)
			(xy 52.354747 -313.974449) (xy 52.346852 -314.023026) (xy 52.331268 -314.069707) (xy 52.308397 -314.113284)
			(xy 52.278832 -314.152628) (xy 52.243339 -314.18672) (xy 52.202836 -314.214676) (xy 52.158374 -314.235774)
			(xy 52.111103 -314.249466) (xy 52.062248 -314.255398) (xy 52.013073 -314.253417) (xy 51.964854 -314.243573)
			(xy 51.918838 -314.226121) (xy 51.876217 -314.201514) (xy 51.838096 -314.170389) (xy 51.805461 -314.133552)
			(xy 51.779158 -314.091956) (xy 51.759867 -314.04668) (xy 51.74809 -313.998896) (xy 51.74413 -313.949842)
			(xy 51.405282 -313.949842) (xy 51.404787 -313.974449) (xy 51.396892 -314.023026) (xy 51.381308 -314.069707)
			(xy 51.358437 -314.113284) (xy 51.328872 -314.152628) (xy 51.293379 -314.18672) (xy 51.252876 -314.214676)
			(xy 51.208414 -314.235774) (xy 51.161143 -314.249466) (xy 51.112288 -314.255398) (xy 51.063113 -314.253417)
			(xy 51.014894 -314.243573) (xy 50.968878 -314.226121) (xy 50.926257 -314.201514) (xy 50.888136 -314.170389)
			(xy 50.855501 -314.133552) (xy 50.829198 -314.091956) (xy 50.809907 -314.04668) (xy 50.79813 -313.998896)
			(xy 50.79417 -313.949842) (xy 50.455068 -313.949842) (xy 50.454573 -313.974449) (xy 50.446678 -314.023026)
			(xy 50.431094 -314.069707) (xy 50.408223 -314.113284) (xy 50.378658 -314.152628) (xy 50.343165 -314.18672)
			(xy 50.302662 -314.214676) (xy 50.2582 -314.235774) (xy 50.210929 -314.249466) (xy 50.162074 -314.255398)
			(xy 50.112899 -314.253417) (xy 50.06468 -314.243573) (xy 50.018664 -314.226121) (xy 49.976043 -314.201514)
			(xy 49.937922 -314.170389) (xy 49.905287 -314.133552) (xy 49.878984 -314.091956) (xy 49.859693 -314.04668)
			(xy 49.847916 -313.998896) (xy 49.843956 -313.949842) (xy 49.505108 -313.949842) (xy 49.504613 -313.974449)
			(xy 49.496718 -314.023026) (xy 49.481134 -314.069707) (xy 49.458263 -314.113284) (xy 49.428698 -314.152628)
			(xy 49.393205 -314.18672) (xy 49.352702 -314.214676) (xy 49.30824 -314.235774) (xy 49.260969 -314.249466)
			(xy 49.212114 -314.255398) (xy 49.162939 -314.253417) (xy 49.11472 -314.243573) (xy 49.068704 -314.226121)
			(xy 49.026083 -314.201514) (xy 48.987962 -314.170389) (xy 48.955327 -314.133552) (xy 48.929024 -314.091956)
			(xy 48.909733 -314.04668) (xy 48.897956 -313.998896) (xy 48.893996 -313.949842) (xy 48.555148 -313.949842)
			(xy 48.554653 -313.974449) (xy 48.546758 -314.023026) (xy 48.531174 -314.069707) (xy 48.508303 -314.113284)
			(xy 48.478738 -314.152628) (xy 48.443245 -314.18672) (xy 48.402742 -314.214676) (xy 48.35828 -314.235774)
			(xy 48.311009 -314.249466) (xy 48.262154 -314.255398) (xy 48.212979 -314.253417) (xy 48.16476 -314.243573)
			(xy 48.118744 -314.226121) (xy 48.076123 -314.201514) (xy 48.038002 -314.170389) (xy 48.005367 -314.133552)
			(xy 47.979064 -314.091956) (xy 47.959773 -314.04668) (xy 47.947996 -313.998896) (xy 47.944036 -313.949842)
			(xy 47.605188 -313.949842) (xy 47.604693 -313.974449) (xy 47.596798 -314.023026) (xy 47.581214 -314.069707)
			(xy 47.558343 -314.113284) (xy 47.528778 -314.152628) (xy 47.493285 -314.18672) (xy 47.452782 -314.214676)
			(xy 47.40832 -314.235774) (xy 47.361049 -314.249466) (xy 47.312194 -314.255398) (xy 47.263019 -314.253417)
			(xy 47.2148 -314.243573) (xy 47.168784 -314.226121) (xy 47.126163 -314.201514) (xy 47.088042 -314.170389)
			(xy 47.055407 -314.133552) (xy 47.029104 -314.091956) (xy 47.009813 -314.04668) (xy 46.998036 -313.998896)
			(xy 46.994076 -313.949842) (xy 46.655228 -313.949842) (xy 46.654733 -313.974449) (xy 46.646838 -314.023026)
			(xy 46.631254 -314.069707) (xy 46.608383 -314.113284) (xy 46.578818 -314.152628) (xy 46.543325 -314.18672)
			(xy 46.502822 -314.214676) (xy 46.45836 -314.235774) (xy 46.411089 -314.249466) (xy 46.362234 -314.255398)
			(xy 46.313059 -314.253417) (xy 46.26484 -314.243573) (xy 46.218824 -314.226121) (xy 46.176203 -314.201514)
			(xy 46.138082 -314.170389) (xy 46.105447 -314.133552) (xy 46.079144 -314.091956) (xy 46.059853 -314.04668)
			(xy 46.048076 -313.998896) (xy 46.044116 -313.949842) (xy 45.705268 -313.949842) (xy 45.704773 -313.974449)
			(xy 45.696878 -314.023026) (xy 45.681294 -314.069707) (xy 45.658423 -314.113284) (xy 45.628858 -314.152628)
			(xy 45.593365 -314.18672) (xy 45.552862 -314.214676) (xy 45.5084 -314.235774) (xy 45.461129 -314.249466)
			(xy 45.412274 -314.255398) (xy 45.363099 -314.253417) (xy 45.31488 -314.243573) (xy 45.268864 -314.226121)
			(xy 45.226243 -314.201514) (xy 45.188122 -314.170389) (xy 45.155487 -314.133552) (xy 45.129184 -314.091956)
			(xy 45.109893 -314.04668) (xy 45.098116 -313.998896) (xy 45.094156 -313.949842) (xy 44.755054 -313.949842)
			(xy 44.754559 -313.974449) (xy 44.746664 -314.023026) (xy 44.73108 -314.069707) (xy 44.708209 -314.113284)
			(xy 44.678644 -314.152628) (xy 44.643151 -314.18672) (xy 44.602648 -314.214676) (xy 44.558186 -314.235774)
			(xy 44.510915 -314.249466) (xy 44.46206 -314.255398) (xy 44.412885 -314.253417) (xy 44.364666 -314.243573)
			(xy 44.31865 -314.226121) (xy 44.276029 -314.201514) (xy 44.237908 -314.170389) (xy 44.205273 -314.133552)
			(xy 44.17897 -314.091956) (xy 44.159679 -314.04668) (xy 44.147902 -313.998896) (xy 44.143942 -313.949842)
			(xy 43.805094 -313.949842) (xy 43.804599 -313.974449) (xy 43.796704 -314.023026) (xy 43.78112 -314.069707)
			(xy 43.758249 -314.113284) (xy 43.728684 -314.152628) (xy 43.693191 -314.18672) (xy 43.652688 -314.214676)
			(xy 43.608226 -314.235774) (xy 43.560955 -314.249466) (xy 43.5121 -314.255398) (xy 43.462925 -314.253417)
			(xy 43.414706 -314.243573) (xy 43.36869 -314.226121) (xy 43.326069 -314.201514) (xy 43.287948 -314.170389)
			(xy 43.255313 -314.133552) (xy 43.22901 -314.091956) (xy 43.209719 -314.04668) (xy 43.197942 -313.998896)
			(xy 43.193982 -313.949842) (xy 42.876978 -313.949842) (xy 42.876474 -313.97555) (xy 42.868431 -314.026332)
			(xy 42.852543 -314.075231) (xy 42.8292 -314.121043) (xy 42.798979 -314.162639) (xy 42.762623 -314.198995)
			(xy 42.721027 -314.229216) (xy 42.675215 -314.252559) (xy 42.626316 -314.268447) (xy 42.575534 -314.27649)
			(xy 42.524118 -314.27649) (xy 42.473336 -314.268447) (xy 42.424437 -314.252559) (xy 42.378625 -314.229216)
			(xy 42.337029 -314.198995) (xy 42.300673 -314.162639) (xy 42.270452 -314.121043) (xy 42.247109 -314.075231)
			(xy 42.231221 -314.026332) (xy 42.223178 -313.97555) (xy 41.9045 -313.97555) (xy 41.896784 -314.023026)
			(xy 41.8812 -314.069707) (xy 41.858329 -314.113284) (xy 41.828764 -314.152628) (xy 41.793271 -314.18672)
			(xy 41.752768 -314.214676) (xy 41.708306 -314.235774) (xy 41.661035 -314.249466) (xy 41.61218 -314.255398)
			(xy 41.563005 -314.253417) (xy 41.514786 -314.243573) (xy 41.46877 -314.226121) (xy 41.426149 -314.201514)
			(xy 41.388028 -314.170389) (xy 41.355393 -314.133552) (xy 41.32909 -314.091956) (xy 41.309799 -314.04668)
			(xy 41.298022 -313.998896) (xy 41.294062 -313.949842) (xy 40.977058 -313.949842) (xy 40.976554 -313.97555)
			(xy 40.968511 -314.026332) (xy 40.952623 -314.075231) (xy 40.92928 -314.121043) (xy 40.899059 -314.162639)
			(xy 40.862703 -314.198995) (xy 40.821107 -314.229216) (xy 40.775295 -314.252559) (xy 40.726396 -314.268447)
			(xy 40.675614 -314.27649) (xy 40.624198 -314.27649) (xy 40.573416 -314.268447) (xy 40.524517 -314.252559)
			(xy 40.478705 -314.229216) (xy 40.437109 -314.198995) (xy 40.400753 -314.162639) (xy 40.370532 -314.121043)
			(xy 40.347189 -314.075231) (xy 40.331301 -314.026332) (xy 40.323258 -313.97555) (xy 40.00458 -313.97555)
			(xy 39.996864 -314.023026) (xy 39.98128 -314.069707) (xy 39.958409 -314.113284) (xy 39.928844 -314.152628)
			(xy 39.893351 -314.18672) (xy 39.852848 -314.214676) (xy 39.808386 -314.235774) (xy 39.761115 -314.249466)
			(xy 39.71226 -314.255398) (xy 39.663085 -314.253417) (xy 39.614866 -314.243573) (xy 39.56885 -314.226121)
			(xy 39.526229 -314.201514) (xy 39.488108 -314.170389) (xy 39.455473 -314.133552) (xy 39.42917 -314.091956)
			(xy 39.409879 -314.04668) (xy 39.398102 -313.998896) (xy 39.394142 -313.949842) (xy 39.077138 -313.949842)
			(xy 39.076634 -313.97555) (xy 39.068591 -314.026332) (xy 39.052703 -314.075231) (xy 39.02936 -314.121043)
			(xy 38.999139 -314.162639) (xy 38.962783 -314.198995) (xy 38.921187 -314.229216) (xy 38.875375 -314.252559)
			(xy 38.826476 -314.268447) (xy 38.775694 -314.27649) (xy 38.724278 -314.27649) (xy 38.673496 -314.268447)
			(xy 38.624597 -314.252559) (xy 38.578785 -314.229216) (xy 38.537189 -314.198995) (xy 38.500833 -314.162639)
			(xy 38.470612 -314.121043) (xy 38.447269 -314.075231) (xy 38.431381 -314.026332) (xy 38.423338 -313.97555)
			(xy 38.104406 -313.97555) (xy 38.09669 -314.023026) (xy 38.081106 -314.069707) (xy 38.058235 -314.113284)
			(xy 38.02867 -314.152628) (xy 37.993177 -314.18672) (xy 37.952674 -314.214676) (xy 37.908212 -314.235774)
			(xy 37.860941 -314.249466) (xy 37.812086 -314.255398) (xy 37.762911 -314.253417) (xy 37.714692 -314.243573)
			(xy 37.668676 -314.226121) (xy 37.626055 -314.201514) (xy 37.587934 -314.170389) (xy 37.555299 -314.133552)
			(xy 37.528996 -314.091956) (xy 37.509705 -314.04668) (xy 37.497928 -313.998896) (xy 37.493968 -313.949842)
			(xy 37.15512 -313.949842) (xy 37.154625 -313.974449) (xy 37.14673 -314.023026) (xy 37.131146 -314.069707)
			(xy 37.108275 -314.113284) (xy 37.07871 -314.152628) (xy 37.043217 -314.18672) (xy 37.002714 -314.214676)
			(xy 36.958252 -314.235774) (xy 36.910981 -314.249466) (xy 36.862126 -314.255398) (xy 36.812951 -314.253417)
			(xy 36.764732 -314.243573) (xy 36.718716 -314.226121) (xy 36.676095 -314.201514) (xy 36.637974 -314.170389)
			(xy 36.605339 -314.133552) (xy 36.579036 -314.091956) (xy 36.559745 -314.04668) (xy 36.547968 -313.998896)
			(xy 36.544008 -313.949842) (xy 34.663063 -313.949842) (xy 34.626073 -313.980625) (xy 34.578467 -314.009679)
			(xy 34.527138 -314.031491) (xy 34.473181 -314.045597) (xy 34.417744 -314.051697) (xy 34.36201 -314.04966)
			(xy 34.307167 -314.03953) (xy 34.254383 -314.021523) (xy 34.204783 -313.996022) (xy 34.159425 -313.963571)
			(xy 34.119276 -313.924862) (xy 34.08519 -313.880719) (xy 34.057894 -313.832084) (xy 34.037971 -313.779993)
			(xy 34.025845 -313.725556) (xy 34.021774 -313.669934) (xy 17.635982 -313.669934) (xy 17.635982 -314.899548)
			(xy 35.59354 -314.899548) (xy 35.5975 -314.850494) (xy 35.609277 -314.80271) (xy 35.628568 -314.757434)
			(xy 35.654871 -314.715838) (xy 35.687506 -314.679001) (xy 35.725627 -314.647876) (xy 35.768248 -314.623269)
			(xy 35.814264 -314.605817) (xy 35.862483 -314.595973) (xy 35.911658 -314.593992) (xy 35.960513 -314.599924)
			(xy 36.007784 -314.613616) (xy 36.052246 -314.634714) (xy 36.092749 -314.66267) (xy 36.128242 -314.696762)
			(xy 36.157807 -314.736106) (xy 36.180678 -314.779683) (xy 36.196262 -314.826364) (xy 36.204157 -314.874941)
			(xy 36.204652 -314.899548) (xy 36.204157 -314.924155) (xy 36.203937 -314.92551) (xy 36.523164 -314.92551)
			(xy 36.523164 -314.874094) (xy 36.531207 -314.823312) (xy 36.547095 -314.774413) (xy 36.570438 -314.728601)
			(xy 36.600659 -314.687005) (xy 36.637015 -314.650649) (xy 36.678611 -314.620428) (xy 36.724423 -314.597085)
			(xy 36.773322 -314.581197) (xy 36.824104 -314.573154) (xy 36.87552 -314.573154) (xy 36.926302 -314.581197)
			(xy 36.975201 -314.597085) (xy 37.021013 -314.620428) (xy 37.062609 -314.650649) (xy 37.098965 -314.687005)
			(xy 37.129186 -314.728601) (xy 37.152529 -314.774413) (xy 37.168417 -314.823312) (xy 37.17646 -314.874094)
			(xy 37.176964 -314.899802) (xy 37.17646 -314.92551) (xy 37.473124 -314.92551) (xy 37.473124 -314.874094)
			(xy 37.481167 -314.823312) (xy 37.497055 -314.774413) (xy 37.520398 -314.728601) (xy 37.550619 -314.687005)
			(xy 37.586975 -314.650649) (xy 37.628571 -314.620428) (xy 37.674383 -314.597085) (xy 37.723282 -314.581197)
			(xy 37.774064 -314.573154) (xy 37.82548 -314.573154) (xy 37.876262 -314.581197) (xy 37.925161 -314.597085)
			(xy 37.970973 -314.620428) (xy 38.012569 -314.650649) (xy 38.048925 -314.687005) (xy 38.079146 -314.728601)
			(xy 38.102489 -314.774413) (xy 38.118377 -314.823312) (xy 38.12642 -314.874094) (xy 38.126924 -314.899802)
			(xy 38.444182 -314.899802) (xy 38.448142 -314.850748) (xy 38.459919 -314.802964) (xy 38.47921 -314.757688)
			(xy 38.505513 -314.716092) (xy 38.538148 -314.679255) (xy 38.576269 -314.64813) (xy 38.61889 -314.623523)
			(xy 38.664906 -314.606071) (xy 38.713125 -314.596227) (xy 38.7623 -314.594246) (xy 38.811155 -314.600178)
			(xy 38.858426 -314.61387) (xy 38.902888 -314.634968) (xy 38.943391 -314.662924) (xy 38.978884 -314.697016)
			(xy 39.008449 -314.73636) (xy 39.03132 -314.779937) (xy 39.046904 -314.826618) (xy 39.054799 -314.875195)
			(xy 39.055294 -314.899802) (xy 39.394142 -314.899802) (xy 39.398102 -314.850748) (xy 39.409879 -314.802964)
			(xy 39.42917 -314.757688) (xy 39.455473 -314.716092) (xy 39.488108 -314.679255) (xy 39.526229 -314.64813)
			(xy 39.56885 -314.623523) (xy 39.614866 -314.606071) (xy 39.663085 -314.596227) (xy 39.71226 -314.594246)
			(xy 39.761115 -314.600178) (xy 39.808386 -314.61387) (xy 39.852848 -314.634968) (xy 39.893351 -314.662924)
			(xy 39.928844 -314.697016) (xy 39.958409 -314.73636) (xy 39.98128 -314.779937) (xy 39.996864 -314.826618)
			(xy 40.004759 -314.875195) (xy 40.005254 -314.899802) (xy 40.344102 -314.899802) (xy 40.348062 -314.850748)
			(xy 40.359839 -314.802964) (xy 40.37913 -314.757688) (xy 40.405433 -314.716092) (xy 40.438068 -314.679255)
			(xy 40.476189 -314.64813) (xy 40.51881 -314.623523) (xy 40.564826 -314.606071) (xy 40.613045 -314.596227)
			(xy 40.66222 -314.594246) (xy 40.711075 -314.600178) (xy 40.758346 -314.61387) (xy 40.802808 -314.634968)
			(xy 40.843311 -314.662924) (xy 40.878804 -314.697016) (xy 40.908369 -314.73636) (xy 40.93124 -314.779937)
			(xy 40.946824 -314.826618) (xy 40.954719 -314.875195) (xy 40.955214 -314.899802) (xy 41.294062 -314.899802)
			(xy 41.298022 -314.850748) (xy 41.309799 -314.802964) (xy 41.32909 -314.757688) (xy 41.355393 -314.716092)
			(xy 41.388028 -314.679255) (xy 41.426149 -314.64813) (xy 41.46877 -314.623523) (xy 41.514786 -314.606071)
			(xy 41.563005 -314.596227) (xy 41.61218 -314.594246) (xy 41.661035 -314.600178) (xy 41.708306 -314.61387)
			(xy 41.752768 -314.634968) (xy 41.793271 -314.662924) (xy 41.828764 -314.697016) (xy 41.858329 -314.73636)
			(xy 41.8812 -314.779937) (xy 41.896784 -314.826618) (xy 41.904679 -314.875195) (xy 41.905174 -314.899802)
			(xy 42.244022 -314.899802) (xy 42.247982 -314.850748) (xy 42.259759 -314.802964) (xy 42.27905 -314.757688)
			(xy 42.305353 -314.716092) (xy 42.337988 -314.679255) (xy 42.376109 -314.64813) (xy 42.41873 -314.623523)
			(xy 42.464746 -314.606071) (xy 42.512965 -314.596227) (xy 42.56214 -314.594246) (xy 42.610995 -314.600178)
			(xy 42.658266 -314.61387) (xy 42.702728 -314.634968) (xy 42.743231 -314.662924) (xy 42.778724 -314.697016)
			(xy 42.808289 -314.73636) (xy 42.83116 -314.779937) (xy 42.846744 -314.826618) (xy 42.854639 -314.875195)
			(xy 42.855134 -314.899802) (xy 43.193982 -314.899802) (xy 43.197942 -314.850748) (xy 43.209719 -314.802964)
			(xy 43.22901 -314.757688) (xy 43.255313 -314.716092) (xy 43.287948 -314.679255) (xy 43.326069 -314.64813)
			(xy 43.36869 -314.623523) (xy 43.414706 -314.606071) (xy 43.462925 -314.596227) (xy 43.5121 -314.594246)
			(xy 43.560955 -314.600178) (xy 43.608226 -314.61387) (xy 43.652688 -314.634968) (xy 43.693191 -314.662924)
			(xy 43.728684 -314.697016) (xy 43.758249 -314.73636) (xy 43.78112 -314.779937) (xy 43.796704 -314.826618)
			(xy 43.804599 -314.875195) (xy 43.805094 -314.899802) (xy 44.143942 -314.899802) (xy 44.147902 -314.850748)
			(xy 44.159679 -314.802964) (xy 44.17897 -314.757688) (xy 44.205273 -314.716092) (xy 44.237908 -314.679255)
			(xy 44.276029 -314.64813) (xy 44.31865 -314.623523) (xy 44.364666 -314.606071) (xy 44.412885 -314.596227)
			(xy 44.46206 -314.594246) (xy 44.510915 -314.600178) (xy 44.558186 -314.61387) (xy 44.602648 -314.634968)
			(xy 44.643151 -314.662924) (xy 44.678644 -314.697016) (xy 44.708209 -314.73636) (xy 44.73108 -314.779937)
			(xy 44.746664 -314.826618) (xy 44.754559 -314.875195) (xy 44.755054 -314.899802) (xy 45.094156 -314.899802)
			(xy 45.098116 -314.850748) (xy 45.109893 -314.802964) (xy 45.129184 -314.757688) (xy 45.155487 -314.716092)
			(xy 45.188122 -314.679255) (xy 45.226243 -314.64813) (xy 45.268864 -314.623523) (xy 45.31488 -314.606071)
			(xy 45.363099 -314.596227) (xy 45.412274 -314.594246) (xy 45.461129 -314.600178) (xy 45.5084 -314.61387)
			(xy 45.552862 -314.634968) (xy 45.593365 -314.662924) (xy 45.628858 -314.697016) (xy 45.658423 -314.73636)
			(xy 45.681294 -314.779937) (xy 45.696878 -314.826618) (xy 45.704773 -314.875195) (xy 45.705268 -314.899802)
			(xy 46.044116 -314.899802) (xy 46.048076 -314.850748) (xy 46.059853 -314.802964) (xy 46.079144 -314.757688)
			(xy 46.105447 -314.716092) (xy 46.138082 -314.679255) (xy 46.176203 -314.64813) (xy 46.218824 -314.623523)
			(xy 46.26484 -314.606071) (xy 46.313059 -314.596227) (xy 46.362234 -314.594246) (xy 46.411089 -314.600178)
			(xy 46.45836 -314.61387) (xy 46.502822 -314.634968) (xy 46.543325 -314.662924) (xy 46.578818 -314.697016)
			(xy 46.608383 -314.73636) (xy 46.631254 -314.779937) (xy 46.646838 -314.826618) (xy 46.654733 -314.875195)
			(xy 46.655228 -314.899802) (xy 46.994076 -314.899802) (xy 46.998036 -314.850748) (xy 47.009813 -314.802964)
			(xy 47.029104 -314.757688) (xy 47.055407 -314.716092) (xy 47.088042 -314.679255) (xy 47.126163 -314.64813)
			(xy 47.168784 -314.623523) (xy 47.2148 -314.606071) (xy 47.263019 -314.596227) (xy 47.312194 -314.594246)
			(xy 47.361049 -314.600178) (xy 47.40832 -314.61387) (xy 47.452782 -314.634968) (xy 47.493285 -314.662924)
			(xy 47.528778 -314.697016) (xy 47.558343 -314.73636) (xy 47.581214 -314.779937) (xy 47.596798 -314.826618)
			(xy 47.604693 -314.875195) (xy 47.605188 -314.899802) (xy 47.944036 -314.899802) (xy 47.947996 -314.850748)
			(xy 47.959773 -314.802964) (xy 47.979064 -314.757688) (xy 48.005367 -314.716092) (xy 48.038002 -314.679255)
			(xy 48.076123 -314.64813) (xy 48.118744 -314.623523) (xy 48.16476 -314.606071) (xy 48.212979 -314.596227)
			(xy 48.262154 -314.594246) (xy 48.311009 -314.600178) (xy 48.35828 -314.61387) (xy 48.402742 -314.634968)
			(xy 48.443245 -314.662924) (xy 48.478738 -314.697016) (xy 48.508303 -314.73636) (xy 48.531174 -314.779937)
			(xy 48.546758 -314.826618) (xy 48.554653 -314.875195) (xy 48.555148 -314.899802) (xy 48.893996 -314.899802)
			(xy 48.897956 -314.850748) (xy 48.909733 -314.802964) (xy 48.929024 -314.757688) (xy 48.955327 -314.716092)
			(xy 48.987962 -314.679255) (xy 49.026083 -314.64813) (xy 49.068704 -314.623523) (xy 49.11472 -314.606071)
			(xy 49.162939 -314.596227) (xy 49.212114 -314.594246) (xy 49.260969 -314.600178) (xy 49.30824 -314.61387)
			(xy 49.352702 -314.634968) (xy 49.393205 -314.662924) (xy 49.428698 -314.697016) (xy 49.458263 -314.73636)
			(xy 49.481134 -314.779937) (xy 49.496718 -314.826618) (xy 49.504613 -314.875195) (xy 49.505108 -314.899802)
			(xy 49.843956 -314.899802) (xy 49.847916 -314.850748) (xy 49.859693 -314.802964) (xy 49.878984 -314.757688)
			(xy 49.905287 -314.716092) (xy 49.937922 -314.679255) (xy 49.976043 -314.64813) (xy 50.018664 -314.623523)
			(xy 50.06468 -314.606071) (xy 50.112899 -314.596227) (xy 50.162074 -314.594246) (xy 50.210929 -314.600178)
			(xy 50.2582 -314.61387) (xy 50.302662 -314.634968) (xy 50.343165 -314.662924) (xy 50.378658 -314.697016)
			(xy 50.408223 -314.73636) (xy 50.431094 -314.779937) (xy 50.446678 -314.826618) (xy 50.454573 -314.875195)
			(xy 50.455068 -314.899802) (xy 50.79417 -314.899802) (xy 50.79813 -314.850748) (xy 50.809907 -314.802964)
			(xy 50.829198 -314.757688) (xy 50.855501 -314.716092) (xy 50.888136 -314.679255) (xy 50.926257 -314.64813)
			(xy 50.968878 -314.623523) (xy 51.014894 -314.606071) (xy 51.063113 -314.596227) (xy 51.112288 -314.594246)
			(xy 51.161143 -314.600178) (xy 51.208414 -314.61387) (xy 51.252876 -314.634968) (xy 51.293379 -314.662924)
			(xy 51.328872 -314.697016) (xy 51.358437 -314.73636) (xy 51.381308 -314.779937) (xy 51.396892 -314.826618)
			(xy 51.404787 -314.875195) (xy 51.405282 -314.899802) (xy 51.74413 -314.899802) (xy 51.74809 -314.850748)
			(xy 51.759867 -314.802964) (xy 51.779158 -314.757688) (xy 51.805461 -314.716092) (xy 51.838096 -314.679255)
			(xy 51.876217 -314.64813) (xy 51.918838 -314.623523) (xy 51.964854 -314.606071) (xy 52.013073 -314.596227)
			(xy 52.062248 -314.594246) (xy 52.111103 -314.600178) (xy 52.158374 -314.61387) (xy 52.202836 -314.634968)
			(xy 52.243339 -314.662924) (xy 52.278832 -314.697016) (xy 52.308397 -314.73636) (xy 52.331268 -314.779937)
			(xy 52.346852 -314.826618) (xy 52.354747 -314.875195) (xy 52.355242 -314.899802) (xy 52.69409 -314.899802)
			(xy 52.69805 -314.850748) (xy 52.709827 -314.802964) (xy 52.729118 -314.757688) (xy 52.755421 -314.716092)
			(xy 52.788056 -314.679255) (xy 52.826177 -314.64813) (xy 52.868798 -314.623523) (xy 52.914814 -314.606071)
			(xy 52.963033 -314.596227) (xy 53.012208 -314.594246) (xy 53.061063 -314.600178) (xy 53.108334 -314.61387)
			(xy 53.152796 -314.634968) (xy 53.193299 -314.662924) (xy 53.228792 -314.697016) (xy 53.258357 -314.73636)
			(xy 53.281228 -314.779937) (xy 53.296812 -314.826618) (xy 53.304707 -314.875195) (xy 53.305202 -314.899802)
			(xy 53.64405 -314.899802) (xy 53.64801 -314.850748) (xy 53.659787 -314.802964) (xy 53.679078 -314.757688)
			(xy 53.705381 -314.716092) (xy 53.738016 -314.679255) (xy 53.776137 -314.64813) (xy 53.818758 -314.623523)
			(xy 53.864774 -314.606071) (xy 53.912993 -314.596227) (xy 53.962168 -314.594246) (xy 54.011023 -314.600178)
			(xy 54.058294 -314.61387) (xy 54.102756 -314.634968) (xy 54.143259 -314.662924) (xy 54.178752 -314.697016)
			(xy 54.208317 -314.73636) (xy 54.231188 -314.779937) (xy 54.246772 -314.826618) (xy 54.254667 -314.875195)
			(xy 54.255162 -314.899802) (xy 54.59401 -314.899802) (xy 54.59797 -314.850748) (xy 54.609747 -314.802964)
			(xy 54.629038 -314.757688) (xy 54.655341 -314.716092) (xy 54.687976 -314.679255) (xy 54.726097 -314.64813)
			(xy 54.768718 -314.623523) (xy 54.814734 -314.606071) (xy 54.862953 -314.596227) (xy 54.912128 -314.594246)
			(xy 54.960983 -314.600178) (xy 55.008254 -314.61387) (xy 55.052716 -314.634968) (xy 55.093219 -314.662924)
			(xy 55.128712 -314.697016) (xy 55.158277 -314.73636) (xy 55.181148 -314.779937) (xy 55.196732 -314.826618)
			(xy 55.204627 -314.875195) (xy 55.205122 -314.899802) (xy 55.54397 -314.899802) (xy 55.54793 -314.850748)
			(xy 55.559707 -314.802964) (xy 55.578998 -314.757688) (xy 55.605301 -314.716092) (xy 55.637936 -314.679255)
			(xy 55.676057 -314.64813) (xy 55.718678 -314.623523) (xy 55.764694 -314.606071) (xy 55.812913 -314.596227)
			(xy 55.862088 -314.594246) (xy 55.910943 -314.600178) (xy 55.958214 -314.61387) (xy 56.002676 -314.634968)
			(xy 56.043179 -314.662924) (xy 56.078672 -314.697016) (xy 56.108237 -314.73636) (xy 56.131108 -314.779937)
			(xy 56.146692 -314.826618) (xy 56.154587 -314.875195) (xy 56.155082 -314.899802) (xy 56.494184 -314.899802)
			(xy 56.498144 -314.850748) (xy 56.509921 -314.802964) (xy 56.529212 -314.757688) (xy 56.555515 -314.716092)
			(xy 56.58815 -314.679255) (xy 56.626271 -314.64813) (xy 56.668892 -314.623523) (xy 56.714908 -314.606071)
			(xy 56.763127 -314.596227) (xy 56.812302 -314.594246) (xy 56.861157 -314.600178) (xy 56.908428 -314.61387)
			(xy 56.95289 -314.634968) (xy 56.993393 -314.662924) (xy 57.028886 -314.697016) (xy 57.058451 -314.73636)
			(xy 57.081322 -314.779937) (xy 57.096906 -314.826618) (xy 57.104801 -314.875195) (xy 57.105296 -314.899802)
			(xy 57.444144 -314.899802) (xy 57.448104 -314.850748) (xy 57.459881 -314.802964) (xy 57.479172 -314.757688)
			(xy 57.505475 -314.716092) (xy 57.53811 -314.679255) (xy 57.576231 -314.64813) (xy 57.618852 -314.623523)
			(xy 57.664868 -314.606071) (xy 57.713087 -314.596227) (xy 57.762262 -314.594246) (xy 57.811117 -314.600178)
			(xy 57.858388 -314.61387) (xy 57.90285 -314.634968) (xy 57.943353 -314.662924) (xy 57.978846 -314.697016)
			(xy 58.008411 -314.73636) (xy 58.031282 -314.779937) (xy 58.046866 -314.826618) (xy 58.054761 -314.875195)
			(xy 58.055256 -314.899802) (xy 58.394104 -314.899802) (xy 58.398064 -314.850748) (xy 58.409841 -314.802964)
			(xy 58.429132 -314.757688) (xy 58.455435 -314.716092) (xy 58.48807 -314.679255) (xy 58.526191 -314.64813)
			(xy 58.568812 -314.623523) (xy 58.614828 -314.606071) (xy 58.663047 -314.596227) (xy 58.712222 -314.594246)
			(xy 58.761077 -314.600178) (xy 58.808348 -314.61387) (xy 58.85281 -314.634968) (xy 58.893313 -314.662924)
			(xy 58.928806 -314.697016) (xy 58.958371 -314.73636) (xy 58.981242 -314.779937) (xy 58.996826 -314.826618)
			(xy 59.004721 -314.875195) (xy 59.005216 -314.899802) (xy 59.344064 -314.899802) (xy 59.348024 -314.850748)
			(xy 59.359801 -314.802964) (xy 59.379092 -314.757688) (xy 59.405395 -314.716092) (xy 59.43803 -314.679255)
			(xy 59.476151 -314.64813) (xy 59.518772 -314.623523) (xy 59.564788 -314.606071) (xy 59.613007 -314.596227)
			(xy 59.662182 -314.594246) (xy 59.711037 -314.600178) (xy 59.758308 -314.61387) (xy 59.80277 -314.634968)
			(xy 59.843273 -314.662924) (xy 59.878766 -314.697016) (xy 59.908331 -314.73636) (xy 59.931202 -314.779937)
			(xy 59.946786 -314.826618) (xy 59.954681 -314.875195) (xy 59.955176 -314.899802) (xy 60.294024 -314.899802)
			(xy 60.297984 -314.850748) (xy 60.309761 -314.802964) (xy 60.329052 -314.757688) (xy 60.355355 -314.716092)
			(xy 60.38799 -314.679255) (xy 60.426111 -314.64813) (xy 60.468732 -314.623523) (xy 60.514748 -314.606071)
			(xy 60.562967 -314.596227) (xy 60.612142 -314.594246) (xy 60.660997 -314.600178) (xy 60.708268 -314.61387)
			(xy 60.75273 -314.634968) (xy 60.793233 -314.662924) (xy 60.828726 -314.697016) (xy 60.858291 -314.73636)
			(xy 60.881162 -314.779937) (xy 60.896746 -314.826618) (xy 60.904641 -314.875195) (xy 60.905136 -314.899802)
			(xy 61.243984 -314.899802) (xy 61.247944 -314.850748) (xy 61.259721 -314.802964) (xy 61.279012 -314.757688)
			(xy 61.305315 -314.716092) (xy 61.33795 -314.679255) (xy 61.376071 -314.64813) (xy 61.418692 -314.623523)
			(xy 61.464708 -314.606071) (xy 61.512927 -314.596227) (xy 61.562102 -314.594246) (xy 61.610957 -314.600178)
			(xy 61.658228 -314.61387) (xy 61.70269 -314.634968) (xy 61.743193 -314.662924) (xy 61.778686 -314.697016)
			(xy 61.808251 -314.73636) (xy 61.831122 -314.779937) (xy 61.846706 -314.826618) (xy 61.854601 -314.875195)
			(xy 61.855096 -314.899802) (xy 62.193944 -314.899802) (xy 62.197904 -314.850748) (xy 62.209681 -314.802964)
			(xy 62.228972 -314.757688) (xy 62.255275 -314.716092) (xy 62.28791 -314.679255) (xy 62.326031 -314.64813)
			(xy 62.368652 -314.623523) (xy 62.414668 -314.606071) (xy 62.462887 -314.596227) (xy 62.512062 -314.594246)
			(xy 62.560917 -314.600178) (xy 62.608188 -314.61387) (xy 62.65265 -314.634968) (xy 62.693153 -314.662924)
			(xy 62.728646 -314.697016) (xy 62.758211 -314.73636) (xy 62.781082 -314.779937) (xy 62.796666 -314.826618)
			(xy 62.804561 -314.875195) (xy 62.805056 -314.899802) (xy 63.144158 -314.899802) (xy 63.148118 -314.850748)
			(xy 63.159895 -314.802964) (xy 63.179186 -314.757688) (xy 63.205489 -314.716092) (xy 63.238124 -314.679255)
			(xy 63.276245 -314.64813) (xy 63.318866 -314.623523) (xy 63.364882 -314.606071) (xy 63.413101 -314.596227)
			(xy 63.462276 -314.594246) (xy 63.511131 -314.600178) (xy 63.558402 -314.61387) (xy 63.602864 -314.634968)
			(xy 63.643367 -314.662924) (xy 63.67886 -314.697016) (xy 63.708425 -314.73636) (xy 63.731296 -314.779937)
			(xy 63.74688 -314.826618) (xy 63.754775 -314.875195) (xy 63.75527 -314.899802) (xy 64.094118 -314.899802)
			(xy 64.098078 -314.850748) (xy 64.109855 -314.802964) (xy 64.129146 -314.757688) (xy 64.155449 -314.716092)
			(xy 64.188084 -314.679255) (xy 64.226205 -314.64813) (xy 64.268826 -314.623523) (xy 64.314842 -314.606071)
			(xy 64.363061 -314.596227) (xy 64.412236 -314.594246) (xy 64.461091 -314.600178) (xy 64.508362 -314.61387)
			(xy 64.552824 -314.634968) (xy 64.593327 -314.662924) (xy 64.62882 -314.697016) (xy 64.658385 -314.73636)
			(xy 64.681256 -314.779937) (xy 64.69684 -314.826618) (xy 64.704735 -314.875195) (xy 64.70523 -314.899802)
			(xy 65.044078 -314.899802) (xy 65.048038 -314.850748) (xy 65.059815 -314.802964) (xy 65.079106 -314.757688)
			(xy 65.105409 -314.716092) (xy 65.138044 -314.679255) (xy 65.176165 -314.64813) (xy 65.218786 -314.623523)
			(xy 65.264802 -314.606071) (xy 65.313021 -314.596227) (xy 65.362196 -314.594246) (xy 65.411051 -314.600178)
			(xy 65.458322 -314.61387) (xy 65.502784 -314.634968) (xy 65.543287 -314.662924) (xy 65.57878 -314.697016)
			(xy 65.608345 -314.73636) (xy 65.631216 -314.779937) (xy 65.6468 -314.826618) (xy 65.654695 -314.875195)
			(xy 65.65519 -314.899802) (xy 65.994038 -314.899802) (xy 65.997998 -314.850748) (xy 66.009775 -314.802964)
			(xy 66.029066 -314.757688) (xy 66.055369 -314.716092) (xy 66.088004 -314.679255) (xy 66.126125 -314.64813)
			(xy 66.168746 -314.623523) (xy 66.214762 -314.606071) (xy 66.262981 -314.596227) (xy 66.312156 -314.594246)
			(xy 66.361011 -314.600178) (xy 66.408282 -314.61387) (xy 66.452744 -314.634968) (xy 66.493247 -314.662924)
			(xy 66.52874 -314.697016) (xy 66.558305 -314.73636) (xy 66.581176 -314.779937) (xy 66.59676 -314.826618)
			(xy 66.604655 -314.875195) (xy 66.60515 -314.899802) (xy 66.943998 -314.899802) (xy 66.947958 -314.850748)
			(xy 66.959735 -314.802964) (xy 66.979026 -314.757688) (xy 67.005329 -314.716092) (xy 67.037964 -314.679255)
			(xy 67.076085 -314.64813) (xy 67.118706 -314.623523) (xy 67.164722 -314.606071) (xy 67.212941 -314.596227)
			(xy 67.262116 -314.594246) (xy 67.310971 -314.600178) (xy 67.358242 -314.61387) (xy 67.402704 -314.634968)
			(xy 67.443207 -314.662924) (xy 67.4787 -314.697016) (xy 67.508265 -314.73636) (xy 67.531136 -314.779937)
			(xy 67.54672 -314.826618) (xy 67.554615 -314.875195) (xy 67.55511 -314.899802) (xy 67.893958 -314.899802)
			(xy 67.897918 -314.850748) (xy 67.909695 -314.802964) (xy 67.928986 -314.757688) (xy 67.955289 -314.716092)
			(xy 67.987924 -314.679255) (xy 68.026045 -314.64813) (xy 68.068666 -314.623523) (xy 68.114682 -314.606071)
			(xy 68.162901 -314.596227) (xy 68.212076 -314.594246) (xy 68.260931 -314.600178) (xy 68.308202 -314.61387)
			(xy 68.352664 -314.634968) (xy 68.393167 -314.662924) (xy 68.42866 -314.697016) (xy 68.458225 -314.73636)
			(xy 68.481096 -314.779937) (xy 68.49668 -314.826618) (xy 68.504575 -314.875195) (xy 68.50507 -314.899802)
			(xy 68.844172 -314.899802) (xy 68.848132 -314.850748) (xy 68.859909 -314.802964) (xy 68.8792 -314.757688)
			(xy 68.905503 -314.716092) (xy 68.938138 -314.679255) (xy 68.976259 -314.64813) (xy 69.01888 -314.623523)
			(xy 69.064896 -314.606071) (xy 69.113115 -314.596227) (xy 69.16229 -314.594246) (xy 69.211145 -314.600178)
			(xy 69.258416 -314.61387) (xy 69.302878 -314.634968) (xy 69.343381 -314.662924) (xy 69.378874 -314.697016)
			(xy 69.408439 -314.73636) (xy 69.43131 -314.779937) (xy 69.446894 -314.826618) (xy 69.454789 -314.875195)
			(xy 69.455284 -314.899802) (xy 69.794132 -314.899802) (xy 69.798092 -314.850748) (xy 69.809869 -314.802964)
			(xy 69.82916 -314.757688) (xy 69.855463 -314.716092) (xy 69.888098 -314.679255) (xy 69.926219 -314.64813)
			(xy 69.96884 -314.623523) (xy 70.014856 -314.606071) (xy 70.063075 -314.596227) (xy 70.11225 -314.594246)
			(xy 70.161105 -314.600178) (xy 70.208376 -314.61387) (xy 70.252838 -314.634968) (xy 70.293341 -314.662924)
			(xy 70.328834 -314.697016) (xy 70.358399 -314.73636) (xy 70.38127 -314.779937) (xy 70.396854 -314.826618)
			(xy 70.404749 -314.875195) (xy 70.405244 -314.899802) (xy 70.744092 -314.899802) (xy 70.748052 -314.850748)
			(xy 70.759829 -314.802964) (xy 70.77912 -314.757688) (xy 70.805423 -314.716092) (xy 70.838058 -314.679255)
			(xy 70.876179 -314.64813) (xy 70.9188 -314.623523) (xy 70.964816 -314.606071) (xy 71.013035 -314.596227)
			(xy 71.06221 -314.594246) (xy 71.111065 -314.600178) (xy 71.158336 -314.61387) (xy 71.202798 -314.634968)
			(xy 71.243301 -314.662924) (xy 71.278794 -314.697016) (xy 71.308359 -314.73636) (xy 71.33123 -314.779937)
			(xy 71.346814 -314.826618) (xy 71.354709 -314.875195) (xy 71.355204 -314.899802) (xy 71.354709 -314.924409)
			(xy 71.346814 -314.972986) (xy 71.33123 -315.019667) (xy 71.308359 -315.063244) (xy 71.278794 -315.102588)
			(xy 71.243301 -315.13668) (xy 71.202798 -315.164636) (xy 71.158336 -315.185734) (xy 71.111065 -315.199426)
			(xy 71.06221 -315.205358) (xy 71.013035 -315.203377) (xy 70.964816 -315.193533) (xy 70.9188 -315.176081)
			(xy 70.876179 -315.151474) (xy 70.838058 -315.120349) (xy 70.805423 -315.083512) (xy 70.77912 -315.041916)
			(xy 70.759829 -314.99664) (xy 70.748052 -314.948856) (xy 70.744092 -314.899802) (xy 70.405244 -314.899802)
			(xy 70.404749 -314.924409) (xy 70.396854 -314.972986) (xy 70.38127 -315.019667) (xy 70.358399 -315.063244)
			(xy 70.328834 -315.102588) (xy 70.293341 -315.13668) (xy 70.252838 -315.164636) (xy 70.208376 -315.185734)
			(xy 70.161105 -315.199426) (xy 70.11225 -315.205358) (xy 70.063075 -315.203377) (xy 70.014856 -315.193533)
			(xy 69.96884 -315.176081) (xy 69.926219 -315.151474) (xy 69.888098 -315.120349) (xy 69.855463 -315.083512)
			(xy 69.82916 -315.041916) (xy 69.809869 -314.99664) (xy 69.798092 -314.948856) (xy 69.794132 -314.899802)
			(xy 69.455284 -314.899802) (xy 69.454789 -314.924409) (xy 69.446894 -314.972986) (xy 69.43131 -315.019667)
			(xy 69.408439 -315.063244) (xy 69.378874 -315.102588) (xy 69.343381 -315.13668) (xy 69.302878 -315.164636)
			(xy 69.258416 -315.185734) (xy 69.211145 -315.199426) (xy 69.16229 -315.205358) (xy 69.113115 -315.203377)
			(xy 69.064896 -315.193533) (xy 69.01888 -315.176081) (xy 68.976259 -315.151474) (xy 68.938138 -315.120349)
			(xy 68.905503 -315.083512) (xy 68.8792 -315.041916) (xy 68.859909 -314.99664) (xy 68.848132 -314.948856)
			(xy 68.844172 -314.899802) (xy 68.50507 -314.899802) (xy 68.504575 -314.924409) (xy 68.49668 -314.972986)
			(xy 68.481096 -315.019667) (xy 68.458225 -315.063244) (xy 68.42866 -315.102588) (xy 68.393167 -315.13668)
			(xy 68.352664 -315.164636) (xy 68.308202 -315.185734) (xy 68.260931 -315.199426) (xy 68.212076 -315.205358)
			(xy 68.162901 -315.203377) (xy 68.114682 -315.193533) (xy 68.068666 -315.176081) (xy 68.026045 -315.151474)
			(xy 67.987924 -315.120349) (xy 67.955289 -315.083512) (xy 67.928986 -315.041916) (xy 67.909695 -314.99664)
			(xy 67.897918 -314.948856) (xy 67.893958 -314.899802) (xy 67.55511 -314.899802) (xy 67.554615 -314.924409)
			(xy 67.54672 -314.972986) (xy 67.531136 -315.019667) (xy 67.508265 -315.063244) (xy 67.4787 -315.102588)
			(xy 67.443207 -315.13668) (xy 67.402704 -315.164636) (xy 67.358242 -315.185734) (xy 67.310971 -315.199426)
			(xy 67.262116 -315.205358) (xy 67.212941 -315.203377) (xy 67.164722 -315.193533) (xy 67.118706 -315.176081)
			(xy 67.076085 -315.151474) (xy 67.037964 -315.120349) (xy 67.005329 -315.083512) (xy 66.979026 -315.041916)
			(xy 66.959735 -314.99664) (xy 66.947958 -314.948856) (xy 66.943998 -314.899802) (xy 66.60515 -314.899802)
			(xy 66.604655 -314.924409) (xy 66.59676 -314.972986) (xy 66.581176 -315.019667) (xy 66.558305 -315.063244)
			(xy 66.52874 -315.102588) (xy 66.493247 -315.13668) (xy 66.452744 -315.164636) (xy 66.408282 -315.185734)
			(xy 66.361011 -315.199426) (xy 66.312156 -315.205358) (xy 66.262981 -315.203377) (xy 66.214762 -315.193533)
			(xy 66.168746 -315.176081) (xy 66.126125 -315.151474) (xy 66.088004 -315.120349) (xy 66.055369 -315.083512)
			(xy 66.029066 -315.041916) (xy 66.009775 -314.99664) (xy 65.997998 -314.948856) (xy 65.994038 -314.899802)
			(xy 65.65519 -314.899802) (xy 65.654695 -314.924409) (xy 65.6468 -314.972986) (xy 65.631216 -315.019667)
			(xy 65.608345 -315.063244) (xy 65.57878 -315.102588) (xy 65.543287 -315.13668) (xy 65.502784 -315.164636)
			(xy 65.458322 -315.185734) (xy 65.411051 -315.199426) (xy 65.362196 -315.205358) (xy 65.313021 -315.203377)
			(xy 65.264802 -315.193533) (xy 65.218786 -315.176081) (xy 65.176165 -315.151474) (xy 65.138044 -315.120349)
			(xy 65.105409 -315.083512) (xy 65.079106 -315.041916) (xy 65.059815 -314.99664) (xy 65.048038 -314.948856)
			(xy 65.044078 -314.899802) (xy 64.70523 -314.899802) (xy 64.704735 -314.924409) (xy 64.69684 -314.972986)
			(xy 64.681256 -315.019667) (xy 64.658385 -315.063244) (xy 64.62882 -315.102588) (xy 64.593327 -315.13668)
			(xy 64.552824 -315.164636) (xy 64.508362 -315.185734) (xy 64.461091 -315.199426) (xy 64.412236 -315.205358)
			(xy 64.363061 -315.203377) (xy 64.314842 -315.193533) (xy 64.268826 -315.176081) (xy 64.226205 -315.151474)
			(xy 64.188084 -315.120349) (xy 64.155449 -315.083512) (xy 64.129146 -315.041916) (xy 64.109855 -314.99664)
			(xy 64.098078 -314.948856) (xy 64.094118 -314.899802) (xy 63.75527 -314.899802) (xy 63.754775 -314.924409)
			(xy 63.74688 -314.972986) (xy 63.731296 -315.019667) (xy 63.708425 -315.063244) (xy 63.67886 -315.102588)
			(xy 63.643367 -315.13668) (xy 63.602864 -315.164636) (xy 63.558402 -315.185734) (xy 63.511131 -315.199426)
			(xy 63.462276 -315.205358) (xy 63.413101 -315.203377) (xy 63.364882 -315.193533) (xy 63.318866 -315.176081)
			(xy 63.276245 -315.151474) (xy 63.238124 -315.120349) (xy 63.205489 -315.083512) (xy 63.179186 -315.041916)
			(xy 63.159895 -314.99664) (xy 63.148118 -314.948856) (xy 63.144158 -314.899802) (xy 62.805056 -314.899802)
			(xy 62.804561 -314.924409) (xy 62.796666 -314.972986) (xy 62.781082 -315.019667) (xy 62.758211 -315.063244)
			(xy 62.728646 -315.102588) (xy 62.693153 -315.13668) (xy 62.65265 -315.164636) (xy 62.608188 -315.185734)
			(xy 62.560917 -315.199426) (xy 62.512062 -315.205358) (xy 62.462887 -315.203377) (xy 62.414668 -315.193533)
			(xy 62.368652 -315.176081) (xy 62.326031 -315.151474) (xy 62.28791 -315.120349) (xy 62.255275 -315.083512)
			(xy 62.228972 -315.041916) (xy 62.209681 -314.99664) (xy 62.197904 -314.948856) (xy 62.193944 -314.899802)
			(xy 61.855096 -314.899802) (xy 61.854601 -314.924409) (xy 61.846706 -314.972986) (xy 61.831122 -315.019667)
			(xy 61.808251 -315.063244) (xy 61.778686 -315.102588) (xy 61.743193 -315.13668) (xy 61.70269 -315.164636)
			(xy 61.658228 -315.185734) (xy 61.610957 -315.199426) (xy 61.562102 -315.205358) (xy 61.512927 -315.203377)
			(xy 61.464708 -315.193533) (xy 61.418692 -315.176081) (xy 61.376071 -315.151474) (xy 61.33795 -315.120349)
			(xy 61.305315 -315.083512) (xy 61.279012 -315.041916) (xy 61.259721 -314.99664) (xy 61.247944 -314.948856)
			(xy 61.243984 -314.899802) (xy 60.905136 -314.899802) (xy 60.904641 -314.924409) (xy 60.896746 -314.972986)
			(xy 60.881162 -315.019667) (xy 60.858291 -315.063244) (xy 60.828726 -315.102588) (xy 60.793233 -315.13668)
			(xy 60.75273 -315.164636) (xy 60.708268 -315.185734) (xy 60.660997 -315.199426) (xy 60.612142 -315.205358)
			(xy 60.562967 -315.203377) (xy 60.514748 -315.193533) (xy 60.468732 -315.176081) (xy 60.426111 -315.151474)
			(xy 60.38799 -315.120349) (xy 60.355355 -315.083512) (xy 60.329052 -315.041916) (xy 60.309761 -314.99664)
			(xy 60.297984 -314.948856) (xy 60.294024 -314.899802) (xy 59.955176 -314.899802) (xy 59.954681 -314.924409)
			(xy 59.946786 -314.972986) (xy 59.931202 -315.019667) (xy 59.908331 -315.063244) (xy 59.878766 -315.102588)
			(xy 59.843273 -315.13668) (xy 59.80277 -315.164636) (xy 59.758308 -315.185734) (xy 59.711037 -315.199426)
			(xy 59.662182 -315.205358) (xy 59.613007 -315.203377) (xy 59.564788 -315.193533) (xy 59.518772 -315.176081)
			(xy 59.476151 -315.151474) (xy 59.43803 -315.120349) (xy 59.405395 -315.083512) (xy 59.379092 -315.041916)
			(xy 59.359801 -314.99664) (xy 59.348024 -314.948856) (xy 59.344064 -314.899802) (xy 59.005216 -314.899802)
			(xy 59.004721 -314.924409) (xy 58.996826 -314.972986) (xy 58.981242 -315.019667) (xy 58.958371 -315.063244)
			(xy 58.928806 -315.102588) (xy 58.893313 -315.13668) (xy 58.85281 -315.164636) (xy 58.808348 -315.185734)
			(xy 58.761077 -315.199426) (xy 58.712222 -315.205358) (xy 58.663047 -315.203377) (xy 58.614828 -315.193533)
			(xy 58.568812 -315.176081) (xy 58.526191 -315.151474) (xy 58.48807 -315.120349) (xy 58.455435 -315.083512)
			(xy 58.429132 -315.041916) (xy 58.409841 -314.99664) (xy 58.398064 -314.948856) (xy 58.394104 -314.899802)
			(xy 58.055256 -314.899802) (xy 58.054761 -314.924409) (xy 58.046866 -314.972986) (xy 58.031282 -315.019667)
			(xy 58.008411 -315.063244) (xy 57.978846 -315.102588) (xy 57.943353 -315.13668) (xy 57.90285 -315.164636)
			(xy 57.858388 -315.185734) (xy 57.811117 -315.199426) (xy 57.762262 -315.205358) (xy 57.713087 -315.203377)
			(xy 57.664868 -315.193533) (xy 57.618852 -315.176081) (xy 57.576231 -315.151474) (xy 57.53811 -315.120349)
			(xy 57.505475 -315.083512) (xy 57.479172 -315.041916) (xy 57.459881 -314.99664) (xy 57.448104 -314.948856)
			(xy 57.444144 -314.899802) (xy 57.105296 -314.899802) (xy 57.104801 -314.924409) (xy 57.096906 -314.972986)
			(xy 57.081322 -315.019667) (xy 57.058451 -315.063244) (xy 57.028886 -315.102588) (xy 56.993393 -315.13668)
			(xy 56.95289 -315.164636) (xy 56.908428 -315.185734) (xy 56.861157 -315.199426) (xy 56.812302 -315.205358)
			(xy 56.763127 -315.203377) (xy 56.714908 -315.193533) (xy 56.668892 -315.176081) (xy 56.626271 -315.151474)
			(xy 56.58815 -315.120349) (xy 56.555515 -315.083512) (xy 56.529212 -315.041916) (xy 56.509921 -314.99664)
			(xy 56.498144 -314.948856) (xy 56.494184 -314.899802) (xy 56.155082 -314.899802) (xy 56.154587 -314.924409)
			(xy 56.146692 -314.972986) (xy 56.131108 -315.019667) (xy 56.108237 -315.063244) (xy 56.078672 -315.102588)
			(xy 56.043179 -315.13668) (xy 56.002676 -315.164636) (xy 55.958214 -315.185734) (xy 55.910943 -315.199426)
			(xy 55.862088 -315.205358) (xy 55.812913 -315.203377) (xy 55.764694 -315.193533) (xy 55.718678 -315.176081)
			(xy 55.676057 -315.151474) (xy 55.637936 -315.120349) (xy 55.605301 -315.083512) (xy 55.578998 -315.041916)
			(xy 55.559707 -314.99664) (xy 55.54793 -314.948856) (xy 55.54397 -314.899802) (xy 55.205122 -314.899802)
			(xy 55.204627 -314.924409) (xy 55.196732 -314.972986) (xy 55.181148 -315.019667) (xy 55.158277 -315.063244)
			(xy 55.128712 -315.102588) (xy 55.093219 -315.13668) (xy 55.052716 -315.164636) (xy 55.008254 -315.185734)
			(xy 54.960983 -315.199426) (xy 54.912128 -315.205358) (xy 54.862953 -315.203377) (xy 54.814734 -315.193533)
			(xy 54.768718 -315.176081) (xy 54.726097 -315.151474) (xy 54.687976 -315.120349) (xy 54.655341 -315.083512)
			(xy 54.629038 -315.041916) (xy 54.609747 -314.99664) (xy 54.59797 -314.948856) (xy 54.59401 -314.899802)
			(xy 54.255162 -314.899802) (xy 54.254667 -314.924409) (xy 54.246772 -314.972986) (xy 54.231188 -315.019667)
			(xy 54.208317 -315.063244) (xy 54.178752 -315.102588) (xy 54.143259 -315.13668) (xy 54.102756 -315.164636)
			(xy 54.058294 -315.185734) (xy 54.011023 -315.199426) (xy 53.962168 -315.205358) (xy 53.912993 -315.203377)
			(xy 53.864774 -315.193533) (xy 53.818758 -315.176081) (xy 53.776137 -315.151474) (xy 53.738016 -315.120349)
			(xy 53.705381 -315.083512) (xy 53.679078 -315.041916) (xy 53.659787 -314.99664) (xy 53.64801 -314.948856)
			(xy 53.64405 -314.899802) (xy 53.305202 -314.899802) (xy 53.304707 -314.924409) (xy 53.296812 -314.972986)
			(xy 53.281228 -315.019667) (xy 53.258357 -315.063244) (xy 53.228792 -315.102588) (xy 53.193299 -315.13668)
			(xy 53.152796 -315.164636) (xy 53.108334 -315.185734) (xy 53.061063 -315.199426) (xy 53.012208 -315.205358)
			(xy 52.963033 -315.203377) (xy 52.914814 -315.193533) (xy 52.868798 -315.176081) (xy 52.826177 -315.151474)
			(xy 52.788056 -315.120349) (xy 52.755421 -315.083512) (xy 52.729118 -315.041916) (xy 52.709827 -314.99664)
			(xy 52.69805 -314.948856) (xy 52.69409 -314.899802) (xy 52.355242 -314.899802) (xy 52.354747 -314.924409)
			(xy 52.346852 -314.972986) (xy 52.331268 -315.019667) (xy 52.308397 -315.063244) (xy 52.278832 -315.102588)
			(xy 52.243339 -315.13668) (xy 52.202836 -315.164636) (xy 52.158374 -315.185734) (xy 52.111103 -315.199426)
			(xy 52.062248 -315.205358) (xy 52.013073 -315.203377) (xy 51.964854 -315.193533) (xy 51.918838 -315.176081)
			(xy 51.876217 -315.151474) (xy 51.838096 -315.120349) (xy 51.805461 -315.083512) (xy 51.779158 -315.041916)
			(xy 51.759867 -314.99664) (xy 51.74809 -314.948856) (xy 51.74413 -314.899802) (xy 51.405282 -314.899802)
			(xy 51.404787 -314.924409) (xy 51.396892 -314.972986) (xy 51.381308 -315.019667) (xy 51.358437 -315.063244)
			(xy 51.328872 -315.102588) (xy 51.293379 -315.13668) (xy 51.252876 -315.164636) (xy 51.208414 -315.185734)
			(xy 51.161143 -315.199426) (xy 51.112288 -315.205358) (xy 51.063113 -315.203377) (xy 51.014894 -315.193533)
			(xy 50.968878 -315.176081) (xy 50.926257 -315.151474) (xy 50.888136 -315.120349) (xy 50.855501 -315.083512)
			(xy 50.829198 -315.041916) (xy 50.809907 -314.99664) (xy 50.79813 -314.948856) (xy 50.79417 -314.899802)
			(xy 50.455068 -314.899802) (xy 50.454573 -314.924409) (xy 50.446678 -314.972986) (xy 50.431094 -315.019667)
			(xy 50.408223 -315.063244) (xy 50.378658 -315.102588) (xy 50.343165 -315.13668) (xy 50.302662 -315.164636)
			(xy 50.2582 -315.185734) (xy 50.210929 -315.199426) (xy 50.162074 -315.205358) (xy 50.112899 -315.203377)
			(xy 50.06468 -315.193533) (xy 50.018664 -315.176081) (xy 49.976043 -315.151474) (xy 49.937922 -315.120349)
			(xy 49.905287 -315.083512) (xy 49.878984 -315.041916) (xy 49.859693 -314.99664) (xy 49.847916 -314.948856)
			(xy 49.843956 -314.899802) (xy 49.505108 -314.899802) (xy 49.504613 -314.924409) (xy 49.496718 -314.972986)
			(xy 49.481134 -315.019667) (xy 49.458263 -315.063244) (xy 49.428698 -315.102588) (xy 49.393205 -315.13668)
			(xy 49.352702 -315.164636) (xy 49.30824 -315.185734) (xy 49.260969 -315.199426) (xy 49.212114 -315.205358)
			(xy 49.162939 -315.203377) (xy 49.11472 -315.193533) (xy 49.068704 -315.176081) (xy 49.026083 -315.151474)
			(xy 48.987962 -315.120349) (xy 48.955327 -315.083512) (xy 48.929024 -315.041916) (xy 48.909733 -314.99664)
			(xy 48.897956 -314.948856) (xy 48.893996 -314.899802) (xy 48.555148 -314.899802) (xy 48.554653 -314.924409)
			(xy 48.546758 -314.972986) (xy 48.531174 -315.019667) (xy 48.508303 -315.063244) (xy 48.478738 -315.102588)
			(xy 48.443245 -315.13668) (xy 48.402742 -315.164636) (xy 48.35828 -315.185734) (xy 48.311009 -315.199426)
			(xy 48.262154 -315.205358) (xy 48.212979 -315.203377) (xy 48.16476 -315.193533) (xy 48.118744 -315.176081)
			(xy 48.076123 -315.151474) (xy 48.038002 -315.120349) (xy 48.005367 -315.083512) (xy 47.979064 -315.041916)
			(xy 47.959773 -314.99664) (xy 47.947996 -314.948856) (xy 47.944036 -314.899802) (xy 47.605188 -314.899802)
			(xy 47.604693 -314.924409) (xy 47.596798 -314.972986) (xy 47.581214 -315.019667) (xy 47.558343 -315.063244)
			(xy 47.528778 -315.102588) (xy 47.493285 -315.13668) (xy 47.452782 -315.164636) (xy 47.40832 -315.185734)
			(xy 47.361049 -315.199426) (xy 47.312194 -315.205358) (xy 47.263019 -315.203377) (xy 47.2148 -315.193533)
			(xy 47.168784 -315.176081) (xy 47.126163 -315.151474) (xy 47.088042 -315.120349) (xy 47.055407 -315.083512)
			(xy 47.029104 -315.041916) (xy 47.009813 -314.99664) (xy 46.998036 -314.948856) (xy 46.994076 -314.899802)
			(xy 46.655228 -314.899802) (xy 46.654733 -314.924409) (xy 46.646838 -314.972986) (xy 46.631254 -315.019667)
			(xy 46.608383 -315.063244) (xy 46.578818 -315.102588) (xy 46.543325 -315.13668) (xy 46.502822 -315.164636)
			(xy 46.45836 -315.185734) (xy 46.411089 -315.199426) (xy 46.362234 -315.205358) (xy 46.313059 -315.203377)
			(xy 46.26484 -315.193533) (xy 46.218824 -315.176081) (xy 46.176203 -315.151474) (xy 46.138082 -315.120349)
			(xy 46.105447 -315.083512) (xy 46.079144 -315.041916) (xy 46.059853 -314.99664) (xy 46.048076 -314.948856)
			(xy 46.044116 -314.899802) (xy 45.705268 -314.899802) (xy 45.704773 -314.924409) (xy 45.696878 -314.972986)
			(xy 45.681294 -315.019667) (xy 45.658423 -315.063244) (xy 45.628858 -315.102588) (xy 45.593365 -315.13668)
			(xy 45.552862 -315.164636) (xy 45.5084 -315.185734) (xy 45.461129 -315.199426) (xy 45.412274 -315.205358)
			(xy 45.363099 -315.203377) (xy 45.31488 -315.193533) (xy 45.268864 -315.176081) (xy 45.226243 -315.151474)
			(xy 45.188122 -315.120349) (xy 45.155487 -315.083512) (xy 45.129184 -315.041916) (xy 45.109893 -314.99664)
			(xy 45.098116 -314.948856) (xy 45.094156 -314.899802) (xy 44.755054 -314.899802) (xy 44.754559 -314.924409)
			(xy 44.746664 -314.972986) (xy 44.73108 -315.019667) (xy 44.708209 -315.063244) (xy 44.678644 -315.102588)
			(xy 44.643151 -315.13668) (xy 44.602648 -315.164636) (xy 44.558186 -315.185734) (xy 44.510915 -315.199426)
			(xy 44.46206 -315.205358) (xy 44.412885 -315.203377) (xy 44.364666 -315.193533) (xy 44.31865 -315.176081)
			(xy 44.276029 -315.151474) (xy 44.237908 -315.120349) (xy 44.205273 -315.083512) (xy 44.17897 -315.041916)
			(xy 44.159679 -314.99664) (xy 44.147902 -314.948856) (xy 44.143942 -314.899802) (xy 43.805094 -314.899802)
			(xy 43.804599 -314.924409) (xy 43.796704 -314.972986) (xy 43.78112 -315.019667) (xy 43.758249 -315.063244)
			(xy 43.728684 -315.102588) (xy 43.693191 -315.13668) (xy 43.652688 -315.164636) (xy 43.608226 -315.185734)
			(xy 43.560955 -315.199426) (xy 43.5121 -315.205358) (xy 43.462925 -315.203377) (xy 43.414706 -315.193533)
			(xy 43.36869 -315.176081) (xy 43.326069 -315.151474) (xy 43.287948 -315.120349) (xy 43.255313 -315.083512)
			(xy 43.22901 -315.041916) (xy 43.209719 -314.99664) (xy 43.197942 -314.948856) (xy 43.193982 -314.899802)
			(xy 42.855134 -314.899802) (xy 42.854639 -314.924409) (xy 42.846744 -314.972986) (xy 42.83116 -315.019667)
			(xy 42.808289 -315.063244) (xy 42.778724 -315.102588) (xy 42.743231 -315.13668) (xy 42.702728 -315.164636)
			(xy 42.658266 -315.185734) (xy 42.610995 -315.199426) (xy 42.56214 -315.205358) (xy 42.512965 -315.203377)
			(xy 42.464746 -315.193533) (xy 42.41873 -315.176081) (xy 42.376109 -315.151474) (xy 42.337988 -315.120349)
			(xy 42.305353 -315.083512) (xy 42.27905 -315.041916) (xy 42.259759 -314.99664) (xy 42.247982 -314.948856)
			(xy 42.244022 -314.899802) (xy 41.905174 -314.899802) (xy 41.904679 -314.924409) (xy 41.896784 -314.972986)
			(xy 41.8812 -315.019667) (xy 41.858329 -315.063244) (xy 41.828764 -315.102588) (xy 41.793271 -315.13668)
			(xy 41.752768 -315.164636) (xy 41.708306 -315.185734) (xy 41.661035 -315.199426) (xy 41.61218 -315.205358)
			(xy 41.563005 -315.203377) (xy 41.514786 -315.193533) (xy 41.46877 -315.176081) (xy 41.426149 -315.151474)
			(xy 41.388028 -315.120349) (xy 41.355393 -315.083512) (xy 41.32909 -315.041916) (xy 41.309799 -314.99664)
			(xy 41.298022 -314.948856) (xy 41.294062 -314.899802) (xy 40.955214 -314.899802) (xy 40.954719 -314.924409)
			(xy 40.946824 -314.972986) (xy 40.93124 -315.019667) (xy 40.908369 -315.063244) (xy 40.878804 -315.102588)
			(xy 40.843311 -315.13668) (xy 40.802808 -315.164636) (xy 40.758346 -315.185734) (xy 40.711075 -315.199426)
			(xy 40.66222 -315.205358) (xy 40.613045 -315.203377) (xy 40.564826 -315.193533) (xy 40.51881 -315.176081)
			(xy 40.476189 -315.151474) (xy 40.438068 -315.120349) (xy 40.405433 -315.083512) (xy 40.37913 -315.041916)
			(xy 40.359839 -314.99664) (xy 40.348062 -314.948856) (xy 40.344102 -314.899802) (xy 40.005254 -314.899802)
			(xy 40.004759 -314.924409) (xy 39.996864 -314.972986) (xy 39.98128 -315.019667) (xy 39.958409 -315.063244)
			(xy 39.928844 -315.102588) (xy 39.893351 -315.13668) (xy 39.852848 -315.164636) (xy 39.808386 -315.185734)
			(xy 39.761115 -315.199426) (xy 39.71226 -315.205358) (xy 39.663085 -315.203377) (xy 39.614866 -315.193533)
			(xy 39.56885 -315.176081) (xy 39.526229 -315.151474) (xy 39.488108 -315.120349) (xy 39.455473 -315.083512)
			(xy 39.42917 -315.041916) (xy 39.409879 -314.99664) (xy 39.398102 -314.948856) (xy 39.394142 -314.899802)
			(xy 39.055294 -314.899802) (xy 39.054799 -314.924409) (xy 39.046904 -314.972986) (xy 39.03132 -315.019667)
			(xy 39.008449 -315.063244) (xy 38.978884 -315.102588) (xy 38.943391 -315.13668) (xy 38.902888 -315.164636)
			(xy 38.858426 -315.185734) (xy 38.811155 -315.199426) (xy 38.7623 -315.205358) (xy 38.713125 -315.203377)
			(xy 38.664906 -315.193533) (xy 38.61889 -315.176081) (xy 38.576269 -315.151474) (xy 38.538148 -315.120349)
			(xy 38.505513 -315.083512) (xy 38.47921 -315.041916) (xy 38.459919 -314.99664) (xy 38.448142 -314.948856)
			(xy 38.444182 -314.899802) (xy 38.126924 -314.899802) (xy 38.12642 -314.92551) (xy 38.118377 -314.976292)
			(xy 38.102489 -315.025191) (xy 38.079146 -315.071003) (xy 38.048925 -315.112599) (xy 38.012569 -315.148955)
			(xy 37.970973 -315.179176) (xy 37.925161 -315.202519) (xy 37.876262 -315.218407) (xy 37.82548 -315.22645)
			(xy 37.774064 -315.22645) (xy 37.723282 -315.218407) (xy 37.674383 -315.202519) (xy 37.628571 -315.179176)
			(xy 37.586975 -315.148955) (xy 37.550619 -315.112599) (xy 37.520398 -315.071003) (xy 37.497055 -315.025191)
			(xy 37.481167 -314.976292) (xy 37.473124 -314.92551) (xy 37.17646 -314.92551) (xy 37.168417 -314.976292)
			(xy 37.152529 -315.025191) (xy 37.129186 -315.071003) (xy 37.098965 -315.112599) (xy 37.062609 -315.148955)
			(xy 37.021013 -315.179176) (xy 36.975201 -315.202519) (xy 36.926302 -315.218407) (xy 36.87552 -315.22645)
			(xy 36.824104 -315.22645) (xy 36.773322 -315.218407) (xy 36.724423 -315.202519) (xy 36.678611 -315.179176)
			(xy 36.637015 -315.148955) (xy 36.600659 -315.112599) (xy 36.570438 -315.071003) (xy 36.547095 -315.025191)
			(xy 36.531207 -314.976292) (xy 36.523164 -314.92551) (xy 36.203937 -314.92551) (xy 36.196262 -314.972732)
			(xy 36.180678 -315.019413) (xy 36.157807 -315.06299) (xy 36.128242 -315.102334) (xy 36.092749 -315.136426)
			(xy 36.052246 -315.164382) (xy 36.007784 -315.18548) (xy 35.960513 -315.199172) (xy 35.911658 -315.205104)
			(xy 35.862483 -315.203123) (xy 35.814264 -315.193279) (xy 35.768248 -315.175827) (xy 35.725627 -315.15122)
			(xy 35.687506 -315.120095) (xy 35.654871 -315.083258) (xy 35.628568 -315.041662) (xy 35.609277 -314.996386)
			(xy 35.5975 -314.948602) (xy 35.59354 -314.899548) (xy 17.635982 -314.899548) (xy 17.635982 -315.849762)
			(xy 36.544008 -315.849762) (xy 36.547968 -315.800708) (xy 36.559745 -315.752924) (xy 36.579036 -315.707648)
			(xy 36.605339 -315.666052) (xy 36.637974 -315.629215) (xy 36.676095 -315.59809) (xy 36.718716 -315.573483)
			(xy 36.764732 -315.556031) (xy 36.812951 -315.546187) (xy 36.862126 -315.544206) (xy 36.910981 -315.550138)
			(xy 36.958252 -315.56383) (xy 37.002714 -315.584928) (xy 37.043217 -315.612884) (xy 37.07871 -315.646976)
			(xy 37.108275 -315.68632) (xy 37.131146 -315.729897) (xy 37.14673 -315.776578) (xy 37.154625 -315.825155)
			(xy 37.15512 -315.849762) (xy 37.493968 -315.849762) (xy 37.497928 -315.800708) (xy 37.509705 -315.752924)
			(xy 37.528996 -315.707648) (xy 37.555299 -315.666052) (xy 37.587934 -315.629215) (xy 37.626055 -315.59809)
			(xy 37.668676 -315.573483) (xy 37.714692 -315.556031) (xy 37.762911 -315.546187) (xy 37.812086 -315.544206)
			(xy 37.860941 -315.550138) (xy 37.908212 -315.56383) (xy 37.952674 -315.584928) (xy 37.993177 -315.612884)
			(xy 38.02867 -315.646976) (xy 38.058235 -315.68632) (xy 38.081106 -315.729897) (xy 38.09669 -315.776578)
			(xy 38.104585 -315.825155) (xy 38.10508 -315.849762) (xy 38.444182 -315.849762) (xy 38.448142 -315.800708)
			(xy 38.459919 -315.752924) (xy 38.47921 -315.707648) (xy 38.505513 -315.666052) (xy 38.538148 -315.629215)
			(xy 38.576269 -315.59809) (xy 38.61889 -315.573483) (xy 38.664906 -315.556031) (xy 38.713125 -315.546187)
			(xy 38.7623 -315.544206) (xy 38.811155 -315.550138) (xy 38.858426 -315.56383) (xy 38.902888 -315.584928)
			(xy 38.943391 -315.612884) (xy 38.978884 -315.646976) (xy 39.008449 -315.68632) (xy 39.03132 -315.729897)
			(xy 39.046904 -315.776578) (xy 39.054799 -315.825155) (xy 39.055294 -315.849762) (xy 39.054799 -315.874369)
			(xy 39.05462 -315.87547) (xy 39.373298 -315.87547) (xy 39.373298 -315.824054) (xy 39.381341 -315.773272)
			(xy 39.397229 -315.724373) (xy 39.420572 -315.678561) (xy 39.450793 -315.636965) (xy 39.487149 -315.600609)
			(xy 39.528745 -315.570388) (xy 39.574557 -315.547045) (xy 39.623456 -315.531157) (xy 39.674238 -315.523114)
			(xy 39.725654 -315.523114) (xy 39.776436 -315.531157) (xy 39.825335 -315.547045) (xy 39.871147 -315.570388)
			(xy 39.912743 -315.600609) (xy 39.949099 -315.636965) (xy 39.97932 -315.678561) (xy 40.002663 -315.724373)
			(xy 40.018551 -315.773272) (xy 40.026594 -315.824054) (xy 40.027098 -315.849762) (xy 40.344102 -315.849762)
			(xy 40.348062 -315.800708) (xy 40.359839 -315.752924) (xy 40.37913 -315.707648) (xy 40.405433 -315.666052)
			(xy 40.438068 -315.629215) (xy 40.476189 -315.59809) (xy 40.51881 -315.573483) (xy 40.564826 -315.556031)
			(xy 40.613045 -315.546187) (xy 40.66222 -315.544206) (xy 40.711075 -315.550138) (xy 40.758346 -315.56383)
			(xy 40.802808 -315.584928) (xy 40.843311 -315.612884) (xy 40.878804 -315.646976) (xy 40.908369 -315.68632)
			(xy 40.93124 -315.729897) (xy 40.946824 -315.776578) (xy 40.954719 -315.825155) (xy 40.955214 -315.849762)
			(xy 40.954719 -315.874369) (xy 40.95454 -315.87547) (xy 41.273218 -315.87547) (xy 41.273218 -315.824054)
			(xy 41.281261 -315.773272) (xy 41.297149 -315.724373) (xy 41.320492 -315.678561) (xy 41.350713 -315.636965)
			(xy 41.387069 -315.600609) (xy 41.428665 -315.570388) (xy 41.474477 -315.547045) (xy 41.523376 -315.531157)
			(xy 41.574158 -315.523114) (xy 41.625574 -315.523114) (xy 41.676356 -315.531157) (xy 41.725255 -315.547045)
			(xy 41.771067 -315.570388) (xy 41.812663 -315.600609) (xy 41.849019 -315.636965) (xy 41.87924 -315.678561)
			(xy 41.902583 -315.724373) (xy 41.918471 -315.773272) (xy 41.926514 -315.824054) (xy 41.927018 -315.849762)
			(xy 42.244022 -315.849762) (xy 42.247982 -315.800708) (xy 42.259759 -315.752924) (xy 42.27905 -315.707648)
			(xy 42.305353 -315.666052) (xy 42.337988 -315.629215) (xy 42.376109 -315.59809) (xy 42.41873 -315.573483)
			(xy 42.464746 -315.556031) (xy 42.512965 -315.546187) (xy 42.56214 -315.544206) (xy 42.610995 -315.550138)
			(xy 42.658266 -315.56383) (xy 42.702728 -315.584928) (xy 42.743231 -315.612884) (xy 42.778724 -315.646976)
			(xy 42.808289 -315.68632) (xy 42.83116 -315.729897) (xy 42.846744 -315.776578) (xy 42.854639 -315.825155)
			(xy 42.855134 -315.849762) (xy 42.854639 -315.874369) (xy 42.85446 -315.87547) (xy 43.173138 -315.87547)
			(xy 43.173138 -315.824054) (xy 43.181181 -315.773272) (xy 43.197069 -315.724373) (xy 43.220412 -315.678561)
			(xy 43.250633 -315.636965) (xy 43.286989 -315.600609) (xy 43.328585 -315.570388) (xy 43.374397 -315.547045)
			(xy 43.423296 -315.531157) (xy 43.474078 -315.523114) (xy 43.525494 -315.523114) (xy 43.576276 -315.531157)
			(xy 43.625175 -315.547045) (xy 43.670987 -315.570388) (xy 43.712583 -315.600609) (xy 43.748939 -315.636965)
			(xy 43.77916 -315.678561) (xy 43.802503 -315.724373) (xy 43.818391 -315.773272) (xy 43.826434 -315.824054)
			(xy 43.826938 -315.849762) (xy 44.143942 -315.849762) (xy 44.147902 -315.800708) (xy 44.159679 -315.752924)
			(xy 44.17897 -315.707648) (xy 44.205273 -315.666052) (xy 44.237908 -315.629215) (xy 44.276029 -315.59809)
			(xy 44.31865 -315.573483) (xy 44.364666 -315.556031) (xy 44.412885 -315.546187) (xy 44.46206 -315.544206)
			(xy 44.510915 -315.550138) (xy 44.558186 -315.56383) (xy 44.602648 -315.584928) (xy 44.643151 -315.612884)
			(xy 44.678644 -315.646976) (xy 44.708209 -315.68632) (xy 44.73108 -315.729897) (xy 44.746664 -315.776578)
			(xy 44.754559 -315.825155) (xy 44.755054 -315.849762) (xy 44.754559 -315.874369) (xy 44.75438 -315.87547)
			(xy 45.073312 -315.87547) (xy 45.073312 -315.824054) (xy 45.081355 -315.773272) (xy 45.097243 -315.724373)
			(xy 45.120586 -315.678561) (xy 45.150807 -315.636965) (xy 45.187163 -315.600609) (xy 45.228759 -315.570388)
			(xy 45.274571 -315.547045) (xy 45.32347 -315.531157) (xy 45.374252 -315.523114) (xy 45.425668 -315.523114)
			(xy 45.47645 -315.531157) (xy 45.525349 -315.547045) (xy 45.571161 -315.570388) (xy 45.612757 -315.600609)
			(xy 45.649113 -315.636965) (xy 45.679334 -315.678561) (xy 45.702677 -315.724373) (xy 45.718565 -315.773272)
			(xy 45.726608 -315.824054) (xy 45.727112 -315.849762) (xy 46.044116 -315.849762) (xy 46.048076 -315.800708)
			(xy 46.059853 -315.752924) (xy 46.079144 -315.707648) (xy 46.105447 -315.666052) (xy 46.138082 -315.629215)
			(xy 46.176203 -315.59809) (xy 46.218824 -315.573483) (xy 46.26484 -315.556031) (xy 46.313059 -315.546187)
			(xy 46.362234 -315.544206) (xy 46.411089 -315.550138) (xy 46.45836 -315.56383) (xy 46.502822 -315.584928)
			(xy 46.543325 -315.612884) (xy 46.578818 -315.646976) (xy 46.608383 -315.68632) (xy 46.631254 -315.729897)
			(xy 46.646838 -315.776578) (xy 46.654733 -315.825155) (xy 46.655228 -315.849762) (xy 46.654733 -315.874369)
			(xy 46.654554 -315.87547) (xy 46.973232 -315.87547) (xy 46.973232 -315.824054) (xy 46.981275 -315.773272)
			(xy 46.997163 -315.724373) (xy 47.020506 -315.678561) (xy 47.050727 -315.636965) (xy 47.087083 -315.600609)
			(xy 47.128679 -315.570388) (xy 47.174491 -315.547045) (xy 47.22339 -315.531157) (xy 47.274172 -315.523114)
			(xy 47.325588 -315.523114) (xy 47.37637 -315.531157) (xy 47.425269 -315.547045) (xy 47.471081 -315.570388)
			(xy 47.512677 -315.600609) (xy 47.549033 -315.636965) (xy 47.579254 -315.678561) (xy 47.602597 -315.724373)
			(xy 47.618485 -315.773272) (xy 47.626528 -315.824054) (xy 47.627032 -315.849762) (xy 47.944036 -315.849762)
			(xy 47.947996 -315.800708) (xy 47.959773 -315.752924) (xy 47.979064 -315.707648) (xy 48.005367 -315.666052)
			(xy 48.038002 -315.629215) (xy 48.076123 -315.59809) (xy 48.118744 -315.573483) (xy 48.16476 -315.556031)
			(xy 48.212979 -315.546187) (xy 48.262154 -315.544206) (xy 48.311009 -315.550138) (xy 48.35828 -315.56383)
			(xy 48.402742 -315.584928) (xy 48.443245 -315.612884) (xy 48.478738 -315.646976) (xy 48.508303 -315.68632)
			(xy 48.531174 -315.729897) (xy 48.546758 -315.776578) (xy 48.554653 -315.825155) (xy 48.555148 -315.849762)
			(xy 48.554653 -315.874369) (xy 48.554474 -315.87547) (xy 48.873152 -315.87547) (xy 48.873152 -315.824054)
			(xy 48.881195 -315.773272) (xy 48.897083 -315.724373) (xy 48.920426 -315.678561) (xy 48.950647 -315.636965)
			(xy 48.987003 -315.600609) (xy 49.028599 -315.570388) (xy 49.074411 -315.547045) (xy 49.12331 -315.531157)
			(xy 49.174092 -315.523114) (xy 49.225508 -315.523114) (xy 49.27629 -315.531157) (xy 49.325189 -315.547045)
			(xy 49.371001 -315.570388) (xy 49.412597 -315.600609) (xy 49.448953 -315.636965) (xy 49.479174 -315.678561)
			(xy 49.502517 -315.724373) (xy 49.518405 -315.773272) (xy 49.526448 -315.824054) (xy 49.526952 -315.849762)
			(xy 49.843956 -315.849762) (xy 49.847916 -315.800708) (xy 49.859693 -315.752924) (xy 49.878984 -315.707648)
			(xy 49.905287 -315.666052) (xy 49.937922 -315.629215) (xy 49.976043 -315.59809) (xy 50.018664 -315.573483)
			(xy 50.06468 -315.556031) (xy 50.112899 -315.546187) (xy 50.162074 -315.544206) (xy 50.210929 -315.550138)
			(xy 50.2582 -315.56383) (xy 50.302662 -315.584928) (xy 50.343165 -315.612884) (xy 50.378658 -315.646976)
			(xy 50.408223 -315.68632) (xy 50.431094 -315.729897) (xy 50.446678 -315.776578) (xy 50.454573 -315.825155)
			(xy 50.455068 -315.849762) (xy 50.454573 -315.874369) (xy 50.454394 -315.87547) (xy 50.773326 -315.87547)
			(xy 50.773326 -315.824054) (xy 50.781369 -315.773272) (xy 50.797257 -315.724373) (xy 50.8206 -315.678561)
			(xy 50.850821 -315.636965) (xy 50.887177 -315.600609) (xy 50.928773 -315.570388) (xy 50.974585 -315.547045)
			(xy 51.023484 -315.531157) (xy 51.074266 -315.523114) (xy 51.125682 -315.523114) (xy 51.176464 -315.531157)
			(xy 51.225363 -315.547045) (xy 51.271175 -315.570388) (xy 51.312771 -315.600609) (xy 51.349127 -315.636965)
			(xy 51.379348 -315.678561) (xy 51.402691 -315.724373) (xy 51.418579 -315.773272) (xy 51.426622 -315.824054)
			(xy 51.427126 -315.849762) (xy 51.74413 -315.849762) (xy 51.74809 -315.800708) (xy 51.759867 -315.752924)
			(xy 51.779158 -315.707648) (xy 51.805461 -315.666052) (xy 51.838096 -315.629215) (xy 51.876217 -315.59809)
			(xy 51.918838 -315.573483) (xy 51.964854 -315.556031) (xy 52.013073 -315.546187) (xy 52.062248 -315.544206)
			(xy 52.111103 -315.550138) (xy 52.158374 -315.56383) (xy 52.202836 -315.584928) (xy 52.243339 -315.612884)
			(xy 52.278832 -315.646976) (xy 52.308397 -315.68632) (xy 52.331268 -315.729897) (xy 52.346852 -315.776578)
			(xy 52.354747 -315.825155) (xy 52.355242 -315.849762) (xy 52.354747 -315.874369) (xy 52.354568 -315.87547)
			(xy 52.673246 -315.87547) (xy 52.673246 -315.824054) (xy 52.681289 -315.773272) (xy 52.697177 -315.724373)
			(xy 52.72052 -315.678561) (xy 52.750741 -315.636965) (xy 52.787097 -315.600609) (xy 52.828693 -315.570388)
			(xy 52.874505 -315.547045) (xy 52.923404 -315.531157) (xy 52.974186 -315.523114) (xy 53.025602 -315.523114)
			(xy 53.076384 -315.531157) (xy 53.125283 -315.547045) (xy 53.171095 -315.570388) (xy 53.212691 -315.600609)
			(xy 53.249047 -315.636965) (xy 53.279268 -315.678561) (xy 53.302611 -315.724373) (xy 53.318499 -315.773272)
			(xy 53.326542 -315.824054) (xy 53.327046 -315.849762) (xy 53.64405 -315.849762) (xy 53.64801 -315.800708)
			(xy 53.659787 -315.752924) (xy 53.679078 -315.707648) (xy 53.705381 -315.666052) (xy 53.738016 -315.629215)
			(xy 53.776137 -315.59809) (xy 53.818758 -315.573483) (xy 53.864774 -315.556031) (xy 53.912993 -315.546187)
			(xy 53.962168 -315.544206) (xy 54.011023 -315.550138) (xy 54.058294 -315.56383) (xy 54.102756 -315.584928)
			(xy 54.143259 -315.612884) (xy 54.178752 -315.646976) (xy 54.208317 -315.68632) (xy 54.231188 -315.729897)
			(xy 54.246772 -315.776578) (xy 54.254667 -315.825155) (xy 54.255162 -315.849762) (xy 54.254667 -315.874369)
			(xy 54.254488 -315.87547) (xy 54.573166 -315.87547) (xy 54.573166 -315.824054) (xy 54.581209 -315.773272)
			(xy 54.597097 -315.724373) (xy 54.62044 -315.678561) (xy 54.650661 -315.636965) (xy 54.687017 -315.600609)
			(xy 54.728613 -315.570388) (xy 54.774425 -315.547045) (xy 54.823324 -315.531157) (xy 54.874106 -315.523114)
			(xy 54.925522 -315.523114) (xy 54.976304 -315.531157) (xy 55.025203 -315.547045) (xy 55.071015 -315.570388)
			(xy 55.112611 -315.600609) (xy 55.148967 -315.636965) (xy 55.179188 -315.678561) (xy 55.202531 -315.724373)
			(xy 55.218419 -315.773272) (xy 55.226462 -315.824054) (xy 55.226966 -315.849762) (xy 55.54397 -315.849762)
			(xy 55.54793 -315.800708) (xy 55.559707 -315.752924) (xy 55.578998 -315.707648) (xy 55.605301 -315.666052)
			(xy 55.637936 -315.629215) (xy 55.676057 -315.59809) (xy 55.718678 -315.573483) (xy 55.764694 -315.556031)
			(xy 55.812913 -315.546187) (xy 55.862088 -315.544206) (xy 55.910943 -315.550138) (xy 55.958214 -315.56383)
			(xy 56.002676 -315.584928) (xy 56.043179 -315.612884) (xy 56.078672 -315.646976) (xy 56.108237 -315.68632)
			(xy 56.131108 -315.729897) (xy 56.146692 -315.776578) (xy 56.154587 -315.825155) (xy 56.155082 -315.849762)
			(xy 56.154587 -315.874369) (xy 56.154408 -315.87547) (xy 56.47334 -315.87547) (xy 56.47334 -315.824054)
			(xy 56.481383 -315.773272) (xy 56.497271 -315.724373) (xy 56.520614 -315.678561) (xy 56.550835 -315.636965)
			(xy 56.587191 -315.600609) (xy 56.628787 -315.570388) (xy 56.674599 -315.547045) (xy 56.723498 -315.531157)
			(xy 56.77428 -315.523114) (xy 56.825696 -315.523114) (xy 56.876478 -315.531157) (xy 56.925377 -315.547045)
			(xy 56.971189 -315.570388) (xy 57.012785 -315.600609) (xy 57.049141 -315.636965) (xy 57.079362 -315.678561)
			(xy 57.102705 -315.724373) (xy 57.118593 -315.773272) (xy 57.126636 -315.824054) (xy 57.12714 -315.849762)
			(xy 57.444144 -315.849762) (xy 57.448104 -315.800708) (xy 57.459881 -315.752924) (xy 57.479172 -315.707648)
			(xy 57.505475 -315.666052) (xy 57.53811 -315.629215) (xy 57.576231 -315.59809) (xy 57.618852 -315.573483)
			(xy 57.664868 -315.556031) (xy 57.713087 -315.546187) (xy 57.762262 -315.544206) (xy 57.811117 -315.550138)
			(xy 57.858388 -315.56383) (xy 57.90285 -315.584928) (xy 57.943353 -315.612884) (xy 57.978846 -315.646976)
			(xy 58.008411 -315.68632) (xy 58.031282 -315.729897) (xy 58.046866 -315.776578) (xy 58.054761 -315.825155)
			(xy 58.055256 -315.849762) (xy 58.054761 -315.874369) (xy 58.054582 -315.87547) (xy 58.37326 -315.87547)
			(xy 58.37326 -315.824054) (xy 58.381303 -315.773272) (xy 58.397191 -315.724373) (xy 58.420534 -315.678561)
			(xy 58.450755 -315.636965) (xy 58.487111 -315.600609) (xy 58.528707 -315.570388) (xy 58.574519 -315.547045)
			(xy 58.623418 -315.531157) (xy 58.6742 -315.523114) (xy 58.725616 -315.523114) (xy 58.776398 -315.531157)
			(xy 58.825297 -315.547045) (xy 58.871109 -315.570388) (xy 58.912705 -315.600609) (xy 58.949061 -315.636965)
			(xy 58.979282 -315.678561) (xy 59.002625 -315.724373) (xy 59.018513 -315.773272) (xy 59.026556 -315.824054)
			(xy 59.02706 -315.849762) (xy 59.344064 -315.849762) (xy 59.348024 -315.800708) (xy 59.359801 -315.752924)
			(xy 59.379092 -315.707648) (xy 59.405395 -315.666052) (xy 59.43803 -315.629215) (xy 59.476151 -315.59809)
			(xy 59.518772 -315.573483) (xy 59.564788 -315.556031) (xy 59.613007 -315.546187) (xy 59.662182 -315.544206)
			(xy 59.711037 -315.550138) (xy 59.758308 -315.56383) (xy 59.80277 -315.584928) (xy 59.843273 -315.612884)
			(xy 59.878766 -315.646976) (xy 59.908331 -315.68632) (xy 59.931202 -315.729897) (xy 59.946786 -315.776578)
			(xy 59.954681 -315.825155) (xy 59.955176 -315.849762) (xy 59.954681 -315.874369) (xy 59.954502 -315.87547)
			(xy 60.27318 -315.87547) (xy 60.27318 -315.824054) (xy 60.281223 -315.773272) (xy 60.297111 -315.724373)
			(xy 60.320454 -315.678561) (xy 60.350675 -315.636965) (xy 60.387031 -315.600609) (xy 60.428627 -315.570388)
			(xy 60.474439 -315.547045) (xy 60.523338 -315.531157) (xy 60.57412 -315.523114) (xy 60.625536 -315.523114)
			(xy 60.676318 -315.531157) (xy 60.725217 -315.547045) (xy 60.771029 -315.570388) (xy 60.812625 -315.600609)
			(xy 60.848981 -315.636965) (xy 60.879202 -315.678561) (xy 60.902545 -315.724373) (xy 60.918433 -315.773272)
			(xy 60.926476 -315.824054) (xy 60.92698 -315.849762) (xy 61.243984 -315.849762) (xy 61.247944 -315.800708)
			(xy 61.259721 -315.752924) (xy 61.279012 -315.707648) (xy 61.305315 -315.666052) (xy 61.33795 -315.629215)
			(xy 61.376071 -315.59809) (xy 61.418692 -315.573483) (xy 61.464708 -315.556031) (xy 61.512927 -315.546187)
			(xy 61.562102 -315.544206) (xy 61.610957 -315.550138) (xy 61.658228 -315.56383) (xy 61.70269 -315.584928)
			(xy 61.743193 -315.612884) (xy 61.778686 -315.646976) (xy 61.808251 -315.68632) (xy 61.831122 -315.729897)
			(xy 61.846706 -315.776578) (xy 61.854601 -315.825155) (xy 61.855096 -315.849762) (xy 61.854601 -315.874369)
			(xy 61.854422 -315.87547) (xy 62.1731 -315.87547) (xy 62.1731 -315.824054) (xy 62.181143 -315.773272)
			(xy 62.197031 -315.724373) (xy 62.220374 -315.678561) (xy 62.250595 -315.636965) (xy 62.286951 -315.600609)
			(xy 62.328547 -315.570388) (xy 62.374359 -315.547045) (xy 62.423258 -315.531157) (xy 62.47404 -315.523114)
			(xy 62.525456 -315.523114) (xy 62.576238 -315.531157) (xy 62.625137 -315.547045) (xy 62.670949 -315.570388)
			(xy 62.712545 -315.600609) (xy 62.748901 -315.636965) (xy 62.779122 -315.678561) (xy 62.802465 -315.724373)
			(xy 62.818353 -315.773272) (xy 62.826396 -315.824054) (xy 62.8269 -315.849762) (xy 63.144158 -315.849762)
			(xy 63.148118 -315.800708) (xy 63.159895 -315.752924) (xy 63.179186 -315.707648) (xy 63.205489 -315.666052)
			(xy 63.238124 -315.629215) (xy 63.276245 -315.59809) (xy 63.318866 -315.573483) (xy 63.364882 -315.556031)
			(xy 63.413101 -315.546187) (xy 63.462276 -315.544206) (xy 63.511131 -315.550138) (xy 63.558402 -315.56383)
			(xy 63.602864 -315.584928) (xy 63.643367 -315.612884) (xy 63.67886 -315.646976) (xy 63.708425 -315.68632)
			(xy 63.731296 -315.729897) (xy 63.74688 -315.776578) (xy 63.754775 -315.825155) (xy 63.75527 -315.849762)
			(xy 63.754775 -315.874369) (xy 63.754596 -315.87547) (xy 64.073274 -315.87547) (xy 64.073274 -315.824054)
			(xy 64.081317 -315.773272) (xy 64.097205 -315.724373) (xy 64.120548 -315.678561) (xy 64.150769 -315.636965)
			(xy 64.187125 -315.600609) (xy 64.228721 -315.570388) (xy 64.274533 -315.547045) (xy 64.323432 -315.531157)
			(xy 64.374214 -315.523114) (xy 64.42563 -315.523114) (xy 64.476412 -315.531157) (xy 64.525311 -315.547045)
			(xy 64.571123 -315.570388) (xy 64.612719 -315.600609) (xy 64.649075 -315.636965) (xy 64.679296 -315.678561)
			(xy 64.702639 -315.724373) (xy 64.718527 -315.773272) (xy 64.72657 -315.824054) (xy 64.727074 -315.849762)
			(xy 65.044078 -315.849762) (xy 65.048038 -315.800708) (xy 65.059815 -315.752924) (xy 65.079106 -315.707648)
			(xy 65.105409 -315.666052) (xy 65.138044 -315.629215) (xy 65.176165 -315.59809) (xy 65.218786 -315.573483)
			(xy 65.264802 -315.556031) (xy 65.313021 -315.546187) (xy 65.362196 -315.544206) (xy 65.411051 -315.550138)
			(xy 65.458322 -315.56383) (xy 65.502784 -315.584928) (xy 65.543287 -315.612884) (xy 65.57878 -315.646976)
			(xy 65.608345 -315.68632) (xy 65.631216 -315.729897) (xy 65.6468 -315.776578) (xy 65.654695 -315.825155)
			(xy 65.65519 -315.849762) (xy 65.654695 -315.874369) (xy 65.654516 -315.87547) (xy 65.973194 -315.87547)
			(xy 65.973194 -315.824054) (xy 65.981237 -315.773272) (xy 65.997125 -315.724373) (xy 66.020468 -315.678561)
			(xy 66.050689 -315.636965) (xy 66.087045 -315.600609) (xy 66.128641 -315.570388) (xy 66.174453 -315.547045)
			(xy 66.223352 -315.531157) (xy 66.274134 -315.523114) (xy 66.32555 -315.523114) (xy 66.376332 -315.531157)
			(xy 66.425231 -315.547045) (xy 66.471043 -315.570388) (xy 66.512639 -315.600609) (xy 66.548995 -315.636965)
			(xy 66.579216 -315.678561) (xy 66.602559 -315.724373) (xy 66.618447 -315.773272) (xy 66.62649 -315.824054)
			(xy 66.626994 -315.849762) (xy 66.943998 -315.849762) (xy 66.947958 -315.800708) (xy 66.959735 -315.752924)
			(xy 66.979026 -315.707648) (xy 67.005329 -315.666052) (xy 67.037964 -315.629215) (xy 67.076085 -315.59809)
			(xy 67.118706 -315.573483) (xy 67.164722 -315.556031) (xy 67.212941 -315.546187) (xy 67.262116 -315.544206)
			(xy 67.310971 -315.550138) (xy 67.358242 -315.56383) (xy 67.402704 -315.584928) (xy 67.443207 -315.612884)
			(xy 67.4787 -315.646976) (xy 67.508265 -315.68632) (xy 67.531136 -315.729897) (xy 67.54672 -315.776578)
			(xy 67.554615 -315.825155) (xy 67.55511 -315.849762) (xy 67.554615 -315.874369) (xy 67.554436 -315.87547)
			(xy 67.873114 -315.87547) (xy 67.873114 -315.824054) (xy 67.881157 -315.773272) (xy 67.897045 -315.724373)
			(xy 67.920388 -315.678561) (xy 67.950609 -315.636965) (xy 67.986965 -315.600609) (xy 68.028561 -315.570388)
			(xy 68.074373 -315.547045) (xy 68.123272 -315.531157) (xy 68.174054 -315.523114) (xy 68.22547 -315.523114)
			(xy 68.276252 -315.531157) (xy 68.325151 -315.547045) (xy 68.370963 -315.570388) (xy 68.412559 -315.600609)
			(xy 68.448915 -315.636965) (xy 68.479136 -315.678561) (xy 68.502479 -315.724373) (xy 68.518367 -315.773272)
			(xy 68.52641 -315.824054) (xy 68.526914 -315.849762) (xy 68.844172 -315.849762) (xy 68.848132 -315.800708)
			(xy 68.859909 -315.752924) (xy 68.8792 -315.707648) (xy 68.905503 -315.666052) (xy 68.938138 -315.629215)
			(xy 68.976259 -315.59809) (xy 69.01888 -315.573483) (xy 69.064896 -315.556031) (xy 69.113115 -315.546187)
			(xy 69.16229 -315.544206) (xy 69.211145 -315.550138) (xy 69.258416 -315.56383) (xy 69.302878 -315.584928)
			(xy 69.343381 -315.612884) (xy 69.378874 -315.646976) (xy 69.408439 -315.68632) (xy 69.43131 -315.729897)
			(xy 69.446894 -315.776578) (xy 69.454789 -315.825155) (xy 69.455284 -315.849762) (xy 69.454789 -315.874369)
			(xy 69.45461 -315.87547) (xy 69.773288 -315.87547) (xy 69.773288 -315.824054) (xy 69.781331 -315.773272)
			(xy 69.797219 -315.724373) (xy 69.820562 -315.678561) (xy 69.850783 -315.636965) (xy 69.887139 -315.600609)
			(xy 69.928735 -315.570388) (xy 69.974547 -315.547045) (xy 70.023446 -315.531157) (xy 70.074228 -315.523114)
			(xy 70.125644 -315.523114) (xy 70.176426 -315.531157) (xy 70.225325 -315.547045) (xy 70.271137 -315.570388)
			(xy 70.312733 -315.600609) (xy 70.349089 -315.636965) (xy 70.37931 -315.678561) (xy 70.402653 -315.724373)
			(xy 70.418541 -315.773272) (xy 70.426584 -315.824054) (xy 70.427088 -315.849762) (xy 70.744092 -315.849762)
			(xy 70.748052 -315.800708) (xy 70.759829 -315.752924) (xy 70.77912 -315.707648) (xy 70.805423 -315.666052)
			(xy 70.838058 -315.629215) (xy 70.876179 -315.59809) (xy 70.9188 -315.573483) (xy 70.964816 -315.556031)
			(xy 71.013035 -315.546187) (xy 71.06221 -315.544206) (xy 71.111065 -315.550138) (xy 71.158336 -315.56383)
			(xy 71.202798 -315.584928) (xy 71.243301 -315.612884) (xy 71.278794 -315.646976) (xy 71.308359 -315.68632)
			(xy 71.33123 -315.729897) (xy 71.346814 -315.776578) (xy 71.354709 -315.825155) (xy 71.355204 -315.849762)
			(xy 71.354709 -315.874369) (xy 71.346814 -315.922946) (xy 71.33123 -315.969627) (xy 71.308359 -316.013204)
			(xy 71.278794 -316.052548) (xy 71.243301 -316.08664) (xy 71.202798 -316.114596) (xy 71.158336 -316.135694)
			(xy 71.111065 -316.149386) (xy 71.06221 -316.155318) (xy 71.013035 -316.153337) (xy 70.964816 -316.143493)
			(xy 70.9188 -316.126041) (xy 70.876179 -316.101434) (xy 70.838058 -316.070309) (xy 70.805423 -316.033472)
			(xy 70.77912 -315.991876) (xy 70.759829 -315.9466) (xy 70.748052 -315.898816) (xy 70.744092 -315.849762)
			(xy 70.427088 -315.849762) (xy 70.426584 -315.87547) (xy 70.418541 -315.926252) (xy 70.402653 -315.975151)
			(xy 70.37931 -316.020963) (xy 70.349089 -316.062559) (xy 70.312733 -316.098915) (xy 70.271137 -316.129136)
			(xy 70.225325 -316.152479) (xy 70.176426 -316.168367) (xy 70.125644 -316.17641) (xy 70.074228 -316.17641)
			(xy 70.023446 -316.168367) (xy 69.974547 -316.152479) (xy 69.928735 -316.129136) (xy 69.887139 -316.098915)
			(xy 69.850783 -316.062559) (xy 69.820562 -316.020963) (xy 69.797219 -315.975151) (xy 69.781331 -315.926252)
			(xy 69.773288 -315.87547) (xy 69.45461 -315.87547) (xy 69.446894 -315.922946) (xy 69.43131 -315.969627)
			(xy 69.408439 -316.013204) (xy 69.378874 -316.052548) (xy 69.343381 -316.08664) (xy 69.302878 -316.114596)
			(xy 69.258416 -316.135694) (xy 69.211145 -316.149386) (xy 69.16229 -316.155318) (xy 69.113115 -316.153337)
			(xy 69.064896 -316.143493) (xy 69.01888 -316.126041) (xy 68.976259 -316.101434) (xy 68.938138 -316.070309)
			(xy 68.905503 -316.033472) (xy 68.8792 -315.991876) (xy 68.859909 -315.9466) (xy 68.848132 -315.898816)
			(xy 68.844172 -315.849762) (xy 68.526914 -315.849762) (xy 68.52641 -315.87547) (xy 68.518367 -315.926252)
			(xy 68.502479 -315.975151) (xy 68.479136 -316.020963) (xy 68.448915 -316.062559) (xy 68.412559 -316.098915)
			(xy 68.370963 -316.129136) (xy 68.325151 -316.152479) (xy 68.276252 -316.168367) (xy 68.22547 -316.17641)
			(xy 68.174054 -316.17641) (xy 68.123272 -316.168367) (xy 68.074373 -316.152479) (xy 68.028561 -316.129136)
			(xy 67.986965 -316.098915) (xy 67.950609 -316.062559) (xy 67.920388 -316.020963) (xy 67.897045 -315.975151)
			(xy 67.881157 -315.926252) (xy 67.873114 -315.87547) (xy 67.554436 -315.87547) (xy 67.54672 -315.922946)
			(xy 67.531136 -315.969627) (xy 67.508265 -316.013204) (xy 67.4787 -316.052548) (xy 67.443207 -316.08664)
			(xy 67.402704 -316.114596) (xy 67.358242 -316.135694) (xy 67.310971 -316.149386) (xy 67.262116 -316.155318)
			(xy 67.212941 -316.153337) (xy 67.164722 -316.143493) (xy 67.118706 -316.126041) (xy 67.076085 -316.101434)
			(xy 67.037964 -316.070309) (xy 67.005329 -316.033472) (xy 66.979026 -315.991876) (xy 66.959735 -315.9466)
			(xy 66.947958 -315.898816) (xy 66.943998 -315.849762) (xy 66.626994 -315.849762) (xy 66.62649 -315.87547)
			(xy 66.618447 -315.926252) (xy 66.602559 -315.975151) (xy 66.579216 -316.020963) (xy 66.548995 -316.062559)
			(xy 66.512639 -316.098915) (xy 66.471043 -316.129136) (xy 66.425231 -316.152479) (xy 66.376332 -316.168367)
			(xy 66.32555 -316.17641) (xy 66.274134 -316.17641) (xy 66.223352 -316.168367) (xy 66.174453 -316.152479)
			(xy 66.128641 -316.129136) (xy 66.087045 -316.098915) (xy 66.050689 -316.062559) (xy 66.020468 -316.020963)
			(xy 65.997125 -315.975151) (xy 65.981237 -315.926252) (xy 65.973194 -315.87547) (xy 65.654516 -315.87547)
			(xy 65.6468 -315.922946) (xy 65.631216 -315.969627) (xy 65.608345 -316.013204) (xy 65.57878 -316.052548)
			(xy 65.543287 -316.08664) (xy 65.502784 -316.114596) (xy 65.458322 -316.135694) (xy 65.411051 -316.149386)
			(xy 65.362196 -316.155318) (xy 65.313021 -316.153337) (xy 65.264802 -316.143493) (xy 65.218786 -316.126041)
			(xy 65.176165 -316.101434) (xy 65.138044 -316.070309) (xy 65.105409 -316.033472) (xy 65.079106 -315.991876)
			(xy 65.059815 -315.9466) (xy 65.048038 -315.898816) (xy 65.044078 -315.849762) (xy 64.727074 -315.849762)
			(xy 64.72657 -315.87547) (xy 64.718527 -315.926252) (xy 64.702639 -315.975151) (xy 64.679296 -316.020963)
			(xy 64.649075 -316.062559) (xy 64.612719 -316.098915) (xy 64.571123 -316.129136) (xy 64.525311 -316.152479)
			(xy 64.476412 -316.168367) (xy 64.42563 -316.17641) (xy 64.374214 -316.17641) (xy 64.323432 -316.168367)
			(xy 64.274533 -316.152479) (xy 64.228721 -316.129136) (xy 64.187125 -316.098915) (xy 64.150769 -316.062559)
			(xy 64.120548 -316.020963) (xy 64.097205 -315.975151) (xy 64.081317 -315.926252) (xy 64.073274 -315.87547)
			(xy 63.754596 -315.87547) (xy 63.74688 -315.922946) (xy 63.731296 -315.969627) (xy 63.708425 -316.013204)
			(xy 63.67886 -316.052548) (xy 63.643367 -316.08664) (xy 63.602864 -316.114596) (xy 63.558402 -316.135694)
			(xy 63.511131 -316.149386) (xy 63.462276 -316.155318) (xy 63.413101 -316.153337) (xy 63.364882 -316.143493)
			(xy 63.318866 -316.126041) (xy 63.276245 -316.101434) (xy 63.238124 -316.070309) (xy 63.205489 -316.033472)
			(xy 63.179186 -315.991876) (xy 63.159895 -315.9466) (xy 63.148118 -315.898816) (xy 63.144158 -315.849762)
			(xy 62.8269 -315.849762) (xy 62.826396 -315.87547) (xy 62.818353 -315.926252) (xy 62.802465 -315.975151)
			(xy 62.779122 -316.020963) (xy 62.748901 -316.062559) (xy 62.712545 -316.098915) (xy 62.670949 -316.129136)
			(xy 62.625137 -316.152479) (xy 62.576238 -316.168367) (xy 62.525456 -316.17641) (xy 62.47404 -316.17641)
			(xy 62.423258 -316.168367) (xy 62.374359 -316.152479) (xy 62.328547 -316.129136) (xy 62.286951 -316.098915)
			(xy 62.250595 -316.062559) (xy 62.220374 -316.020963) (xy 62.197031 -315.975151) (xy 62.181143 -315.926252)
			(xy 62.1731 -315.87547) (xy 61.854422 -315.87547) (xy 61.846706 -315.922946) (xy 61.831122 -315.969627)
			(xy 61.808251 -316.013204) (xy 61.778686 -316.052548) (xy 61.743193 -316.08664) (xy 61.70269 -316.114596)
			(xy 61.658228 -316.135694) (xy 61.610957 -316.149386) (xy 61.562102 -316.155318) (xy 61.512927 -316.153337)
			(xy 61.464708 -316.143493) (xy 61.418692 -316.126041) (xy 61.376071 -316.101434) (xy 61.33795 -316.070309)
			(xy 61.305315 -316.033472) (xy 61.279012 -315.991876) (xy 61.259721 -315.9466) (xy 61.247944 -315.898816)
			(xy 61.243984 -315.849762) (xy 60.92698 -315.849762) (xy 60.926476 -315.87547) (xy 60.918433 -315.926252)
			(xy 60.902545 -315.975151) (xy 60.879202 -316.020963) (xy 60.848981 -316.062559) (xy 60.812625 -316.098915)
			(xy 60.771029 -316.129136) (xy 60.725217 -316.152479) (xy 60.676318 -316.168367) (xy 60.625536 -316.17641)
			(xy 60.57412 -316.17641) (xy 60.523338 -316.168367) (xy 60.474439 -316.152479) (xy 60.428627 -316.129136)
			(xy 60.387031 -316.098915) (xy 60.350675 -316.062559) (xy 60.320454 -316.020963) (xy 60.297111 -315.975151)
			(xy 60.281223 -315.926252) (xy 60.27318 -315.87547) (xy 59.954502 -315.87547) (xy 59.946786 -315.922946)
			(xy 59.931202 -315.969627) (xy 59.908331 -316.013204) (xy 59.878766 -316.052548) (xy 59.843273 -316.08664)
			(xy 59.80277 -316.114596) (xy 59.758308 -316.135694) (xy 59.711037 -316.149386) (xy 59.662182 -316.155318)
			(xy 59.613007 -316.153337) (xy 59.564788 -316.143493) (xy 59.518772 -316.126041) (xy 59.476151 -316.101434)
			(xy 59.43803 -316.070309) (xy 59.405395 -316.033472) (xy 59.379092 -315.991876) (xy 59.359801 -315.9466)
			(xy 59.348024 -315.898816) (xy 59.344064 -315.849762) (xy 59.02706 -315.849762) (xy 59.026556 -315.87547)
			(xy 59.018513 -315.926252) (xy 59.002625 -315.975151) (xy 58.979282 -316.020963) (xy 58.949061 -316.062559)
			(xy 58.912705 -316.098915) (xy 58.871109 -316.129136) (xy 58.825297 -316.152479) (xy 58.776398 -316.168367)
			(xy 58.725616 -316.17641) (xy 58.6742 -316.17641) (xy 58.623418 -316.168367) (xy 58.574519 -316.152479)
			(xy 58.528707 -316.129136) (xy 58.487111 -316.098915) (xy 58.450755 -316.062559) (xy 58.420534 -316.020963)
			(xy 58.397191 -315.975151) (xy 58.381303 -315.926252) (xy 58.37326 -315.87547) (xy 58.054582 -315.87547)
			(xy 58.046866 -315.922946) (xy 58.031282 -315.969627) (xy 58.008411 -316.013204) (xy 57.978846 -316.052548)
			(xy 57.943353 -316.08664) (xy 57.90285 -316.114596) (xy 57.858388 -316.135694) (xy 57.811117 -316.149386)
			(xy 57.762262 -316.155318) (xy 57.713087 -316.153337) (xy 57.664868 -316.143493) (xy 57.618852 -316.126041)
			(xy 57.576231 -316.101434) (xy 57.53811 -316.070309) (xy 57.505475 -316.033472) (xy 57.479172 -315.991876)
			(xy 57.459881 -315.9466) (xy 57.448104 -315.898816) (xy 57.444144 -315.849762) (xy 57.12714 -315.849762)
			(xy 57.126636 -315.87547) (xy 57.118593 -315.926252) (xy 57.102705 -315.975151) (xy 57.079362 -316.020963)
			(xy 57.049141 -316.062559) (xy 57.012785 -316.098915) (xy 56.971189 -316.129136) (xy 56.925377 -316.152479)
			(xy 56.876478 -316.168367) (xy 56.825696 -316.17641) (xy 56.77428 -316.17641) (xy 56.723498 -316.168367)
			(xy 56.674599 -316.152479) (xy 56.628787 -316.129136) (xy 56.587191 -316.098915) (xy 56.550835 -316.062559)
			(xy 56.520614 -316.020963) (xy 56.497271 -315.975151) (xy 56.481383 -315.926252) (xy 56.47334 -315.87547)
			(xy 56.154408 -315.87547) (xy 56.146692 -315.922946) (xy 56.131108 -315.969627) (xy 56.108237 -316.013204)
			(xy 56.078672 -316.052548) (xy 56.043179 -316.08664) (xy 56.002676 -316.114596) (xy 55.958214 -316.135694)
			(xy 55.910943 -316.149386) (xy 55.862088 -316.155318) (xy 55.812913 -316.153337) (xy 55.764694 -316.143493)
			(xy 55.718678 -316.126041) (xy 55.676057 -316.101434) (xy 55.637936 -316.070309) (xy 55.605301 -316.033472)
			(xy 55.578998 -315.991876) (xy 55.559707 -315.9466) (xy 55.54793 -315.898816) (xy 55.54397 -315.849762)
			(xy 55.226966 -315.849762) (xy 55.226462 -315.87547) (xy 55.218419 -315.926252) (xy 55.202531 -315.975151)
			(xy 55.179188 -316.020963) (xy 55.148967 -316.062559) (xy 55.112611 -316.098915) (xy 55.071015 -316.129136)
			(xy 55.025203 -316.152479) (xy 54.976304 -316.168367) (xy 54.925522 -316.17641) (xy 54.874106 -316.17641)
			(xy 54.823324 -316.168367) (xy 54.774425 -316.152479) (xy 54.728613 -316.129136) (xy 54.687017 -316.098915)
			(xy 54.650661 -316.062559) (xy 54.62044 -316.020963) (xy 54.597097 -315.975151) (xy 54.581209 -315.926252)
			(xy 54.573166 -315.87547) (xy 54.254488 -315.87547) (xy 54.246772 -315.922946) (xy 54.231188 -315.969627)
			(xy 54.208317 -316.013204) (xy 54.178752 -316.052548) (xy 54.143259 -316.08664) (xy 54.102756 -316.114596)
			(xy 54.058294 -316.135694) (xy 54.011023 -316.149386) (xy 53.962168 -316.155318) (xy 53.912993 -316.153337)
			(xy 53.864774 -316.143493) (xy 53.818758 -316.126041) (xy 53.776137 -316.101434) (xy 53.738016 -316.070309)
			(xy 53.705381 -316.033472) (xy 53.679078 -315.991876) (xy 53.659787 -315.9466) (xy 53.64801 -315.898816)
			(xy 53.64405 -315.849762) (xy 53.327046 -315.849762) (xy 53.326542 -315.87547) (xy 53.318499 -315.926252)
			(xy 53.302611 -315.975151) (xy 53.279268 -316.020963) (xy 53.249047 -316.062559) (xy 53.212691 -316.098915)
			(xy 53.171095 -316.129136) (xy 53.125283 -316.152479) (xy 53.076384 -316.168367) (xy 53.025602 -316.17641)
			(xy 52.974186 -316.17641) (xy 52.923404 -316.168367) (xy 52.874505 -316.152479) (xy 52.828693 -316.129136)
			(xy 52.787097 -316.098915) (xy 52.750741 -316.062559) (xy 52.72052 -316.020963) (xy 52.697177 -315.975151)
			(xy 52.681289 -315.926252) (xy 52.673246 -315.87547) (xy 52.354568 -315.87547) (xy 52.346852 -315.922946)
			(xy 52.331268 -315.969627) (xy 52.308397 -316.013204) (xy 52.278832 -316.052548) (xy 52.243339 -316.08664)
			(xy 52.202836 -316.114596) (xy 52.158374 -316.135694) (xy 52.111103 -316.149386) (xy 52.062248 -316.155318)
			(xy 52.013073 -316.153337) (xy 51.964854 -316.143493) (xy 51.918838 -316.126041) (xy 51.876217 -316.101434)
			(xy 51.838096 -316.070309) (xy 51.805461 -316.033472) (xy 51.779158 -315.991876) (xy 51.759867 -315.9466)
			(xy 51.74809 -315.898816) (xy 51.74413 -315.849762) (xy 51.427126 -315.849762) (xy 51.426622 -315.87547)
			(xy 51.418579 -315.926252) (xy 51.402691 -315.975151) (xy 51.379348 -316.020963) (xy 51.349127 -316.062559)
			(xy 51.312771 -316.098915) (xy 51.271175 -316.129136) (xy 51.225363 -316.152479) (xy 51.176464 -316.168367)
			(xy 51.125682 -316.17641) (xy 51.074266 -316.17641) (xy 51.023484 -316.168367) (xy 50.974585 -316.152479)
			(xy 50.928773 -316.129136) (xy 50.887177 -316.098915) (xy 50.850821 -316.062559) (xy 50.8206 -316.020963)
			(xy 50.797257 -315.975151) (xy 50.781369 -315.926252) (xy 50.773326 -315.87547) (xy 50.454394 -315.87547)
			(xy 50.446678 -315.922946) (xy 50.431094 -315.969627) (xy 50.408223 -316.013204) (xy 50.378658 -316.052548)
			(xy 50.343165 -316.08664) (xy 50.302662 -316.114596) (xy 50.2582 -316.135694) (xy 50.210929 -316.149386)
			(xy 50.162074 -316.155318) (xy 50.112899 -316.153337) (xy 50.06468 -316.143493) (xy 50.018664 -316.126041)
			(xy 49.976043 -316.101434) (xy 49.937922 -316.070309) (xy 49.905287 -316.033472) (xy 49.878984 -315.991876)
			(xy 49.859693 -315.9466) (xy 49.847916 -315.898816) (xy 49.843956 -315.849762) (xy 49.526952 -315.849762)
			(xy 49.526448 -315.87547) (xy 49.518405 -315.926252) (xy 49.502517 -315.975151) (xy 49.479174 -316.020963)
			(xy 49.448953 -316.062559) (xy 49.412597 -316.098915) (xy 49.371001 -316.129136) (xy 49.325189 -316.152479)
			(xy 49.27629 -316.168367) (xy 49.225508 -316.17641) (xy 49.174092 -316.17641) (xy 49.12331 -316.168367)
			(xy 49.074411 -316.152479) (xy 49.028599 -316.129136) (xy 48.987003 -316.098915) (xy 48.950647 -316.062559)
			(xy 48.920426 -316.020963) (xy 48.897083 -315.975151) (xy 48.881195 -315.926252) (xy 48.873152 -315.87547)
			(xy 48.554474 -315.87547) (xy 48.546758 -315.922946) (xy 48.531174 -315.969627) (xy 48.508303 -316.013204)
			(xy 48.478738 -316.052548) (xy 48.443245 -316.08664) (xy 48.402742 -316.114596) (xy 48.35828 -316.135694)
			(xy 48.311009 -316.149386) (xy 48.262154 -316.155318) (xy 48.212979 -316.153337) (xy 48.16476 -316.143493)
			(xy 48.118744 -316.126041) (xy 48.076123 -316.101434) (xy 48.038002 -316.070309) (xy 48.005367 -316.033472)
			(xy 47.979064 -315.991876) (xy 47.959773 -315.9466) (xy 47.947996 -315.898816) (xy 47.944036 -315.849762)
			(xy 47.627032 -315.849762) (xy 47.626528 -315.87547) (xy 47.618485 -315.926252) (xy 47.602597 -315.975151)
			(xy 47.579254 -316.020963) (xy 47.549033 -316.062559) (xy 47.512677 -316.098915) (xy 47.471081 -316.129136)
			(xy 47.425269 -316.152479) (xy 47.37637 -316.168367) (xy 47.325588 -316.17641) (xy 47.274172 -316.17641)
			(xy 47.22339 -316.168367) (xy 47.174491 -316.152479) (xy 47.128679 -316.129136) (xy 47.087083 -316.098915)
			(xy 47.050727 -316.062559) (xy 47.020506 -316.020963) (xy 46.997163 -315.975151) (xy 46.981275 -315.926252)
			(xy 46.973232 -315.87547) (xy 46.654554 -315.87547) (xy 46.646838 -315.922946) (xy 46.631254 -315.969627)
			(xy 46.608383 -316.013204) (xy 46.578818 -316.052548) (xy 46.543325 -316.08664) (xy 46.502822 -316.114596)
			(xy 46.45836 -316.135694) (xy 46.411089 -316.149386) (xy 46.362234 -316.155318) (xy 46.313059 -316.153337)
			(xy 46.26484 -316.143493) (xy 46.218824 -316.126041) (xy 46.176203 -316.101434) (xy 46.138082 -316.070309)
			(xy 46.105447 -316.033472) (xy 46.079144 -315.991876) (xy 46.059853 -315.9466) (xy 46.048076 -315.898816)
			(xy 46.044116 -315.849762) (xy 45.727112 -315.849762) (xy 45.726608 -315.87547) (xy 45.718565 -315.926252)
			(xy 45.702677 -315.975151) (xy 45.679334 -316.020963) (xy 45.649113 -316.062559) (xy 45.612757 -316.098915)
			(xy 45.571161 -316.129136) (xy 45.525349 -316.152479) (xy 45.47645 -316.168367) (xy 45.425668 -316.17641)
			(xy 45.374252 -316.17641) (xy 45.32347 -316.168367) (xy 45.274571 -316.152479) (xy 45.228759 -316.129136)
			(xy 45.187163 -316.098915) (xy 45.150807 -316.062559) (xy 45.120586 -316.020963) (xy 45.097243 -315.975151)
			(xy 45.081355 -315.926252) (xy 45.073312 -315.87547) (xy 44.75438 -315.87547) (xy 44.746664 -315.922946)
			(xy 44.73108 -315.969627) (xy 44.708209 -316.013204) (xy 44.678644 -316.052548) (xy 44.643151 -316.08664)
			(xy 44.602648 -316.114596) (xy 44.558186 -316.135694) (xy 44.510915 -316.149386) (xy 44.46206 -316.155318)
			(xy 44.412885 -316.153337) (xy 44.364666 -316.143493) (xy 44.31865 -316.126041) (xy 44.276029 -316.101434)
			(xy 44.237908 -316.070309) (xy 44.205273 -316.033472) (xy 44.17897 -315.991876) (xy 44.159679 -315.9466)
			(xy 44.147902 -315.898816) (xy 44.143942 -315.849762) (xy 43.826938 -315.849762) (xy 43.826434 -315.87547)
			(xy 43.818391 -315.926252) (xy 43.802503 -315.975151) (xy 43.77916 -316.020963) (xy 43.748939 -316.062559)
			(xy 43.712583 -316.098915) (xy 43.670987 -316.129136) (xy 43.625175 -316.152479) (xy 43.576276 -316.168367)
			(xy 43.525494 -316.17641) (xy 43.474078 -316.17641) (xy 43.423296 -316.168367) (xy 43.374397 -316.152479)
			(xy 43.328585 -316.129136) (xy 43.286989 -316.098915) (xy 43.250633 -316.062559) (xy 43.220412 -316.020963)
			(xy 43.197069 -315.975151) (xy 43.181181 -315.926252) (xy 43.173138 -315.87547) (xy 42.85446 -315.87547)
			(xy 42.846744 -315.922946) (xy 42.83116 -315.969627) (xy 42.808289 -316.013204) (xy 42.778724 -316.052548)
			(xy 42.743231 -316.08664) (xy 42.702728 -316.114596) (xy 42.658266 -316.135694) (xy 42.610995 -316.149386)
			(xy 42.56214 -316.155318) (xy 42.512965 -316.153337) (xy 42.464746 -316.143493) (xy 42.41873 -316.126041)
			(xy 42.376109 -316.101434) (xy 42.337988 -316.070309) (xy 42.305353 -316.033472) (xy 42.27905 -315.991876)
			(xy 42.259759 -315.9466) (xy 42.247982 -315.898816) (xy 42.244022 -315.849762) (xy 41.927018 -315.849762)
			(xy 41.926514 -315.87547) (xy 41.918471 -315.926252) (xy 41.902583 -315.975151) (xy 41.87924 -316.020963)
			(xy 41.849019 -316.062559) (xy 41.812663 -316.098915) (xy 41.771067 -316.129136) (xy 41.725255 -316.152479)
			(xy 41.676356 -316.168367) (xy 41.625574 -316.17641) (xy 41.574158 -316.17641) (xy 41.523376 -316.168367)
			(xy 41.474477 -316.152479) (xy 41.428665 -316.129136) (xy 41.387069 -316.098915) (xy 41.350713 -316.062559)
			(xy 41.320492 -316.020963) (xy 41.297149 -315.975151) (xy 41.281261 -315.926252) (xy 41.273218 -315.87547)
			(xy 40.95454 -315.87547) (xy 40.946824 -315.922946) (xy 40.93124 -315.969627) (xy 40.908369 -316.013204)
			(xy 40.878804 -316.052548) (xy 40.843311 -316.08664) (xy 40.802808 -316.114596) (xy 40.758346 -316.135694)
			(xy 40.711075 -316.149386) (xy 40.66222 -316.155318) (xy 40.613045 -316.153337) (xy 40.564826 -316.143493)
			(xy 40.51881 -316.126041) (xy 40.476189 -316.101434) (xy 40.438068 -316.070309) (xy 40.405433 -316.033472)
			(xy 40.37913 -315.991876) (xy 40.359839 -315.9466) (xy 40.348062 -315.898816) (xy 40.344102 -315.849762)
			(xy 40.027098 -315.849762) (xy 40.026594 -315.87547) (xy 40.018551 -315.926252) (xy 40.002663 -315.975151)
			(xy 39.97932 -316.020963) (xy 39.949099 -316.062559) (xy 39.912743 -316.098915) (xy 39.871147 -316.129136)
			(xy 39.825335 -316.152479) (xy 39.776436 -316.168367) (xy 39.725654 -316.17641) (xy 39.674238 -316.17641)
			(xy 39.623456 -316.168367) (xy 39.574557 -316.152479) (xy 39.528745 -316.129136) (xy 39.487149 -316.098915)
			(xy 39.450793 -316.062559) (xy 39.420572 -316.020963) (xy 39.397229 -315.975151) (xy 39.381341 -315.926252)
			(xy 39.373298 -315.87547) (xy 39.05462 -315.87547) (xy 39.046904 -315.922946) (xy 39.03132 -315.969627)
			(xy 39.008449 -316.013204) (xy 38.978884 -316.052548) (xy 38.943391 -316.08664) (xy 38.902888 -316.114596)
			(xy 38.858426 -316.135694) (xy 38.811155 -316.149386) (xy 38.7623 -316.155318) (xy 38.713125 -316.153337)
			(xy 38.664906 -316.143493) (xy 38.61889 -316.126041) (xy 38.576269 -316.101434) (xy 38.538148 -316.070309)
			(xy 38.505513 -316.033472) (xy 38.47921 -315.991876) (xy 38.459919 -315.9466) (xy 38.448142 -315.898816)
			(xy 38.444182 -315.849762) (xy 38.10508 -315.849762) (xy 38.104585 -315.874369) (xy 38.09669 -315.922946)
			(xy 38.081106 -315.969627) (xy 38.058235 -316.013204) (xy 38.02867 -316.052548) (xy 37.993177 -316.08664)
			(xy 37.952674 -316.114596) (xy 37.908212 -316.135694) (xy 37.860941 -316.149386) (xy 37.812086 -316.155318)
			(xy 37.762911 -316.153337) (xy 37.714692 -316.143493) (xy 37.668676 -316.126041) (xy 37.626055 -316.101434)
			(xy 37.587934 -316.070309) (xy 37.555299 -316.033472) (xy 37.528996 -315.991876) (xy 37.509705 -315.9466)
			(xy 37.497928 -315.898816) (xy 37.493968 -315.849762) (xy 37.15512 -315.849762) (xy 37.154625 -315.874369)
			(xy 37.14673 -315.922946) (xy 37.131146 -315.969627) (xy 37.108275 -316.013204) (xy 37.07871 -316.052548)
			(xy 37.043217 -316.08664) (xy 37.002714 -316.114596) (xy 36.958252 -316.135694) (xy 36.910981 -316.149386)
			(xy 36.862126 -316.155318) (xy 36.812951 -316.153337) (xy 36.764732 -316.143493) (xy 36.718716 -316.126041)
			(xy 36.676095 -316.101434) (xy 36.637974 -316.070309) (xy 36.605339 -316.033472) (xy 36.579036 -315.991876)
			(xy 36.559745 -315.9466) (xy 36.547968 -315.898816) (xy 36.544008 -315.849762) (xy 17.635982 -315.849762)
			(xy 17.635982 -323.0245) (xy 17.636744 -323.032628) (xy 17.636744 -323.033136) (xy 17.638343 -323.040656)
			(xy 17.645315 -323.054348) (xy 17.65046 -323.06006) (xy 18.06702 -323.47662) (xy 18.0727 -323.481812)
			(xy 18.086406 -323.488787) (xy 18.093944 -323.490336) (xy 18.094452 -323.490336) (xy 18.10258 -323.491098)
		)
		(stroke
			(width 0)
			(type solid)
		)
		(fill yes)
		(layer "In11.Cu")
		(net "P1V25_SERDES_VDDPLL_PEX0")
	)
	(gr_poly
		(pts
			(xy 61.590428 -281.286712) (xy 61.600304 -281.28625) (xy 61.618601 -281.278806) (xy 61.625988 -281.272234)
			(xy 61.62675 -281.271472) (xy 61.681868 -281.214322) (xy 61.687427 -281.207292) (xy 61.693678 -281.190509)
			(xy 61.69406 -281.181556) (xy 61.69406 -280.224992) (xy 61.69457 -280.199004) (xy 61.702701 -280.147669)
			(xy 61.718763 -280.098237) (xy 61.742359 -280.051927) (xy 61.772908 -280.009877) (xy 61.809659 -279.973123)
			(xy 61.851706 -279.942571) (xy 61.898015 -279.918972) (xy 61.947446 -279.902907) (xy 61.99878 -279.894772)
			(xy 62.024768 -279.894284) (xy 62.025276 -279.894284) (xy 62.04009 -279.894461) (xy 62.069599 -279.897131)
			(xy 62.084204 -279.899618) (xy 62.084712 -279.899618) (xy 62.091316 -279.900634) (xy 62.102238 -279.897332)
			(xy 62.107787 -279.895439) (xy 62.117916 -279.889538) (xy 62.122304 -279.885648) (xy 62.148466 -279.860756)
			(xy 62.162182 -279.847548) (xy 62.170589 -279.838428) (xy 62.178411 -279.814932) (xy 62.177168 -279.80259)
			(xy 62.175077 -279.789481) (xy 62.172785 -279.763031) (xy 62.172596 -279.749758) (xy 62.172596 -279.74925)
			(xy 62.173119 -279.723557) (xy 62.181194 -279.672807) (xy 62.197105 -279.623945) (xy 62.220461 -279.578171)
			(xy 62.250687 -279.536613) (xy 62.28704 -279.500293) (xy 62.328626 -279.470105) (xy 62.37442 -279.44679)
			(xy 62.423297 -279.430924) (xy 62.474054 -279.422896) (xy 62.499748 -279.422352) (xy 62.525453 -279.42286)
			(xy 62.576229 -279.430909) (xy 62.625121 -279.446801) (xy 62.670925 -279.470145) (xy 62.712514 -279.500367)
			(xy 62.748864 -279.536722) (xy 62.77908 -279.578316) (xy 62.802417 -279.624123) (xy 62.818303 -279.673018)
			(xy 62.826344 -279.723795) (xy 62.826344 -279.775205) (xy 62.818303 -279.825982) (xy 62.802417 -279.874877)
			(xy 62.77908 -279.920684) (xy 62.748864 -279.962278) (xy 62.712514 -279.998633) (xy 62.670925 -280.028855)
			(xy 62.625121 -280.052199) (xy 62.576229 -280.068091) (xy 62.525453 -280.07614) (xy 62.499748 -280.076656)
			(xy 62.48648 -280.076509) (xy 62.460032 -280.074349) (xy 62.446916 -280.072338) (xy 62.43447 -280.070306)
			(xy 62.410594 -280.07818) (xy 62.356492 -280.135076) (xy 62.355984 -280.135584) (xy 62.348872 -280.157936)
			(xy 62.35065 -280.16835) (xy 62.3529 -280.18221) (xy 62.355312 -280.210189) (xy 62.355476 -280.22423)
			(xy 62.355476 -280.295096) (xy 62.35573 -280.30043) (xy 62.356921 -280.30861) (xy 62.363797 -280.32363)
			(xy 62.369192 -280.329894) (xy 62.37224 -280.332942) (xy 62.415674 -280.372058) (xy 62.437518 -280.378408)
			(xy 62.448948 -280.37663) (xy 62.461568 -280.374809) (xy 62.486997 -280.372902) (xy 62.499748 -280.37282)
			(xy 62.525432 -280.373327) (xy 62.576166 -280.38137) (xy 62.625018 -280.397249) (xy 62.670785 -280.420574)
			(xy 62.71234 -280.450771) (xy 62.74866 -280.487097) (xy 62.778851 -280.528656) (xy 62.802169 -280.574426)
			(xy 62.818041 -280.62328) (xy 62.826076 -280.674016) (xy 62.826076 -280.725384) (xy 62.818041 -280.77612)
			(xy 62.802169 -280.824974) (xy 62.778851 -280.870744) (xy 62.74866 -280.912303) (xy 62.71234 -280.948629)
			(xy 62.670785 -280.978826) (xy 62.625018 -281.002151) (xy 62.576166 -281.01803) (xy 62.525432 -281.026073)
			(xy 62.499748 -281.026616) (xy 62.486997 -281.026534) (xy 62.461568 -281.024631) (xy 62.448948 -281.022806)
			(xy 62.437518 -281.021028) (xy 62.415674 -281.027378) (xy 62.37224 -281.066494) (xy 62.369192 -281.069542)
			(xy 62.363772 -281.075787) (xy 62.356907 -281.09082) (xy 62.35573 -281.099006) (xy 62.355476 -281.10434)
			(xy 62.355476 -281.18181) (xy 62.355623 -281.187679) (xy 62.358311 -281.199104) (xy 62.36081 -281.204416)
			(xy 62.365128 -281.213052) (xy 62.421516 -281.270456) (xy 62.423294 -281.27198) (xy 62.430483 -281.277856)
			(xy 62.447801 -281.284515) (xy 62.457076 -281.284934) (xy 63.451486 -281.284934) (xy 63.460884 -281.285696)
			(xy 63.465456 -281.286712) (xy 63.490348 -281.286712) (xy 63.500223 -281.286247) (xy 63.518515 -281.278797)
			(xy 63.525908 -281.272234) (xy 63.52667 -281.271472) (xy 63.581788 -281.214322) (xy 63.587345 -281.207292)
			(xy 63.593594 -281.190509) (xy 63.59398 -281.181556) (xy 63.59398 -280.224992) (xy 63.59449 -280.199005)
			(xy 63.602622 -280.147671) (xy 63.618683 -280.09824) (xy 63.642279 -280.051931) (xy 63.672829 -280.009883)
			(xy 63.70958 -279.973132) (xy 63.751628 -279.942581) (xy 63.797937 -279.918985) (xy 63.847367 -279.902923)
			(xy 63.898701 -279.89479) (xy 63.924688 -279.894284) (xy 63.924942 -279.894284) (xy 63.938273 -279.89443)
			(xy 63.964848 -279.896593) (xy 63.978028 -279.898602) (xy 63.982346 -279.899364) (xy 63.982854 -279.899364)
			(xy 63.99149 -279.900888) (xy 64.00292 -279.897332) (xy 64.00841 -279.895435) (xy 64.018406 -279.889525)
			(xy 64.022732 -279.885648) (xy 64.0715 -279.838912) (xy 64.079374 -279.815544) (xy 64.077342 -279.802844)
			(xy 64.075327 -279.789793) (xy 64.073169 -279.763471) (xy 64.073024 -279.750266) (xy 64.073024 -279.749504)
			(xy 64.073528 -279.723798) (xy 64.081568 -279.673019) (xy 64.097453 -279.624123) (xy 64.120789 -279.578313)
			(xy 64.151004 -279.536716) (xy 64.187353 -279.500358) (xy 64.228941 -279.470133) (xy 64.274746 -279.446785)
			(xy 64.323638 -279.430888) (xy 64.374415 -279.422834) (xy 64.425827 -279.422822) (xy 64.476608 -279.430851)
			(xy 64.525508 -279.446724) (xy 64.571323 -279.47005) (xy 64.612926 -279.500255) (xy 64.649293 -279.536596)
			(xy 64.679528 -279.578177) (xy 64.702887 -279.623976) (xy 64.718795 -279.672865) (xy 64.72686 -279.72364)
			(xy 64.726884 -279.775051) (xy 64.718867 -279.825834) (xy 64.703005 -279.874738) (xy 64.67969 -279.920559)
			(xy 64.649494 -279.962169) (xy 64.613162 -279.998544) (xy 64.571587 -280.028788) (xy 64.525794 -280.052158)
			(xy 64.476909 -280.068077) (xy 64.426136 -280.076154) (xy 64.40043 -280.076656) (xy 64.399922 -280.076656)
			(xy 64.386586 -280.076455) (xy 64.360011 -280.074163) (xy 64.346836 -280.072084) (xy 64.346582 -280.072084)
			(xy 64.33439 -280.070052) (xy 64.310514 -280.07818) (xy 64.264032 -280.126948) (xy 64.260144 -280.131265)
			(xy 64.254244 -280.141269) (xy 64.252348 -280.14676) (xy 64.248792 -280.15819) (xy 64.250062 -280.165556)
			(xy 64.252566 -280.180223) (xy 64.25524 -280.20986) (xy 64.255396 -280.224738) (xy 64.255396 -280.295096)
			(xy 64.25565 -280.299922) (xy 64.256598 -280.307397) (xy 64.26228 -280.321344) (xy 64.266826 -280.327354)
			(xy 64.272414 -280.333196) (xy 64.307212 -280.364438) (xy 64.316088 -280.371505) (xy 64.337843 -280.377848)
			(xy 64.349122 -280.37663) (xy 64.361742 -280.374808) (xy 64.387171 -280.372899) (xy 64.399922 -280.37282)
			(xy 64.425607 -280.373325) (xy 64.476345 -280.381365) (xy 64.5252 -280.397242) (xy 64.570971 -280.420565)
			(xy 64.612529 -280.450762) (xy 64.648852 -280.487088) (xy 64.679046 -280.528648) (xy 64.702367 -280.57442)
			(xy 64.718241 -280.623277) (xy 64.726276 -280.674015) (xy 64.726276 -280.725385) (xy 64.718241 -280.776123)
			(xy 64.702367 -280.82498) (xy 64.679046 -280.870752) (xy 64.648852 -280.912312) (xy 64.612529 -280.948638)
			(xy 64.570971 -280.978835) (xy 64.5252 -281.002158) (xy 64.476345 -281.018035) (xy 64.425607 -281.026075)
			(xy 64.399922 -281.026616) (xy 64.387171 -281.026533) (xy 64.361742 -281.024628) (xy 64.349122 -281.022806)
			(xy 64.337841 -281.021596) (xy 64.316085 -281.027927) (xy 64.307212 -281.034998) (xy 64.272414 -281.06624)
			(xy 64.266826 -281.072082) (xy 64.262282 -281.078094) (xy 64.256589 -281.092038) (xy 64.25565 -281.099514)
			(xy 64.255396 -281.10434) (xy 64.255396 -281.18181) (xy 64.255543 -281.187679) (xy 64.258233 -281.199103)
			(xy 64.26073 -281.204416) (xy 64.265048 -281.213052) (xy 64.321436 -281.270456) (xy 64.323214 -281.27198)
			(xy 64.330404 -281.277854) (xy 64.347722 -281.284505) (xy 64.356996 -281.284934) (xy 65.351406 -281.284934)
			(xy 65.360804 -281.285696) (xy 65.365376 -281.286712) (xy 65.390268 -281.286712) (xy 65.400141 -281.286243)
			(xy 65.418428 -281.278788) (xy 65.425828 -281.272234) (xy 65.42659 -281.271472) (xy 65.481708 -281.214322)
			(xy 65.487263 -281.207291) (xy 65.49351 -281.190508) (xy 65.4939 -281.181556) (xy 65.4939 -280.224992)
			(xy 65.49441 -280.199005) (xy 65.502542 -280.147672) (xy 65.518604 -280.098243) (xy 65.5422 -280.051936)
			(xy 65.57275 -280.009889) (xy 65.609501 -279.97314) (xy 65.651549 -279.942592) (xy 65.697858 -279.918997)
			(xy 65.747288 -279.902938) (xy 65.798621 -279.894809) (xy 65.824608 -279.894284) (xy 65.824862 -279.894284)
			(xy 65.838193 -279.894431) (xy 65.864768 -279.896596) (xy 65.877948 -279.898602) (xy 65.882266 -279.899364)
			(xy 65.882774 -279.899364) (xy 65.89141 -279.900888) (xy 65.90284 -279.897332) (xy 65.908335 -279.895443)
			(xy 65.918341 -279.889544) (xy 65.922652 -279.885648) (xy 65.97142 -279.838912) (xy 65.979294 -279.815544)
			(xy 65.977262 -279.802844) (xy 65.975247 -279.789793) (xy 65.973089 -279.763471) (xy 65.972944 -279.750266)
			(xy 65.972944 -279.749504) (xy 65.973447 -279.7238) (xy 65.981488 -279.673025) (xy 65.99737 -279.624132)
			(xy 66.020705 -279.578325) (xy 66.050917 -279.536732) (xy 66.087263 -279.500376) (xy 66.128848 -279.470152)
			(xy 66.174649 -279.446805) (xy 66.223537 -279.430909) (xy 66.27431 -279.422855) (xy 66.325718 -279.422841)
			(xy 66.376495 -279.430868) (xy 66.425392 -279.446739) (xy 66.471205 -279.470062) (xy 66.512806 -279.500264)
			(xy 66.549171 -279.536601) (xy 66.579405 -279.578178) (xy 66.602764 -279.623973) (xy 66.618672 -279.672857)
			(xy 66.626739 -279.723628) (xy 66.626765 -279.775036) (xy 66.618751 -279.825816) (xy 66.602892 -279.874716)
			(xy 66.579581 -279.920535) (xy 66.549389 -279.962143) (xy 66.513062 -279.998517) (xy 66.471492 -280.028762)
			(xy 66.425703 -280.052132) (xy 66.376823 -280.068053) (xy 66.326054 -280.076133) (xy 66.30035 -280.076656)
			(xy 66.299842 -280.076656) (xy 66.286506 -280.076456) (xy 66.25993 -280.074165) (xy 66.246756 -280.072084)
			(xy 66.246502 -280.072084) (xy 66.23431 -280.070052) (xy 66.210434 -280.07818) (xy 66.163952 -280.126948)
			(xy 66.160063 -280.131264) (xy 66.154161 -280.141267) (xy 66.152268 -280.14676) (xy 66.148712 -280.15819)
			(xy 66.149982 -280.165556) (xy 66.152486 -280.180223) (xy 66.15516 -280.20986) (xy 66.155316 -280.224738)
			(xy 66.155316 -280.295096) (xy 66.15557 -280.299922) (xy 66.156518 -280.307397) (xy 66.162203 -280.321343)
			(xy 66.166746 -280.327354) (xy 66.172334 -280.333196) (xy 66.207132 -280.364438) (xy 66.216009 -280.371501)
			(xy 66.237763 -280.377836) (xy 66.249042 -280.37663) (xy 66.261662 -280.374809) (xy 66.287091 -280.372901)
			(xy 66.299842 -280.37282) (xy 66.325526 -280.373327) (xy 66.376261 -280.381369) (xy 66.425114 -280.397247)
			(xy 66.470882 -280.420572) (xy 66.512437 -280.450769) (xy 66.548758 -280.487095) (xy 66.57895 -280.528654)
			(xy 66.602269 -280.574425) (xy 66.618141 -280.62328) (xy 66.626176 -280.674016) (xy 66.626176 -280.725384)
			(xy 66.618141 -280.77612) (xy 66.602269 -280.824975) (xy 66.57895 -280.870746) (xy 66.548758 -280.912305)
			(xy 66.512437 -280.948631) (xy 66.470882 -280.978828) (xy 66.425114 -281.002153) (xy 66.376261 -281.018031)
			(xy 66.325526 -281.026073) (xy 66.299842 -281.026616) (xy 66.287091 -281.026534) (xy 66.261662 -281.02463)
			(xy 66.249042 -281.022806) (xy 66.23776 -281.021592) (xy 66.215998 -281.027916) (xy 66.207132 -281.034998)
			(xy 66.172334 -281.06624) (xy 66.166746 -281.072082) (xy 66.162208 -281.078096) (xy 66.156524 -281.092041)
			(xy 66.15557 -281.099514) (xy 66.155316 -281.10434) (xy 66.155316 -281.18181) (xy 66.155476 -281.187678)
			(xy 66.158161 -281.199101) (xy 66.16065 -281.204416) (xy 66.164968 -281.213052) (xy 66.221356 -281.270456)
			(xy 66.223134 -281.27198) (xy 66.230325 -281.277851) (xy 66.247644 -281.284496) (xy 66.256916 -281.284934)
			(xy 67.25158 -281.284934) (xy 67.260978 -281.285696) (xy 67.26555 -281.286712) (xy 67.290442 -281.286712)
			(xy 67.300406 -281.28623) (xy 67.318838 -281.27865) (xy 67.326256 -281.27198) (xy 67.326764 -281.271472)
			(xy 67.379596 -281.217116) (xy 67.38325 -281.213164) (xy 67.389 -281.204069) (xy 67.391026 -281.199082)
			(xy 67.394582 -281.189176) (xy 67.394074 -281.178254) (xy 67.39382 -281.174952) (xy 67.39382 -280.224992)
			(xy 67.394331 -280.198985) (xy 67.402469 -280.147611) (xy 67.418542 -280.098142) (xy 67.442156 -280.051797)
			(xy 67.472729 -280.009716) (xy 67.509509 -279.972936) (xy 67.551589 -279.942362) (xy 67.597933 -279.918746)
			(xy 67.647401 -279.902671) (xy 67.698775 -279.894532) (xy 67.724782 -279.89403) (xy 67.738373 -279.894198)
			(xy 67.765458 -279.896485) (xy 67.778884 -279.898602) (xy 67.784726 -279.899618) (xy 67.785488 -279.899618)
			(xy 67.79133 -279.900634) (xy 67.80276 -279.897078) (xy 67.808254 -279.895188) (xy 67.818262 -279.889291)
			(xy 67.822572 -279.885394) (xy 67.87134 -279.838658) (xy 67.879214 -279.81529) (xy 67.877182 -279.80259)
			(xy 67.875173 -279.789474) (xy 67.873012 -279.763026) (xy 67.872864 -279.749758) (xy 67.872864 -279.749504)
			(xy 67.873367 -279.723802) (xy 67.881407 -279.67303) (xy 67.897288 -279.624141) (xy 67.920621 -279.578337)
			(xy 67.950831 -279.536747) (xy 67.987173 -279.500393) (xy 68.028755 -279.470172) (xy 68.074552 -279.446825)
			(xy 68.123436 -279.430929) (xy 68.174205 -279.422875) (xy 68.22561 -279.42286) (xy 68.276383 -279.430886)
			(xy 68.325277 -279.446754) (xy 68.371087 -279.470075) (xy 68.412685 -279.500273) (xy 68.449049 -279.536606)
			(xy 68.479282 -279.578179) (xy 68.502641 -279.62397) (xy 68.51855 -279.67285) (xy 68.526618 -279.723617)
			(xy 68.526647 -279.775021) (xy 68.518635 -279.825797) (xy 68.50278 -279.874695) (xy 68.479472 -279.920511)
			(xy 68.449285 -279.962118) (xy 68.412962 -279.998491) (xy 68.371396 -280.028736) (xy 68.325612 -280.052107)
			(xy 68.276736 -280.068029) (xy 68.225972 -280.076111) (xy 68.20027 -280.076656) (xy 68.199762 -280.076656)
			(xy 68.186558 -280.0765) (xy 68.160237 -280.074337) (xy 68.147184 -280.072338) (xy 68.134992 -280.070306)
			(xy 68.111116 -280.07818) (xy 68.06438 -280.127456) (xy 68.060517 -280.131718) (xy 68.054625 -280.141595)
			(xy 68.052696 -280.147014) (xy 68.04914 -280.157936) (xy 68.050156 -280.16454) (xy 68.050664 -280.16708)
			(xy 68.053028 -280.181377) (xy 68.055568 -280.210247) (xy 68.055744 -280.224738) (xy 68.055744 -280.295096)
			(xy 68.055998 -280.30043) (xy 68.057189 -280.30861) (xy 68.064061 -280.323634) (xy 68.06946 -280.329894)
			(xy 68.072508 -280.332942) (xy 68.115942 -280.372058) (xy 68.137786 -280.378408) (xy 68.149216 -280.37663)
			(xy 68.161773 -280.374816) (xy 68.187075 -280.372906) (xy 68.199762 -280.37282) (xy 68.225452 -280.373295)
			(xy 68.276201 -280.381327) (xy 68.325069 -280.3972) (xy 68.370851 -280.420523) (xy 68.412421 -280.450721)
			(xy 68.448755 -280.48705) (xy 68.478957 -280.528617) (xy 68.502285 -280.574396) (xy 68.518164 -280.623262)
			(xy 68.526202 -280.67401) (xy 68.526202 -280.72539) (xy 68.518164 -280.776138) (xy 68.502285 -280.825004)
			(xy 68.478957 -280.870783) (xy 68.448755 -280.91235) (xy 68.412421 -280.948679) (xy 68.370851 -280.978877)
			(xy 68.325069 -281.0022) (xy 68.276201 -281.018073) (xy 68.225452 -281.026105) (xy 68.199762 -281.026616)
			(xy 68.187075 -281.026523) (xy 68.161773 -281.024617) (xy 68.149216 -281.022806) (xy 68.137786 -281.021028)
			(xy 68.115942 -281.027378) (xy 68.072508 -281.066494) (xy 68.06946 -281.069542) (xy 68.064034 -281.075785)
			(xy 68.05716 -281.090817) (xy 68.055998 -281.099006) (xy 68.055744 -281.10434) (xy 68.055744 -281.173936)
			(xy 68.05549 -281.178762) (xy 68.05549 -281.184096) (xy 68.056132 -281.191931) (xy 68.061559 -281.206677)
			(xy 68.066158 -281.213052) (xy 68.069206 -281.216608) (xy 68.081652 -281.229816) (xy 68.08216 -281.23007)
			(xy 68.120768 -281.269694) (xy 68.124578 -281.272996) (xy 68.125086 -281.273504) (xy 68.132049 -281.278707)
			(xy 68.148406 -281.284555) (xy 68.15709 -281.284934) (xy 69.1515 -281.284934) (xy 69.160898 -281.285696)
			(xy 69.16547 -281.286712) (xy 69.190362 -281.286712) (xy 69.200325 -281.286227) (xy 69.218751 -281.278641)
			(xy 69.226176 -281.27198) (xy 69.226684 -281.271472) (xy 69.279516 -281.217116) (xy 69.283175 -281.213167)
			(xy 69.288933 -281.204075) (xy 69.290946 -281.199082) (xy 69.294502 -281.189176) (xy 69.293994 -281.178254)
			(xy 69.29374 -281.174952) (xy 69.29374 -280.224992) (xy 69.294251 -280.198985) (xy 69.302389 -280.147613)
			(xy 69.318463 -280.098145) (xy 69.342077 -280.051802) (xy 69.372651 -280.009722) (xy 69.40943 -279.972944)
			(xy 69.45151 -279.942372) (xy 69.497855 -279.918759) (xy 69.547322 -279.902686) (xy 69.598695 -279.89455)
			(xy 69.624702 -279.89403) (xy 69.625464 -279.89403) (xy 69.638795 -279.894177) (xy 69.66537 -279.896342)
			(xy 69.67855 -279.898348) (xy 69.682868 -279.89911) (xy 69.683122 -279.89911) (xy 69.69125 -279.90038)
			(xy 69.702172 -279.897078) (xy 69.707823 -279.895191) (xy 69.718091 -279.889156) (xy 69.722492 -279.88514)
			(xy 69.771514 -279.838658) (xy 69.779134 -279.814782) (xy 69.777102 -279.802336) (xy 69.775077 -279.789222)
			(xy 69.772919 -279.762773) (xy 69.772784 -279.749504) (xy 69.773288 -279.7238) (xy 69.781329 -279.673024)
			(xy 69.797214 -279.624131) (xy 69.820552 -279.578325) (xy 69.850769 -279.536733) (xy 69.887119 -279.500381)
			(xy 69.928709 -279.470162) (xy 69.974513 -279.446821) (xy 70.023405 -279.430933) (xy 70.074181 -279.422889)
			(xy 70.12559 -279.422887) (xy 70.176366 -279.430926) (xy 70.225259 -279.44681) (xy 70.271066 -279.470147)
			(xy 70.312659 -279.500362) (xy 70.349012 -279.536711) (xy 70.379232 -279.5783) (xy 70.402575 -279.624104)
			(xy 70.418464 -279.672995) (xy 70.42651 -279.72377) (xy 70.426514 -279.775179) (xy 70.418476 -279.825956)
			(xy 70.402594 -279.87485) (xy 70.379259 -279.920657) (xy 70.349045 -279.962251) (xy 70.312697 -279.998605)
			(xy 70.27111 -280.028827) (xy 70.225306 -280.05217) (xy 70.176415 -280.068062) (xy 70.12564 -280.076109)
			(xy 70.099936 -280.076656) (xy 70.086668 -280.076509) (xy 70.06022 -280.074347) (xy 70.047104 -280.072338)
			(xy 70.034658 -280.070306) (xy 70.010782 -280.07818) (xy 69.95668 -280.135076) (xy 69.956172 -280.135584)
			(xy 69.94906 -280.157936) (xy 69.950076 -280.16454) (xy 69.950584 -280.16708) (xy 69.952948 -280.181377)
			(xy 69.955488 -280.210247) (xy 69.955664 -280.224738) (xy 69.955664 -280.295096) (xy 69.955918 -280.30043)
			(xy 69.957109 -280.30861) (xy 69.963983 -280.323632) (xy 69.96938 -280.329894) (xy 69.972428 -280.332942)
			(xy 70.015862 -280.372058) (xy 70.037706 -280.378408) (xy 70.049136 -280.37663) (xy 70.061756 -280.374809)
			(xy 70.087185 -280.3729) (xy 70.099936 -280.37282) (xy 70.125621 -280.373326) (xy 70.176356 -280.381367)
			(xy 70.22521 -280.397246) (xy 70.270978 -280.42057) (xy 70.312535 -280.450767) (xy 70.348856 -280.487092)
			(xy 70.379049 -280.528652) (xy 70.402368 -280.574423) (xy 70.418241 -280.623279) (xy 70.426276 -280.674015)
			(xy 70.426276 -280.725385) (xy 70.418241 -280.776121) (xy 70.402368 -280.824977) (xy 70.379049 -280.870748)
			(xy 70.348856 -280.912308) (xy 70.312535 -280.948633) (xy 70.270978 -280.97883) (xy 70.22521 -281.002154)
			(xy 70.176356 -281.018033) (xy 70.125621 -281.026074) (xy 70.099936 -281.026616) (xy 70.087185 -281.026534)
			(xy 70.061756 -281.024629) (xy 70.049136 -281.022806) (xy 70.037706 -281.021028) (xy 70.015862 -281.027378)
			(xy 69.972428 -281.066494) (xy 69.96938 -281.069542) (xy 69.963952 -281.075784) (xy 69.957075 -281.090816)
			(xy 69.955918 -281.099006) (xy 69.955664 -281.10434) (xy 69.955664 -281.173936) (xy 69.95541 -281.178762)
			(xy 69.95541 -281.184096) (xy 69.956052 -281.191931) (xy 69.961481 -281.206675) (xy 69.966078 -281.213052)
			(xy 69.969126 -281.216608) (xy 69.981572 -281.229816) (xy 69.98208 -281.23007) (xy 70.020688 -281.269694)
			(xy 70.024498 -281.272996) (xy 70.025006 -281.273504) (xy 70.03197 -281.278705) (xy 70.048327 -281.284546)
			(xy 70.05701 -281.284934) (xy 71.05142 -281.284934) (xy 71.060818 -281.285696) (xy 71.06539 -281.286712)
			(xy 71.090282 -281.286712) (xy 71.100243 -281.286223) (xy 71.118664 -281.278633) (xy 71.126096 -281.27198)
			(xy 71.126604 -281.271472) (xy 71.179436 -281.217116) (xy 71.183093 -281.213167) (xy 71.18885 -281.204073)
			(xy 71.190866 -281.199082) (xy 71.194422 -281.189176) (xy 71.193914 -281.178254) (xy 71.19366 -281.174952)
			(xy 71.19366 -280.224992) (xy 71.194144 -280.198984) (xy 71.202283 -280.147608) (xy 71.218358 -280.098138)
			(xy 71.241975 -280.051792) (xy 71.272551 -280.009711) (xy 71.309334 -279.972932) (xy 71.351418 -279.942359)
			(xy 71.397766 -279.918747) (xy 71.447237 -279.902676) (xy 71.498614 -279.894542) (xy 71.524622 -279.89403)
			(xy 71.525384 -279.89403) (xy 71.538715 -279.894174) (xy 71.565291 -279.896333) (xy 71.57847 -279.898348)
			(xy 71.582788 -279.89911) (xy 71.583042 -279.89911) (xy 71.59117 -279.90038) (xy 71.602092 -279.897078)
			(xy 71.607748 -279.895199) (xy 71.618028 -279.889176) (xy 71.622412 -279.88514) (xy 71.671434 -279.838658)
			(xy 71.679054 -279.814782) (xy 71.677022 -279.802336) (xy 71.674997 -279.789222) (xy 71.672839 -279.762773)
			(xy 71.672704 -279.749504) (xy 71.673182 -279.72379) (xy 71.681227 -279.672995) (xy 71.697119 -279.624084)
			(xy 71.720467 -279.578261) (xy 71.750696 -279.536655) (xy 71.787061 -279.500291) (xy 71.828668 -279.470063)
			(xy 71.874491 -279.446716) (xy 71.923403 -279.430825) (xy 71.974198 -279.422781) (xy 72.025626 -279.422783)
			(xy 72.076421 -279.430831) (xy 72.125331 -279.446725) (xy 72.171152 -279.470075) (xy 72.212757 -279.500306)
			(xy 72.24912 -279.536674) (xy 72.279346 -279.578282) (xy 72.30269 -279.624106) (xy 72.318579 -279.673018)
			(xy 72.32662 -279.723814) (xy 72.326615 -279.775242) (xy 72.318566 -279.826036) (xy 72.302669 -279.874946)
			(xy 72.279316 -279.920766) (xy 72.249083 -279.962369) (xy 72.212714 -279.99873) (xy 72.171105 -280.028954)
			(xy 72.125279 -280.052297) (xy 72.076366 -280.068183) (xy 72.02557 -280.076221) (xy 71.999856 -280.076656)
			(xy 71.986588 -280.076509) (xy 71.96014 -280.07435) (xy 71.947024 -280.072338) (xy 71.934578 -280.070306)
			(xy 71.910702 -280.07818) (xy 71.8566 -280.135076) (xy 71.856092 -280.135584) (xy 71.84898 -280.157936)
			(xy 71.849996 -280.16454) (xy 71.850504 -280.16708) (xy 71.852869 -280.181377) (xy 71.855408 -280.210247)
			(xy 71.855584 -280.224738) (xy 71.855584 -280.295096) (xy 71.855838 -280.30043) (xy 71.85703 -280.308609)
			(xy 71.863906 -280.32363) (xy 71.8693 -280.329894) (xy 71.872348 -280.332942) (xy 71.915782 -280.372058)
			(xy 71.937626 -280.378408) (xy 71.949056 -280.37663) (xy 71.961676 -280.374809) (xy 71.987105 -280.372903)
			(xy 71.999856 -280.37282) (xy 72.025547 -280.373295) (xy 72.076296 -280.381326) (xy 72.125164 -280.397199)
			(xy 72.170948 -280.420521) (xy 72.212518 -280.450719) (xy 72.248853 -280.487048) (xy 72.279056 -280.528615)
			(xy 72.302385 -280.574395) (xy 72.318264 -280.623261) (xy 72.326302 -280.674009) (xy 72.326302 -280.725391)
			(xy 72.318264 -280.776139) (xy 72.302385 -280.825005) (xy 72.279056 -280.870785) (xy 72.248853 -280.912352)
			(xy 72.212518 -280.948681) (xy 72.170948 -280.978879) (xy 72.125164 -281.002201) (xy 72.076296 -281.018074)
			(xy 72.025547 -281.026105) (xy 71.999856 -281.026616) (xy 71.987106 -281.026531) (xy 71.961677 -281.02462)
			(xy 71.949056 -281.022806) (xy 71.937626 -281.021028) (xy 71.915782 -281.027378) (xy 71.872348 -281.066494)
			(xy 71.8693 -281.069542) (xy 71.863879 -281.075787) (xy 71.857013 -281.09082) (xy 71.855838 -281.099006)
			(xy 71.855584 -281.10434) (xy 71.855584 -281.173936) (xy 71.85533 -281.178762) (xy 71.85533 -281.184096)
			(xy 71.855972 -281.191931) (xy 71.861403 -281.206674) (xy 71.865998 -281.213052) (xy 71.869046 -281.216608)
			(xy 71.881492 -281.229816) (xy 71.882 -281.23007) (xy 71.920608 -281.269694) (xy 71.924418 -281.272996)
			(xy 71.924926 -281.273504) (xy 71.931891 -281.278702) (xy 71.948248 -281.284537) (xy 71.95693 -281.284934)
			(xy 72.951594 -281.284934) (xy 72.960992 -281.285696) (xy 72.965564 -281.286712) (xy 72.990456 -281.286712)
			(xy 73.00033 -281.286245) (xy 73.01862 -281.278794) (xy 73.026016 -281.272234) (xy 73.026778 -281.271472)
			(xy 73.081896 -281.214322) (xy 73.087452 -281.207292) (xy 73.0937 -281.190508) (xy 73.094088 -281.181556)
			(xy 73.094088 -280.224992) (xy 73.094598 -280.199005) (xy 73.10273 -280.147671) (xy 73.118791 -280.098242)
			(xy 73.142388 -280.051933) (xy 73.172937 -280.009886) (xy 73.209689 -279.973135) (xy 73.251736 -279.942585)
			(xy 73.298045 -279.91899) (xy 73.347475 -279.902929) (xy 73.398809 -279.894798) (xy 73.424796 -279.894284)
			(xy 73.425304 -279.894284) (xy 73.440118 -279.894462) (xy 73.469626 -279.897135) (xy 73.484232 -279.899618)
			(xy 73.48474 -279.899618) (xy 73.491344 -279.900634) (xy 73.502266 -279.897332) (xy 73.507814 -279.895436)
			(xy 73.517939 -279.889531) (xy 73.522332 -279.885648) (xy 73.548494 -279.860756) (xy 73.56221 -279.847548)
			(xy 73.570742 -279.838505) (xy 73.578596 -279.814944) (xy 73.577196 -279.80259) (xy 73.575105 -279.789481)
			(xy 73.572813 -279.763031) (xy 73.572624 -279.749758) (xy 73.572624 -279.74925) (xy 73.573147 -279.723554)
			(xy 73.581221 -279.672801) (xy 73.597131 -279.623934) (xy 73.620486 -279.578155) (xy 73.650711 -279.536591)
			(xy 73.687063 -279.500264) (xy 73.728648 -279.470067) (xy 73.774443 -279.446744) (xy 73.823321 -279.430868)
			(xy 73.87408 -279.422829) (xy 73.899776 -279.422352) (xy 73.925487 -279.422828) (xy 73.976276 -279.430869)
			(xy 74.025181 -279.446756) (xy 74.070999 -279.470099) (xy 74.112601 -279.500322) (xy 74.148963 -279.536681)
			(xy 74.179189 -279.57828) (xy 74.202535 -279.624097) (xy 74.218425 -279.673001) (xy 74.22647 -279.723789)
			(xy 74.22647 -279.775211) (xy 74.218425 -279.825999) (xy 74.202535 -279.874903) (xy 74.179189 -279.92072)
			(xy 74.148963 -279.962319) (xy 74.112601 -279.998678) (xy 74.070999 -280.028901) (xy 74.025181 -280.052244)
			(xy 73.976276 -280.068131) (xy 73.925487 -280.076172) (xy 73.899776 -280.076656) (xy 73.886508 -280.07651)
			(xy 73.860059 -280.074352) (xy 73.846944 -280.072338) (xy 73.834498 -280.070306) (xy 73.810622 -280.07818)
			(xy 73.75652 -280.135076) (xy 73.756012 -280.135584) (xy 73.7489 -280.157936) (xy 73.750678 -280.16835)
			(xy 73.752929 -280.18221) (xy 73.755341 -280.210189) (xy 73.755504 -280.22423) (xy 73.755504 -280.295096)
			(xy 73.755758 -280.30043) (xy 73.756947 -280.308611) (xy 73.763815 -280.323638) (xy 73.76922 -280.329894)
			(xy 73.772268 -280.332942) (xy 73.815702 -280.372058) (xy 73.837546 -280.378408) (xy 73.848976 -280.37663)
			(xy 73.861596 -280.37481) (xy 73.887025 -280.372905) (xy 73.899776 -280.37282) (xy 73.925466 -280.373296)
			(xy 73.976213 -280.38133) (xy 74.025078 -280.397204) (xy 74.070859 -280.420528) (xy 74.112427 -280.450726)
			(xy 74.148759 -280.487055) (xy 74.17896 -280.528621) (xy 74.202286 -280.574399) (xy 74.218164 -280.623264)
			(xy 74.226202 -280.67401) (xy 74.226202 -280.72539) (xy 74.218164 -280.776136) (xy 74.202286 -280.825001)
			(xy 74.17896 -280.870779) (xy 74.148759 -280.912345) (xy 74.112427 -280.948674) (xy 74.070859 -280.978872)
			(xy 74.025078 -281.002196) (xy 73.976213 -281.01807) (xy 73.925466 -281.026104) (xy 73.899776 -281.026616)
			(xy 73.887026 -281.026532) (xy 73.861597 -281.024622) (xy 73.848976 -281.022806) (xy 73.837546 -281.021028)
			(xy 73.815702 -281.027378) (xy 73.772268 -281.066494) (xy 73.76922 -281.069542) (xy 73.763797 -281.075786)
			(xy 73.756929 -281.090819) (xy 73.755758 -281.099006) (xy 73.755504 -281.10434) (xy 73.755504 -281.18181)
			(xy 73.755664 -281.187678) (xy 73.758348 -281.199101) (xy 73.760838 -281.204416) (xy 73.765156 -281.213052)
			(xy 73.821544 -281.270456) (xy 73.823322 -281.27198) (xy 73.830513 -281.277852) (xy 73.847831 -281.284502)
			(xy 73.857104 -281.284934) (xy 74.851514 -281.284934) (xy 74.860912 -281.285696) (xy 74.865484 -281.286712)
			(xy 74.890376 -281.286712) (xy 74.900249 -281.286242) (xy 74.918533 -281.278785) (xy 74.925936 -281.272234)
			(xy 74.926698 -281.271472) (xy 74.981816 -281.214322) (xy 74.98737 -281.207291) (xy 74.993616 -281.190508)
			(xy 74.994008 -281.181556) (xy 74.994008 -280.224992) (xy 74.994492 -280.199004) (xy 75.002624 -280.147667)
			(xy 75.018687 -280.098235) (xy 75.042286 -280.051924) (xy 75.072838 -280.009874) (xy 75.109593 -279.973123)
			(xy 75.151644 -279.942573) (xy 75.197957 -279.918978) (xy 75.24739 -279.902918) (xy 75.298728 -279.89479)
			(xy 75.324716 -279.894284) (xy 75.32497 -279.894284) (xy 75.338302 -279.894427) (xy 75.364877 -279.896585)
			(xy 75.378056 -279.898602) (xy 75.382374 -279.899364) (xy 75.382882 -279.899364) (xy 75.391518 -279.900888)
			(xy 75.402948 -279.897332) (xy 75.408442 -279.895442) (xy 75.418448 -279.889542) (xy 75.42276 -279.885648)
			(xy 75.471528 -279.838912) (xy 75.479402 -279.815544) (xy 75.47737 -279.802844) (xy 75.475355 -279.789793)
			(xy 75.473197 -279.763471) (xy 75.473052 -279.750266) (xy 75.473052 -279.749504) (xy 75.473555 -279.723801)
			(xy 75.481595 -279.673027) (xy 75.497478 -279.624136) (xy 75.520811 -279.57833) (xy 75.551023 -279.536738)
			(xy 75.587367 -279.500383) (xy 75.628951 -279.47016) (xy 75.67475 -279.446813) (xy 75.723637 -279.430917)
			(xy 75.774408 -279.422863) (xy 75.825815 -279.422849) (xy 75.876591 -279.430875) (xy 75.925486 -279.446745)
			(xy 75.971298 -279.470067) (xy 76.012898 -279.500268) (xy 76.049262 -279.536603) (xy 76.079496 -279.578179)
			(xy 76.102854 -279.623971) (xy 76.118763 -279.672854) (xy 76.126831 -279.723624) (xy 76.126858 -279.77503)
			(xy 76.118844 -279.825808) (xy 76.102987 -279.874708) (xy 76.079677 -279.920525) (xy 76.049488 -279.962133)
			(xy 76.013162 -279.998507) (xy 75.971594 -280.028751) (xy 75.925807 -280.052122) (xy 75.876928 -280.068043)
			(xy 75.826161 -280.076124) (xy 75.800458 -280.076656) (xy 75.79995 -280.076656) (xy 75.786614 -280.076456)
			(xy 75.760038 -280.074166) (xy 75.746864 -280.072084) (xy 75.74661 -280.072084) (xy 75.734418 -280.070052)
			(xy 75.710542 -280.07818) (xy 75.66406 -280.126948) (xy 75.66017 -280.131264) (xy 75.654267 -280.141267)
			(xy 75.652376 -280.14676) (xy 75.64882 -280.15819) (xy 75.65009 -280.165556) (xy 75.652594 -280.180223)
			(xy 75.655268 -280.20986) (xy 75.655424 -280.224738) (xy 75.655424 -280.295096) (xy 75.655678 -280.299922)
			(xy 75.656626 -280.307397) (xy 75.662311 -280.321342) (xy 75.666854 -280.327354) (xy 75.672442 -280.333196)
			(xy 75.70724 -280.364438) (xy 75.716118 -280.371499) (xy 75.737871 -280.37783) (xy 75.74915 -280.37663)
			(xy 75.76177 -280.374809) (xy 75.787199 -280.372902) (xy 75.79995 -280.37282) (xy 75.825641 -280.373294)
			(xy 75.876391 -280.381325) (xy 75.92526 -280.397197) (xy 75.971044 -280.420519) (xy 76.012616 -280.450716)
			(xy 76.048951 -280.487046) (xy 76.079155 -280.528613) (xy 76.102484 -280.574393) (xy 76.118363 -280.62326)
			(xy 76.126402 -280.674009) (xy 76.126402 -280.725391) (xy 76.118363 -280.77614) (xy 76.102484 -280.825007)
			(xy 76.079155 -280.870787) (xy 76.048951 -280.912354) (xy 76.012616 -280.948684) (xy 75.971044 -280.978881)
			(xy 75.92526 -281.002203) (xy 75.876391 -281.018075) (xy 75.825641 -281.026106) (xy 75.79995 -281.026616)
			(xy 75.7872 -281.026531) (xy 75.761771 -281.024619) (xy 75.74915 -281.022806) (xy 75.737867 -281.02159)
			(xy 75.716103 -281.027912) (xy 75.70724 -281.034998) (xy 75.672442 -281.06624) (xy 75.666854 -281.072082)
			(xy 75.662316 -281.078096) (xy 75.656631 -281.092041) (xy 75.655678 -281.099514) (xy 75.655424 -281.10434)
			(xy 75.655424 -281.18181) (xy 75.655584 -281.187678) (xy 75.658269 -281.199101) (xy 75.660758 -281.204416)
			(xy 75.665076 -281.213052) (xy 75.721464 -281.270456) (xy 75.723242 -281.27198) (xy 75.730433 -281.27785)
			(xy 75.747752 -281.284492) (xy 75.757024 -281.284934) (xy 76.751434 -281.284934) (xy 76.760832 -281.285696)
			(xy 76.765404 -281.286712) (xy 76.790296 -281.286712) (xy 76.800175 -281.286256) (xy 76.81848 -281.27882)
			(xy 76.825856 -281.272234) (xy 76.826618 -281.271472) (xy 76.881736 -281.214322) (xy 76.887289 -281.20729)
			(xy 76.893532 -281.190507) (xy 76.893928 -281.181556) (xy 76.893928 -280.224992) (xy 76.894412 -280.199004)
			(xy 76.902544 -280.147669) (xy 76.918608 -280.098238) (xy 76.942206 -280.051928) (xy 76.972759 -280.009881)
			(xy 77.009514 -279.973131) (xy 77.051566 -279.942583) (xy 77.097878 -279.918991) (xy 77.147312 -279.902934)
			(xy 77.198648 -279.894808) (xy 77.224636 -279.894284) (xy 77.22489 -279.894284) (xy 77.238221 -279.894428)
			(xy 77.264797 -279.896587) (xy 77.277976 -279.898602) (xy 77.282294 -279.899364) (xy 77.282802 -279.899364)
			(xy 77.291438 -279.900888) (xy 77.302868 -279.897332) (xy 77.308361 -279.89544) (xy 77.318364 -279.889537)
			(xy 77.32268 -279.885648) (xy 77.371448 -279.838912) (xy 77.379322 -279.815544) (xy 77.37729 -279.802844)
			(xy 77.375275 -279.789793) (xy 77.373117 -279.763471) (xy 77.372972 -279.750266) (xy 77.372972 -279.749504)
			(xy 77.373475 -279.723803) (xy 77.381514 -279.673033) (xy 77.397395 -279.624145) (xy 77.420727 -279.578342)
			(xy 77.450936 -279.536753) (xy 77.487277 -279.5004) (xy 77.528858 -279.470179) (xy 77.574653 -279.446833)
			(xy 77.623536 -279.430938) (xy 77.674304 -279.422883) (xy 77.725706 -279.422868) (xy 77.776478 -279.430893)
			(xy 77.825371 -279.44676) (xy 77.87118 -279.47008) (xy 77.912777 -279.500276) (xy 77.94914 -279.536608)
			(xy 77.979373 -279.57818) (xy 78.002732 -279.623968) (xy 78.018641 -279.672847) (xy 78.02671 -279.723612)
			(xy 78.026739 -279.775015) (xy 78.026668 -279.775466) (xy 79.273142 -279.775466) (xy 79.273142 -279.72405)
			(xy 79.281185 -279.673268) (xy 79.297073 -279.624369) (xy 79.320416 -279.578557) (xy 79.350637 -279.536961)
			(xy 79.386993 -279.500605) (xy 79.428589 -279.470384) (xy 79.474401 -279.447041) (xy 79.5233 -279.431153)
			(xy 79.574082 -279.42311) (xy 79.625498 -279.42311) (xy 79.67628 -279.431153) (xy 79.725179 -279.447041)
			(xy 79.770991 -279.470384) (xy 79.812587 -279.500605) (xy 79.848943 -279.536961) (xy 79.879164 -279.578557)
			(xy 79.902507 -279.624369) (xy 79.918395 -279.673268) (xy 79.926438 -279.72405) (xy 79.926942 -279.749758)
			(xy 79.926438 -279.775466) (xy 81.173316 -279.775466) (xy 81.173316 -279.72405) (xy 81.181359 -279.673268)
			(xy 81.197247 -279.624369) (xy 81.22059 -279.578557) (xy 81.250811 -279.536961) (xy 81.287167 -279.500605)
			(xy 81.328763 -279.470384) (xy 81.374575 -279.447041) (xy 81.423474 -279.431153) (xy 81.474256 -279.42311)
			(xy 81.525672 -279.42311) (xy 81.576454 -279.431153) (xy 81.625353 -279.447041) (xy 81.671165 -279.470384)
			(xy 81.712761 -279.500605) (xy 81.749117 -279.536961) (xy 81.779338 -279.578557) (xy 81.802681 -279.624369)
			(xy 81.818569 -279.673268) (xy 81.826612 -279.72405) (xy 81.827116 -279.749758) (xy 81.826612 -279.775466)
			(xy 82.123276 -279.775466) (xy 82.123276 -279.72405) (xy 82.131319 -279.673268) (xy 82.147207 -279.624369)
			(xy 82.17055 -279.578557) (xy 82.200771 -279.536961) (xy 82.237127 -279.500605) (xy 82.278723 -279.470384)
			(xy 82.324535 -279.447041) (xy 82.373434 -279.431153) (xy 82.424216 -279.42311) (xy 82.475632 -279.42311)
			(xy 82.526414 -279.431153) (xy 82.575313 -279.447041) (xy 82.621125 -279.470384) (xy 82.662721 -279.500605)
			(xy 82.699077 -279.536961) (xy 82.729298 -279.578557) (xy 82.752641 -279.624369) (xy 82.768529 -279.673268)
			(xy 82.776572 -279.72405) (xy 82.777076 -279.749758) (xy 82.776572 -279.775466) (xy 82.768529 -279.826248)
			(xy 82.752641 -279.875147) (xy 82.729298 -279.920959) (xy 82.699077 -279.962555) (xy 82.662721 -279.998911)
			(xy 82.621125 -280.029132) (xy 82.575313 -280.052475) (xy 82.526414 -280.068363) (xy 82.475632 -280.076406)
			(xy 82.424216 -280.076406) (xy 82.373434 -280.068363) (xy 82.324535 -280.052475) (xy 82.278723 -280.029132)
			(xy 82.237127 -279.998911) (xy 82.200771 -279.962555) (xy 82.17055 -279.920959) (xy 82.147207 -279.875147)
			(xy 82.131319 -279.826248) (xy 82.123276 -279.775466) (xy 81.826612 -279.775466) (xy 81.818569 -279.826248)
			(xy 81.802681 -279.875147) (xy 81.779338 -279.920959) (xy 81.749117 -279.962555) (xy 81.712761 -279.998911)
			(xy 81.671165 -280.029132) (xy 81.625353 -280.052475) (xy 81.576454 -280.068363) (xy 81.525672 -280.076406)
			(xy 81.474256 -280.076406) (xy 81.423474 -280.068363) (xy 81.374575 -280.052475) (xy 81.328763 -280.029132)
			(xy 81.287167 -279.998911) (xy 81.250811 -279.962555) (xy 81.22059 -279.920959) (xy 81.197247 -279.875147)
			(xy 81.181359 -279.826248) (xy 81.173316 -279.775466) (xy 79.926438 -279.775466) (xy 79.918395 -279.826248)
			(xy 79.902507 -279.875147) (xy 79.879164 -279.920959) (xy 79.848943 -279.962555) (xy 79.812587 -279.998911)
			(xy 79.770991 -280.029132) (xy 79.725179 -280.052475) (xy 79.67628 -280.068363) (xy 79.625498 -280.076406)
			(xy 79.574082 -280.076406) (xy 79.5233 -280.068363) (xy 79.474401 -280.052475) (xy 79.428589 -280.029132)
			(xy 79.386993 -279.998911) (xy 79.350637 -279.962555) (xy 79.320416 -279.920959) (xy 79.297073 -279.875147)
			(xy 79.281185 -279.826248) (xy 79.273142 -279.775466) (xy 78.026668 -279.775466) (xy 78.018728 -279.82579)
			(xy 78.002875 -279.874686) (xy 77.979568 -279.920502) (xy 77.949383 -279.962108) (xy 77.913062 -279.998481)
			(xy 77.871498 -280.028725) (xy 77.825716 -280.052096) (xy 77.776842 -280.06802) (xy 77.726079 -280.076102)
			(xy 77.700378 -280.076656) (xy 77.69987 -280.076656) (xy 77.686534 -280.076457) (xy 77.659958 -280.074169)
			(xy 77.646784 -280.072084) (xy 77.64653 -280.072084) (xy 77.634338 -280.070052) (xy 77.610462 -280.07818)
			(xy 77.56398 -280.126948) (xy 77.560089 -280.131263) (xy 77.554184 -280.141266) (xy 77.552296 -280.14676)
			(xy 77.54874 -280.15819) (xy 77.55001 -280.165556) (xy 77.552514 -280.180223) (xy 77.555187 -280.20986)
			(xy 77.555344 -280.224738) (xy 77.555344 -280.295096) (xy 77.555598 -280.299922) (xy 77.556544 -280.307398)
			(xy 77.562222 -280.321349) (xy 77.566774 -280.327354) (xy 77.572362 -280.333196) (xy 77.60716 -280.364438)
			(xy 77.616038 -280.371496) (xy 77.63779 -280.377818) (xy 77.64907 -280.37663) (xy 77.66169 -280.37481)
			(xy 77.687119 -280.372904) (xy 77.69987 -280.37282) (xy 77.72556 -280.373296) (xy 77.776308 -280.381329)
			(xy 77.825174 -280.397203) (xy 77.870955 -280.420526) (xy 77.912524 -280.450724) (xy 77.948857 -280.487053)
			(xy 77.979059 -280.528619) (xy 78.002386 -280.574398) (xy 78.018264 -280.623263) (xy 78.026302 -280.67401)
			(xy 78.026302 -280.72539) (xy 78.026296 -280.725426) (xy 79.273142 -280.725426) (xy 79.273142 -280.67401)
			(xy 79.281185 -280.623228) (xy 79.297073 -280.574329) (xy 79.320416 -280.528517) (xy 79.350637 -280.486921)
			(xy 79.386993 -280.450565) (xy 79.428589 -280.420344) (xy 79.474401 -280.397001) (xy 79.5233 -280.381113)
			(xy 79.574082 -280.37307) (xy 79.625498 -280.37307) (xy 79.67628 -280.381113) (xy 79.725179 -280.397001)
			(xy 79.770991 -280.420344) (xy 79.812587 -280.450565) (xy 79.848943 -280.486921) (xy 79.879164 -280.528517)
			(xy 79.902507 -280.574329) (xy 79.918395 -280.623228) (xy 79.926438 -280.67401) (xy 79.926942 -280.699718)
			(xy 79.926438 -280.725426) (xy 79.918395 -280.776208) (xy 79.902507 -280.825107) (xy 79.879164 -280.870919)
			(xy 79.848943 -280.912515) (xy 79.812587 -280.948871) (xy 79.770991 -280.979092) (xy 79.725179 -281.002435)
			(xy 79.67628 -281.018323) (xy 79.625498 -281.026366) (xy 79.574082 -281.026366) (xy 79.5233 -281.018323)
			(xy 79.474401 -281.002435) (xy 79.428589 -280.979092) (xy 79.386993 -280.948871) (xy 79.350637 -280.912515)
			(xy 79.320416 -280.870919) (xy 79.297073 -280.825107) (xy 79.281185 -280.776208) (xy 79.273142 -280.725426)
			(xy 78.026296 -280.725426) (xy 78.018264 -280.776137) (xy 78.002386 -280.825002) (xy 77.979059 -280.870781)
			(xy 77.948857 -280.912347) (xy 77.912524 -280.948676) (xy 77.870955 -280.978874) (xy 77.825174 -281.002197)
			(xy 77.776308 -281.018071) (xy 77.72556 -281.026104) (xy 77.69987 -281.026616) (xy 77.68712 -281.026531)
			(xy 77.661691 -281.024622) (xy 77.64907 -281.022806) (xy 77.637786 -281.021586) (xy 77.616016 -281.027901)
			(xy 77.60716 -281.034998) (xy 77.572362 -281.06624) (xy 77.566774 -281.072082) (xy 77.562234 -281.078095)
			(xy 77.556547 -281.09204) (xy 77.555598 -281.099514) (xy 77.555344 -281.10434) (xy 77.555344 -281.18181)
			(xy 77.55549 -281.187679) (xy 77.558177 -281.199105) (xy 77.560678 -281.204416) (xy 77.564996 -281.213052)
			(xy 77.621384 -281.270456) (xy 77.623162 -281.27198) (xy 77.630355 -281.277846) (xy 77.647673 -281.284482)
			(xy 77.656944 -281.284934) (xy 81.501742 -281.284934) (xy 81.51114 -281.285696) (xy 81.515712 -281.286712)
			(xy 81.540604 -281.286712) (xy 81.550482 -281.286255) (xy 81.568786 -281.278816) (xy 81.576164 -281.272234)
			(xy 81.576926 -281.271472) (xy 81.632044 -281.214322) (xy 81.637596 -281.20729) (xy 81.643838 -281.190507)
			(xy 81.644236 -281.181556) (xy 81.644236 -281.174952) (xy 81.64475 -281.148969) (xy 81.652886 -281.097643)
			(xy 81.668952 -281.048221) (xy 81.692551 -281.001922) (xy 81.723103 -280.959884) (xy 81.759854 -280.923143)
			(xy 81.8019 -280.892603) (xy 81.848206 -280.869017) (xy 81.897632 -280.852965) (xy 81.94896 -280.844842)
			(xy 81.974944 -280.844244) (xy 82.924904 -280.844244) (xy 82.950892 -280.844754) (xy 83.002229 -280.852885)
			(xy 83.051662 -280.868945) (xy 83.097975 -280.892541) (xy 83.140026 -280.92309) (xy 83.176782 -280.95984)
			(xy 83.207336 -281.001888) (xy 83.230938 -281.048197) (xy 83.247005 -281.097628) (xy 83.255143 -281.148964)
			(xy 83.255612 -281.174952) (xy 83.255612 -281.182064) (xy 83.256081 -281.191937) (xy 83.263537 -281.210223)
			(xy 83.27009 -281.217624) (xy 83.282028 -281.229816) (xy 83.32089 -281.269694) (xy 83.324192 -281.272742)
			(xy 83.33128 -281.278324) (xy 83.348197 -281.284564) (xy 83.357212 -281.284934) (xy 84.106512 -281.284934)
			(xy 84.116521 -281.284444) (xy 84.135014 -281.276784) (xy 84.149172 -281.262633) (xy 84.15684 -281.244142)
			(xy 84.157312 -281.234134) (xy 84.157312 -276.115018) (xy 84.157058 -276.111208) (xy 84.154518 -276.098508)
			(xy 83.24723 -273.90852) (xy 83.242539 -273.899681) (xy 83.227762 -273.886217) (xy 83.218528 -273.882358)
			(xy 83.187794 -273.872198) (xy 83.143852 -273.85772) (xy 83.138421 -273.8561) (xy 83.127135 -273.855081)
			(xy 83.1215 -273.855688) (xy 83.11134 -273.856958) (xy 83.102704 -273.861784) (xy 83.10118 -273.8628)
			(xy 83.08125 -273.874535) (xy 83.038864 -273.893042) (xy 82.994349 -273.905591) (xy 82.948537 -273.911946)
			(xy 82.925412 -273.91233) (xy 82.924904 -273.91233) (xy 82.898377 -273.911837) (xy 82.845975 -273.903537)
			(xy 82.795517 -273.887142) (xy 82.748246 -273.863055) (xy 82.705325 -273.831868) (xy 82.667811 -273.794351)
			(xy 82.636629 -273.751427) (xy 82.612546 -273.704153) (xy 82.596155 -273.653694) (xy 82.587861 -273.601291)
			(xy 82.587338 -273.574764) (xy 82.587808 -273.549241) (xy 82.595495 -273.498777) (xy 82.610688 -273.450044)
			(xy 82.633041 -273.404152) (xy 82.662045 -273.362147) (xy 82.697041 -273.324984) (xy 82.737229 -273.29351)
			(xy 82.781697 -273.268443) (xy 82.82943 -273.250352) (xy 82.854292 -273.244564) (xy 82.856578 -273.243802)
			(xy 82.865214 -273.237198) (xy 82.869573 -273.233608) (xy 82.876748 -273.224891) (xy 82.879438 -273.219926)
			(xy 82.914744 -273.15033) (xy 82.91898 -273.140467) (xy 82.919639 -273.119031) (xy 82.916014 -273.108928)
			(xy 82.867754 -272.992596) (xy 82.743294 -272.692368) (xy 82.383122 -271.822926) (xy 82.37149 -271.793499)
			(xy 82.3551 -271.732383) (xy 82.346814 -271.669652) (xy 82.346292 -271.638014) (xy 82.346292 -260.088634)
			(xy 82.346123 -260.082625) (xy 82.343295 -260.070944) (xy 82.340704 -260.06552) (xy 82.338867 -260.062044)
			(xy 82.334277 -260.055662) (xy 82.33156 -260.05282) (xy 71.28129 -249.00255) (xy 71.258183 -248.978664)
			(xy 71.218072 -248.925677) (xy 71.185602 -248.867692) (xy 71.161386 -248.805804) (xy 71.145881 -248.741181)
			(xy 71.142098 -248.708164) (xy 71.142098 -248.706894) (xy 71.141336 -248.701306) (xy 71.140066 -248.690638)
			(xy 71.140066 -248.671334) (xy 71.139812 -248.66092) (xy 71.139812 -242.29695) (xy 71.140066 -242.287552)
			(xy 71.140066 -242.118134) (xy 71.140551 -242.108171) (xy 71.148135 -242.089743) (xy 71.154798 -242.08232)
			(xy 71.271638 -241.96548) (xy 71.272146 -241.964718) (xy 71.286878 -241.95024) (xy 71.287894 -241.949224)
			(xy 71.408036 -241.829082) (xy 71.415448 -241.822405) (xy 71.433884 -241.814839) (xy 71.44385 -241.81435)
			(xy 71.613268 -241.81435) (xy 71.622666 -241.814096) (xy 71.623174 -241.814096) (xy 71.632572 -241.81435)
			(xy 71.80199 -241.81435) (xy 71.811957 -241.814824) (xy 71.830397 -241.822397) (xy 71.837804 -241.829082)
			(xy 71.957946 -241.949224) (xy 71.958962 -241.95024) (xy 71.973694 -241.964718) (xy 71.974202 -241.96548)
			(xy 72.091042 -242.08232) (xy 72.097718 -242.089733) (xy 72.105287 -242.108168) (xy 72.105774 -242.118134)
			(xy 72.105774 -242.287552) (xy 72.106028 -242.29695) (xy 72.106028 -248.290334) (xy 72.107044 -248.299732)
			(xy 72.107044 -248.30024) (xy 72.108754 -248.307397) (xy 72.115591 -248.320418) (xy 72.120506 -248.325894)
			(xy 76.899262 -253.104904) (xy 76.906729 -253.111563) (xy 76.925246 -253.119082) (xy 76.945231 -253.118988)
			(xy 76.954634 -253.115572) (xy 76.963701 -253.111372) (xy 76.977831 -253.097262) (xy 76.985486 -253.07882)
			(xy 76.985876 -253.068836) (xy 76.985876 -190.561722) (xy 76.986335 -190.528868) (xy 76.993689 -190.463572)
			(xy 77.008307 -190.39951) (xy 77.030005 -190.337488) (xy 77.058511 -190.278285) (xy 77.093466 -190.222645)
			(xy 77.13443 -190.171269) (xy 77.157326 -190.147702) (xy 88.900762 -178.404012) (xy 88.924317 -178.381066)
			(xy 88.975716 -178.340047) (xy 89.031387 -178.305044) (xy 89.09063 -178.276499) (xy 89.152697 -178.254771)
			(xy 89.216808 -178.240132) (xy 89.282156 -178.232769) (xy 89.315036 -178.232308) (xy 98.611182 -178.232308)
			(xy 98.643577 -178.232758) (xy 98.70797 -178.239936) (xy 98.771177 -178.254173) (xy 98.832428 -178.275296)
			(xy 98.890975 -178.303047) (xy 98.918776 -178.319684) (xy 98.919792 -178.320446) (xy 98.923602 -178.322732)
			(xy 98.92538 -178.323494) (xy 98.925634 -178.323748) (xy 98.926142 -178.323748) (xy 98.937318 -178.331368)
			(xy 98.938842 -178.332638) (xy 98.941128 -178.334416) (xy 98.942906 -178.335686) (xy 98.96476 -178.351088)
			(xy 99.005848 -178.385303) (xy 99.024948 -178.404012) (xy 101.95941 -181.338728) (xy 101.964192 -181.343196)
			(xy 101.975507 -181.349759) (xy 101.981762 -181.351682) (xy 101.995224 -181.35346) (xy 108.0897 -181.35346)
			(xy 108.100232 -181.352868) (xy 108.119497 -181.344329) (xy 108.127038 -181.33695) (xy 108.13358 -181.329232)
			(xy 108.140509 -181.310239) (xy 108.1405 -181.30012) (xy 108.139738 -181.291992) (xy 108.138214 -181.27599)
			(xy 108.136944 -181.268116) (xy 108.135928 -181.263544) (xy 108.133991 -181.256889) (xy 108.12702 -181.244916)
			(xy 108.122212 -181.239922) (xy 108.119418 -181.237382) (xy 108.114846 -181.233318) (xy 108.114592 -181.233064)
			(xy 108.095147 -181.2164) (xy 108.060464 -181.178722) (xy 108.031147 -181.136734) (xy 108.007726 -181.091193)
			(xy 107.998768 -181.067202) (xy 107.988659 -181.036878) (xy 107.977557 -180.973933) (xy 107.97667 -180.94198)
			(xy 107.97667 -180.939186) (xy 107.976924 -180.926486) (xy 107.976924 -180.92293) (xy 107.977178 -180.918104)
			(xy 107.977178 -180.91785) (xy 107.979162 -180.891343) (xy 107.989543 -180.839212) (xy 108.00705 -180.789023)
			(xy 108.031345 -180.741746) (xy 108.06196 -180.698293) (xy 108.079794 -180.678582) (xy 108.086906 -180.670962)
			(xy 108.090208 -180.662326) (xy 108.09097 -180.660548) (xy 108.092204 -180.6566) (xy 108.093486 -180.648428)
			(xy 108.09351 -180.644292) (xy 108.09351 -180.574188) (xy 108.09344 -180.570056) (xy 108.092159 -180.561891)
			(xy 108.09097 -180.557932) (xy 108.090208 -180.556154) (xy 108.086906 -180.547518) (xy 108.079794 -180.539898)
			(xy 108.060522 -180.518571) (xy 108.027954 -180.471209) (xy 108.00286 -180.419498) (xy 107.985805 -180.364607)
			(xy 107.977177 -180.307779) (xy 107.97667 -180.27904) (xy 107.97713 -180.251785) (xy 107.984882 -180.197828)
			(xy 108.000235 -180.145524) (xy 108.022875 -180.095938) (xy 108.052341 -180.050078) (xy 108.088035 -180.008879)
			(xy 108.129228 -179.973178) (xy 108.175083 -179.943704) (xy 108.224666 -179.921056) (xy 108.276968 -179.905696)
			(xy 108.330923 -179.897935) (xy 108.358178 -179.897532) (xy 108.358686 -179.897532) (xy 108.388137 -179.898101)
			(xy 108.446332 -179.907196) (xy 108.502439 -179.925126) (xy 108.555124 -179.951465) (xy 108.603136 -179.985588)
			(xy 108.624624 -180.005736) (xy 108.627926 -180.009292) (xy 108.631482 -180.012594) (xy 108.66628 -180.027326)
			(xy 108.676186 -180.02758) (xy 108.737654 -180.02885) (xy 108.738162 -180.02885) (xy 108.759752 -180.029358)
			(xy 108.777867 -180.010461) (xy 108.818373 -179.977302) (xy 108.86303 -179.949989) (xy 108.910999 -179.929032)
			(xy 108.961382 -179.914825) (xy 109.013233 -179.907634) (xy 109.039406 -179.907184) (xy 109.039914 -179.907184)
			(xy 109.071664 -179.908708) (xy 109.07649 -179.909216) (xy 109.076744 -179.909216) (xy 109.078014 -179.90947)
			(xy 109.089794 -179.910735) (xy 109.113179 -179.914548) (xy 109.12475 -179.91709) (xy 109.152247 -179.923914)
			(xy 109.204997 -179.944578) (xy 109.254116 -179.972806) (xy 109.276642 -179.989988) (xy 109.27715 -179.990242)
			(xy 109.28477 -179.996084) (xy 109.292898 -179.998878) (xy 109.303566 -180.001164) (xy 109.308646 -180.001418)
			(xy 109.33049 -180.001418) (xy 109.33593 -180.001557) (xy 109.346566 -180.003857) (xy 109.351572 -180.00599)
			(xy 109.356652 -180.00853) (xy 109.363654 -180.011852) (xy 109.378905 -180.014562) (xy 109.386624 -180.013864)
			(xy 109.402118 -180.011832) (xy 109.406436 -180.007768) (xy 109.408214 -180.00599) (xy 109.41177 -180.002688)
			(xy 109.433381 -179.983553) (xy 109.4812 -179.951227) (xy 109.533276 -179.926334) (xy 109.588464 -179.909423)
			(xy 109.645546 -179.900867) (xy 109.674406 -179.900326) (xy 109.67466 -179.900326) (xy 109.701533 -179.9008)
			(xy 109.75476 -179.908246) (xy 109.806452 -179.922961) (xy 109.855621 -179.944663) (xy 109.901329 -179.972937)
			(xy 109.92231 -179.989734) (xy 109.929168 -179.995322) (xy 109.93755 -179.99837) (xy 109.941729 -179.999781)
			(xy 109.950413 -180.001315) (xy 109.954822 -180.001418) (xy 109.96549 -180.001418) (xy 109.97093 -180.001557)
			(xy 109.981566 -180.003857) (xy 109.986572 -180.00599) (xy 109.991652 -180.00853) (xy 109.998654 -180.011852)
			(xy 110.013905 -180.014562) (xy 110.021624 -180.013864) (xy 110.037118 -180.011832) (xy 110.041436 -180.007768)
			(xy 110.043214 -180.00599) (xy 110.04677 -180.002688) (xy 110.068381 -179.983553) (xy 110.1162 -179.951227)
			(xy 110.168276 -179.926334) (xy 110.223464 -179.909423) (xy 110.280546 -179.900867) (xy 110.309406 -179.900326)
			(xy 110.30966 -179.900326) (xy 110.336533 -179.9008) (xy 110.38976 -179.908246) (xy 110.441452 -179.922961)
			(xy 110.490621 -179.944663) (xy 110.536329 -179.972937) (xy 110.55731 -179.989734) (xy 110.564168 -179.995322)
			(xy 110.57255 -179.99837) (xy 110.576729 -179.999781) (xy 110.585413 -180.001315) (xy 110.589822 -180.001418)
			(xy 110.60049 -180.001418) (xy 110.60593 -180.001557) (xy 110.616566 -180.003857) (xy 110.621572 -180.00599)
			(xy 110.626652 -180.00853) (xy 110.633654 -180.011852) (xy 110.648905 -180.014562) (xy 110.656624 -180.013864)
			(xy 110.672118 -180.011832) (xy 110.676436 -180.007768) (xy 110.678214 -180.00599) (xy 110.68177 -180.002688)
			(xy 110.703381 -179.983553) (xy 110.7512 -179.951227) (xy 110.803276 -179.926334) (xy 110.858464 -179.909423)
			(xy 110.915546 -179.900867) (xy 110.944406 -179.900326) (xy 110.94466 -179.900326) (xy 110.971533 -179.9008)
			(xy 111.02476 -179.908246) (xy 111.076452 -179.922961) (xy 111.125621 -179.944663) (xy 111.171329 -179.972937)
			(xy 111.19231 -179.989734) (xy 111.199168 -179.995322) (xy 111.20755 -179.99837) (xy 111.211729 -179.999781)
			(xy 111.220413 -180.001315) (xy 111.224822 -180.001418) (xy 111.23549 -180.001418) (xy 111.24093 -180.001557)
			(xy 111.251566 -180.003857) (xy 111.256572 -180.00599) (xy 111.261652 -180.00853) (xy 111.268654 -180.011852)
			(xy 111.283905 -180.014562) (xy 111.291624 -180.013864) (xy 111.307118 -180.011832) (xy 111.311436 -180.007768)
			(xy 111.313214 -180.00599) (xy 111.31677 -180.002688) (xy 111.338381 -179.983553) (xy 111.3862 -179.951227)
			(xy 111.438276 -179.926334) (xy 111.493464 -179.909423) (xy 111.550546 -179.900867) (xy 111.579406 -179.900326)
			(xy 111.57966 -179.900326) (xy 111.607422 -179.900795) (xy 111.66238 -179.908692) (xy 111.715655 -179.924332)
			(xy 111.766162 -179.947395) (xy 111.812871 -179.977412) (xy 111.854833 -180.013771) (xy 111.891192 -180.055734)
			(xy 111.921208 -180.102444) (xy 111.94427 -180.152951) (xy 111.959909 -180.206226) (xy 111.967805 -180.261184)
			(xy 111.96828 -180.288946) (xy 111.96773 -180.318891) (xy 111.958542 -180.378072) (xy 111.940376 -180.43514)
			(xy 111.913663 -180.488742) (xy 111.879036 -180.537607) (xy 111.858552 -180.559456) (xy 111.851694 -180.566568)
			(xy 111.847884 -180.575712) (xy 111.84636 -180.580284) (xy 111.845413 -180.583763) (xy 111.844395 -180.590902)
			(xy 111.844328 -180.594508) (xy 111.844328 -180.653944) (xy 111.845344 -180.66385) (xy 111.847122 -180.670454)
			(xy 111.848839 -180.675108) (xy 111.853828 -180.683681) (xy 111.857028 -180.687472) (xy 111.858044 -180.688488)
			(xy 111.877315 -180.709815) (xy 111.909881 -180.757178) (xy 111.934975 -180.808889) (xy 111.95203 -180.86378)
			(xy 111.960659 -180.920607) (xy 111.961168 -180.949346) (xy 111.960718 -180.977473) (xy 111.952571 -181.033134)
			(xy 111.936357 -181.087) (xy 111.924846 -181.112668) (xy 111.921036 -181.120034) (xy 111.917734 -181.126638)
			(xy 111.903854 -181.151909) (xy 111.869669 -181.198334) (xy 111.849662 -181.219094) (xy 111.849408 -181.219348)
			(xy 111.847122 -181.221634) (xy 111.828326 -181.24043) (xy 111.823683 -181.245408) (xy 111.816984 -181.257252)
			(xy 111.815118 -181.263798) (xy 111.813594 -181.26964) (xy 111.813848 -181.277006) (xy 111.81416 -181.28091)
			(xy 111.815821 -181.288562) (xy 111.81715 -181.292246) (xy 111.822992 -181.30774) (xy 111.82985 -181.325774)
			(xy 111.82985 -181.326028) (xy 111.833406 -181.335426) (xy 111.846106 -181.344316) (xy 111.852663 -181.348529)
			(xy 111.867528 -181.353185) (xy 111.875316 -181.35346) (xy 121.784364 -181.35346) (xy 121.792072 -181.353228)
			(xy 121.806805 -181.348698) (xy 121.81332 -181.34457) (xy 121.817384 -181.341268) (xy 123.558554 -179.600098)
			(xy 123.55957 -179.598828) (xy 123.566815 -179.590311) (xy 123.573784 -179.569092) (xy 123.573032 -179.557934)
			(xy 123.572016 -179.552346) (xy 123.551696 -179.468018) (xy 123.549875 -179.461591) (xy 123.543446 -179.449886)
			(xy 123.538996 -179.444904) (xy 123.534622 -179.440532) (xy 123.524218 -179.433852) (xy 123.518422 -179.431696)
			(xy 123.51766 -179.431442) (xy 123.490248 -179.422255) (xy 123.437803 -179.397925) (xy 123.388838 -179.367185)
			(xy 123.344134 -179.330525) (xy 123.3044 -179.288528) (xy 123.270271 -179.241863) (xy 123.242288 -179.191272)
			(xy 123.220898 -179.13756) (xy 123.206441 -179.081583) (xy 123.199146 -179.024231) (xy 123.198636 -178.995324)
			(xy 123.198636 -178.131724) (xy 123.199124 -178.101767) (xy 123.206939 -178.042365) (xy 123.222439 -177.98449)
			(xy 123.245359 -177.929133) (xy 123.275306 -177.877241) (xy 123.311769 -177.8297) (xy 123.354124 -177.787323)
			(xy 123.401646 -177.750836) (xy 123.453523 -177.720862) (xy 123.508869 -177.697914) (xy 123.566735 -177.682385)
			(xy 123.626133 -177.674539) (xy 123.65609 -177.674016) (xy 123.656598 -177.674016) (xy 123.684369 -177.674379)
			(xy 123.739513 -177.681002) (xy 123.76658 -177.687224) (xy 123.771914 -177.688494) (xy 123.775724 -177.68951)
			(xy 123.781758 -177.690465) (xy 123.793956 -177.689831) (xy 123.799854 -177.68824) (xy 123.804303 -177.686847)
			(xy 123.812619 -177.682635) (xy 123.816364 -177.679858) (xy 123.879864 -177.630582) (xy 123.888738 -177.623002)
			(xy 123.899072 -177.602103) (xy 123.899676 -177.59045) (xy 123.899676 -171.933362) (xy 123.900124 -171.900674)
			(xy 123.907403 -171.835706) (xy 123.921878 -171.771953) (xy 123.943367 -171.710211) (xy 123.971603 -171.651248)
			(xy 124.006235 -171.595799) (xy 124.026168 -171.569888) (xy 124.028434 -171.566282) (xy 124.031885 -171.558497)
			(xy 124.033026 -171.554394) (xy 124.034804 -171.54144) (xy 124.034804 -171.11218) (xy 124.035272 -171.079913)
			(xy 124.042521 -171.015786) (xy 124.056893 -170.952871) (xy 124.078207 -170.891957) (xy 124.106196 -170.833807)
			(xy 124.14051 -170.77915) (xy 124.180718 -170.728671) (xy 124.203206 -170.705526) (xy 125.615954 -169.292778)
			(xy 125.616462 -169.29227) (xy 125.624029 -169.283603) (xy 125.63141 -169.261843) (xy 125.630686 -169.25036)
			(xy 125.629924 -169.245026) (xy 125.629416 -169.242486) (xy 125.629416 -169.242232) (xy 125.629162 -169.240454)
			(xy 125.624946 -169.220268) (xy 125.620365 -169.179284) (xy 125.620018 -169.158666) (xy 125.620018 -169.157904)
			(xy 125.620504 -169.130634) (xy 125.628265 -169.076649) (xy 125.64363 -169.024318) (xy 125.666286 -168.974706)
			(xy 125.695771 -168.928823) (xy 125.731486 -168.887603) (xy 125.772704 -168.851886) (xy 125.818585 -168.822397)
			(xy 125.868195 -168.799738) (xy 125.920525 -168.78437) (xy 125.97451 -168.776606) (xy 126.00178 -168.776142)
			(xy 126.002542 -168.776142) (xy 126.023678 -168.776439) (xy 126.065686 -168.781149) (xy 126.086362 -168.78554)
			(xy 126.088902 -168.786048) (xy 126.094236 -168.78681) (xy 126.101828 -168.787467) (xy 126.116814 -168.784742)
			(xy 126.1237 -168.781476) (xy 126.127174 -168.779637) (xy 126.133553 -168.775043) (xy 126.1364 -168.772332)
			(xy 126.527814 -168.380918) (xy 126.550955 -168.358422) (xy 126.601419 -168.318186) (xy 126.65607 -168.283852)
			(xy 126.71422 -168.255851) (xy 126.77514 -168.234536) (xy 126.838063 -168.220174) (xy 126.902198 -168.212945)
			(xy 126.934468 -168.212516) (xy 127.521462 -168.212516) (xy 127.526034 -168.211754) (xy 127.551846 -168.207372)
			(xy 127.603994 -168.202662) (xy 127.630174 -168.202356) (xy 131.096512 -168.202356) (xy 131.104223 -168.202131)
			(xy 131.118964 -168.197613) (xy 131.125468 -168.193466) (xy 131.129532 -168.190164) (xy 131.363974 -167.955722)
			(xy 131.38275 -167.937338) (xy 131.42307 -167.903631) (xy 131.444492 -167.888412) (xy 131.446778 -167.886888)
			(xy 131.448556 -167.885618) (xy 131.52501 -167.809418) (xy 131.532355 -167.802607) (xy 131.550817 -167.794876)
			(xy 131.560824 -167.794432) (xy 131.668774 -167.794432) (xy 131.673346 -167.79367) (xy 131.699347 -167.789263)
			(xy 131.751877 -167.784554) (xy 131.778248 -167.784272) (xy 131.80462 -167.784536) (xy 131.857152 -167.789238)
			(xy 131.88315 -167.79367) (xy 131.887722 -167.794432) (xy 131.995672 -167.794432) (xy 132.005661 -167.794965)
			(xy 132.024098 -167.802675) (xy 132.031486 -167.809418) (xy 132.107178 -167.88511) (xy 132.110988 -167.88765)
			(xy 132.139889 -167.908217) (xy 132.192988 -167.955255) (xy 132.240021 -168.008359) (xy 132.260594 -168.037256)
			(xy 132.263134 -168.041066) (xy 132.338826 -168.116758) (xy 132.345636 -168.124103) (xy 132.353359 -168.142566)
			(xy 132.353812 -168.152572) (xy 132.353812 -168.260522) (xy 132.354574 -168.265094) (xy 132.358979 -168.291095)
			(xy 132.363685 -168.343626) (xy 132.363972 -168.369996) (xy 132.363706 -168.396367) (xy 132.358999 -168.448899)
			(xy 132.354574 -168.474898) (xy 132.353812 -168.47947) (xy 132.353812 -168.58742) (xy 132.353271 -168.597406)
			(xy 132.345554 -168.615834) (xy 132.338826 -168.623234) (xy 132.262626 -168.699688) (xy 132.262286 -168.700164)
			(xy 133.213906 -168.700164) (xy 133.213906 -168.640236) (xy 133.221728 -168.58082) (xy 133.237237 -168.522933)
			(xy 133.26017 -168.467566) (xy 133.290132 -168.415665) (xy 133.326612 -168.368119) (xy 133.368986 -168.325742)
			(xy 133.416529 -168.289257) (xy 133.468426 -168.259289) (xy 133.523791 -168.236351) (xy 133.581677 -168.220836)
			(xy 133.641092 -168.213009) (xy 133.671056 -168.212516) (xy 134.534656 -168.212516) (xy 134.564628 -168.212934)
			(xy 134.624061 -168.220754) (xy 134.681965 -168.236264) (xy 134.737348 -168.2592) (xy 134.789264 -168.289169)
			(xy 134.836823 -168.325658) (xy 134.879213 -168.368044) (xy 134.915707 -168.4156) (xy 134.945681 -168.467512)
			(xy 134.968622 -168.522894) (xy 134.984138 -168.580796) (xy 134.991963 -168.640228) (xy 134.991963 -168.700172)
			(xy 134.984138 -168.759604) (xy 134.968622 -168.817506) (xy 134.945681 -168.872888) (xy 134.915707 -168.9248)
			(xy 134.879213 -168.972356) (xy 134.836823 -169.014742) (xy 134.789264 -169.051231) (xy 134.737348 -169.0812)
			(xy 134.681965 -169.104136) (xy 134.624061 -169.119646) (xy 134.564628 -169.127466) (xy 134.534656 -169.127932)
			(xy 133.671056 -169.127932) (xy 133.641092 -169.127391) (xy 133.581677 -169.119564) (xy 133.523791 -169.104049)
			(xy 133.468426 -169.081111) (xy 133.416529 -169.051143) (xy 133.368986 -169.014658) (xy 133.326612 -168.972281)
			(xy 133.290132 -168.924735) (xy 133.26017 -168.872834) (xy 133.237237 -168.817467) (xy 133.221728 -168.75958)
			(xy 133.213906 -168.700164) (xy 132.262286 -168.700164) (xy 132.261356 -168.701466) (xy 132.259832 -168.703752)
			(xy 132.244612 -168.725173) (xy 132.210909 -168.765496) (xy 132.192522 -168.78427) (xy 132.102606 -168.874186)
			(xy 132.099605 -168.877276) (xy 132.094625 -168.884303) (xy 132.0927 -168.888156) (xy 132.089144 -168.895776)
			(xy 132.088382 -168.903904) (xy 132.10286 -168.92905) (xy 132.103368 -168.930066) (xy 132.11091 -168.942683)
			(xy 132.124261 -168.968873) (xy 132.130038 -168.98239) (xy 132.131308 -168.985438) (xy 132.133888 -168.990313)
			(xy 132.140809 -168.998898) (xy 132.145024 -169.002456) (xy 132.160518 -169.014902) (xy 132.164574 -169.018034)
			(xy 132.173662 -169.022767) (xy 132.178552 -169.0243) (xy 132.244592 -169.03954) (xy 132.245354 -169.03954)
			(xy 132.247386 -169.040048) (xy 132.254752 -169.04081) (xy 132.259279 -169.040795) (xy 132.268221 -169.039395)
			(xy 132.272532 -169.038016) (xy 132.2832 -169.033698) (xy 132.290058 -169.03065) (xy 132.301742 -169.023792)
			(xy 132.305552 -169.021252) (xy 132.306822 -169.019982) (xy 132.32764 -169.002848) (xy 132.373188 -168.973996)
			(xy 132.422345 -168.951846) (xy 132.47413 -168.936837) (xy 132.527513 -168.92927) (xy 132.554472 -168.928796)
			(xy 132.581744 -168.92928) (xy 132.635733 -168.937039) (xy 132.688068 -168.952401) (xy 132.737684 -168.975055)
			(xy 132.783572 -169.00454) (xy 132.824796 -169.040254) (xy 132.860518 -169.081472) (xy 132.890011 -169.127354)
			(xy 132.912674 -169.176966) (xy 132.928046 -169.229299) (xy 132.935815 -169.283286) (xy 132.936234 -169.310558)
			(xy 132.935726 -169.338814) (xy 132.927399 -169.394708) (xy 132.91092 -169.448763) (xy 132.886651 -169.499797)
			(xy 132.855121 -169.546694) (xy 132.81702 -169.588429) (xy 132.773181 -169.624089) (xy 132.724563 -169.652895)
			(xy 132.672228 -169.674216) (xy 132.644896 -169.681398) (xy 132.644134 -169.681652) (xy 132.64134 -169.682414)
			(xy 132.636006 -169.684192) (xy 132.626354 -169.68851) (xy 132.620512 -169.69232) (xy 132.402834 -169.909998)
			(xy 132.384618 -169.92755) (xy 132.343693 -169.957282) (xy 132.298619 -169.98024) (xy 132.250507 -169.99586)
			(xy 132.200542 -170.003755) (xy 132.17525 -170.004232) (xy 131.58851 -170.004232) (xy 131.574024 -170.004785)
			(xy 131.546239 -170.013004) (xy 131.521883 -170.028699) (xy 131.502917 -170.050605) (xy 131.490869 -170.076957)
			(xy 131.48671 -170.105632) (xy 131.48818 -170.120056) (xy 131.489634 -170.128096) (xy 131.496896 -170.142722)
			(xy 131.502404 -170.148758) (xy 133.053074 -171.699428) (xy 133.071459 -171.718203) (xy 133.105169 -171.758521)
			(xy 133.120384 -171.779946) (xy 133.122924 -171.783756) (xy 133.199378 -171.860464) (xy 133.206181 -171.867812)
			(xy 133.213893 -171.886275) (xy 133.214364 -171.896278) (xy 133.214364 -172.004228) (xy 133.215126 -172.0088)
			(xy 133.219531 -172.034801) (xy 133.224235 -172.087332) (xy 133.224524 -172.113702) (xy 133.224258 -172.140073)
			(xy 133.219551 -172.192605) (xy 133.215126 -172.218604) (xy 133.214364 -172.223176) (xy 133.214364 -172.331126)
			(xy 133.213821 -172.34111) (xy 133.206097 -172.359532) (xy 133.199378 -172.36694) (xy 133.123178 -172.443394)
			(xy 133.121908 -172.445172) (xy 133.120384 -172.447458) (xy 133.100002 -172.475968) (xy 133.053495 -172.528397)
			(xy 133.001065 -172.574904) (xy 132.972556 -172.595286) (xy 132.97027 -172.59681) (xy 132.968492 -172.59808)
			(xy 132.892038 -172.67428) (xy 132.88469 -172.681083) (xy 132.866227 -172.688796) (xy 132.856224 -172.689266)
			(xy 132.748274 -172.689266) (xy 132.743702 -172.690028) (xy 132.717707 -172.69451) (xy 132.665176 -172.699342)
			(xy 132.6388 -172.69968) (xy 132.612424 -172.699345) (xy 132.559892 -172.694512) (xy 132.533898 -172.690028)
			(xy 132.529326 -172.689266) (xy 132.421376 -172.689266) (xy 132.411391 -172.688724) (xy 132.392969 -172.681)
			(xy 132.385562 -172.67428) (xy 132.309108 -172.59808) (xy 132.30733 -172.59681) (xy 132.305044 -172.595286)
			(xy 132.283623 -172.580065) (xy 132.243303 -172.54636) (xy 132.224526 -172.527976) (xy 129.607818 -169.911268)
			(xy 129.604969 -169.90856) (xy 129.598593 -169.903962) (xy 129.595118 -169.902124) (xy 129.589691 -169.899544)
			(xy 129.578011 -169.896728) (xy 129.572004 -169.896536) (xy 128.056894 -169.896536) (xy 128.050883 -169.896698)
			(xy 128.039197 -169.899515) (xy 128.03378 -169.902124) (xy 128.030306 -169.903964) (xy 128.023929 -169.90856)
			(xy 128.02108 -169.911268) (xy 125.637036 -172.295312) (xy 125.636528 -172.30217) (xy 125.636528 -173.089062)
			(xy 126.182628 -173.089062) (xy 126.183124 -173.061693) (xy 126.190933 -173.007515) (xy 126.206415 -172.955012)
			(xy 126.22925 -172.905264) (xy 126.258969 -172.859296) (xy 126.276608 -172.838364) (xy 126.276862 -172.83811)
			(xy 126.282458 -172.83103) (xy 126.288697 -172.814108) (xy 126.289054 -172.80509) (xy 126.289054 -172.738034)
			(xy 126.288691 -172.729018) (xy 126.282449 -172.7121) (xy 126.276862 -172.705014) (xy 126.276608 -172.705014)
			(xy 126.276608 -172.70476) (xy 126.258985 -172.683815) (xy 126.22927 -172.637846) (xy 126.206431 -172.588102)
			(xy 126.190936 -172.535604) (xy 126.183104 -172.48143) (xy 126.182628 -172.454062) (xy 126.183114 -172.426811)
			(xy 126.19087 -172.372863) (xy 126.206225 -172.320568) (xy 126.228867 -172.270991) (xy 126.258333 -172.225141)
			(xy 126.294024 -172.18395) (xy 126.335215 -172.148259) (xy 126.381065 -172.118793) (xy 126.430642 -172.096151)
			(xy 126.482937 -172.080796) (xy 126.536885 -172.07304) (xy 126.591387 -172.07304) (xy 126.645335 -172.080796)
			(xy 126.69763 -172.096151) (xy 126.747207 -172.118793) (xy 126.793057 -172.148259) (xy 126.834248 -172.18395)
			(xy 126.869939 -172.225141) (xy 126.877491 -172.236892) (xy 127.879346 -172.236892) (xy 127.883417 -172.18127)
			(xy 127.895543 -172.126833) (xy 127.915466 -172.074742) (xy 127.942762 -172.026107) (xy 127.976848 -171.981964)
			(xy 128.016997 -171.943255) (xy 128.062355 -171.910804) (xy 128.111955 -171.885303) (xy 128.164739 -171.867296)
			(xy 128.219582 -171.857166) (xy 128.275316 -171.855129) (xy 128.330753 -171.861229) (xy 128.38471 -171.875335)
			(xy 128.436039 -171.897147) (xy 128.483645 -171.926201) (xy 128.526513 -171.961876) (xy 128.56373 -172.003413)
			(xy 128.594503 -172.049926) (xy 128.618175 -172.100423) (xy 128.634243 -172.15383) (xy 128.642363 -172.209006)
			(xy 128.642872 -172.236892) (xy 128.642363 -172.264778) (xy 128.634243 -172.319954) (xy 128.618175 -172.373361)
			(xy 128.594503 -172.423858) (xy 128.56373 -172.470371) (xy 128.526513 -172.511908) (xy 128.483645 -172.547583)
			(xy 128.436039 -172.576637) (xy 128.38471 -172.598449) (xy 128.330753 -172.612555) (xy 128.275316 -172.618655)
			(xy 128.219582 -172.616618) (xy 128.164739 -172.606488) (xy 128.111955 -172.588481) (xy 128.062355 -172.56298)
			(xy 128.016997 -172.530529) (xy 127.976848 -172.49182) (xy 127.942762 -172.447677) (xy 127.915466 -172.399042)
			(xy 127.895543 -172.346951) (xy 127.883417 -172.292514) (xy 127.879346 -172.236892) (xy 126.877491 -172.236892)
			(xy 126.899405 -172.270991) (xy 126.922047 -172.320568) (xy 126.937402 -172.372863) (xy 126.945158 -172.426811)
			(xy 126.945644 -172.454062) (xy 126.945169 -172.481432) (xy 126.937356 -172.535611) (xy 126.921869 -172.588115)
			(xy 126.899029 -172.637862) (xy 126.869305 -172.683829) (xy 126.851664 -172.70476) (xy 126.85141 -172.705014)
			(xy 126.845813 -172.712093) (xy 126.839572 -172.729016) (xy 126.839218 -172.738034) (xy 126.839218 -172.80509)
			(xy 126.839576 -172.814107) (xy 126.845822 -172.831024) (xy 126.85141 -172.83811) (xy 126.851664 -172.83811)
			(xy 126.851664 -172.838364) (xy 126.869294 -172.859303) (xy 126.899009 -172.905274) (xy 126.921847 -172.955019)
			(xy 126.93734 -173.007518) (xy 126.945169 -173.061693) (xy 126.945644 -173.089062) (xy 126.945158 -173.116313)
			(xy 126.937402 -173.170261) (xy 126.922047 -173.222556) (xy 126.899405 -173.272133) (xy 126.869939 -173.317983)
			(xy 126.834248 -173.359174) (xy 126.793057 -173.394865) (xy 126.747207 -173.424331) (xy 126.69763 -173.446973)
			(xy 126.645335 -173.462328) (xy 126.591387 -173.470084) (xy 126.536885 -173.470084) (xy 126.482937 -173.462328)
			(xy 126.430642 -173.446973) (xy 126.381065 -173.424331) (xy 126.335215 -173.394865) (xy 126.294024 -173.359174)
			(xy 126.258333 -173.317983) (xy 126.228867 -173.272133) (xy 126.206225 -173.222556) (xy 126.19087 -173.170261)
			(xy 126.183114 -173.116313) (xy 126.182628 -173.089062) (xy 125.636528 -173.089062) (xy 125.636528 -173.544484)
			(xy 129.265932 -173.544484) (xy 129.270003 -173.488862) (xy 129.282129 -173.434425) (xy 129.302052 -173.382334)
			(xy 129.329348 -173.333699) (xy 129.363434 -173.289556) (xy 129.403583 -173.250847) (xy 129.448941 -173.218396)
			(xy 129.498541 -173.192895) (xy 129.551325 -173.174888) (xy 129.606168 -173.164758) (xy 129.661902 -173.162721)
			(xy 129.717339 -173.168821) (xy 129.771296 -173.182927) (xy 129.822625 -173.204739) (xy 129.870231 -173.233793)
			(xy 129.913099 -173.269468) (xy 129.950316 -173.311005) (xy 129.981089 -173.357518) (xy 130.004761 -173.408015)
			(xy 130.020829 -173.461422) (xy 130.028949 -173.516598) (xy 130.029458 -173.544484) (xy 130.028949 -173.57237)
			(xy 130.020829 -173.627546) (xy 130.004761 -173.680953) (xy 129.981089 -173.73145) (xy 129.950316 -173.777963)
			(xy 129.913099 -173.8195) (xy 129.870231 -173.855175) (xy 129.822625 -173.884229) (xy 129.771296 -173.906041)
			(xy 129.717339 -173.920147) (xy 129.661902 -173.926247) (xy 129.606168 -173.92421) (xy 129.551325 -173.91408)
			(xy 129.498541 -173.896073) (xy 129.448941 -173.870572) (xy 129.403583 -173.838121) (xy 129.363434 -173.799412)
			(xy 129.329348 -173.755269) (xy 129.302052 -173.706634) (xy 129.282129 -173.654543) (xy 129.270003 -173.600106)
			(xy 129.265932 -173.544484) (xy 125.636528 -173.544484) (xy 125.636528 -175.437038) (xy 125.636674 -175.442764)
			(xy 125.639232 -175.453925) (xy 125.641608 -175.459136) (xy 125.66777 -175.470058) (xy 125.677074 -175.473442)
			(xy 125.696853 -175.473575) (xy 125.715198 -175.466184) (xy 125.722634 -175.459644) (xy 126.536196 -174.646082)
			(xy 126.555754 -174.628048) (xy 126.566281 -174.61932) (xy 126.588534 -174.603425) (xy 126.600204 -174.596298)
			(xy 126.601982 -174.595028) (xy 126.62281 -174.5742) (xy 126.630156 -174.567391) (xy 126.648618 -174.559663)
			(xy 126.658624 -174.559214) (xy 126.688596 -174.559214) (xy 126.694438 -174.557944) (xy 126.713268 -174.553704)
			(xy 126.751593 -174.549125) (xy 126.770892 -174.5488) (xy 130.400552 -174.5488) (xy 130.410204 -174.547784)
			(xy 130.417445 -174.54615) (xy 130.430606 -174.539301) (xy 130.436112 -174.534322) (xy 130.559556 -174.410878)
			(xy 130.579114 -174.392844) (xy 130.58964 -174.384116) (xy 130.611892 -174.368218) (xy 130.623564 -174.361094)
			(xy 130.625342 -174.359824) (xy 130.64617 -174.338996) (xy 130.653519 -174.332197) (xy 130.671982 -174.32449)
			(xy 130.681984 -174.32401) (xy 130.711956 -174.32401) (xy 130.717798 -174.32274) (xy 130.736627 -174.318497)
			(xy 130.774953 -174.313914) (xy 130.794252 -174.313596) (xy 131.99237 -174.313596) (xy 131.999482 -174.313088)
			(xy 132.006502 -174.311849) (xy 132.019515 -174.306043) (xy 132.025136 -174.301658) (xy 132.09397 -174.232824)
			(xy 132.097994 -174.22854) (xy 132.10416 -174.218538) (xy 132.106162 -174.213012) (xy 132.106416 -174.21225)
			(xy 132.114826 -174.186623) (xy 132.137852 -174.13785) (xy 132.167514 -174.092804) (xy 132.203222 -174.052382)
			(xy 132.244264 -174.017388) (xy 132.289824 -173.988521) (xy 132.338993 -173.966354) (xy 132.390793 -173.951329)
			(xy 132.444192 -173.943745) (xy 132.47116 -173.943264) (xy 132.498432 -173.943725) (xy 132.552422 -173.951482)
			(xy 132.604758 -173.966845) (xy 132.654375 -173.989501) (xy 132.700261 -174.018988) (xy 132.741484 -174.054706)
			(xy 132.777203 -174.095927) (xy 132.806692 -174.141813) (xy 132.82935 -174.191429) (xy 132.844715 -174.243764)
			(xy 132.852474 -174.297754) (xy 132.852922 -174.325026) (xy 132.852456 -174.352004) (xy 132.844864 -174.405424)
			(xy 132.829835 -174.457246) (xy 132.807667 -174.506438) (xy 132.778802 -174.552025) (xy 132.743812 -174.593098)
			(xy 132.703394 -174.628843) (xy 132.65835 -174.658548) (xy 132.609577 -174.681623) (xy 132.583936 -174.690024)
			(xy 132.578094 -174.691802) (xy 132.57276 -174.69485) (xy 132.562854 -174.702724) (xy 132.385308 -174.88027)
			(xy 132.36575 -174.898304) (xy 132.355222 -174.907031) (xy 132.332968 -174.922924) (xy 132.3213 -174.930054)
			(xy 132.319522 -174.931324) (xy 132.298694 -174.952152) (xy 132.291351 -174.958967) (xy 132.272888 -174.966705)
			(xy 132.26288 -174.967138) (xy 132.232908 -174.967138) (xy 132.227066 -174.968408) (xy 132.208236 -174.972649)
			(xy 132.169911 -174.977227) (xy 132.150612 -174.977552) (xy 130.952748 -174.977552) (xy 130.946738 -174.977719)
			(xy 130.935055 -174.980541) (xy 130.929634 -174.98314) (xy 130.926159 -174.984978) (xy 130.919778 -174.989569)
			(xy 130.916934 -174.992284) (xy 130.793744 -175.115474) (xy 130.774186 -175.133508) (xy 130.763659 -175.142235)
			(xy 130.741406 -175.158131) (xy 130.729736 -175.165258) (xy 130.727958 -175.166528) (xy 130.70713 -175.187356)
			(xy 130.699783 -175.19416) (xy 130.68132 -175.201874) (xy 130.671316 -175.202342) (xy 130.641344 -175.202342)
			(xy 130.635502 -175.203612) (xy 130.616673 -175.207855) (xy 130.578347 -175.212437) (xy 130.559048 -175.212756)
			(xy 126.929388 -175.212756) (xy 126.923377 -175.212919) (xy 126.91169 -175.215732) (xy 126.906274 -175.218344)
			(xy 126.902801 -175.220185) (xy 126.896426 -175.224782) (xy 126.893574 -175.227488) (xy 125.84684 -176.274222)
			(xy 125.844135 -176.277074) (xy 125.839544 -176.283453) (xy 125.837696 -176.286922) (xy 125.835111 -176.292348)
			(xy 125.832283 -176.304028) (xy 125.832108 -176.310036) (xy 125.832108 -176.722278) (xy 130.560318 -176.722278)
			(xy 130.560719 -176.696161) (xy 130.568017 -176.64444) (xy 130.582466 -176.594244) (xy 130.603785 -176.546558)
			(xy 130.631554 -176.502317) (xy 130.665229 -176.462388) (xy 130.704151 -176.427553) (xy 130.747556 -176.398495)
			(xy 130.770884 -176.386744) (xy 130.783584 -176.380648) (xy 130.799078 -176.357026) (xy 130.803142 -176.25314)
			(xy 130.803054 -176.24395) (xy 130.797134 -176.226565) (xy 130.785492 -176.21236) (xy 130.777742 -176.20742)
			(xy 130.777488 -176.207166) (xy 130.754665 -176.193402) (xy 130.712988 -176.160184) (xy 130.67673 -176.121124)
			(xy 130.6467 -176.077096) (xy 130.623569 -176.029082) (xy 130.607855 -175.978156) (xy 130.599908 -175.925457)
			(xy 130.599434 -175.89881) (xy 130.599922 -175.870823) (xy 130.608677 -175.815538) (xy 130.625975 -175.762303)
			(xy 130.651387 -175.71243) (xy 130.684289 -175.667147) (xy 130.723871 -175.627569) (xy 130.769157 -175.59467)
			(xy 130.819032 -175.569262) (xy 130.872269 -175.55197) (xy 130.927555 -175.543219) (xy 130.955542 -175.542702)
			(xy 130.95605 -175.542702) (xy 130.984909 -175.543265) (xy 131.041862 -175.552626) (xy 131.096562 -175.571047)
			(xy 131.147576 -175.598046) (xy 131.19357 -175.632916) (xy 131.21386 -175.653446) (xy 131.22148 -175.661574)
			(xy 131.242054 -175.669956) (xy 131.329684 -175.665638) (xy 131.340595 -175.664593) (xy 131.360076 -175.654597)
			(xy 131.367276 -175.646334) (xy 131.36753 -175.64608) (xy 131.384499 -175.625173) (xy 131.423683 -175.588242)
			(xy 131.467983 -175.557635) (xy 131.516387 -175.534049) (xy 131.567792 -175.518021) (xy 131.621023 -175.509919)
			(xy 131.647946 -175.509428) (xy 131.6482 -175.509428) (xy 131.675496 -175.509931) (xy 131.729445 -175.518299)
			(xy 131.781487 -175.534795) (xy 131.830405 -175.559033) (xy 131.875057 -175.590445) (xy 131.895088 -175.608996)
			(xy 131.902454 -175.616108) (xy 131.920234 -175.62322) (xy 132.010658 -175.62322) (xy 132.028438 -175.616108)
			(xy 132.035804 -175.608996) (xy 132.055803 -175.590405) (xy 132.100448 -175.558971) (xy 132.149374 -175.534729)
			(xy 132.201429 -175.518249) (xy 132.255391 -175.509919) (xy 132.282692 -175.509428) (xy 132.282946 -175.509428)
			(xy 132.309596 -175.509857) (xy 132.362299 -175.517807) (xy 132.413229 -175.533523) (xy 132.461248 -175.556653)
			(xy 132.505284 -175.586681) (xy 132.544353 -175.622937) (xy 132.577583 -175.66461) (xy 132.60423 -175.71077)
			(xy 132.623701 -175.760386) (xy 132.635561 -175.812349) (xy 132.639544 -175.8655) (xy 132.635561 -175.918651)
			(xy 132.623701 -175.970614) (xy 132.60423 -176.02023) (xy 132.577583 -176.06639) (xy 132.544353 -176.108063)
			(xy 132.505284 -176.144319) (xy 132.461248 -176.174347) (xy 132.413229 -176.197477) (xy 132.362299 -176.213193)
			(xy 132.309596 -176.221143) (xy 132.282946 -176.221644) (xy 132.282692 -176.221644) (xy 132.255399 -176.221065)
			(xy 132.201455 -176.212712) (xy 132.149414 -176.196233) (xy 132.100494 -176.172013) (xy 132.055839 -176.140619)
			(xy 132.035804 -176.122076) (xy 132.028438 -176.114964) (xy 132.010658 -176.107852) (xy 131.920234 -176.107852)
			(xy 131.902454 -176.114964) (xy 131.895088 -176.122076) (xy 131.875069 -176.140682) (xy 131.830378 -176.17214)
			(xy 131.781401 -176.196391) (xy 131.72929 -176.212864) (xy 131.675273 -176.221171) (xy 131.647946 -176.221644)
			(xy 131.619036 -176.221112) (xy 131.561973 -176.211799) (xy 131.507162 -176.193393) (xy 131.456043 -176.166378)
			(xy 131.409957 -176.131462) (xy 131.389628 -176.1109) (xy 131.382008 -176.102772) (xy 131.361434 -176.09439)
			(xy 131.273804 -176.098708) (xy 131.262896 -176.099765) (xy 131.243415 -176.109754) (xy 131.236212 -176.118012)
			(xy 131.235958 -176.118266) (xy 131.219566 -176.138489) (xy 131.181872 -176.174391) (xy 131.139345 -176.204411)
			(xy 131.116324 -176.216564) (xy 131.103624 -176.222914) (xy 131.088892 -176.246536) (xy 131.086606 -176.365154)
			(xy 131.100576 -176.389284) (xy 131.113022 -176.396142) (xy 131.137625 -176.410325) (xy 131.18261 -176.444981)
			(xy 131.221811 -176.486066) (xy 131.25432 -176.532626) (xy 131.279381 -176.583583) (xy 131.296415 -176.637755)
			(xy 131.305025 -176.693885) (xy 131.305554 -176.722278) (xy 131.305033 -176.750163) (xy 131.296721 -176.80531)
			(xy 131.280283 -176.858602) (xy 131.256085 -176.908848) (xy 131.224669 -176.954927) (xy 131.186736 -176.995809)
			(xy 131.143134 -177.030581) (xy 131.094836 -177.058466) (xy 131.042921 -177.078841) (xy 130.98855 -177.091251)
			(xy 130.932936 -177.095419) (xy 130.877322 -177.091251) (xy 130.822951 -177.078841) (xy 130.771036 -177.058466)
			(xy 130.722738 -177.030581) (xy 130.679136 -176.995809) (xy 130.641203 -176.954927) (xy 130.609787 -176.908848)
			(xy 130.585589 -176.858602) (xy 130.569151 -176.80531) (xy 130.560839 -176.750163) (xy 130.560318 -176.722278)
			(xy 125.832108 -176.722278) (xy 125.832108 -178.143154) (xy 130.5649 -178.143154) (xy 130.568876 -178.088828)
			(xy 130.580719 -178.035659) (xy 130.600178 -177.984782) (xy 130.626838 -177.93728) (xy 130.660129 -177.894166)
			(xy 130.699343 -177.856359) (xy 130.743645 -177.824664) (xy 130.792088 -177.799758) (xy 130.843642 -177.78217)
			(xy 130.897208 -177.772276) (xy 130.951643 -177.770286) (xy 131.005788 -177.776244) (xy 131.058488 -177.790022)
			(xy 131.108621 -177.811326) (xy 131.155117 -177.839702) (xy 131.196987 -177.874546) (xy 131.233336 -177.915115)
			(xy 131.263392 -177.960544) (xy 131.286513 -178.009865) (xy 131.302206 -178.062027) (xy 131.310137 -178.115918)
			(xy 131.310634 -178.143154) (xy 131.310137 -178.17039) (xy 131.302206 -178.224281) (xy 131.286513 -178.276443)
			(xy 131.263392 -178.325764) (xy 131.233336 -178.371193) (xy 131.196987 -178.411762) (xy 131.155117 -178.446606)
			(xy 131.108621 -178.474982) (xy 131.058488 -178.496286) (xy 131.005788 -178.510064) (xy 130.951643 -178.516022)
			(xy 130.897208 -178.514032) (xy 130.843642 -178.504138) (xy 130.792088 -178.48655) (xy 130.743645 -178.461644)
			(xy 130.699343 -178.429949) (xy 130.660129 -178.392142) (xy 130.626838 -178.349028) (xy 130.600178 -178.301526)
			(xy 130.580719 -178.250649) (xy 130.568876 -178.19748) (xy 130.5649 -178.143154) (xy 125.832108 -178.143154)
			(xy 125.832108 -178.869086) (xy 141.546072 -178.869086) (xy 141.546072 -178.005486) (xy 141.546562 -177.975518)
			(xy 141.554385 -177.916096) (xy 141.569898 -177.858203) (xy 141.592834 -177.80283) (xy 141.622801 -177.750924)
			(xy 141.659288 -177.703374) (xy 141.701668 -177.660994) (xy 141.749218 -177.624507) (xy 141.801124 -177.59454)
			(xy 141.856497 -177.571604) (xy 141.91439 -177.556091) (xy 141.973812 -177.548268) (xy 142.033748 -177.548268)
			(xy 142.09317 -177.556091) (xy 142.151063 -177.571604) (xy 142.206436 -177.59454) (xy 142.258342 -177.624507)
			(xy 142.305892 -177.660994) (xy 142.348272 -177.703374) (xy 142.384759 -177.750924) (xy 142.414726 -177.80283)
			(xy 142.437662 -177.858203) (xy 142.453175 -177.916096) (xy 142.460998 -177.975518) (xy 142.461488 -178.005486)
			(xy 142.461488 -178.869086) (xy 142.460998 -178.899054) (xy 142.453175 -178.958476) (xy 142.437662 -179.016369)
			(xy 142.414726 -179.071742) (xy 142.384759 -179.123648) (xy 142.348272 -179.171198) (xy 142.305892 -179.213578)
			(xy 142.258342 -179.250065) (xy 142.206436 -179.280032) (xy 142.151063 -179.302968) (xy 142.09317 -179.318481)
			(xy 142.033748 -179.326304) (xy 141.973812 -179.326304) (xy 141.91439 -179.318481) (xy 141.856497 -179.302968)
			(xy 141.801124 -179.280032) (xy 141.749218 -179.250065) (xy 141.701668 -179.213578) (xy 141.659288 -179.171198)
			(xy 141.622801 -179.123648) (xy 141.592834 -179.071742) (xy 141.569898 -179.016369) (xy 141.554385 -178.958476)
			(xy 141.546562 -178.899054) (xy 141.546072 -178.869086) (xy 125.832108 -178.869086) (xy 125.832108 -179.4226)
			(xy 130.601585 -179.4226) (xy 130.605755 -179.366971) (xy 130.618169 -179.312585) (xy 130.638551 -179.260656)
			(xy 130.666446 -179.212346) (xy 130.701229 -179.168734) (xy 130.742125 -179.130793) (xy 130.788219 -179.099371)
			(xy 130.838482 -179.075172) (xy 130.89179 -179.058734) (xy 130.946953 -179.050426) (xy 130.974846 -179.049934)
			(xy 131.000437 -179.050342) (xy 131.051131 -179.057392) (xy 131.100383 -179.071313) (xy 131.147268 -179.091843)
			(xy 131.190902 -179.118595) (xy 131.230465 -179.151066) (xy 131.24815 -179.169568) (xy 131.255704 -179.176897)
			(xy 131.274977 -179.185295) (xy 131.285488 -179.185824) (xy 131.360164 -179.185824) (xy 131.370689 -179.185353)
			(xy 131.389981 -179.176947) (xy 131.397502 -179.169568) (xy 131.41516 -179.15104) (xy 131.454728 -179.118574)
			(xy 131.498368 -179.091829) (xy 131.545259 -179.071311) (xy 131.594517 -179.057404) (xy 131.645215 -179.050371)
			(xy 131.670806 -179.049934) (xy 131.696761 -179.050402) (xy 131.748167 -179.057608) (xy 131.798077 -179.071878)
			(xy 131.845522 -179.092938) (xy 131.889585 -179.120378) (xy 131.929414 -179.153669) (xy 131.947158 -179.172616)
			(xy 131.954607 -179.180257) (xy 131.974087 -179.18893) (xy 131.98475 -179.18938) (xy 132.060442 -179.18938)
			(xy 132.07107 -179.188786) (xy 132.090488 -179.180124) (xy 132.098034 -179.172616) (xy 132.117413 -179.151956)
			(xy 132.161313 -179.116161) (xy 132.210127 -179.087426) (xy 132.262729 -179.066415) (xy 132.317906 -179.053611)
			(xy 132.374386 -179.04931) (xy 132.430866 -179.053611) (xy 132.486043 -179.066415) (xy 132.538645 -179.087426)
			(xy 132.587459 -179.116161) (xy 132.631359 -179.151956) (xy 132.650738 -179.172616) (xy 132.658195 -179.180248)
			(xy 132.677669 -179.188926) (xy 132.68833 -179.18938) (xy 132.764022 -179.18938) (xy 132.774648 -179.188775)
			(xy 132.794067 -179.18012) (xy 132.801614 -179.172616) (xy 132.820993 -179.151956) (xy 132.864893 -179.116161)
			(xy 132.913707 -179.087426) (xy 132.966309 -179.066415) (xy 133.021486 -179.053611) (xy 133.077966 -179.04931)
			(xy 133.134446 -179.053611) (xy 133.189623 -179.066415) (xy 133.242225 -179.087426) (xy 133.291039 -179.116161)
			(xy 133.334939 -179.151956) (xy 133.354318 -179.172616) (xy 133.361782 -179.180239) (xy 133.381251 -179.188922)
			(xy 133.39191 -179.18938) (xy 133.467602 -179.18938) (xy 133.478227 -179.188765) (xy 133.497646 -179.180117)
			(xy 133.505194 -179.172616) (xy 133.522919 -179.153649) (xy 133.562749 -179.120353) (xy 133.606815 -179.09291)
			(xy 133.654264 -179.07185) (xy 133.704178 -179.057581) (xy 133.755589 -179.05038) (xy 133.781546 -179.049934)
			(xy 133.810645 -179.050478) (xy 133.868132 -179.059541) (xy 133.923509 -179.077439) (xy 133.975426 -179.103735)
			(xy 134.022619 -179.137791) (xy 134.043674 -179.157884) (xy 134.043928 -179.158138) (xy 134.051887 -179.165112)
			(xy 134.071701 -179.172468) (xy 134.082282 -179.172362) (xy 134.168642 -179.167536) (xy 134.187692 -179.15763)
			(xy 134.19455 -179.149248) (xy 134.212347 -179.1279) (xy 134.253176 -179.090195) (xy 134.299154 -179.058972)
			(xy 134.349259 -179.034925) (xy 134.402379 -179.018587) (xy 134.457338 -179.010321) (xy 134.485126 -179.009802)
			(xy 134.513011 -179.010285) (xy 134.568158 -179.0186) (xy 134.621449 -179.035042) (xy 134.671695 -179.059242)
			(xy 134.717773 -179.090661) (xy 134.758654 -179.128595) (xy 134.793425 -179.172199) (xy 134.821309 -179.220498)
			(xy 134.841683 -179.272414) (xy 134.854093 -179.326786) (xy 134.858261 -179.3824) (xy 134.854093 -179.438014)
			(xy 134.841683 -179.492386) (xy 134.821309 -179.544302) (xy 134.793425 -179.592601) (xy 134.758654 -179.636205)
			(xy 134.717773 -179.674139) (xy 134.671695 -179.705558) (xy 134.621449 -179.729758) (xy 134.568158 -179.7462)
			(xy 134.513011 -179.754515) (xy 134.485126 -179.755038) (xy 134.456029 -179.754457) (xy 134.398543 -179.745405)
			(xy 134.343166 -179.727516) (xy 134.291248 -179.701227) (xy 134.244054 -179.667178) (xy 134.222998 -179.647088)
			(xy 134.222744 -179.646834) (xy 134.214798 -179.639843) (xy 134.194974 -179.632498) (xy 134.18439 -179.63261)
			(xy 134.09803 -179.637436) (xy 134.07898 -179.647342) (xy 134.072122 -179.655724) (xy 134.05492 -179.67638)
			(xy 134.015629 -179.713062) (xy 133.971473 -179.743713) (xy 133.923367 -179.767695) (xy 133.872314 -179.784512)
			(xy 133.819372 -179.793812) (xy 133.765644 -179.795403) (xy 133.712245 -179.789252) (xy 133.660285 -179.775486)
			(xy 133.610845 -179.754392) (xy 133.564952 -179.726408) (xy 133.52356 -179.692116) (xy 133.505194 -179.672488)
			(xy 133.497725 -179.66487) (xy 133.47826 -179.656184) (xy 133.467602 -179.655724) (xy 133.39191 -179.655724)
			(xy 133.381285 -179.656344) (xy 133.361867 -179.664988) (xy 133.354318 -179.672488) (xy 133.334939 -179.693148)
			(xy 133.291039 -179.728943) (xy 133.242225 -179.757678) (xy 133.189623 -179.778689) (xy 133.134446 -179.791493)
			(xy 133.077966 -179.795794) (xy 133.021486 -179.791493) (xy 132.966309 -179.778689) (xy 132.913707 -179.757678)
			(xy 132.864893 -179.728943) (xy 132.820993 -179.693148) (xy 132.801614 -179.672488) (xy 132.794137 -179.664879)
			(xy 132.774678 -179.656188) (xy 132.764022 -179.655724) (xy 132.68833 -179.655724) (xy 132.677707 -179.656355)
			(xy 132.658288 -179.664991) (xy 132.650738 -179.672488) (xy 132.631359 -179.693148) (xy 132.587459 -179.728943)
			(xy 132.538645 -179.757678) (xy 132.486043 -179.778689) (xy 132.430866 -179.791493) (xy 132.374386 -179.795794)
			(xy 132.317906 -179.791493) (xy 132.262729 -179.778689) (xy 132.210127 -179.757678) (xy 132.161313 -179.728943)
			(xy 132.117413 -179.693148) (xy 132.098034 -179.672488) (xy 132.090588 -179.664843) (xy 132.071106 -179.656173)
			(xy 132.060442 -179.655724) (xy 131.98475 -179.655724) (xy 131.974122 -179.656312) (xy 131.954703 -179.664978)
			(xy 131.947158 -179.672488) (xy 131.929408 -179.69143) (xy 131.889584 -179.724728) (xy 131.845523 -179.752175)
			(xy 131.798078 -179.773239) (xy 131.748169 -179.787513) (xy 131.696761 -179.794721) (xy 131.670806 -179.79517)
			(xy 131.645217 -179.794726) (xy 131.594524 -179.787683) (xy 131.545272 -179.773769) (xy 131.498388 -179.753246)
			(xy 131.454753 -179.7265) (xy 131.415188 -179.694035) (xy 131.397502 -179.675536) (xy 131.389966 -179.668186)
			(xy 131.370679 -179.6598) (xy 131.360164 -179.65928) (xy 131.285488 -179.65928) (xy 131.27496 -179.659724)
			(xy 131.255668 -179.668149) (xy 131.24815 -179.675536) (xy 131.230468 -179.694039) (xy 131.190905 -179.726508)
			(xy 131.147269 -179.753255) (xy 131.100384 -179.773778) (xy 131.05113 -179.78769) (xy 131.000436 -179.794729)
			(xy 130.974846 -179.79517) (xy 130.946953 -179.794774) (xy 130.89179 -179.786466) (xy 130.838482 -179.770028)
			(xy 130.788219 -179.745829) (xy 130.742125 -179.714407) (xy 130.701229 -179.676466) (xy 130.666446 -179.632854)
			(xy 130.638551 -179.584544) (xy 130.618169 -179.532615) (xy 130.605755 -179.478229) (xy 130.601585 -179.4226)
			(xy 125.832108 -179.4226) (xy 125.832108 -179.99964) (xy 125.831766 -180.018937) (xy 125.831188 -180.02377)
			(xy 126.799338 -180.02377) (xy 126.803409 -179.968148) (xy 126.815535 -179.913711) (xy 126.835458 -179.86162)
			(xy 126.862754 -179.812985) (xy 126.89684 -179.768842) (xy 126.936989 -179.730133) (xy 126.982347 -179.697682)
			(xy 127.031947 -179.672181) (xy 127.084731 -179.654174) (xy 127.139574 -179.644044) (xy 127.195308 -179.642007)
			(xy 127.250745 -179.648107) (xy 127.304702 -179.662213) (xy 127.356031 -179.684025) (xy 127.403637 -179.713079)
			(xy 127.446505 -179.748754) (xy 127.483722 -179.790291) (xy 127.514495 -179.836804) (xy 127.538167 -179.887301)
			(xy 127.554235 -179.940708) (xy 127.562355 -179.995884) (xy 127.562864 -180.02377) (xy 127.562355 -180.051656)
			(xy 127.554235 -180.106832) (xy 127.538167 -180.160239) (xy 127.514495 -180.210736) (xy 127.483722 -180.257249)
			(xy 127.446505 -180.298786) (xy 127.403637 -180.334461) (xy 127.356031 -180.363515) (xy 127.304702 -180.385327)
			(xy 127.250745 -180.399433) (xy 127.195308 -180.405533) (xy 127.139574 -180.403496) (xy 127.084731 -180.393366)
			(xy 127.031947 -180.375359) (xy 126.982347 -180.349858) (xy 126.936989 -180.317407) (xy 126.89684 -180.278698)
			(xy 126.862754 -180.234555) (xy 126.835458 -180.18592) (xy 126.815535 -180.133829) (xy 126.803409 -180.079392)
			(xy 126.799338 -180.02377) (xy 125.831188 -180.02377) (xy 125.82718 -180.05726) (xy 125.822964 -180.076094)
			(xy 125.821694 -180.081936) (xy 125.821694 -180.111908) (xy 125.821155 -180.121895) (xy 125.813439 -180.140324)
			(xy 125.806708 -180.147722) (xy 125.806454 -180.147976) (xy 125.785626 -180.169058) (xy 125.782578 -180.173884)
			(xy 125.772223 -180.190184) (xy 125.748288 -180.220491) (xy 125.734826 -180.234336) (xy 125.068076 -180.901086)
			(xy 142.181072 -180.901086) (xy 142.181072 -180.037486) (xy 142.181562 -180.007518) (xy 142.189385 -179.948096)
			(xy 142.204898 -179.890203) (xy 142.227834 -179.83483) (xy 142.257801 -179.782924) (xy 142.294288 -179.735374)
			(xy 142.336668 -179.692994) (xy 142.384218 -179.656507) (xy 142.436124 -179.62654) (xy 142.491497 -179.603604)
			(xy 142.54939 -179.588091) (xy 142.608812 -179.580268) (xy 142.668748 -179.580268) (xy 142.72817 -179.588091)
			(xy 142.786063 -179.603604) (xy 142.841436 -179.62654) (xy 142.893342 -179.656507) (xy 142.940892 -179.692994)
			(xy 142.983272 -179.735374) (xy 143.019759 -179.782924) (xy 143.049726 -179.83483) (xy 143.072662 -179.890203)
			(xy 143.088175 -179.948096) (xy 143.095998 -180.007518) (xy 143.096488 -180.037486) (xy 143.096488 -180.901086)
			(xy 143.095998 -180.931054) (xy 143.088175 -180.990476) (xy 143.072662 -181.048369) (xy 143.049726 -181.103742)
			(xy 143.019759 -181.155648) (xy 142.983272 -181.203198) (xy 142.940892 -181.245578) (xy 142.893342 -181.282065)
			(xy 142.841436 -181.312032) (xy 142.786063 -181.334968) (xy 142.72817 -181.350481) (xy 142.668748 -181.358304)
			(xy 142.608812 -181.358304) (xy 142.54939 -181.350481) (xy 142.491497 -181.334968) (xy 142.436124 -181.312032)
			(xy 142.384218 -181.282065) (xy 142.336668 -181.245578) (xy 142.294288 -181.203198) (xy 142.257801 -181.155648)
			(xy 142.227834 -181.103742) (xy 142.204898 -181.048369) (xy 142.189385 -180.990476) (xy 142.181562 -180.931054)
			(xy 142.181072 -180.901086) (xy 125.068076 -180.901086) (xy 123.493405 -182.475757) (xy 129.801509 -182.475757)
			(xy 129.801509 -182.421243) (xy 129.809267 -182.367284) (xy 129.824626 -182.314978) (xy 129.847273 -182.26539)
			(xy 129.876747 -182.219531) (xy 129.912447 -182.178333) (xy 129.953647 -182.142635) (xy 129.999508 -182.113163)
			(xy 130.049097 -182.090519) (xy 130.101403 -182.075163) (xy 130.155363 -182.067408) (xy 130.18262 -182.066946)
			(xy 130.182874 -182.066946) (xy 130.202432 -182.067454) (xy 130.212846 -182.067962) (xy 130.232658 -182.06085)
			(xy 130.293618 -182.002684) (xy 130.300754 -181.995193) (xy 130.308881 -181.976188) (xy 130.309366 -181.965854)
			(xy 130.309797 -181.938567) (xy 130.317466 -181.884535) (xy 130.332755 -181.832148) (xy 130.355353 -181.782474)
			(xy 130.384799 -181.736526) (xy 130.420491 -181.695243) (xy 130.461701 -181.659467) (xy 130.507588 -181.629928)
			(xy 130.557216 -181.607228) (xy 130.609572 -181.591831) (xy 130.663588 -181.584052) (xy 130.690874 -181.583584)
			(xy 130.718127 -181.584062) (xy 130.77208 -181.591815) (xy 130.82438 -181.607169) (xy 130.873962 -181.629809)
			(xy 130.919818 -181.659276) (xy 130.961013 -181.694969) (xy 130.996708 -181.736161) (xy 131.026178 -181.782015)
			(xy 131.048822 -181.831596) (xy 131.064179 -181.883894) (xy 131.071937 -181.937847) (xy 131.071937 -181.992353)
			(xy 131.064179 -182.046306) (xy 131.048822 -182.098604) (xy 131.026178 -182.148185) (xy 130.996708 -182.194039)
			(xy 130.961013 -182.235231) (xy 130.919818 -182.270924) (xy 130.873962 -182.300391) (xy 130.82438 -182.323031)
			(xy 130.77208 -182.338385) (xy 130.718127 -182.346138) (xy 130.690874 -182.3466) (xy 130.69062 -182.3466)
			(xy 130.671062 -182.346092) (xy 130.660648 -182.345584) (xy 130.640836 -182.352696) (xy 130.579876 -182.410862)
			(xy 130.572719 -182.418335) (xy 130.564605 -182.437354) (xy 130.564128 -182.447692) (xy 130.563653 -182.474978)
			(xy 130.555991 -182.529009) (xy 130.540708 -182.581395) (xy 130.518116 -182.63107) (xy 130.488675 -182.677018)
			(xy 130.452988 -182.718302) (xy 130.411782 -182.754079) (xy 130.365898 -182.783619) (xy 130.316272 -182.806319)
			(xy 130.263919 -182.821716) (xy 130.238408 -182.82539) (xy 136.874248 -182.82539) (xy 136.878319 -182.769768)
			(xy 136.890445 -182.715331) (xy 136.910368 -182.66324) (xy 136.937664 -182.614605) (xy 136.97175 -182.570462)
			(xy 137.011899 -182.531753) (xy 137.057257 -182.499302) (xy 137.106857 -182.473801) (xy 137.159641 -182.455794)
			(xy 137.214484 -182.445664) (xy 137.270218 -182.443627) (xy 137.325655 -182.449727) (xy 137.379612 -182.463833)
			(xy 137.430941 -182.485645) (xy 137.478547 -182.514699) (xy 137.521415 -182.550374) (xy 137.558632 -182.591911)
			(xy 137.589405 -182.638424) (xy 137.613077 -182.688921) (xy 137.629145 -182.742328) (xy 137.637265 -182.797504)
			(xy 137.637774 -182.82539) (xy 137.637265 -182.853276) (xy 137.629145 -182.908452) (xy 137.613077 -182.961859)
			(xy 137.589405 -183.012356) (xy 137.558632 -183.058869) (xy 137.521415 -183.100406) (xy 137.478547 -183.136081)
			(xy 137.430941 -183.165135) (xy 137.379612 -183.186947) (xy 137.325655 -183.201053) (xy 137.270218 -183.207153)
			(xy 137.214484 -183.205116) (xy 137.159641 -183.194986) (xy 137.106857 -183.176979) (xy 137.057257 -183.151478)
			(xy 137.011899 -183.119027) (xy 136.97175 -183.080318) (xy 136.937664 -183.036175) (xy 136.910368 -182.98754)
			(xy 136.890445 -182.935449) (xy 136.878319 -182.881012) (xy 136.874248 -182.82539) (xy 130.238408 -182.82539)
			(xy 130.209905 -182.829495) (xy 130.18262 -182.829962) (xy 130.155363 -182.829592) (xy 130.101403 -182.821837)
			(xy 130.049097 -182.806481) (xy 129.999508 -182.783837) (xy 129.953647 -182.754365) (xy 129.912447 -182.718667)
			(xy 129.876747 -182.677469) (xy 129.847273 -182.63161) (xy 129.824626 -182.582022) (xy 129.809267 -182.529716)
			(xy 129.801509 -182.475757) (xy 123.493405 -182.475757) (xy 122.964448 -183.004714) (xy 127.33731 -183.004714)
			(xy 127.341381 -182.949092) (xy 127.353507 -182.894655) (xy 127.37343 -182.842564) (xy 127.400726 -182.793929)
			(xy 127.434812 -182.749786) (xy 127.474961 -182.711077) (xy 127.520319 -182.678626) (xy 127.569919 -182.653125)
			(xy 127.622703 -182.635118) (xy 127.677546 -182.624988) (xy 127.73328 -182.622951) (xy 127.788717 -182.629051)
			(xy 127.842674 -182.643157) (xy 127.894003 -182.664969) (xy 127.941609 -182.694023) (xy 127.984477 -182.729698)
			(xy 128.021694 -182.771235) (xy 128.052467 -182.817748) (xy 128.076139 -182.868245) (xy 128.092207 -182.921652)
			(xy 128.100327 -182.976828) (xy 128.100836 -183.004714) (xy 128.100327 -183.0326) (xy 128.092207 -183.087776)
			(xy 128.076139 -183.141183) (xy 128.052467 -183.19168) (xy 128.021694 -183.238193) (xy 127.984477 -183.27973)
			(xy 127.941609 -183.315405) (xy 127.894003 -183.344459) (xy 127.842674 -183.366271) (xy 127.788717 -183.380377)
			(xy 127.73328 -183.386477) (xy 127.677546 -183.38444) (xy 127.622703 -183.37431) (xy 127.569919 -183.356303)
			(xy 127.520319 -183.330802) (xy 127.474961 -183.298351) (xy 127.434812 -183.259642) (xy 127.400726 -183.215499)
			(xy 127.37343 -183.166864) (xy 127.353507 -183.114773) (xy 127.341381 -183.060336) (xy 127.33731 -183.004714)
			(xy 122.964448 -183.004714) (xy 122.754136 -183.215026) (xy 122.734578 -183.23306) (xy 122.724052 -183.241788)
			(xy 122.701799 -183.257685) (xy 122.690128 -183.26481) (xy 122.68835 -183.26608) (xy 122.667522 -183.286908)
			(xy 122.660172 -183.293706) (xy 122.64171 -183.301409) (xy 122.631708 -183.301894) (xy 122.601736 -183.301894)
			(xy 122.595894 -183.303164) (xy 122.577065 -183.307406) (xy 122.538739 -183.311988) (xy 122.51944 -183.312308)
			(xy 101.20249 -183.312308) (xy 101.183193 -183.311968) (xy 101.144869 -183.307385) (xy 101.126036 -183.303164)
			(xy 101.120194 -183.301894) (xy 101.090222 -183.301894) (xy 101.080233 -183.30136) (xy 101.061796 -183.293652)
			(xy 101.054408 -183.286908) (xy 101.03358 -183.26608) (xy 101.031802 -183.26481) (xy 101.020126 -183.257691)
			(xy 100.997871 -183.241797) (xy 100.987352 -183.23306) (xy 100.967794 -183.215026) (xy 97.961196 -180.208428)
			(xy 97.954084 -180.20792) (xy 95.382334 -180.20792) (xy 95.376238 -180.208174) (xy 95.361777 -180.209741)
			(xy 95.334545 -180.219925) (xy 95.311282 -180.237363) (xy 95.293869 -180.260646) (xy 95.283717 -180.287889)
			(xy 95.281644 -180.316889) (xy 95.287821 -180.345299) (xy 95.301746 -180.37082) (xy 95.311722 -180.381402)
			(xy 95.943674 -181.013354) (xy 95.96035 -181.030625) (xy 95.988605 -181.069436) (xy 96.010436 -181.112192)
			(xy 96.025304 -181.157839) (xy 96.032843 -181.205251) (xy 96.033336 -181.229254) (xy 96.033336 -184.130442)
			(xy 96.033082 -184.134506) (xy 96.033082 -184.135522) (xy 96.032828 -184.1373) (xy 96.032828 -184.140602)
			(xy 96.031732 -184.155834) (xy 96.026897 -184.185989) (xy 96.023176 -184.2008) (xy 96.016612 -184.223944)
			(xy 95.997213 -184.267964) (xy 95.984568 -184.28843) (xy 95.975563 -184.302065) (xy 95.955073 -184.327522)
			(xy 95.943674 -184.33923) (xy 95.296952 -184.985914) (xy 107.566204 -184.985914) (xy 107.570275 -184.930292)
			(xy 107.582401 -184.875855) (xy 107.602324 -184.823764) (xy 107.62962 -184.775129) (xy 107.663706 -184.730986)
			(xy 107.703855 -184.692277) (xy 107.749213 -184.659826) (xy 107.798813 -184.634325) (xy 107.851597 -184.616318)
			(xy 107.90644 -184.606188) (xy 107.962174 -184.604151) (xy 108.017611 -184.610251) (xy 108.071568 -184.624357)
			(xy 108.122897 -184.646169) (xy 108.170503 -184.675223) (xy 108.213371 -184.710898) (xy 108.250588 -184.752435)
			(xy 108.281361 -184.798948) (xy 108.305033 -184.849445) (xy 108.321101 -184.902852) (xy 108.329221 -184.958028)
			(xy 108.32973 -184.985914) (xy 108.329221 -185.0138) (xy 108.321101 -185.068976) (xy 108.305033 -185.122383)
			(xy 108.281361 -185.17288) (xy 108.250588 -185.219393) (xy 108.213371 -185.26093) (xy 108.170503 -185.296605)
			(xy 108.122897 -185.325659) (xy 108.071568 -185.347471) (xy 108.017611 -185.361577) (xy 107.962174 -185.367677)
			(xy 107.90644 -185.36564) (xy 107.851597 -185.35551) (xy 107.798813 -185.337503) (xy 107.749213 -185.312002)
			(xy 107.703855 -185.279551) (xy 107.663706 -185.240842) (xy 107.62962 -185.196699) (xy 107.602324 -185.148064)
			(xy 107.582401 -185.095973) (xy 107.570275 -185.041536) (xy 107.566204 -184.985914) (xy 95.296952 -184.985914)
			(xy 94.608825 -185.674) (xy 96.382584 -185.674) (xy 96.386655 -185.618378) (xy 96.398781 -185.563941)
			(xy 96.418704 -185.51185) (xy 96.446 -185.463215) (xy 96.480086 -185.419072) (xy 96.520235 -185.380363)
			(xy 96.565593 -185.347912) (xy 96.615193 -185.322411) (xy 96.667977 -185.304404) (xy 96.72282 -185.294274)
			(xy 96.778554 -185.292237) (xy 96.833991 -185.298337) (xy 96.887948 -185.312443) (xy 96.939277 -185.334255)
			(xy 96.986883 -185.363309) (xy 97.029751 -185.398984) (xy 97.066968 -185.440521) (xy 97.097741 -185.487034)
			(xy 97.121413 -185.537531) (xy 97.137481 -185.590938) (xy 97.145601 -185.646114) (xy 97.14611 -185.674)
			(xy 97.145601 -185.701886) (xy 97.137481 -185.757062) (xy 97.121413 -185.810469) (xy 97.097741 -185.860966)
			(xy 97.066968 -185.907479) (xy 97.029751 -185.949016) (xy 96.986883 -185.984691) (xy 96.939277 -186.013745)
			(xy 96.887948 -186.035557) (xy 96.833991 -186.049663) (xy 96.778554 -186.055763) (xy 96.72282 -186.053726)
			(xy 96.667977 -186.043596) (xy 96.615193 -186.025589) (xy 96.565593 -186.000088) (xy 96.520235 -185.967637)
			(xy 96.480086 -185.928928) (xy 96.446 -185.884785) (xy 96.418704 -185.83615) (xy 96.398781 -185.784059)
			(xy 96.386655 -185.729622) (xy 96.382584 -185.674) (xy 94.608825 -185.674) (xy 94.135087 -186.14771)
			(xy 99.051362 -186.14771) (xy 99.055433 -186.092088) (xy 99.067559 -186.037651) (xy 99.087482 -185.98556)
			(xy 99.114778 -185.936925) (xy 99.148864 -185.892782) (xy 99.189013 -185.854073) (xy 99.234371 -185.821622)
			(xy 99.283971 -185.796121) (xy 99.336755 -185.778114) (xy 99.391598 -185.767984) (xy 99.447332 -185.765947)
			(xy 99.502769 -185.772047) (xy 99.556726 -185.786153) (xy 99.608055 -185.807965) (xy 99.655661 -185.837019)
			(xy 99.698529 -185.872694) (xy 99.735746 -185.914231) (xy 99.766519 -185.960744) (xy 99.790191 -186.011241)
			(xy 99.806259 -186.064648) (xy 99.809968 -186.089848) (xy 141.507498 -186.089848) (xy 141.507498 -186.035352)
			(xy 141.515253 -185.98141) (xy 141.530606 -185.929121) (xy 141.553243 -185.879549) (xy 141.582704 -185.833703)
			(xy 141.61839 -185.792516) (xy 141.659574 -185.756826) (xy 141.705417 -185.72736) (xy 141.754987 -185.704718)
			(xy 141.807275 -185.689361) (xy 141.861216 -185.681601) (xy 141.888464 -185.681112) (xy 141.916961 -185.681633)
			(xy 141.973321 -185.690107) (xy 142.027793 -185.706871) (xy 142.079165 -185.731552) (xy 142.126293 -185.763602)
			(xy 142.168129 -185.802306) (xy 142.203742 -185.846803) (xy 142.232338 -185.896104) (xy 142.243302 -185.922412)
			(xy 142.248869 -185.935335) (xy 142.265945 -185.957689) (xy 142.288471 -185.974537) (xy 142.314739 -185.984601)
			(xy 142.342756 -185.987118) (xy 142.370397 -185.981897) (xy 142.395566 -185.969334) (xy 142.416353 -185.950382)
			(xy 142.42415 -185.938668) (xy 142.439172 -185.915414) (xy 142.474842 -185.87308) (xy 142.51626 -185.836349)
			(xy 142.562554 -185.805994) (xy 142.612752 -185.782653) (xy 142.665797 -185.766817) (xy 142.720575 -185.758819)
			(xy 142.748254 -185.758328) (xy 142.775512 -185.758716) (xy 142.829473 -185.766468) (xy 142.881781 -185.781822)
			(xy 142.931372 -185.804464) (xy 142.977235 -185.833933) (xy 143.018437 -185.86963) (xy 143.054139 -185.910828)
			(xy 143.083614 -185.956688) (xy 143.106262 -186.006276) (xy 143.121622 -186.058582) (xy 143.129381 -186.112542)
			(xy 143.129381 -186.167058) (xy 143.121622 -186.221018) (xy 143.106262 -186.273324) (xy 143.083614 -186.322912)
			(xy 143.054139 -186.368772) (xy 143.018437 -186.40997) (xy 142.977235 -186.445667) (xy 142.931372 -186.475136)
			(xy 142.881781 -186.497778) (xy 142.829473 -186.513132) (xy 142.775512 -186.520884) (xy 142.748254 -186.521344)
			(xy 142.719756 -186.520835) (xy 142.663395 -186.512363) (xy 142.608921 -186.495599) (xy 142.557547 -186.470917)
			(xy 142.510418 -186.438865) (xy 142.468582 -186.400158) (xy 142.432971 -186.355658) (xy 142.404378 -186.306354)
			(xy 142.393416 -186.280044) (xy 142.387818 -186.267133) (xy 142.370752 -186.244772) (xy 142.348232 -186.227916)
			(xy 142.321967 -186.217847) (xy 142.29395 -186.215327) (xy 142.26631 -186.220548) (xy 142.241143 -186.233114)
			(xy 142.220362 -186.252071) (xy 142.212568 -186.263788) (xy 142.197553 -186.287046) (xy 142.161879 -186.329378)
			(xy 142.12046 -186.366107) (xy 142.074164 -186.39646) (xy 142.023966 -186.4198) (xy 141.970921 -186.435636)
			(xy 141.916143 -186.443636) (xy 141.888464 -186.444128) (xy 141.861216 -186.443599) (xy 141.807275 -186.435839)
			(xy 141.754987 -186.420482) (xy 141.705417 -186.39784) (xy 141.659574 -186.368374) (xy 141.61839 -186.332684)
			(xy 141.582704 -186.291497) (xy 141.553243 -186.245651) (xy 141.530606 -186.196079) (xy 141.515253 -186.14379)
			(xy 141.507498 -186.089848) (xy 99.809968 -186.089848) (xy 99.814379 -186.119824) (xy 99.814888 -186.14771)
			(xy 99.814379 -186.175596) (xy 99.806259 -186.230772) (xy 99.790191 -186.284179) (xy 99.766519 -186.334676)
			(xy 99.735746 -186.381189) (xy 99.698529 -186.422726) (xy 99.655661 -186.458401) (xy 99.608055 -186.487455)
			(xy 99.556726 -186.509267) (xy 99.502769 -186.523373) (xy 99.447332 -186.529473) (xy 99.391598 -186.527436)
			(xy 99.336755 -186.517306) (xy 99.283971 -186.499299) (xy 99.234371 -186.473798) (xy 99.189013 -186.441347)
			(xy 99.148864 -186.402638) (xy 99.114778 -186.358495) (xy 99.087482 -186.30986) (xy 99.067559 -186.257769)
			(xy 99.055433 -186.203332) (xy 99.051362 -186.14771) (xy 94.135087 -186.14771) (xy 93.158158 -187.124582)
			(xy 135.58115 -187.124582) (xy 135.58115 -187.064618) (xy 135.588977 -187.005166) (xy 135.604497 -186.947244)
			(xy 135.627444 -186.891844) (xy 135.657426 -186.839912) (xy 135.69393 -186.792339) (xy 135.736331 -186.749937)
			(xy 135.783904 -186.713432) (xy 135.835835 -186.683448) (xy 135.891235 -186.6605) (xy 135.949156 -186.644979)
			(xy 136.008608 -186.637151) (xy 136.03859 -186.63666) (xy 136.90219 -186.63666) (xy 136.932178 -186.637085)
			(xy 136.99164 -186.644912) (xy 137.049571 -186.660433) (xy 137.104981 -186.683384) (xy 137.156922 -186.713371)
			(xy 137.204504 -186.749881) (xy 137.246913 -186.792289) (xy 137.283424 -186.83987) (xy 137.313412 -186.89181)
			(xy 137.336363 -186.947219) (xy 137.351886 -187.005151) (xy 137.359715 -187.064612) (xy 137.359715 -187.124588)
			(xy 137.351886 -187.184049) (xy 137.336363 -187.241981) (xy 137.313412 -187.29739) (xy 137.283424 -187.34933)
			(xy 137.246913 -187.396911) (xy 137.204504 -187.439319) (xy 137.156922 -187.475829) (xy 137.104981 -187.505816)
			(xy 137.049571 -187.528767) (xy 136.99164 -187.544288) (xy 136.932178 -187.552115) (xy 136.90219 -187.552584)
			(xy 136.03859 -187.552584) (xy 136.008608 -187.552049) (xy 135.949156 -187.544221) (xy 135.891235 -187.5287)
			(xy 135.835835 -187.505752) (xy 135.783904 -187.475768) (xy 135.736331 -187.439263) (xy 135.69393 -187.396861)
			(xy 135.657426 -187.349288) (xy 135.627444 -187.297356) (xy 135.604497 -187.241956) (xy 135.588977 -187.184034)
			(xy 135.58115 -187.124582) (xy 93.158158 -187.124582) (xy 92.236072 -188.046614) (xy 96.614232 -188.046614)
			(xy 96.618303 -187.990992) (xy 96.630429 -187.936555) (xy 96.650352 -187.884464) (xy 96.677648 -187.835829)
			(xy 96.711734 -187.791686) (xy 96.751883 -187.752977) (xy 96.797241 -187.720526) (xy 96.846841 -187.695025)
			(xy 96.899625 -187.677018) (xy 96.954468 -187.666888) (xy 97.010202 -187.664851) (xy 97.065639 -187.670951)
			(xy 97.119596 -187.685057) (xy 97.170925 -187.706869) (xy 97.218531 -187.735923) (xy 97.261399 -187.771598)
			(xy 97.298616 -187.813135) (xy 97.329389 -187.859648) (xy 97.353061 -187.910145) (xy 97.369129 -187.963552)
			(xy 97.377249 -188.018728) (xy 97.377758 -188.046614) (xy 97.377249 -188.0745) (xy 97.369129 -188.129676)
			(xy 97.353061 -188.183083) (xy 97.329389 -188.23358) (xy 97.298616 -188.280093) (xy 97.28956 -188.2902)
			(xy 102.792782 -188.2902) (xy 102.796853 -188.234578) (xy 102.808979 -188.180141) (xy 102.828902 -188.12805)
			(xy 102.856198 -188.079415) (xy 102.890284 -188.035272) (xy 102.930433 -187.996563) (xy 102.975791 -187.964112)
			(xy 103.025391 -187.938611) (xy 103.078175 -187.920604) (xy 103.133018 -187.910474) (xy 103.188752 -187.908437)
			(xy 103.244189 -187.914537) (xy 103.298146 -187.928643) (xy 103.349475 -187.950455) (xy 103.397081 -187.979509)
			(xy 103.439949 -188.015184) (xy 103.477166 -188.056721) (xy 103.507939 -188.103234) (xy 103.531611 -188.153731)
			(xy 103.547679 -188.207138) (xy 103.554411 -188.252885) (xy 128.656818 -188.252885) (xy 128.656818 -188.192915)
			(xy 128.664646 -188.133459) (xy 128.680167 -188.075533) (xy 128.703116 -188.020128) (xy 128.733101 -187.968193)
			(xy 128.769608 -187.920615) (xy 128.812012 -187.87821) (xy 128.859589 -187.841703) (xy 128.911524 -187.811718)
			(xy 128.966929 -187.788768) (xy 129.024855 -187.773246) (xy 129.084311 -187.765418) (xy 129.114296 -187.764928)
			(xy 129.977896 -187.764928) (xy 130.007881 -187.765417) (xy 130.067339 -187.773244) (xy 130.125266 -187.788765)
			(xy 130.180671 -187.811714) (xy 130.232607 -187.841699) (xy 130.280185 -187.878207) (xy 130.322591 -187.920612)
			(xy 130.359098 -187.96819) (xy 130.389084 -188.020125) (xy 130.412034 -188.075531) (xy 130.427555 -188.133458)
			(xy 130.435383 -188.192915) (xy 130.435383 -188.252885) (xy 130.434185 -188.261981) (xy 131.046262 -188.261981)
			(xy 131.046262 -188.202019) (xy 131.054088 -188.14257) (xy 131.069607 -188.084651) (xy 131.092553 -188.029253)
			(xy 131.122533 -187.977324) (xy 131.159034 -187.929752) (xy 131.201432 -187.887351) (xy 131.249002 -187.850847)
			(xy 131.30093 -187.820864) (xy 131.356326 -187.797915) (xy 131.414244 -187.782393) (xy 131.473693 -187.774564)
			(xy 131.503674 -187.774072) (xy 132.367274 -187.774072) (xy 132.397263 -187.774472) (xy 132.456728 -187.782297)
			(xy 132.514663 -187.797818) (xy 132.570077 -187.820768) (xy 132.62202 -187.850755) (xy 132.631984 -187.8584)
			(xy 142.670782 -187.8584) (xy 142.674853 -187.802778) (xy 142.686979 -187.748341) (xy 142.706902 -187.69625)
			(xy 142.734198 -187.647615) (xy 142.768284 -187.603472) (xy 142.808433 -187.564763) (xy 142.853791 -187.532312)
			(xy 142.903391 -187.506811) (xy 142.956175 -187.488804) (xy 143.011018 -187.478674) (xy 143.066752 -187.476637)
			(xy 143.122189 -187.482737) (xy 143.176146 -187.496843) (xy 143.227475 -187.518655) (xy 143.275081 -187.547709)
			(xy 143.317949 -187.583384) (xy 143.355166 -187.624921) (xy 143.385939 -187.671434) (xy 143.409611 -187.721931)
			(xy 143.425679 -187.775338) (xy 143.433799 -187.830514) (xy 143.434308 -187.8584) (xy 143.433799 -187.886286)
			(xy 143.425679 -187.941462) (xy 143.409611 -187.994869) (xy 143.385939 -188.045366) (xy 143.355166 -188.091879)
			(xy 143.317949 -188.133416) (xy 143.275081 -188.169091) (xy 143.227475 -188.198145) (xy 143.176146 -188.219957)
			(xy 143.122189 -188.234063) (xy 143.066752 -188.240163) (xy 143.011018 -188.238126) (xy 142.956175 -188.227996)
			(xy 142.903391 -188.209989) (xy 142.853791 -188.184488) (xy 142.808433 -188.152037) (xy 142.768284 -188.113328)
			(xy 142.734198 -188.069185) (xy 142.706902 -188.02055) (xy 142.686979 -187.968459) (xy 142.674853 -187.914022)
			(xy 142.670782 -187.8584) (xy 132.631984 -187.8584) (xy 132.669605 -187.887266) (xy 132.712017 -187.929675)
			(xy 132.74853 -187.977258) (xy 132.77852 -188.0292) (xy 132.801474 -188.084612) (xy 132.816998 -188.142546)
			(xy 132.824827 -188.202011) (xy 132.824827 -188.261989) (xy 132.816998 -188.321454) (xy 132.801474 -188.379388)
			(xy 132.79518 -188.394582) (xy 133.54915 -188.394582) (xy 133.54915 -188.334618) (xy 133.556977 -188.275166)
			(xy 133.572497 -188.217244) (xy 133.595444 -188.161844) (xy 133.625426 -188.109912) (xy 133.66193 -188.062339)
			(xy 133.704331 -188.019937) (xy 133.751904 -187.983432) (xy 133.803835 -187.953448) (xy 133.859235 -187.9305)
			(xy 133.917156 -187.914979) (xy 133.976608 -187.907151) (xy 134.00659 -187.90666) (xy 134.87019 -187.90666)
			(xy 134.900178 -187.907085) (xy 134.95964 -187.914912) (xy 135.017571 -187.930433) (xy 135.072981 -187.953384)
			(xy 135.124922 -187.983371) (xy 135.172504 -188.019881) (xy 135.214913 -188.062289) (xy 135.251424 -188.10987)
			(xy 135.281412 -188.16181) (xy 135.304363 -188.217219) (xy 135.319886 -188.275151) (xy 135.327715 -188.334612)
			(xy 135.327715 -188.394588) (xy 135.319886 -188.454049) (xy 135.304363 -188.511981) (xy 135.281412 -188.56739)
			(xy 135.251424 -188.61933) (xy 135.214913 -188.666911) (xy 135.172504 -188.709319) (xy 135.124922 -188.745829)
			(xy 135.072981 -188.775816) (xy 135.017571 -188.798767) (xy 134.95964 -188.814288) (xy 134.900178 -188.822115)
			(xy 134.87019 -188.822584) (xy 134.00659 -188.822584) (xy 133.976608 -188.822049) (xy 133.917156 -188.814221)
			(xy 133.859235 -188.7987) (xy 133.803835 -188.775752) (xy 133.751904 -188.745768) (xy 133.704331 -188.709263)
			(xy 133.66193 -188.666861) (xy 133.625426 -188.619288) (xy 133.595444 -188.567356) (xy 133.572497 -188.511956)
			(xy 133.556977 -188.454034) (xy 133.54915 -188.394582) (xy 132.79518 -188.394582) (xy 132.77852 -188.4348)
			(xy 132.74853 -188.486742) (xy 132.712017 -188.534325) (xy 132.669605 -188.576734) (xy 132.62202 -188.613245)
			(xy 132.570077 -188.643232) (xy 132.514663 -188.666182) (xy 132.456728 -188.681703) (xy 132.397263 -188.689528)
			(xy 132.367274 -188.689996) (xy 131.503674 -188.689996) (xy 131.473693 -188.689436) (xy 131.414244 -188.681607)
			(xy 131.356326 -188.666085) (xy 131.30093 -188.643136) (xy 131.249002 -188.613153) (xy 131.201432 -188.576649)
			(xy 131.159034 -188.534248) (xy 131.122533 -188.486676) (xy 131.092553 -188.434747) (xy 131.069607 -188.379349)
			(xy 131.054088 -188.32143) (xy 131.046262 -188.261981) (xy 130.434185 -188.261981) (xy 130.427555 -188.312342)
			(xy 130.412034 -188.370269) (xy 130.389084 -188.425675) (xy 130.359098 -188.47761) (xy 130.322591 -188.525188)
			(xy 130.280185 -188.567593) (xy 130.232607 -188.604101) (xy 130.180671 -188.634086) (xy 130.125266 -188.657035)
			(xy 130.067339 -188.672556) (xy 130.007881 -188.680383) (xy 129.977896 -188.680852) (xy 129.114296 -188.680852)
			(xy 129.084311 -188.680382) (xy 129.024855 -188.672554) (xy 128.966929 -188.657032) (xy 128.911524 -188.634082)
			(xy 128.859589 -188.604097) (xy 128.812012 -188.56759) (xy 128.769608 -188.525185) (xy 128.733101 -188.477607)
			(xy 128.703116 -188.425672) (xy 128.680167 -188.370267) (xy 128.664646 -188.312341) (xy 128.656818 -188.252885)
			(xy 103.554411 -188.252885) (xy 103.555799 -188.262314) (xy 103.556308 -188.2902) (xy 103.555799 -188.318086)
			(xy 103.547679 -188.373262) (xy 103.531611 -188.426669) (xy 103.507939 -188.477166) (xy 103.477166 -188.523679)
			(xy 103.439949 -188.565216) (xy 103.397081 -188.600891) (xy 103.349475 -188.629945) (xy 103.298146 -188.651757)
			(xy 103.244189 -188.665863) (xy 103.188752 -188.671963) (xy 103.133018 -188.669926) (xy 103.078175 -188.659796)
			(xy 103.025391 -188.641789) (xy 102.975791 -188.616288) (xy 102.930433 -188.583837) (xy 102.890284 -188.545128)
			(xy 102.856198 -188.500985) (xy 102.828902 -188.45235) (xy 102.808979 -188.400259) (xy 102.796853 -188.345822)
			(xy 102.792782 -188.2902) (xy 97.28956 -188.2902) (xy 97.261399 -188.32163) (xy 97.218531 -188.357305)
			(xy 97.170925 -188.386359) (xy 97.119596 -188.408171) (xy 97.065639 -188.422277) (xy 97.010202 -188.428377)
			(xy 96.954468 -188.42634) (xy 96.899625 -188.41621) (xy 96.846841 -188.398203) (xy 96.797241 -188.372702)
			(xy 96.751883 -188.340251) (xy 96.711734 -188.301542) (xy 96.677648 -188.257399) (xy 96.650352 -188.208764)
			(xy 96.630429 -188.156673) (xy 96.618303 -188.102236) (xy 96.614232 -188.046614) (xy 92.236072 -188.046614)
			(xy 91.62923 -188.65342) (xy 91.626704 -188.656051) (xy 91.622376 -188.661922) (xy 91.620594 -188.665104)
			(xy 91.620086 -188.665866) (xy 91.61653 -188.675264) (xy 91.614498 -188.68898) (xy 91.614498 -189.5602)
			(xy 94.207582 -189.5602) (xy 94.211653 -189.504578) (xy 94.223779 -189.450141) (xy 94.243702 -189.39805)
			(xy 94.270998 -189.349415) (xy 94.305084 -189.305272) (xy 94.345233 -189.266563) (xy 94.390591 -189.234112)
			(xy 94.440191 -189.208611) (xy 94.492975 -189.190604) (xy 94.547818 -189.180474) (xy 94.603552 -189.178437)
			(xy 94.658989 -189.184537) (xy 94.712946 -189.198643) (xy 94.764275 -189.220455) (xy 94.811881 -189.249509)
			(xy 94.854749 -189.285184) (xy 94.891966 -189.326721) (xy 94.922739 -189.373234) (xy 94.946411 -189.423731)
			(xy 94.962479 -189.477138) (xy 94.970599 -189.532314) (xy 94.971108 -189.5602) (xy 94.970599 -189.588086)
			(xy 94.962479 -189.643262) (xy 94.946411 -189.696669) (xy 94.922739 -189.747166) (xy 94.891966 -189.793679)
			(xy 94.854749 -189.835216) (xy 94.811881 -189.870891) (xy 94.764275 -189.899945) (xy 94.712946 -189.921757)
			(xy 94.658989 -189.935863) (xy 94.603552 -189.941963) (xy 94.547818 -189.939926) (xy 94.492975 -189.929796)
			(xy 94.440191 -189.911789) (xy 94.390591 -189.886288) (xy 94.345233 -189.853837) (xy 94.305084 -189.815128)
			(xy 94.270998 -189.770985) (xy 94.243702 -189.72235) (xy 94.223779 -189.670259) (xy 94.211653 -189.615822)
			(xy 94.207582 -189.5602) (xy 91.614498 -189.5602) (xy 91.614498 -190.5) (xy 94.182182 -190.5) (xy 94.186253 -190.444378)
			(xy 94.198379 -190.389941) (xy 94.218302 -190.33785) (xy 94.245598 -190.289215) (xy 94.279684 -190.245072)
			(xy 94.319833 -190.206363) (xy 94.365191 -190.173912) (xy 94.414791 -190.148411) (xy 94.467575 -190.130404)
			(xy 94.522418 -190.120274) (xy 94.578152 -190.118237) (xy 94.633589 -190.124337) (xy 94.687546 -190.138443)
			(xy 94.738875 -190.160255) (xy 94.786481 -190.189309) (xy 94.829349 -190.224984) (xy 94.866566 -190.266521)
			(xy 94.897339 -190.313034) (xy 94.921011 -190.363531) (xy 94.937079 -190.416938) (xy 94.945199 -190.472114)
			(xy 94.945708 -190.5) (xy 94.945199 -190.527886) (xy 94.937079 -190.583062) (xy 94.921011 -190.636469)
			(xy 94.897339 -190.686966) (xy 94.866566 -190.733479) (xy 94.829349 -190.775016) (xy 94.786481 -190.810691)
			(xy 94.738875 -190.839745) (xy 94.687546 -190.861557) (xy 94.633589 -190.875663) (xy 94.578152 -190.881763)
			(xy 94.522418 -190.879726) (xy 94.467575 -190.869596) (xy 94.414791 -190.851589) (xy 94.365191 -190.826088)
			(xy 94.319833 -190.793637) (xy 94.279684 -190.754928) (xy 94.245598 -190.710785) (xy 94.218302 -190.66215)
			(xy 94.198379 -190.610059) (xy 94.186253 -190.555622) (xy 94.182182 -190.5) (xy 91.614498 -190.5)
			(xy 91.614498 -191.280288) (xy 128.928366 -191.280288) (xy 128.932437 -191.224666) (xy 128.944563 -191.170229)
			(xy 128.964486 -191.118138) (xy 128.991782 -191.069503) (xy 129.025868 -191.02536) (xy 129.066017 -190.986651)
			(xy 129.111375 -190.9542) (xy 129.160975 -190.928699) (xy 129.213759 -190.910692) (xy 129.268602 -190.900562)
			(xy 129.324336 -190.898525) (xy 129.379773 -190.904625) (xy 129.43373 -190.918731) (xy 129.485059 -190.940543)
			(xy 129.532665 -190.969597) (xy 129.575533 -191.005272) (xy 129.61275 -191.046809) (xy 129.643523 -191.093322)
			(xy 129.667195 -191.143819) (xy 129.683263 -191.197226) (xy 129.691383 -191.252402) (xy 129.691892 -191.280288)
			(xy 129.691383 -191.308174) (xy 129.683263 -191.36335) (xy 129.667195 -191.416757) (xy 129.643523 -191.467254)
			(xy 129.61275 -191.513767) (xy 129.575533 -191.555304) (xy 129.532665 -191.590979) (xy 129.485059 -191.620033)
			(xy 129.43373 -191.641845) (xy 129.379773 -191.655951) (xy 129.324336 -191.662051) (xy 129.268602 -191.660014)
			(xy 129.213759 -191.649884) (xy 129.160975 -191.631877) (xy 129.111375 -191.606376) (xy 129.066017 -191.573925)
			(xy 129.025868 -191.535216) (xy 128.991782 -191.491073) (xy 128.964486 -191.442438) (xy 128.944563 -191.390347)
			(xy 128.932437 -191.33591) (xy 128.928366 -191.280288) (xy 91.614498 -191.280288) (xy 91.614498 -192.001436)
			(xy 130.04897 -192.001436) (xy 130.048972 -191.946932) (xy 130.056731 -191.892984) (xy 130.072089 -191.840689)
			(xy 130.094733 -191.791112) (xy 130.124201 -191.745262) (xy 130.159895 -191.704072) (xy 130.201088 -191.668382)
			(xy 130.24694 -191.638917) (xy 130.296519 -191.616278) (xy 130.348815 -191.600925) (xy 130.402764 -191.59317)
			(xy 130.430016 -191.592708) (xy 130.443986 -191.592962) (xy 130.4574 -191.593097) (xy 130.483522 -191.587017)
			(xy 130.507163 -191.57435) (xy 130.526692 -191.555966) (xy 130.540766 -191.533135) (xy 130.548413 -191.507427)
			(xy 130.549107 -191.480616) (xy 130.546348 -191.467486) (xy 130.541379 -191.445533) (xy 130.536037 -191.400838)
			(xy 130.53568 -191.378332) (xy 130.53568 -191.37757) (xy 130.53621 -191.350321) (xy 130.54397 -191.296379)
			(xy 130.559328 -191.24409) (xy 130.581971 -191.194519) (xy 130.611438 -191.148675) (xy 130.647129 -191.107491)
			(xy 130.688318 -191.071805) (xy 130.734166 -191.042345) (xy 130.783741 -191.019709) (xy 130.836032 -191.004359)
			(xy 130.889975 -190.996606) (xy 130.944473 -190.99661) (xy 130.998415 -191.004369) (xy 131.050704 -191.019726)
			(xy 131.100276 -191.042368) (xy 131.14612 -191.071834) (xy 131.187305 -191.107525) (xy 131.222991 -191.148713)
			(xy 131.252452 -191.194561) (xy 131.275089 -191.244135) (xy 131.29044 -191.296426) (xy 131.298193 -191.350369)
			(xy 131.298193 -191.360298) (xy 132.865874 -191.360298) (xy 132.869945 -191.304676) (xy 132.882071 -191.250239)
			(xy 132.901994 -191.198148) (xy 132.92929 -191.149513) (xy 132.963376 -191.10537) (xy 133.003525 -191.066661)
			(xy 133.048883 -191.03421) (xy 133.098483 -191.008709) (xy 133.151267 -190.990702) (xy 133.20611 -190.980572)
			(xy 133.261844 -190.978535) (xy 133.317281 -190.984635) (xy 133.371238 -190.998741) (xy 133.422567 -191.020553)
			(xy 133.470173 -191.049607) (xy 133.513041 -191.085282) (xy 133.550258 -191.126819) (xy 133.581031 -191.173332)
			(xy 133.604703 -191.223829) (xy 133.620771 -191.277236) (xy 133.628891 -191.332412) (xy 133.6294 -191.360298)
			(xy 133.628891 -191.388184) (xy 133.620771 -191.44336) (xy 133.604703 -191.496767) (xy 133.581031 -191.547264)
			(xy 133.550258 -191.593777) (xy 133.513041 -191.635314) (xy 133.470173 -191.670989) (xy 133.422567 -191.700043)
			(xy 133.371238 -191.721855) (xy 133.317281 -191.735961) (xy 133.261844 -191.742061) (xy 133.20611 -191.740024)
			(xy 133.151267 -191.729894) (xy 133.098483 -191.711887) (xy 133.048883 -191.686386) (xy 133.003525 -191.653935)
			(xy 132.963376 -191.615226) (xy 132.92929 -191.571083) (xy 132.901994 -191.522448) (xy 132.882071 -191.470357)
			(xy 132.869945 -191.41592) (xy 132.865874 -191.360298) (xy 131.298193 -191.360298) (xy 131.298191 -191.404867)
			(xy 131.290432 -191.458809) (xy 131.275076 -191.511099) (xy 131.252435 -191.56067) (xy 131.222969 -191.606516)
			(xy 131.187279 -191.647701) (xy 131.146092 -191.683387) (xy 131.100244 -191.712849) (xy 131.050671 -191.735487)
			(xy 130.99838 -191.750839) (xy 130.944437 -191.758593) (xy 130.917188 -191.759078) (xy 130.903218 -191.758824)
			(xy 130.889805 -191.75871) (xy 130.863686 -191.764787) (xy 130.840047 -191.777452) (xy 130.820518 -191.795832)
			(xy 130.806445 -191.81866) (xy 130.798796 -191.844363) (xy 130.798099 -191.871172) (xy 130.800856 -191.8843)
			(xy 130.805823 -191.906254) (xy 130.811167 -191.950948) (xy 130.811524 -191.973454) (xy 130.811524 -191.974216)
			(xy 130.811028 -192.001468) (xy 130.803269 -192.055416) (xy 130.787911 -192.107711) (xy 130.765267 -192.157288)
			(xy 130.735799 -192.203138) (xy 130.700105 -192.244328) (xy 130.658912 -192.280018) (xy 130.61306 -192.309483)
			(xy 130.563481 -192.332122) (xy 130.511185 -192.347475) (xy 130.457236 -192.35523) (xy 130.402732 -192.355228)
			(xy 130.348784 -192.347469) (xy 130.296489 -192.332111) (xy 130.246912 -192.309467) (xy 130.201062 -192.279999)
			(xy 130.159872 -192.244305) (xy 130.124182 -192.203112) (xy 130.094717 -192.15726) (xy 130.072078 -192.107681)
			(xy 130.056725 -192.055385) (xy 130.04897 -192.001436) (xy 91.614498 -192.001436) (xy 91.614498 -193.001138)
			(xy 108.648244 -193.001138) (xy 108.652315 -192.945516) (xy 108.664441 -192.891079) (xy 108.684364 -192.838988)
			(xy 108.71166 -192.790353) (xy 108.745746 -192.74621) (xy 108.785895 -192.707501) (xy 108.831253 -192.67505)
			(xy 108.880853 -192.649549) (xy 108.933637 -192.631542) (xy 108.98848 -192.621412) (xy 109.044214 -192.619375)
			(xy 109.099651 -192.625475) (xy 109.153608 -192.639581) (xy 109.204937 -192.661393) (xy 109.252543 -192.690447)
			(xy 109.295411 -192.726122) (xy 109.332628 -192.767659) (xy 109.363401 -192.814172) (xy 109.387073 -192.864669)
			(xy 109.403141 -192.918076) (xy 109.411261 -192.973252) (xy 109.41177 -193.001138) (xy 109.411261 -193.029024)
			(xy 109.403141 -193.0842) (xy 109.387073 -193.137607) (xy 109.363401 -193.188104) (xy 109.332628 -193.234617)
			(xy 109.295411 -193.276154) (xy 109.252543 -193.311829) (xy 109.204937 -193.340883) (xy 109.153608 -193.362695)
			(xy 109.099651 -193.376801) (xy 109.044214 -193.382901) (xy 108.98848 -193.380864) (xy 108.933637 -193.370734)
			(xy 108.880853 -193.352727) (xy 108.831253 -193.327226) (xy 108.785895 -193.294775) (xy 108.745746 -193.256066)
			(xy 108.71166 -193.211923) (xy 108.684364 -193.163288) (xy 108.664441 -193.111197) (xy 108.652315 -193.05676)
			(xy 108.648244 -193.001138) (xy 91.614498 -193.001138) (xy 91.614498 -193.543428) (xy 131.837428 -193.543428)
			(xy 131.841499 -193.487806) (xy 131.853625 -193.433369) (xy 131.873548 -193.381278) (xy 131.900844 -193.332643)
			(xy 131.93493 -193.2885) (xy 131.975079 -193.249791) (xy 132.020437 -193.21734) (xy 132.070037 -193.191839)
			(xy 132.122821 -193.173832) (xy 132.177664 -193.163702) (xy 132.233398 -193.161665) (xy 132.288835 -193.167765)
			(xy 132.342792 -193.181871) (xy 132.394121 -193.203683) (xy 132.441727 -193.232737) (xy 132.484595 -193.268412)
			(xy 132.521812 -193.309949) (xy 132.552585 -193.356462) (xy 132.576257 -193.406959) (xy 132.592325 -193.460366)
			(xy 132.600445 -193.515542) (xy 132.600954 -193.543428) (xy 132.600445 -193.571314) (xy 132.592325 -193.62649)
			(xy 132.576257 -193.679897) (xy 132.552585 -193.730394) (xy 132.521812 -193.776907) (xy 132.484595 -193.818444)
			(xy 132.441727 -193.854119) (xy 132.394121 -193.883173) (xy 132.342792 -193.904985) (xy 132.288835 -193.919091)
			(xy 132.233398 -193.925191) (xy 132.177664 -193.923154) (xy 132.122821 -193.913024) (xy 132.070037 -193.895017)
			(xy 132.020437 -193.869516) (xy 131.975079 -193.837065) (xy 131.93493 -193.798356) (xy 131.900844 -193.754213)
			(xy 131.873548 -193.705578) (xy 131.853625 -193.653487) (xy 131.841499 -193.59905) (xy 131.837428 -193.543428)
			(xy 91.614498 -193.543428) (xy 91.614498 -194.618651) (xy 93.704387 -194.618651) (xy 93.704387 -194.564149)
			(xy 93.712144 -194.510202) (xy 93.727499 -194.457907) (xy 93.75014 -194.408331) (xy 93.779607 -194.362481)
			(xy 93.815299 -194.321292) (xy 93.856489 -194.285601) (xy 93.90234 -194.256136) (xy 93.951917 -194.233496)
			(xy 94.004211 -194.218142) (xy 94.058159 -194.210387) (xy 94.08541 -194.209924) (xy 94.112557 -194.210397)
			(xy 94.166299 -194.218116) (xy 94.218406 -194.233369) (xy 94.267828 -194.255848) (xy 94.313568 -194.2851)
			(xy 94.354704 -194.320535) (xy 94.390406 -194.36144) (xy 94.419956 -194.406988) (xy 94.442756 -194.456263)
			(xy 94.458348 -194.508269) (xy 94.462854 -194.535044) (xy 94.462854 -194.535298) (xy 94.464558 -194.544101)
			(xy 94.473145 -194.559826) (xy 94.486624 -194.57163) (xy 94.494858 -194.575176) (xy 94.589854 -194.612006)
			(xy 94.616778 -194.607688) (xy 94.627446 -194.598798) (xy 94.647958 -194.582592) (xy 94.692585 -194.555367)
			(xy 94.740506 -194.534479) (xy 94.790827 -194.520316) (xy 94.842608 -194.513143) (xy 94.868746 -194.512692)
			(xy 94.869 -194.512692) (xy 94.895314 -194.513162) (xy 94.947442 -194.520397) (xy 94.998085 -194.534715)
			(xy 95.046284 -194.555847) (xy 95.091127 -194.583393) (xy 95.131767 -194.616831) (xy 95.149924 -194.635882)
			(xy 95.157437 -194.643294) (xy 95.176724 -194.651813) (xy 95.187262 -194.652392) (xy 95.261938 -194.652392)
			(xy 95.272486 -194.651845) (xy 95.291781 -194.643323) (xy 95.299276 -194.635882) (xy 95.317447 -194.616842)
			(xy 95.358074 -194.583384) (xy 95.402911 -194.555823) (xy 95.451109 -194.534682) (xy 95.501753 -194.520362)
			(xy 95.553885 -194.513133) (xy 95.5802 -194.512692) (xy 95.607451 -194.513178) (xy 95.661399 -194.520934)
			(xy 95.713694 -194.536289) (xy 95.763271 -194.558931) (xy 95.809121 -194.588397) (xy 95.850312 -194.624088)
			(xy 95.886003 -194.665279) (xy 95.915469 -194.711129) (xy 95.938111 -194.760706) (xy 95.953466 -194.813001)
			(xy 95.961222 -194.866949) (xy 95.961222 -194.921451) (xy 95.953466 -194.975399) (xy 95.938111 -195.027694)
			(xy 95.915469 -195.077271) (xy 95.886003 -195.123121) (xy 95.850312 -195.164312) (xy 95.809121 -195.200003)
			(xy 95.763271 -195.229469) (xy 95.713694 -195.252111) (xy 95.661399 -195.267466) (xy 95.607451 -195.275222)
			(xy 95.5802 -195.275708) (xy 95.553886 -195.275238) (xy 95.501758 -195.268003) (xy 95.451115 -195.253685)
			(xy 95.402916 -195.232553) (xy 95.358073 -195.205007) (xy 95.317433 -195.171569) (xy 95.299276 -195.152518)
			(xy 95.291763 -195.145106) (xy 95.272476 -195.136587) (xy 95.261938 -195.136008) (xy 95.187262 -195.136008)
			(xy 95.176714 -195.136555) (xy 95.157419 -195.145077) (xy 95.149924 -195.152518) (xy 95.131753 -195.171558)
			(xy 95.091126 -195.205016) (xy 95.046289 -195.232577) (xy 94.998091 -195.253718) (xy 94.947447 -195.268038)
			(xy 94.895315 -195.275267) (xy 94.869 -195.275708) (xy 94.841855 -195.275198) (xy 94.788115 -195.267481)
			(xy 94.73601 -195.252231) (xy 94.686591 -195.229756) (xy 94.640852 -195.200508) (xy 94.599716 -195.165077)
			(xy 94.564013 -195.124177) (xy 94.534463 -195.078633) (xy 94.51166 -195.029363) (xy 94.496065 -194.977361)
			(xy 94.491556 -194.950588) (xy 94.491556 -194.950334) (xy 94.489888 -194.941522) (xy 94.481283 -194.925799)
			(xy 94.467791 -194.913999) (xy 94.459552 -194.910456) (xy 94.364556 -194.873626) (xy 94.337632 -194.877944)
			(xy 94.326964 -194.886834) (xy 94.306452 -194.90304) (xy 94.261825 -194.930264) (xy 94.213903 -194.951152)
			(xy 94.163583 -194.965315) (xy 94.111801 -194.972488) (xy 94.085664 -194.97294) (xy 94.08541 -194.97294)
			(xy 94.058159 -194.972413) (xy 94.004211 -194.964658) (xy 93.951917 -194.949304) (xy 93.90234 -194.926664)
			(xy 93.856489 -194.897199) (xy 93.815299 -194.861508) (xy 93.779607 -194.820319) (xy 93.75014 -194.774469)
			(xy 93.727499 -194.724893) (xy 93.712144 -194.672598) (xy 93.704387 -194.618651) (xy 91.614498 -194.618651)
			(xy 91.614498 -195.3768) (xy 96.087182 -195.3768) (xy 96.091253 -195.321178) (xy 96.103379 -195.266741)
			(xy 96.123302 -195.21465) (xy 96.150598 -195.166015) (xy 96.184684 -195.121872) (xy 96.224833 -195.083163)
			(xy 96.270191 -195.050712) (xy 96.319791 -195.025211) (xy 96.372575 -195.007204) (xy 96.427418 -194.997074)
			(xy 96.483152 -194.995037) (xy 96.538589 -195.001137) (xy 96.592546 -195.015243) (xy 96.643875 -195.037055)
			(xy 96.691481 -195.066109) (xy 96.734349 -195.101784) (xy 96.771566 -195.143321) (xy 96.802339 -195.189834)
			(xy 96.826011 -195.240331) (xy 96.842079 -195.293738) (xy 96.850199 -195.348914) (xy 96.850708 -195.3768)
			(xy 96.850199 -195.404686) (xy 96.842079 -195.459862) (xy 96.826011 -195.513269) (xy 96.802339 -195.563766)
			(xy 96.771566 -195.610279) (xy 96.734349 -195.651816) (xy 96.691481 -195.687491) (xy 96.643875 -195.716545)
			(xy 96.621418 -195.726088) (xy 126.922185 -195.726088) (xy 126.922185 -195.666112) (xy 126.930014 -195.606648)
			(xy 126.945538 -195.548715) (xy 126.968491 -195.493304) (xy 126.99848 -195.441364) (xy 127.034993 -195.393782)
			(xy 127.077404 -195.351373) (xy 127.124989 -195.314864) (xy 127.176931 -195.284878) (xy 127.232344 -195.261928)
			(xy 127.290278 -195.246408) (xy 127.349742 -195.238583) (xy 127.37973 -195.238116) (xy 128.24333 -195.238116)
			(xy 128.273312 -195.238652) (xy 128.332761 -195.246482) (xy 128.39068 -195.262005) (xy 128.446078 -195.284955)
			(xy 128.498007 -195.314939) (xy 128.545577 -195.351444) (xy 128.587976 -195.393845) (xy 128.624478 -195.441418)
			(xy 128.654459 -195.493349) (xy 128.677405 -195.548748) (xy 128.692924 -195.606668) (xy 128.70075 -195.666118)
			(xy 128.70075 -195.726082) (xy 128.692924 -195.785532) (xy 128.677405 -195.843452) (xy 128.654459 -195.898851)
			(xy 128.624478 -195.950782) (xy 128.587976 -195.998355) (xy 128.545577 -196.040756) (xy 128.498007 -196.077261)
			(xy 128.446078 -196.107245) (xy 128.39068 -196.130195) (xy 128.332761 -196.145718) (xy 128.273312 -196.153548)
			(xy 128.24333 -196.15404) (xy 127.37973 -196.15404) (xy 127.349742 -196.153617) (xy 127.290278 -196.145792)
			(xy 127.232344 -196.130272) (xy 127.176931 -196.107322) (xy 127.124989 -196.077336) (xy 127.077404 -196.040827)
			(xy 127.034993 -195.998418) (xy 126.99848 -195.950836) (xy 126.968491 -195.898896) (xy 126.945538 -195.843485)
			(xy 126.930014 -195.785552) (xy 126.922185 -195.726088) (xy 96.621418 -195.726088) (xy 96.592546 -195.738357)
			(xy 96.538589 -195.752463) (xy 96.483152 -195.758563) (xy 96.427418 -195.756526) (xy 96.372575 -195.746396)
			(xy 96.319791 -195.728389) (xy 96.270191 -195.702888) (xy 96.224833 -195.670437) (xy 96.184684 -195.631728)
			(xy 96.150598 -195.587585) (xy 96.123302 -195.53895) (xy 96.103379 -195.486859) (xy 96.091253 -195.432422)
			(xy 96.087182 -195.3768) (xy 91.614498 -195.3768) (xy 91.614498 -196.5833) (xy 92.543882 -196.5833)
			(xy 92.547953 -196.527678) (xy 92.560079 -196.473241) (xy 92.580002 -196.42115) (xy 92.607298 -196.372515)
			(xy 92.641384 -196.328372) (xy 92.681533 -196.289663) (xy 92.726891 -196.257212) (xy 92.776491 -196.231711)
			(xy 92.829275 -196.213704) (xy 92.884118 -196.203574) (xy 92.939852 -196.201537) (xy 92.995289 -196.207637)
			(xy 93.049246 -196.221743) (xy 93.100575 -196.243555) (xy 93.148181 -196.272609) (xy 93.191049 -196.308284)
			(xy 93.228266 -196.349821) (xy 93.257205 -196.393562) (xy 130.059936 -196.393562) (xy 130.064007 -196.33794)
			(xy 130.076133 -196.283503) (xy 130.096056 -196.231412) (xy 130.123352 -196.182777) (xy 130.157438 -196.138634)
			(xy 130.197587 -196.099925) (xy 130.242945 -196.067474) (xy 130.292545 -196.041973) (xy 130.345329 -196.023966)
			(xy 130.400172 -196.013836) (xy 130.455906 -196.011799) (xy 130.511343 -196.017899) (xy 130.5653 -196.032005)
			(xy 130.616629 -196.053817) (xy 130.664235 -196.082871) (xy 130.707103 -196.118546) (xy 130.74432 -196.160083)
			(xy 130.775093 -196.206596) (xy 130.798765 -196.257093) (xy 130.814833 -196.3105) (xy 130.822953 -196.365676)
			(xy 130.823462 -196.393562) (xy 130.822953 -196.421448) (xy 130.820104 -196.440806) (xy 131.909564 -196.440806)
			(xy 131.913635 -196.385184) (xy 131.925761 -196.330747) (xy 131.945684 -196.278656) (xy 131.97298 -196.230021)
			(xy 132.007066 -196.185878) (xy 132.047215 -196.147169) (xy 132.092573 -196.114718) (xy 132.142173 -196.089217)
			(xy 132.194957 -196.07121) (xy 132.2498 -196.06108) (xy 132.305534 -196.059043) (xy 132.360971 -196.065143)
			(xy 132.414928 -196.079249) (xy 132.466257 -196.101061) (xy 132.513863 -196.130115) (xy 132.556731 -196.16579)
			(xy 132.593948 -196.207327) (xy 132.624721 -196.25384) (xy 132.648393 -196.304337) (xy 132.664461 -196.357744)
			(xy 132.672581 -196.41292) (xy 132.67309 -196.440806) (xy 132.672581 -196.468692) (xy 132.664461 -196.523868)
			(xy 132.648393 -196.577275) (xy 132.624721 -196.627772) (xy 132.593948 -196.674285) (xy 132.556731 -196.715822)
			(xy 132.513863 -196.751497) (xy 132.466257 -196.780551) (xy 132.414928 -196.802363) (xy 132.360971 -196.816469)
			(xy 132.305534 -196.822569) (xy 132.2498 -196.820532) (xy 132.194957 -196.810402) (xy 132.142173 -196.792395)
			(xy 132.092573 -196.766894) (xy 132.047215 -196.734443) (xy 132.007066 -196.695734) (xy 131.97298 -196.651591)
			(xy 131.945684 -196.602956) (xy 131.925761 -196.550865) (xy 131.913635 -196.496428) (xy 131.909564 -196.440806)
			(xy 130.820104 -196.440806) (xy 130.814833 -196.476624) (xy 130.798765 -196.530031) (xy 130.775093 -196.580528)
			(xy 130.74432 -196.627041) (xy 130.707103 -196.668578) (xy 130.664235 -196.704253) (xy 130.616629 -196.733307)
			(xy 130.5653 -196.755119) (xy 130.511343 -196.769225) (xy 130.455906 -196.775325) (xy 130.400172 -196.773288)
			(xy 130.345329 -196.763158) (xy 130.292545 -196.745151) (xy 130.242945 -196.71965) (xy 130.197587 -196.687199)
			(xy 130.157438 -196.64849) (xy 130.123352 -196.604347) (xy 130.096056 -196.555712) (xy 130.076133 -196.503621)
			(xy 130.064007 -196.449184) (xy 130.059936 -196.393562) (xy 93.257205 -196.393562) (xy 93.259039 -196.396334)
			(xy 93.282711 -196.446831) (xy 93.298779 -196.500238) (xy 93.306899 -196.555414) (xy 93.307408 -196.5833)
			(xy 93.306899 -196.611186) (xy 93.298779 -196.666362) (xy 93.282711 -196.719769) (xy 93.259039 -196.770266)
			(xy 93.228266 -196.816779) (xy 93.191049 -196.858316) (xy 93.148181 -196.893991) (xy 93.100575 -196.923045)
			(xy 93.049246 -196.944857) (xy 92.995289 -196.958963) (xy 92.939852 -196.965063) (xy 92.884118 -196.963026)
			(xy 92.829275 -196.952896) (xy 92.776491 -196.934889) (xy 92.726891 -196.909388) (xy 92.681533 -196.876937)
			(xy 92.641384 -196.838228) (xy 92.607298 -196.794085) (xy 92.580002 -196.74545) (xy 92.560079 -196.693359)
			(xy 92.547953 -196.638922) (xy 92.543882 -196.5833) (xy 91.614498 -196.5833) (xy 91.614498 -198.76897)
			(xy 94.538544 -198.76897) (xy 94.542615 -198.713348) (xy 94.554741 -198.658911) (xy 94.574664 -198.60682)
			(xy 94.60196 -198.558185) (xy 94.636046 -198.514042) (xy 94.676195 -198.475333) (xy 94.721553 -198.442882)
			(xy 94.771153 -198.417381) (xy 94.823937 -198.399374) (xy 94.87878 -198.389244) (xy 94.934514 -198.387207)
			(xy 94.989951 -198.393307) (xy 95.043908 -198.407413) (xy 95.095237 -198.429225) (xy 95.142843 -198.458279)
			(xy 95.185711 -198.493954) (xy 95.222928 -198.535491) (xy 95.253701 -198.582004) (xy 95.277373 -198.632501)
			(xy 95.293441 -198.685908) (xy 95.301561 -198.741084) (xy 95.30207 -198.76897) (xy 95.301736 -198.787258)
			(xy 96.222056 -198.787258) (xy 96.226127 -198.731636) (xy 96.238253 -198.677199) (xy 96.258176 -198.625108)
			(xy 96.285472 -198.576473) (xy 96.319558 -198.53233) (xy 96.359707 -198.493621) (xy 96.405065 -198.46117)
			(xy 96.454665 -198.435669) (xy 96.507449 -198.417662) (xy 96.562292 -198.407532) (xy 96.618026 -198.405495)
			(xy 96.673463 -198.411595) (xy 96.72742 -198.425701) (xy 96.778749 -198.447513) (xy 96.826355 -198.476567)
			(xy 96.869223 -198.512242) (xy 96.90644 -198.553779) (xy 96.937213 -198.600292) (xy 96.960885 -198.650789)
			(xy 96.976953 -198.704196) (xy 96.985073 -198.759372) (xy 96.985582 -198.787258) (xy 96.985073 -198.815144)
			(xy 96.976953 -198.87032) (xy 96.960885 -198.923727) (xy 96.937213 -198.974224) (xy 96.90644 -199.020737)
			(xy 96.869223 -199.062274) (xy 96.826355 -199.097949) (xy 96.778749 -199.127003) (xy 96.72742 -199.148815)
			(xy 96.673463 -199.162921) (xy 96.618026 -199.169021) (xy 96.562292 -199.166984) (xy 96.507449 -199.156854)
			(xy 96.454665 -199.138847) (xy 96.405065 -199.113346) (xy 96.359707 -199.080895) (xy 96.319558 -199.042186)
			(xy 96.285472 -198.998043) (xy 96.258176 -198.949408) (xy 96.238253 -198.897317) (xy 96.226127 -198.84288)
			(xy 96.222056 -198.787258) (xy 95.301736 -198.787258) (xy 95.301561 -198.796856) (xy 95.293441 -198.852032)
			(xy 95.277373 -198.905439) (xy 95.253701 -198.955936) (xy 95.222928 -199.002449) (xy 95.185711 -199.043986)
			(xy 95.142843 -199.079661) (xy 95.095237 -199.108715) (xy 95.043908 -199.130527) (xy 94.989951 -199.144633)
			(xy 94.934514 -199.150733) (xy 94.87878 -199.148696) (xy 94.823937 -199.138566) (xy 94.771153 -199.120559)
			(xy 94.721553 -199.095058) (xy 94.676195 -199.062607) (xy 94.636046 -199.023898) (xy 94.60196 -198.979755)
			(xy 94.574664 -198.93112) (xy 94.554741 -198.879029) (xy 94.542615 -198.824592) (xy 94.538544 -198.76897)
			(xy 91.614498 -198.76897) (xy 91.614498 -199.3138) (xy 102.995982 -199.3138) (xy 103.000053 -199.258178)
			(xy 103.012179 -199.203741) (xy 103.032102 -199.15165) (xy 103.059398 -199.103015) (xy 103.093484 -199.058872)
			(xy 103.133633 -199.020163) (xy 103.178991 -198.987712) (xy 103.228591 -198.962211) (xy 103.281375 -198.944204)
			(xy 103.336218 -198.934074) (xy 103.391952 -198.932037) (xy 103.447389 -198.938137) (xy 103.501346 -198.952243)
			(xy 103.552675 -198.974055) (xy 103.600281 -199.003109) (xy 103.643149 -199.038784) (xy 103.680366 -199.080321)
			(xy 103.711139 -199.126834) (xy 103.734811 -199.177331) (xy 103.750879 -199.230738) (xy 103.758999 -199.285914)
			(xy 103.759508 -199.3138) (xy 103.758999 -199.341686) (xy 103.750879 -199.396862) (xy 103.734811 -199.450269)
			(xy 103.711139 -199.500766) (xy 103.680366 -199.547279) (xy 103.643149 -199.588816) (xy 103.600281 -199.624491)
			(xy 103.552675 -199.653545) (xy 103.501346 -199.675357) (xy 103.447389 -199.689463) (xy 103.391952 -199.695563)
			(xy 103.336218 -199.693526) (xy 103.281375 -199.683396) (xy 103.228591 -199.665389) (xy 103.178991 -199.639888)
			(xy 103.133633 -199.607437) (xy 103.093484 -199.568728) (xy 103.059398 -199.524585) (xy 103.032102 -199.47595)
			(xy 103.012179 -199.423859) (xy 103.000053 -199.369422) (xy 102.995982 -199.3138) (xy 91.614498 -199.3138)
			(xy 91.614498 -199.854312) (xy 91.615514 -199.86371) (xy 91.615514 -199.864218) (xy 91.617223 -199.871375)
			(xy 91.624064 -199.884393) (xy 91.628976 -199.889872) (xy 91.926918 -200.187814) (xy 91.932347 -200.192797)
			(xy 91.945385 -200.199649) (xy 91.952572 -200.201276) (xy 91.95308 -200.201276) (xy 91.962478 -200.202292)
			(xy 96.244918 -200.202292) (xy 96.257011 -200.201426) (xy 96.278358 -200.190011) (xy 96.285812 -200.180448)
			(xy 96.303846 -200.151746) (xy 96.303846 -200.151238) (xy 96.328484 -200.11136) (xy 96.332776 -200.103831)
			(xy 96.3365 -200.086916) (xy 96.334331 -200.069733) (xy 96.33077 -200.06183) (xy 96.330516 -200.061576)
			(xy 96.328992 -200.058274) (xy 96.325182 -200.050654) (xy 96.312805 -200.024097) (xy 96.295298 -199.968185)
			(xy 96.2864 -199.910276) (xy 96.285812 -199.880982) (xy 96.285812 -199.880728) (xy 96.286307 -199.852987)
			(xy 96.294203 -199.798069) (xy 96.309834 -199.744835) (xy 96.332882 -199.694366) (xy 96.362878 -199.647692)
			(xy 96.399211 -199.605761) (xy 96.441142 -199.569428) (xy 96.487816 -199.539432) (xy 96.538285 -199.516384)
			(xy 96.591519 -199.500753) (xy 96.646437 -199.492857) (xy 96.701919 -199.492857) (xy 96.756837 -199.500753)
			(xy 96.810071 -199.516384) (xy 96.86054 -199.539432) (xy 96.907214 -199.569428) (xy 96.949145 -199.605761)
			(xy 96.985478 -199.647692) (xy 97.015474 -199.694366) (xy 97.038522 -199.744835) (xy 97.054153 -199.798069)
			(xy 97.062049 -199.852987) (xy 97.062544 -199.880728) (xy 97.062544 -199.881236) (xy 97.061975 -199.911415)
			(xy 97.052637 -199.971045) (xy 97.034177 -200.028509) (xy 97.021142 -200.055734) (xy 97.018348 -200.061322)
			(xy 97.012506 -200.084944) (xy 97.012757 -200.090758) (xy 97.015589 -200.102043) (xy 97.018094 -200.107296)
			(xy 97.024952 -200.119234) (xy 97.02546 -200.119742) (xy 97.043748 -200.150476) (xy 97.049336 -200.159366)
			(xy 97.04959 -200.15962) (xy 97.05848 -200.174098) (xy 97.065846 -200.183496) (xy 97.070164 -200.187814)
			(xy 97.075841 -200.193012) (xy 97.089544 -200.200004) (xy 97.097088 -200.20153) (xy 97.097596 -200.20153)
			(xy 97.105724 -200.202292) (xy 100.707952 -200.202292) (xy 100.71295 -200.201918) (xy 100.722672 -200.19949)
			(xy 100.727256 -200.197466) (xy 100.738432 -200.192386) (xy 100.739448 -200.191878) (xy 100.74656 -200.188322)
			(xy 100.75164 -200.185274) (xy 100.75926 -200.179432) (xy 100.763324 -200.174098) (xy 100.780069 -200.152943)
			(xy 100.818529 -200.115108) (xy 100.861935 -200.083067) (xy 100.909421 -200.057459) (xy 100.96004 -200.038793)
			(xy 101.012784 -200.027443) (xy 101.0666 -200.023635) (xy 101.120416 -200.027443) (xy 101.17316 -200.038793)
			(xy 101.223779 -200.057459) (xy 101.271265 -200.083067) (xy 101.314671 -200.115108) (xy 101.353131 -200.152943)
			(xy 101.369876 -200.174098) (xy 101.37394 -200.179432) (xy 101.378258 -200.182734) (xy 101.38664 -200.188322)
			(xy 101.402388 -200.195942) (xy 101.406452 -200.197974) (xy 101.409982 -200.199481) (xy 101.417382 -200.201514)
			(xy 101.421184 -200.202038) (xy 101.425502 -200.202292) (xy 102.729792 -200.202292) (xy 102.740968 -200.201022)
			(xy 102.749858 -200.199244) (xy 102.768146 -200.18756) (xy 102.768654 -200.187052) (xy 102.780084 -200.17994)
			(xy 102.787958 -200.172828) (xy 102.792276 -200.168002) (xy 102.795578 -200.161652) (xy 102.795832 -200.161398)
			(xy 102.795832 -200.16089) (xy 102.8101 -200.133922) (xy 102.843841 -200.083086) (xy 102.883108 -200.036387)
			(xy 102.927401 -199.994424) (xy 102.97615 -199.957733) (xy 103.028733 -199.926785) (xy 103.056436 -199.914002)
			(xy 103.087592 -199.900623) (xy 103.15247 -199.880911) (xy 103.219308 -199.869491) (xy 103.28705 -199.866543)
			(xy 103.354627 -199.872112) (xy 103.420972 -199.886112) (xy 103.485039 -199.90832) (xy 103.545814 -199.938387)
			(xy 103.60234 -199.975838) (xy 103.653722 -200.020082) (xy 103.699152 -200.07042) (xy 103.73791 -200.126057)
			(xy 103.754174 -200.15581) (xy 103.756968 -200.161398) (xy 103.770938 -200.177146) (xy 103.780844 -200.18502)
			(xy 103.782368 -200.186036) (xy 103.783892 -200.186798) (xy 103.799386 -200.196704) (xy 103.804282 -200.199076)
			(xy 103.814788 -200.201892) (xy 103.820214 -200.202292) (xy 106.656886 -200.202292) (xy 106.670439 -200.201868)
			(xy 106.69659 -200.194736) (xy 106.719943 -200.180973) (xy 106.738849 -200.161549) (xy 106.751975 -200.137833)
			(xy 106.758397 -200.111499) (xy 106.75766 -200.084402) (xy 106.749817 -200.058456) (xy 106.735421 -200.035488)
			(xy 106.72572 -200.026016) (xy 106.706732 -200.007878) (xy 106.673412 -199.967293) (xy 106.645971 -199.922522)
			(xy 106.624927 -199.874413) (xy 106.610678 -199.823872) (xy 106.603492 -199.771856) (xy 106.603038 -199.7456)
			(xy 106.603524 -199.718331) (xy 106.611286 -199.664347) (xy 106.626651 -199.612017) (xy 106.649308 -199.562407)
			(xy 106.678794 -199.516526) (xy 106.714509 -199.475309) (xy 106.755726 -199.439594) (xy 106.801607 -199.410108)
			(xy 106.851217 -199.387451) (xy 106.903547 -199.372086) (xy 106.957531 -199.364324) (xy 107.012069 -199.364324)
			(xy 107.066053 -199.372086) (xy 107.118383 -199.387451) (xy 107.161227 -199.407018) (xy 109.422944 -199.407018)
			(xy 109.427015 -199.351396) (xy 109.439141 -199.296959) (xy 109.459064 -199.244868) (xy 109.48636 -199.196233)
			(xy 109.520446 -199.15209) (xy 109.560595 -199.113381) (xy 109.605953 -199.08093) (xy 109.655553 -199.055429)
			(xy 109.708337 -199.037422) (xy 109.76318 -199.027292) (xy 109.818914 -199.025255) (xy 109.874351 -199.031355)
			(xy 109.928308 -199.045461) (xy 109.979637 -199.067273) (xy 110.016086 -199.089518) (xy 127.763014 -199.089518)
			(xy 127.767085 -199.033896) (xy 127.779211 -198.979459) (xy 127.799134 -198.927368) (xy 127.82643 -198.878733)
			(xy 127.860516 -198.83459) (xy 127.900665 -198.795881) (xy 127.946023 -198.76343) (xy 127.995623 -198.737929)
			(xy 128.048407 -198.719922) (xy 128.10325 -198.709792) (xy 128.158984 -198.707755) (xy 128.214421 -198.713855)
			(xy 128.268378 -198.727961) (xy 128.319707 -198.749773) (xy 128.367313 -198.778827) (xy 128.410181 -198.814502)
			(xy 128.447398 -198.856039) (xy 128.478171 -198.902552) (xy 128.501843 -198.953049) (xy 128.510508 -198.98185)
			(xy 129.991599 -198.98185) (xy 129.991599 -198.92735) (xy 129.999356 -198.873404) (xy 130.014711 -198.821111)
			(xy 130.037351 -198.771536) (xy 130.066817 -198.725688) (xy 130.102508 -198.684499) (xy 130.143697 -198.64881)
			(xy 130.189547 -198.619346) (xy 130.239122 -198.596706) (xy 130.291416 -198.581353) (xy 130.345362 -198.573598)
			(xy 130.372612 -198.573136) (xy 130.403415 -198.573743) (xy 130.464216 -198.583669) (xy 130.52263 -198.603244)
			(xy 130.550158 -198.617078) (xy 130.555689 -198.619777) (xy 130.567629 -198.622744) (xy 130.57378 -198.62292)
			(xy 132.681218 -198.62292) (xy 132.691291 -198.622525) (xy 132.70989 -198.614785) (xy 132.717286 -198.607934)
			(xy 133.63321 -197.691756) (xy 133.640063 -197.684366) (xy 133.647775 -197.665759) (xy 133.648196 -197.655688)
			(xy 133.648196 -192.4304) (xy 133.64867 -192.404312) (xy 133.656838 -192.35278) (xy 133.672973 -192.303161)
			(xy 133.696676 -192.256681) (xy 133.727364 -192.214484) (xy 133.745478 -192.195704) (xy 137.047732 -188.89345)
			(xy 137.066503 -188.875327) (xy 137.108704 -188.844644) (xy 137.155187 -188.820945) (xy 137.204807 -188.804815)
			(xy 137.25634 -188.796652) (xy 137.282428 -188.796168) (xy 141.498574 -188.796168) (xy 141.50975 -188.793628)
			(xy 141.515084 -188.790834) (xy 141.5161 -188.790326) (xy 141.543574 -188.776601) (xy 141.601822 -188.757148)
			(xy 141.662433 -188.747273) (xy 141.693138 -188.746638) (xy 141.720391 -188.747034) (xy 141.774341 -188.754796)
			(xy 141.826637 -188.770157) (xy 141.876216 -188.792803) (xy 141.922067 -188.822274) (xy 141.963258 -188.857969)
			(xy 141.998949 -188.899164) (xy 142.028416 -188.945018) (xy 142.051057 -188.994598) (xy 142.066412 -189.046896)
			(xy 142.074168 -189.100847) (xy 142.074168 -189.155353) (xy 142.066412 -189.209304) (xy 142.051057 -189.261602)
			(xy 142.028416 -189.311182) (xy 141.998949 -189.357036) (xy 141.963258 -189.398231) (xy 141.922067 -189.433927)
			(xy 141.876216 -189.463397) (xy 141.826637 -189.486043) (xy 141.774341 -189.501404) (xy 141.720391 -189.509166)
			(xy 141.693138 -189.509654) (xy 141.662334 -189.509067) (xy 141.601532 -189.499133) (xy 141.543119 -189.47955)
			(xy 141.515592 -189.465712) (xy 141.515084 -189.465458) (xy 141.50976 -189.462991) (xy 141.498344 -189.460291)
			(xy 141.492478 -189.460124) (xy 137.440924 -189.460124) (xy 137.430855 -189.460555) (xy 137.412257 -189.468271)
			(xy 137.404856 -189.47511) (xy 134.327138 -192.552828) (xy 134.320299 -192.560229) (xy 134.312577 -192.578827)
			(xy 134.312152 -192.588896) (xy 134.312152 -193.82486) (xy 144.777204 -193.82486) (xy 144.781275 -193.769238)
			(xy 144.793401 -193.714801) (xy 144.813324 -193.66271) (xy 144.84062 -193.614075) (xy 144.874706 -193.569932)
			(xy 144.914855 -193.531223) (xy 144.960213 -193.498772) (xy 145.009813 -193.473271) (xy 145.062597 -193.455264)
			(xy 145.11744 -193.445134) (xy 145.173174 -193.443097) (xy 145.228611 -193.449197) (xy 145.282568 -193.463303)
			(xy 145.333897 -193.485115) (xy 145.381503 -193.514169) (xy 145.424371 -193.549844) (xy 145.461588 -193.591381)
			(xy 145.492361 -193.637894) (xy 145.516033 -193.688391) (xy 145.532101 -193.741798) (xy 145.540221 -193.796974)
			(xy 145.54073 -193.82486) (xy 145.540221 -193.852746) (xy 145.532101 -193.907922) (xy 145.52148 -193.943224)
			(xy 146.498816 -193.943224) (xy 146.502887 -193.887602) (xy 146.515013 -193.833165) (xy 146.534936 -193.781074)
			(xy 146.562232 -193.732439) (xy 146.596318 -193.688296) (xy 146.636467 -193.649587) (xy 146.681825 -193.617136)
			(xy 146.731425 -193.591635) (xy 146.784209 -193.573628) (xy 146.839052 -193.563498) (xy 146.894786 -193.561461)
			(xy 146.950223 -193.567561) (xy 147.00418 -193.581667) (xy 147.055509 -193.603479) (xy 147.103115 -193.632533)
			(xy 147.145983 -193.668208) (xy 147.1832 -193.709745) (xy 147.213973 -193.756258) (xy 147.237645 -193.806755)
			(xy 147.253713 -193.860162) (xy 147.261833 -193.915338) (xy 147.262342 -193.943224) (xy 147.261833 -193.97111)
			(xy 147.253713 -194.026286) (xy 147.237645 -194.079693) (xy 147.213973 -194.13019) (xy 147.1832 -194.176703)
			(xy 147.145983 -194.21824) (xy 147.103115 -194.253915) (xy 147.055509 -194.282969) (xy 147.00418 -194.304781)
			(xy 146.950223 -194.318887) (xy 146.894786 -194.324987) (xy 146.839052 -194.32295) (xy 146.784209 -194.31282)
			(xy 146.731425 -194.294813) (xy 146.681825 -194.269312) (xy 146.636467 -194.236861) (xy 146.596318 -194.198152)
			(xy 146.562232 -194.154009) (xy 146.534936 -194.105374) (xy 146.515013 -194.053283) (xy 146.502887 -193.998846)
			(xy 146.498816 -193.943224) (xy 145.52148 -193.943224) (xy 145.516033 -193.961329) (xy 145.492361 -194.011826)
			(xy 145.461588 -194.058339) (xy 145.424371 -194.099876) (xy 145.381503 -194.135551) (xy 145.333897 -194.164605)
			(xy 145.282568 -194.186417) (xy 145.228611 -194.200523) (xy 145.173174 -194.206623) (xy 145.11744 -194.204586)
			(xy 145.062597 -194.194456) (xy 145.009813 -194.176449) (xy 144.960213 -194.150948) (xy 144.914855 -194.118497)
			(xy 144.874706 -194.079788) (xy 144.84062 -194.035645) (xy 144.813324 -193.98701) (xy 144.793401 -193.934919)
			(xy 144.781275 -193.880482) (xy 144.777204 -193.82486) (xy 134.312152 -193.82486) (xy 134.312152 -194.852798)
			(xy 147.72589 -194.852798) (xy 147.729961 -194.797176) (xy 147.742087 -194.742739) (xy 147.76201 -194.690648)
			(xy 147.789306 -194.642013) (xy 147.823392 -194.59787) (xy 147.863541 -194.559161) (xy 147.908899 -194.52671)
			(xy 147.958499 -194.501209) (xy 148.011283 -194.483202) (xy 148.066126 -194.473072) (xy 148.12186 -194.471035)
			(xy 148.177297 -194.477135) (xy 148.231254 -194.491241) (xy 148.282583 -194.513053) (xy 148.330189 -194.542107)
			(xy 148.373057 -194.577782) (xy 148.410274 -194.619319) (xy 148.441047 -194.665832) (xy 148.464719 -194.716329)
			(xy 148.480787 -194.769736) (xy 148.488907 -194.824912) (xy 148.489416 -194.852798) (xy 148.488907 -194.880684)
			(xy 148.480787 -194.93586) (xy 148.464719 -194.989267) (xy 148.441047 -195.039764) (xy 148.410274 -195.086277)
			(xy 148.373057 -195.127814) (xy 148.330189 -195.163489) (xy 148.282583 -195.192543) (xy 148.231254 -195.214355)
			(xy 148.177297 -195.228461) (xy 148.12186 -195.234561) (xy 148.066126 -195.232524) (xy 148.011283 -195.222394)
			(xy 147.958499 -195.204387) (xy 147.908899 -195.178886) (xy 147.863541 -195.146435) (xy 147.823392 -195.107726)
			(xy 147.789306 -195.063583) (xy 147.76201 -195.014948) (xy 147.742087 -194.962857) (xy 147.729961 -194.90842)
			(xy 147.72589 -194.852798) (xy 134.312152 -194.852798) (xy 134.312152 -195.522088) (xy 146.338034 -195.522088)
			(xy 146.342105 -195.466466) (xy 146.354231 -195.412029) (xy 146.374154 -195.359938) (xy 146.40145 -195.311303)
			(xy 146.435536 -195.26716) (xy 146.475685 -195.228451) (xy 146.521043 -195.196) (xy 146.570643 -195.170499)
			(xy 146.623427 -195.152492) (xy 146.67827 -195.142362) (xy 146.734004 -195.140325) (xy 146.789441 -195.146425)
			(xy 146.843398 -195.160531) (xy 146.894727 -195.182343) (xy 146.942333 -195.211397) (xy 146.985201 -195.247072)
			(xy 147.022418 -195.288609) (xy 147.053191 -195.335122) (xy 147.076863 -195.385619) (xy 147.092931 -195.439026)
			(xy 147.101051 -195.494202) (xy 147.10156 -195.522088) (xy 147.101051 -195.549974) (xy 147.092931 -195.60515)
			(xy 147.076863 -195.658557) (xy 147.053191 -195.709054) (xy 147.022418 -195.755567) (xy 146.985201 -195.797104)
			(xy 146.942333 -195.832779) (xy 146.894727 -195.861833) (xy 146.843398 -195.883645) (xy 146.789441 -195.897751)
			(xy 146.734004 -195.903851) (xy 146.67827 -195.901814) (xy 146.623427 -195.891684) (xy 146.570643 -195.873677)
			(xy 146.521043 -195.848176) (xy 146.475685 -195.815725) (xy 146.435536 -195.777016) (xy 146.40145 -195.732873)
			(xy 146.374154 -195.684238) (xy 146.354231 -195.632147) (xy 146.342105 -195.57771) (xy 146.338034 -195.522088)
			(xy 134.312152 -195.522088) (xy 134.312152 -196.196712) (xy 136.162794 -196.196712) (xy 136.166865 -196.14109)
			(xy 136.178991 -196.086653) (xy 136.198914 -196.034562) (xy 136.22621 -195.985927) (xy 136.260296 -195.941784)
			(xy 136.300445 -195.903075) (xy 136.345803 -195.870624) (xy 136.395403 -195.845123) (xy 136.448187 -195.827116)
			(xy 136.50303 -195.816986) (xy 136.558764 -195.814949) (xy 136.614201 -195.821049) (xy 136.668158 -195.835155)
			(xy 136.719487 -195.856967) (xy 136.767093 -195.886021) (xy 136.809961 -195.921696) (xy 136.847178 -195.963233)
			(xy 136.877951 -196.009746) (xy 136.901623 -196.060243) (xy 136.917691 -196.11365) (xy 136.925811 -196.168826)
			(xy 136.92632 -196.196712) (xy 136.925811 -196.224598) (xy 136.917691 -196.279774) (xy 136.901623 -196.333181)
			(xy 136.877951 -196.383678) (xy 136.847178 -196.430191) (xy 136.809961 -196.471728) (xy 136.767093 -196.507403)
			(xy 136.719487 -196.536457) (xy 136.668158 -196.558269) (xy 136.614201 -196.572375) (xy 136.558764 -196.578475)
			(xy 136.50303 -196.576438) (xy 136.448187 -196.566308) (xy 136.395403 -196.548301) (xy 136.345803 -196.5228)
			(xy 136.300445 -196.490349) (xy 136.260296 -196.45164) (xy 136.22621 -196.407497) (xy 136.198914 -196.358862)
			(xy 136.178991 -196.306771) (xy 136.166865 -196.252334) (xy 136.162794 -196.196712) (xy 134.312152 -196.196712)
			(xy 134.312152 -196.884798) (xy 146.481798 -196.884798) (xy 146.485869 -196.829176) (xy 146.497995 -196.774739)
			(xy 146.517918 -196.722648) (xy 146.545214 -196.674013) (xy 146.5793 -196.62987) (xy 146.619449 -196.591161)
			(xy 146.664807 -196.55871) (xy 146.714407 -196.533209) (xy 146.767191 -196.515202) (xy 146.822034 -196.505072)
			(xy 146.877768 -196.503035) (xy 146.933205 -196.509135) (xy 146.987162 -196.523241) (xy 147.038491 -196.545053)
			(xy 147.086097 -196.574107) (xy 147.128965 -196.609782) (xy 147.166182 -196.651319) (xy 147.196955 -196.697832)
			(xy 147.220627 -196.748329) (xy 147.236695 -196.801736) (xy 147.244815 -196.856912) (xy 147.245324 -196.884798)
			(xy 147.244815 -196.912684) (xy 147.236695 -196.96786) (xy 147.220627 -197.021267) (xy 147.196955 -197.071764)
			(xy 147.166182 -197.118277) (xy 147.128965 -197.159814) (xy 147.086097 -197.195489) (xy 147.038491 -197.224543)
			(xy 146.987162 -197.246355) (xy 146.933205 -197.260461) (xy 146.877768 -197.266561) (xy 146.822034 -197.264524)
			(xy 146.767191 -197.254394) (xy 146.714407 -197.236387) (xy 146.664807 -197.210886) (xy 146.619449 -197.178435)
			(xy 146.5793 -197.139726) (xy 146.545214 -197.095583) (xy 146.517918 -197.046948) (xy 146.497995 -196.994857)
			(xy 146.485869 -196.94042) (xy 146.481798 -196.884798) (xy 134.312152 -196.884798) (xy 134.312152 -197.814184)
			(xy 134.311683 -197.840272) (xy 134.304949 -197.882764) (xy 143.667986 -197.882764) (xy 143.672057 -197.827142)
			(xy 143.684183 -197.772705) (xy 143.704106 -197.720614) (xy 143.731402 -197.671979) (xy 143.765488 -197.627836)
			(xy 143.805637 -197.589127) (xy 143.850995 -197.556676) (xy 143.900595 -197.531175) (xy 143.953379 -197.513168)
			(xy 144.008222 -197.503038) (xy 144.063956 -197.501001) (xy 144.119393 -197.507101) (xy 144.17335 -197.521207)
			(xy 144.224679 -197.543019) (xy 144.272285 -197.572073) (xy 144.315153 -197.607748) (xy 144.35237 -197.649285)
			(xy 144.383143 -197.695798) (xy 144.399823 -197.73138) (xy 148.43963 -197.73138) (xy 148.443701 -197.675758)
			(xy 148.455827 -197.621321) (xy 148.47575 -197.56923) (xy 148.503046 -197.520595) (xy 148.537132 -197.476452)
			(xy 148.577281 -197.437743) (xy 148.622639 -197.405292) (xy 148.672239 -197.379791) (xy 148.725023 -197.361784)
			(xy 148.779866 -197.351654) (xy 148.8356 -197.349617) (xy 148.891037 -197.355717) (xy 148.944994 -197.369823)
			(xy 148.996323 -197.391635) (xy 149.043929 -197.420689) (xy 149.086797 -197.456364) (xy 149.124014 -197.497901)
			(xy 149.154787 -197.544414) (xy 149.178459 -197.594911) (xy 149.194527 -197.648318) (xy 149.202647 -197.703494)
			(xy 149.203156 -197.73138) (xy 149.202647 -197.759266) (xy 149.194527 -197.814442) (xy 149.178459 -197.867849)
			(xy 149.154787 -197.918346) (xy 149.124014 -197.964859) (xy 149.086797 -198.006396) (xy 149.043929 -198.042071)
			(xy 148.996323 -198.071125) (xy 148.944994 -198.092937) (xy 148.891037 -198.107043) (xy 148.8356 -198.113143)
			(xy 148.779866 -198.111106) (xy 148.725023 -198.100976) (xy 148.672239 -198.082969) (xy 148.622639 -198.057468)
			(xy 148.577281 -198.025017) (xy 148.537132 -197.986308) (xy 148.503046 -197.942165) (xy 148.47575 -197.89353)
			(xy 148.455827 -197.841439) (xy 148.443701 -197.787002) (xy 148.43963 -197.73138) (xy 144.399823 -197.73138)
			(xy 144.406815 -197.746295) (xy 144.422883 -197.799702) (xy 144.431003 -197.854878) (xy 144.431512 -197.882764)
			(xy 144.431003 -197.91065) (xy 144.422883 -197.965826) (xy 144.406815 -198.019233) (xy 144.383143 -198.06973)
			(xy 144.35237 -198.116243) (xy 144.315153 -198.15778) (xy 144.272285 -198.193455) (xy 144.224679 -198.222509)
			(xy 144.17335 -198.244321) (xy 144.119393 -198.258427) (xy 144.063956 -198.264527) (xy 144.008222 -198.26249)
			(xy 143.953379 -198.25236) (xy 143.900595 -198.234353) (xy 143.850995 -198.208852) (xy 143.805637 -198.176401)
			(xy 143.765488 -198.137692) (xy 143.731402 -198.093549) (xy 143.704106 -198.044914) (xy 143.684183 -197.992823)
			(xy 143.672057 -197.938386) (xy 143.667986 -197.882764) (xy 134.304949 -197.882764) (xy 134.303516 -197.891806)
			(xy 134.287381 -197.941425) (xy 134.263676 -197.987905) (xy 134.232986 -198.030101) (xy 134.21487 -198.04888)
			(xy 133.536944 -198.726806) (xy 136.638028 -198.726806) (xy 136.642099 -198.671184) (xy 136.654225 -198.616747)
			(xy 136.674148 -198.564656) (xy 136.701444 -198.516021) (xy 136.73553 -198.471878) (xy 136.775679 -198.433169)
			(xy 136.821037 -198.400718) (xy 136.870637 -198.375217) (xy 136.923421 -198.35721) (xy 136.978264 -198.34708)
			(xy 137.033998 -198.345043) (xy 137.089435 -198.351143) (xy 137.143392 -198.365249) (xy 137.194721 -198.387061)
			(xy 137.242327 -198.416115) (xy 137.285195 -198.45179) (xy 137.322412 -198.493327) (xy 137.353185 -198.53984)
			(xy 137.359659 -198.55365) (xy 138.244078 -198.55365) (xy 138.244078 -198.49915) (xy 138.251833 -198.445205)
			(xy 138.267187 -198.392912) (xy 138.289826 -198.343337) (xy 138.31929 -198.297488) (xy 138.354978 -198.256298)
			(xy 138.396165 -198.220607) (xy 138.442012 -198.19114) (xy 138.491586 -198.168497) (xy 138.543877 -198.153139)
			(xy 138.597822 -198.14538) (xy 138.625072 -198.144892) (xy 139.488672 -198.144892) (xy 139.515926 -198.145353)
			(xy 139.56988 -198.153107) (xy 139.622181 -198.168461) (xy 139.671765 -198.191102) (xy 139.717622 -198.220569)
			(xy 139.758818 -198.256263) (xy 139.794514 -198.297456) (xy 139.823985 -198.34331) (xy 139.846629 -198.392892)
			(xy 139.861987 -198.445192) (xy 139.869745 -198.499146) (xy 139.869745 -198.553654) (xy 139.861987 -198.607608)
			(xy 139.846629 -198.659908) (xy 139.837189 -198.680578) (xy 141.924784 -198.680578) (xy 141.928855 -198.624956)
			(xy 141.940981 -198.570519) (xy 141.960904 -198.518428) (xy 141.9882 -198.469793) (xy 142.022286 -198.42565)
			(xy 142.062435 -198.386941) (xy 142.107793 -198.35449) (xy 142.157393 -198.328989) (xy 142.210177 -198.310982)
			(xy 142.26502 -198.300852) (xy 142.320754 -198.298815) (xy 142.376191 -198.304915) (xy 142.430148 -198.319021)
			(xy 142.481477 -198.340833) (xy 142.529083 -198.369887) (xy 142.571951 -198.405562) (xy 142.609168 -198.447099)
			(xy 142.639941 -198.493612) (xy 142.663613 -198.544109) (xy 142.679681 -198.597516) (xy 142.687801 -198.652692)
			(xy 142.68831 -198.680578) (xy 142.687801 -198.708464) (xy 142.679681 -198.76364) (xy 142.663613 -198.817047)
			(xy 142.639941 -198.867544) (xy 142.609168 -198.914057) (xy 142.571951 -198.955594) (xy 142.529083 -198.991269)
			(xy 142.481477 -199.020323) (xy 142.430148 -199.042135) (xy 142.376191 -199.056241) (xy 142.320754 -199.062341)
			(xy 142.26502 -199.060304) (xy 142.210177 -199.050174) (xy 142.157393 -199.032167) (xy 142.107793 -199.006666)
			(xy 142.062435 -198.974215) (xy 142.022286 -198.935506) (xy 141.9882 -198.891363) (xy 141.960904 -198.842728)
			(xy 141.940981 -198.790637) (xy 141.928855 -198.7362) (xy 141.924784 -198.680578) (xy 139.837189 -198.680578)
			(xy 139.823985 -198.70949) (xy 139.794514 -198.755344) (xy 139.758818 -198.796537) (xy 139.717622 -198.832231)
			(xy 139.671765 -198.861698) (xy 139.622181 -198.884339) (xy 139.56988 -198.899693) (xy 139.515926 -198.907447)
			(xy 139.488672 -198.907908) (xy 139.477343 -198.907862) (xy 139.454723 -198.90659) (xy 139.44346 -198.905368)
			(xy 139.440412 -198.90486) (xy 138.67257 -198.90486) (xy 138.669776 -198.905368) (xy 138.65864 -198.906575)
			(xy 138.636273 -198.907848) (xy 138.625072 -198.907908) (xy 138.597822 -198.90742) (xy 138.543877 -198.899661)
			(xy 138.491586 -198.884303) (xy 138.442012 -198.86166) (xy 138.396165 -198.832193) (xy 138.354978 -198.796502)
			(xy 138.31929 -198.755312) (xy 138.289826 -198.709463) (xy 138.267187 -198.659888) (xy 138.251833 -198.607595)
			(xy 138.244078 -198.55365) (xy 137.359659 -198.55365) (xy 137.376857 -198.590337) (xy 137.392925 -198.643744)
			(xy 137.401045 -198.69892) (xy 137.401554 -198.726806) (xy 137.401045 -198.754692) (xy 137.392925 -198.809868)
			(xy 137.376857 -198.863275) (xy 137.353185 -198.913772) (xy 137.322412 -198.960285) (xy 137.285195 -199.001822)
			(xy 137.242327 -199.037497) (xy 137.194721 -199.066551) (xy 137.143392 -199.088363) (xy 137.089435 -199.102469)
			(xy 137.033998 -199.108569) (xy 136.978264 -199.106532) (xy 136.923421 -199.096402) (xy 136.870637 -199.078395)
			(xy 136.821037 -199.052894) (xy 136.775679 -199.020443) (xy 136.73553 -198.981734) (xy 136.701444 -198.937591)
			(xy 136.674148 -198.888956) (xy 136.654225 -198.836865) (xy 136.642099 -198.782428) (xy 136.638028 -198.726806)
			(xy 133.536944 -198.726806) (xy 133.07441 -199.18934) (xy 133.055656 -199.207391) (xy 133.013534 -199.237967)
			(xy 132.967153 -199.26159) (xy 132.957345 -199.264778) (xy 144.901918 -199.264778) (xy 144.905989 -199.209156)
			(xy 144.918115 -199.154719) (xy 144.938038 -199.102628) (xy 144.965334 -199.053993) (xy 144.99942 -199.00985)
			(xy 145.039569 -198.971141) (xy 145.084927 -198.93869) (xy 145.134527 -198.913189) (xy 145.187311 -198.895182)
			(xy 145.242154 -198.885052) (xy 145.297888 -198.883015) (xy 145.353325 -198.889115) (xy 145.407282 -198.903221)
			(xy 145.458611 -198.925033) (xy 145.506217 -198.954087) (xy 145.549085 -198.989762) (xy 145.586302 -199.031299)
			(xy 145.617075 -199.077812) (xy 145.640747 -199.128309) (xy 145.656815 -199.181716) (xy 145.664935 -199.236892)
			(xy 145.665444 -199.264778) (xy 145.664935 -199.292664) (xy 145.656815 -199.34784) (xy 145.643519 -199.392032)
			(xy 148.762464 -199.392032) (xy 148.766535 -199.33641) (xy 148.778661 -199.281973) (xy 148.798584 -199.229882)
			(xy 148.82588 -199.181247) (xy 148.859966 -199.137104) (xy 148.900115 -199.098395) (xy 148.945473 -199.065944)
			(xy 148.995073 -199.040443) (xy 149.047857 -199.022436) (xy 149.1027 -199.012306) (xy 149.158434 -199.010269)
			(xy 149.213871 -199.016369) (xy 149.267828 -199.030475) (xy 149.319157 -199.052287) (xy 149.366763 -199.081341)
			(xy 149.409631 -199.117016) (xy 149.446848 -199.158553) (xy 149.477621 -199.205066) (xy 149.501293 -199.255563)
			(xy 149.517361 -199.30897) (xy 149.525481 -199.364146) (xy 149.52599 -199.392032) (xy 149.525481 -199.419918)
			(xy 149.517361 -199.475094) (xy 149.501293 -199.528501) (xy 149.477621 -199.578998) (xy 149.446848 -199.625511)
			(xy 149.409631 -199.667048) (xy 149.366763 -199.702723) (xy 149.319157 -199.731777) (xy 149.267828 -199.753589)
			(xy 149.213871 -199.767695) (xy 149.158434 -199.773795) (xy 149.1027 -199.771758) (xy 149.047857 -199.761628)
			(xy 148.995073 -199.743621) (xy 148.945473 -199.71812) (xy 148.900115 -199.685669) (xy 148.859966 -199.64696)
			(xy 148.82588 -199.602817) (xy 148.798584 -199.554182) (xy 148.778661 -199.502091) (xy 148.766535 -199.447654)
			(xy 148.762464 -199.392032) (xy 145.643519 -199.392032) (xy 145.640747 -199.401247) (xy 145.617075 -199.451744)
			(xy 145.586302 -199.498257) (xy 145.549085 -199.539794) (xy 145.506217 -199.575469) (xy 145.458611 -199.604523)
			(xy 145.407282 -199.626335) (xy 145.353325 -199.640441) (xy 145.297888 -199.646541) (xy 145.242154 -199.644504)
			(xy 145.187311 -199.634374) (xy 145.134527 -199.616367) (xy 145.084927 -199.590866) (xy 145.039569 -199.558415)
			(xy 144.99942 -199.519706) (xy 144.965334 -199.475563) (xy 144.938038 -199.426928) (xy 144.918115 -199.374837)
			(xy 144.905989 -199.3204) (xy 144.901918 -199.264778) (xy 132.957345 -199.264778) (xy 132.917653 -199.27768)
			(xy 132.866247 -199.285843) (xy 132.840222 -199.286368) (xy 130.57378 -199.286368) (xy 130.567629 -199.28655)
			(xy 130.555689 -199.289511) (xy 130.550158 -199.29221) (xy 130.522624 -199.30603) (xy 130.464211 -199.3256)
			(xy 130.403414 -199.335539) (xy 130.372612 -199.336152) (xy 130.345362 -199.335602) (xy 130.291416 -199.327847)
			(xy 130.239122 -199.312494) (xy 130.189547 -199.289854) (xy 130.143697 -199.26039) (xy 130.102508 -199.224701)
			(xy 130.066817 -199.183512) (xy 130.037351 -199.137664) (xy 130.014711 -199.088089) (xy 129.999356 -199.035796)
			(xy 129.991599 -198.98185) (xy 128.510508 -198.98185) (xy 128.517911 -199.006456) (xy 128.526031 -199.061632)
			(xy 128.52654 -199.089518) (xy 128.526031 -199.117404) (xy 128.517911 -199.17258) (xy 128.501843 -199.225987)
			(xy 128.478171 -199.276484) (xy 128.447398 -199.322997) (xy 128.410181 -199.364534) (xy 128.367313 -199.400209)
			(xy 128.319707 -199.429263) (xy 128.268378 -199.451075) (xy 128.214421 -199.465181) (xy 128.158984 -199.471281)
			(xy 128.10325 -199.469244) (xy 128.048407 -199.459114) (xy 127.995623 -199.441107) (xy 127.946023 -199.415606)
			(xy 127.900665 -199.383155) (xy 127.860516 -199.344446) (xy 127.82643 -199.300303) (xy 127.799134 -199.251668)
			(xy 127.779211 -199.199577) (xy 127.767085 -199.14514) (xy 127.763014 -199.089518) (xy 110.016086 -199.089518)
			(xy 110.027243 -199.096327) (xy 110.070111 -199.132002) (xy 110.107328 -199.173539) (xy 110.138101 -199.220052)
			(xy 110.161773 -199.270549) (xy 110.177841 -199.323956) (xy 110.185961 -199.379132) (xy 110.18647 -199.407018)
			(xy 110.185961 -199.434904) (xy 110.177841 -199.49008) (xy 110.161773 -199.543487) (xy 110.138101 -199.593984)
			(xy 110.107328 -199.640497) (xy 110.070111 -199.682034) (xy 110.027243 -199.717709) (xy 109.979637 -199.746763)
			(xy 109.928308 -199.768575) (xy 109.874351 -199.782681) (xy 109.818914 -199.788781) (xy 109.76318 -199.786744)
			(xy 109.708337 -199.776614) (xy 109.655553 -199.758607) (xy 109.605953 -199.733106) (xy 109.560595 -199.700655)
			(xy 109.520446 -199.661946) (xy 109.48636 -199.617803) (xy 109.459064 -199.569168) (xy 109.439141 -199.517077)
			(xy 109.427015 -199.46264) (xy 109.422944 -199.407018) (xy 107.161227 -199.407018) (xy 107.167993 -199.410108)
			(xy 107.213874 -199.439594) (xy 107.255091 -199.475309) (xy 107.290806 -199.516526) (xy 107.320292 -199.562407)
			(xy 107.342949 -199.612017) (xy 107.358314 -199.664347) (xy 107.366076 -199.718331) (xy 107.366562 -199.7456)
			(xy 107.366125 -199.771856) (xy 107.35893 -199.823872) (xy 107.344675 -199.874412) (xy 107.32363 -199.922522)
			(xy 107.29619 -199.967295) (xy 107.262875 -200.007885) (xy 107.24388 -200.026016) (xy 107.234212 -200.035516)
			(xy 107.219834 -200.058483) (xy 107.212003 -200.084422) (xy 107.211271 -200.111508) (xy 107.217689 -200.137833)
			(xy 107.230805 -200.161542) (xy 107.249696 -200.180967) (xy 107.273031 -200.194739) (xy 107.299166 -200.201888)
			(xy 107.312714 -200.202292) (xy 127.847852 -200.202292) (xy 127.853228 -200.202132) (xy 127.863733 -200.199832)
			(xy 127.86868 -200.19772) (xy 127.89535 -200.185782) (xy 127.902208 -200.178416) (xy 127.921966 -200.158375)
			(xy 127.96632 -200.123737) (xy 128.015279 -200.095986) (xy 128.067782 -200.075723) (xy 128.12269 -200.063387)
			(xy 128.178814 -200.059245) (xy 128.234938 -200.063387) (xy 128.289846 -200.075723) (xy 128.342349 -200.095986)
			(xy 128.391308 -200.123737) (xy 128.435662 -200.158375) (xy 128.45542 -200.178416) (xy 128.462278 -200.185782)
			(xy 128.488948 -200.19772) (xy 128.493895 -200.199833) (xy 128.504399 -200.202146) (xy 128.509776 -200.202292)
			(xy 147.372832 -200.202292) (xy 147.387024 -200.201778) (xy 147.41429 -200.193882) (xy 147.438334 -200.178792)
			(xy 147.4573 -200.157671) (xy 147.469725 -200.132148) (xy 147.474652 -200.104192) (xy 147.47367 -200.090024)
			(xy 147.472721 -200.080273) (xy 147.471703 -200.060705) (xy 147.471638 -200.050908) (xy 147.471638 -200.0504)
			(xy 147.472124 -200.023131) (xy 147.479886 -199.969147) (xy 147.495251 -199.916817) (xy 147.517908 -199.867207)
			(xy 147.547394 -199.821326) (xy 147.583109 -199.780109) (xy 147.624326 -199.744394) (xy 147.670207 -199.714908)
			(xy 147.719817 -199.692251) (xy 147.772147 -199.676886) (xy 147.826131 -199.669124) (xy 147.880669 -199.669124)
			(xy 147.934653 -199.676886) (xy 147.986983 -199.692251) (xy 148.036593 -199.714908) (xy 148.082474 -199.744394)
			(xy 148.123691 -199.780109) (xy 148.159406 -199.821326) (xy 148.188892 -199.867207) (xy 148.211549 -199.916817)
			(xy 148.226914 -199.969147) (xy 148.234676 -200.023131) (xy 148.235162 -200.0504) (xy 148.235162 -200.050908)
			(xy 148.235092 -200.060705) (xy 148.234073 -200.080272) (xy 148.23313 -200.090024) (xy 148.232105 -200.104192)
			(xy 148.237015 -200.13216) (xy 148.249441 -200.157692) (xy 148.268421 -200.178812) (xy 148.292485 -200.193885)
			(xy 148.319771 -200.201744) (xy 148.333968 -200.202292) (xy 150.007828 -200.202292) (xy 150.017896 -200.20272)
			(xy 150.036494 -200.21044) (xy 150.043896 -200.217278) (xy 150.05177 -200.225152) (xy 150.059182 -200.231836)
			(xy 150.077615 -200.239433) (xy 150.097553 -200.239433) (xy 150.115986 -200.231836) (xy 150.123398 -200.225152)
			(xy 152.012142 -198.336408) (xy 152.019239 -198.328634) (xy 152.026989 -198.309087) (xy 152.027128 -198.298562)
			(xy 146.708876 -138.330432) (xy 146.707534 -138.314458) (xy 146.705756 -138.282448) (xy 146.70532 -138.266424)
			(xy 146.191224 -117.09527) (xy 146.191224 -117.092984) (xy 146.190716 -117.07114) (xy 146.190716 -117.070632)
			(xy 146.19224 -117.017292) (xy 146.866356 -104.50957) (xy 146.869658 -104.46639) (xy 146.87423 -104.427782)
			(xy 149.213062 -87.34298) (xy 149.213062 -87.342472) (xy 150.256748 -78.903576) (xy 150.256748 -78.903322)
			(xy 150.258018 -78.893416) (xy 150.253446 -78.876398) (xy 150.250906 -78.869286) (xy 150.239729 -78.844186)
			(xy 150.223878 -78.791578) (xy 150.21572 -78.737243) (xy 150.215092 -78.709774) (xy 150.215092 -78.702916)
			(xy 150.21687 -78.670404) (xy 150.219867 -78.644177) (xy 150.232158 -78.592841) (xy 150.251396 -78.543684)
			(xy 150.277215 -78.497642) (xy 150.292816 -78.476348) (xy 150.293324 -78.47584) (xy 150.305008 -78.460092)
			(xy 150.308856 -78.454717) (xy 150.313868 -78.44249) (xy 150.314914 -78.435962) (xy 150.342854 -78.209394)
			(xy 150.409148 -77.672946) (xy 150.467822 -77.196188) (xy 150.468076 -77.192632) (xy 150.875492 -69.484748)
			(xy 151.237188 -62.641988) (xy 151.237188 -62.6364) (xy 151.145494 -61.013594) (xy 151.144946 -61.007126)
			(xy 151.140954 -60.99478) (xy 151.13762 -60.98921) (xy 151.134064 -60.983876) (xy 151.124412 -60.974986)
			(xy 151.118316 -60.971684) (xy 151.0955 -60.959233) (xy 151.053156 -60.929089) (xy 151.015289 -60.893484)
			(xy 150.982597 -60.853074) (xy 150.955685 -60.808607) (xy 150.935047 -60.760902) (xy 150.921067 -60.71084)
			(xy 150.914001 -60.659345) (xy 150.913592 -60.633356) (xy 150.914058 -60.606728) (xy 150.921465 -60.553989)
			(xy 150.93613 -60.502791) (xy 150.957769 -60.454128) (xy 150.98596 -60.408945) (xy 151.020157 -60.368118)
			(xy 151.059696 -60.33244) (xy 151.081486 -60.317126) (xy 151.086691 -60.31336) (xy 151.095172 -60.303715)
			(xy 151.09825 -60.298076) (xy 151.101552 -60.29198) (xy 151.104092 -60.279026) (xy 151.016462 -58.729626)
			(xy 151.015444 -58.721894) (xy 151.009376 -58.707537) (xy 151.004524 -58.701432) (xy 151.00427 -58.701178)
			(xy 150.9865 -58.680217) (xy 150.956544 -58.634149) (xy 150.933516 -58.584257) (xy 150.917892 -58.531574)
			(xy 150.909997 -58.477193) (xy 150.909528 -58.449718) (xy 150.910043 -58.419178) (xy 150.91961 -58.358855)
			(xy 150.93868 -58.300831) (xy 150.9522 -58.273442) (xy 150.957955 -58.262615) (xy 150.970667 -58.241645)
			(xy 150.9776 -58.231532) (xy 150.982426 -58.224674) (xy 150.984712 -58.216546) (xy 150.985764 -58.212506)
			(xy 150.986662 -58.204207) (xy 150.98649 -58.200036) (xy 150.974552 -57.988454) (xy 150.874984 -56.223916)
			(xy 150.78583 -54.644798) (xy 150.784362 -54.635128) (xy 150.77517 -54.617883) (xy 150.760177 -54.605349)
			(xy 150.751032 -54.601872) (xy 150.750778 -54.601872) (xy 150.725534 -54.59324) (xy 150.677554 -54.569913)
			(xy 150.633291 -54.540129) (xy 150.593608 -54.50447) (xy 150.559279 -54.463632) (xy 150.530973 -54.41841)
			(xy 150.509243 -54.369685) (xy 150.494511 -54.318409) (xy 150.487065 -54.265581) (xy 150.486618 -54.238906)
			(xy 150.487091 -54.211575) (xy 150.494897 -54.157472) (xy 150.510335 -54.105034) (xy 150.533089 -54.055333)
			(xy 150.562697 -54.009383) (xy 150.598552 -53.968122) (xy 150.639922 -53.932394) (xy 150.685963 -53.902928)
			(xy 150.710646 -53.89118) (xy 150.7109 -53.89118) (xy 150.717825 -53.887722) (xy 150.729329 -53.877377)
			(xy 150.733506 -53.87086) (xy 150.737316 -53.864764) (xy 150.740872 -53.850032) (xy 150.644098 -52.13731)
			(xy 150.619714 -51.70551) (xy 150.618312 -51.692976) (xy 150.605124 -51.671517) (xy 150.594568 -51.664616)
			(xy 150.593298 -51.663854) (xy 150.587836 -51.660869) (xy 150.575887 -51.657398) (xy 150.569676 -51.656996)
			(xy 150.55723 -51.656488) (xy 150.545546 -51.66233) (xy 150.51918 -51.674738) (xy 150.463615 -51.692282)
			(xy 150.406025 -51.701149) (xy 150.37689 -51.7017) (xy 150.372318 -51.7017) (xy 150.345204 -51.700913)
			(xy 150.2916 -51.692619) (xy 150.23971 -51.67682) (xy 150.190579 -51.653835) (xy 150.145197 -51.624126)
			(xy 150.104476 -51.588292) (xy 150.069239 -51.547055) (xy 150.05431 -51.524408) (xy 150.05304 -51.522122)
			(xy 150.052532 -51.521614) (xy 150.051516 -51.520344) (xy 150.051008 -51.519582) (xy 150.046436 -51.513994)
			(xy 150.039924 -51.507524) (xy 150.023515 -51.499327) (xy 150.014432 -51.497992) (xy 149.974808 -51.493928)
			(xy 149.9743 -51.493928) (xy 149.950678 -51.491388) (xy 149.95017 -51.491388) (xy 149.934422 -51.489864)
			(xy 149.922792 -51.489277) (xy 149.900977 -51.497358) (xy 149.892512 -51.505358) (xy 149.892258 -51.505612)
			(xy 149.874163 -51.524177) (xy 149.833825 -51.556741) (xy 149.789451 -51.583547) (xy 149.741857 -51.6041)
			(xy 149.691919 -51.618022) (xy 149.640557 -51.625057) (xy 149.614636 -51.6255) (xy 149.587382 -51.625039)
			(xy 149.533427 -51.617286) (xy 149.481126 -51.601933) (xy 149.431541 -51.579293) (xy 149.385684 -51.549826)
			(xy 149.344488 -51.514132) (xy 149.308791 -51.472938) (xy 149.279321 -51.427083) (xy 149.256677 -51.377501)
			(xy 149.24132 -51.3252) (xy 149.233563 -51.271246) (xy 149.233128 -51.243992) (xy 149.233553 -51.218481)
			(xy 149.240349 -51.167913) (xy 149.253817 -51.118701) (xy 149.273719 -51.07172) (xy 149.2997 -51.027808)
			(xy 149.31517 -51.007518) (xy 149.31771 -51.00447) (xy 149.318726 -51.002946) (xy 149.322028 -50.996342)
			(xy 149.324371 -50.991119) (xy 149.326936 -50.979966) (xy 149.327108 -50.974244) (xy 149.327108 -50.94224)
			(xy 149.338284 -50.94224) (xy 149.338284 -50.89144) (xy 149.33795 -50.882836) (xy 149.332237 -50.866605)
			(xy 149.327108 -50.85969) (xy 149.325838 -50.858166) (xy 149.308445 -50.837289) (xy 149.279128 -50.791539)
			(xy 149.256602 -50.742091) (xy 149.241321 -50.689946) (xy 149.233596 -50.636161) (xy 149.233128 -50.608992)
			(xy 149.233592 -50.58174) (xy 149.24135 -50.527792) (xy 149.256707 -50.475497) (xy 149.279351 -50.425921)
			(xy 149.308819 -50.380071) (xy 149.344514 -50.338882) (xy 149.385706 -50.303193) (xy 149.431559 -50.273729)
			(xy 149.481139 -50.251092) (xy 149.533435 -50.235741) (xy 149.587384 -50.227989) (xy 149.614636 -50.227484)
			(xy 149.642676 -50.227982) (xy 149.698151 -50.236199) (xy 149.751825 -50.252451) (xy 149.802541 -50.276387)
			(xy 149.849205 -50.307492) (xy 149.890812 -50.345094) (xy 149.909022 -50.366422) (xy 149.909276 -50.366676)
			(xy 149.916134 -50.374804) (xy 149.939756 -50.386488) (xy 149.946106 -50.389536) (xy 149.950996 -50.391619)
			(xy 149.961368 -50.393934) (xy 149.96668 -50.394108) (xy 150.024338 -50.394108) (xy 150.034752 -50.393092)
			(xy 150.046436 -50.389028) (xy 150.06574 -50.379376) (xy 150.069924 -50.377221) (xy 150.077469 -50.371597)
			(xy 150.080726 -50.3682) (xy 150.08225 -50.366168) (xy 150.101639 -50.343555) (xy 150.146216 -50.304048)
			(xy 150.196391 -50.271949) (xy 150.250945 -50.248037) (xy 150.279608 -50.23993) (xy 150.282402 -50.239168)
			(xy 150.290022 -50.237136) (xy 150.294086 -50.234088) (xy 150.298404 -50.230532) (xy 150.300436 -50.229008)
			(xy 150.306024 -50.223166) (xy 150.311612 -50.21453) (xy 150.32101 -50.197004) (xy 150.325415 -50.187513)
			(xy 150.32698 -50.166667) (xy 150.324058 -50.156618) (xy 150.256494 -49.961292) (xy 150.246588 -49.93259)
			(xy 150.229062 -49.88179) (xy 150.224974 -49.872629) (xy 150.211007 -49.858252) (xy 150.192596 -49.850323)
			(xy 150.18258 -49.849786) (xy 150.148036 -49.849786) (xy 150.143425 -49.849891) (xy 150.134354 -49.851559)
			(xy 150.130002 -49.853088) (xy 150.121874 -49.856136) (xy 150.114762 -49.862232) (xy 150.093829 -49.879871)
			(xy 150.047861 -49.90959) (xy 149.998114 -49.932426) (xy 149.945611 -49.947909) (xy 149.891433 -49.955722)
			(xy 149.864064 -49.956212) (xy 149.838553 -49.955785) (xy 149.787987 -49.948987) (xy 149.738776 -49.935516)
			(xy 149.691796 -49.915613) (xy 149.647885 -49.889633) (xy 149.62759 -49.87417) (xy 149.624542 -49.87163)
			(xy 149.623018 -49.870614) (xy 149.616414 -49.867312) (xy 149.611191 -49.86497) (xy 149.600037 -49.862409)
			(xy 149.594316 -49.862232) (xy 149.562312 -49.862232) (xy 149.562312 -49.851056) (xy 149.511512 -49.851056)
			(xy 149.502911 -49.851395) (xy 149.486688 -49.857118) (xy 149.479762 -49.862232) (xy 149.478238 -49.863502)
			(xy 149.457361 -49.880896) (xy 149.411612 -49.910214) (xy 149.362164 -49.93274) (xy 149.310019 -49.94802)
			(xy 149.256233 -49.955742) (xy 149.229064 -49.956212) (xy 149.203553 -49.955785) (xy 149.152987 -49.948987)
			(xy 149.103776 -49.935516) (xy 149.056796 -49.915613) (xy 149.012885 -49.889633) (xy 148.99259 -49.87417)
			(xy 148.989542 -49.87163) (xy 148.988018 -49.870614) (xy 148.981414 -49.867312) (xy 148.976191 -49.86497)
			(xy 148.965037 -49.862409) (xy 148.959316 -49.862232) (xy 148.927312 -49.862232) (xy 148.927312 -49.851056)
			(xy 148.876512 -49.851056) (xy 148.867911 -49.851395) (xy 148.851688 -49.857118) (xy 148.844762 -49.862232)
			(xy 148.843238 -49.863502) (xy 148.822361 -49.880896) (xy 148.776612 -49.910214) (xy 148.727164 -49.93274)
			(xy 148.675019 -49.94802) (xy 148.621233 -49.955742) (xy 148.594064 -49.956212) (xy 148.566814 -49.955724)
			(xy 148.51287 -49.947963) (xy 148.460579 -49.932605) (xy 148.411006 -49.909961) (xy 148.365159 -49.880494)
			(xy 148.323973 -49.844802) (xy 148.288285 -49.803612) (xy 148.258822 -49.757763) (xy 148.236183 -49.708187)
			(xy 148.220829 -49.655895) (xy 148.213074 -49.60195) (xy 148.213074 -49.54745) (xy 148.220829 -49.493505)
			(xy 148.236183 -49.441213) (xy 148.258822 -49.391637) (xy 148.288285 -49.345788) (xy 148.323973 -49.304598)
			(xy 148.365159 -49.268906) (xy 148.411006 -49.239439) (xy 148.460579 -49.216795) (xy 148.51287 -49.201437)
			(xy 148.566814 -49.193676) (xy 148.594064 -49.193196) (xy 148.619574 -49.193625) (xy 148.670139 -49.200426)
			(xy 148.719348 -49.2139) (xy 148.766325 -49.233806) (xy 148.810233 -49.259789) (xy 148.830538 -49.275238)
			(xy 148.833586 -49.277778) (xy 148.83511 -49.278794) (xy 148.841714 -49.282096) (xy 148.846938 -49.284435)
			(xy 148.858091 -49.286989) (xy 148.863812 -49.287176) (xy 148.895816 -49.287176) (xy 148.895816 -49.298352)
			(xy 148.946616 -49.298352) (xy 148.955222 -49.298024) (xy 148.97146 -49.29232) (xy 148.978366 -49.287176)
			(xy 148.97989 -49.285906) (xy 149.000767 -49.268513) (xy 149.046517 -49.239198) (xy 149.095965 -49.216675)
			(xy 149.14811 -49.201399) (xy 149.201896 -49.19368) (xy 149.229064 -49.193196) (xy 149.254574 -49.193625)
			(xy 149.305139 -49.200426) (xy 149.354348 -49.2139) (xy 149.401325 -49.233806) (xy 149.445233 -49.259789)
			(xy 149.465538 -49.275238) (xy 149.468586 -49.277778) (xy 149.47011 -49.278794) (xy 149.476714 -49.282096)
			(xy 149.481938 -49.284435) (xy 149.493091 -49.286989) (xy 149.498812 -49.287176) (xy 149.530816 -49.287176)
			(xy 149.530816 -49.298352) (xy 149.581616 -49.298352) (xy 149.590222 -49.298024) (xy 149.60646 -49.29232)
			(xy 149.613366 -49.287176) (xy 149.61489 -49.285906) (xy 149.622256 -49.279302) (xy 149.623272 -49.278794)
			(xy 149.624542 -49.277778) (xy 149.62505 -49.27727) (xy 149.647148 -49.26076) (xy 149.647402 -49.260506)
			(xy 149.64791 -49.260252) (xy 149.662642 -49.250346) (xy 149.66315 -49.250346) (xy 149.679406 -49.240694)
			(xy 149.684293 -49.237806) (xy 149.692754 -49.230242) (xy 149.69617 -49.225708) (xy 149.699726 -49.221136)
			(xy 149.704044 -49.210468) (xy 149.707092 -49.19091) (xy 149.717506 -49.125886) (xy 149.718217 -49.120139)
			(xy 149.717314 -49.108596) (xy 149.715728 -49.103026) (xy 149.714712 -49.099978) (xy 149.713189 -49.096154)
			(xy 149.709104 -49.089008) (xy 149.706584 -49.085754) (xy 143.9672 -42.828718) (xy 143.962928 -42.824913)
			(xy 143.953054 -42.81914) (xy 143.947642 -42.817288) (xy 143.94053 -42.81551) (xy 143.934669 -42.814705)
			(xy 143.922867 -42.815471) (xy 143.917162 -42.817034) (xy 143.9164 -42.817288) (xy 143.82877 -42.845482)
			(xy 143.819495 -42.848923) (xy 143.804328 -42.861597) (xy 143.799306 -42.87012) (xy 143.797495 -42.873796)
			(xy 143.794935 -42.881579) (xy 143.794226 -42.885614) (xy 143.793972 -42.887646) (xy 143.790104 -42.915018)
			(xy 143.775495 -42.968332) (xy 143.753343 -43.018978) (xy 143.724113 -43.065897) (xy 143.688415 -43.108104)
			(xy 143.646999 -43.144717) (xy 143.600732 -43.174967) (xy 143.550582 -43.198222) (xy 143.497601 -43.213995)
			(xy 143.442898 -43.221954) (xy 143.415258 -43.222418) (xy 143.388008 -43.221929) (xy 143.334063 -43.214168)
			(xy 143.281772 -43.198809) (xy 143.232199 -43.176164) (xy 143.186353 -43.146696) (xy 143.145166 -43.111004)
			(xy 143.109479 -43.069814) (xy 143.080015 -43.023964) (xy 143.057377 -42.974388) (xy 143.042023 -42.922096)
			(xy 143.034268 -42.86815) (xy 143.034268 -42.81365) (xy 143.042023 -42.759704) (xy 143.057377 -42.707412)
			(xy 143.080015 -42.657836) (xy 143.109479 -42.611986) (xy 143.145166 -42.570796) (xy 143.186353 -42.535104)
			(xy 143.232199 -42.505636) (xy 143.281772 -42.482991) (xy 143.334063 -42.467632) (xy 143.388008 -42.459871)
			(xy 143.415258 -42.459402) (xy 143.422878 -42.459402) (xy 143.435298 -42.458789) (xy 143.457276 -42.447213)
			(xy 143.464788 -42.437304) (xy 143.466566 -42.434256) (xy 143.470376 -42.427906) (xy 143.50619 -42.365168)
			(xy 143.50619 -42.36466) (xy 143.510762 -42.356278) (xy 143.513906 -42.350343) (xy 143.51725 -42.33734)
			(xy 143.517366 -42.330624) (xy 143.517112 -42.316908) (xy 143.509746 -42.30497) (xy 143.490188 -42.271696)
			(xy 143.48968 -42.27068) (xy 143.489426 -42.270426) (xy 142.926308 -41.331388) (xy 142.918942 -41.322498)
			(xy 142.918688 -41.322244) (xy 142.913354 -41.317164) (xy 142.906242 -41.313354) (xy 142.90548 -41.3131)
			(xy 142.882059 -41.3009) (xy 142.838525 -41.271007) (xy 142.799534 -41.235391) (xy 142.765833 -41.194733)
			(xy 142.738068 -41.149813) (xy 142.716769 -41.101489) (xy 142.702345 -41.050688) (xy 142.695071 -40.998383)
			(xy 142.69466 -40.971978) (xy 142.69466 -40.960548) (xy 142.694914 -40.953182) (xy 142.693136 -40.946324)
			(xy 142.692203 -40.942663) (xy 142.689399 -40.935647) (xy 142.687548 -40.932354) (xy 142.68069 -40.921178)
			(xy 142.354046 -40.37711) (xy 142.353792 -40.376602) (xy 142.352522 -40.37457) (xy 142.35049 -40.371268)
			(xy 142.344372 -40.362606) (xy 142.326787 -40.350794) (xy 142.316454 -40.348408) (xy 142.315946 -40.348408)
			(xy 142.289515 -40.343593) (xy 142.238252 -40.327516) (xy 142.189752 -40.304405) (xy 142.144974 -40.274719)
			(xy 142.104804 -40.239043) (xy 142.070038 -40.198084) (xy 142.041362 -40.152652) (xy 142.019344 -40.103646)
			(xy 142.00442 -40.052036) (xy 141.996885 -39.998842) (xy 141.996414 -39.97198) (xy 141.996414 -39.971726)
			(xy 141.996998 -39.941422) (xy 142.006568 -39.881575) (xy 142.015464 -39.8526) (xy 142.016734 -39.849044)
			(xy 142.018258 -39.840662) (xy 142.019353 -39.831777) (xy 142.015982 -39.814207) (xy 142.011654 -39.806372)
			(xy 142.011654 -39.806118) (xy 141.489684 -38.93566) (xy 141.48487 -38.928382) (xy 141.471376 -38.917336)
			(xy 141.454967 -38.911431) (xy 141.44625 -38.911022) (xy 141.444472 -38.911022) (xy 141.403578 -38.911784)
			(xy 141.396658 -38.912158) (xy 141.383396 -38.916156) (xy 141.377416 -38.919658) (xy 141.371574 -38.923214)
			(xy 141.362176 -38.933374) (xy 141.359128 -38.939724) (xy 141.34562 -38.965574) (xy 141.312548 -39.013615)
			(xy 141.27317 -39.05664) (xy 141.228238 -39.093826) (xy 141.178609 -39.124464) (xy 141.125231 -39.14797)
			(xy 141.069122 -39.163893) (xy 141.011354 -39.171931) (xy 140.982192 -39.172388) (xy 140.953325 -39.171915)
			(xy 140.896131 -39.164044) (xy 140.840544 -39.148448) (xy 140.787602 -39.125421) (xy 140.738294 -39.095391)
			(xy 140.69354 -39.058919) (xy 140.654175 -39.016687) (xy 140.620936 -38.969482) (xy 140.607288 -38.944042)
			(xy 140.605764 -38.940994) (xy 140.599102 -38.931099) (xy 140.578953 -38.91839) (xy 140.567156 -38.91661)
			(xy 140.558266 -38.916102) (xy 140.529818 -38.914324) (xy 140.518982 -38.914122) (xy 140.498725 -38.921767)
			(xy 140.490702 -38.929056) (xy 140.486892 -38.932866) (xy 140.485114 -38.935152) (xy 140.484352 -38.936168)
			(xy 140.466353 -38.958589) (xy 140.424753 -38.998275) (xy 140.377668 -39.031269) (xy 140.326165 -39.056824)
			(xy 140.27141 -39.074359) (xy 140.214644 -39.083479) (xy 140.185902 -39.08425) (xy 140.182092 -39.08425)
			(xy 140.154838 -39.083764) (xy 140.100885 -39.076005) (xy 140.048586 -39.060648) (xy 139.999004 -39.038004)
			(xy 139.95315 -39.008534) (xy 139.911956 -38.972838) (xy 139.876261 -38.931644) (xy 139.846792 -38.885789)
			(xy 139.824149 -38.836207) (xy 139.808793 -38.783907) (xy 139.801036 -38.729954) (xy 139.801036 -38.675446)
			(xy 139.808793 -38.621493) (xy 139.824149 -38.569193) (xy 139.846792 -38.519611) (xy 139.876261 -38.473756)
			(xy 139.911956 -38.432562) (xy 139.95315 -38.396866) (xy 139.999004 -38.367396) (xy 140.048586 -38.344752)
			(xy 140.100885 -38.329395) (xy 140.154838 -38.321636) (xy 140.182092 -38.321234) (xy 140.209576 -38.321711)
			(xy 140.263977 -38.32959) (xy 140.316687 -38.345185) (xy 140.366618 -38.368175) (xy 140.412736 -38.398084)
			(xy 140.454092 -38.434296) (xy 140.489829 -38.476062) (xy 140.504926 -38.499034) (xy 140.504926 -38.499288)
			(xy 140.507466 -38.503352) (xy 140.508228 -38.504368) (xy 140.512546 -38.508432) (xy 140.520928 -38.515036)
			(xy 140.540232 -38.526974) (xy 140.543567 -38.528971) (xy 140.550709 -38.532038) (xy 140.554456 -38.53307)
			(xy 140.563854 -38.534594) (xy 140.564108 -38.534594) (xy 140.588492 -38.536118) (xy 140.595049 -38.536303)
			(xy 140.607906 -38.533723) (xy 140.613892 -38.531038) (xy 140.619734 -38.528244) (xy 140.62964 -38.519608)
			(xy 140.63345 -38.513766) (xy 140.650352 -38.489796) (xy 140.689725 -38.446325) (xy 140.734743 -38.408731)
			(xy 140.784536 -38.377738) (xy 140.838145 -38.353944) (xy 140.894533 -38.33781) (xy 140.952613 -38.329646)
			(xy 140.981938 -38.329108) (xy 140.982446 -38.329108) (xy 140.994892 -38.329362) (xy 141.005052 -38.328346)
			(xy 141.009878 -38.327076) (xy 141.018316 -38.324062) (xy 141.032496 -38.313129) (xy 141.037564 -38.30574)
			(xy 141.037818 -38.305232) (xy 141.03858 -38.303708) (xy 141.039088 -38.302946) (xy 141.045692 -38.291262)
			(xy 141.045692 -38.290754) (xy 141.053566 -38.27653) (xy 141.05763 -38.265862) (xy 141.059154 -38.253416)
			(xy 141.059154 -38.231318) (xy 141.058925 -38.224945) (xy 141.055717 -38.212607) (xy 141.052804 -38.206934)
			(xy 140.798804 -37.783262) (xy 140.529056 -37.333428) (xy 140.52677 -37.329872) (xy 140.438632 -37.219636)
			(xy 140.410493 -37.183653) (xy 140.360184 -37.107402) (xy 140.31707 -37.026863) (xy 140.281514 -36.942715)
			(xy 140.267182 -36.899342) (xy 140.265404 -36.893754) (xy 140.226034 -36.827968) (xy 140.186664 -36.76269)
			(xy 140.179044 -36.756594) (xy 140.153964 -36.736641) (xy 140.110225 -36.689805) (xy 140.074941 -36.636309)
			(xy 140.061442 -36.607242) (xy 140.057632 -36.598352) (xy 139.636754 -36.177474) (xy 139.626594 -36.1696)
			(xy 139.62126 -36.166552) (xy 139.615164 -36.164774) (xy 139.57935 -36.153344) (xy 139.570968 -36.15055)
			(xy 139.562586 -36.15055) (xy 139.558029 -36.150743) (xy 139.549085 -36.152526) (xy 139.544806 -36.154106)
			(xy 139.52474 -36.16198) (xy 139.518136 -36.167568) (xy 139.497336 -36.184614) (xy 139.451853 -36.213307)
			(xy 139.402794 -36.235336) (xy 139.35113 -36.250263) (xy 139.297883 -36.257793) (xy 139.270994 -36.258246)
			(xy 139.24418 -36.257784) (xy 139.191081 -36.250264) (xy 139.139557 -36.235386) (xy 139.090623 -36.213443)
			(xy 139.045242 -36.184867) (xy 139.004306 -36.150222) (xy 138.968623 -36.110188) (xy 138.938893 -36.065553)
			(xy 138.915704 -36.017198) (xy 138.89951 -35.966072) (xy 138.890631 -35.913184) (xy 138.889486 -35.88639)
			(xy 138.889486 -35.875976) (xy 138.889983 -35.847555) (xy 138.89837 -35.791336) (xy 138.915014 -35.736985)
			(xy 138.926824 -35.71113) (xy 138.929618 -35.705542) (xy 138.931904 -35.695128) (xy 138.931904 -35.672522)
			(xy 138.931409 -35.663079) (xy 138.924498 -35.645495) (xy 138.918442 -35.638232) (xy 138.882882 -35.602672)
			(xy 138.852857 -35.57202) (xy 138.797642 -35.506334) (xy 138.748329 -35.436109) (xy 138.726418 -35.399218)
			(xy 138.721592 -35.390582) (xy 138.698224 -35.372802) (xy 138.69414 -35.369804) (xy 138.685055 -35.365325)
			(xy 138.68019 -35.363912) (xy 138.648948 -35.355784) (xy 138.64844 -35.355784) (xy 138.628374 -35.350958)
			(xy 138.61796 -35.349688) (xy 138.590274 -35.357816) (xy 138.584178 -35.361626) (xy 138.544066 -35.386574)
			(xy 138.459989 -35.429648) (xy 138.372216 -35.46458) (xy 138.281534 -35.491059) (xy 138.188755 -35.508847)
			(xy 138.09471 -35.517785) (xy 138.047476 -35.518344) (xy 138.034522 -35.518344) (xy 137.975086 -35.515804)
			(xy 137.931998 -35.512194) (xy 137.846623 -35.498452) (xy 137.76276 -35.477369) (xy 137.681037 -35.449102)
			(xy 137.602069 -35.413864) (xy 137.526449 -35.371921) (xy 137.454745 -35.323586) (xy 137.387497 -35.269224)
			(xy 137.325208 -35.209242) (xy 137.268348 -35.144092) (xy 137.217344 -35.074262) (xy 137.194544 -35.037522)
			(xy 137.192004 -35.033712) (xy 137.18159 -35.021774) (xy 137.180066 -35.020504) (xy 137.157441 -35.002319)
			(xy 137.117437 -34.960262) (xy 137.084264 -34.912632) (xy 137.058688 -34.860526) (xy 137.0413 -34.805147)
			(xy 137.032501 -34.747774) (xy 137.031984 -34.718752) (xy 137.031984 -34.718498) (xy 137.032447 -34.689997)
			(xy 137.040865 -34.633623) (xy 137.048748 -34.60623) (xy 137.050272 -34.599118) (xy 137.05205 -34.588196)
			(xy 137.05205 -34.58464) (xy 137.051796 -34.581846) (xy 137.051288 -34.567622) (xy 137.051288 -34.566606)
			(xy 137.050272 -34.520886) (xy 137.050707 -34.4783) (xy 137.057948 -34.393435) (xy 137.072402 -34.309498)
			(xy 137.093962 -34.227099) (xy 137.122473 -34.14684) (xy 137.13968 -34.107882) (xy 137.142858 -34.098749)
			(xy 137.142853 -34.079426) (xy 137.13968 -34.07029) (xy 137.122471 -34.031334) (xy 137.093977 -33.95107)
			(xy 137.072426 -33.86867) (xy 137.057974 -33.784734) (xy 137.050727 -33.699872) (xy 137.050272 -33.657286)
			(xy 137.05205 -33.595818) (xy 137.052812 -33.583626) (xy 137.05078 -33.578038) (xy 137.045954 -33.56864)
			(xy 137.037826 -33.55721) (xy 137.007854 -33.525206) (xy 137.004142 -33.521563) (xy 136.995568 -33.51568)
			(xy 136.990836 -33.513522) (xy 136.98093 -33.509204) (xy 136.978898 -33.509204) (xy 136.970262 -33.509458)
			(xy 136.953244 -33.509712) (xy 136.45769 -33.509712) (xy 136.414434 -33.509252) (xy 136.328246 -33.501759)
			(xy 136.243032 -33.486823) (xy 136.159434 -33.464556) (xy 136.1186 -33.450276) (xy 136.1143 -33.448827)
			(xy 136.105357 -33.447288) (xy 136.10082 -33.447228) (xy 136.0678 -33.459928) (xy 136.060942 -33.46577)
			(xy 136.026948 -33.494749) (xy 135.954633 -33.547201) (xy 135.877918 -33.592976) (xy 135.797416 -33.631707)
			(xy 135.713774 -33.663085) (xy 135.627661 -33.686858) (xy 135.539767 -33.702835) (xy 135.450797 -33.710888)
			(xy 135.40613 -33.711388) (xy 135.40613 -33.711642) (xy 135.405368 -33.711642) (xy 135.358886 -33.71111)
			(xy 135.266326 -33.702463) (xy 135.174973 -33.685237) (xy 135.085619 -33.659582) (xy 134.999042 -33.625721)
			(xy 134.915993 -33.583948) (xy 134.837193 -33.534625) (xy 134.763326 -33.478181) (xy 134.695035 -33.415107)
			(xy 134.632911 -33.345949) (xy 134.577494 -33.271309) (xy 134.552944 -33.231836) (xy 134.550404 -33.227772)
			(xy 134.537958 -33.214056) (xy 134.534656 -33.211516) (xy 134.512455 -33.193283) (xy 134.473253 -33.151289)
			(xy 134.440775 -33.103903) (xy 134.41575 -33.052192) (xy 134.398742 -32.997319) (xy 134.390134 -32.94052)
			(xy 134.389622 -32.911796) (xy 134.391146 -32.879284) (xy 134.392416 -32.867092) (xy 134.394624 -32.849945)
			(xy 134.401751 -32.816112) (xy 134.40664 -32.799528) (xy 134.408164 -32.792416) (xy 134.409942 -32.781494)
			(xy 134.409942 -32.777938) (xy 134.409688 -32.775144) (xy 134.40918 -32.76092) (xy 134.40918 -32.759904)
			(xy 134.408164 -32.714184) (xy 134.408599 -32.671598) (xy 134.41584 -32.586733) (xy 134.430294 -32.502796)
			(xy 134.451855 -32.420397) (xy 134.480365 -32.340138) (xy 134.497572 -32.30118) (xy 134.50075 -32.292047)
			(xy 134.500745 -32.272724) (xy 134.497572 -32.263588) (xy 134.480364 -32.224632) (xy 134.45187 -32.144368)
			(xy 134.430319 -32.061968) (xy 134.415867 -31.978032) (xy 134.40862 -31.89317) (xy 134.408164 -31.850584)
			(xy 134.40918 -31.804864) (xy 134.40918 -31.803848) (xy 134.409688 -31.789624) (xy 134.409942 -31.78683)
			(xy 134.409942 -31.783274) (xy 134.408164 -31.772352) (xy 134.40664 -31.76524) (xy 134.398004 -31.731712)
			(xy 134.392416 -31.697676) (xy 134.391146 -31.685484) (xy 134.389622 -31.652972) (xy 134.390168 -31.62392)
			(xy 134.398979 -31.566488) (xy 134.416393 -31.511055) (xy 134.442008 -31.458902) (xy 134.475232 -31.411234)
			(xy 134.515297 -31.369153) (xy 134.537958 -31.350966) (xy 134.54162 -31.348005) (xy 134.54788 -31.340971)
			(xy 134.550404 -31.336996) (xy 134.55142 -31.335218) (xy 134.552944 -31.332932) (xy 134.57752 -31.293483)
			(xy 134.632945 -31.218865) (xy 134.695075 -31.149731) (xy 134.76337 -31.08668) (xy 134.837238 -31.03026)
			(xy 134.916037 -30.980961) (xy 134.999083 -30.939211) (xy 135.085655 -30.905372) (xy 135.175 -30.87974)
			(xy 135.266344 -30.862535) (xy 135.358893 -30.853907) (xy 135.405368 -30.85338) (xy 135.405622 -30.85338)
			(xy 135.448073 -30.853818) (xy 135.532667 -30.861032) (xy 135.616342 -30.875413) (xy 135.698491 -30.896857)
			(xy 135.778518 -30.92521) (xy 135.855845 -30.960265) (xy 135.92991 -31.001769) (xy 136.000178 -31.049422)
			(xy 136.066139 -31.102877) (xy 136.09701 -31.132018) (xy 136.103756 -31.137271) (xy 136.119722 -31.143358)
			(xy 136.128252 -31.143956) (xy 136.976866 -31.143956) (xy 136.983216 -31.143448) (xy 136.991714 -31.142075)
			(xy 137.007135 -31.134453) (xy 137.019154 -31.122145) (xy 137.023094 -31.114492) (xy 137.032746 -31.091124)
			(xy 137.033508 -31.083504) (xy 137.033762 -31.081218) (xy 137.033762 -31.080456) (xy 137.036046 -31.060694)
			(xy 137.044192 -31.021753) (xy 137.050018 -31.002732) (xy 137.051272 -30.998273) (xy 137.052292 -30.989069)
			(xy 137.05205 -30.984444) (xy 137.05205 -30.983936) (xy 137.051164 -30.96814) (xy 137.050274 -30.936511)
			(xy 137.050272 -30.92069) (xy 137.050707 -30.878103) (xy 137.057948 -30.793239) (xy 137.072401 -30.709302)
			(xy 137.093961 -30.626903) (xy 137.122472 -30.546644) (xy 137.13968 -30.507686) (xy 137.142859 -30.498553)
			(xy 137.142855 -30.479229) (xy 137.13968 -30.470094) (xy 137.122471 -30.431138) (xy 137.093977 -30.350874)
			(xy 137.072425 -30.268474) (xy 137.057973 -30.184538) (xy 137.050725 -30.099676) (xy 137.050272 -30.05709)
			(xy 137.05205 -29.996384) (xy 137.052304 -29.99232) (xy 137.052812 -29.983684) (xy 137.051288 -29.97962)
			(xy 137.044176 -29.966666) (xy 137.03808 -29.95803) (xy 137.028682 -29.947108) (xy 137.020046 -29.942536)
			(xy 136.99617 -29.929836) (xy 136.986518 -29.928566) (xy 136.959778 -29.925389) (xy 136.906662 -29.916495)
			(xy 136.880346 -29.910786) (xy 136.874758 -29.909516) (xy 136.785096 -29.909516) (xy 136.74373 -29.909099)
			(xy 136.661282 -29.902246) (xy 136.579687 -29.888579) (xy 136.499506 -29.868193) (xy 136.421292 -29.841227)
			(xy 136.383268 -29.824934) (xy 136.373616 -29.820616) (xy 136.13003 -29.820616) (xy 136.125153 -29.820714)
			(xy 136.115564 -29.822504) (xy 136.11098 -29.824172) (xy 136.102344 -29.827728) (xy 136.094978 -29.83484)
			(xy 136.064106 -29.863777) (xy 135.998242 -29.916909) (xy 135.928111 -29.964266) (xy 135.85422 -30.00551)
			(xy 135.777098 -30.040343) (xy 135.697302 -30.068515) (xy 135.615406 -30.089822) (xy 135.531998 -30.104112)
			(xy 135.447679 -30.111281) (xy 135.405368 -30.1117) (xy 135.35884 -30.111148) (xy 135.266192 -30.102451)
			(xy 135.174756 -30.085162) (xy 135.085328 -30.059432) (xy 134.998685 -30.025485) (xy 134.915581 -29.983616)
			(xy 134.836737 -29.934189) (xy 134.762839 -29.877634) (xy 134.69453 -29.814442) (xy 134.632403 -29.745162)
			(xy 134.576999 -29.670398) (xy 134.552436 -29.630878) (xy 134.549896 -29.627068) (xy 134.539482 -29.61513)
			(xy 134.537958 -29.61386) (xy 134.515336 -29.595674) (xy 134.475337 -29.553616) (xy 134.44217 -29.505984)
			(xy 134.416601 -29.453878) (xy 134.39922 -29.3985) (xy 134.390427 -29.341129) (xy 134.389876 -29.312108)
			(xy 134.389876 -29.311854) (xy 134.390343 -29.283354) (xy 134.398766 -29.226981) (xy 134.40664 -29.199586)
			(xy 134.408164 -29.192474) (xy 134.409942 -29.181552) (xy 134.409942 -29.177996) (xy 134.409688 -29.175202)
			(xy 134.40918 -29.160978) (xy 134.40918 -29.159962) (xy 134.408164 -29.114242) (xy 134.408597 -29.071655)
			(xy 134.415833 -28.986789) (xy 134.430282 -28.90285) (xy 134.451839 -28.820449) (xy 134.480345 -28.740188)
			(xy 134.497572 -28.701238) (xy 134.500761 -28.692104) (xy 134.500776 -28.672773) (xy 134.497572 -28.663646)
			(xy 134.480361 -28.62469) (xy 134.451863 -28.544427) (xy 134.430307 -28.462028) (xy 134.415851 -28.378091)
			(xy 134.408599 -28.293228) (xy 134.408164 -28.250642) (xy 134.40918 -28.204922) (xy 134.40918 -28.203906)
			(xy 134.409688 -28.189682) (xy 134.409942 -28.186888) (xy 134.409942 -28.183332) (xy 134.408164 -28.17241)
			(xy 134.40664 -28.165298) (xy 134.398004 -28.13177) (xy 134.392416 -28.097734) (xy 134.391146 -28.085542)
			(xy 134.389622 -28.05303) (xy 134.390138 -28.024324) (xy 134.398735 -27.967559) (xy 134.415739 -27.912723)
			(xy 134.440766 -27.861053) (xy 134.473252 -27.813715) (xy 134.512462 -27.771779) (xy 134.534656 -27.753564)
			(xy 134.540498 -27.747976) (xy 134.550404 -27.737054) (xy 134.552944 -27.732736) (xy 134.57753 -27.693295)
			(xy 134.632971 -27.618693) (xy 134.695111 -27.549572) (xy 134.763411 -27.48653) (xy 134.837279 -27.430116)
			(xy 134.916075 -27.380817) (xy 134.999114 -27.339061) (xy 135.085678 -27.305212) (xy 135.175016 -27.279561)
			(xy 135.266352 -27.262332) (xy 135.358895 -27.253673) (xy 135.405368 -27.253184) (xy 135.452382 -27.253739)
			(xy 135.545989 -27.262612) (xy 135.638347 -27.280255) (xy 135.728634 -27.306511) (xy 135.81605 -27.341147)
			(xy 135.899819 -27.383855) (xy 135.979196 -27.434256) (xy 136.053479 -27.491904) (xy 136.08812 -27.523694)
			(xy 136.093454 -27.528774) (xy 136.094724 -27.530044) (xy 136.094978 -27.530298) (xy 136.120378 -27.540458)
			(xy 136.124945 -27.542215) (xy 136.134537 -27.544138) (xy 136.139428 -27.544268) (xy 138.23061 -27.544268)
			(xy 138.2736 -27.544757) (xy 138.359255 -27.55223) (xy 138.44395 -27.567042) (xy 138.527058 -27.589083)
			(xy 138.567668 -27.603196) (xy 138.609578 -27.619452) (xy 139.952222 -28.173426) (xy 139.958478 -28.175789)
			(xy 139.971739 -28.177473) (xy 139.978384 -28.176728) (xy 139.991338 -28.17495) (xy 140.00226 -28.166568)
			(xy 140.022325 -28.151649) (xy 140.065617 -28.126627) (xy 140.111804 -28.107472) (xy 140.160097 -28.09451)
			(xy 140.209669 -28.087965) (xy 140.23467 -28.087574) (xy 140.261912 -28.088057) (xy 140.315841 -28.095803)
			(xy 140.36812 -28.111143) (xy 140.417686 -28.133763) (xy 140.426052 -28.139136) (xy 144.498058 -28.139136)
			(xy 144.502129 -28.083514) (xy 144.514255 -28.029077) (xy 144.534178 -27.976986) (xy 144.561474 -27.928351)
			(xy 144.59556 -27.884208) (xy 144.635709 -27.845499) (xy 144.681067 -27.813048) (xy 144.730667 -27.787547)
			(xy 144.783451 -27.76954) (xy 144.838294 -27.75941) (xy 144.894028 -27.757373) (xy 144.949465 -27.763473)
			(xy 145.003422 -27.777579) (xy 145.054751 -27.799391) (xy 145.102357 -27.828445) (xy 145.145225 -27.86412)
			(xy 145.182442 -27.905657) (xy 145.213215 -27.95217) (xy 145.236887 -28.002667) (xy 145.252955 -28.056074)
			(xy 145.261075 -28.11125) (xy 145.261584 -28.139136) (xy 145.768058 -28.139136) (xy 145.772129 -28.083514)
			(xy 145.784255 -28.029077) (xy 145.804178 -27.976986) (xy 145.831474 -27.928351) (xy 145.86556 -27.884208)
			(xy 145.905709 -27.845499) (xy 145.951067 -27.813048) (xy 146.000667 -27.787547) (xy 146.053451 -27.76954)
			(xy 146.108294 -27.75941) (xy 146.164028 -27.757373) (xy 146.219465 -27.763473) (xy 146.273422 -27.777579)
			(xy 146.324751 -27.799391) (xy 146.372357 -27.828445) (xy 146.415225 -27.86412) (xy 146.452442 -27.905657)
			(xy 146.483215 -27.95217) (xy 146.506887 -28.002667) (xy 146.522955 -28.056074) (xy 146.531075 -28.11125)
			(xy 146.531584 -28.139136) (xy 146.531075 -28.167022) (xy 146.522955 -28.222198) (xy 146.506887 -28.275605)
			(xy 146.483215 -28.326102) (xy 146.452442 -28.372615) (xy 146.415225 -28.414152) (xy 146.372357 -28.449827)
			(xy 146.324751 -28.478881) (xy 146.273422 -28.500693) (xy 146.219465 -28.514799) (xy 146.164028 -28.520899)
			(xy 146.108294 -28.518862) (xy 146.053451 -28.508732) (xy 146.000667 -28.490725) (xy 145.951067 -28.465224)
			(xy 145.905709 -28.432773) (xy 145.86556 -28.394064) (xy 145.831474 -28.349921) (xy 145.804178 -28.301286)
			(xy 145.784255 -28.249195) (xy 145.772129 -28.194758) (xy 145.768058 -28.139136) (xy 145.261584 -28.139136)
			(xy 145.261075 -28.167022) (xy 145.252955 -28.222198) (xy 145.236887 -28.275605) (xy 145.213215 -28.326102)
			(xy 145.182442 -28.372615) (xy 145.145225 -28.414152) (xy 145.102357 -28.449827) (xy 145.054751 -28.478881)
			(xy 145.003422 -28.500693) (xy 144.949465 -28.514799) (xy 144.894028 -28.520899) (xy 144.838294 -28.518862)
			(xy 144.783451 -28.508732) (xy 144.730667 -28.490725) (xy 144.681067 -28.465224) (xy 144.635709 -28.432773)
			(xy 144.59556 -28.394064) (xy 144.561474 -28.349921) (xy 144.534178 -28.301286) (xy 144.514255 -28.249195)
			(xy 144.502129 -28.194758) (xy 144.498058 -28.139136) (xy 140.426052 -28.139136) (xy 140.463529 -28.163205)
			(xy 140.504717 -28.198869) (xy 140.540414 -28.240029) (xy 140.569892 -28.285849) (xy 140.592551 -28.335396)
			(xy 140.607932 -28.387663) (xy 140.615721 -28.441587) (xy 140.616178 -28.468828) (xy 140.616178 -28.469336)
			(xy 140.61567 -28.4861) (xy 140.646583 -28.510727) (xy 140.704847 -28.564142) (xy 140.758707 -28.621995)
			(xy 140.783564 -28.652724) (xy 141.155785 -29.12237) (xy 150.706836 -29.12237) (xy 150.706836 -28.25877)
			(xy 150.707326 -28.228786) (xy 150.715154 -28.16933) (xy 150.730675 -28.111405) (xy 150.753624 -28.056001)
			(xy 150.783608 -28.004067) (xy 150.820114 -27.956491) (xy 150.862519 -27.914086) (xy 150.910095 -27.87758)
			(xy 150.962029 -27.847596) (xy 151.017433 -27.824647) (xy 151.075358 -27.809126) (xy 151.134814 -27.801298)
			(xy 151.194782 -27.801298) (xy 151.254238 -27.809126) (xy 151.312163 -27.824647) (xy 151.367567 -27.847596)
			(xy 151.419501 -27.87758) (xy 151.467077 -27.914086) (xy 151.509482 -27.956491) (xy 151.545988 -28.004067)
			(xy 151.575972 -28.056001) (xy 151.598921 -28.111405) (xy 151.614442 -28.16933) (xy 151.62227 -28.228786)
			(xy 151.62276 -28.25877) (xy 151.62276 -29.12237) (xy 151.62227 -29.152354) (xy 151.614442 -29.21181)
			(xy 151.598921 -29.269735) (xy 151.575972 -29.325139) (xy 151.545988 -29.377073) (xy 151.509482 -29.424649)
			(xy 151.467077 -29.467054) (xy 151.419501 -29.50356) (xy 151.367567 -29.533544) (xy 151.312163 -29.556493)
			(xy 151.254238 -29.572014) (xy 151.194782 -29.579842) (xy 151.134814 -29.579842) (xy 151.075358 -29.572014)
			(xy 151.017433 -29.556493) (xy 150.962029 -29.533544) (xy 150.910095 -29.50356) (xy 150.862519 -29.467054)
			(xy 150.820114 -29.424649) (xy 150.783608 -29.377073) (xy 150.753624 -29.325139) (xy 150.730675 -29.269735)
			(xy 150.715154 -29.21181) (xy 150.707326 -29.152354) (xy 150.706836 -29.12237) (xy 141.155785 -29.12237)
			(xy 141.367764 -29.389832) (xy 141.375234 -29.397171) (xy 141.394389 -29.405577) (xy 141.404848 -29.406088)
			(xy 141.411198 -29.40558) (xy 141.412214 -29.40558) (xy 141.412976 -29.405326) (xy 141.424112 -29.404118)
			(xy 141.446479 -29.40285) (xy 141.45768 -29.402786) (xy 141.484934 -29.403248) (xy 141.538887 -29.411003)
			(xy 141.591188 -29.426357) (xy 141.640771 -29.448998) (xy 141.686627 -29.478465) (xy 141.727823 -29.514159)
			(xy 141.763519 -29.555352) (xy 141.792989 -29.601206) (xy 141.815634 -29.650788) (xy 141.830992 -29.703087)
			(xy 141.83875 -29.75704) (xy 141.839188 -29.784294) (xy 141.839188 -29.784802) (xy 141.838478 -29.817192)
			(xy 141.827492 -29.881034) (xy 141.817344 -29.911802) (xy 141.81582 -29.915866) (xy 141.812772 -29.933138)
			(xy 141.813033 -29.941782) (xy 141.818622 -29.958137) (xy 141.823694 -29.965142) (xy 142.150123 -30.376876)
			(xy 142.989046 -30.376876) (xy 142.989602 -30.34796) (xy 142.998321 -30.29079) (xy 143.01557 -30.235591)
			(xy 143.040955 -30.183629) (xy 143.073892 -30.136094) (xy 143.113629 -30.094077) (xy 143.136112 -30.075886)
			(xy 143.144917 -30.068277) (xy 143.155101 -30.047378) (xy 143.15567 -30.035754) (xy 143.15567 -29.955998)
			(xy 143.155128 -29.944366) (xy 143.144942 -29.923456) (xy 143.136112 -29.915866) (xy 143.113615 -29.897691)
			(xy 143.07388 -29.855668) (xy 143.040942 -29.80813) (xy 143.015556 -29.756166) (xy 142.998303 -29.700965)
			(xy 142.989578 -29.643793) (xy 142.989046 -29.614876) (xy 142.989532 -29.587625) (xy 142.997288 -29.533677)
			(xy 143.012643 -29.481382) (xy 143.035285 -29.431805) (xy 143.064751 -29.385955) (xy 143.100442 -29.344764)
			(xy 143.141633 -29.309073) (xy 143.187483 -29.279607) (xy 143.23706 -29.256965) (xy 143.289355 -29.24161)
			(xy 143.343303 -29.233854) (xy 143.397805 -29.233854) (xy 143.451753 -29.24161) (xy 143.504048 -29.256965)
			(xy 143.553625 -29.279607) (xy 143.599475 -29.309073) (xy 143.640666 -29.344764) (xy 143.676357 -29.385955)
			(xy 143.705823 -29.431805) (xy 143.728465 -29.481382) (xy 143.74382 -29.533677) (xy 143.751576 -29.587625)
			(xy 143.752062 -29.614876) (xy 143.751541 -29.643793) (xy 143.742814 -29.700965) (xy 143.725558 -29.756164)
			(xy 143.700167 -29.808126) (xy 143.667223 -29.85566) (xy 143.627482 -29.897676) (xy 143.604996 -29.915866)
			(xy 143.596214 -29.923497) (xy 143.586017 -29.94438) (xy 143.585438 -29.955998) (xy 143.585438 -30.035754)
			(xy 143.585947 -30.04739) (xy 143.596156 -30.0683) (xy 143.604996 -30.075886) (xy 143.627472 -30.094086)
			(xy 143.667208 -30.136104) (xy 143.700148 -30.183637) (xy 143.725538 -30.235596) (xy 143.742795 -30.290792)
			(xy 143.751526 -30.347961) (xy 143.752062 -30.376876) (xy 146.029172 -30.376876) (xy 146.029718 -30.34796)
			(xy 146.038437 -30.290789) (xy 146.055688 -30.235589) (xy 146.081074 -30.183627) (xy 146.114015 -30.136092)
			(xy 146.153753 -30.094076) (xy 146.176238 -30.075886) (xy 146.185048 -30.068282) (xy 146.195228 -30.047379)
			(xy 146.195796 -30.035754) (xy 146.195796 -29.955998) (xy 146.195245 -29.944368) (xy 146.185065 -29.923458)
			(xy 146.176238 -29.915866) (xy 146.153746 -29.897685) (xy 146.11401 -29.855664) (xy 146.081071 -29.808127)
			(xy 146.055683 -29.756164) (xy 146.03843 -29.700964) (xy 146.029704 -29.643793) (xy 146.029172 -29.614876)
			(xy 146.029658 -29.587625) (xy 146.037414 -29.533677) (xy 146.052769 -29.481382) (xy 146.075411 -29.431805)
			(xy 146.104877 -29.385955) (xy 146.140568 -29.344764) (xy 146.181759 -29.309073) (xy 146.227609 -29.279607)
			(xy 146.277186 -29.256965) (xy 146.329481 -29.24161) (xy 146.383429 -29.233854) (xy 146.437931 -29.233854)
			(xy 146.491879 -29.24161) (xy 146.544174 -29.256965) (xy 146.593751 -29.279607) (xy 146.639601 -29.309073)
			(xy 146.680792 -29.344764) (xy 146.716483 -29.385955) (xy 146.745949 -29.431805) (xy 146.768591 -29.481382)
			(xy 146.783946 -29.533677) (xy 146.791702 -29.587625) (xy 146.792188 -29.614876) (xy 146.791657 -29.643792)
			(xy 146.782931 -29.700963) (xy 146.765676 -29.756162) (xy 146.740287 -29.808124) (xy 146.707345 -29.855658)
			(xy 146.667606 -29.897676) (xy 146.645122 -29.915866) (xy 146.636327 -29.923484) (xy 146.62614 -29.944377)
			(xy 146.625564 -29.955998) (xy 146.625564 -30.035754) (xy 146.626064 -30.047391) (xy 146.636278 -30.068302)
			(xy 146.645122 -30.075886) (xy 146.667603 -30.094079) (xy 146.707338 -30.136099) (xy 146.740276 -30.183634)
			(xy 146.765665 -30.235595) (xy 146.782922 -30.290791) (xy 146.791652 -30.34796) (xy 146.792188 -30.376876)
			(xy 146.791702 -30.404127) (xy 146.783946 -30.458075) (xy 146.768591 -30.51037) (xy 146.745949 -30.559947)
			(xy 146.716483 -30.605797) (xy 146.680792 -30.646988) (xy 146.639601 -30.682679) (xy 146.593751 -30.712145)
			(xy 146.544174 -30.734787) (xy 146.491879 -30.750142) (xy 146.437931 -30.757898) (xy 146.383429 -30.757898)
			(xy 146.329481 -30.750142) (xy 146.277186 -30.734787) (xy 146.227609 -30.712145) (xy 146.181759 -30.682679)
			(xy 146.140568 -30.646988) (xy 146.104877 -30.605797) (xy 146.075411 -30.559947) (xy 146.052769 -30.51037)
			(xy 146.037414 -30.458075) (xy 146.029658 -30.404127) (xy 146.029172 -30.376876) (xy 143.752062 -30.376876)
			(xy 143.751576 -30.404127) (xy 143.74382 -30.458075) (xy 143.728465 -30.51037) (xy 143.705823 -30.559947)
			(xy 143.676357 -30.605797) (xy 143.640666 -30.646988) (xy 143.599475 -30.682679) (xy 143.553625 -30.712145)
			(xy 143.504048 -30.734787) (xy 143.451753 -30.750142) (xy 143.397805 -30.757898) (xy 143.343303 -30.757898)
			(xy 143.289355 -30.750142) (xy 143.23706 -30.734787) (xy 143.187483 -30.712145) (xy 143.141633 -30.682679)
			(xy 143.100442 -30.646988) (xy 143.064751 -30.605797) (xy 143.035285 -30.559947) (xy 143.012643 -30.51037)
			(xy 142.997288 -30.458075) (xy 142.989532 -30.404127) (xy 142.989046 -30.376876) (xy 142.150123 -30.376876)
			(xy 142.582676 -30.922468) (xy 148.852636 -30.922468) (xy 148.852636 -30.058868) (xy 148.853126 -30.028884)
			(xy 148.860954 -29.969428) (xy 148.876475 -29.911503) (xy 148.899424 -29.856099) (xy 148.929408 -29.804165)
			(xy 148.965914 -29.756589) (xy 149.008319 -29.714184) (xy 149.055895 -29.677678) (xy 149.107829 -29.647694)
			(xy 149.163233 -29.624745) (xy 149.221158 -29.609224) (xy 149.280614 -29.601396) (xy 149.340582 -29.601396)
			(xy 149.400038 -29.609224) (xy 149.457963 -29.624745) (xy 149.513367 -29.647694) (xy 149.565301 -29.677678)
			(xy 149.612877 -29.714184) (xy 149.655282 -29.756589) (xy 149.691788 -29.804165) (xy 149.721772 -29.856099)
			(xy 149.744721 -29.911503) (xy 149.760242 -29.969428) (xy 149.76807 -30.028884) (xy 149.76856 -30.058868)
			(xy 149.76856 -30.922468) (xy 149.76807 -30.952452) (xy 149.760242 -31.011908) (xy 149.744721 -31.069833)
			(xy 149.721772 -31.125237) (xy 149.691788 -31.177171) (xy 149.655282 -31.224747) (xy 149.612877 -31.267152)
			(xy 149.565301 -31.303658) (xy 149.513367 -31.333642) (xy 149.457963 -31.356591) (xy 149.400038 -31.372112)
			(xy 149.340582 -31.37994) (xy 149.280614 -31.37994) (xy 149.221158 -31.372112) (xy 149.163233 -31.356591)
			(xy 149.107829 -31.333642) (xy 149.055895 -31.303658) (xy 149.008319 -31.267152) (xy 148.965914 -31.224747)
			(xy 148.929408 -31.177171) (xy 148.899424 -31.125237) (xy 148.876475 -31.069833) (xy 148.860954 -31.011908)
			(xy 148.853126 -30.952452) (xy 148.852636 -30.922468) (xy 142.582676 -30.922468) (xy 142.642082 -30.997398)
			(xy 142.644876 -31.0007) (xy 142.679928 -31.035752) (xy 143.011144 -31.367222) (xy 143.019445 -31.374491)
			(xy 143.040257 -31.381741) (xy 143.051276 -31.381192) (xy 143.08201 -31.378398) (xy 143.082518 -31.378398)
			(xy 143.091916 -31.377382) (xy 143.096657 -31.377031) (xy 143.106119 -31.377934) (xy 143.110712 -31.37916)
			(xy 143.112998 -31.379668) (xy 143.133826 -31.384748) (xy 143.145256 -31.382462) (xy 143.165322 -31.353252)
			(xy 143.180626 -31.331566) (xy 143.216275 -31.292244) (xy 143.257034 -31.258247) (xy 143.302113 -31.23023)
			(xy 143.350643 -31.208737) (xy 143.401685 -31.194182) (xy 143.454252 -31.186847) (xy 143.48079 -31.186374)
			(xy 143.508042 -31.186859) (xy 143.561992 -31.194614) (xy 143.614289 -31.209968) (xy 143.663869 -31.232609)
			(xy 143.709722 -31.262074) (xy 143.750914 -31.297766) (xy 143.786609 -31.338956) (xy 143.816078 -31.384807)
			(xy 143.838722 -31.434385) (xy 143.85408 -31.486681) (xy 143.861839 -31.54063) (xy 143.862298 -31.567882)
			(xy 143.861752 -31.596983) (xy 143.852918 -31.654511) (xy 143.835453 -31.710031) (xy 143.83091 -31.719266)
			(xy 144.385536 -31.719266) (xy 144.389607 -31.663644) (xy 144.401733 -31.609207) (xy 144.421656 -31.557116)
			(xy 144.448952 -31.508481) (xy 144.483038 -31.464338) (xy 144.523187 -31.425629) (xy 144.568545 -31.393178)
			(xy 144.618145 -31.367677) (xy 144.670929 -31.34967) (xy 144.725772 -31.33954) (xy 144.781506 -31.337503)
			(xy 144.836943 -31.343603) (xy 144.8909 -31.357709) (xy 144.942229 -31.379521) (xy 144.989835 -31.408575)
			(xy 145.032703 -31.44425) (xy 145.06992 -31.485787) (xy 145.100693 -31.5323) (xy 145.124365 -31.582797)
			(xy 145.140433 -31.636204) (xy 145.144583 -31.664402) (xy 145.661124 -31.664402) (xy 145.665195 -31.60878)
			(xy 145.677321 -31.554343) (xy 145.697244 -31.502252) (xy 145.72454 -31.453617) (xy 145.758626 -31.409474)
			(xy 145.798775 -31.370765) (xy 145.844133 -31.338314) (xy 145.893733 -31.312813) (xy 145.946517 -31.294806)
			(xy 146.00136 -31.284676) (xy 146.057094 -31.282639) (xy 146.112531 -31.288739) (xy 146.166488 -31.302845)
			(xy 146.217817 -31.324657) (xy 146.265423 -31.353711) (xy 146.308291 -31.389386) (xy 146.345508 -31.430923)
			(xy 146.376281 -31.477436) (xy 146.399953 -31.527933) (xy 146.416021 -31.58134) (xy 146.424141 -31.636516)
			(xy 146.42465 -31.664402) (xy 146.424141 -31.692288) (xy 146.416021 -31.747464) (xy 146.407081 -31.777178)
			(xy 146.926298 -31.777178) (xy 146.930369 -31.721556) (xy 146.942495 -31.667119) (xy 146.962418 -31.615028)
			(xy 146.989714 -31.566393) (xy 147.0238 -31.52225) (xy 147.063949 -31.483541) (xy 147.109307 -31.45109)
			(xy 147.158907 -31.425589) (xy 147.211691 -31.407582) (xy 147.266534 -31.397452) (xy 147.322268 -31.395415)
			(xy 147.377705 -31.401515) (xy 147.431662 -31.415621) (xy 147.482991 -31.437433) (xy 147.530597 -31.466487)
			(xy 147.573465 -31.502162) (xy 147.610682 -31.543699) (xy 147.641455 -31.590212) (xy 147.665127 -31.640709)
			(xy 147.681195 -31.694116) (xy 147.689315 -31.749292) (xy 147.689824 -31.777178) (xy 147.689315 -31.805064)
			(xy 147.681195 -31.86024) (xy 147.665127 -31.913647) (xy 147.641455 -31.964144) (xy 147.610682 -32.010657)
			(xy 147.573465 -32.052194) (xy 147.530597 -32.087869) (xy 147.482991 -32.116923) (xy 147.431662 -32.138735)
			(xy 147.377705 -32.152841) (xy 147.322268 -32.158941) (xy 147.266534 -32.156904) (xy 147.211691 -32.146774)
			(xy 147.158907 -32.128767) (xy 147.109307 -32.103266) (xy 147.063949 -32.070815) (xy 147.0238 -32.032106)
			(xy 146.989714 -31.987963) (xy 146.962418 -31.939328) (xy 146.942495 -31.887237) (xy 146.930369 -31.8328)
			(xy 146.926298 -31.777178) (xy 146.407081 -31.777178) (xy 146.399953 -31.800871) (xy 146.376281 -31.851368)
			(xy 146.345508 -31.897881) (xy 146.308291 -31.939418) (xy 146.265423 -31.975093) (xy 146.217817 -32.004147)
			(xy 146.166488 -32.025959) (xy 146.112531 -32.040065) (xy 146.057094 -32.046165) (xy 146.00136 -32.044128)
			(xy 145.946517 -32.033998) (xy 145.893733 -32.015991) (xy 145.844133 -31.99049) (xy 145.798775 -31.958039)
			(xy 145.758626 -31.91933) (xy 145.72454 -31.875187) (xy 145.697244 -31.826552) (xy 145.677321 -31.774461)
			(xy 145.665195 -31.720024) (xy 145.661124 -31.664402) (xy 145.144583 -31.664402) (xy 145.148553 -31.69138)
			(xy 145.149062 -31.719266) (xy 145.148553 -31.747152) (xy 145.140433 -31.802328) (xy 145.124365 -31.855735)
			(xy 145.100693 -31.906232) (xy 145.06992 -31.952745) (xy 145.032703 -31.994282) (xy 144.989835 -32.029957)
			(xy 144.942229 -32.059011) (xy 144.8909 -32.080823) (xy 144.836943 -32.094929) (xy 144.781506 -32.101029)
			(xy 144.725772 -32.098992) (xy 144.670929 -32.088862) (xy 144.618145 -32.070855) (xy 144.568545 -32.045354)
			(xy 144.523187 -32.012903) (xy 144.483038 -31.974194) (xy 144.448952 -31.930051) (xy 144.421656 -31.881416)
			(xy 144.401733 -31.829325) (xy 144.389607 -31.774888) (xy 144.385536 -31.719266) (xy 143.83091 -31.719266)
			(xy 143.809762 -31.762257) (xy 143.77644 -31.809976) (xy 143.73626 -31.852084) (xy 143.690153 -31.887603)
			(xy 143.66494 -31.902146) (xy 143.664686 -31.902146) (xy 143.65605 -31.906972) (xy 143.636238 -31.931102)
			(xy 143.633916 -31.934319) (xy 143.630219 -31.94134) (xy 143.628872 -31.945072) (xy 143.610076 -32.01289)
			(xy 143.608587 -32.021776) (xy 143.611197 -32.039593) (xy 143.615156 -32.047688) (xy 143.678656 -32.15132)
			(xy 143.708374 -32.19958) (xy 144.029991 -32.722312) (xy 150.706836 -32.722312) (xy 150.706836 -31.858712)
			(xy 150.707326 -31.828728) (xy 150.715154 -31.769272) (xy 150.730675 -31.711347) (xy 150.753624 -31.655943)
			(xy 150.783608 -31.604009) (xy 150.820114 -31.556433) (xy 150.862519 -31.514028) (xy 150.910095 -31.477522)
			(xy 150.962029 -31.447538) (xy 151.017433 -31.424589) (xy 151.075358 -31.409068) (xy 151.134814 -31.40124)
			(xy 151.194782 -31.40124) (xy 151.254238 -31.409068) (xy 151.312163 -31.424589) (xy 151.367567 -31.447538)
			(xy 151.419501 -31.477522) (xy 151.467077 -31.514028) (xy 151.509482 -31.556433) (xy 151.545988 -31.604009)
			(xy 151.575972 -31.655943) (xy 151.598921 -31.711347) (xy 151.614442 -31.769272) (xy 151.62227 -31.828728)
			(xy 151.62276 -31.858712) (xy 151.62276 -32.722312) (xy 151.62227 -32.752296) (xy 151.614442 -32.811752)
			(xy 151.598921 -32.869677) (xy 151.575972 -32.925081) (xy 151.545988 -32.977015) (xy 151.509482 -33.024591)
			(xy 151.467077 -33.066996) (xy 151.419501 -33.103502) (xy 151.367567 -33.133486) (xy 151.312163 -33.156435)
			(xy 151.254238 -33.171956) (xy 151.194782 -33.179784) (xy 151.134814 -33.179784) (xy 151.075358 -33.171956)
			(xy 151.017433 -33.156435) (xy 150.962029 -33.133486) (xy 150.910095 -33.103502) (xy 150.862519 -33.066996)
			(xy 150.820114 -33.024591) (xy 150.783608 -32.977015) (xy 150.753624 -32.925081) (xy 150.730675 -32.869677)
			(xy 150.715154 -32.811752) (xy 150.707326 -32.752296) (xy 150.706836 -32.722312) (xy 144.029991 -32.722312)
			(xy 144.101566 -32.838644) (xy 144.102074 -32.83966) (xy 144.103852 -32.841946) (xy 144.106432 -32.845089)
			(xy 144.112433 -32.850574) (xy 144.11579 -32.852868) (xy 144.141698 -32.869632) (xy 144.152366 -32.87141)
			(xy 144.180737 -32.876514) (xy 144.235619 -32.894141) (xy 144.287225 -32.919824) (xy 144.334378 -32.95298)
			(xy 144.376005 -32.992854) (xy 144.41116 -33.038537) (xy 144.43904 -33.08899) (xy 144.459011 -33.143063)
			(xy 144.470619 -33.199525) (xy 144.47266 -33.22828) (xy 144.473168 -33.23717) (xy 144.473168 -33.2486)
			(xy 144.471644 -33.283652) (xy 144.470882 -33.293304) (xy 144.473422 -33.30194) (xy 144.474856 -33.30668)
			(xy 144.479331 -33.315512) (xy 144.482312 -33.319466) (xy 145.435871 -34.52241) (xy 148.852636 -34.52241)
			(xy 148.852636 -33.65881) (xy 148.853126 -33.628826) (xy 148.860954 -33.56937) (xy 148.876475 -33.511445)
			(xy 148.899424 -33.456041) (xy 148.929408 -33.404107) (xy 148.965914 -33.356531) (xy 149.008319 -33.314126)
			(xy 149.055895 -33.27762) (xy 149.107829 -33.247636) (xy 149.163233 -33.224687) (xy 149.221158 -33.209166)
			(xy 149.280614 -33.201338) (xy 149.340582 -33.201338) (xy 149.400038 -33.209166) (xy 149.457963 -33.224687)
			(xy 149.513367 -33.247636) (xy 149.565301 -33.27762) (xy 149.612877 -33.314126) (xy 149.655282 -33.356531)
			(xy 149.691788 -33.404107) (xy 149.721772 -33.456041) (xy 149.744721 -33.511445) (xy 149.760242 -33.56937)
			(xy 149.76807 -33.628826) (xy 149.76856 -33.65881) (xy 149.76856 -34.52241) (xy 149.76807 -34.552394)
			(xy 149.760242 -34.61185) (xy 149.744721 -34.669775) (xy 149.721772 -34.725179) (xy 149.691788 -34.777113)
			(xy 149.655282 -34.824689) (xy 149.612877 -34.867094) (xy 149.565301 -34.9036) (xy 149.513367 -34.933584)
			(xy 149.457963 -34.956533) (xy 149.400038 -34.972054) (xy 149.340582 -34.979882) (xy 149.280614 -34.979882)
			(xy 149.221158 -34.972054) (xy 149.163233 -34.956533) (xy 149.107829 -34.933584) (xy 149.055895 -34.9036)
			(xy 149.008319 -34.867094) (xy 148.965914 -34.824689) (xy 148.929408 -34.777113) (xy 148.899424 -34.725179)
			(xy 148.876475 -34.669775) (xy 148.860954 -34.61185) (xy 148.853126 -34.552394) (xy 148.852636 -34.52241)
			(xy 145.435871 -34.52241) (xy 145.886678 -35.091116) (xy 145.894939 -35.099691) (xy 145.91694 -35.108712)
			(xy 145.928842 -35.108388) (xy 146.012408 -35.102038) (xy 146.024563 -35.100413) (xy 146.04539 -35.087541)
			(xy 146.052286 -35.0774) (xy 146.052794 -35.076638) (xy 146.052794 -35.076384) (xy 146.067443 -35.051649)
			(xy 146.103014 -35.006491) (xy 146.144957 -34.96718) (xy 146.192324 -34.934608) (xy 146.244042 -34.909512)
			(xy 146.29894 -34.892459) (xy 146.355775 -34.883837) (xy 146.384518 -34.883344) (xy 146.41177 -34.883831)
			(xy 146.465718 -34.891589) (xy 146.518013 -34.906945) (xy 146.567591 -34.929587) (xy 146.613443 -34.959053)
			(xy 146.654635 -34.994744) (xy 146.690329 -35.035933) (xy 146.719799 -35.081782) (xy 146.742444 -35.131359)
			(xy 146.757804 -35.183653) (xy 146.765567 -35.2376) (xy 146.766026 -35.264852) (xy 146.765551 -35.29231)
			(xy 146.75768 -35.34666) (xy 146.742094 -35.399318) (xy 146.719116 -35.449196) (xy 146.68922 -35.495262)
			(xy 146.653025 -35.536562) (xy 146.61128 -35.572244) (xy 146.564848 -35.601568) (xy 146.51469 -35.623928)
			(xy 146.488404 -35.631882) (xy 146.480022 -35.634422) (xy 146.471132 -35.643058) (xy 146.466792 -35.647568)
			(xy 146.460244 -35.658232) (xy 146.458178 -35.66414) (xy 146.432778 -35.74415) (xy 146.429633 -35.756226)
			(xy 146.434156 -35.780736) (xy 146.441414 -35.790886) (xy 146.834473 -36.286948) (xy 147.30044 -36.286948)
			(xy 147.304511 -36.231326) (xy 147.316637 -36.176889) (xy 147.33656 -36.124798) (xy 147.363856 -36.076163)
			(xy 147.397942 -36.03202) (xy 147.438091 -35.993311) (xy 147.483449 -35.96086) (xy 147.533049 -35.935359)
			(xy 147.585833 -35.917352) (xy 147.640676 -35.907222) (xy 147.69641 -35.905185) (xy 147.751847 -35.911285)
			(xy 147.805804 -35.925391) (xy 147.857133 -35.947203) (xy 147.904739 -35.976257) (xy 147.947607 -36.011932)
			(xy 147.984824 -36.053469) (xy 148.015597 -36.099982) (xy 148.039269 -36.150479) (xy 148.055337 -36.203886)
			(xy 148.063457 -36.259062) (xy 148.063966 -36.286948) (xy 148.063457 -36.314834) (xy 148.055337 -36.37001)
			(xy 148.039269 -36.423417) (xy 148.015597 -36.473914) (xy 147.988052 -36.515548) (xy 149.114254 -36.515548)
			(xy 149.118325 -36.459926) (xy 149.130451 -36.405489) (xy 149.150374 -36.353398) (xy 149.17767 -36.304763)
			(xy 149.211756 -36.26062) (xy 149.251905 -36.221911) (xy 149.297263 -36.18946) (xy 149.346863 -36.163959)
			(xy 149.399647 -36.145952) (xy 149.45449 -36.135822) (xy 149.510224 -36.133785) (xy 149.565661 -36.139885)
			(xy 149.619618 -36.153991) (xy 149.670947 -36.175803) (xy 149.718553 -36.204857) (xy 149.761421 -36.240532)
			(xy 149.798638 -36.282069) (xy 149.829411 -36.328582) (xy 149.853083 -36.379079) (xy 149.869151 -36.432486)
			(xy 149.877271 -36.487662) (xy 149.87778 -36.515548) (xy 149.877271 -36.543434) (xy 149.869151 -36.59861)
			(xy 149.868694 -36.60013) (xy 154.098251 -36.60013) (xy 154.102256 -36.512222) (xy 154.114239 -36.425042)
			(xy 154.134099 -36.339313) (xy 154.161674 -36.255745) (xy 154.196733 -36.175031) (xy 154.238986 -36.097839)
			(xy 154.288084 -36.02481) (xy 154.34362 -35.956548) (xy 154.405132 -35.893618) (xy 154.472113 -35.836544)
			(xy 154.544006 -35.785796) (xy 154.620215 -35.741796) (xy 154.70011 -35.704909) (xy 154.783029 -35.67544)
			(xy 154.868284 -35.653633) (xy 154.955168 -35.639669) (xy 155.042962 -35.633663) (xy 155.130939 -35.635667)
			(xy 155.218369 -35.645662) (xy 155.304528 -35.663566) (xy 155.388702 -35.68923) (xy 155.470193 -35.722443)
			(xy 155.548327 -35.762929) (xy 155.622455 -35.810351) (xy 155.691963 -35.864318) (xy 155.705262 -35.876738)
			(xy 160.817304 -35.876738) (xy 160.821375 -35.821116) (xy 160.833501 -35.766679) (xy 160.853424 -35.714588)
			(xy 160.88072 -35.665953) (xy 160.914806 -35.62181) (xy 160.954955 -35.583101) (xy 161.000313 -35.55065)
			(xy 161.049913 -35.525149) (xy 161.102697 -35.507142) (xy 161.15754 -35.497012) (xy 161.213274 -35.494975)
			(xy 161.268711 -35.501075) (xy 161.322668 -35.515181) (xy 161.373997 -35.536993) (xy 161.421603 -35.566047)
			(xy 161.464471 -35.601722) (xy 161.501688 -35.643259) (xy 161.532461 -35.689772) (xy 161.556133 -35.740269)
			(xy 161.572201 -35.793676) (xy 161.580321 -35.848852) (xy 161.58083 -35.876738) (xy 161.580321 -35.904624)
			(xy 161.572201 -35.9598) (xy 161.556133 -36.013207) (xy 161.532461 -36.063704) (xy 161.501688 -36.110217)
			(xy 161.464471 -36.151754) (xy 161.421603 -36.187429) (xy 161.373997 -36.216483) (xy 161.322668 -36.238295)
			(xy 161.268711 -36.252401) (xy 161.213274 -36.258501) (xy 161.15754 -36.256464) (xy 161.102697 -36.246334)
			(xy 161.049913 -36.228327) (xy 161.000313 -36.202826) (xy 160.954955 -36.170375) (xy 160.914806 -36.131666)
			(xy 160.88072 -36.087523) (xy 160.853424 -36.038888) (xy 160.833501 -35.986797) (xy 160.821375 -35.93236)
			(xy 160.817304 -35.876738) (xy 155.705262 -35.876738) (xy 155.756277 -35.924383) (xy 155.814861 -35.990047)
			(xy 155.867232 -36.060766) (xy 155.912955 -36.135954) (xy 155.951652 -36.214989) (xy 155.983001 -36.297215)
			(xy 156.006743 -36.381951) (xy 156.022681 -36.468495) (xy 156.026467 -36.50996) (xy 162.713922 -36.50996)
			(xy 162.717993 -36.454338) (xy 162.730119 -36.399901) (xy 162.750042 -36.34781) (xy 162.777338 -36.299175)
			(xy 162.811424 -36.255032) (xy 162.851573 -36.216323) (xy 162.896931 -36.183872) (xy 162.946531 -36.158371)
			(xy 162.999315 -36.140364) (xy 163.054158 -36.130234) (xy 163.109892 -36.128197) (xy 163.165329 -36.134297)
			(xy 163.219286 -36.148403) (xy 163.270615 -36.170215) (xy 163.318221 -36.199269) (xy 163.361089 -36.234944)
			(xy 163.398306 -36.276481) (xy 163.429079 -36.322994) (xy 163.452751 -36.373491) (xy 163.468819 -36.426898)
			(xy 163.476939 -36.482074) (xy 163.477448 -36.50996) (xy 163.476939 -36.537846) (xy 163.468819 -36.593022)
			(xy 163.452751 -36.646429) (xy 163.429079 -36.696926) (xy 163.398306 -36.743439) (xy 163.361089 -36.784976)
			(xy 163.318221 -36.820651) (xy 163.270615 -36.849705) (xy 163.219286 -36.871517) (xy 163.165329 -36.885623)
			(xy 163.109892 -36.891723) (xy 163.054158 -36.889686) (xy 162.999315 -36.879556) (xy 162.946531 -36.861549)
			(xy 162.896931 -36.836048) (xy 162.851573 -36.803597) (xy 162.811424 -36.764888) (xy 162.777338 -36.720745)
			(xy 162.750042 -36.67211) (xy 162.730119 -36.620019) (xy 162.717993 -36.565582) (xy 162.713922 -36.50996)
			(xy 156.026467 -36.50996) (xy 156.030683 -36.55613) (xy 156.031184 -36.60013) (xy 156.030683 -36.64413)
			(xy 156.022681 -36.731765) (xy 156.006743 -36.818309) (xy 155.983001 -36.903045) (xy 155.951652 -36.985271)
			(xy 155.912955 -37.064306) (xy 155.867232 -37.139494) (xy 155.814861 -37.210213) (xy 155.756277 -37.275877)
			(xy 155.691963 -37.335942) (xy 155.622455 -37.389909) (xy 155.548327 -37.437331) (xy 155.475321 -37.47516)
			(xy 159.859216 -37.47516) (xy 159.863287 -37.419538) (xy 159.875413 -37.365101) (xy 159.895336 -37.31301)
			(xy 159.922632 -37.264375) (xy 159.956718 -37.220232) (xy 159.996867 -37.181523) (xy 160.042225 -37.149072)
			(xy 160.091825 -37.123571) (xy 160.144609 -37.105564) (xy 160.199452 -37.095434) (xy 160.255186 -37.093397)
			(xy 160.310623 -37.099497) (xy 160.36458 -37.113603) (xy 160.415909 -37.135415) (xy 160.463515 -37.164469)
			(xy 160.506383 -37.200144) (xy 160.5436 -37.241681) (xy 160.574373 -37.288194) (xy 160.598045 -37.338691)
			(xy 160.614113 -37.392098) (xy 160.622233 -37.447274) (xy 160.622742 -37.47516) (xy 160.622233 -37.503046)
			(xy 160.614113 -37.558222) (xy 160.598045 -37.611629) (xy 160.574373 -37.662126) (xy 160.57422 -37.662358)
			(xy 162.048442 -37.662358) (xy 162.052513 -37.606736) (xy 162.064639 -37.552299) (xy 162.084562 -37.500208)
			(xy 162.111858 -37.451573) (xy 162.145944 -37.40743) (xy 162.186093 -37.368721) (xy 162.231451 -37.33627)
			(xy 162.281051 -37.310769) (xy 162.333835 -37.292762) (xy 162.388678 -37.282632) (xy 162.444412 -37.280595)
			(xy 162.499849 -37.286695) (xy 162.553806 -37.300801) (xy 162.605135 -37.322613) (xy 162.652741 -37.351667)
			(xy 162.695609 -37.387342) (xy 162.732826 -37.428879) (xy 162.763599 -37.475392) (xy 162.787271 -37.525889)
			(xy 162.803339 -37.579296) (xy 162.811459 -37.634472) (xy 162.811968 -37.662358) (xy 162.811459 -37.690244)
			(xy 162.803339 -37.74542) (xy 162.787271 -37.798827) (xy 162.763599 -37.849324) (xy 162.732826 -37.895837)
			(xy 162.695609 -37.937374) (xy 162.652741 -37.973049) (xy 162.605135 -38.002103) (xy 162.553806 -38.023915)
			(xy 162.499849 -38.038021) (xy 162.444412 -38.044121) (xy 162.388678 -38.042084) (xy 162.333835 -38.031954)
			(xy 162.281051 -38.013947) (xy 162.231451 -37.988446) (xy 162.186093 -37.955995) (xy 162.145944 -37.917286)
			(xy 162.111858 -37.873143) (xy 162.084562 -37.824508) (xy 162.064639 -37.772417) (xy 162.052513 -37.71798)
			(xy 162.048442 -37.662358) (xy 160.57422 -37.662358) (xy 160.5436 -37.708639) (xy 160.506383 -37.750176)
			(xy 160.463515 -37.785851) (xy 160.415909 -37.814905) (xy 160.36458 -37.836717) (xy 160.310623 -37.850823)
			(xy 160.255186 -37.856923) (xy 160.199452 -37.854886) (xy 160.144609 -37.844756) (xy 160.091825 -37.826749)
			(xy 160.042225 -37.801248) (xy 159.996867 -37.768797) (xy 159.956718 -37.730088) (xy 159.922632 -37.685945)
			(xy 159.895336 -37.63731) (xy 159.875413 -37.585219) (xy 159.863287 -37.530782) (xy 159.859216 -37.47516)
			(xy 155.475321 -37.47516) (xy 155.470193 -37.477817) (xy 155.388702 -37.51103) (xy 155.304528 -37.536694)
			(xy 155.218369 -37.554598) (xy 155.130939 -37.564593) (xy 155.042962 -37.566597) (xy 154.955168 -37.560591)
			(xy 154.868284 -37.546627) (xy 154.783029 -37.52482) (xy 154.70011 -37.495351) (xy 154.620215 -37.458464)
			(xy 154.544006 -37.414464) (xy 154.472113 -37.363716) (xy 154.405132 -37.306642) (xy 154.34362 -37.243712)
			(xy 154.288084 -37.17545) (xy 154.238986 -37.102421) (xy 154.196733 -37.025229) (xy 154.161674 -36.944515)
			(xy 154.134099 -36.860947) (xy 154.114239 -36.775218) (xy 154.102256 -36.688038) (xy 154.098251 -36.60013)
			(xy 149.868694 -36.60013) (xy 149.853083 -36.652017) (xy 149.829411 -36.702514) (xy 149.798638 -36.749027)
			(xy 149.761421 -36.790564) (xy 149.718553 -36.826239) (xy 149.670947 -36.855293) (xy 149.619618 -36.877105)
			(xy 149.565661 -36.891211) (xy 149.510224 -36.897311) (xy 149.45449 -36.895274) (xy 149.399647 -36.885144)
			(xy 149.346863 -36.867137) (xy 149.297263 -36.841636) (xy 149.251905 -36.809185) (xy 149.211756 -36.770476)
			(xy 149.17767 -36.726333) (xy 149.150374 -36.677698) (xy 149.130451 -36.625607) (xy 149.118325 -36.57117)
			(xy 149.114254 -36.515548) (xy 147.988052 -36.515548) (xy 147.984824 -36.520427) (xy 147.947607 -36.561964)
			(xy 147.904739 -36.597639) (xy 147.857133 -36.626693) (xy 147.805804 -36.648505) (xy 147.751847 -36.662611)
			(xy 147.69641 -36.668711) (xy 147.640676 -36.666674) (xy 147.585833 -36.656544) (xy 147.533049 -36.638537)
			(xy 147.483449 -36.613036) (xy 147.438091 -36.580585) (xy 147.397942 -36.541876) (xy 147.363856 -36.497733)
			(xy 147.33656 -36.449098) (xy 147.316637 -36.397007) (xy 147.304511 -36.34257) (xy 147.30044 -36.286948)
			(xy 146.834473 -36.286948) (xy 147.726654 -37.41293) (xy 147.732159 -37.419365) (xy 147.74643 -37.428463)
			(xy 147.754594 -37.43071) (xy 147.762976 -37.432742) (xy 147.77974 -37.430964) (xy 147.787614 -37.427408)
			(xy 147.812707 -37.41641) (xy 147.865255 -37.40091) (xy 147.919479 -37.393085) (xy 147.946872 -37.39261)
			(xy 147.974126 -37.393071) (xy 148.028079 -37.400825) (xy 148.080379 -37.416179) (xy 148.129961 -37.43882)
			(xy 148.175817 -37.468288) (xy 148.217011 -37.503982) (xy 148.252706 -37.545175) (xy 148.282175 -37.59103)
			(xy 148.304817 -37.640612) (xy 148.320173 -37.692912) (xy 148.327928 -37.746864) (xy 148.32838 -37.774118)
			(xy 148.327973 -37.799339) (xy 148.321328 -37.849342) (xy 148.308156 -37.898034) (xy 148.288686 -37.944568)
			(xy 148.263258 -37.988132) (xy 148.248116 -38.008306) (xy 148.247862 -38.00856) (xy 148.243026 -38.015514)
			(xy 148.237721 -38.031589) (xy 148.237448 -38.040056) (xy 148.237448 -38.048184) (xy 148.243036 -38.063932)
			(xy 150.783128 -41.268751) (xy 157.28365 -41.268751) (xy 157.28365 -41.214249) (xy 157.291406 -41.160301)
			(xy 157.30676 -41.108005) (xy 157.3294 -41.058427) (xy 157.358864 -41.012576) (xy 157.394554 -40.971383)
			(xy 157.435742 -40.935689) (xy 157.48159 -40.90622) (xy 157.531166 -40.883575) (xy 157.58346 -40.868215)
			(xy 157.637407 -40.860453) (xy 157.664658 -40.859964) (xy 157.693398 -40.860462) (xy 157.750226 -40.869092)
			(xy 157.805116 -40.886149) (xy 157.856828 -40.911246) (xy 157.90419 -40.943815) (xy 157.925516 -40.963088)
			(xy 157.932374 -40.969692) (xy 157.950408 -40.976804) (xy 158.039308 -40.976804) (xy 158.057342 -40.969692)
			(xy 158.0642 -40.963088) (xy 158.085527 -40.943818) (xy 158.13289 -40.911253) (xy 158.184601 -40.886162)
			(xy 158.239492 -40.869112) (xy 158.296319 -40.86049) (xy 158.353797 -40.86049) (xy 158.410624 -40.869112)
			(xy 158.465515 -40.886162) (xy 158.517226 -40.911253) (xy 158.564589 -40.943818) (xy 158.585916 -40.963088)
			(xy 158.592774 -40.969692) (xy 158.610808 -40.976804) (xy 158.699708 -40.976804) (xy 158.717742 -40.969692)
			(xy 158.7246 -40.963088) (xy 158.745911 -40.943798) (xy 158.793276 -40.911233) (xy 158.844992 -40.886143)
			(xy 158.899887 -40.869097) (xy 158.956718 -40.860481) (xy 158.985458 -40.859964) (xy 159.012711 -40.86048)
			(xy 159.066662 -40.868232) (xy 159.118961 -40.883583) (xy 159.168543 -40.906222) (xy 159.214398 -40.935686)
			(xy 159.255593 -40.971377) (xy 159.291288 -41.012568) (xy 159.320758 -41.05842) (xy 159.343402 -41.107999)
			(xy 159.358759 -41.160297) (xy 159.366517 -41.214247) (xy 159.366517 -41.268753) (xy 159.358759 -41.322703)
			(xy 159.343402 -41.375001) (xy 159.320758 -41.42458) (xy 159.291288 -41.470432) (xy 159.255593 -41.511623)
			(xy 159.214398 -41.547314) (xy 159.168543 -41.576778) (xy 159.118961 -41.599417) (xy 159.066662 -41.614768)
			(xy 159.012711 -41.62252) (xy 158.985458 -41.62298) (xy 158.956719 -41.62246) (xy 158.899893 -41.613834)
			(xy 158.845003 -41.596781) (xy 158.793291 -41.571689) (xy 158.745928 -41.539126) (xy 158.7246 -41.519856)
			(xy 158.717742 -41.513252) (xy 158.699708 -41.50614) (xy 158.610808 -41.50614) (xy 158.592774 -41.513252)
			(xy 158.585916 -41.519856) (xy 158.564589 -41.539126) (xy 158.517226 -41.571691) (xy 158.465515 -41.596782)
			(xy 158.410624 -41.613832) (xy 158.353797 -41.622454) (xy 158.296319 -41.622454) (xy 158.239492 -41.613832)
			(xy 158.184601 -41.596782) (xy 158.13289 -41.571691) (xy 158.085527 -41.539126) (xy 158.0642 -41.519856)
			(xy 158.057342 -41.513252) (xy 158.039308 -41.50614) (xy 157.950408 -41.50614) (xy 157.932374 -41.513252)
			(xy 157.925516 -41.519856) (xy 157.904205 -41.539146) (xy 157.856839 -41.57171) (xy 157.805123 -41.596799)
			(xy 157.750229 -41.613845) (xy 157.693398 -41.622462) (xy 157.664658 -41.62298) (xy 157.637407 -41.622547)
			(xy 157.58346 -41.614785) (xy 157.531166 -41.599425) (xy 157.48159 -41.57678) (xy 157.435742 -41.547311)
			(xy 157.394554 -41.511617) (xy 157.358864 -41.470424) (xy 157.3294 -41.424573) (xy 157.30676 -41.374995)
			(xy 157.291406 -41.322699) (xy 157.28365 -41.268751) (xy 150.783128 -41.268751) (xy 152.397204 -43.305222)
			(xy 160.40735 -43.305222) (xy 160.407817 -43.277852) (xy 160.415633 -43.223672) (xy 160.431121 -43.171169)
			(xy 160.453963 -43.121422) (xy 160.483688 -43.075455) (xy 160.50133 -43.054524) (xy 160.501584 -43.05427)
			(xy 160.507146 -43.047166) (xy 160.513408 -43.030263) (xy 160.513776 -43.02125) (xy 160.513776 -42.954194)
			(xy 160.513427 -42.945176) (xy 160.507175 -42.928259) (xy 160.501584 -42.921174) (xy 160.50133 -42.921174)
			(xy 160.50133 -42.92092) (xy 160.483691 -42.899987) (xy 160.453979 -42.854015) (xy 160.431142 -42.804268)
			(xy 160.415651 -42.751767) (xy 160.407823 -42.697591) (xy 160.40735 -42.670222) (xy 160.4079 -42.641484)
			(xy 160.416519 -42.584659) (xy 160.433563 -42.529769) (xy 160.458648 -42.478057) (xy 160.491207 -42.430692)
			(xy 160.510474 -42.409364) (xy 160.517078 -42.402506) (xy 160.52419 -42.384472) (xy 160.52419 -42.295572)
			(xy 160.517078 -42.277538) (xy 160.510474 -42.27068) (xy 160.491227 -42.249333) (xy 160.458665 -42.201973)
			(xy 160.433576 -42.150264) (xy 160.416527 -42.095377) (xy 160.407903 -42.038553) (xy 160.407901 -41.981079)
			(xy 160.41652 -41.924255) (xy 160.433564 -41.869366) (xy 160.458649 -41.817655) (xy 160.491207 -41.770292)
			(xy 160.510474 -41.748964) (xy 160.517078 -41.742106) (xy 160.52419 -41.724072) (xy 160.52419 -41.635172)
			(xy 160.517078 -41.617138) (xy 160.510474 -41.61028) (xy 160.49122 -41.588939) (xy 160.45865 -41.541581)
			(xy 160.433554 -41.489873) (xy 160.416499 -41.434985) (xy 160.407873 -41.37816) (xy 160.40735 -41.349422)
			(xy 160.407836 -41.322171) (xy 160.415592 -41.268223) (xy 160.430947 -41.215928) (xy 160.453589 -41.166351)
			(xy 160.483055 -41.120501) (xy 160.518746 -41.07931) (xy 160.559937 -41.043619) (xy 160.605787 -41.014153)
			(xy 160.655364 -40.991511) (xy 160.707659 -40.976156) (xy 160.761607 -40.9684) (xy 160.816109 -40.9684)
			(xy 160.870057 -40.976156) (xy 160.922352 -40.991511) (xy 160.971929 -41.014153) (xy 161.017779 -41.043619)
			(xy 161.05897 -41.07931) (xy 161.094661 -41.120501) (xy 161.124127 -41.166351) (xy 161.146769 -41.215928)
			(xy 161.162124 -41.268223) (xy 161.16988 -41.322171) (xy 161.170366 -41.349422) (xy 161.169838 -41.378161)
			(xy 161.161214 -41.434987) (xy 161.144164 -41.489877) (xy 161.119074 -41.541589) (xy 161.086511 -41.588952)
			(xy 161.067242 -41.61028) (xy 161.060638 -41.617138) (xy 161.053526 -41.635172) (xy 161.053526 -41.724072)
			(xy 161.060638 -41.742106) (xy 161.067242 -41.748964) (xy 161.086536 -41.770271) (xy 161.119103 -41.817636)
			(xy 161.144196 -41.869351) (xy 161.161246 -41.924245) (xy 161.169868 -41.981076) (xy 161.169865 -42.038557)
			(xy 161.161239 -42.095387) (xy 161.144184 -42.150279) (xy 161.119087 -42.201992) (xy 161.086516 -42.249354)
			(xy 161.067242 -42.27068) (xy 161.060638 -42.277538) (xy 161.053526 -42.295572) (xy 161.053526 -42.384472)
			(xy 161.060638 -42.402506) (xy 161.067242 -42.409364) (xy 161.08652 -42.430685) (xy 161.119086 -42.478048)
			(xy 161.144177 -42.529761) (xy 161.161226 -42.584654) (xy 161.169847 -42.641483) (xy 161.170366 -42.670222)
			(xy 161.169921 -42.697593) (xy 161.162099 -42.751773) (xy 161.146606 -42.804277) (xy 161.126049 -42.849038)
			(xy 162.992052 -42.849038) (xy 162.996123 -42.793416) (xy 163.008249 -42.738979) (xy 163.028172 -42.686888)
			(xy 163.055468 -42.638253) (xy 163.089554 -42.59411) (xy 163.129703 -42.555401) (xy 163.175061 -42.52295)
			(xy 163.224661 -42.497449) (xy 163.277445 -42.479442) (xy 163.332288 -42.469312) (xy 163.388022 -42.467275)
			(xy 163.443459 -42.473375) (xy 163.497416 -42.487481) (xy 163.548745 -42.509293) (xy 163.596351 -42.538347)
			(xy 163.639219 -42.574022) (xy 163.676436 -42.615559) (xy 163.707209 -42.662072) (xy 163.730881 -42.712569)
			(xy 163.746949 -42.765976) (xy 163.755069 -42.821152) (xy 163.755578 -42.849038) (xy 163.755069 -42.876924)
			(xy 163.746949 -42.9321) (xy 163.730881 -42.985507) (xy 163.707209 -43.036004) (xy 163.676436 -43.082517)
			(xy 163.639219 -43.124054) (xy 163.596351 -43.159729) (xy 163.548745 -43.188783) (xy 163.497416 -43.210595)
			(xy 163.443459 -43.224701) (xy 163.388022 -43.230801) (xy 163.332288 -43.228764) (xy 163.277445 -43.218634)
			(xy 163.224661 -43.200627) (xy 163.175061 -43.175126) (xy 163.129703 -43.142675) (xy 163.089554 -43.103966)
			(xy 163.055468 -43.059823) (xy 163.028172 -43.011188) (xy 163.008249 -42.959097) (xy 162.996123 -42.90466)
			(xy 162.992052 -42.849038) (xy 161.126049 -42.849038) (xy 161.123759 -42.854024) (xy 161.09403 -42.899989)
			(xy 161.076386 -42.92092) (xy 161.076132 -42.921174) (xy 161.070542 -42.928258) (xy 161.064299 -42.945177)
			(xy 161.06394 -42.954194) (xy 161.06394 -43.02125) (xy 161.064312 -43.030266) (xy 161.070548 -43.047183)
			(xy 161.076132 -43.05427) (xy 161.076386 -43.05427) (xy 161.076386 -43.054524) (xy 161.094001 -43.075476)
			(xy 161.123717 -43.121443) (xy 161.146558 -43.171185) (xy 161.162054 -43.223682) (xy 161.169889 -43.277854)
			(xy 161.170366 -43.305222) (xy 161.16988 -43.332473) (xy 161.162124 -43.386421) (xy 161.146769 -43.438716)
			(xy 161.124127 -43.488293) (xy 161.094661 -43.534143) (xy 161.05897 -43.575334) (xy 161.017779 -43.611025)
			(xy 160.971929 -43.640491) (xy 160.922352 -43.663133) (xy 160.870057 -43.678488) (xy 160.816109 -43.686244)
			(xy 160.761607 -43.686244) (xy 160.707659 -43.678488) (xy 160.655364 -43.663133) (xy 160.605787 -43.640491)
			(xy 160.559937 -43.611025) (xy 160.518746 -43.575334) (xy 160.483055 -43.534143) (xy 160.453589 -43.488293)
			(xy 160.430947 -43.438716) (xy 160.415592 -43.386421) (xy 160.407836 -43.332473) (xy 160.40735 -43.305222)
			(xy 152.397204 -43.305222) (xy 152.738839 -43.73626) (xy 162.31311 -43.73626) (xy 162.317181 -43.680638)
			(xy 162.329307 -43.626201) (xy 162.34923 -43.57411) (xy 162.376526 -43.525475) (xy 162.410612 -43.481332)
			(xy 162.450761 -43.442623) (xy 162.496119 -43.410172) (xy 162.545719 -43.384671) (xy 162.598503 -43.366664)
			(xy 162.653346 -43.356534) (xy 162.70908 -43.354497) (xy 162.764517 -43.360597) (xy 162.818474 -43.374703)
			(xy 162.869803 -43.396515) (xy 162.917409 -43.425569) (xy 162.960277 -43.461244) (xy 162.997494 -43.502781)
			(xy 163.028267 -43.549294) (xy 163.051939 -43.599791) (xy 163.068007 -43.653198) (xy 163.076127 -43.708374)
			(xy 163.076636 -43.73626) (xy 163.076127 -43.764146) (xy 163.068007 -43.819322) (xy 163.056698 -43.85691)
			(xy 166.819832 -43.85691) (xy 166.823903 -43.801288) (xy 166.836029 -43.746851) (xy 166.855952 -43.69476)
			(xy 166.883248 -43.646125) (xy 166.917334 -43.601982) (xy 166.957483 -43.563273) (xy 167.002841 -43.530822)
			(xy 167.052441 -43.505321) (xy 167.105225 -43.487314) (xy 167.160068 -43.477184) (xy 167.215802 -43.475147)
			(xy 167.271239 -43.481247) (xy 167.325196 -43.495353) (xy 167.376525 -43.517165) (xy 167.424131 -43.546219)
			(xy 167.466999 -43.581894) (xy 167.504216 -43.623431) (xy 167.534989 -43.669944) (xy 167.558661 -43.720441)
			(xy 167.574729 -43.773848) (xy 167.582849 -43.829024) (xy 167.583358 -43.85691) (xy 167.582849 -43.884796)
			(xy 167.574729 -43.939972) (xy 167.558661 -43.993379) (xy 167.534989 -44.043876) (xy 167.504216 -44.090389)
			(xy 167.466999 -44.131926) (xy 167.424131 -44.167601) (xy 167.376525 -44.196655) (xy 167.325196 -44.218467)
			(xy 167.271239 -44.232573) (xy 167.215802 -44.238673) (xy 167.160068 -44.236636) (xy 167.105225 -44.226506)
			(xy 167.052441 -44.208499) (xy 167.002841 -44.182998) (xy 166.957483 -44.150547) (xy 166.917334 -44.111838)
			(xy 166.883248 -44.067695) (xy 166.855952 -44.01906) (xy 166.836029 -43.966969) (xy 166.823903 -43.912532)
			(xy 166.819832 -43.85691) (xy 163.056698 -43.85691) (xy 163.051939 -43.872729) (xy 163.028267 -43.923226)
			(xy 162.997494 -43.969739) (xy 162.960277 -44.011276) (xy 162.917409 -44.046951) (xy 162.869803 -44.076005)
			(xy 162.818474 -44.097817) (xy 162.764517 -44.111923) (xy 162.70908 -44.118023) (xy 162.653346 -44.115986)
			(xy 162.598503 -44.105856) (xy 162.545719 -44.087849) (xy 162.496119 -44.062348) (xy 162.450761 -44.029897)
			(xy 162.410612 -43.991188) (xy 162.376526 -43.947045) (xy 162.34923 -43.89841) (xy 162.329307 -43.846319)
			(xy 162.317181 -43.791882) (xy 162.31311 -43.73626) (xy 152.738839 -43.73626) (xy 152.809702 -43.825668)
			(xy 152.8391 -43.863719) (xy 152.891264 -43.944504) (xy 152.913842 -43.986958) (xy 152.91435 -43.98772)
			(xy 152.914604 -43.988482) (xy 153.2128 -44.536868) (xy 153.526947 -45.114464) (xy 162.165536 -45.114464)
			(xy 162.169607 -45.058842) (xy 162.181733 -45.004405) (xy 162.201656 -44.952314) (xy 162.228952 -44.903679)
			(xy 162.263038 -44.859536) (xy 162.303187 -44.820827) (xy 162.348545 -44.788376) (xy 162.398145 -44.762875)
			(xy 162.450929 -44.744868) (xy 162.505772 -44.734738) (xy 162.561506 -44.732701) (xy 162.616943 -44.738801)
			(xy 162.6709 -44.752907) (xy 162.722229 -44.774719) (xy 162.769835 -44.803773) (xy 162.812703 -44.839448)
			(xy 162.842685 -44.87291) (xy 169.033188 -44.87291) (xy 169.037259 -44.817288) (xy 169.049385 -44.762851)
			(xy 169.069308 -44.71076) (xy 169.096604 -44.662125) (xy 169.13069 -44.617982) (xy 169.170839 -44.579273)
			(xy 169.216197 -44.546822) (xy 169.265797 -44.521321) (xy 169.318581 -44.503314) (xy 169.373424 -44.493184)
			(xy 169.429158 -44.491147) (xy 169.484595 -44.497247) (xy 169.538552 -44.511353) (xy 169.589881 -44.533165)
			(xy 169.637487 -44.562219) (xy 169.680355 -44.597894) (xy 169.717572 -44.639431) (xy 169.748345 -44.685944)
			(xy 169.772017 -44.736441) (xy 169.788085 -44.789848) (xy 169.796205 -44.845024) (xy 169.796714 -44.87291)
			(xy 169.796205 -44.900796) (xy 169.788085 -44.955972) (xy 169.772017 -45.009379) (xy 169.748345 -45.059876)
			(xy 169.717572 -45.106389) (xy 169.680355 -45.147926) (xy 169.637487 -45.183601) (xy 169.589881 -45.212655)
			(xy 169.538552 -45.234467) (xy 169.484595 -45.248573) (xy 169.429158 -45.254673) (xy 169.373424 -45.252636)
			(xy 169.318581 -45.242506) (xy 169.265797 -45.224499) (xy 169.216197 -45.198998) (xy 169.170839 -45.166547)
			(xy 169.13069 -45.127838) (xy 169.096604 -45.083695) (xy 169.069308 -45.03506) (xy 169.049385 -44.982969)
			(xy 169.037259 -44.928532) (xy 169.033188 -44.87291) (xy 162.842685 -44.87291) (xy 162.84992 -44.880985)
			(xy 162.880693 -44.927498) (xy 162.904365 -44.977995) (xy 162.920433 -45.031402) (xy 162.928553 -45.086578)
			(xy 162.929062 -45.114464) (xy 162.928553 -45.14235) (xy 162.920433 -45.197526) (xy 162.904365 -45.250933)
			(xy 162.880693 -45.30143) (xy 162.84992 -45.347943) (xy 162.844278 -45.35424) (xy 166.80383 -45.35424)
			(xy 166.807901 -45.298618) (xy 166.820027 -45.244181) (xy 166.83995 -45.19209) (xy 166.867246 -45.143455)
			(xy 166.901332 -45.099312) (xy 166.941481 -45.060603) (xy 166.986839 -45.028152) (xy 167.036439 -45.002651)
			(xy 167.089223 -44.984644) (xy 167.144066 -44.974514) (xy 167.1998 -44.972477) (xy 167.255237 -44.978577)
			(xy 167.309194 -44.992683) (xy 167.360523 -45.014495) (xy 167.408129 -45.043549) (xy 167.450997 -45.079224)
			(xy 167.488214 -45.120761) (xy 167.518987 -45.167274) (xy 167.542659 -45.217771) (xy 167.558727 -45.271178)
			(xy 167.566847 -45.326354) (xy 167.567356 -45.35424) (xy 167.566847 -45.382126) (xy 167.558727 -45.437302)
			(xy 167.542659 -45.490709) (xy 167.518987 -45.541206) (xy 167.488214 -45.587719) (xy 167.450997 -45.629256)
			(xy 167.408129 -45.664931) (xy 167.360523 -45.693985) (xy 167.309194 -45.715797) (xy 167.255237 -45.729903)
			(xy 167.1998 -45.736003) (xy 167.144066 -45.733966) (xy 167.089223 -45.723836) (xy 167.036439 -45.705829)
			(xy 166.986839 -45.680328) (xy 166.941481 -45.647877) (xy 166.901332 -45.609168) (xy 166.867246 -45.565025)
			(xy 166.83995 -45.51639) (xy 166.820027 -45.464299) (xy 166.807901 -45.409862) (xy 166.80383 -45.35424)
			(xy 162.844278 -45.35424) (xy 162.812703 -45.38948) (xy 162.769835 -45.425155) (xy 162.722229 -45.454209)
			(xy 162.6709 -45.476021) (xy 162.616943 -45.490127) (xy 162.561506 -45.496227) (xy 162.505772 -45.49419)
			(xy 162.450929 -45.48406) (xy 162.398145 -45.466053) (xy 162.348545 -45.440552) (xy 162.303187 -45.408101)
			(xy 162.263038 -45.369392) (xy 162.228952 -45.325249) (xy 162.201656 -45.276614) (xy 162.181733 -45.224523)
			(xy 162.169607 -45.170086) (xy 162.165536 -45.114464) (xy 153.526947 -45.114464) (xy 153.829766 -45.671232)
			(xy 153.833068 -45.676058) (xy 154.205679 -46.082204) (xy 160.152588 -46.082204) (xy 160.153081 -46.054953)
			(xy 160.160837 -46.001006) (xy 160.176192 -45.948711) (xy 160.198832 -45.899134) (xy 160.228298 -45.853284)
			(xy 160.263988 -45.812094) (xy 160.305178 -45.776402) (xy 160.351027 -45.746936) (xy 160.400604 -45.724295)
			(xy 160.452898 -45.708939) (xy 160.506845 -45.701182) (xy 160.534096 -45.700696) (xy 160.560998 -45.701161)
			(xy 160.614268 -45.708733) (xy 160.665947 -45.723711) (xy 160.715008 -45.745801) (xy 160.760481 -45.774563)
			(xy 160.801462 -45.809427) (xy 160.83714 -45.849702) (xy 160.852358 -45.871892) (xy 160.85947 -45.882814)
			(xy 160.88233 -45.894752) (xy 160.994598 -45.89272) (xy 161.01695 -45.879766) (xy 161.023808 -45.86859)
			(xy 161.038738 -45.844994) (xy 161.074415 -45.802042) (xy 161.115972 -45.764749) (xy 161.162521 -45.733911)
			(xy 161.213067 -45.710187) (xy 161.266531 -45.694083) (xy 161.321772 -45.685943) (xy 161.34969 -45.685456)
			(xy 161.376683 -45.685923) (xy 161.430131 -45.693527) (xy 161.481974 -45.708586) (xy 161.531179 -45.730799)
			(xy 161.576763 -45.759722) (xy 161.597594 -45.776896) (xy 161.605722 -45.784008) (xy 161.626296 -45.790104)
			(xy 161.71164 -45.779182) (xy 161.72218 -45.777388) (xy 161.740465 -45.766348) (xy 161.746946 -45.757846)
			(xy 161.762277 -45.736599) (xy 161.797868 -45.698146) (xy 161.838389 -45.664929) (xy 161.883076 -45.637572)
			(xy 161.931087 -45.616592) (xy 161.98152 -45.602382) (xy 162.033422 -45.595211) (xy 162.05962 -45.594778)
			(xy 162.086869 -45.595294) (xy 162.140813 -45.603052) (xy 162.193103 -45.618408) (xy 162.242676 -45.64105)
			(xy 162.288522 -45.670516) (xy 162.329708 -45.706206) (xy 162.365396 -45.747394) (xy 162.39486 -45.793242)
			(xy 162.417499 -45.842816) (xy 162.432852 -45.895107) (xy 162.440608 -45.949051) (xy 162.440608 -46.003549)
			(xy 162.432852 -46.057493) (xy 162.417499 -46.109784) (xy 162.39486 -46.159358) (xy 162.365396 -46.205206)
			(xy 162.329708 -46.246394) (xy 162.288522 -46.282084) (xy 162.242676 -46.31155) (xy 162.193103 -46.334192)
			(xy 162.140813 -46.349548) (xy 162.086869 -46.357306) (xy 162.05962 -46.357794) (xy 162.032628 -46.357309)
			(xy 161.979181 -46.349707) (xy 161.927338 -46.334652) (xy 161.878133 -46.312444) (xy 161.832548 -46.283525)
			(xy 161.811716 -46.266354) (xy 161.803588 -46.259242) (xy 161.783014 -46.253146) (xy 161.69767 -46.264068)
			(xy 161.687124 -46.265835) (xy 161.668843 -46.276896) (xy 161.662364 -46.285404) (xy 161.644753 -46.309706)
			(xy 161.603156 -46.352964) (xy 161.57956 -46.37151) (xy 161.571686 -46.377352) (xy 161.561272 -46.394878)
			(xy 161.548064 -46.485302) (xy 161.55289 -46.504606) (xy 161.558732 -46.51248) (xy 161.558732 -46.512734)
			(xy 161.57623 -46.537482) (xy 161.604035 -46.591333) (xy 161.622973 -46.648904) (xy 161.630176 -46.693836)
			(xy 166.7764 -46.693836) (xy 166.776886 -46.666585) (xy 166.784642 -46.612637) (xy 166.799997 -46.560342)
			(xy 166.822639 -46.510765) (xy 166.852105 -46.464915) (xy 166.887796 -46.423724) (xy 166.928987 -46.388033)
			(xy 166.974837 -46.358567) (xy 167.024414 -46.335925) (xy 167.076709 -46.32057) (xy 167.130657 -46.312814)
			(xy 167.185159 -46.312814) (xy 167.239107 -46.32057) (xy 167.291402 -46.335925) (xy 167.340979 -46.358567)
			(xy 167.386829 -46.388033) (xy 167.42802 -46.423724) (xy 167.463711 -46.464915) (xy 167.493177 -46.510765)
			(xy 167.515819 -46.560342) (xy 167.531174 -46.612637) (xy 167.53893 -46.666585) (xy 167.539416 -46.693836)
			(xy 167.538941 -46.720263) (xy 167.531632 -46.772611) (xy 167.517159 -46.823446) (xy 167.4958 -46.871793)
			(xy 167.482266 -46.894496) (xy 167.482012 -46.89475) (xy 167.476675 -46.904768) (xy 167.474419 -46.927318)
			(xy 167.477694 -46.938184) (xy 167.503856 -47.01286) (xy 167.508238 -47.023376) (xy 167.524328 -47.039464)
			(xy 167.534844 -47.043848) (xy 167.535098 -47.043848) (xy 167.559618 -47.052888) (xy 167.606069 -47.076837)
			(xy 167.648819 -47.106898) (xy 167.68707 -47.14251) (xy 167.720104 -47.183006) (xy 167.747306 -47.22763)
			(xy 167.768167 -47.275548) (xy 167.782296 -47.325863) (xy 167.789429 -47.377635) (xy 167.78986 -47.403766)
			(xy 167.789374 -47.431017) (xy 167.787851 -47.441612) (xy 169.06189 -47.441612) (xy 169.065961 -47.38599)
			(xy 169.078087 -47.331553) (xy 169.09801 -47.279462) (xy 169.125306 -47.230827) (xy 169.159392 -47.186684)
			(xy 169.199541 -47.147975) (xy 169.244899 -47.115524) (xy 169.294499 -47.090023) (xy 169.347283 -47.072016)
			(xy 169.402126 -47.061886) (xy 169.45786 -47.059849) (xy 169.513297 -47.065949) (xy 169.567254 -47.080055)
			(xy 169.618583 -47.101867) (xy 169.666189 -47.130921) (xy 169.709057 -47.166596) (xy 169.746274 -47.208133)
			(xy 169.777047 -47.254646) (xy 169.800719 -47.305143) (xy 169.816787 -47.35855) (xy 169.824907 -47.413726)
			(xy 169.825416 -47.441612) (xy 169.824907 -47.469498) (xy 169.816787 -47.524674) (xy 169.800719 -47.578081)
			(xy 169.777047 -47.628578) (xy 169.746274 -47.675091) (xy 169.709057 -47.716628) (xy 169.666189 -47.752303)
			(xy 169.618583 -47.781357) (xy 169.567254 -47.803169) (xy 169.513297 -47.817275) (xy 169.45786 -47.823375)
			(xy 169.402126 -47.821338) (xy 169.347283 -47.811208) (xy 169.294499 -47.793201) (xy 169.244899 -47.7677)
			(xy 169.199541 -47.735249) (xy 169.159392 -47.69654) (xy 169.125306 -47.652397) (xy 169.09801 -47.603762)
			(xy 169.078087 -47.551671) (xy 169.065961 -47.497234) (xy 169.06189 -47.441612) (xy 167.787851 -47.441612)
			(xy 167.781618 -47.484965) (xy 167.766263 -47.53726) (xy 167.743621 -47.586837) (xy 167.714155 -47.632687)
			(xy 167.678464 -47.673878) (xy 167.637273 -47.709569) (xy 167.591423 -47.739035) (xy 167.541846 -47.761677)
			(xy 167.489551 -47.777032) (xy 167.435603 -47.784788) (xy 167.381101 -47.784788) (xy 167.327153 -47.777032)
			(xy 167.274858 -47.761677) (xy 167.225281 -47.739035) (xy 167.179431 -47.709569) (xy 167.13824 -47.673878)
			(xy 167.102549 -47.632687) (xy 167.073083 -47.586837) (xy 167.050441 -47.53726) (xy 167.035086 -47.484965)
			(xy 167.02733 -47.431017) (xy 167.026844 -47.403766) (xy 167.027312 -47.377338) (xy 167.034622 -47.32499)
			(xy 167.049096 -47.274155) (xy 167.070458 -47.225809) (xy 167.083994 -47.203106) (xy 167.084248 -47.202852)
			(xy 167.089583 -47.192834) (xy 167.091842 -47.170284) (xy 167.088566 -47.159418) (xy 167.062404 -47.084742)
			(xy 167.058039 -47.074217) (xy 167.041938 -47.058132) (xy 167.031416 -47.053754) (xy 167.031162 -47.053754)
			(xy 167.006656 -47.044678) (xy 166.960203 -47.020737) (xy 166.917451 -46.990682) (xy 166.879199 -46.955076)
			(xy 166.846162 -46.914584) (xy 166.818958 -46.869963) (xy 166.798096 -46.822048) (xy 166.783965 -46.771736)
			(xy 166.776831 -46.719966) (xy 166.7764 -46.693836) (xy 161.630176 -46.693836) (xy 161.632566 -46.708745)
			(xy 161.633154 -46.739048) (xy 161.632667 -46.766298) (xy 161.624905 -46.820244) (xy 161.609546 -46.872536)
			(xy 161.586903 -46.92211) (xy 161.557436 -46.967958) (xy 161.521745 -47.009146) (xy 161.480556 -47.044837)
			(xy 161.434708 -47.074304) (xy 161.385134 -47.096947) (xy 161.332842 -47.112306) (xy 161.278896 -47.120067)
			(xy 161.251646 -47.120556) (xy 161.225612 -47.120132) (xy 161.174028 -47.113038) (xy 161.123886 -47.099003)
			(xy 161.076116 -47.078287) (xy 161.031602 -47.051274) (xy 161.011108 -47.035212) (xy 161.003355 -47.029463)
			(xy 160.984941 -47.023727) (xy 160.975294 -47.024036) (xy 160.895538 -47.030386) (xy 160.877758 -47.039022)
			(xy 160.871408 -47.046388) (xy 160.853246 -47.066052) (xy 160.812334 -47.100573) (xy 160.767001 -47.129039)
			(xy 160.718136 -47.150894) (xy 160.666697 -47.165707) (xy 160.613693 -47.173189) (xy 160.586928 -47.173642)
			(xy 160.559679 -47.173096) (xy 160.505735 -47.165344) (xy 160.453444 -47.149994) (xy 160.403869 -47.127359)
			(xy 160.35802 -47.097899) (xy 160.31683 -47.062213) (xy 160.281139 -47.02103) (xy 160.251671 -46.975185)
			(xy 160.229028 -46.925614) (xy 160.213669 -46.873325) (xy 160.205909 -46.819383) (xy 160.20542 -46.792134)
			(xy 160.205939 -46.76336) (xy 160.214591 -46.706465) (xy 160.231688 -46.651514) (xy 160.256843 -46.599754)
			(xy 160.289485 -46.552359) (xy 160.308798 -46.531022) (xy 160.316164 -46.523148) (xy 160.323276 -46.503336)
			(xy 160.31591 -46.40707) (xy 160.306004 -46.388274) (xy 160.297622 -46.38167) (xy 160.275438 -46.363445)
			(xy 160.236228 -46.32151) (xy 160.203742 -46.274174) (xy 160.178713 -46.222506) (xy 160.161707 -46.167672)
			(xy 160.153106 -46.110909) (xy 160.152588 -46.082204) (xy 154.205679 -46.082204) (xy 154.264868 -46.14672)
			(xy 154.291819 -46.176731) (xy 154.341301 -46.240441) (xy 154.385427 -46.30797) (xy 154.423904 -46.37887)
			(xy 154.456478 -46.45267) (xy 154.4701 -46.490636) (xy 154.81427 -47.481236) (xy 154.816048 -47.485554)
			(xy 154.914854 -47.667418) (xy 154.934926 -47.705317) (xy 154.969262 -47.783913) (xy 154.983434 -47.82439)
			(xy 155.146591 -48.30699) (xy 166.65397 -48.30699) (xy 166.658041 -48.251368) (xy 166.670167 -48.196931)
			(xy 166.69009 -48.14484) (xy 166.717386 -48.096205) (xy 166.751472 -48.052062) (xy 166.791621 -48.013353)
			(xy 166.836979 -47.980902) (xy 166.886579 -47.955401) (xy 166.939363 -47.937394) (xy 166.994206 -47.927264)
			(xy 167.04994 -47.925227) (xy 167.105377 -47.931327) (xy 167.159334 -47.945433) (xy 167.210663 -47.967245)
			(xy 167.258269 -47.996299) (xy 167.301137 -48.031974) (xy 167.338354 -48.073511) (xy 167.369127 -48.120024)
			(xy 167.392799 -48.170521) (xy 167.408867 -48.223928) (xy 167.416987 -48.279104) (xy 167.417496 -48.30699)
			(xy 167.416987 -48.334876) (xy 167.408867 -48.390052) (xy 167.392799 -48.443459) (xy 167.369127 -48.493956)
			(xy 167.338354 -48.540469) (xy 167.301137 -48.582006) (xy 167.258269 -48.617681) (xy 167.210663 -48.646735)
			(xy 167.159334 -48.668547) (xy 167.105377 -48.682653) (xy 167.04994 -48.688753) (xy 166.994206 -48.686716)
			(xy 166.939363 -48.676586) (xy 166.886579 -48.658579) (xy 166.836979 -48.633078) (xy 166.791621 -48.600627)
			(xy 166.751472 -48.561918) (xy 166.717386 -48.517775) (xy 166.69009 -48.46914) (xy 166.670167 -48.417049)
			(xy 166.658041 -48.362612) (xy 166.65397 -48.30699) (xy 155.146591 -48.30699) (xy 155.297382 -48.753014)
			(xy 163.268404 -48.753014) (xy 163.272475 -48.697392) (xy 163.284601 -48.642955) (xy 163.304524 -48.590864)
			(xy 163.33182 -48.542229) (xy 163.365906 -48.498086) (xy 163.406055 -48.459377) (xy 163.451413 -48.426926)
			(xy 163.501013 -48.401425) (xy 163.553797 -48.383418) (xy 163.60864 -48.373288) (xy 163.664374 -48.371251)
			(xy 163.719811 -48.377351) (xy 163.773768 -48.391457) (xy 163.825097 -48.413269) (xy 163.872703 -48.442323)
			(xy 163.915571 -48.477998) (xy 163.952788 -48.519535) (xy 163.983561 -48.566048) (xy 164.007233 -48.616545)
			(xy 164.023301 -48.669952) (xy 164.031421 -48.725128) (xy 164.03193 -48.753014) (xy 164.031421 -48.7809)
			(xy 164.023301 -48.836076) (xy 164.007233 -48.889483) (xy 164.005837 -48.89246) (xy 165.31412 -48.89246)
			(xy 165.318191 -48.836838) (xy 165.330317 -48.782401) (xy 165.35024 -48.73031) (xy 165.377536 -48.681675)
			(xy 165.411622 -48.637532) (xy 165.451771 -48.598823) (xy 165.497129 -48.566372) (xy 165.546729 -48.540871)
			(xy 165.599513 -48.522864) (xy 165.654356 -48.512734) (xy 165.71009 -48.510697) (xy 165.765527 -48.516797)
			(xy 165.819484 -48.530903) (xy 165.870813 -48.552715) (xy 165.918419 -48.581769) (xy 165.961287 -48.617444)
			(xy 165.998504 -48.658981) (xy 166.029277 -48.705494) (xy 166.052949 -48.755991) (xy 166.069017 -48.809398)
			(xy 166.077137 -48.864574) (xy 166.077646 -48.89246) (xy 166.077137 -48.920346) (xy 166.074699 -48.93691)
			(xy 169.033188 -48.93691) (xy 169.037259 -48.881288) (xy 169.049385 -48.826851) (xy 169.069308 -48.77476)
			(xy 169.096604 -48.726125) (xy 169.13069 -48.681982) (xy 169.170839 -48.643273) (xy 169.216197 -48.610822)
			(xy 169.265797 -48.585321) (xy 169.318581 -48.567314) (xy 169.373424 -48.557184) (xy 169.429158 -48.555147)
			(xy 169.484595 -48.561247) (xy 169.538552 -48.575353) (xy 169.589881 -48.597165) (xy 169.637487 -48.626219)
			(xy 169.680355 -48.661894) (xy 169.717572 -48.703431) (xy 169.748345 -48.749944) (xy 169.772017 -48.800441)
			(xy 169.788085 -48.853848) (xy 169.796205 -48.909024) (xy 169.796714 -48.93691) (xy 169.796205 -48.964796)
			(xy 169.788085 -49.019972) (xy 169.772017 -49.073379) (xy 169.748345 -49.123876) (xy 169.717572 -49.170389)
			(xy 169.680355 -49.211926) (xy 169.637487 -49.247601) (xy 169.589881 -49.276655) (xy 169.538552 -49.298467)
			(xy 169.484595 -49.312573) (xy 169.429158 -49.318673) (xy 169.373424 -49.316636) (xy 169.318581 -49.306506)
			(xy 169.265797 -49.288499) (xy 169.216197 -49.262998) (xy 169.170839 -49.230547) (xy 169.13069 -49.191838)
			(xy 169.096604 -49.147695) (xy 169.069308 -49.09906) (xy 169.049385 -49.046969) (xy 169.037259 -48.992532)
			(xy 169.033188 -48.93691) (xy 166.074699 -48.93691) (xy 166.069017 -48.975522) (xy 166.052949 -49.028929)
			(xy 166.029277 -49.079426) (xy 165.998504 -49.125939) (xy 165.961287 -49.167476) (xy 165.918419 -49.203151)
			(xy 165.870813 -49.232205) (xy 165.819484 -49.254017) (xy 165.765527 -49.268123) (xy 165.71009 -49.274223)
			(xy 165.654356 -49.272186) (xy 165.599513 -49.262056) (xy 165.546729 -49.244049) (xy 165.497129 -49.218548)
			(xy 165.451771 -49.186097) (xy 165.411622 -49.147388) (xy 165.377536 -49.103245) (xy 165.35024 -49.05461)
			(xy 165.330317 -49.002519) (xy 165.318191 -48.948082) (xy 165.31412 -48.89246) (xy 164.005837 -48.89246)
			(xy 163.983561 -48.93998) (xy 163.952788 -48.986493) (xy 163.915571 -49.02803) (xy 163.872703 -49.063705)
			(xy 163.825097 -49.092759) (xy 163.773768 -49.114571) (xy 163.719811 -49.128677) (xy 163.664374 -49.134777)
			(xy 163.60864 -49.13274) (xy 163.553797 -49.12261) (xy 163.501013 -49.104603) (xy 163.451413 -49.079102)
			(xy 163.406055 -49.046651) (xy 163.365906 -49.007942) (xy 163.33182 -48.963799) (xy 163.304524 -48.915164)
			(xy 163.284601 -48.863073) (xy 163.272475 -48.808636) (xy 163.268404 -48.753014) (xy 155.297382 -48.753014)
			(xy 155.70304 -49.95291) (xy 169.033188 -49.95291) (xy 169.037259 -49.897288) (xy 169.049385 -49.842851)
			(xy 169.069308 -49.79076) (xy 169.096604 -49.742125) (xy 169.13069 -49.697982) (xy 169.170839 -49.659273)
			(xy 169.216197 -49.626822) (xy 169.265797 -49.601321) (xy 169.318581 -49.583314) (xy 169.373424 -49.573184)
			(xy 169.429158 -49.571147) (xy 169.484595 -49.577247) (xy 169.538552 -49.591353) (xy 169.589881 -49.613165)
			(xy 169.637487 -49.642219) (xy 169.680355 -49.677894) (xy 169.717572 -49.719431) (xy 169.748345 -49.765944)
			(xy 169.772017 -49.816441) (xy 169.788085 -49.869848) (xy 169.796205 -49.925024) (xy 169.796714 -49.95291)
			(xy 169.796205 -49.980796) (xy 169.788085 -50.035972) (xy 169.772017 -50.089379) (xy 169.748345 -50.139876)
			(xy 169.717572 -50.186389) (xy 169.680355 -50.227926) (xy 169.637487 -50.263601) (xy 169.589881 -50.292655)
			(xy 169.538552 -50.314467) (xy 169.484595 -50.328573) (xy 169.429158 -50.334673) (xy 169.373424 -50.332636)
			(xy 169.318581 -50.322506) (xy 169.265797 -50.304499) (xy 169.216197 -50.278998) (xy 169.170839 -50.246547)
			(xy 169.13069 -50.207838) (xy 169.096604 -50.163695) (xy 169.069308 -50.11506) (xy 169.049385 -50.062969)
			(xy 169.037259 -50.008532) (xy 169.033188 -49.95291) (xy 155.70304 -49.95291) (xy 155.731464 -50.036984)
			(xy 155.745201 -50.079111) (xy 155.766029 -50.165242) (xy 155.779137 -50.252881) (xy 155.782264 -50.29708)
			(xy 155.793186 -50.480214) (xy 155.825184 -51.019456) (xy 166.84955 -51.019456) (xy 166.853621 -50.963834)
			(xy 166.865747 -50.909397) (xy 166.88567 -50.857306) (xy 166.912966 -50.808671) (xy 166.947052 -50.764528)
			(xy 166.987201 -50.725819) (xy 167.032559 -50.693368) (xy 167.082159 -50.667867) (xy 167.134943 -50.64986)
			(xy 167.189786 -50.63973) (xy 167.24552 -50.637693) (xy 167.300957 -50.643793) (xy 167.354914 -50.657899)
			(xy 167.406243 -50.679711) (xy 167.453849 -50.708765) (xy 167.496717 -50.74444) (xy 167.533934 -50.785977)
			(xy 167.564707 -50.83249) (xy 167.588379 -50.882987) (xy 167.604447 -50.936394) (xy 167.612567 -50.99157)
			(xy 167.613076 -51.019456) (xy 167.612567 -51.047342) (xy 167.604447 -51.102518) (xy 167.588379 -51.155925)
			(xy 167.564707 -51.206422) (xy 167.533934 -51.252935) (xy 167.496717 -51.294472) (xy 167.453849 -51.330147)
			(xy 167.406243 -51.359201) (xy 167.354914 -51.381013) (xy 167.300957 -51.395119) (xy 167.24552 -51.401219)
			(xy 167.189786 -51.399182) (xy 167.134943 -51.389052) (xy 167.082159 -51.371045) (xy 167.032559 -51.345544)
			(xy 166.987201 -51.313093) (xy 166.947052 -51.274384) (xy 166.912966 -51.230241) (xy 166.88567 -51.181606)
			(xy 166.865747 -51.129515) (xy 166.853621 -51.075078) (xy 166.84955 -51.019456) (xy 155.825184 -51.019456)
			(xy 155.83281 -51.14798) (xy 155.885764 -52.035456) (xy 169.041316 -52.035456) (xy 169.045387 -51.979834)
			(xy 169.057513 -51.925397) (xy 169.077436 -51.873306) (xy 169.104732 -51.824671) (xy 169.138818 -51.780528)
			(xy 169.178967 -51.741819) (xy 169.224325 -51.709368) (xy 169.273925 -51.683867) (xy 169.326709 -51.66586)
			(xy 169.381552 -51.65573) (xy 169.437286 -51.653693) (xy 169.492723 -51.659793) (xy 169.54668 -51.673899)
			(xy 169.598009 -51.695711) (xy 169.645615 -51.724765) (xy 169.688483 -51.76044) (xy 169.7257 -51.801977)
			(xy 169.756473 -51.84849) (xy 169.780145 -51.898987) (xy 169.796213 -51.952394) (xy 169.804333 -52.00757)
			(xy 169.804842 -52.035456) (xy 169.804333 -52.063342) (xy 169.796213 -52.118518) (xy 169.780145 -52.171925)
			(xy 169.756473 -52.222422) (xy 169.7257 -52.268935) (xy 169.688483 -52.310472) (xy 169.645615 -52.346147)
			(xy 169.598009 -52.375201) (xy 169.54668 -52.397013) (xy 169.492723 -52.411119) (xy 169.437286 -52.417219)
			(xy 169.381552 -52.415182) (xy 169.326709 -52.405052) (xy 169.273925 -52.387045) (xy 169.224325 -52.361544)
			(xy 169.178967 -52.329093) (xy 169.138818 -52.290384) (xy 169.104732 -52.246241) (xy 169.077436 -52.197606)
			(xy 169.057513 -52.145515) (xy 169.045387 -52.091078) (xy 169.041316 -52.035456) (xy 155.885764 -52.035456)
			(xy 155.90774 -52.403756) (xy 155.91002 -52.415108) (xy 155.923122 -52.434172) (xy 155.943226 -52.445615)
			(xy 155.95473 -52.446936) (xy 155.962858 -52.446936) (xy 155.965398 -52.446682) (xy 156.002228 -52.444904)
			(xy 156.029478 -52.445392) (xy 156.083422 -52.453152) (xy 156.135712 -52.46851) (xy 156.185285 -52.491153)
			(xy 156.231131 -52.52062) (xy 156.272317 -52.556311) (xy 156.308004 -52.597501) (xy 156.337467 -52.64335)
			(xy 156.360104 -52.692925) (xy 156.375457 -52.745218) (xy 156.383211 -52.799162) (xy 156.383736 -52.826412)
			(xy 156.38331 -52.851923) (xy 156.376514 -52.90249) (xy 156.363044 -52.951702) (xy 156.34314 -52.998681)
			(xy 156.317157 -53.042591) (xy 156.301694 -53.062886) (xy 156.299154 -53.065934) (xy 156.298138 -53.067458)
			(xy 156.294836 -53.074062) (xy 156.29249 -53.079284) (xy 156.289923 -53.090438) (xy 156.289756 -53.09616)
			(xy 156.289756 -53.128164) (xy 156.27858 -53.128164) (xy 156.27858 -53.178964) (xy 156.278914 -53.187568)
			(xy 156.284624 -53.2038) (xy 156.289756 -53.210714) (xy 156.291026 -53.212238) (xy 156.30842 -53.233115)
			(xy 156.337739 -53.278864) (xy 156.360268 -53.328312) (xy 156.375549 -53.380457) (xy 156.383274 -53.434243)
			(xy 156.383736 -53.461412) (xy 156.38331 -53.486923) (xy 156.376514 -53.53749) (xy 156.363044 -53.586702)
			(xy 156.34314 -53.633681) (xy 156.317157 -53.677591) (xy 156.301694 -53.697886) (xy 156.299154 -53.700934)
			(xy 156.298138 -53.702458) (xy 156.294836 -53.709062) (xy 156.29249 -53.714284) (xy 156.289923 -53.725438)
			(xy 156.289756 -53.73116) (xy 156.289756 -53.763164) (xy 156.27858 -53.763164) (xy 156.27858 -53.813964)
			(xy 156.278914 -53.822568) (xy 156.284624 -53.8388) (xy 156.289756 -53.845714) (xy 156.291026 -53.847238)
			(xy 156.30842 -53.868115) (xy 156.337739 -53.913864) (xy 156.360268 -53.963312) (xy 156.375549 -54.015457)
			(xy 156.383274 -54.069243) (xy 156.383736 -54.096412) (xy 156.38331 -54.121923) (xy 156.376514 -54.17249)
			(xy 156.363044 -54.221702) (xy 156.34314 -54.268681) (xy 156.317157 -54.312591) (xy 156.301694 -54.332886)
			(xy 156.299154 -54.335934) (xy 156.298138 -54.337458) (xy 156.294836 -54.344062) (xy 156.29249 -54.349284)
			(xy 156.289923 -54.360438) (xy 156.289756 -54.36616) (xy 156.289756 -54.398164) (xy 156.27858 -54.398164)
			(xy 156.27858 -54.448964) (xy 156.278914 -54.457568) (xy 156.284624 -54.4738) (xy 156.289756 -54.480714)
			(xy 156.291026 -54.482238) (xy 156.30842 -54.503115) (xy 156.337739 -54.548864) (xy 156.360268 -54.598312)
			(xy 156.375549 -54.650457) (xy 156.383274 -54.704243) (xy 156.383736 -54.731412) (xy 156.383271 -54.75877)
			(xy 156.37861 -54.791102) (xy 158.276544 -54.791102) (xy 158.277001 -54.763731) (xy 158.284819 -54.709551)
			(xy 158.30031 -54.657048) (xy 158.323154 -54.607301) (xy 158.352881 -54.561335) (xy 158.370524 -54.540404)
			(xy 158.370778 -54.54015) (xy 158.376359 -54.53306) (xy 158.382607 -54.516146) (xy 158.38297 -54.50713)
			(xy 158.38297 -54.440074) (xy 158.382632 -54.431055) (xy 158.376372 -54.414138) (xy 158.370778 -54.407054)
			(xy 158.370524 -54.407054) (xy 158.370524 -54.4068) (xy 158.352885 -54.385866) (xy 158.323161 -54.339898)
			(xy 158.300315 -54.290152) (xy 158.284819 -54.23765) (xy 158.27699 -54.183472) (xy 158.27699 -54.128731)
			(xy 158.284819 -54.074553) (xy 158.300314 -54.022051) (xy 158.323159 -53.972305) (xy 158.352884 -53.926337)
			(xy 158.370524 -53.905404) (xy 158.370778 -53.90515) (xy 158.376359 -53.89806) (xy 158.382607 -53.881146)
			(xy 158.38297 -53.87213) (xy 158.38297 -53.805074) (xy 158.382632 -53.796055) (xy 158.376372 -53.779138)
			(xy 158.370778 -53.772054) (xy 158.370524 -53.772054) (xy 158.370524 -53.7718) (xy 158.352885 -53.750866)
			(xy 158.323161 -53.704898) (xy 158.300315 -53.655152) (xy 158.284819 -53.60265) (xy 158.27699 -53.548472)
			(xy 158.27699 -53.493731) (xy 158.284819 -53.439553) (xy 158.300314 -53.387051) (xy 158.323159 -53.337305)
			(xy 158.352884 -53.291337) (xy 158.370524 -53.270404) (xy 158.370778 -53.27015) (xy 158.376359 -53.26306)
			(xy 158.382607 -53.246146) (xy 158.38297 -53.23713) (xy 158.38297 -53.170074) (xy 158.382632 -53.161055)
			(xy 158.376372 -53.144138) (xy 158.370778 -53.137054) (xy 158.370524 -53.137054) (xy 158.370524 -53.1368)
			(xy 158.352875 -53.115876) (xy 158.323164 -53.069901) (xy 158.30033 -53.020152) (xy 158.284841 -52.967649)
			(xy 158.277016 -52.913472) (xy 158.276544 -52.886102) (xy 158.27703 -52.858851) (xy 158.284786 -52.804903)
			(xy 158.300141 -52.752608) (xy 158.322783 -52.703031) (xy 158.352249 -52.657181) (xy 158.38794 -52.61599)
			(xy 158.429131 -52.580299) (xy 158.474981 -52.550833) (xy 158.524558 -52.528191) (xy 158.576853 -52.512836)
			(xy 158.630801 -52.50508) (xy 158.685303 -52.50508) (xy 158.739251 -52.512836) (xy 158.791546 -52.528191)
			(xy 158.830655 -52.546052) (xy 163.779673 -52.546052) (xy 163.779673 -52.491548) (xy 163.78743 -52.437599)
			(xy 163.802786 -52.385303) (xy 163.825428 -52.335725) (xy 163.854895 -52.289873) (xy 163.890588 -52.248682)
			(xy 163.93178 -52.21299) (xy 163.977632 -52.183524) (xy 164.02721 -52.160883) (xy 164.079507 -52.145528)
			(xy 164.133456 -52.137773) (xy 164.160708 -52.13731) (xy 164.188079 -52.137769) (xy 164.242258 -52.145588)
			(xy 164.294761 -52.161079) (xy 164.344508 -52.183922) (xy 164.390475 -52.213648) (xy 164.411406 -52.23129)
			(xy 164.41166 -52.231544) (xy 164.41875 -52.237125) (xy 164.435664 -52.243374) (xy 164.44468 -52.243736)
			(xy 164.511736 -52.243736) (xy 164.520754 -52.243388) (xy 164.53767 -52.237134) (xy 164.544756 -52.231544)
			(xy 164.544756 -52.23129) (xy 164.54501 -52.23129) (xy 164.565943 -52.213649) (xy 164.611911 -52.183925)
			(xy 164.661657 -52.161079) (xy 164.714159 -52.145583) (xy 164.768337 -52.137754) (xy 164.823079 -52.137754)
			(xy 164.877257 -52.145583) (xy 164.929759 -52.161079) (xy 164.979505 -52.183925) (xy 165.025473 -52.213649)
			(xy 165.046406 -52.23129) (xy 165.04666 -52.231544) (xy 165.05375 -52.237125) (xy 165.070664 -52.243374)
			(xy 165.07968 -52.243736) (xy 165.146736 -52.243736) (xy 165.155754 -52.243388) (xy 165.17267 -52.237134)
			(xy 165.179756 -52.231544) (xy 165.179756 -52.23129) (xy 165.18001 -52.23129) (xy 165.200926 -52.213631)
			(xy 165.246904 -52.183923) (xy 165.296655 -52.161091) (xy 165.349159 -52.145604) (xy 165.403338 -52.137781)
			(xy 165.430708 -52.13731) (xy 165.45796 -52.13776) (xy 165.51191 -52.145518) (xy 165.564206 -52.160875)
			(xy 165.613784 -52.183517) (xy 165.659636 -52.212985) (xy 165.700827 -52.248678) (xy 165.73652 -52.28987)
			(xy 165.765986 -52.335723) (xy 165.788628 -52.385302) (xy 165.803984 -52.437598) (xy 165.81174 -52.491548)
			(xy 165.81174 -52.546052) (xy 165.805796 -52.587398) (xy 166.855392 -52.587398) (xy 166.859463 -52.531776)
			(xy 166.871589 -52.477339) (xy 166.891512 -52.425248) (xy 166.918808 -52.376613) (xy 166.952894 -52.33247)
			(xy 166.993043 -52.293761) (xy 167.038401 -52.26131) (xy 167.088001 -52.235809) (xy 167.140785 -52.217802)
			(xy 167.195628 -52.207672) (xy 167.251362 -52.205635) (xy 167.306799 -52.211735) (xy 167.360756 -52.225841)
			(xy 167.412085 -52.247653) (xy 167.459691 -52.276707) (xy 167.502559 -52.312382) (xy 167.539776 -52.353919)
			(xy 167.570549 -52.400432) (xy 167.594221 -52.450929) (xy 167.610289 -52.504336) (xy 167.617885 -52.555952)
			(xy 174.683879 -52.555952) (xy 174.683879 -52.501448) (xy 174.691637 -52.447498) (xy 174.706993 -52.395201)
			(xy 174.729636 -52.345622) (xy 174.759105 -52.29977) (xy 174.794799 -52.25858) (xy 174.835993 -52.222888)
			(xy 174.881847 -52.193423) (xy 174.931427 -52.170783) (xy 174.983725 -52.155431) (xy 175.037676 -52.147677)
			(xy 175.064928 -52.147216) (xy 175.092299 -52.147662) (xy 175.146479 -52.155484) (xy 175.198983 -52.170978)
			(xy 175.248729 -52.193824) (xy 175.294695 -52.223553) (xy 175.315626 -52.241196) (xy 175.31588 -52.24145)
			(xy 175.322964 -52.24704) (xy 175.339883 -52.253284) (xy 175.3489 -52.253642) (xy 175.415956 -52.253642)
			(xy 175.424972 -52.253277) (xy 175.44189 -52.247036) (xy 175.448976 -52.24145) (xy 175.448976 -52.241196)
			(xy 175.44923 -52.241196) (xy 175.470177 -52.223576) (xy 175.516146 -52.193861) (xy 175.56589 -52.171022)
			(xy 175.618387 -52.155526) (xy 175.67256 -52.147693) (xy 175.699928 -52.147216) (xy 175.72718 -52.147656)
			(xy 175.781128 -52.155416) (xy 175.833422 -52.170775) (xy 175.882999 -52.193419) (xy 175.928849 -52.222888)
			(xy 175.970038 -52.258581) (xy 176.005729 -52.299773) (xy 176.035195 -52.345625) (xy 176.057835 -52.395204)
			(xy 176.07319 -52.4475) (xy 176.080946 -52.501448) (xy 176.080946 -52.555952) (xy 176.07319 -52.6099)
			(xy 176.057835 -52.662196) (xy 176.035195 -52.711775) (xy 176.005729 -52.757627) (xy 175.970038 -52.798819)
			(xy 175.928849 -52.834512) (xy 175.882999 -52.863981) (xy 175.833422 -52.886625) (xy 175.781128 -52.901984)
			(xy 175.72718 -52.909744) (xy 175.699928 -52.910232) (xy 175.672558 -52.909766) (xy 175.618378 -52.901951)
			(xy 175.565874 -52.886463) (xy 175.516127 -52.86362) (xy 175.470161 -52.833894) (xy 175.44923 -52.816252)
			(xy 175.448976 -52.815998) (xy 175.441901 -52.810395) (xy 175.424975 -52.804158) (xy 175.415956 -52.803806)
			(xy 175.3489 -52.803806) (xy 175.339883 -52.804162) (xy 175.322966 -52.81041) (xy 175.31588 -52.815998)
			(xy 175.31588 -52.816252) (xy 175.315626 -52.816252) (xy 175.294689 -52.833885) (xy 175.248718 -52.863599)
			(xy 175.198972 -52.886437) (xy 175.146472 -52.90193) (xy 175.092297 -52.909758) (xy 175.064928 -52.910232)
			(xy 175.037676 -52.909723) (xy 174.983725 -52.901969) (xy 174.931427 -52.886617) (xy 174.881847 -52.863977)
			(xy 174.835993 -52.834512) (xy 174.794799 -52.79882) (xy 174.759105 -52.75763) (xy 174.729636 -52.711778)
			(xy 174.706993 -52.662199) (xy 174.691637 -52.609902) (xy 174.683879 -52.555952) (xy 167.617885 -52.555952)
			(xy 167.618409 -52.559512) (xy 167.618918 -52.587398) (xy 167.618409 -52.615284) (xy 167.610289 -52.67046)
			(xy 167.594221 -52.723867) (xy 167.570549 -52.774364) (xy 167.539776 -52.820877) (xy 167.502559 -52.862414)
			(xy 167.459691 -52.898089) (xy 167.412085 -52.927143) (xy 167.360756 -52.948955) (xy 167.306799 -52.963061)
			(xy 167.251362 -52.969161) (xy 167.195628 -52.967124) (xy 167.140785 -52.956994) (xy 167.088001 -52.938987)
			(xy 167.038401 -52.913486) (xy 166.993043 -52.881035) (xy 166.952894 -52.842326) (xy 166.918808 -52.798183)
			(xy 166.891512 -52.749548) (xy 166.871589 -52.697457) (xy 166.859463 -52.64302) (xy 166.855392 -52.587398)
			(xy 165.805796 -52.587398) (xy 165.803984 -52.600002) (xy 165.788628 -52.652298) (xy 165.765986 -52.701877)
			(xy 165.73652 -52.74773) (xy 165.700827 -52.788922) (xy 165.659636 -52.824615) (xy 165.613784 -52.854083)
			(xy 165.564206 -52.876725) (xy 165.51191 -52.892082) (xy 165.45796 -52.89984) (xy 165.430708 -52.900326)
			(xy 165.403337 -52.899873) (xy 165.349157 -52.892055) (xy 165.296653 -52.876564) (xy 165.246906 -52.853719)
			(xy 165.20094 -52.82399) (xy 165.18001 -52.806346) (xy 165.179756 -52.806092) (xy 165.172658 -52.800522)
			(xy 165.15575 -52.794266) (xy 165.146736 -52.7939) (xy 165.07968 -52.7939) (xy 165.070662 -52.794248)
			(xy 165.053745 -52.800502) (xy 165.04666 -52.806092) (xy 165.046406 -52.806346) (xy 165.025473 -52.823987)
			(xy 164.979505 -52.853711) (xy 164.929759 -52.876557) (xy 164.877257 -52.892053) (xy 164.823079 -52.899882)
			(xy 164.768337 -52.899882) (xy 164.714159 -52.892053) (xy 164.661657 -52.876557) (xy 164.611911 -52.853711)
			(xy 164.565943 -52.823987) (xy 164.54501 -52.806346) (xy 164.544756 -52.806092) (xy 164.537658 -52.800522)
			(xy 164.52075 -52.794266) (xy 164.511736 -52.7939) (xy 164.44468 -52.7939) (xy 164.435662 -52.794248)
			(xy 164.418745 -52.800502) (xy 164.41166 -52.806092) (xy 164.41166 -52.806346) (xy 164.411406 -52.806346)
			(xy 164.390476 -52.823987) (xy 164.344503 -52.853701) (xy 164.294755 -52.876537) (xy 164.242254 -52.892027)
			(xy 164.188077 -52.899854) (xy 164.160708 -52.900326) (xy 164.133456 -52.899827) (xy 164.079507 -52.892072)
			(xy 164.02721 -52.876717) (xy 163.977632 -52.854076) (xy 163.93178 -52.82461) (xy 163.890588 -52.788918)
			(xy 163.854895 -52.747727) (xy 163.825428 -52.701875) (xy 163.802786 -52.652297) (xy 163.78743 -52.600001)
			(xy 163.779673 -52.546052) (xy 158.830655 -52.546052) (xy 158.841123 -52.550833) (xy 158.886973 -52.580299)
			(xy 158.928164 -52.61599) (xy 158.963855 -52.657181) (xy 158.993321 -52.703031) (xy 159.015963 -52.752608)
			(xy 159.031318 -52.804903) (xy 159.039074 -52.858851) (xy 159.03956 -52.886102) (xy 159.039105 -52.913473)
			(xy 159.031286 -52.967653) (xy 159.015795 -53.020156) (xy 158.99295 -53.069903) (xy 158.963223 -53.115869)
			(xy 158.94558 -53.1368) (xy 158.945326 -53.137054) (xy 158.939744 -53.144143) (xy 158.933496 -53.161058)
			(xy 158.933134 -53.170074) (xy 158.933134 -53.23713) (xy 158.933469 -53.246149) (xy 158.939731 -53.263066)
			(xy 158.945326 -53.27015) (xy 158.94558 -53.27015) (xy 158.94558 -53.270404) (xy 158.963222 -53.291335)
			(xy 158.992947 -53.337304) (xy 159.015791 -53.38705) (xy 159.031287 -53.439552) (xy 159.039115 -53.493731)
			(xy 159.039115 -53.548472) (xy 159.031287 -53.602651) (xy 159.01579 -53.655153) (xy 158.992945 -53.704899)
			(xy 158.963221 -53.750867) (xy 158.94665 -53.77053) (xy 159.310832 -53.77053) (xy 159.31136 -53.741613)
			(xy 159.320085 -53.684442) (xy 159.33734 -53.629243) (xy 159.36273 -53.577281) (xy 159.395673 -53.529747)
			(xy 159.435413 -53.48773) (xy 159.457898 -53.46954) (xy 159.466677 -53.461905) (xy 159.476876 -53.441026)
			(xy 159.477456 -53.429408) (xy 159.477456 -53.349652) (xy 159.476946 -53.338016) (xy 159.466738 -53.317106)
			(xy 159.457898 -53.30952) (xy 159.435424 -53.291318) (xy 159.395688 -53.249301) (xy 159.362748 -53.201768)
			(xy 159.337358 -53.149809) (xy 159.3201 -53.094613) (xy 159.311368 -53.037445) (xy 159.310832 -53.00853)
			(xy 159.311283 -52.981276) (xy 159.319037 -52.927323) (xy 159.334392 -52.875022) (xy 159.357033 -52.825439)
			(xy 159.386502 -52.779584) (xy 159.422197 -52.73839) (xy 159.463392 -52.702696) (xy 159.509248 -52.673229)
			(xy 159.558831 -52.650588) (xy 159.611132 -52.635235) (xy 159.665086 -52.627483) (xy 159.69234 -52.627022)
			(xy 159.718655 -52.627456) (xy 159.770785 -52.634696) (xy 159.821429 -52.649022) (xy 159.869628 -52.67016)
			(xy 159.914471 -52.697713) (xy 159.955109 -52.731158) (xy 159.973264 -52.750212) (xy 159.980795 -52.757602)
			(xy 160.000068 -52.766133) (xy 160.010602 -52.766722) (xy 160.085278 -52.766722) (xy 160.095827 -52.766188)
			(xy 160.115122 -52.757655) (xy 160.122616 -52.750212) (xy 160.140773 -52.731158) (xy 160.181402 -52.6977)
			(xy 160.226242 -52.670141) (xy 160.274443 -52.649002) (xy 160.32509 -52.634685) (xy 160.377224 -52.62746)
			(xy 160.40354 -52.627022) (xy 160.430794 -52.627441) (xy 160.484745 -52.635203) (xy 160.537043 -52.650565)
			(xy 160.586622 -52.673213) (xy 160.632474 -52.702686) (xy 160.673665 -52.738385) (xy 160.709356 -52.779582)
			(xy 160.73882 -52.825439) (xy 160.761459 -52.875023) (xy 160.776811 -52.927323) (xy 160.784564 -52.981276)
			(xy 160.785048 -53.00853) (xy 160.784583 -53.036197) (xy 160.782352 -53.051456) (xy 169.041316 -53.051456)
			(xy 169.045387 -52.995834) (xy 169.057513 -52.941397) (xy 169.077436 -52.889306) (xy 169.104732 -52.840671)
			(xy 169.138818 -52.796528) (xy 169.178967 -52.757819) (xy 169.224325 -52.725368) (xy 169.273925 -52.699867)
			(xy 169.326709 -52.68186) (xy 169.381552 -52.67173) (xy 169.437286 -52.669693) (xy 169.492723 -52.675793)
			(xy 169.54668 -52.689899) (xy 169.598009 -52.711711) (xy 169.645615 -52.740765) (xy 169.688483 -52.77644)
			(xy 169.7257 -52.817977) (xy 169.756473 -52.86449) (xy 169.780145 -52.914987) (xy 169.796213 -52.968394)
			(xy 169.804333 -53.02357) (xy 169.804842 -53.051456) (xy 169.804333 -53.079342) (xy 169.796213 -53.134518)
			(xy 169.780145 -53.187925) (xy 169.756473 -53.238422) (xy 169.7257 -53.284935) (xy 169.688483 -53.326472)
			(xy 169.645615 -53.362147) (xy 169.598009 -53.391201) (xy 169.54668 -53.413013) (xy 169.492723 -53.427119)
			(xy 169.437286 -53.433219) (xy 169.381552 -53.431182) (xy 169.326709 -53.421052) (xy 169.273925 -53.403045)
			(xy 169.224325 -53.377544) (xy 169.178967 -53.345093) (xy 169.138818 -53.306384) (xy 169.104732 -53.262241)
			(xy 169.077436 -53.213606) (xy 169.057513 -53.161515) (xy 169.045387 -53.107078) (xy 169.041316 -53.051456)
			(xy 160.782352 -53.051456) (xy 160.776578 -53.090949) (xy 160.760755 -53.143973) (xy 160.737445 -53.194158)
			(xy 160.707136 -53.240453) (xy 160.670462 -53.28189) (xy 160.628193 -53.317599) (xy 160.604962 -53.332634)
			(xy 160.595274 -53.339257) (xy 160.582835 -53.359128) (xy 160.581086 -53.370734) (xy 160.573212 -53.450744)
			(xy 160.572572 -53.462382) (xy 160.580659 -53.484219) (xy 160.588706 -53.492654) (xy 160.58896 -53.492908)
			(xy 160.60752 -53.51101) (xy 160.640102 -53.551337) (xy 160.666919 -53.595706) (xy 160.687475 -53.643301)
			(xy 160.701393 -53.693242) (xy 160.708414 -53.744608) (xy 160.708848 -53.77053) (xy 160.70835 -53.79778)
			(xy 160.700591 -53.851725) (xy 160.685234 -53.904017) (xy 160.662592 -53.953592) (xy 160.633126 -53.99944)
			(xy 160.597436 -54.040629) (xy 160.556248 -54.07632) (xy 160.510401 -54.105787) (xy 160.460827 -54.12843)
			(xy 160.408535 -54.143789) (xy 160.35459 -54.15155) (xy 160.32734 -54.152038) (xy 160.29997 -54.151564)
			(xy 160.245791 -54.14375) (xy 160.193287 -54.128264) (xy 160.14354 -54.105424) (xy 160.097573 -54.075699)
			(xy 160.076642 -54.058058) (xy 160.076388 -54.057804) (xy 160.069309 -54.052207) (xy 160.052386 -54.045966)
			(xy 160.043368 -54.045612) (xy 159.976312 -54.045612) (xy 159.967295 -54.045972) (xy 159.950378 -54.052217)
			(xy 159.943292 -54.057804) (xy 159.943292 -54.058058) (xy 159.943038 -54.058058) (xy 159.922097 -54.075686)
			(xy 159.876127 -54.105401) (xy 159.826382 -54.12824) (xy 159.773883 -54.143733) (xy 159.719709 -54.151563)
			(xy 159.69234 -54.152038) (xy 159.665089 -54.151508) (xy 159.611143 -54.143757) (xy 159.558848 -54.128407)
			(xy 159.50927 -54.105772) (xy 159.463418 -54.076311) (xy 159.422226 -54.040624) (xy 159.386531 -53.999438)
			(xy 159.357062 -53.953592) (xy 159.334417 -53.904018) (xy 159.319058 -53.851726) (xy 159.311297 -53.79778)
			(xy 159.310832 -53.77053) (xy 158.94665 -53.77053) (xy 158.94558 -53.7718) (xy 158.945326 -53.772054)
			(xy 158.939744 -53.779143) (xy 158.933496 -53.796058) (xy 158.933134 -53.805074) (xy 158.933134 -53.87213)
			(xy 158.933469 -53.881149) (xy 158.939731 -53.898066) (xy 158.945326 -53.90515) (xy 158.94558 -53.90515)
			(xy 158.94558 -53.905404) (xy 158.963222 -53.926335) (xy 158.992947 -53.972304) (xy 159.015791 -54.02205)
			(xy 159.031287 -54.074552) (xy 159.039115 -54.128731) (xy 159.039115 -54.183472) (xy 159.031287 -54.237651)
			(xy 159.01579 -54.290153) (xy 159.001998 -54.320186) (xy 161.230564 -54.320186) (xy 161.231006 -54.292815)
			(xy 161.238827 -54.238634) (xy 161.254321 -54.18613) (xy 161.277169 -54.136383) (xy 161.3069 -54.090418)
			(xy 161.324544 -54.069488) (xy 161.324798 -54.069234) (xy 161.330376 -54.062142) (xy 161.336628 -54.045229)
			(xy 161.33699 -54.036214) (xy 161.33699 -53.969158) (xy 161.336607 -53.960144) (xy 161.330378 -53.943226)
			(xy 161.324798 -53.936138) (xy 161.324544 -53.936138) (xy 161.324544 -53.935884) (xy 161.306938 -53.914925)
			(xy 161.277219 -53.868961) (xy 161.254376 -53.81922) (xy 161.238878 -53.766725) (xy 161.231042 -53.712553)
			(xy 161.230564 -53.685186) (xy 161.23105 -53.657935) (xy 161.238806 -53.603987) (xy 161.254161 -53.551692)
			(xy 161.276803 -53.502115) (xy 161.306269 -53.456265) (xy 161.34196 -53.415074) (xy 161.383151 -53.379383)
			(xy 161.429001 -53.349917) (xy 161.478578 -53.327275) (xy 161.530873 -53.31192) (xy 161.584821 -53.304164)
			(xy 161.639323 -53.304164) (xy 161.693271 -53.31192) (xy 161.745566 -53.327275) (xy 161.795143 -53.349917)
			(xy 161.840993 -53.379383) (xy 161.882184 -53.415074) (xy 161.917875 -53.456265) (xy 161.943766 -53.496552)
			(xy 174.233564 -53.496552) (xy 174.233564 -53.442048) (xy 174.24132 -53.3881) (xy 174.256675 -53.335804)
			(xy 174.279316 -53.286226) (xy 174.308782 -53.240375) (xy 174.344474 -53.199183) (xy 174.385664 -53.163491)
			(xy 174.431514 -53.134023) (xy 174.481091 -53.11138) (xy 174.533386 -53.096023) (xy 174.587334 -53.088265)
			(xy 174.614586 -53.087778) (xy 174.641957 -53.088233) (xy 174.696137 -53.096051) (xy 174.748641 -53.111541)
			(xy 174.798388 -53.134386) (xy 174.844353 -53.164114) (xy 174.865284 -53.181758) (xy 174.865538 -53.182012)
			(xy 174.872637 -53.18758) (xy 174.889544 -53.193838) (xy 174.898558 -53.194204) (xy 174.965614 -53.194204)
			(xy 174.974631 -53.193853) (xy 174.991548 -53.187601) (xy 174.998634 -53.182012) (xy 174.998634 -53.181758)
			(xy 174.998888 -53.181758) (xy 175.019808 -53.164104) (xy 175.065785 -53.134396) (xy 175.115535 -53.111563)
			(xy 175.168039 -53.096075) (xy 175.222216 -53.08825) (xy 175.249586 -53.087778) (xy 175.276839 -53.088268)
			(xy 175.330789 -53.096023) (xy 175.383087 -53.111378) (xy 175.432667 -53.134019) (xy 175.47852 -53.163485)
			(xy 175.519713 -53.199177) (xy 175.555407 -53.240369) (xy 175.584875 -53.286221) (xy 175.607517 -53.3358)
			(xy 175.622874 -53.388097) (xy 175.630631 -53.442048) (xy 175.630631 -53.496552) (xy 175.622874 -53.550503)
			(xy 175.607517 -53.6028) (xy 175.584875 -53.652379) (xy 175.555407 -53.698231) (xy 175.519713 -53.739423)
			(xy 175.47852 -53.775115) (xy 175.432667 -53.804581) (xy 175.383087 -53.827222) (xy 175.330789 -53.842577)
			(xy 175.276839 -53.850332) (xy 175.249586 -53.850794) (xy 175.222215 -53.850338) (xy 175.168036 -53.842518)
			(xy 175.115533 -53.827026) (xy 175.065786 -53.804183) (xy 175.019819 -53.774456) (xy 174.998888 -53.756814)
			(xy 174.998634 -53.75656) (xy 174.991545 -53.750977) (xy 174.97463 -53.744729) (xy 174.965614 -53.744368)
			(xy 174.898558 -53.744368) (xy 174.889545 -53.74476) (xy 174.872628 -53.750984) (xy 174.865538 -53.75656)
			(xy 174.865538 -53.756814) (xy 174.865284 -53.756814) (xy 174.844333 -53.774429) (xy 174.798365 -53.804144)
			(xy 174.748622 -53.826985) (xy 174.696126 -53.842481) (xy 174.641954 -53.850316) (xy 174.614586 -53.850794)
			(xy 174.587334 -53.850335) (xy 174.533386 -53.842577) (xy 174.481091 -53.82722) (xy 174.431514 -53.804577)
			(xy 174.385664 -53.775109) (xy 174.344474 -53.739417) (xy 174.308782 -53.698225) (xy 174.279316 -53.652374)
			(xy 174.256675 -53.602796) (xy 174.24132 -53.5505) (xy 174.233564 -53.496552) (xy 161.943766 -53.496552)
			(xy 161.947341 -53.502115) (xy 161.969983 -53.551692) (xy 161.985338 -53.603987) (xy 161.993094 -53.657935)
			(xy 161.99358 -53.685186) (xy 161.993111 -53.712556) (xy 161.985294 -53.766735) (xy 161.969806 -53.819239)
			(xy 161.946965 -53.868986) (xy 161.917241 -53.914952) (xy 161.8996 -53.935884) (xy 161.899346 -53.936138)
			(xy 161.893773 -53.943233) (xy 161.887519 -53.960144) (xy 161.887154 -53.969158) (xy 161.887154 -54.036214)
			(xy 161.887493 -54.045233) (xy 161.893752 -54.06215) (xy 161.899346 -54.069234) (xy 161.8996 -54.069234)
			(xy 161.8996 -54.069488) (xy 161.917247 -54.090414) (xy 161.946958 -54.136388) (xy 161.969792 -54.186137)
			(xy 161.985281 -54.238639) (xy 161.993107 -54.292816) (xy 161.99358 -54.320186) (xy 161.993094 -54.347437)
			(xy 161.985338 -54.401385) (xy 161.969983 -54.45368) (xy 161.947341 -54.503257) (xy 161.917875 -54.549107)
			(xy 161.882184 -54.590298) (xy 161.840993 -54.625989) (xy 161.795143 -54.655455) (xy 161.745566 -54.678097)
			(xy 161.693271 -54.693452) (xy 161.639323 -54.701208) (xy 161.584821 -54.701208) (xy 161.530873 -54.693452)
			(xy 161.478578 -54.678097) (xy 161.429001 -54.655455) (xy 161.383151 -54.625989) (xy 161.34196 -54.590298)
			(xy 161.306269 -54.549107) (xy 161.276803 -54.503257) (xy 161.254161 -54.45368) (xy 161.238806 -54.401385)
			(xy 161.23105 -54.347437) (xy 161.230564 -54.320186) (xy 159.001998 -54.320186) (xy 158.992945 -54.339899)
			(xy 158.963221 -54.385867) (xy 158.94558 -54.4068) (xy 158.945326 -54.407054) (xy 158.939744 -54.414143)
			(xy 158.933496 -54.431058) (xy 158.933134 -54.440074) (xy 158.933134 -54.50713) (xy 158.933469 -54.516149)
			(xy 158.939731 -54.533066) (xy 158.945326 -54.54015) (xy 158.94558 -54.54015) (xy 158.94558 -54.540404)
			(xy 158.963231 -54.561326) (xy 158.992942 -54.607301) (xy 159.015776 -54.657051) (xy 159.031264 -54.709554)
			(xy 159.039088 -54.763732) (xy 159.039205 -54.770528) (xy 162.171126 -54.770528) (xy 162.171602 -54.743158)
			(xy 162.179417 -54.688979) (xy 162.194903 -54.636476) (xy 162.217743 -54.586729) (xy 162.247465 -54.540762)
			(xy 162.265106 -54.51983) (xy 162.26536 -54.519576) (xy 162.27097 -54.512506) (xy 162.277201 -54.495576)
			(xy 162.277552 -54.486556) (xy 162.277552 -54.4195) (xy 162.277205 -54.410482) (xy 162.270952 -54.393565)
			(xy 162.26536 -54.38648) (xy 162.265106 -54.38648) (xy 162.265106 -54.386226) (xy 162.247467 -54.365294)
			(xy 162.217755 -54.319321) (xy 162.194919 -54.269574) (xy 162.179428 -54.217073) (xy 162.1716 -54.162897)
			(xy 162.171126 -54.135528) (xy 162.171612 -54.108277) (xy 162.179368 -54.054329) (xy 162.194723 -54.002034)
			(xy 162.217365 -53.952457) (xy 162.246831 -53.906607) (xy 162.282522 -53.865416) (xy 162.323713 -53.829725)
			(xy 162.369563 -53.800259) (xy 162.41914 -53.777617) (xy 162.471435 -53.762262) (xy 162.525383 -53.754506)
			(xy 162.579885 -53.754506) (xy 162.633833 -53.762262) (xy 162.686128 -53.777617) (xy 162.735705 -53.800259)
			(xy 162.781555 -53.829725) (xy 162.822746 -53.865416) (xy 162.858437 -53.906607) (xy 162.887903 -53.952457)
			(xy 162.892978 -53.96357) (xy 166.872156 -53.96357) (xy 166.876227 -53.907948) (xy 166.888353 -53.853511)
			(xy 166.908276 -53.80142) (xy 166.935572 -53.752785) (xy 166.969658 -53.708642) (xy 167.009807 -53.669933)
			(xy 167.055165 -53.637482) (xy 167.104765 -53.611981) (xy 167.157549 -53.593974) (xy 167.212392 -53.583844)
			(xy 167.268126 -53.581807) (xy 167.323563 -53.587907) (xy 167.37752 -53.602013) (xy 167.428849 -53.623825)
			(xy 167.476455 -53.652879) (xy 167.519323 -53.688554) (xy 167.55654 -53.730091) (xy 167.587313 -53.776604)
			(xy 167.610985 -53.827101) (xy 167.627053 -53.880508) (xy 167.635173 -53.935684) (xy 167.635682 -53.96357)
			(xy 167.635173 -53.991456) (xy 167.627053 -54.046632) (xy 167.610985 -54.100039) (xy 167.587313 -54.150536)
			(xy 167.55654 -54.197049) (xy 167.519323 -54.238586) (xy 167.476455 -54.274261) (xy 167.428849 -54.303315)
			(xy 167.37752 -54.325127) (xy 167.323563 -54.339233) (xy 167.268126 -54.345333) (xy 167.212392 -54.343296)
			(xy 167.157549 -54.333166) (xy 167.104765 -54.315159) (xy 167.055165 -54.289658) (xy 167.009807 -54.257207)
			(xy 166.969658 -54.218498) (xy 166.935572 -54.174355) (xy 166.908276 -54.12572) (xy 166.888353 -54.073629)
			(xy 166.876227 -54.019192) (xy 166.872156 -53.96357) (xy 162.892978 -53.96357) (xy 162.910545 -54.002034)
			(xy 162.9259 -54.054329) (xy 162.933656 -54.108277) (xy 162.934142 -54.135528) (xy 162.933706 -54.162899)
			(xy 162.925883 -54.21708) (xy 162.910388 -54.269584) (xy 162.887539 -54.319331) (xy 162.857807 -54.365296)
			(xy 162.840162 -54.386226) (xy 162.839908 -54.38648) (xy 162.834325 -54.393569) (xy 162.828076 -54.410484)
			(xy 162.827716 -54.4195) (xy 162.827716 -54.486556) (xy 162.828091 -54.495571) (xy 162.834326 -54.512488)
			(xy 162.839908 -54.519576) (xy 162.840162 -54.519576) (xy 162.840162 -54.51983) (xy 162.857776 -54.540783)
			(xy 162.887493 -54.586749) (xy 162.910334 -54.636491) (xy 162.925831 -54.688988) (xy 162.933665 -54.74316)
			(xy 162.934142 -54.770528) (xy 162.933656 -54.797779) (xy 162.9259 -54.851727) (xy 162.910545 -54.904022)
			(xy 162.887903 -54.953599) (xy 162.865119 -54.989051) (xy 172.001168 -54.989051) (xy 172.001168 -54.934549)
			(xy 172.008924 -54.880602) (xy 172.024278 -54.828307) (xy 172.046919 -54.77873) (xy 172.076384 -54.732879)
			(xy 172.112074 -54.691688) (xy 172.153263 -54.655996) (xy 172.199112 -54.626528) (xy 172.248688 -54.603885)
			(xy 172.300982 -54.588528) (xy 172.354929 -54.580769) (xy 172.38218 -54.580282) (xy 172.410271 -54.580793)
			(xy 172.465847 -54.589017) (xy 172.519616 -54.605305) (xy 172.570413 -54.629305) (xy 172.61714 -54.660498)
			(xy 172.658786 -54.698208) (xy 172.694449 -54.741619) (xy 172.709332 -54.765448) (xy 172.714666 -54.774338)
			(xy 172.731684 -54.78653) (xy 172.824902 -54.80685) (xy 172.845476 -54.802532) (xy 172.854112 -54.79669)
			(xy 172.87817 -54.780681) (xy 172.930104 -54.755341) (xy 172.985264 -54.738118) (xy 173.042389 -54.729405)
			(xy 173.071282 -54.728872) (xy 173.098532 -54.729395) (xy 173.152477 -54.737148) (xy 173.20477 -54.7525)
			(xy 173.254346 -54.775138) (xy 173.300195 -54.8046) (xy 173.341385 -54.840288) (xy 173.377077 -54.881474)
			(xy 173.406544 -54.927321) (xy 173.429186 -54.976894) (xy 173.444543 -55.029186) (xy 173.452302 -55.08313)
			(xy 173.45279 -55.11038) (xy 173.452315 -55.13775) (xy 173.444499 -55.191929) (xy 173.429013 -55.244432)
			(xy 173.406173 -55.294179) (xy 173.37645 -55.340146) (xy 173.35881 -55.361078) (xy 173.358556 -55.361332)
			(xy 173.352986 -55.36843) (xy 173.346731 -55.385338) (xy 173.346364 -55.394352) (xy 173.346364 -55.461408)
			(xy 173.346725 -55.470424) (xy 173.35297 -55.487341) (xy 173.358556 -55.494428) (xy 173.35881 -55.494428)
			(xy 173.35881 -55.494682) (xy 173.37643 -55.515631) (xy 173.406152 -55.561597) (xy 173.428997 -55.611341)
			(xy 173.444493 -55.66384) (xy 173.452323 -55.718016) (xy 173.452325 -55.772754) (xy 173.444499 -55.82693)
			(xy 173.429007 -55.879431) (xy 173.406167 -55.929176) (xy 173.376448 -55.975145) (xy 173.35881 -55.996078)
			(xy 173.358556 -55.996332) (xy 173.352986 -56.00343) (xy 173.346731 -56.020338) (xy 173.346364 -56.029352)
			(xy 173.346364 -56.096408) (xy 173.346725 -56.105424) (xy 173.35297 -56.122341) (xy 173.358556 -56.129428)
			(xy 173.35881 -56.129428) (xy 173.35881 -56.129682) (xy 173.376456 -56.150609) (xy 173.406166 -56.196583)
			(xy 173.429001 -56.246332) (xy 173.44449 -56.298834) (xy 173.452317 -56.35301) (xy 173.45279 -56.38038)
			(xy 173.452304 -56.407631) (xy 173.444548 -56.461579) (xy 173.429193 -56.513874) (xy 173.406551 -56.563451)
			(xy 173.377085 -56.609301) (xy 173.341394 -56.650492) (xy 173.300203 -56.686183) (xy 173.254353 -56.715649)
			(xy 173.204776 -56.738291) (xy 173.152481 -56.753646) (xy 173.098533 -56.761402) (xy 173.044031 -56.761402)
			(xy 172.990083 -56.753646) (xy 172.937788 -56.738291) (xy 172.888211 -56.715649) (xy 172.842361 -56.686183)
			(xy 172.80117 -56.650492) (xy 172.765479 -56.609301) (xy 172.736013 -56.563451) (xy 172.713371 -56.513874)
			(xy 172.698016 -56.461579) (xy 172.69026 -56.407631) (xy 172.689774 -56.38038) (xy 172.69021 -56.353008)
			(xy 172.698033 -56.298827) (xy 172.713528 -56.246323) (xy 172.736376 -56.196577) (xy 172.766109 -56.150612)
			(xy 172.783754 -56.129682) (xy 172.784008 -56.129428) (xy 172.78959 -56.122338) (xy 172.795839 -56.105424)
			(xy 172.7962 -56.096408) (xy 172.7962 -56.029352) (xy 172.795818 -56.020338) (xy 172.789588 -56.003421)
			(xy 172.784008 -55.996332) (xy 172.783754 -55.996332) (xy 172.783754 -55.996078) (xy 172.766093 -55.975162)
			(xy 172.736367 -55.929192) (xy 172.713521 -55.879443) (xy 172.698025 -55.826938) (xy 172.690197 -55.772757)
			(xy 172.6902 -55.718013) (xy 172.698031 -55.663832) (xy 172.713531 -55.611329) (xy 172.736381 -55.561582)
			(xy 172.766111 -55.515614) (xy 172.783754 -55.494682) (xy 172.784008 -55.494428) (xy 172.78959 -55.487338)
			(xy 172.795839 -55.470424) (xy 172.7962 -55.461408) (xy 172.7962 -55.394352) (xy 172.795818 -55.385338)
			(xy 172.789588 -55.368421) (xy 172.784008 -55.361332) (xy 172.783754 -55.360824) (xy 172.772808 -55.348091)
			(xy 172.752968 -55.320999) (xy 172.74413 -55.306722) (xy 172.738796 -55.297832) (xy 172.721778 -55.28564)
			(xy 172.62856 -55.26532) (xy 172.607986 -55.269638) (xy 172.59935 -55.27548) (xy 172.575273 -55.291459)
			(xy 172.523346 -55.316807) (xy 172.468192 -55.334038) (xy 172.411071 -55.34276) (xy 172.38218 -55.343298)
			(xy 172.354929 -55.342831) (xy 172.300982 -55.335072) (xy 172.248688 -55.319715) (xy 172.199112 -55.297072)
			(xy 172.153263 -55.267604) (xy 172.112074 -55.231912) (xy 172.076384 -55.190721) (xy 172.046919 -55.14487)
			(xy 172.024278 -55.095293) (xy 172.008924 -55.042998) (xy 172.001168 -54.989051) (xy 162.865119 -54.989051)
			(xy 162.858437 -54.999449) (xy 162.822746 -55.04064) (xy 162.781555 -55.076331) (xy 162.735705 -55.105797)
			(xy 162.686128 -55.128439) (xy 162.633833 -55.143794) (xy 162.579885 -55.15155) (xy 162.525383 -55.15155)
			(xy 162.471435 -55.143794) (xy 162.41914 -55.128439) (xy 162.369563 -55.105797) (xy 162.323713 -55.076331)
			(xy 162.282522 -55.04064) (xy 162.246831 -54.999449) (xy 162.217365 -54.953599) (xy 162.194723 -54.904022)
			(xy 162.179368 -54.851727) (xy 162.171612 -54.797779) (xy 162.171126 -54.770528) (xy 159.039205 -54.770528)
			(xy 159.03956 -54.791102) (xy 159.039074 -54.818353) (xy 159.031318 -54.872301) (xy 159.015963 -54.924596)
			(xy 158.993321 -54.974173) (xy 158.963855 -55.020023) (xy 158.928164 -55.061214) (xy 158.886973 -55.096905)
			(xy 158.841123 -55.126371) (xy 158.791546 -55.149013) (xy 158.739251 -55.164368) (xy 158.685303 -55.172124)
			(xy 158.630801 -55.172124) (xy 158.576853 -55.164368) (xy 158.524558 -55.149013) (xy 158.474981 -55.126371)
			(xy 158.429131 -55.096905) (xy 158.38794 -55.061214) (xy 158.352249 -55.020023) (xy 158.322783 -54.974173)
			(xy 158.300141 -54.924596) (xy 158.284786 -54.872301) (xy 158.27703 -54.818353) (xy 158.276544 -54.791102)
			(xy 156.37861 -54.791102) (xy 156.375464 -54.812924) (xy 156.359996 -54.865408) (xy 156.337187 -54.915141)
			(xy 156.307504 -54.961104) (xy 156.271556 -55.002353) (xy 156.230082 -55.038041) (xy 156.183933 -55.067435)
			(xy 156.134057 -55.089931) (xy 156.107892 -55.097934) (xy 156.105098 -55.098696) (xy 156.095424 -55.102601)
			(xy 156.080099 -55.116724) (xy 156.071656 -55.135778) (xy 156.071062 -55.146194) (xy 156.105372 -55.722266)
			(xy 167.93413 -55.722266) (xy 167.938201 -55.666644) (xy 167.950327 -55.612207) (xy 167.97025 -55.560116)
			(xy 167.997546 -55.511481) (xy 168.031632 -55.467338) (xy 168.071781 -55.428629) (xy 168.117139 -55.396178)
			(xy 168.166739 -55.370677) (xy 168.219523 -55.35267) (xy 168.274366 -55.34254) (xy 168.3301 -55.340503)
			(xy 168.385537 -55.346603) (xy 168.439494 -55.360709) (xy 168.490823 -55.382521) (xy 168.538429 -55.411575)
			(xy 168.549575 -55.420851) (xy 170.324768 -55.420851) (xy 170.324768 -55.366349) (xy 170.332524 -55.312402)
			(xy 170.347878 -55.260107) (xy 170.370519 -55.21053) (xy 170.399984 -55.164679) (xy 170.435674 -55.123488)
			(xy 170.476863 -55.087796) (xy 170.522712 -55.058328) (xy 170.572288 -55.035685) (xy 170.624582 -55.020328)
			(xy 170.678529 -55.012569) (xy 170.70578 -55.012082) (xy 170.732093 -55.012569) (xy 170.784221 -55.0198)
			(xy 170.834863 -55.034116) (xy 170.883062 -55.055245) (xy 170.927906 -55.082787) (xy 170.968547 -55.116222)
			(xy 170.986704 -55.135272) (xy 170.994226 -55.142673) (xy 171.013506 -55.151199) (xy 171.024042 -55.151782)
			(xy 171.098718 -55.151782) (xy 171.109265 -55.151227) (xy 171.128561 -55.142711) (xy 171.136056 -55.135272)
			(xy 171.154186 -55.116191) (xy 171.194822 -55.082737) (xy 171.239668 -55.055182) (xy 171.287873 -55.034048)
			(xy 171.338525 -55.019736) (xy 171.390662 -55.012517) (xy 171.41698 -55.012082) (xy 171.444233 -55.012564)
			(xy 171.498185 -55.020318) (xy 171.550484 -55.035672) (xy 171.600065 -55.058313) (xy 171.645919 -55.08778)
			(xy 171.687113 -55.123472) (xy 171.722808 -55.164665) (xy 171.752277 -55.210517) (xy 171.774921 -55.260098)
			(xy 171.790277 -55.312396) (xy 171.798035 -55.366347) (xy 171.798035 -55.420853) (xy 171.790277 -55.474804)
			(xy 171.774921 -55.527102) (xy 171.752277 -55.576683) (xy 171.722808 -55.622535) (xy 171.687113 -55.663728)
			(xy 171.645919 -55.69942) (xy 171.600065 -55.728887) (xy 171.550484 -55.751528) (xy 171.498185 -55.766882)
			(xy 171.444233 -55.774636) (xy 171.41698 -55.775098) (xy 171.390666 -55.774645) (xy 171.338536 -55.767407)
			(xy 171.287893 -55.753085) (xy 171.239694 -55.73195) (xy 171.194851 -55.704402) (xy 171.154212 -55.670961)
			(xy 171.136056 -55.651908) (xy 171.128552 -55.644486) (xy 171.109259 -55.635973) (xy 171.098718 -55.635398)
			(xy 171.024042 -55.635398) (xy 171.013493 -55.635937) (xy 170.994198 -55.644465) (xy 170.986704 -55.651908)
			(xy 170.968541 -55.670956) (xy 170.927913 -55.704414) (xy 170.883074 -55.731973) (xy 170.834875 -55.753113)
			(xy 170.784229 -55.767432) (xy 170.732096 -55.774658) (xy 170.70578 -55.775098) (xy 170.678529 -55.774631)
			(xy 170.624582 -55.766872) (xy 170.572288 -55.751515) (xy 170.522712 -55.728872) (xy 170.476863 -55.699404)
			(xy 170.435674 -55.663712) (xy 170.399984 -55.622521) (xy 170.370519 -55.57667) (xy 170.347878 -55.527093)
			(xy 170.332524 -55.474798) (xy 170.324768 -55.420851) (xy 168.549575 -55.420851) (xy 168.581297 -55.44725)
			(xy 168.618514 -55.488787) (xy 168.649287 -55.5353) (xy 168.672959 -55.585797) (xy 168.689027 -55.639204)
			(xy 168.697147 -55.69438) (xy 168.697656 -55.722266) (xy 168.697147 -55.750152) (xy 168.689027 -55.805328)
			(xy 168.672959 -55.858735) (xy 168.649287 -55.909232) (xy 168.618514 -55.955745) (xy 168.581297 -55.997282)
			(xy 168.538429 -56.032957) (xy 168.490823 -56.062011) (xy 168.439494 -56.083823) (xy 168.385537 -56.097929)
			(xy 168.3301 -56.104029) (xy 168.274366 -56.101992) (xy 168.219523 -56.091862) (xy 168.166739 -56.073855)
			(xy 168.117139 -56.048354) (xy 168.071781 -56.015903) (xy 168.031632 -55.977194) (xy 167.997546 -55.933051)
			(xy 167.97025 -55.884416) (xy 167.950327 -55.832325) (xy 167.938201 -55.777888) (xy 167.93413 -55.722266)
			(xy 156.105372 -55.722266) (xy 156.148532 -56.446928) (xy 156.149714 -56.455291) (xy 156.156839 -56.470593)
			(xy 156.168566 -56.482734) (xy 156.175964 -56.486806) (xy 156.202046 -56.500784) (xy 156.249925 -56.535554)
			(xy 156.291865 -56.577296) (xy 156.326862 -56.625009) (xy 156.354078 -56.677551) (xy 156.37286 -56.733664)
			(xy 156.382759 -56.792002) (xy 156.383736 -56.821578) (xy 156.383736 -56.826658) (xy 156.383323 -56.852274)
			(xy 156.376463 -56.903045) (xy 156.362863 -56.95244) (xy 156.342766 -56.999566) (xy 156.340759 -57.002934)
			(xy 163.66363 -57.002934) (xy 163.664128 -56.974842) (xy 163.672352 -56.919264) (xy 163.688641 -56.865494)
			(xy 163.712642 -56.814696) (xy 163.743837 -56.767969) (xy 163.78155 -56.726324) (xy 163.824965 -56.690663)
			(xy 163.848796 -56.675782) (xy 163.857686 -56.670448) (xy 163.869878 -56.65343) (xy 163.890198 -56.560212)
			(xy 163.88588 -56.539638) (xy 163.880038 -56.531002) (xy 163.864041 -56.506936) (xy 163.838697 -56.455006)
			(xy 163.82147 -56.399848) (xy 163.812754 -56.342724) (xy 163.81222 -56.313832) (xy 163.812685 -56.286579)
			(xy 163.820439 -56.232626) (xy 163.835792 -56.180327) (xy 163.858433 -56.130745) (xy 163.8879 -56.08489)
			(xy 163.923594 -56.043697) (xy 163.964787 -56.008002) (xy 164.010641 -55.978535) (xy 164.060223 -55.955893)
			(xy 164.112522 -55.940539) (xy 164.166475 -55.932785) (xy 164.193728 -55.932324) (xy 164.221099 -55.932768)
			(xy 164.275279 -55.94059) (xy 164.327783 -55.956084) (xy 164.377529 -55.978931) (xy 164.423495 -56.00866)
			(xy 164.444426 -56.026304) (xy 164.44468 -56.026558) (xy 164.451763 -56.032149) (xy 164.468683 -56.038392)
			(xy 164.4777 -56.03875) (xy 164.544756 -56.03875) (xy 164.553772 -56.038383) (xy 164.57069 -56.032144)
			(xy 164.577776 -56.026558) (xy 164.577776 -56.026304) (xy 164.57803 -56.026304) (xy 164.598963 -56.008663)
			(xy 164.644931 -55.978939) (xy 164.694677 -55.956093) (xy 164.747179 -55.940597) (xy 164.801357 -55.932768)
			(xy 164.856099 -55.932768) (xy 164.910277 -55.940597) (xy 164.962779 -55.956093) (xy 165.012525 -55.978939)
			(xy 165.058493 -56.008663) (xy 165.079426 -56.026304) (xy 165.07968 -56.026558) (xy 165.086763 -56.032149)
			(xy 165.103683 -56.038392) (xy 165.1127 -56.03875) (xy 165.179756 -56.03875) (xy 165.188772 -56.038383)
			(xy 165.20569 -56.032144) (xy 165.212776 -56.026558) (xy 165.212776 -56.026304) (xy 165.21303 -56.026304)
			(xy 165.233978 -56.008685) (xy 165.279946 -55.97897) (xy 165.32969 -55.95613) (xy 165.382187 -55.940634)
			(xy 165.43636 -55.932801) (xy 165.463728 -55.932324) (xy 165.49098 -55.932748) (xy 165.544929 -55.940508)
			(xy 165.597225 -55.955867) (xy 165.646803 -55.978512) (xy 165.692654 -56.007981) (xy 165.733844 -56.043676)
			(xy 165.769536 -56.084869) (xy 165.799002 -56.130722) (xy 165.821643 -56.180301) (xy 165.836998 -56.232598)
			(xy 165.844754 -56.286548) (xy 165.844754 -56.297068) (xy 166.18661 -56.297068) (xy 166.190681 -56.241446)
			(xy 166.202807 -56.187009) (xy 166.22273 -56.134918) (xy 166.250026 -56.086283) (xy 166.284112 -56.04214)
			(xy 166.324261 -56.003431) (xy 166.369619 -55.97098) (xy 166.419219 -55.945479) (xy 166.472003 -55.927472)
			(xy 166.526846 -55.917342) (xy 166.58258 -55.915305) (xy 166.638017 -55.921405) (xy 166.691974 -55.935511)
			(xy 166.743303 -55.957323) (xy 166.790909 -55.986377) (xy 166.833777 -56.022052) (xy 166.870994 -56.063589)
			(xy 166.901767 -56.110102) (xy 166.925439 -56.160599) (xy 166.941507 -56.214006) (xy 166.949627 -56.269182)
			(xy 166.950136 -56.297068) (xy 166.949627 -56.324954) (xy 166.941507 -56.38013) (xy 166.925439 -56.433537)
			(xy 166.901767 -56.484034) (xy 166.870994 -56.530547) (xy 166.833777 -56.572084) (xy 166.790909 -56.607759)
			(xy 166.743303 -56.636813) (xy 166.691974 -56.658625) (xy 166.638017 -56.672731) (xy 166.58258 -56.678831)
			(xy 166.526846 -56.676794) (xy 166.472003 -56.666664) (xy 166.419219 -56.648657) (xy 166.369619 -56.623156)
			(xy 166.324261 -56.590705) (xy 166.284112 -56.551996) (xy 166.250026 -56.507853) (xy 166.22273 -56.459218)
			(xy 166.202807 -56.407127) (xy 166.190681 -56.35269) (xy 166.18661 -56.297068) (xy 165.844754 -56.297068)
			(xy 165.844754 -56.341052) (xy 165.836998 -56.395002) (xy 165.821643 -56.447299) (xy 165.799002 -56.496878)
			(xy 165.769536 -56.542731) (xy 165.733844 -56.583924) (xy 165.692654 -56.619619) (xy 165.646803 -56.649088)
			(xy 165.597225 -56.671733) (xy 165.544929 -56.687092) (xy 165.49098 -56.694852) (xy 165.463728 -56.69534)
			(xy 165.436358 -56.694872) (xy 165.382178 -56.687057) (xy 165.329674 -56.671569) (xy 165.279927 -56.648727)
			(xy 165.233961 -56.619002) (xy 165.21303 -56.60136) (xy 165.212776 -56.601106) (xy 165.2057 -56.595504)
			(xy 165.188775 -56.589266) (xy 165.179756 -56.588914) (xy 165.1127 -56.588914) (xy 165.103683 -56.589268)
			(xy 165.086766 -56.595517) (xy 165.07968 -56.601106) (xy 165.07968 -56.60136) (xy 165.079426 -56.60136)
			(xy 165.058493 -56.619001) (xy 165.012525 -56.648725) (xy 164.962779 -56.671571) (xy 164.910277 -56.687067)
			(xy 164.856099 -56.694896) (xy 164.801357 -56.694896) (xy 164.747179 -56.687067) (xy 164.694677 -56.671571)
			(xy 164.644931 -56.648725) (xy 164.598963 -56.619001) (xy 164.57803 -56.60136) (xy 164.577776 -56.601106)
			(xy 164.5707 -56.595504) (xy 164.553775 -56.589266) (xy 164.544756 -56.588914) (xy 164.4777 -56.588914)
			(xy 164.468683 -56.589268) (xy 164.451766 -56.595517) (xy 164.44468 -56.601106) (xy 164.444172 -56.60136)
			(xy 164.431437 -56.612303) (xy 164.404346 -56.632145) (xy 164.39007 -56.640984) (xy 164.38118 -56.646318)
			(xy 164.368988 -56.663336) (xy 164.348668 -56.756554) (xy 164.352986 -56.777128) (xy 164.358828 -56.785764)
			(xy 164.374818 -56.809834) (xy 164.400162 -56.861764) (xy 164.417391 -56.91692) (xy 164.426109 -56.974042)
			(xy 164.426646 -57.002934) (xy 164.42616 -57.030185) (xy 164.418404 -57.084133) (xy 164.403049 -57.136428)
			(xy 164.380407 -57.186005) (xy 164.350941 -57.231855) (xy 164.31525 -57.273046) (xy 164.274059 -57.308737)
			(xy 164.228209 -57.338203) (xy 164.178632 -57.360845) (xy 164.126337 -57.3762) (xy 164.072389 -57.383956)
			(xy 164.017887 -57.383956) (xy 163.963939 -57.3762) (xy 163.911644 -57.360845) (xy 163.862067 -57.338203)
			(xy 163.816217 -57.308737) (xy 163.775026 -57.273046) (xy 163.739335 -57.231855) (xy 163.709869 -57.186005)
			(xy 163.687227 -57.136428) (xy 163.671872 -57.084133) (xy 163.664116 -57.030185) (xy 163.66363 -57.002934)
			(xy 156.340759 -57.002934) (xy 156.316536 -57.043574) (xy 156.300932 -57.063894) (xy 156.295598 -57.070498)
			(xy 156.292296 -57.079642) (xy 156.290772 -57.085484) (xy 156.289756 -57.09539) (xy 156.289756 -57.128156)
			(xy 156.27858 -57.128156) (xy 156.27858 -57.178956) (xy 156.278913 -57.18756) (xy 156.284621 -57.203795)
			(xy 156.289756 -57.210706) (xy 156.291026 -57.21223) (xy 156.308421 -57.233106) (xy 156.337741 -57.278856)
			(xy 156.36027 -57.328304) (xy 156.375553 -57.380449) (xy 156.383279 -57.434235) (xy 156.383736 -57.461404)
			(xy 156.383354 -57.48528) (xy 172.706028 -57.48528) (xy 172.710099 -57.429658) (xy 172.722225 -57.375221)
			(xy 172.742148 -57.32313) (xy 172.769444 -57.274495) (xy 172.80353 -57.230352) (xy 172.843679 -57.191643)
			(xy 172.889037 -57.159192) (xy 172.938637 -57.133691) (xy 172.991421 -57.115684) (xy 173.046264 -57.105554)
			(xy 173.101998 -57.103517) (xy 173.157435 -57.109617) (xy 173.211392 -57.123723) (xy 173.262721 -57.145535)
			(xy 173.310327 -57.174589) (xy 173.353195 -57.210264) (xy 173.390412 -57.251801) (xy 173.421185 -57.298314)
			(xy 173.444857 -57.348811) (xy 173.460925 -57.402218) (xy 173.469045 -57.457394) (xy 173.469554 -57.48528)
			(xy 173.469045 -57.513166) (xy 173.460925 -57.568342) (xy 173.444857 -57.621749) (xy 173.421185 -57.672246)
			(xy 173.390412 -57.718759) (xy 173.353195 -57.760296) (xy 173.310327 -57.795971) (xy 173.262721 -57.825025)
			(xy 173.211392 -57.846837) (xy 173.157435 -57.860943) (xy 173.101998 -57.867043) (xy 173.046264 -57.865006)
			(xy 172.991421 -57.854876) (xy 172.938637 -57.836869) (xy 172.889037 -57.811368) (xy 172.843679 -57.778917)
			(xy 172.80353 -57.740208) (xy 172.769444 -57.696065) (xy 172.742148 -57.64743) (xy 172.722225 -57.595339)
			(xy 172.710099 -57.540902) (xy 172.706028 -57.48528) (xy 156.383354 -57.48528) (xy 156.383326 -57.487021)
			(xy 156.376474 -57.537796) (xy 156.362879 -57.587194) (xy 156.342787 -57.634325) (xy 156.316561 -57.678339)
			(xy 156.300932 -57.69864) (xy 156.300678 -57.698894) (xy 156.299154 -57.700672) (xy 156.294849 -57.707198)
			(xy 156.290052 -57.72207) (xy 156.289756 -57.729882) (xy 156.289756 -57.763156) (xy 156.27858 -57.763156)
			(xy 156.27858 -57.813956) (xy 156.278913 -57.82256) (xy 156.284621 -57.838795) (xy 156.289756 -57.845706)
			(xy 156.291026 -57.84723) (xy 156.308421 -57.868106) (xy 156.337741 -57.913856) (xy 156.36027 -57.963304)
			(xy 156.375553 -58.015449) (xy 156.383279 -58.069235) (xy 156.383736 -58.096404) (xy 156.383326 -58.122021)
			(xy 156.376474 -58.172796) (xy 156.362879 -58.222194) (xy 156.342787 -58.269325) (xy 156.316561 -58.313339)
			(xy 156.300932 -58.33364) (xy 156.300678 -58.333894) (xy 156.299154 -58.335672) (xy 156.294849 -58.342198)
			(xy 156.290052 -58.35707) (xy 156.289756 -58.364882) (xy 156.289756 -58.398156) (xy 156.27858 -58.398156)
			(xy 156.27858 -58.448956) (xy 156.278913 -58.45756) (xy 156.284621 -58.473795) (xy 156.289756 -58.480706)
			(xy 156.291026 -58.48223) (xy 156.308421 -58.503106) (xy 156.337741 -58.548856) (xy 156.36027 -58.598304)
			(xy 156.375553 -58.650449) (xy 156.379702 -58.679334) (xy 164.09543 -58.679334) (xy 164.095844 -58.653018)
			(xy 164.103088 -58.600887) (xy 164.117417 -58.550243) (xy 164.13856 -58.502044) (xy 164.166116 -58.457202)
			(xy 164.199564 -58.416565) (xy 164.21862 -58.39841) (xy 164.226022 -58.390889) (xy 164.234546 -58.371608)
			(xy 164.23513 -58.361072) (xy 164.23513 -58.286396) (xy 164.234608 -58.275846) (xy 164.226067 -58.256551)
			(xy 164.21862 -58.249058) (xy 164.199555 -58.230912) (xy 164.166098 -58.190281) (xy 164.13854 -58.145439)
			(xy 164.117403 -58.097236) (xy 164.103088 -58.046586) (xy 164.095866 -57.994451) (xy 164.09543 -57.968134)
			(xy 164.095916 -57.940883) (xy 164.103672 -57.886935) (xy 164.119027 -57.83464) (xy 164.141669 -57.785063)
			(xy 164.171135 -57.739213) (xy 164.206826 -57.698022) (xy 164.248017 -57.662331) (xy 164.293867 -57.632865)
			(xy 164.343444 -57.610223) (xy 164.395739 -57.594868) (xy 164.449687 -57.587112) (xy 164.504189 -57.587112)
			(xy 164.558137 -57.594868) (xy 164.610432 -57.610223) (xy 164.660009 -57.632865) (xy 164.705859 -57.662331)
			(xy 164.74705 -57.698022) (xy 164.782741 -57.739213) (xy 164.812207 -57.785063) (xy 164.834849 -57.83464)
			(xy 164.850204 -57.886935) (xy 164.85796 -57.940883) (xy 164.858446 -57.968134) (xy 164.858018 -57.99445)
			(xy 164.850778 -58.04658) (xy 164.84351 -58.072274) (xy 168.093642 -58.072274) (xy 168.097713 -58.016652)
			(xy 168.109839 -57.962215) (xy 168.129762 -57.910124) (xy 168.157058 -57.861489) (xy 168.191144 -57.817346)
			(xy 168.231293 -57.778637) (xy 168.276651 -57.746186) (xy 168.326251 -57.720685) (xy 168.379035 -57.702678)
			(xy 168.433878 -57.692548) (xy 168.489612 -57.690511) (xy 168.545049 -57.696611) (xy 168.599006 -57.710717)
			(xy 168.650335 -57.732529) (xy 168.697941 -57.761583) (xy 168.740809 -57.797258) (xy 168.778026 -57.838795)
			(xy 168.808799 -57.885308) (xy 168.832471 -57.935805) (xy 168.848539 -57.989212) (xy 168.856659 -58.044388)
			(xy 168.857168 -58.072274) (xy 168.857098 -58.076084) (xy 173.458122 -58.076084) (xy 173.462193 -58.020462)
			(xy 173.474319 -57.966025) (xy 173.494242 -57.913934) (xy 173.521538 -57.865299) (xy 173.555624 -57.821156)
			(xy 173.595773 -57.782447) (xy 173.641131 -57.749996) (xy 173.690731 -57.724495) (xy 173.743515 -57.706488)
			(xy 173.798358 -57.696358) (xy 173.854092 -57.694321) (xy 173.909529 -57.700421) (xy 173.963486 -57.714527)
			(xy 174.014815 -57.736339) (xy 174.062421 -57.765393) (xy 174.105289 -57.801068) (xy 174.142506 -57.842605)
			(xy 174.158842 -57.867296) (xy 175.743106 -57.867296) (xy 175.747177 -57.811674) (xy 175.759303 -57.757237)
			(xy 175.779226 -57.705146) (xy 175.806522 -57.656511) (xy 175.840608 -57.612368) (xy 175.880757 -57.573659)
			(xy 175.926115 -57.541208) (xy 175.975715 -57.515707) (xy 176.028499 -57.4977) (xy 176.083342 -57.48757)
			(xy 176.139076 -57.485533) (xy 176.194513 -57.491633) (xy 176.24847 -57.505739) (xy 176.299799 -57.527551)
			(xy 176.347405 -57.556605) (xy 176.390273 -57.59228) (xy 176.42749 -57.633817) (xy 176.458263 -57.68033)
			(xy 176.481935 -57.730827) (xy 176.498003 -57.784234) (xy 176.506123 -57.83941) (xy 176.506632 -57.867296)
			(xy 176.506123 -57.895182) (xy 176.498003 -57.950358) (xy 176.481935 -58.003765) (xy 176.458263 -58.054262)
			(xy 176.42749 -58.100775) (xy 176.390273 -58.142312) (xy 176.347405 -58.177987) (xy 176.299799 -58.207041)
			(xy 176.24847 -58.228853) (xy 176.194513 -58.242959) (xy 176.139076 -58.249059) (xy 176.083342 -58.247022)
			(xy 176.028499 -58.236892) (xy 175.975715 -58.218885) (xy 175.926115 -58.193384) (xy 175.880757 -58.160933)
			(xy 175.840608 -58.122224) (xy 175.806522 -58.078081) (xy 175.779226 -58.029446) (xy 175.759303 -57.977355)
			(xy 175.747177 -57.922918) (xy 175.743106 -57.867296) (xy 174.158842 -57.867296) (xy 174.173279 -57.889118)
			(xy 174.196951 -57.939615) (xy 174.213019 -57.993022) (xy 174.221139 -58.048198) (xy 174.221648 -58.076084)
			(xy 174.221139 -58.10397) (xy 174.213019 -58.159146) (xy 174.196951 -58.212553) (xy 174.173279 -58.26305)
			(xy 174.142506 -58.309563) (xy 174.105289 -58.3511) (xy 174.062421 -58.386775) (xy 174.014815 -58.415829)
			(xy 173.963486 -58.437641) (xy 173.909529 -58.451747) (xy 173.854092 -58.457847) (xy 173.798358 -58.45581)
			(xy 173.743515 -58.44568) (xy 173.690731 -58.427673) (xy 173.641131 -58.402172) (xy 173.595773 -58.369721)
			(xy 173.555624 -58.331012) (xy 173.521538 -58.286869) (xy 173.494242 -58.238234) (xy 173.474319 -58.186143)
			(xy 173.462193 -58.131706) (xy 173.458122 -58.076084) (xy 168.857098 -58.076084) (xy 168.856659 -58.10016)
			(xy 168.848539 -58.155336) (xy 168.832471 -58.208743) (xy 168.808799 -58.25924) (xy 168.778026 -58.305753)
			(xy 168.740809 -58.34729) (xy 168.697941 -58.382965) (xy 168.650335 -58.412019) (xy 168.599006 -58.433831)
			(xy 168.545049 -58.447937) (xy 168.489612 -58.454037) (xy 168.433878 -58.452) (xy 168.379035 -58.44187)
			(xy 168.326251 -58.423863) (xy 168.276651 -58.398362) (xy 168.231293 -58.365911) (xy 168.191144 -58.327202)
			(xy 168.157058 -58.283059) (xy 168.129762 -58.234424) (xy 168.109839 -58.182333) (xy 168.097713 -58.127896)
			(xy 168.093642 -58.072274) (xy 164.84351 -58.072274) (xy 164.836452 -58.097225) (xy 164.815312 -58.145424)
			(xy 164.787758 -58.190266) (xy 164.754312 -58.230903) (xy 164.735256 -58.249058) (xy 164.727879 -58.256601)
			(xy 164.719339 -58.275864) (xy 164.718746 -58.286396) (xy 164.718746 -58.361072) (xy 164.719263 -58.371623)
			(xy 164.727805 -58.390919) (xy 164.735256 -58.39841) (xy 164.75432 -58.416557) (xy 164.787774 -58.45719)
			(xy 164.815331 -58.502032) (xy 164.836467 -58.550234) (xy 164.839573 -58.561224) (xy 174.662336 -58.561224)
			(xy 174.666407 -58.505602) (xy 174.678533 -58.451165) (xy 174.698456 -58.399074) (xy 174.725752 -58.350439)
			(xy 174.759838 -58.306296) (xy 174.799987 -58.267587) (xy 174.845345 -58.235136) (xy 174.894945 -58.209635)
			(xy 174.947729 -58.191628) (xy 175.002572 -58.181498) (xy 175.058306 -58.179461) (xy 175.113743 -58.185561)
			(xy 175.1677 -58.199667) (xy 175.219029 -58.221479) (xy 175.266635 -58.250533) (xy 175.309503 -58.286208)
			(xy 175.34672 -58.327745) (xy 175.377493 -58.374258) (xy 175.401165 -58.424755) (xy 175.417233 -58.478162)
			(xy 175.425353 -58.533338) (xy 175.425862 -58.561224) (xy 175.425353 -58.58911) (xy 175.417233 -58.644286)
			(xy 175.401165 -58.697693) (xy 175.377493 -58.74819) (xy 175.34672 -58.794703) (xy 175.309503 -58.83624)
			(xy 175.266635 -58.871915) (xy 175.219029 -58.900969) (xy 175.1677 -58.922781) (xy 175.113743 -58.936887)
			(xy 175.058306 -58.942987) (xy 175.002572 -58.94095) (xy 174.947729 -58.93082) (xy 174.894945 -58.912813)
			(xy 174.845345 -58.887312) (xy 174.799987 -58.854861) (xy 174.759838 -58.816152) (xy 174.725752 -58.772009)
			(xy 174.698456 -58.723374) (xy 174.678533 -58.671283) (xy 174.666407 -58.616846) (xy 174.662336 -58.561224)
			(xy 164.839573 -58.561224) (xy 164.850783 -58.600883) (xy 164.858008 -58.653018) (xy 164.858446 -58.679334)
			(xy 164.85796 -58.706585) (xy 164.850204 -58.760533) (xy 164.834849 -58.812828) (xy 164.812207 -58.862405)
			(xy 164.782741 -58.908255) (xy 164.74705 -58.949446) (xy 164.705859 -58.985137) (xy 164.660009 -59.014603)
			(xy 164.610432 -59.037245) (xy 164.558137 -59.0526) (xy 164.504189 -59.060356) (xy 164.449687 -59.060356)
			(xy 164.395739 -59.0526) (xy 164.343444 -59.037245) (xy 164.293867 -59.014603) (xy 164.248017 -58.985137)
			(xy 164.206826 -58.949446) (xy 164.171135 -58.908255) (xy 164.141669 -58.862405) (xy 164.119027 -58.812828)
			(xy 164.103672 -58.760533) (xy 164.095916 -58.706585) (xy 164.09543 -58.679334) (xy 156.379702 -58.679334)
			(xy 156.383279 -58.704235) (xy 156.383736 -58.731404) (xy 156.383176 -58.759729) (xy 156.37472 -58.815745)
			(xy 156.358082 -58.869898) (xy 156.333627 -58.920999) (xy 156.318204 -58.944764) (xy 156.318204 -58.945272)
			(xy 156.314261 -58.951649) (xy 156.309862 -58.965975) (xy 156.309568 -58.973466) (xy 156.309568 -59.149996)
			(xy 156.309568 -59.153044) (xy 156.310855 -59.174634) (xy 173.1932 -59.174634) (xy 173.197271 -59.119012)
			(xy 173.209397 -59.064575) (xy 173.22932 -59.012484) (xy 173.256616 -58.963849) (xy 173.290702 -58.919706)
			(xy 173.330851 -58.880997) (xy 173.376209 -58.848546) (xy 173.425809 -58.823045) (xy 173.478593 -58.805038)
			(xy 173.533436 -58.794908) (xy 173.58917 -58.792871) (xy 173.644607 -58.798971) (xy 173.698564 -58.813077)
			(xy 173.749893 -58.834889) (xy 173.797499 -58.863943) (xy 173.840367 -58.899618) (xy 173.877584 -58.941155)
			(xy 173.908357 -58.987668) (xy 173.932029 -59.038165) (xy 173.948097 -59.091572) (xy 173.956217 -59.146748)
			(xy 173.956726 -59.174634) (xy 173.956217 -59.20252) (xy 173.948097 -59.257696) (xy 173.932029 -59.311103)
			(xy 173.908357 -59.3616) (xy 173.877584 -59.408113) (xy 173.840367 -59.44965) (xy 173.797499 -59.485325)
			(xy 173.749893 -59.514379) (xy 173.698564 -59.536191) (xy 173.644607 -59.550297) (xy 173.58917 -59.556397)
			(xy 173.533436 -59.55436) (xy 173.478593 -59.54423) (xy 173.425809 -59.526223) (xy 173.376209 -59.500722)
			(xy 173.330851 -59.468271) (xy 173.290702 -59.429562) (xy 173.256616 -59.385419) (xy 173.22932 -59.336784)
			(xy 173.209397 -59.284693) (xy 173.197271 -59.230256) (xy 173.1932 -59.174634) (xy 156.310855 -59.174634)
			(xy 156.3612 -60.01925) (xy 164.235884 -60.01925) (xy 164.235884 -59.96475) (xy 164.24364 -59.910803)
			(xy 164.258994 -59.85851) (xy 164.281635 -59.808934) (xy 164.3111 -59.763085) (xy 164.34679 -59.721895)
			(xy 164.387978 -59.686204) (xy 164.433827 -59.656738) (xy 164.483403 -59.634097) (xy 164.535696 -59.618742)
			(xy 164.589642 -59.610984) (xy 164.616892 -59.610498) (xy 164.644262 -59.610969) (xy 164.698441 -59.618786)
			(xy 164.750944 -59.634274) (xy 164.800691 -59.657114) (xy 164.846658 -59.686837) (xy 164.86759 -59.704478)
			(xy 164.867844 -59.704732) (xy 164.87494 -59.710305) (xy 164.89185 -59.716559) (xy 164.900864 -59.716924)
			(xy 164.96792 -59.716924) (xy 164.976937 -59.716572) (xy 164.993854 -59.71032) (xy 165.00094 -59.704732)
			(xy 165.00094 -59.704478) (xy 165.001194 -59.704478) (xy 165.022127 -59.686837) (xy 165.068095 -59.657113)
			(xy 165.117841 -59.634267) (xy 165.170343 -59.618771) (xy 165.224521 -59.610942) (xy 165.279263 -59.610942)
			(xy 165.333441 -59.618771) (xy 165.385943 -59.634267) (xy 165.435689 -59.657113) (xy 165.481657 -59.686837)
			(xy 165.50259 -59.704478) (xy 165.502844 -59.704732) (xy 165.50994 -59.710305) (xy 165.52685 -59.716559)
			(xy 165.535864 -59.716924) (xy 165.60292 -59.716924) (xy 165.611937 -59.716572) (xy 165.628854 -59.71032)
			(xy 165.63594 -59.704732) (xy 165.63594 -59.704478) (xy 165.636194 -59.704478) (xy 165.657115 -59.686825)
			(xy 165.703091 -59.657116) (xy 165.752841 -59.634283) (xy 165.805344 -59.618795) (xy 165.859522 -59.61097)
			(xy 165.886892 -59.610498) (xy 165.914146 -59.610949) (xy 165.968098 -59.618705) (xy 166.020398 -59.634061)
			(xy 166.06998 -59.656703) (xy 166.115835 -59.686171) (xy 166.157029 -59.721865) (xy 166.192724 -59.763059)
			(xy 166.222193 -59.808913) (xy 166.244837 -59.858495) (xy 166.260193 -59.910794) (xy 166.267951 -59.964746)
			(xy 166.267951 -60.019254) (xy 166.260193 -60.073206) (xy 166.244837 -60.125505) (xy 166.222193 -60.175087)
			(xy 166.192724 -60.220941) (xy 166.157029 -60.262135) (xy 166.115835 -60.297829) (xy 166.06998 -60.327297)
			(xy 166.020398 -60.349939) (xy 165.968098 -60.365295) (xy 165.914146 -60.373051) (xy 165.886892 -60.373514)
			(xy 165.859522 -60.373049) (xy 165.805343 -60.365231) (xy 165.75284 -60.349741) (xy 165.703093 -60.326899)
			(xy 165.657126 -60.297175) (xy 165.636194 -60.279534) (xy 165.63594 -60.27928) (xy 165.628848 -60.273702)
			(xy 165.611935 -60.267451) (xy 165.60292 -60.267088) (xy 165.535864 -60.267088) (xy 165.526846 -60.26743)
			(xy 165.509929 -60.273688) (xy 165.502844 -60.27928) (xy 165.50259 -60.279534) (xy 165.481657 -60.297175)
			(xy 165.435689 -60.326899) (xy 165.385943 -60.349745) (xy 165.333441 -60.365241) (xy 165.279263 -60.37307)
			(xy 165.224521 -60.37307) (xy 165.170343 -60.365241) (xy 165.117841 -60.349745) (xy 165.068095 -60.326899)
			(xy 165.022127 -60.297175) (xy 165.001194 -60.279534) (xy 165.00094 -60.27928) (xy 164.993848 -60.273702)
			(xy 164.976935 -60.267451) (xy 164.96792 -60.267088) (xy 164.900864 -60.267088) (xy 164.891846 -60.26743)
			(xy 164.874929 -60.273688) (xy 164.867844 -60.27928) (xy 164.867844 -60.279534) (xy 164.86759 -60.279534)
			(xy 164.846677 -60.297197) (xy 164.800698 -60.326904) (xy 164.750946 -60.349735) (xy 164.698441 -60.36522)
			(xy 164.644262 -60.373043) (xy 164.616892 -60.373514) (xy 164.589642 -60.373016) (xy 164.535696 -60.365258)
			(xy 164.483403 -60.349903) (xy 164.433827 -60.327262) (xy 164.387978 -60.297796) (xy 164.34679 -60.262105)
			(xy 164.3111 -60.220915) (xy 164.281635 -60.175066) (xy 164.258994 -60.12549) (xy 164.24364 -60.073197)
			(xy 164.235884 -60.01925) (xy 156.3612 -60.01925) (xy 156.397805 -60.633356) (xy 175.89703 -60.633356)
			(xy 175.901101 -60.577734) (xy 175.913227 -60.523297) (xy 175.93315 -60.471206) (xy 175.960446 -60.422571)
			(xy 175.994532 -60.378428) (xy 176.034681 -60.339719) (xy 176.080039 -60.307268) (xy 176.129639 -60.281767)
			(xy 176.182423 -60.26376) (xy 176.237266 -60.25363) (xy 176.293 -60.251593) (xy 176.348437 -60.257693)
			(xy 176.402394 -60.271799) (xy 176.453723 -60.293611) (xy 176.501329 -60.322665) (xy 176.544197 -60.35834)
			(xy 176.581414 -60.399877) (xy 176.612187 -60.44639) (xy 176.635859 -60.496887) (xy 176.651927 -60.550294)
			(xy 176.660047 -60.60547) (xy 176.660556 -60.633356) (xy 176.660047 -60.661242) (xy 176.651927 -60.716418)
			(xy 176.635859 -60.769825) (xy 176.612187 -60.820322) (xy 176.581414 -60.866835) (xy 176.544197 -60.908372)
			(xy 176.501329 -60.944047) (xy 176.453723 -60.973101) (xy 176.402394 -60.994913) (xy 176.348437 -61.009019)
			(xy 176.293 -61.015119) (xy 176.237266 -61.013082) (xy 176.182423 -61.002952) (xy 176.129639 -60.984945)
			(xy 176.080039 -60.959444) (xy 176.034681 -60.926993) (xy 175.994532 -60.888284) (xy 175.960446 -60.844141)
			(xy 175.93315 -60.795506) (xy 175.913227 -60.743415) (xy 175.901101 -60.688978) (xy 175.89703 -60.633356)
			(xy 156.397805 -60.633356) (xy 156.448736 -61.487812) (xy 174.404526 -61.487812) (xy 174.408597 -61.43219)
			(xy 174.420723 -61.377753) (xy 174.440646 -61.325662) (xy 174.467942 -61.277027) (xy 174.502028 -61.232884)
			(xy 174.542177 -61.194175) (xy 174.587535 -61.161724) (xy 174.637135 -61.136223) (xy 174.689919 -61.118216)
			(xy 174.744762 -61.108086) (xy 174.800496 -61.106049) (xy 174.855933 -61.112149) (xy 174.90989 -61.126255)
			(xy 174.961219 -61.148067) (xy 175.008825 -61.177121) (xy 175.051693 -61.212796) (xy 175.08891 -61.254333)
			(xy 175.119683 -61.300846) (xy 175.143355 -61.351343) (xy 175.159423 -61.40475) (xy 175.167543 -61.459926)
			(xy 175.168052 -61.487812) (xy 175.167543 -61.515698) (xy 175.159423 -61.570874) (xy 175.143355 -61.624281)
			(xy 175.119683 -61.674778) (xy 175.08891 -61.721291) (xy 175.051693 -61.762828) (xy 175.008825 -61.798503)
			(xy 174.961219 -61.827557) (xy 174.90989 -61.849369) (xy 174.855933 -61.863475) (xy 174.800496 -61.869575)
			(xy 174.744762 -61.867538) (xy 174.689919 -61.857408) (xy 174.637135 -61.839401) (xy 174.587535 -61.8139)
			(xy 174.542177 -61.781449) (xy 174.502028 -61.74274) (xy 174.467942 -61.698597) (xy 174.440646 -61.649962)
			(xy 174.420723 -61.597871) (xy 174.408597 -61.543434) (xy 174.404526 -61.487812) (xy 156.448736 -61.487812)
			(xy 156.483558 -62.072012) (xy 156.484932 -62.121034) (xy 172.3423 -62.121034) (xy 172.346371 -62.065412)
			(xy 172.358497 -62.010975) (xy 172.37842 -61.958884) (xy 172.405716 -61.910249) (xy 172.439802 -61.866106)
			(xy 172.479951 -61.827397) (xy 172.525309 -61.794946) (xy 172.574909 -61.769445) (xy 172.627693 -61.751438)
			(xy 172.682536 -61.741308) (xy 172.73827 -61.739271) (xy 172.793707 -61.745371) (xy 172.847664 -61.759477)
			(xy 172.898993 -61.781289) (xy 172.946599 -61.810343) (xy 172.989467 -61.846018) (xy 173.026684 -61.887555)
			(xy 173.057457 -61.934068) (xy 173.081129 -61.984565) (xy 173.097197 -62.037972) (xy 173.105317 -62.093148)
			(xy 173.105826 -62.121034) (xy 173.105317 -62.14892) (xy 173.097197 -62.204096) (xy 173.081129 -62.257503)
			(xy 173.057457 -62.308) (xy 173.026684 -62.354513) (xy 172.989467 -62.39605) (xy 172.946599 -62.431725)
			(xy 172.898993 -62.460779) (xy 172.847664 -62.482591) (xy 172.793707 -62.496697) (xy 172.73827 -62.502797)
			(xy 172.682536 -62.50076) (xy 172.627693 -62.49063) (xy 172.574909 -62.472623) (xy 172.525309 -62.447122)
			(xy 172.479951 -62.414671) (xy 172.439802 -62.375962) (xy 172.405716 -62.331819) (xy 172.37842 -62.283184)
			(xy 172.358497 -62.231093) (xy 172.346371 -62.176656) (xy 172.3423 -62.121034) (xy 156.484932 -62.121034)
			(xy 156.485082 -62.126368) (xy 156.489654 -63.024004) (xy 156.489654 -63.02502) (xy 156.490924 -63.07455)
			(xy 156.490924 -63.075058) (xy 156.490162 -63.110872) (xy 156.490162 -63.11392) (xy 156.489908 -63.114936)
			(xy 156.490394 -63.213552) (xy 164.220865 -63.213552) (xy 164.220865 -63.159048) (xy 164.228622 -63.105098)
			(xy 164.243978 -63.052801) (xy 164.266621 -63.003221) (xy 164.296088 -62.957369) (xy 164.331782 -62.916177)
			(xy 164.372974 -62.880485) (xy 164.418827 -62.851018) (xy 164.468406 -62.828376) (xy 164.520703 -62.813021)
			(xy 164.574654 -62.805265) (xy 164.601906 -62.804802) (xy 164.629276 -62.805264) (xy 164.683456 -62.813083)
			(xy 164.735959 -62.828573) (xy 164.785706 -62.851415) (xy 164.831672 -62.881141) (xy 164.852604 -62.898782)
			(xy 164.852858 -62.899036) (xy 164.859949 -62.904615) (xy 164.876863 -62.910865) (xy 164.885878 -62.911228)
			(xy 164.952934 -62.911228) (xy 164.961952 -62.910881) (xy 164.978868 -62.904626) (xy 164.985954 -62.899036)
			(xy 164.985954 -62.898782) (xy 164.986208 -62.898782) (xy 165.007141 -62.881141) (xy 165.053109 -62.851417)
			(xy 165.102855 -62.828571) (xy 165.155357 -62.813075) (xy 165.209535 -62.805246) (xy 165.264277 -62.805246)
			(xy 165.318455 -62.813075) (xy 165.370957 -62.828571) (xy 165.420703 -62.851417) (xy 165.466671 -62.881141)
			(xy 165.487604 -62.898782) (xy 165.487858 -62.899036) (xy 165.494949 -62.904615) (xy 165.511863 -62.910865)
			(xy 165.520878 -62.911228) (xy 165.587934 -62.911228) (xy 165.596952 -62.910881) (xy 165.613868 -62.904626)
			(xy 165.620954 -62.899036) (xy 165.620954 -62.898782) (xy 165.621208 -62.898782) (xy 165.642124 -62.881123)
			(xy 165.688101 -62.851415) (xy 165.737853 -62.828583) (xy 165.790357 -62.813096) (xy 165.844536 -62.805273)
			(xy 165.871906 -62.804802) (xy 165.899158 -62.805268) (xy 165.953106 -62.813026) (xy 166.005402 -62.828382)
			(xy 166.054979 -62.851024) (xy 166.10083 -62.880491) (xy 166.142021 -62.916183) (xy 166.177713 -62.957375)
			(xy 166.207179 -63.003226) (xy 166.22982 -63.052804) (xy 166.239636 -63.086234) (xy 169.515026 -63.086234)
			(xy 169.519097 -63.030612) (xy 169.531223 -62.976175) (xy 169.551146 -62.924084) (xy 169.578442 -62.875449)
			(xy 169.612528 -62.831306) (xy 169.652677 -62.792597) (xy 169.698035 -62.760146) (xy 169.747635 -62.734645)
			(xy 169.800419 -62.716638) (xy 169.855262 -62.706508) (xy 169.910996 -62.704471) (xy 169.966433 -62.710571)
			(xy 170.02039 -62.724677) (xy 170.071719 -62.746489) (xy 170.119325 -62.775543) (xy 170.162193 -62.811218)
			(xy 170.19941 -62.852755) (xy 170.230183 -62.899268) (xy 170.253855 -62.949765) (xy 170.269923 -63.003172)
			(xy 170.278043 -63.058348) (xy 170.278552 -63.086234) (xy 170.278043 -63.11412) (xy 170.269923 -63.169296)
			(xy 170.253855 -63.222703) (xy 170.230183 -63.2732) (xy 170.23003 -63.273432) (xy 171.67682 -63.273432)
			(xy 171.680891 -63.21781) (xy 171.693017 -63.163373) (xy 171.71294 -63.111282) (xy 171.740236 -63.062647)
			(xy 171.774322 -63.018504) (xy 171.814471 -62.979795) (xy 171.859829 -62.947344) (xy 171.909429 -62.921843)
			(xy 171.962213 -62.903836) (xy 172.017056 -62.893706) (xy 172.07279 -62.891669) (xy 172.128227 -62.897769)
			(xy 172.182184 -62.911875) (xy 172.233513 -62.933687) (xy 172.281119 -62.962741) (xy 172.323987 -62.998416)
			(xy 172.361204 -63.039953) (xy 172.391977 -63.086466) (xy 172.415649 -63.136963) (xy 172.431717 -63.19037)
			(xy 172.439837 -63.245546) (xy 172.440346 -63.273432) (xy 172.439837 -63.301318) (xy 172.431717 -63.356494)
			(xy 172.415649 -63.409901) (xy 172.391977 -63.460398) (xy 172.361204 -63.506911) (xy 172.323987 -63.548448)
			(xy 172.281119 -63.584123) (xy 172.233513 -63.613177) (xy 172.182184 -63.634989) (xy 172.128227 -63.649095)
			(xy 172.07279 -63.655195) (xy 172.017056 -63.653158) (xy 171.962213 -63.643028) (xy 171.909429 -63.625021)
			(xy 171.859829 -63.59952) (xy 171.814471 -63.567069) (xy 171.774322 -63.52836) (xy 171.740236 -63.484217)
			(xy 171.71294 -63.435582) (xy 171.693017 -63.383491) (xy 171.680891 -63.329054) (xy 171.67682 -63.273432)
			(xy 170.23003 -63.273432) (xy 170.19941 -63.319713) (xy 170.162193 -63.36125) (xy 170.119325 -63.396925)
			(xy 170.071719 -63.425979) (xy 170.02039 -63.447791) (xy 169.966433 -63.461897) (xy 169.910996 -63.467997)
			(xy 169.855262 -63.46596) (xy 169.800419 -63.45583) (xy 169.747635 -63.437823) (xy 169.698035 -63.412322)
			(xy 169.652677 -63.379871) (xy 169.612528 -63.341162) (xy 169.578442 -63.297019) (xy 169.551146 -63.248384)
			(xy 169.531223 -63.196293) (xy 169.519097 -63.141856) (xy 169.515026 -63.086234) (xy 166.239636 -63.086234)
			(xy 166.245176 -63.1051) (xy 166.252932 -63.159048) (xy 166.252932 -63.213552) (xy 166.245176 -63.2675)
			(xy 166.22982 -63.319796) (xy 166.207179 -63.369374) (xy 166.177713 -63.415225) (xy 166.142021 -63.456417)
			(xy 166.10083 -63.492109) (xy 166.054979 -63.521576) (xy 166.005402 -63.544218) (xy 165.953106 -63.559574)
			(xy 165.899158 -63.567332) (xy 165.871906 -63.567818) (xy 165.844535 -63.567368) (xy 165.790354 -63.55955)
			(xy 165.73785 -63.544058) (xy 165.688104 -63.521212) (xy 165.642138 -63.491482) (xy 165.621208 -63.473838)
			(xy 165.620954 -63.473584) (xy 165.613857 -63.468012) (xy 165.596948 -63.461757) (xy 165.587934 -63.461392)
			(xy 165.520878 -63.461392) (xy 165.51186 -63.46174) (xy 165.494944 -63.467994) (xy 165.487858 -63.473584)
			(xy 165.487604 -63.473838) (xy 165.466671 -63.491479) (xy 165.420703 -63.521203) (xy 165.370957 -63.544049)
			(xy 165.318455 -63.559545) (xy 165.264277 -63.567374) (xy 165.209535 -63.567374) (xy 165.155357 -63.559545)
			(xy 165.102855 -63.544049) (xy 165.053109 -63.521203) (xy 165.007141 -63.491479) (xy 164.986208 -63.473838)
			(xy 164.985954 -63.473584) (xy 164.978857 -63.468012) (xy 164.961948 -63.461757) (xy 164.952934 -63.461392)
			(xy 164.885878 -63.461392) (xy 164.87686 -63.46174) (xy 164.859944 -63.467994) (xy 164.852858 -63.473584)
			(xy 164.852858 -63.473838) (xy 164.852604 -63.473838) (xy 164.831686 -63.491495) (xy 164.785709 -63.521203)
			(xy 164.735958 -63.544035) (xy 164.683454 -63.559522) (xy 164.629276 -63.567346) (xy 164.601906 -63.567818)
			(xy 164.574654 -63.567335) (xy 164.520703 -63.559579) (xy 164.468406 -63.544224) (xy 164.418827 -63.521582)
			(xy 164.372974 -63.492115) (xy 164.331782 -63.456423) (xy 164.296088 -63.415231) (xy 164.266621 -63.369379)
			(xy 164.243978 -63.319799) (xy 164.228622 -63.267502) (xy 164.220865 -63.213552) (xy 156.490394 -63.213552)
			(xy 156.495805 -64.312292) (xy 175.005998 -64.312292) (xy 175.010069 -64.25667) (xy 175.022195 -64.202233)
			(xy 175.042118 -64.150142) (xy 175.069414 -64.101507) (xy 175.1035 -64.057364) (xy 175.143649 -64.018655)
			(xy 175.189007 -63.986204) (xy 175.238607 -63.960703) (xy 175.291391 -63.942696) (xy 175.346234 -63.932566)
			(xy 175.401968 -63.930529) (xy 175.457405 -63.936629) (xy 175.511362 -63.950735) (xy 175.562691 -63.972547)
			(xy 175.610297 -64.001601) (xy 175.653165 -64.037276) (xy 175.690382 -64.078813) (xy 175.721155 -64.125326)
			(xy 175.744827 -64.175823) (xy 175.760895 -64.22923) (xy 175.769015 -64.284406) (xy 175.769524 -64.312292)
			(xy 175.769015 -64.340178) (xy 175.760895 -64.395354) (xy 175.744827 -64.448761) (xy 175.721155 -64.499258)
			(xy 175.690382 -64.545771) (xy 175.653165 -64.587308) (xy 175.610297 -64.622983) (xy 175.562691 -64.652037)
			(xy 175.511362 -64.673849) (xy 175.457405 -64.687955) (xy 175.401968 -64.694055) (xy 175.346234 -64.692018)
			(xy 175.291391 -64.681888) (xy 175.238607 -64.663881) (xy 175.189007 -64.63838) (xy 175.143649 -64.605929)
			(xy 175.1035 -64.56722) (xy 175.069414 -64.523077) (xy 175.042118 -64.474442) (xy 175.022195 -64.422351)
			(xy 175.010069 -64.367914) (xy 175.005998 -64.312292) (xy 156.495805 -64.312292) (xy 156.499689 -65.100962)
			(xy 162.232592 -65.100962) (xy 162.236663 -65.04534) (xy 162.248789 -64.990903) (xy 162.268712 -64.938812)
			(xy 162.296008 -64.890177) (xy 162.330094 -64.846034) (xy 162.370243 -64.807325) (xy 162.415601 -64.774874)
			(xy 162.465201 -64.749373) (xy 162.517985 -64.731366) (xy 162.572828 -64.721236) (xy 162.628562 -64.719199)
			(xy 162.683999 -64.725299) (xy 162.737956 -64.739405) (xy 162.789285 -64.761217) (xy 162.836891 -64.790271)
			(xy 162.879759 -64.825946) (xy 162.916976 -64.867483) (xy 162.947749 -64.913996) (xy 162.971421 -64.964493)
			(xy 162.987489 -65.0179) (xy 162.995609 -65.073076) (xy 162.996118 -65.100962) (xy 162.995609 -65.128848)
			(xy 162.987489 -65.184024) (xy 162.971421 -65.237431) (xy 162.947749 -65.287928) (xy 162.916976 -65.334441)
			(xy 162.879759 -65.375978) (xy 162.836891 -65.411653) (xy 162.789285 -65.440707) (xy 162.737956 -65.462519)
			(xy 162.683999 -65.476625) (xy 162.628562 -65.482725) (xy 162.572828 -65.480688) (xy 162.517985 -65.470558)
			(xy 162.465201 -65.452551) (xy 162.415601 -65.42705) (xy 162.370243 -65.394599) (xy 162.330094 -65.35589)
			(xy 162.296008 -65.311747) (xy 162.268712 -65.263112) (xy 162.248789 -65.211021) (xy 162.236663 -65.156584)
			(xy 162.232592 -65.100962) (xy 156.499689 -65.100962) (xy 156.50083 -65.33261) (xy 156.502305 -65.344471)
			(xy 156.5145 -65.364991) (xy 156.524198 -65.37198) (xy 156.601922 -65.418208) (xy 156.607474 -65.421083)
			(xy 156.619551 -65.424304) (xy 156.625798 -65.424558) (xy 156.644086 -65.419986) (xy 156.654754 -65.415922)
			(xy 156.681795 -65.402729) (xy 156.738994 -65.384072) (xy 156.798408 -65.374602) (xy 156.82849 -65.374012)
			(xy 156.832046 -65.374012) (xy 156.859145 -65.374718) (xy 156.912741 -65.382848) (xy 156.964646 -65.398482)
			(xy 157.013815 -65.421307) (xy 157.059259 -65.450862) (xy 157.100061 -65.486551) (xy 157.1354 -65.527658)
			(xy 157.164565 -65.573352) (xy 157.186968 -65.622715) (xy 157.202157 -65.674752) (xy 157.209828 -65.728416)
			(xy 157.210252 -65.75552) (xy 157.209765 -65.782771) (xy 157.202006 -65.836719) (xy 157.18665 -65.889014)
			(xy 157.164008 -65.938592) (xy 157.134542 -65.984443) (xy 157.098851 -66.025634) (xy 157.057662 -66.061328)
			(xy 157.011813 -66.090797) (xy 156.962237 -66.113441) (xy 156.909943 -66.128801) (xy 156.855995 -66.136563)
			(xy 156.828744 -66.137028) (xy 156.827982 -66.137028) (xy 156.797751 -66.13643) (xy 156.738055 -66.126843)
			(xy 156.680623 -66.107943) (xy 156.653484 -66.09461) (xy 156.65323 -66.094356) (xy 156.652976 -66.094102)
			(xy 156.647195 -66.091373) (xy 156.634731 -66.088543) (xy 156.628338 -66.088514) (xy 156.614876 -66.089022)
			(xy 156.529024 -66.141346) (xy 156.521789 -66.14623) (xy 156.510873 -66.159835) (xy 156.505141 -66.17631)
			(xy 156.504894 -66.185034) (xy 156.505656 -66.37274) (xy 156.50591 -66.402458) (xy 156.50718 -66.685668)
			(xy 156.508641 -66.697339) (xy 156.520539 -66.717599) (xy 156.53004 -66.72453) (xy 156.53258 -66.726054)
			(xy 156.545026 -66.733166) (xy 156.597604 -66.763392) (xy 156.603481 -66.766537) (xy 156.616343 -66.770017)
			(xy 156.623004 -66.77025) (xy 156.658564 -66.77025) (xy 156.668216 -66.76517) (xy 156.69602 -66.751038)
			(xy 156.755082 -66.731009) (xy 156.816612 -66.720835) (xy 156.847794 -66.720212) (xy 156.873838 -66.720675)
			(xy 156.925437 -66.727798) (xy 156.975587 -66.741872) (xy 157.023358 -66.762636) (xy 157.067862 -66.789703)
			(xy 157.088332 -66.80581) (xy 157.089348 -66.806318) (xy 157.092142 -66.808604) (xy 157.108144 -66.814192)
			(xy 157.149546 -66.814192) (xy 157.149546 -66.826638) (xy 157.199076 -66.826638) (xy 157.203902 -66.826384)
			(xy 157.211314 -66.825416) (xy 157.225132 -66.819736) (xy 157.23108 -66.815208) (xy 157.232096 -66.814192)
			(xy 157.253027 -66.79655) (xy 157.298994 -66.766824) (xy 157.348741 -66.743981) (xy 157.401244 -66.728491)
			(xy 157.455424 -66.720672) (xy 157.482794 -66.720212) (xy 157.510046 -66.720675) (xy 157.563994 -66.728431)
			(xy 157.61629 -66.743785) (xy 157.665869 -66.766426) (xy 157.71172 -66.795893) (xy 157.752911 -66.831584)
			(xy 157.788604 -66.872775) (xy 157.818071 -66.918626) (xy 157.840712 -66.968204) (xy 157.856068 -67.0205)
			(xy 157.863825 -67.074448) (xy 157.863825 -67.128952) (xy 157.856068 -67.1829) (xy 157.840712 -67.235196)
			(xy 157.818071 -67.284774) (xy 157.788604 -67.330625) (xy 157.752911 -67.371816) (xy 157.71172 -67.407507)
			(xy 157.665869 -67.436974) (xy 157.61629 -67.459615) (xy 157.563994 -67.474969) (xy 157.510046 -67.482725)
			(xy 157.482794 -67.483228) (xy 157.45675 -67.482765) (xy 157.405152 -67.475641) (xy 157.355001 -67.461566)
			(xy 157.30723 -67.440803) (xy 157.262726 -67.413738) (xy 157.242256 -67.39763) (xy 157.24124 -67.397122)
			(xy 157.238446 -67.394836) (xy 157.222444 -67.389248) (xy 157.181042 -67.389248) (xy 157.181042 -67.376802)
			(xy 157.131512 -67.376802) (xy 157.126686 -67.377056) (xy 157.119274 -67.378023) (xy 157.105453 -67.383701)
			(xy 157.099508 -67.388232) (xy 157.098492 -67.389248) (xy 157.077562 -67.406892) (xy 157.031596 -67.436621)
			(xy 156.981849 -67.459466) (xy 156.929345 -67.474957) (xy 156.875165 -67.482776) (xy 156.847794 -67.483228)
			(xy 156.84754 -67.483228) (xy 156.815923 -67.482581) (xy 156.753559 -67.472113) (xy 156.69377 -67.45152)
			(xy 156.665676 -67.437) (xy 156.66212 -67.435222) (xy 156.654552 -67.431326) (xy 156.637808 -67.428315)
			(xy 156.621008 -67.430991) (xy 156.613352 -67.434714) (xy 156.534612 -67.48145) (xy 156.527652 -67.486343)
			(xy 156.526321 -67.488054) (xy 160.87928 -67.488054) (xy 160.883351 -67.432432) (xy 160.895477 -67.377995)
			(xy 160.9154 -67.325904) (xy 160.942696 -67.277269) (xy 160.976782 -67.233126) (xy 161.016931 -67.194417)
			(xy 161.062289 -67.161966) (xy 161.111889 -67.136465) (xy 161.164673 -67.118458) (xy 161.219516 -67.108328)
			(xy 161.27525 -67.106291) (xy 161.330687 -67.112391) (xy 161.384644 -67.126497) (xy 161.435973 -67.148309)
			(xy 161.483579 -67.177363) (xy 161.526447 -67.213038) (xy 161.563664 -67.254575) (xy 161.594437 -67.301088)
			(xy 161.618109 -67.351585) (xy 161.634177 -67.404992) (xy 161.642297 -67.460168) (xy 161.642806 -67.488054)
			(xy 161.642297 -67.51594) (xy 161.639112 -67.537584) (xy 162.171378 -67.537584) (xy 162.175449 -67.481962)
			(xy 162.187575 -67.427525) (xy 162.207498 -67.375434) (xy 162.234794 -67.326799) (xy 162.26888 -67.282656)
			(xy 162.309029 -67.243947) (xy 162.354387 -67.211496) (xy 162.403987 -67.185995) (xy 162.456771 -67.167988)
			(xy 162.511614 -67.157858) (xy 162.567348 -67.155821) (xy 162.622785 -67.161921) (xy 162.676742 -67.176027)
			(xy 162.728071 -67.197839) (xy 162.775677 -67.226893) (xy 162.818545 -67.262568) (xy 162.855762 -67.304105)
			(xy 162.886535 -67.350618) (xy 162.910207 -67.401115) (xy 162.926275 -67.454522) (xy 162.934395 -67.509698)
			(xy 162.934904 -67.537584) (xy 162.934395 -67.56547) (xy 162.93035 -67.592956) (xy 163.445442 -67.592956)
			(xy 163.449513 -67.537334) (xy 163.461639 -67.482897) (xy 163.481562 -67.430806) (xy 163.508858 -67.382171)
			(xy 163.542944 -67.338028) (xy 163.583093 -67.299319) (xy 163.628451 -67.266868) (xy 163.678051 -67.241367)
			(xy 163.730835 -67.22336) (xy 163.785678 -67.21323) (xy 163.841412 -67.211193) (xy 163.896849 -67.217293)
			(xy 163.950806 -67.231399) (xy 164.002135 -67.253211) (xy 164.049741 -67.282265) (xy 164.092609 -67.31794)
			(xy 164.129826 -67.359477) (xy 164.160599 -67.40599) (xy 164.184271 -67.456487) (xy 164.200339 -67.509894)
			(xy 164.208456 -67.565048) (xy 166.546816 -67.565048) (xy 166.546816 -67.510552) (xy 166.554571 -67.456611)
			(xy 166.569924 -67.404323) (xy 166.592562 -67.354752) (xy 166.622024 -67.308907) (xy 166.65771 -67.267721)
			(xy 166.698894 -67.232033) (xy 166.744738 -67.20257) (xy 166.794308 -67.17993) (xy 166.846596 -67.164575)
			(xy 166.900536 -67.156817) (xy 166.927784 -67.15633) (xy 166.955154 -67.156798) (xy 167.009334 -67.164614)
			(xy 167.061837 -67.180103) (xy 167.111584 -67.202944) (xy 167.157551 -67.232669) (xy 167.178482 -67.25031)
			(xy 167.178736 -67.250564) (xy 167.185831 -67.256137) (xy 167.202742 -67.26239) (xy 167.211756 -67.262756)
			(xy 167.278812 -67.262756) (xy 167.287831 -67.262414) (xy 167.304748 -67.256157) (xy 167.311832 -67.250564)
			(xy 167.311832 -67.25031) (xy 167.312086 -67.25031) (xy 167.333014 -67.232666) (xy 167.378988 -67.202954)
			(xy 167.428736 -67.180119) (xy 167.481238 -67.164629) (xy 167.535415 -67.156803) (xy 167.562784 -67.15633)
			(xy 167.59004 -67.156716) (xy 167.643998 -67.164472) (xy 167.696303 -67.179828) (xy 167.745891 -67.202472)
			(xy 167.79175 -67.231942) (xy 167.832949 -67.26764) (xy 167.868648 -67.308837) (xy 167.898121 -67.354695)
			(xy 167.920766 -67.404282) (xy 167.936125 -67.456586) (xy 167.943883 -67.510544) (xy 167.943883 -67.565056)
			(xy 167.936125 -67.619014) (xy 167.920766 -67.671318) (xy 167.898121 -67.720905) (xy 167.868648 -67.766763)
			(xy 167.832949 -67.80796) (xy 167.79175 -67.843658) (xy 167.745891 -67.873128) (xy 167.696303 -67.895772)
			(xy 167.643998 -67.911128) (xy 167.59004 -67.918884) (xy 167.562784 -67.919346) (xy 167.535413 -67.918902)
			(xy 167.481232 -67.911081) (xy 167.428728 -67.895588) (xy 167.378982 -67.872741) (xy 167.333016 -67.84301)
			(xy 167.312086 -67.825366) (xy 167.311832 -67.825112) (xy 167.304739 -67.819534) (xy 167.287827 -67.813282)
			(xy 167.278812 -67.81292) (xy 167.211756 -67.81292) (xy 167.202741 -67.8133) (xy 167.185824 -67.819531)
			(xy 167.178736 -67.825112) (xy 167.178736 -67.825366) (xy 167.178482 -67.825366) (xy 167.157525 -67.842975)
			(xy 167.11156 -67.872692) (xy 167.061819 -67.895535) (xy 167.009323 -67.911033) (xy 166.955152 -67.918868)
			(xy 166.927784 -67.919346) (xy 166.900536 -67.918783) (xy 166.846596 -67.911025) (xy 166.794308 -67.89567)
			(xy 166.744738 -67.87303) (xy 166.698894 -67.843567) (xy 166.65771 -67.807879) (xy 166.622024 -67.766693)
			(xy 166.592562 -67.720848) (xy 166.569924 -67.671277) (xy 166.554571 -67.618989) (xy 166.546816 -67.565048)
			(xy 164.208456 -67.565048) (xy 164.208459 -67.56507) (xy 164.208968 -67.592956) (xy 164.208459 -67.620842)
			(xy 164.200339 -67.676018) (xy 164.184271 -67.729425) (xy 164.160599 -67.779922) (xy 164.129826 -67.826435)
			(xy 164.092609 -67.867972) (xy 164.049741 -67.903647) (xy 164.002135 -67.932701) (xy 163.950806 -67.954513)
			(xy 163.896849 -67.968619) (xy 163.841412 -67.974719) (xy 163.785678 -67.972682) (xy 163.730835 -67.962552)
			(xy 163.678051 -67.944545) (xy 163.628451 -67.919044) (xy 163.583093 -67.886593) (xy 163.542944 -67.847884)
			(xy 163.508858 -67.803741) (xy 163.481562 -67.755106) (xy 163.461639 -67.703015) (xy 163.449513 -67.648578)
			(xy 163.445442 -67.592956) (xy 162.93035 -67.592956) (xy 162.926275 -67.620646) (xy 162.910207 -67.674053)
			(xy 162.886535 -67.72455) (xy 162.855762 -67.771063) (xy 162.818545 -67.8126) (xy 162.775677 -67.848275)
			(xy 162.728071 -67.877329) (xy 162.676742 -67.899141) (xy 162.622785 -67.913247) (xy 162.567348 -67.919347)
			(xy 162.511614 -67.91731) (xy 162.456771 -67.90718) (xy 162.403987 -67.889173) (xy 162.354387 -67.863672)
			(xy 162.309029 -67.831221) (xy 162.26888 -67.792512) (xy 162.234794 -67.748369) (xy 162.207498 -67.699734)
			(xy 162.187575 -67.647643) (xy 162.175449 -67.593206) (xy 162.171378 -67.537584) (xy 161.639112 -67.537584)
			(xy 161.634177 -67.571116) (xy 161.618109 -67.624523) (xy 161.594437 -67.67502) (xy 161.563664 -67.721533)
			(xy 161.526447 -67.76307) (xy 161.483579 -67.798745) (xy 161.435973 -67.827799) (xy 161.384644 -67.849611)
			(xy 161.330687 -67.863717) (xy 161.27525 -67.869817) (xy 161.219516 -67.86778) (xy 161.164673 -67.85765)
			(xy 161.111889 -67.839643) (xy 161.062289 -67.814142) (xy 161.016931 -67.781691) (xy 160.976782 -67.742982)
			(xy 160.942696 -67.698839) (xy 160.9154 -67.650204) (xy 160.895477 -67.598113) (xy 160.883351 -67.543676)
			(xy 160.87928 -67.488054) (xy 156.526321 -67.488054) (xy 156.517215 -67.499764) (xy 156.511774 -67.515872)
			(xy 156.511498 -67.524376) (xy 156.516635 -68.586604) (xy 158.725362 -68.586604) (xy 158.725815 -68.559233)
			(xy 158.733634 -68.505053) (xy 158.749125 -68.452549) (xy 158.77197 -68.402802) (xy 158.801699 -68.356837)
			(xy 158.819342 -68.335906) (xy 158.819596 -68.335652) (xy 158.825167 -68.328554) (xy 158.831423 -68.311646)
			(xy 158.831788 -68.302632) (xy 158.831788 -68.235576) (xy 158.831445 -68.226558) (xy 158.825188 -68.209641)
			(xy 158.819596 -68.202556) (xy 158.819342 -68.202556) (xy 158.819342 -68.202302) (xy 158.801697 -68.181375)
			(xy 158.771985 -68.135401) (xy 158.749149 -68.085653) (xy 158.73366 -68.033151) (xy 158.725834 -67.978974)
			(xy 158.725362 -67.951604) (xy 158.725881 -67.924354) (xy 158.733637 -67.870409) (xy 158.74899 -67.818117)
			(xy 158.771628 -67.768542) (xy 158.801091 -67.722693) (xy 158.836779 -67.681503) (xy 158.877966 -67.645812)
			(xy 158.923812 -67.616345) (xy 158.973385 -67.593702) (xy 159.025676 -67.578344) (xy 159.07962 -67.570584)
			(xy 159.10687 -67.570096) (xy 159.133185 -67.570518) (xy 159.185316 -67.577762) (xy 159.235959 -67.59209)
			(xy 159.284158 -67.613231) (xy 159.329001 -67.640785) (xy 159.369639 -67.674231) (xy 159.387794 -67.693286)
			(xy 159.395318 -67.700685) (xy 159.414596 -67.709211) (xy 159.425132 -67.709796) (xy 159.499808 -67.709796)
			(xy 159.51036 -67.709286) (xy 159.529655 -67.700738) (xy 159.537146 -67.693286) (xy 159.555283 -67.674212)
			(xy 159.595917 -67.640757) (xy 159.640762 -67.613201) (xy 159.688966 -67.592066) (xy 159.739616 -67.577752)
			(xy 159.791753 -67.570532) (xy 159.81807 -67.570096) (xy 159.84544 -67.570581) (xy 159.899618 -67.578394)
			(xy 159.952121 -67.593879) (xy 160.001868 -67.616716) (xy 160.047836 -67.646437) (xy 160.068768 -67.664076)
			(xy 160.069022 -67.66433) (xy 160.076096 -67.669935) (xy 160.093022 -67.67617) (xy 160.102042 -67.676522)
			(xy 160.169098 -67.676522) (xy 160.178114 -67.676159) (xy 160.195031 -67.669915) (xy 160.202118 -67.66433)
			(xy 160.202118 -67.664076) (xy 160.202372 -67.664076) (xy 160.223301 -67.646433) (xy 160.269275 -67.616722)
			(xy 160.319023 -67.593888) (xy 160.371524 -67.578397) (xy 160.425701 -67.57057) (xy 160.45307 -67.570096)
			(xy 160.480322 -67.570583) (xy 160.534273 -67.578336) (xy 160.58657 -67.593689) (xy 160.636151 -67.616328)
			(xy 160.682004 -67.645793) (xy 160.723197 -67.681484) (xy 160.758891 -67.722675) (xy 160.78836 -67.768527)
			(xy 160.811002 -67.818105) (xy 160.826358 -67.870402) (xy 160.834115 -67.924352) (xy 160.834578 -67.951604)
			(xy 160.83412 -67.978975) (xy 160.826301 -68.033154) (xy 160.81081 -68.085658) (xy 160.787967 -68.135404)
			(xy 160.75824 -68.181371) (xy 160.740598 -68.202302) (xy 160.740344 -68.202556) (xy 160.734763 -68.209646)
			(xy 160.728514 -68.22656) (xy 160.728152 -68.235576) (xy 160.728152 -68.302632) (xy 160.728482 -68.311652)
			(xy 160.734747 -68.328569) (xy 160.740344 -68.335652) (xy 160.740598 -68.335652) (xy 160.740598 -68.335906)
			(xy 160.758253 -68.356825) (xy 160.787963 -68.402802) (xy 160.810795 -68.452552) (xy 160.826283 -68.505056)
			(xy 160.834106 -68.559234) (xy 160.834578 -68.586604) (xy 160.834148 -68.613858) (xy 160.82639 -68.667812)
			(xy 160.811032 -68.720112) (xy 160.794399 -68.75653) (xy 164.270436 -68.75653) (xy 164.270911 -68.72916)
			(xy 164.278725 -68.674981) (xy 164.294212 -68.622478) (xy 164.317052 -68.572731) (xy 164.346775 -68.526764)
			(xy 164.364416 -68.505832) (xy 164.36467 -68.505578) (xy 164.37028 -68.498508) (xy 164.376511 -68.481578)
			(xy 164.376862 -68.472558) (xy 164.376862 -68.405502) (xy 164.376512 -68.396484) (xy 164.37026 -68.379567)
			(xy 164.36467 -68.372482) (xy 164.364416 -68.372482) (xy 164.364416 -68.372228) (xy 164.346779 -68.351294)
			(xy 164.317066 -68.305322) (xy 164.29423 -68.255575) (xy 164.278738 -68.203075) (xy 164.27091 -68.148899)
			(xy 164.270436 -68.12153) (xy 164.270883 -68.094276) (xy 164.278637 -68.040322) (xy 164.293992 -67.988021)
			(xy 164.316634 -67.938438) (xy 164.346103 -67.892583) (xy 164.381799 -67.851389) (xy 164.422994 -67.815695)
			(xy 164.468851 -67.786227) (xy 164.518434 -67.763587) (xy 164.570736 -67.748234) (xy 164.62469 -67.740482)
			(xy 164.651944 -67.740022) (xy 164.679313 -67.740516) (xy 164.733491 -67.748326) (xy 164.785994 -67.763808)
			(xy 164.835742 -67.786644) (xy 164.88171 -67.816363) (xy 164.902642 -67.834002) (xy 164.902896 -67.834256)
			(xy 164.909975 -67.839854) (xy 164.926898 -67.846092) (xy 164.935916 -67.846448) (xy 165.002972 -67.846448)
			(xy 165.011989 -67.846089) (xy 165.028906 -67.839844) (xy 165.035992 -67.834256) (xy 165.035992 -67.834002)
			(xy 165.036246 -67.834002) (xy 165.057188 -67.816375) (xy 165.103158 -67.786661) (xy 165.152903 -67.763823)
			(xy 165.205401 -67.748329) (xy 165.259575 -67.740498) (xy 165.286944 -67.740022) (xy 165.313259 -67.740453)
			(xy 165.36539 -67.747694) (xy 165.416033 -67.76202) (xy 165.464232 -67.783159) (xy 165.509075 -67.810712)
			(xy 165.549713 -67.844157) (xy 165.567868 -67.863212) (xy 165.575398 -67.870603) (xy 165.594672 -67.879133)
			(xy 165.605206 -67.879722) (xy 165.679882 -67.879722) (xy 165.690431 -67.87919) (xy 165.709726 -67.870656)
			(xy 165.71722 -67.863212) (xy 165.735375 -67.844156) (xy 165.776005 -67.810698) (xy 165.820845 -67.783139)
			(xy 165.869046 -67.762001) (xy 165.919694 -67.747684) (xy 165.971828 -67.74046) (xy 165.998144 -67.740022)
			(xy 166.025398 -67.740437) (xy 166.07935 -67.7482) (xy 166.131647 -67.763562) (xy 166.181227 -67.786211)
			(xy 166.227078 -67.815685) (xy 166.268269 -67.851383) (xy 166.30396 -67.892581) (xy 166.333425 -67.938438)
			(xy 166.356063 -67.988022) (xy 166.371415 -68.040323) (xy 166.379168 -68.094276) (xy 166.379652 -68.12153)
			(xy 166.379215 -68.148901) (xy 166.371392 -68.203082) (xy 166.355897 -68.255586) (xy 166.333048 -68.305333)
			(xy 166.303317 -68.351298) (xy 166.285672 -68.372228) (xy 166.285418 -68.372482) (xy 166.279835 -68.379571)
			(xy 166.273586 -68.396486) (xy 166.273226 -68.405502) (xy 166.273226 -68.472558) (xy 166.273598 -68.481574)
			(xy 166.279834 -68.498491) (xy 166.285418 -68.505578) (xy 166.285672 -68.505578) (xy 166.285672 -68.505832)
			(xy 166.303288 -68.526782) (xy 166.333005 -68.57275) (xy 166.355845 -68.622493) (xy 166.371342 -68.674989)
			(xy 166.379175 -68.729162) (xy 166.379652 -68.75653) (xy 166.37915 -68.78378) (xy 166.371391 -68.837725)
			(xy 166.356034 -68.890017) (xy 166.333393 -68.939591) (xy 166.303927 -68.985439) (xy 166.268238 -69.026628)
			(xy 166.22705 -69.062319) (xy 166.181203 -69.091786) (xy 166.13163 -69.114429) (xy 166.079339 -69.129788)
			(xy 166.025394 -69.137549) (xy 165.998144 -69.138038) (xy 165.971828 -69.137628) (xy 165.919696 -69.130384)
			(xy 165.869051 -69.116055) (xy 165.820852 -69.094912) (xy 165.77601 -69.067355) (xy 165.735374 -69.033905)
			(xy 165.71722 -69.014848) (xy 165.709686 -69.00746) (xy 165.690416 -68.998926) (xy 165.679882 -68.998338)
			(xy 165.605206 -68.998338) (xy 165.594653 -68.998846) (xy 165.575358 -69.007395) (xy 165.567868 -69.014848)
			(xy 165.54973 -69.033921) (xy 165.509096 -69.067375) (xy 165.464251 -69.09493) (xy 165.416047 -69.116065)
			(xy 165.365397 -69.130379) (xy 165.313261 -69.137601) (xy 165.286944 -69.138038) (xy 165.259574 -69.137561)
			(xy 165.205395 -69.129748) (xy 165.152891 -69.114263) (xy 165.103144 -69.091423) (xy 165.057177 -69.061699)
			(xy 165.036246 -69.044058) (xy 165.035992 -69.043804) (xy 165.028912 -69.038208) (xy 165.01199 -69.031967)
			(xy 165.002972 -69.031612) (xy 164.935916 -69.031612) (xy 164.9269 -69.031974) (xy 164.909982 -69.038218)
			(xy 164.902896 -69.043804) (xy 164.902896 -69.044058) (xy 164.902642 -69.044058) (xy 164.8817 -69.061684)
			(xy 164.83573 -69.0914) (xy 164.785985 -69.114239) (xy 164.733487 -69.129733) (xy 164.679313 -69.137563)
			(xy 164.651944 -69.138038) (xy 164.624694 -69.137504) (xy 164.570747 -69.129754) (xy 164.518452 -69.114405)
			(xy 164.468874 -69.09177) (xy 164.423022 -69.062309) (xy 164.38183 -69.026623) (xy 164.346135 -68.985437)
			(xy 164.316666 -68.939591) (xy 164.294021 -68.890017) (xy 164.278662 -68.837726) (xy 164.270901 -68.78378)
			(xy 164.270436 -68.75653) (xy 160.794399 -68.75653) (xy 160.788387 -68.769694) (xy 160.758916 -68.815549)
			(xy 160.723218 -68.856742) (xy 160.682022 -68.892436) (xy 160.636165 -68.921903) (xy 160.58658 -68.944544)
			(xy 160.534279 -68.959897) (xy 160.480324 -68.967651) (xy 160.45307 -68.968112) (xy 160.425699 -68.967661)
			(xy 160.37152 -68.959839) (xy 160.319017 -68.944346) (xy 160.26927 -68.921501) (xy 160.223304 -68.891774)
			(xy 160.202372 -68.874132) (xy 160.202118 -68.873878) (xy 160.195032 -68.86829) (xy 160.178115 -68.862045)
			(xy 160.169098 -68.861686) (xy 160.102042 -68.861686) (xy 160.093028 -68.862066) (xy 160.076111 -68.868298)
			(xy 160.069022 -68.873878) (xy 160.069022 -68.874132) (xy 160.068768 -68.874132) (xy 160.047825 -68.891758)
			(xy 160.001855 -68.92147) (xy 159.95211 -68.944308) (xy 159.899612 -68.959803) (xy 159.845438 -68.967635)
			(xy 159.81807 -68.968112) (xy 159.791756 -68.967661) (xy 159.739626 -68.960422) (xy 159.688984 -68.9461)
			(xy 159.640785 -68.924964) (xy 159.595942 -68.897415) (xy 159.555302 -68.863974) (xy 159.537146 -68.844922)
			(xy 159.529643 -68.837498) (xy 159.510349 -68.828986) (xy 159.499808 -68.828412) (xy 159.425132 -68.828412)
			(xy 159.414582 -68.828941) (xy 159.395287 -68.837476) (xy 159.387794 -68.844922) (xy 159.369639 -68.863978)
			(xy 159.329008 -68.897434) (xy 159.284168 -68.924992) (xy 159.235967 -68.946131) (xy 159.18532 -68.960448)
			(xy 159.133186 -68.967673) (xy 159.10687 -68.968112) (xy 159.079618 -68.96765) (xy 159.02567 -68.95989)
			(xy 158.973375 -68.944531) (xy 158.923798 -68.921887) (xy 158.877948 -68.892418) (xy 158.836758 -68.856724)
			(xy 158.801067 -68.815531) (xy 158.771601 -68.769679) (xy 158.74896 -68.720101) (xy 158.733605 -68.667805)
			(xy 158.725848 -68.613856) (xy 158.725362 -68.586604) (xy 156.516635 -68.586604) (xy 156.530995 -71.555864)
			(xy 161.29457 -71.555864) (xy 161.298641 -71.500242) (xy 161.310767 -71.445805) (xy 161.33069 -71.393714)
			(xy 161.357986 -71.345079) (xy 161.392072 -71.300936) (xy 161.432221 -71.262227) (xy 161.477579 -71.229776)
			(xy 161.527179 -71.204275) (xy 161.579963 -71.186268) (xy 161.634806 -71.176138) (xy 161.69054 -71.174101)
			(xy 161.745977 -71.180201) (xy 161.799934 -71.194307) (xy 161.851263 -71.216119) (xy 161.898869 -71.245173)
			(xy 161.941737 -71.280848) (xy 161.978954 -71.322385) (xy 162.009727 -71.368898) (xy 162.033399 -71.419395)
			(xy 162.049467 -71.472802) (xy 162.057587 -71.527978) (xy 162.058096 -71.555864) (xy 162.057587 -71.58375)
			(xy 162.051748 -71.623428) (xy 162.803584 -71.623428) (xy 162.807655 -71.567806) (xy 162.819781 -71.513369)
			(xy 162.839704 -71.461278) (xy 162.867 -71.412643) (xy 162.901086 -71.3685) (xy 162.941235 -71.329791)
			(xy 162.986593 -71.29734) (xy 163.036193 -71.271839) (xy 163.088977 -71.253832) (xy 163.14382 -71.243702)
			(xy 163.199554 -71.241665) (xy 163.254991 -71.247765) (xy 163.308948 -71.261871) (xy 163.360277 -71.283683)
			(xy 163.407883 -71.312737) (xy 163.450751 -71.348412) (xy 163.487968 -71.389949) (xy 163.518741 -71.436462)
			(xy 163.542413 -71.486959) (xy 163.558481 -71.540366) (xy 163.566601 -71.595542) (xy 163.56711 -71.623428)
			(xy 163.566601 -71.651314) (xy 163.558481 -71.70649) (xy 163.542413 -71.759897) (xy 163.518741 -71.810394)
			(xy 163.487968 -71.856907) (xy 163.450751 -71.898444) (xy 163.407883 -71.934119) (xy 163.360277 -71.963173)
			(xy 163.308948 -71.984985) (xy 163.254991 -71.999091) (xy 163.199554 -72.005191) (xy 163.14382 -72.003154)
			(xy 163.088977 -71.993024) (xy 163.036193 -71.975017) (xy 162.986593 -71.949516) (xy 162.941235 -71.917065)
			(xy 162.901086 -71.878356) (xy 162.867 -71.834213) (xy 162.839704 -71.785578) (xy 162.819781 -71.733487)
			(xy 162.807655 -71.67905) (xy 162.803584 -71.623428) (xy 162.051748 -71.623428) (xy 162.049467 -71.638926)
			(xy 162.033399 -71.692333) (xy 162.009727 -71.74283) (xy 161.978954 -71.789343) (xy 161.941737 -71.83088)
			(xy 161.898869 -71.866555) (xy 161.851263 -71.895609) (xy 161.799934 -71.917421) (xy 161.745977 -71.931527)
			(xy 161.69054 -71.937627) (xy 161.634806 -71.93559) (xy 161.579963 -71.92546) (xy 161.527179 -71.907453)
			(xy 161.477579 -71.881952) (xy 161.432221 -71.849501) (xy 161.392072 -71.810792) (xy 161.357986 -71.766649)
			(xy 161.33069 -71.718014) (xy 161.310767 -71.665923) (xy 161.298641 -71.611486) (xy 161.29457 -71.555864)
			(xy 156.530995 -71.555864) (xy 156.691584 -104.762046) (xy 156.691584 -104.763062) (xy 156.83992 -111.733838)
			(xy 156.83992 -111.756698) (xy 156.838142 -111.81588) (xy 156.734002 -113.53927) (xy 156.734002 -113.542826)
			(xy 156.84246 -135.965438) (xy 156.84246 -135.970264) (xy 156.84119 -136.023604) (xy 156.837888 -136.068054)
			(xy 156.829506 -136.152128) (xy 156.829506 -136.153144) (xy 156.829252 -136.155938) (xy 156.832046 -136.354566)
			(xy 156.832046 -136.35736) (xy 156.8323 -136.368282) (xy 156.8323 -136.36879) (xy 156.831612 -136.420036)
			(xy 156.820923 -136.52197) (xy 156.810964 -136.572244) (xy 156.768546 -136.773666) (xy 156.767784 -136.779254)
			(xy 156.374338 -140.77315) (xy 156.373932 -140.777681) (xy 156.374574 -140.786754) (xy 156.375608 -140.791184)
			(xy 156.377894 -140.799566) (xy 156.383482 -140.80744) (xy 156.400243 -140.831876) (xy 156.426813 -140.884837)
			(xy 156.444887 -140.941266) (xy 156.454031 -140.99981) (xy 156.454602 -141.029436) (xy 156.454526 -141.042174)
			(xy 156.452876 -141.067596) (xy 156.4513 -141.080236) (xy 156.451554 -141.080236) (xy 156.447631 -141.106103)
			(xy 156.433623 -141.156511) (xy 156.412862 -141.204534) (xy 156.385739 -141.249272) (xy 156.352761 -141.289888)
			(xy 156.333952 -141.308074) (xy 156.327348 -141.31417) (xy 156.323284 -141.322552) (xy 156.321264 -141.326762)
			(xy 156.318585 -141.335706) (xy 156.31795 -141.340332) (xy 156.304742 -141.476476) (xy 156.21381 -142.400782)
			(xy 156.213389 -142.407282) (xy 156.215443 -142.42014) (xy 156.217874 -142.426182) (xy 156.220414 -142.432024)
			(xy 156.228034 -142.441676) (xy 156.233368 -142.445994) (xy 156.255598 -142.463779) (xy 156.295044 -142.504826)
			(xy 156.327964 -142.551271) (xy 156.353629 -142.602086) (xy 156.37147 -142.656147) (xy 156.381093 -142.712256)
			(xy 156.382285 -142.769172) (xy 156.375018 -142.825635) (xy 156.367734 -142.853156) (xy 156.359877 -142.879087)
			(xy 156.33785 -142.928588) (xy 156.309038 -142.974473) (xy 156.274021 -143.015818) (xy 156.233505 -143.051791)
			(xy 156.188305 -143.081666) (xy 156.164026 -143.093694) (xy 156.16301 -143.094202) (xy 156.157676 -143.096996)
			(xy 156.15031 -143.10741) (xy 156.146827 -143.112816) (xy 156.142443 -143.124902) (xy 156.141674 -143.131286)
			(xy 156.121354 -143.337026) (xy 155.936442 -145.214848) (xy 155.936188 -145.222976) (xy 157.121098 -164.701474)
			(xy 157.390592 -169.132758) (xy 157.47238 -170.478704) (xy 158.742126 -191.344804) (xy 158.743106 -191.354375)
			(xy 158.751233 -191.371797) (xy 158.765207 -191.384999) (xy 158.783061 -191.392126) (xy 158.792672 -191.392556)
			(xy 159.652208 -191.392556) (xy 159.662457 -191.392097) (xy 159.681338 -191.384118) (xy 159.688784 -191.377062)
			(xy 159.695896 -191.369696) (xy 159.699706 -191.360044) (xy 159.701402 -191.35521) (xy 159.703064 -191.345101)
			(xy 159.703008 -191.339978) (xy 158.79318 -165.810184) (xy 158.79318 -165.80866) (xy 157.617922 -147.54606)
			(xy 157.616398 -147.515834) (xy 157.616398 -147.51558) (xy 157.615636 -147.482814) (xy 157.615636 -147.482306)
			(xy 157.616906 -147.433538) (xy 157.6324 -147.121372) (xy 157.6324 -147.117308) (xy 157.62351 -146.986244)
			(xy 157.616398 -146.882358) (xy 157.615392 -146.865549) (xy 157.614377 -146.831887) (xy 157.614366 -146.815048)
			(xy 157.614366 -146.814794) (xy 157.62224 -116.429536) (xy 157.622877 -116.37772) (xy 157.633569 -116.274641)
			(xy 157.643576 -116.223796) (xy 157.921452 -114.90706) (xy 157.931817 -114.860634) (xy 157.960242 -114.769848)
			(xy 157.997178 -114.682179) (xy 158.042291 -114.598425) (xy 158.068264 -114.558572) (xy 159.613346 -112.248188)
			(xy 159.642054 -112.206391) (xy 159.706699 -112.128262) (xy 159.742378 -112.092232) (xy 160.735518 -111.11357)
			(xy 160.738682 -111.109825) (xy 160.743664 -111.101382) (xy 160.745424 -111.096806) (xy 161.538158 -108.580936)
			(xy 162.855656 -104.360218) (xy 163.231068 -103.157274) (xy 163.23056 -103.155496) (xy 163.222686 -103.148638)
			(xy 163.209732 -103.137462) (xy 163.18917 -103.11924) (xy 163.152974 -103.077909) (xy 163.123075 -103.031816)
			(xy 163.10009 -102.981915) (xy 163.084493 -102.929235) (xy 163.076606 -102.874864) (xy 163.076128 -102.847394)
			(xy 163.076624 -102.819594) (xy 163.084685 -102.76458) (xy 163.100648 -102.71132) (xy 163.124176 -102.660943)
			(xy 163.15477 -102.614516) (xy 163.191781 -102.573024) (xy 163.234425 -102.537346) (xy 163.281798 -102.508238)
			(xy 163.332896 -102.486318) (xy 163.386635 -102.472051) (xy 163.414202 -102.468426) (xy 163.414456 -102.468426)
			(xy 163.421595 -102.467311) (xy 163.434873 -102.461632) (xy 163.440618 -102.45725) (xy 163.44646 -102.452424)
			(xy 163.454588 -102.440232) (xy 163.540186 -102.165912) (xy 163.807648 -101.30917) (xy 163.808156 -101.307138)
			(xy 164.274754 -99.593146) (xy 164.274754 -99.592638) (xy 164.995352 -96.821498) (xy 165.146482 -96.2406)
			(xy 165.146736 -96.240092) (xy 165.146736 -96.23933) (xy 165.14856 -96.229902) (xy 165.145806 -96.210914)
			(xy 165.136232 -96.194287) (xy 165.128956 -96.188022) (xy 165.12794 -96.18726) (xy 165.127686 -96.18726)
			(xy 165.052248 -96.130872) (xy 165.046037 -96.126563) (xy 165.031836 -96.121398) (xy 165.024308 -96.120712)
			(xy 165.016942 -96.120458) (xy 165.00221 -96.124014) (xy 164.995606 -96.128078) (xy 164.953881 -96.152704)
			(xy 164.86679 -96.195175) (xy 164.776211 -96.229586) (xy 164.682889 -96.255652) (xy 164.587589 -96.27316)
			(xy 164.491095 -96.281966) (xy 164.442648 -96.28251) (xy 164.442394 -96.28251) (xy 164.415615 -96.282349)
			(xy 164.362122 -96.279682) (xy 164.33546 -96.277176) (xy 164.289394 -96.272052) (xy 164.198314 -96.254831)
			(xy 164.10907 -96.229779) (xy 164.022334 -96.197084) (xy 163.938759 -96.156991) (xy 163.858974 -96.109804)
			(xy 163.783582 -96.055877) (xy 163.713148 -95.995616) (xy 163.648205 -95.929476) (xy 163.58924 -95.857954)
			(xy 163.536699 -95.78159) (xy 163.490976 -95.700957) (xy 163.452416 -95.616664) (xy 163.42131 -95.529346)
			(xy 163.397891 -95.439659) (xy 163.382337 -95.348279) (xy 163.374763 -95.255895) (xy 163.375228 -95.163202)
			(xy 163.383728 -95.070899) (xy 163.400198 -94.97968) (xy 163.424515 -94.890232) (xy 163.456496 -94.80323)
			(xy 163.495899 -94.719328) (xy 163.542428 -94.639158) (xy 163.595733 -94.563324) (xy 163.655412 -94.492397)
			(xy 163.721015 -94.426912) (xy 163.792049 -94.367361) (xy 163.867979 -94.314193) (xy 163.948232 -94.267808)
			(xy 164.032205 -94.228556) (xy 164.119265 -94.196732) (xy 164.208756 -94.172576) (xy 164.300005 -94.15627)
			(xy 164.346128 -94.151704) (xy 164.346636 -94.151704) (xy 164.366448 -94.149672) (xy 164.368988 -94.149672)
			(xy 164.388546 -94.148656) (xy 164.44722 -94.147386) (xy 164.450014 -94.147386) (xy 164.49548 -94.14764)
			(xy 164.49548 -94.148656) (xy 164.542343 -94.151486) (xy 164.635348 -94.164345) (xy 164.726865 -94.185323)
			(xy 164.816186 -94.214257) (xy 164.902621 -94.250923) (xy 164.985502 -94.295038) (xy 165.064188 -94.346262)
			(xy 165.138071 -94.404198) (xy 165.206582 -94.468399) (xy 165.269189 -94.538368) (xy 165.32541 -94.613566)
			(xy 165.374809 -94.69341) (xy 165.417006 -94.777284) (xy 165.434772 -94.82074) (xy 165.43782 -94.82836)
			(xy 165.44163 -94.833186) (xy 165.444173 -94.836241) (xy 165.450037 -94.841606) (xy 165.453314 -94.843854)
			(xy 165.455854 -94.845632) (xy 165.461012 -94.848587) (xy 165.472302 -94.852296) (xy 165.478206 -94.852998)
			(xy 165.534848 -94.85249) (xy 165.577012 -94.852236) (xy 165.59022 -94.850458) (xy 175.698404 -68.147184)
			(xy 175.699928 -68.141088) (xy 175.699928 -68.14058) (xy 176.259236 -65.09131) (xy 176.730914 -62.520322)
			(xy 176.731616 -62.51083) (xy 176.726785 -62.492434) (xy 176.721516 -62.484508) (xy 176.696878 -62.450472)
			(xy 176.696624 -62.450218) (xy 176.690253 -62.442284) (xy 176.672838 -62.431792) (xy 176.662842 -62.429898)
			(xy 176.655476 -62.428882) (xy 176.654968 -62.428882) (xy 176.6443 -62.427104) (xy 176.642776 -62.42685)
			(xy 176.617884 -62.421262) (xy 176.61763 -62.421262) (xy 176.610772 -62.419484) (xy 176.596548 -62.419992)
			(xy 176.590198 -62.422024) (xy 176.58356 -62.42434) (xy 176.57183 -62.432078) (xy 176.567084 -62.437264)
			(xy 176.564036 -62.44082) (xy 176.510188 -62.503304) (xy 176.505161 -62.510187) (xy 176.499585 -62.526282)
			(xy 176.499266 -62.5348) (xy 176.499266 -62.54877) (xy 176.50206 -62.563248) (xy 176.5046 -62.57163)
			(xy 176.505108 -62.573154) (xy 176.516208 -62.605173) (xy 176.52821 -62.671862) (xy 176.528984 -62.705742)
			(xy 176.528476 -62.71641) (xy 176.527287 -62.743159) (xy 176.518345 -62.795952) (xy 176.502112 -62.846975)
			(xy 176.478905 -62.895229) (xy 176.449182 -62.939765) (xy 176.413524 -62.979709) (xy 176.372634 -63.014277)
			(xy 176.327312 -63.042789) (xy 176.278451 -63.064686) (xy 176.227008 -63.079538) (xy 176.173994 -63.087054)
			(xy 176.147222 -63.087504) (xy 176.119968 -63.087042) (xy 176.066016 -63.079288) (xy 176.013716 -63.063934)
			(xy 175.964133 -63.041293) (xy 175.918278 -63.011826) (xy 175.877083 -62.976132) (xy 175.841387 -62.93494)
			(xy 175.811918 -62.889086) (xy 175.789274 -62.839505) (xy 175.773917 -62.787206) (xy 175.766159 -62.733254)
			(xy 175.766159 -62.678746) (xy 175.773917 -62.624794) (xy 175.789274 -62.572495) (xy 175.811918 -62.522914)
			(xy 175.841387 -62.47706) (xy 175.877083 -62.435868) (xy 175.918278 -62.400174) (xy 175.964133 -62.370707)
			(xy 176.013716 -62.348066) (xy 176.066016 -62.332712) (xy 176.119968 -62.324958) (xy 176.147222 -62.324488)
			(xy 176.147984 -62.324488) (xy 176.170553 -62.324839) (xy 176.215373 -62.330192) (xy 176.237392 -62.335156)
			(xy 176.24044 -62.335918) (xy 176.249584 -62.336934) (xy 176.261471 -62.337185) (xy 176.28344 -62.32817)
			(xy 176.291748 -62.319662) (xy 176.350676 -62.251336) (xy 176.355102 -62.245862) (xy 176.361035 -62.233103)
			(xy 176.36236 -62.22619) (xy 176.363229 -62.219231) (xy 176.361557 -62.205311) (xy 176.359058 -62.198758)
			(xy 176.359058 -62.198504) (xy 176.349729 -62.175121) (xy 176.336603 -62.126517) (xy 176.32998 -62.07661)
			(xy 176.329594 -62.051438) (xy 176.330055 -62.024183) (xy 176.337807 -61.970229) (xy 176.35316 -61.917926)
			(xy 176.3758 -61.868341) (xy 176.405267 -61.822484) (xy 176.440961 -61.781287) (xy 176.482155 -61.745589)
			(xy 176.52801 -61.716118) (xy 176.577592 -61.693473) (xy 176.629893 -61.678115) (xy 176.683847 -61.670357)
			(xy 176.711102 -61.66993) (xy 176.711864 -61.66993) (xy 176.73326 -61.670258) (xy 176.775778 -61.675093)
			(xy 176.7967 -61.679582) (xy 176.80178 -61.680852) (xy 176.810339 -61.682201) (xy 176.827479 -61.679738)
			(xy 176.835308 -61.676026) (xy 176.839626 -61.673486) (xy 176.874424 -61.650372) (xy 176.882772 -61.644309)
			(xy 176.894189 -61.627146) (xy 176.896522 -61.617098) (xy 176.91354 -61.524642) (xy 176.920144 -61.48832)
			(xy 177.022506 -60.930536) (xy 177.023475 -60.924641) (xy 177.022952 -60.912707) (xy 177.02149 -60.906914)
			(xy 177.018188 -60.895992) (xy 177.010314 -60.887356) (xy 176.991324 -60.865227) (xy 176.959588 -60.81631)
			(xy 176.935657 -60.763137) (xy 176.920086 -60.706944) (xy 176.91608 -60.67806) (xy 176.914556 -60.66409)
			(xy 176.913286 -60.633356) (xy 176.913847 -60.604108) (xy 176.922774 -60.546298) (xy 176.940412 -60.490524)
			(xy 176.966349 -60.438093) (xy 176.999978 -60.39023) (xy 177.040512 -60.348055) (xy 177.087003 -60.312554)
			(xy 177.112422 -60.298076) (xy 177.112676 -60.297822) (xy 177.118757 -60.294222) (xy 177.128812 -60.2843)
			(xy 177.132488 -60.278264) (xy 177.136044 -60.271914) (xy 177.139346 -60.25769) (xy 177.043334 -58.759344)
			(xy 177.042933 -58.754617) (xy 177.040634 -58.745415) (xy 177.038762 -58.741056) (xy 177.035206 -58.733436)
			(xy 177.02784 -58.726324) (xy 177.009447 -58.70824) (xy 176.977204 -58.667978) (xy 176.950678 -58.623741)
			(xy 176.930351 -58.576334) (xy 176.916594 -58.526621) (xy 176.909658 -58.475509) (xy 176.909222 -58.449718)
			(xy 176.90956 -58.427085) (xy 176.914913 -58.382137) (xy 176.91989 -58.360056) (xy 176.924824 -58.340688)
			(xy 176.938182 -58.303017) (xy 176.94656 -58.284872) (xy 176.956565 -58.264693) (xy 176.980628 -58.226618)
			(xy 176.994566 -58.208926) (xy 177.000916 -58.201052) (xy 177.00371 -58.192416) (xy 177.00505 -58.187907)
			(xy 177.00621 -58.178573) (xy 177.005996 -58.173874) (xy 176.920906 -56.844692) (xy 176.78019 -54.642004)
			(xy 176.77852 -54.632675) (xy 176.769432 -54.616062) (xy 176.754961 -54.60385) (xy 176.746154 -54.600348)
			(xy 176.7459 -54.600348) (xy 176.721036 -54.591474) (xy 176.673829 -54.567837) (xy 176.630334 -54.537916)
			(xy 176.591381 -54.502283) (xy 176.557714 -54.461617) (xy 176.529977 -54.416698) (xy 176.5087 -54.368382)
			(xy 176.49429 -54.317593) (xy 176.487022 -54.265303) (xy 176.486566 -54.238906) (xy 176.487036 -54.212269)
			(xy 176.494457 -54.159515) (xy 176.509141 -54.108304) (xy 176.530803 -54.059633) (xy 176.559022 -54.014447)
			(xy 176.59325 -53.973624) (xy 176.632822 -53.937957) (xy 176.676969 -53.908138) (xy 176.700688 -53.896006)
			(xy 176.703736 -53.894482) (xy 176.711713 -53.889341) (xy 176.723569 -53.874544) (xy 176.729306 -53.856472)
			(xy 176.729136 -53.846984) (xy 176.597056 -51.781964) (xy 176.595744 -51.770824) (xy 176.584925 -51.751206)
			(xy 176.576228 -51.744118) (xy 176.544986 -51.721258) (xy 176.544478 -51.72075) (xy 176.511458 -51.697128)
			(xy 176.50229 -51.691666) (xy 176.481293 -51.68798) (xy 176.470818 -51.690016) (xy 176.470564 -51.690016)
			(xy 176.44752 -51.695489) (xy 176.40052 -51.701353) (xy 176.376838 -51.7017) (xy 176.14519 -51.7017)
			(xy 176.135354 -51.701205) (xy 176.117155 -51.693722) (xy 176.103113 -51.679939) (xy 176.095292 -51.661883)
			(xy 176.094843 -51.642212) (xy 176.097946 -51.632866) (xy 176.10582 -51.612038) (xy 176.10074 -51.584098)
			(xy 176.092866 -51.575208) (xy 176.08677 -51.568096) (xy 176.086262 -51.567588) (xy 176.077606 -51.557294)
			(xy 176.061591 -51.535683) (xy 176.054258 -51.524408) (xy 176.052988 -51.522122) (xy 176.05248 -51.521614)
			(xy 176.051464 -51.520344) (xy 176.050956 -51.519582) (xy 176.046384 -51.513994) (xy 176.039874 -51.507518)
			(xy 176.023467 -51.499305) (xy 176.01438 -51.497992) (xy 175.974756 -51.493928) (xy 175.974248 -51.493928)
			(xy 175.950626 -51.491388) (xy 175.950118 -51.491388) (xy 175.93437 -51.489864) (xy 175.922735 -51.489266)
			(xy 175.900905 -51.497334) (xy 175.89246 -51.505358) (xy 175.892206 -51.505612) (xy 175.874111 -51.524179)
			(xy 175.833775 -51.556749) (xy 175.789402 -51.58356) (xy 175.741808 -51.604119) (xy 175.69187 -51.618047)
			(xy 175.640506 -51.625088) (xy 175.614584 -51.6255) (xy 175.587334 -51.625013) (xy 175.533388 -51.617255)
			(xy 175.481096 -51.601898) (xy 175.431521 -51.579256) (xy 175.385673 -51.549789) (xy 175.344486 -51.514097)
			(xy 175.308796 -51.472908) (xy 175.279333 -51.427058) (xy 175.256693 -51.377482) (xy 175.24134 -51.325188)
			(xy 175.233585 -51.271242) (xy 175.233076 -51.243992) (xy 175.233501 -51.218481) (xy 175.240296 -51.167912)
			(xy 175.253763 -51.118699) (xy 175.273663 -51.071717) (xy 175.299641 -51.027802) (xy 175.315118 -51.007518)
			(xy 175.317658 -51.00447) (xy 175.318674 -51.002946) (xy 175.321976 -50.996342) (xy 175.324321 -50.99112)
			(xy 175.326889 -50.979966) (xy 175.327056 -50.974244) (xy 175.327056 -50.94224) (xy 175.338232 -50.94224)
			(xy 175.338232 -50.89144) (xy 175.337897 -50.882837) (xy 175.33218 -50.866609) (xy 175.327056 -50.85969)
			(xy 175.325786 -50.858166) (xy 175.308391 -50.83729) (xy 175.279071 -50.791541) (xy 175.256541 -50.742093)
			(xy 175.241259 -50.689948) (xy 175.233532 -50.636161) (xy 175.233076 -50.608992) (xy 175.233562 -50.581741)
			(xy 175.24132 -50.527793) (xy 175.256675 -50.475498) (xy 175.279317 -50.425921) (xy 175.308783 -50.38007)
			(xy 175.344474 -50.33888) (xy 175.385664 -50.303188) (xy 175.431514 -50.273721) (xy 175.481091 -50.251078)
			(xy 175.533385 -50.235721) (xy 175.587333 -50.227963) (xy 175.614584 -50.227484) (xy 175.642623 -50.227986)
			(xy 175.698094 -50.236209) (xy 175.751763 -50.252466) (xy 175.802474 -50.276406) (xy 175.849133 -50.307513)
			(xy 175.890734 -50.345117) (xy 175.90897 -50.366422) (xy 175.909224 -50.366676) (xy 175.916082 -50.374804)
			(xy 175.939704 -50.386488) (xy 175.946054 -50.389536) (xy 175.950945 -50.391615) (xy 175.961317 -50.393919)
			(xy 175.966628 -50.394108) (xy 176.024032 -50.394108) (xy 176.029757 -50.393962) (xy 176.040918 -50.391402)
			(xy 176.04613 -50.389028) (xy 176.064418 -50.380138) (xy 176.074324 -50.373788) (xy 176.078134 -50.37074)
			(xy 176.08169 -50.366676) (xy 176.102096 -50.342895) (xy 176.149289 -50.301678) (xy 176.20257 -50.268707)
			(xy 176.231296 -50.256186) (xy 176.241394 -50.25205) (xy 176.261981 -50.244806) (xy 176.272444 -50.241708)
			(xy 176.282604 -50.238914) (xy 176.290732 -50.23231) (xy 176.294575 -50.22896) (xy 176.300982 -50.221032)
			(xy 176.303432 -50.216562) (xy 176.320704 -50.183288) (xy 176.325098 -50.173925) (xy 176.32669 -50.153325)
			(xy 176.323752 -50.14341) (xy 176.22901 -49.86782) (xy 176.225086 -49.858032) (xy 176.210817 -49.842536)
			(xy 176.191535 -49.834056) (xy 176.181004 -49.83353) (xy 176.175162 -49.83353) (xy 176.170678 -49.833672)
			(xy 176.161864 -49.835334) (xy 176.157636 -49.836832) (xy 176.130458 -49.848008) (xy 176.1236 -49.854358)
			(xy 176.102297 -49.873386) (xy 176.055097 -49.905549) (xy 176.003631 -49.930323) (xy 175.94905 -49.947152)
			(xy 175.892571 -49.955663) (xy 175.864012 -49.956212) (xy 175.8385 -49.955788) (xy 175.787931 -49.948996)
			(xy 175.738716 -49.93553) (xy 175.691733 -49.915632) (xy 175.647817 -49.889654) (xy 175.627538 -49.87417)
			(xy 175.62449 -49.87163) (xy 175.622966 -49.870614) (xy 175.616362 -49.867312) (xy 175.61114 -49.864965)
			(xy 175.599987 -49.862394) (xy 175.594264 -49.862232) (xy 175.56226 -49.862232) (xy 175.56226 -49.851056)
			(xy 175.51146 -49.851056) (xy 175.502856 -49.851388) (xy 175.486623 -49.857099) (xy 175.47971 -49.862232)
			(xy 175.478186 -49.863502) (xy 175.457309 -49.880893) (xy 175.411558 -49.910204) (xy 175.362109 -49.932725)
			(xy 175.309964 -49.947997) (xy 175.25618 -49.955712) (xy 175.229012 -49.956212) (xy 175.2035 -49.955788)
			(xy 175.152931 -49.948996) (xy 175.103716 -49.93553) (xy 175.056733 -49.915632) (xy 175.012817 -49.889654)
			(xy 174.992538 -49.87417) (xy 174.98949 -49.87163) (xy 174.987966 -49.870614) (xy 174.981362 -49.867312)
			(xy 174.97614 -49.864965) (xy 174.964987 -49.862394) (xy 174.959264 -49.862232) (xy 174.92726 -49.862232)
			(xy 174.92726 -49.851056) (xy 174.87646 -49.851056) (xy 174.867856 -49.851388) (xy 174.851623 -49.857099)
			(xy 174.84471 -49.862232) (xy 174.843186 -49.863502) (xy 174.822309 -49.880893) (xy 174.776558 -49.910204)
			(xy 174.727109 -49.932725) (xy 174.674964 -49.947997) (xy 174.62118 -49.955712) (xy 174.594012 -49.956212)
			(xy 174.566758 -49.955749) (xy 174.512806 -49.947994) (xy 174.460506 -49.932639) (xy 174.410924 -49.909997)
			(xy 174.365068 -49.880529) (xy 174.323874 -49.844835) (xy 174.288179 -49.803641) (xy 174.258709 -49.757787)
			(xy 174.236066 -49.708206) (xy 174.220709 -49.655906) (xy 174.212951 -49.601954) (xy 174.212951 -49.547446)
			(xy 174.220709 -49.493494) (xy 174.236066 -49.441194) (xy 174.258709 -49.391613) (xy 174.288179 -49.345759)
			(xy 174.323874 -49.304565) (xy 174.365068 -49.268871) (xy 174.410924 -49.239403) (xy 174.460506 -49.216761)
			(xy 174.512806 -49.201406) (xy 174.566758 -49.193651) (xy 174.594012 -49.193196) (xy 174.619523 -49.193621)
			(xy 174.670091 -49.200417) (xy 174.719304 -49.213885) (xy 174.766285 -49.233786) (xy 174.810198 -49.259766)
			(xy 174.830486 -49.275238) (xy 174.833534 -49.277778) (xy 174.835058 -49.278794) (xy 174.841662 -49.282096)
			(xy 174.846885 -49.28444) (xy 174.858038 -49.287006) (xy 174.86376 -49.287176) (xy 174.895764 -49.287176)
			(xy 174.895764 -49.298352) (xy 174.946564 -49.298352) (xy 174.955167 -49.298016) (xy 174.971395 -49.2923)
			(xy 174.978314 -49.287176) (xy 174.979838 -49.285906) (xy 175.000714 -49.268511) (xy 175.046463 -49.239189)
			(xy 175.095911 -49.216659) (xy 175.148056 -49.201376) (xy 175.201843 -49.19365) (xy 175.229012 -49.193196)
			(xy 175.254523 -49.193621) (xy 175.305091 -49.200417) (xy 175.354304 -49.213885) (xy 175.401285 -49.233786)
			(xy 175.445198 -49.259766) (xy 175.465486 -49.275238) (xy 175.468534 -49.277778) (xy 175.470058 -49.278794)
			(xy 175.476662 -49.282096) (xy 175.481885 -49.28444) (xy 175.493038 -49.287006) (xy 175.49876 -49.287176)
			(xy 175.530764 -49.287176) (xy 175.530764 -49.298352) (xy 175.581564 -49.298352) (xy 175.590167 -49.298016)
			(xy 175.606395 -49.2923) (xy 175.613314 -49.287176) (xy 175.614838 -49.285906) (xy 175.622204 -49.279302)
			(xy 175.62322 -49.278794) (xy 175.62449 -49.277778) (xy 175.624998 -49.27727) (xy 175.647096 -49.26076)
			(xy 175.64735 -49.260506) (xy 175.647858 -49.260252) (xy 175.670718 -49.24552) (xy 175.671734 -49.245012)
			(xy 175.682402 -49.23917) (xy 175.689514 -49.235106) (xy 175.695864 -49.226216) (xy 175.699152 -49.22139)
			(xy 175.703645 -49.210614) (xy 175.704754 -49.20488) (xy 175.71212 -49.159922) (xy 175.712628 -49.156112)
			(xy 175.713305 -49.150964) (xy 175.712785 -49.140596) (xy 175.711612 -49.135538) (xy 175.71085 -49.132744)
			(xy 175.709539 -49.128878) (xy 175.70584 -49.1216) (xy 175.703484 -49.118266) (xy 175.53178 -48.895508)
			(xy 175.528986 -48.892206) (xy 169.969434 -42.831766) (xy 169.961057 -42.82343) (xy 169.939079 -42.814818)
			(xy 169.92727 -42.815256) (xy 169.916094 -42.817542) (xy 169.865802 -42.834052) (xy 169.865294 -42.834052)
			(xy 169.851324 -42.83837) (xy 169.847177 -42.83975) (xy 169.839385 -42.843702) (xy 169.83583 -42.846244)
			(xy 169.827665 -42.853039) (xy 169.817291 -42.871546) (xy 169.815764 -42.882058) (xy 169.812228 -42.911431)
			(xy 169.797645 -42.968766) (xy 169.774828 -43.02335) (xy 169.744268 -43.074006) (xy 169.706623 -43.119644)
			(xy 169.662704 -43.159281) (xy 169.613457 -43.192064) (xy 169.559942 -43.217285) (xy 169.503312 -43.234403)
			(xy 169.444786 -43.243048) (xy 169.415206 -43.2435) (xy 169.386446 -43.243012) (xy 169.329512 -43.234827)
			(xy 169.274322 -43.218622) (xy 169.222 -43.194728) (xy 169.173611 -43.163631) (xy 169.13014 -43.125964)
			(xy 169.092472 -43.082494) (xy 169.061375 -43.034105) (xy 169.03748 -42.981784) (xy 169.021275 -42.926594)
			(xy 169.013089 -42.86966) (xy 169.013089 -42.81214) (xy 169.021275 -42.755206) (xy 169.03748 -42.700016)
			(xy 169.061375 -42.647695) (xy 169.092472 -42.599306) (xy 169.13014 -42.555836) (xy 169.173611 -42.518169)
			(xy 169.222 -42.487072) (xy 169.274322 -42.463178) (xy 169.329512 -42.446973) (xy 169.386446 -42.438788)
			(xy 169.415206 -42.43832) (xy 169.41546 -42.43832) (xy 169.434371 -42.438556) (xy 169.472024 -42.44212)
			(xy 169.490644 -42.445432) (xy 169.502582 -42.447718) (xy 169.525696 -42.441114) (xy 169.570654 -42.399712)
			(xy 169.56278 -42.388536) (xy 169.50944 -42.330624) (xy 169.509186 -42.330116) (xy 169.506646 -42.327322)
			(xy 169.504106 -42.324782) (xy 169.466939 -42.284227) (xy 169.400866 -42.196268) (xy 169.37228 -42.149268)
			(xy 168.863772 -41.28897) (xy 168.85539 -41.282874) (xy 168.83846 -41.270581) (xy 168.807143 -41.242833)
			(xy 168.792906 -41.227502) (xy 168.771327 -41.202632) (xy 168.7362 -41.146947) (xy 168.723056 -41.116758)
			(xy 168.722548 -41.115234) (xy 168.721532 -41.11244) (xy 168.713887 -41.09253) (xy 168.702558 -41.051413)
			(xy 168.698926 -41.030398) (xy 168.698926 -41.02989) (xy 168.696894 -41.01465) (xy 168.695624 -41.003728)
			(xy 168.317418 -40.36314) (xy 168.312079 -40.356068) (xy 168.297655 -40.345799) (xy 168.289224 -40.343074)
			(xy 168.287954 -40.34282) (xy 168.2877 -40.34282) (xy 168.28389 -40.341804) (xy 168.256892 -40.334439)
			(xy 168.205249 -40.312885) (xy 168.157309 -40.284017) (xy 168.114102 -40.248454) (xy 168.076554 -40.20696)
			(xy 168.045472 -40.160426) (xy 168.021522 -40.109849) (xy 168.005219 -40.056316) (xy 167.996913 -40.000975)
			(xy 167.996362 -39.972996) (xy 167.996362 -39.968424) (xy 167.99687 -39.95166) (xy 167.998194 -39.931532)
			(xy 168.004561 -39.891698) (xy 168.00957 -39.872158) (xy 168.012364 -39.861998) (xy 168.011094 -39.852092)
			(xy 168.01035 -39.846941) (xy 168.007023 -39.837081) (xy 168.00449 -39.832534) (xy 167.73271 -39.37254)
			(xy 167.482012 -38.947344) (xy 167.477129 -38.940352) (xy 167.46372 -38.929828) (xy 167.447609 -38.924263)
			(xy 167.439086 -38.923976) (xy 167.365934 -38.923722) (xy 167.351964 -38.9255) (xy 167.346122 -38.927278)
			(xy 167.340534 -38.930326) (xy 167.340026 -38.930326) (xy 167.316404 -38.943788) (xy 167.312856 -38.946283)
			(xy 167.306593 -38.952281) (xy 167.303958 -38.955726) (xy 167.30218 -38.958266) (xy 167.287025 -38.980784)
			(xy 167.251356 -39.021694) (xy 167.210243 -39.05713) (xy 167.164518 -39.086374) (xy 167.115107 -39.108835)
			(xy 167.063009 -39.124058) (xy 167.009279 -39.131737) (xy 166.98214 -39.132256) (xy 166.963028 -39.132087)
			(xy 166.924982 -39.128398) (xy 166.906194 -39.12489) (xy 166.901114 -39.12362) (xy 166.885818 -39.120132)
			(xy 166.855809 -39.110975) (xy 166.84117 -39.105332) (xy 166.813552 -39.093723) (xy 166.762026 -39.063165)
			(xy 166.715909 -39.024929) (xy 166.676335 -38.979956) (xy 166.659814 -38.954964) (xy 166.658036 -38.952424)
			(xy 166.654226 -38.947852) (xy 166.651704 -38.945013) (xy 166.645964 -38.94004) (xy 166.642796 -38.937946)
			(xy 166.623492 -38.926262) (xy 166.618675 -38.923496) (xy 166.608167 -38.919902) (xy 166.602664 -38.91915)
			(xy 166.600378 -38.918896) (xy 166.600124 -38.918896) (xy 166.529766 -38.914324) (xy 166.518926 -38.914112)
			(xy 166.498655 -38.921744) (xy 166.49065 -38.929056) (xy 166.48684 -38.932866) (xy 166.485062 -38.935152)
			(xy 166.4843 -38.936168) (xy 166.466302 -38.958591) (xy 166.424703 -38.998283) (xy 166.377619 -39.031283)
			(xy 166.326116 -39.056844) (xy 166.271361 -39.074386) (xy 166.214593 -39.083513) (xy 166.18585 -39.08425)
			(xy 166.18204 -39.08425) (xy 166.154782 -39.08379) (xy 166.100821 -39.076037) (xy 166.048513 -39.060682)
			(xy 165.998922 -39.03804) (xy 165.953059 -39.008569) (xy 165.911857 -38.972872) (xy 165.876155 -38.931673)
			(xy 165.84668 -38.885813) (xy 165.824032 -38.836225) (xy 165.808672 -38.783918) (xy 165.800913 -38.729958)
			(xy 165.800913 -38.675442) (xy 165.808672 -38.621482) (xy 165.824032 -38.569175) (xy 165.84668 -38.519587)
			(xy 165.876155 -38.473727) (xy 165.911857 -38.432528) (xy 165.953059 -38.396831) (xy 165.998922 -38.36736)
			(xy 166.048513 -38.344718) (xy 166.100821 -38.329363) (xy 166.154782 -38.32161) (xy 166.18204 -38.321234)
			(xy 166.209526 -38.321708) (xy 166.263932 -38.32958) (xy 166.316647 -38.34517) (xy 166.366583 -38.368155)
			(xy 166.412707 -38.398062) (xy 166.454068 -38.434273) (xy 166.489811 -38.476039) (xy 166.504874 -38.499034)
			(xy 166.504874 -38.499288) (xy 166.507414 -38.503352) (xy 166.508176 -38.504368) (xy 166.51224 -38.508432)
			(xy 166.52113 -38.515036) (xy 166.540688 -38.527228) (xy 166.546067 -38.530306) (xy 166.557884 -38.534026)
			(xy 166.564056 -38.534594) (xy 166.634922 -38.539166) (xy 166.644113 -38.539373) (xy 166.661695 -38.534044)
			(xy 166.669212 -38.528752) (xy 166.678864 -38.5191) (xy 166.680134 -38.517322) (xy 166.703248 -38.490144)
			(xy 166.713662 -38.479222) (xy 166.734134 -38.459748) (xy 166.779768 -38.426434) (xy 166.829813 -38.400208)
			(xy 166.883176 -38.381643) (xy 166.938693 -38.371144) (xy 166.9669 -38.369494) (xy 166.980108 -38.368986)
			(xy 166.991538 -38.361874) (xy 166.997023 -38.358278) (xy 167.006039 -38.348758) (xy 167.009318 -38.343078)
			(xy 167.050974 -38.266878) (xy 167.053514 -38.26129) (xy 167.057305 -38.250217) (xy 167.055466 -38.226911)
			(xy 167.049958 -38.216586) (xy 166.786814 -37.77107) (xy 166.778178 -37.76472) (xy 166.74504 -37.740448)
			(xy 166.682474 -37.687214) (xy 166.624536 -37.628977) (xy 166.571624 -37.566138) (xy 166.524104 -37.49913)
			(xy 166.502842 -37.463984) (xy 166.277798 -37.083238) (xy 166.255554 -37.044637) (xy 166.217311 -36.964165)
			(xy 166.186472 -36.880575) (xy 166.163288 -36.794548) (xy 166.155116 -36.750752) (xy 166.153592 -36.744402)
			(xy 166.15158 -36.738568) (xy 166.145157 -36.728034) (xy 166.140892 -36.723574) (xy 166.123087 -36.705171)
			(xy 166.092058 -36.664436) (xy 166.06675 -36.619921) (xy 166.056818 -36.59632) (xy 166.051484 -36.58235)
			(xy 166.047674 -36.571682) (xy 165.628066 -36.145724) (xy 165.620639 -36.13878) (xy 165.601903 -36.130932)
			(xy 165.591744 -36.130484) (xy 165.577774 -36.130484) (xy 165.567808 -36.130963) (xy 165.549372 -36.138538)
			(xy 165.54196 -36.145216) (xy 165.541706 -36.14547) (xy 165.52008 -36.166445) (xy 165.471444 -36.201997)
			(xy 165.417826 -36.229465) (xy 165.360559 -36.248167) (xy 165.301064 -36.257639) (xy 165.270942 -36.258246)
			(xy 165.244126 -36.257788) (xy 165.191022 -36.250273) (xy 165.139492 -36.235399) (xy 165.090552 -36.213459)
			(xy 165.045165 -36.184884) (xy 165.004224 -36.150239) (xy 164.968535 -36.110204) (xy 164.938801 -36.065567)
			(xy 164.915608 -36.017209) (xy 164.899412 -35.96608) (xy 164.890531 -35.913187) (xy 164.889434 -35.88639)
			(xy 164.889434 -35.877754) (xy 164.889811 -35.850868) (xy 164.897189 -35.797606) (xy 164.911962 -35.745905)
			(xy 164.933838 -35.696786) (xy 164.962384 -35.651219) (xy 164.97935 -35.630358) (xy 164.98316 -35.625786)
			(xy 164.989087 -35.615766) (xy 164.992062 -35.592701) (xy 164.98461 -35.570672) (xy 164.97681 -35.562032)
			(xy 164.778182 -35.363404) (xy 164.744654 -35.328098) (xy 164.744146 -35.32759) (xy 164.743638 -35.326828)
			(xy 164.740336 -35.323526) (xy 164.739828 -35.32251) (xy 164.73805 -35.320732) (xy 164.736018 -35.318446)
			(xy 164.728906 -35.312096) (xy 164.72154 -35.308794) (xy 164.717831 -35.307231) (xy 164.710045 -35.305192)
			(xy 164.706046 -35.30473) (xy 164.689282 -35.302952) (xy 164.684415 -35.302575) (xy 164.674694 -35.303469)
			(xy 164.669978 -35.30473) (xy 164.661088 -35.30727) (xy 164.653214 -35.313112) (xy 164.615943 -35.34095)
			(xy 164.537109 -35.390351) (xy 164.454018 -35.432198) (xy 164.367391 -35.466126) (xy 164.277982 -35.491841)
			(xy 164.186567 -35.50912) (xy 164.093941 -35.517813) (xy 164.047424 -35.518344) (xy 164.04717 -35.518344)
			(xy 163.991642 -35.517584) (xy 163.881276 -35.505232) (xy 163.826952 -35.493706) (xy 163.785909 -35.48394)
			(xy 163.705499 -35.458383) (xy 163.627537 -35.426122) (xy 163.552582 -35.387385) (xy 163.481169 -35.342451)
			(xy 163.41381 -35.291642) (xy 163.350986 -35.23532) (xy 163.321746 -35.204908) (xy 163.286129 -35.166092)
			(xy 163.222372 -35.082221) (xy 163.194492 -35.037522) (xy 163.191952 -35.033712) (xy 163.181538 -35.021774)
			(xy 163.180014 -35.020504) (xy 163.157392 -35.002317) (xy 163.117392 -34.960259) (xy 163.084224 -34.912627)
			(xy 163.058652 -34.860522) (xy 163.041267 -34.805144) (xy 163.032469 -34.747773) (xy 163.031932 -34.718752)
			(xy 163.031932 -34.718498) (xy 163.032396 -34.689997) (xy 163.040814 -34.633623) (xy 163.048696 -34.60623)
			(xy 163.05022 -34.599118) (xy 163.051998 -34.588196) (xy 163.051998 -34.58464) (xy 163.051744 -34.581846)
			(xy 163.051236 -34.567622) (xy 163.051236 -34.566606) (xy 163.05022 -34.520886) (xy 163.050655 -34.478299)
			(xy 163.057896 -34.393435) (xy 163.072349 -34.309497) (xy 163.093908 -34.227098) (xy 163.122418 -34.146839)
			(xy 163.139628 -34.107882) (xy 163.142808 -34.098749) (xy 163.142804 -34.079425) (xy 163.139628 -34.07029)
			(xy 163.12242 -34.031333) (xy 163.093928 -33.95107) (xy 163.072378 -33.86867) (xy 163.057926 -33.784734)
			(xy 163.050679 -33.699872) (xy 163.05022 -33.657286) (xy 163.051998 -33.595818) (xy 163.05276 -33.583626)
			(xy 163.050728 -33.578038) (xy 163.045902 -33.56864) (xy 163.037774 -33.55721) (xy 163.00831 -33.525714)
			(xy 163.000865 -33.518478) (xy 162.981849 -33.510202) (xy 162.97148 -33.509712) (xy 162.641788 -33.509712)
			(xy 162.600948 -33.509293) (xy 162.519543 -33.502591) (xy 162.43896 -33.48925) (xy 162.359739 -33.469358)
			(xy 162.282411 -33.44305) (xy 162.244786 -33.427162) (xy 162.240214 -33.42513) (xy 162.225228 -33.421828)
			(xy 162.21456 -33.420812) (xy 162.129724 -33.420812) (xy 162.120089 -33.421272) (xy 162.102197 -33.428444)
			(xy 162.094926 -33.434782) (xy 162.064068 -33.463683) (xy 161.998239 -33.516747) (xy 161.928153 -33.564045)
			(xy 161.854313 -33.605238) (xy 161.777249 -33.640029) (xy 161.697517 -33.668169) (xy 161.615687 -33.689456)
			(xy 161.532349 -33.703736) (xy 161.4481 -33.710907) (xy 161.405824 -33.711388) (xy 161.40557 -33.711388)
			(xy 161.40557 -33.711642) (xy 161.405316 -33.711642) (xy 161.358835 -33.711108) (xy 161.266278 -33.702456)
			(xy 161.174928 -33.685226) (xy 161.085578 -33.659568) (xy 160.999004 -33.625704) (xy 160.915959 -33.583928)
			(xy 160.837162 -33.534604) (xy 160.7633 -33.478159) (xy 160.695012 -33.415084) (xy 160.632891 -33.345925)
			(xy 160.577479 -33.271285) (xy 160.552892 -33.231836) (xy 160.550352 -33.227772) (xy 160.537906 -33.214056)
			(xy 160.534604 -33.211516) (xy 160.512401 -33.193284) (xy 160.473194 -33.151292) (xy 160.440711 -33.103907)
			(xy 160.415683 -33.052196) (xy 160.398673 -32.997322) (xy 160.390064 -32.940521) (xy 160.38957 -32.911796)
			(xy 160.391094 -32.879284) (xy 160.392364 -32.867092) (xy 160.394571 -32.849945) (xy 160.401698 -32.816111)
			(xy 160.406588 -32.799528) (xy 160.408112 -32.792416) (xy 160.40989 -32.781494) (xy 160.40989 -32.777938)
			(xy 160.409636 -32.775144) (xy 160.409128 -32.76092) (xy 160.409128 -32.759904) (xy 160.408112 -32.714184)
			(xy 160.408547 -32.671598) (xy 160.415789 -32.586733) (xy 160.430243 -32.502796) (xy 160.451805 -32.420398)
			(xy 160.480317 -32.34014) (xy 160.49752 -32.30118) (xy 160.500701 -32.292047) (xy 160.500695 -32.272723)
			(xy 160.49752 -32.263588) (xy 160.480312 -32.224631) (xy 160.45182 -32.144367) (xy 160.43027 -32.061968)
			(xy 160.41582 -31.978032) (xy 160.408573 -31.89317) (xy 160.408112 -31.850584) (xy 160.409128 -31.804864)
			(xy 160.409128 -31.803848) (xy 160.409636 -31.789624) (xy 160.40989 -31.78683) (xy 160.40989 -31.783274)
			(xy 160.408112 -31.772352) (xy 160.406588 -31.76524) (xy 160.397952 -31.731712) (xy 160.392364 -31.697676)
			(xy 160.391094 -31.685484) (xy 160.38957 -31.652972) (xy 160.390116 -31.62392) (xy 160.398926 -31.566487)
			(xy 160.416339 -31.511052) (xy 160.441951 -31.458897) (xy 160.475172 -31.411225) (xy 160.515234 -31.369139)
			(xy 160.537906 -31.350966) (xy 160.54157 -31.348007) (xy 160.547836 -31.340977) (xy 160.550352 -31.336996)
			(xy 160.551368 -31.335218) (xy 160.552892 -31.332932) (xy 160.577468 -31.293482) (xy 160.632891 -31.218861)
			(xy 160.69502 -31.149723) (xy 160.763315 -31.086668) (xy 160.837182 -31.030244) (xy 160.915981 -30.980941)
			(xy 160.999027 -30.939187) (xy 161.085599 -30.905344) (xy 161.174945 -30.879707) (xy 161.26629 -30.862497)
			(xy 161.35884 -30.853865) (xy 161.405316 -30.85338) (xy 161.40557 -30.85338) (xy 161.44802 -30.85382)
			(xy 161.532613 -30.861038) (xy 161.616285 -30.875422) (xy 161.698432 -30.89687) (xy 161.778457 -30.925225)
			(xy 161.855781 -30.960283) (xy 161.929843 -31.00179) (xy 162.000108 -31.049444) (xy 162.066065 -31.1029)
			(xy 162.096958 -31.132018) (xy 162.103702 -31.137278) (xy 162.119667 -31.143381) (xy 162.1282 -31.143956)
			(xy 162.976814 -31.143956) (xy 162.983164 -31.143448) (xy 162.991657 -31.142068) (xy 163.007066 -31.134437)
			(xy 163.019073 -31.122128) (xy 163.023042 -31.114492) (xy 163.032694 -31.091124) (xy 163.033456 -31.083504)
			(xy 163.03371 -31.081218) (xy 163.03371 -31.080456) (xy 163.035993 -31.060694) (xy 163.044138 -31.021753)
			(xy 163.049966 -31.002732) (xy 163.051219 -30.998273) (xy 163.052238 -30.989069) (xy 163.051998 -30.984444)
			(xy 163.051998 -30.983936) (xy 163.051112 -30.96814) (xy 163.050222 -30.936511) (xy 163.05022 -30.92069)
			(xy 163.050655 -30.878103) (xy 163.057895 -30.793239) (xy 163.072348 -30.709301) (xy 163.093907 -30.626902)
			(xy 163.122416 -30.546642) (xy 163.139628 -30.507686) (xy 163.142809 -30.498553) (xy 163.142806 -30.479229)
			(xy 163.139628 -30.470094) (xy 163.12242 -30.431137) (xy 163.093927 -30.350874) (xy 163.072377 -30.268474)
			(xy 163.057925 -30.184538) (xy 163.050678 -30.099676) (xy 163.05022 -30.05709) (xy 163.050474 -30.030166)
			(xy 163.050474 -30.029912) (xy 163.050295 -30.020569) (xy 163.044046 -30.002976) (xy 163.038282 -29.995622)
			(xy 162.9918 -29.948124) (xy 162.98463 -29.942065) (xy 162.967144 -29.935268) (xy 162.957764 -29.934916)
			(xy 162.945826 -29.934916) (xy 162.899105 -29.934339) (xy 162.806086 -29.925451) (xy 162.714321 -29.907819)
			(xy 162.624632 -29.881599) (xy 162.53782 -29.847027) (xy 162.495992 -29.826204) (xy 162.490566 -29.823617)
			(xy 162.478886 -29.820785) (xy 162.472878 -29.820616) (xy 162.139376 -29.820616) (xy 162.134485 -29.82075)
			(xy 162.12489 -29.822664) (xy 162.120326 -29.824426) (xy 162.094926 -29.834586) (xy 162.094672 -29.83484)
			(xy 162.093402 -29.83611) (xy 162.088068 -29.84119) (xy 162.053506 -29.872926) (xy 161.979385 -29.930473)
			(xy 161.900187 -29.980805) (xy 161.816612 -30.023476) (xy 161.729399 -30.058108) (xy 161.639318 -30.084395)
			(xy 161.547166 -30.102106) (xy 161.453758 -30.111082) (xy 161.40684 -30.1117) (xy 161.405316 -30.1117)
			(xy 161.358789 -30.111146) (xy 161.266144 -30.102444) (xy 161.174711 -30.085151) (xy 161.085286 -30.059418)
			(xy 160.998647 -30.025468) (xy 160.915546 -29.983597) (xy 160.836706 -29.934168) (xy 160.762812 -29.877612)
			(xy 160.694507 -29.814419) (xy 160.632384 -29.745139) (xy 160.576983 -29.670374) (xy 160.552384 -29.630878)
			(xy 160.549844 -29.627068) (xy 160.53943 -29.61513) (xy 160.537906 -29.61386) (xy 160.515286 -29.595672)
			(xy 160.475293 -29.553612) (xy 160.442131 -29.505979) (xy 160.416565 -29.453874) (xy 160.399187 -29.398497)
			(xy 160.390395 -29.341128) (xy 160.389824 -29.312108) (xy 160.389824 -29.311854) (xy 160.390291 -29.283354)
			(xy 160.398716 -29.226981) (xy 160.406588 -29.199586) (xy 160.408112 -29.192474) (xy 160.40989 -29.181552)
			(xy 160.40989 -29.177996) (xy 160.409636 -29.175202) (xy 160.409128 -29.160978) (xy 160.409128 -29.159962)
			(xy 160.408112 -29.114242) (xy 160.408545 -29.071655) (xy 160.415781 -28.986789) (xy 160.430231 -28.90285)
			(xy 160.451789 -28.82045) (xy 160.480297 -28.740189) (xy 160.49752 -28.701238) (xy 160.500711 -28.692105)
			(xy 160.500726 -28.672773) (xy 160.49752 -28.663646) (xy 160.48031 -28.62469) (xy 160.451813 -28.544426)
			(xy 160.430259 -28.462027) (xy 160.415803 -28.378091) (xy 160.408551 -28.293228) (xy 160.408112 -28.250642)
			(xy 160.409128 -28.204922) (xy 160.409128 -28.203906) (xy 160.409636 -28.189682) (xy 160.40989 -28.186888)
			(xy 160.40989 -28.183332) (xy 160.408112 -28.17241) (xy 160.406588 -28.165298) (xy 160.397952 -28.13177)
			(xy 160.392364 -28.097734) (xy 160.391094 -28.085542) (xy 160.38957 -28.05303) (xy 160.390086 -28.024323)
			(xy 160.398682 -27.967557) (xy 160.415684 -27.912719) (xy 160.440709 -27.861047) (xy 160.473192 -27.813706)
			(xy 160.5124 -27.771766) (xy 160.534604 -27.753564) (xy 160.540446 -27.747976) (xy 160.550352 -27.737054)
			(xy 160.552892 -27.732736) (xy 160.577479 -27.693296) (xy 160.63292 -27.618697) (xy 160.695061 -27.549579)
			(xy 160.763362 -27.486541) (xy 160.837231 -27.43013) (xy 160.916027 -27.380835) (xy 160.999066 -27.339083)
			(xy 161.08563 -27.305237) (xy 161.174967 -27.279591) (xy 161.266302 -27.262366) (xy 161.358843 -27.253712)
			(xy 161.405316 -27.253184) (xy 161.452329 -27.253741) (xy 161.545935 -27.262619) (xy 161.63829 -27.280266)
			(xy 161.728574 -27.306525) (xy 161.815987 -27.341164) (xy 161.899752 -27.383874) (xy 161.979127 -27.434278)
			(xy 162.053406 -27.491927) (xy 162.088068 -27.523694) (xy 162.093402 -27.528774) (xy 162.094672 -27.530044)
			(xy 162.094926 -27.530298) (xy 162.120326 -27.540458) (xy 162.124893 -27.542211) (xy 162.134486 -27.544125)
			(xy 162.139376 -27.544268) (xy 164.040566 -27.544268) (xy 164.08603 -27.544795) (xy 164.176576 -27.553123)
			(xy 164.265987 -27.569669) (xy 164.353518 -27.594293) (xy 164.396166 -27.610054) (xy 164.422582 -27.620722)
			(xy 165.78834 -28.189428) (xy 165.810611 -28.198784) (xy 165.854318 -28.219367) (xy 165.875716 -28.230576)
			(xy 165.887146 -28.235148) (xy 165.888162 -28.235402) (xy 165.896587 -28.237185) (xy 165.913725 -28.235627)
			(xy 165.92169 -28.232354) (xy 165.943534 -28.222194) (xy 165.950646 -28.21432) (xy 165.968812 -28.194743)
			(xy 166.009674 -28.160356) (xy 166.054932 -28.132003) (xy 166.103702 -28.11024) (xy 166.155031 -28.095491)
			(xy 166.207915 -28.088045) (xy 166.234618 -28.087574) (xy 166.261869 -28.088061) (xy 166.315816 -28.095819)
			(xy 166.368109 -28.111176) (xy 166.417685 -28.133818) (xy 166.42596 -28.139136) (xy 170.498006 -28.139136)
			(xy 170.502077 -28.083514) (xy 170.514203 -28.029077) (xy 170.534126 -27.976986) (xy 170.561422 -27.928351)
			(xy 170.595508 -27.884208) (xy 170.635657 -27.845499) (xy 170.681015 -27.813048) (xy 170.730615 -27.787547)
			(xy 170.783399 -27.76954) (xy 170.838242 -27.75941) (xy 170.893976 -27.757373) (xy 170.949413 -27.763473)
			(xy 171.00337 -27.777579) (xy 171.054699 -27.799391) (xy 171.102305 -27.828445) (xy 171.145173 -27.86412)
			(xy 171.18239 -27.905657) (xy 171.213163 -27.95217) (xy 171.236835 -28.002667) (xy 171.252903 -28.056074)
			(xy 171.261023 -28.11125) (xy 171.261532 -28.139136) (xy 171.768006 -28.139136) (xy 171.772077 -28.083514)
			(xy 171.784203 -28.029077) (xy 171.804126 -27.976986) (xy 171.831422 -27.928351) (xy 171.865508 -27.884208)
			(xy 171.905657 -27.845499) (xy 171.951015 -27.813048) (xy 172.000615 -27.787547) (xy 172.053399 -27.76954)
			(xy 172.108242 -27.75941) (xy 172.163976 -27.757373) (xy 172.219413 -27.763473) (xy 172.27337 -27.777579)
			(xy 172.324699 -27.799391) (xy 172.372305 -27.828445) (xy 172.415173 -27.86412) (xy 172.45239 -27.905657)
			(xy 172.483163 -27.95217) (xy 172.506835 -28.002667) (xy 172.522903 -28.056074) (xy 172.531023 -28.11125)
			(xy 172.531532 -28.139136) (xy 172.531023 -28.167022) (xy 172.522903 -28.222198) (xy 172.506835 -28.275605)
			(xy 172.483163 -28.326102) (xy 172.45239 -28.372615) (xy 172.415173 -28.414152) (xy 172.372305 -28.449827)
			(xy 172.324699 -28.478881) (xy 172.27337 -28.500693) (xy 172.219413 -28.514799) (xy 172.163976 -28.520899)
			(xy 172.108242 -28.518862) (xy 172.053399 -28.508732) (xy 172.000615 -28.490725) (xy 171.951015 -28.465224)
			(xy 171.905657 -28.432773) (xy 171.865508 -28.394064) (xy 171.831422 -28.349921) (xy 171.804126 -28.301286)
			(xy 171.784203 -28.249195) (xy 171.772077 -28.194758) (xy 171.768006 -28.139136) (xy 171.261532 -28.139136)
			(xy 171.261023 -28.167022) (xy 171.252903 -28.222198) (xy 171.236835 -28.275605) (xy 171.213163 -28.326102)
			(xy 171.18239 -28.372615) (xy 171.145173 -28.414152) (xy 171.102305 -28.449827) (xy 171.054699 -28.478881)
			(xy 171.00337 -28.500693) (xy 170.949413 -28.514799) (xy 170.893976 -28.520899) (xy 170.838242 -28.518862)
			(xy 170.783399 -28.508732) (xy 170.730615 -28.490725) (xy 170.681015 -28.465224) (xy 170.635657 -28.432773)
			(xy 170.595508 -28.394064) (xy 170.561422 -28.349921) (xy 170.534126 -28.301286) (xy 170.514203 -28.249195)
			(xy 170.502077 -28.194758) (xy 170.498006 -28.139136) (xy 166.42596 -28.139136) (xy 166.463535 -28.163284)
			(xy 166.504724 -28.198976) (xy 166.540416 -28.240165) (xy 166.569882 -28.286015) (xy 166.592524 -28.335591)
			(xy 166.607881 -28.387884) (xy 166.615639 -28.441831) (xy 166.616126 -28.469082) (xy 166.615674 -28.495877)
			(xy 166.60818 -28.548939) (xy 166.593335 -28.600431) (xy 166.571434 -28.64934) (xy 166.542905 -28.694704)
			(xy 166.525956 -28.715462) (xy 166.521296 -28.721249) (xy 166.515221 -28.734801) (xy 166.514018 -28.742132)
			(xy 166.513764 -28.751022) (xy 166.515288 -28.78201) (xy 166.515542 -28.788614) (xy 166.515796 -28.7909)
			(xy 166.51698 -28.799724) (xy 166.524502 -28.815845) (xy 166.530528 -28.822396) (xy 166.617142 -28.908502)
			(xy 166.832476 -29.12237) (xy 176.706784 -29.12237) (xy 176.706784 -28.25877) (xy 176.707274 -28.228786)
			(xy 176.715102 -28.16933) (xy 176.730623 -28.111405) (xy 176.753572 -28.056001) (xy 176.783556 -28.004067)
			(xy 176.820062 -27.956491) (xy 176.862467 -27.914086) (xy 176.910043 -27.87758) (xy 176.961977 -27.847596)
			(xy 177.017381 -27.824647) (xy 177.075306 -27.809126) (xy 177.134762 -27.801298) (xy 177.19473 -27.801298)
			(xy 177.254186 -27.809126) (xy 177.312111 -27.824647) (xy 177.367515 -27.847596) (xy 177.419449 -27.87758)
			(xy 177.467025 -27.914086) (xy 177.50943 -27.956491) (xy 177.545936 -28.004067) (xy 177.57592 -28.056001)
			(xy 177.598869 -28.111405) (xy 177.61439 -28.16933) (xy 177.622218 -28.228786) (xy 177.622708 -28.25877)
			(xy 177.622708 -29.12237) (xy 177.622218 -29.152354) (xy 177.61439 -29.21181) (xy 177.598869 -29.269735)
			(xy 177.57592 -29.325139) (xy 177.545936 -29.377073) (xy 177.50943 -29.424649) (xy 177.467025 -29.467054)
			(xy 177.419449 -29.50356) (xy 177.367515 -29.533544) (xy 177.312111 -29.556493) (xy 177.254186 -29.572014)
			(xy 177.19473 -29.579842) (xy 177.134762 -29.579842) (xy 177.075306 -29.572014) (xy 177.017381 -29.556493)
			(xy 176.961977 -29.533544) (xy 176.910043 -29.50356) (xy 176.862467 -29.467054) (xy 176.820062 -29.424649)
			(xy 176.783556 -29.377073) (xy 176.753572 -29.325139) (xy 176.730623 -29.269735) (xy 176.715102 -29.21181)
			(xy 176.707274 -29.152354) (xy 176.706784 -29.12237) (xy 166.832476 -29.12237) (xy 167.176704 -29.464254)
			(xy 167.183111 -29.470131) (xy 167.198826 -29.477543) (xy 167.207438 -29.478732) (xy 167.216074 -29.479494)
			(xy 167.233092 -29.475176) (xy 167.240966 -29.469842) (xy 167.248078 -29.465016) (xy 167.248586 -29.465016)
			(xy 167.257984 -29.45892) (xy 167.258238 -29.45892) (xy 167.259 -29.458412) (xy 167.269668 -29.452316)
			(xy 167.297737 -29.437169) (xy 167.357688 -29.415411) (xy 167.420418 -29.403904) (xy 167.452294 -29.402786)
			(xy 167.464232 -29.402786) (xy 167.490875 -29.403693) (xy 167.543528 -29.412029) (xy 167.594509 -29.427614)
			(xy 167.642823 -29.450142) (xy 167.687532 -29.479177) (xy 167.727765 -29.514151) (xy 167.762737 -29.554386)
			(xy 167.791769 -29.599096) (xy 167.814294 -29.647412) (xy 167.829876 -29.698394) (xy 167.838209 -29.751047)
			(xy 167.839136 -29.77769) (xy 167.839136 -29.786326) (xy 167.838636 -29.810483) (xy 167.832265 -29.858381)
			(xy 167.826436 -29.88183) (xy 167.817581 -29.912915) (xy 167.790892 -29.971776) (xy 167.77335 -29.998924)
			(xy 167.768524 -30.005782) (xy 167.762936 -30.014418) (xy 167.764714 -30.032198) (xy 167.765949 -30.040893)
			(xy 167.773471 -30.05675) (xy 167.779446 -30.063186) (xy 168.095042 -30.376876) (xy 168.988994 -30.376876)
			(xy 168.989531 -30.347959) (xy 168.998251 -30.290787) (xy 169.015503 -30.235587) (xy 169.040891 -30.183625)
			(xy 169.073833 -30.136091) (xy 169.113574 -30.094075) (xy 169.13606 -30.075886) (xy 169.144874 -30.068286)
			(xy 169.155051 -30.047379) (xy 169.155618 -30.035754) (xy 169.155618 -29.955998) (xy 169.155059 -29.944369)
			(xy 169.144884 -29.923459) (xy 169.13606 -29.915866) (xy 169.113552 -29.897704) (xy 169.07382 -29.855677)
			(xy 169.040885 -29.808136) (xy 169.015501 -29.756169) (xy 168.99825 -29.700967) (xy 168.989526 -29.643794)
			(xy 168.988994 -29.614876) (xy 168.98948 -29.587625) (xy 168.997236 -29.533677) (xy 169.012591 -29.481382)
			(xy 169.035233 -29.431805) (xy 169.064699 -29.385955) (xy 169.10039 -29.344764) (xy 169.141581 -29.309073)
			(xy 169.187431 -29.279607) (xy 169.237008 -29.256965) (xy 169.289303 -29.24161) (xy 169.343251 -29.233854)
			(xy 169.397753 -29.233854) (xy 169.451701 -29.24161) (xy 169.503996 -29.256965) (xy 169.553573 -29.279607)
			(xy 169.599423 -29.309073) (xy 169.640614 -29.344764) (xy 169.676305 -29.385955) (xy 169.705771 -29.431805)
			(xy 169.728413 -29.481382) (xy 169.743768 -29.533677) (xy 169.751524 -29.587625) (xy 169.75201 -29.614876)
			(xy 169.751509 -29.643794) (xy 169.742781 -29.700968) (xy 169.725522 -29.756168) (xy 169.700127 -29.808131)
			(xy 169.667179 -29.855664) (xy 169.627432 -29.897678) (xy 169.604944 -29.915866) (xy 169.596153 -29.923488)
			(xy 169.585963 -29.944378) (xy 169.585386 -29.955998) (xy 169.585386 -30.035754) (xy 169.585913 -30.047387)
			(xy 169.596111 -30.068296) (xy 169.604944 -30.075886) (xy 169.62743 -30.094074) (xy 169.667163 -30.136096)
			(xy 169.7001 -30.183632) (xy 169.725488 -30.235593) (xy 169.742744 -30.290791) (xy 169.751474 -30.34796)
			(xy 169.75201 -30.376876) (xy 172.02912 -30.376876) (xy 172.029685 -30.347961) (xy 172.038403 -30.290791)
			(xy 172.055651 -30.235593) (xy 172.081034 -30.183631) (xy 172.11397 -30.136096) (xy 172.153704 -30.094077)
			(xy 172.176186 -30.075886) (xy 172.185004 -30.06829) (xy 172.195178 -30.04738) (xy 172.195744 -30.035754)
			(xy 172.195744 -29.955998) (xy 172.195211 -29.944365) (xy 172.18502 -29.923454) (xy 172.176186 -29.915866)
			(xy 172.153683 -29.897698) (xy 172.11395 -29.855673) (xy 172.081014 -29.808133) (xy 172.055629 -29.756167)
			(xy 172.038377 -29.700966) (xy 172.029652 -29.643793) (xy 172.02912 -29.614876) (xy 172.029606 -29.587625)
			(xy 172.037362 -29.533677) (xy 172.052717 -29.481382) (xy 172.075359 -29.431805) (xy 172.104825 -29.385955)
			(xy 172.140516 -29.344764) (xy 172.181707 -29.309073) (xy 172.227557 -29.279607) (xy 172.277134 -29.256965)
			(xy 172.329429 -29.24161) (xy 172.383377 -29.233854) (xy 172.437879 -29.233854) (xy 172.491827 -29.24161)
			(xy 172.544122 -29.256965) (xy 172.593699 -29.279607) (xy 172.639549 -29.309073) (xy 172.68074 -29.344764)
			(xy 172.716431 -29.385955) (xy 172.745897 -29.431805) (xy 172.768539 -29.481382) (xy 172.783894 -29.533677)
			(xy 172.79165 -29.587625) (xy 172.792136 -29.614876) (xy 172.791625 -29.643793) (xy 172.782898 -29.700966)
			(xy 172.76564 -29.756166) (xy 172.740247 -29.808128) (xy 172.707301 -29.855662) (xy 172.667557 -29.897677)
			(xy 172.64507 -29.915866) (xy 172.636283 -29.923493) (xy 172.62609 -29.944379) (xy 172.625512 -29.955998)
			(xy 172.625512 -30.035754) (xy 172.62603 -30.047389) (xy 172.636233 -30.068298) (xy 172.64507 -30.075886)
			(xy 172.667541 -30.094093) (xy 172.707278 -30.136108) (xy 172.740219 -30.18364) (xy 172.76561 -30.235598)
			(xy 172.782869 -30.290793) (xy 172.7916 -30.347961) (xy 172.792136 -30.376876) (xy 172.79165 -30.404127)
			(xy 172.783894 -30.458075) (xy 172.768539 -30.51037) (xy 172.745897 -30.559947) (xy 172.716431 -30.605797)
			(xy 172.68074 -30.646988) (xy 172.639549 -30.682679) (xy 172.593699 -30.712145) (xy 172.544122 -30.734787)
			(xy 172.491827 -30.750142) (xy 172.437879 -30.757898) (xy 172.383377 -30.757898) (xy 172.329429 -30.750142)
			(xy 172.277134 -30.734787) (xy 172.227557 -30.712145) (xy 172.181707 -30.682679) (xy 172.140516 -30.646988)
			(xy 172.104825 -30.605797) (xy 172.075359 -30.559947) (xy 172.052717 -30.51037) (xy 172.037362 -30.458075)
			(xy 172.029606 -30.404127) (xy 172.02912 -30.376876) (xy 169.75201 -30.376876) (xy 169.751524 -30.404127)
			(xy 169.743768 -30.458075) (xy 169.728413 -30.51037) (xy 169.705771 -30.559947) (xy 169.676305 -30.605797)
			(xy 169.640614 -30.646988) (xy 169.599423 -30.682679) (xy 169.553573 -30.712145) (xy 169.503996 -30.734787)
			(xy 169.451701 -30.750142) (xy 169.397753 -30.757898) (xy 169.343251 -30.757898) (xy 169.289303 -30.750142)
			(xy 169.237008 -30.734787) (xy 169.187431 -30.712145) (xy 169.141581 -30.682679) (xy 169.10039 -30.646988)
			(xy 169.064699 -30.605797) (xy 169.035233 -30.559947) (xy 169.012591 -30.51037) (xy 168.997236 -30.458075)
			(xy 168.98948 -30.404127) (xy 168.988994 -30.376876) (xy 168.095042 -30.376876) (xy 168.643948 -30.922468)
			(xy 174.852584 -30.922468) (xy 174.852584 -30.058868) (xy 174.853074 -30.028884) (xy 174.860902 -29.969428)
			(xy 174.876423 -29.911503) (xy 174.899372 -29.856099) (xy 174.929356 -29.804165) (xy 174.965862 -29.756589)
			(xy 175.008267 -29.714184) (xy 175.055843 -29.677678) (xy 175.107777 -29.647694) (xy 175.163181 -29.624745)
			(xy 175.221106 -29.609224) (xy 175.280562 -29.601396) (xy 175.34053 -29.601396) (xy 175.399986 -29.609224)
			(xy 175.457911 -29.624745) (xy 175.513315 -29.647694) (xy 175.565249 -29.677678) (xy 175.612825 -29.714184)
			(xy 175.65523 -29.756589) (xy 175.691736 -29.804165) (xy 175.72172 -29.856099) (xy 175.744669 -29.911503)
			(xy 175.76019 -29.969428) (xy 175.768018 -30.028884) (xy 175.768508 -30.058868) (xy 175.768508 -30.922468)
			(xy 175.768018 -30.952452) (xy 175.76019 -31.011908) (xy 175.744669 -31.069833) (xy 175.72172 -31.125237)
			(xy 175.691736 -31.177171) (xy 175.65523 -31.224747) (xy 175.612825 -31.267152) (xy 175.565249 -31.303658)
			(xy 175.513315 -31.333642) (xy 175.457911 -31.356591) (xy 175.399986 -31.372112) (xy 175.34053 -31.37994)
			(xy 175.280562 -31.37994) (xy 175.221106 -31.372112) (xy 175.163181 -31.356591) (xy 175.107777 -31.333642)
			(xy 175.055843 -31.303658) (xy 175.008267 -31.267152) (xy 174.965862 -31.224747) (xy 174.929356 -31.177171)
			(xy 174.899372 -31.125237) (xy 174.876423 -31.069833) (xy 174.860902 -31.011908) (xy 174.853074 -30.952452)
			(xy 174.852584 -30.922468) (xy 168.643948 -30.922468) (xy 168.87317 -31.150306) (xy 168.901201 -31.178679)
			(xy 168.953148 -31.239209) (xy 169.000097 -31.303693) (xy 169.021252 -31.337504) (xy 169.02303 -31.340298)
			(xy 169.032936 -31.3563) (xy 169.040024 -31.366199) (xy 169.060973 -31.378537) (xy 169.073068 -31.379922)
			(xy 169.120058 -31.380684) (xy 169.128277 -31.380034) (xy 169.143691 -31.374205) (xy 169.150284 -31.369254)
			(xy 169.151046 -31.368746) (xy 169.154094 -31.365952) (xy 169.161968 -31.358078) (xy 169.164762 -31.354014)
			(xy 169.164762 -31.35376) (xy 169.180075 -31.33204) (xy 169.215745 -31.292648) (xy 169.256529 -31.258578)
			(xy 169.301638 -31.230485) (xy 169.350205 -31.208912) (xy 169.401292 -31.194276) (xy 169.453913 -31.186857)
			(xy 169.480484 -31.186374) (xy 169.480992 -31.186374) (xy 169.51706 -31.187898) (xy 169.525442 -31.188914)
			(xy 169.552933 -31.192656) (xy 169.60651 -31.207064) (xy 169.657434 -31.229083) (xy 169.70463 -31.258247)
			(xy 169.747104 -31.293942) (xy 169.783957 -31.335414) (xy 169.814413 -31.381787) (xy 169.837829 -31.432084)
			(xy 169.85371 -31.485243) (xy 169.861722 -31.540142) (xy 169.862246 -31.567882) (xy 169.861744 -31.595678)
			(xy 169.853675 -31.650682) (xy 169.837704 -31.703932) (xy 169.830539 -31.719266) (xy 170.385484 -31.719266)
			(xy 170.389555 -31.663644) (xy 170.401681 -31.609207) (xy 170.421604 -31.557116) (xy 170.4489 -31.508481)
			(xy 170.482986 -31.464338) (xy 170.523135 -31.425629) (xy 170.568493 -31.393178) (xy 170.618093 -31.367677)
			(xy 170.670877 -31.34967) (xy 170.72572 -31.33954) (xy 170.781454 -31.337503) (xy 170.836891 -31.343603)
			(xy 170.890848 -31.357709) (xy 170.942177 -31.379521) (xy 170.989783 -31.408575) (xy 171.032651 -31.44425)
			(xy 171.069868 -31.485787) (xy 171.100641 -31.5323) (xy 171.124313 -31.582797) (xy 171.140381 -31.636204)
			(xy 171.144531 -31.664402) (xy 171.661072 -31.664402) (xy 171.665143 -31.60878) (xy 171.677269 -31.554343)
			(xy 171.697192 -31.502252) (xy 171.724488 -31.453617) (xy 171.758574 -31.409474) (xy 171.798723 -31.370765)
			(xy 171.844081 -31.338314) (xy 171.893681 -31.312813) (xy 171.946465 -31.294806) (xy 172.001308 -31.284676)
			(xy 172.057042 -31.282639) (xy 172.112479 -31.288739) (xy 172.166436 -31.302845) (xy 172.217765 -31.324657)
			(xy 172.265371 -31.353711) (xy 172.308239 -31.389386) (xy 172.345456 -31.430923) (xy 172.376229 -31.477436)
			(xy 172.399901 -31.527933) (xy 172.415969 -31.58134) (xy 172.424089 -31.636516) (xy 172.424598 -31.664402)
			(xy 172.424089 -31.692288) (xy 172.415969 -31.747464) (xy 172.407029 -31.777178) (xy 172.926246 -31.777178)
			(xy 172.930317 -31.721556) (xy 172.942443 -31.667119) (xy 172.962366 -31.615028) (xy 172.989662 -31.566393)
			(xy 173.023748 -31.52225) (xy 173.063897 -31.483541) (xy 173.109255 -31.45109) (xy 173.158855 -31.425589)
			(xy 173.211639 -31.407582) (xy 173.266482 -31.397452) (xy 173.322216 -31.395415) (xy 173.377653 -31.401515)
			(xy 173.43161 -31.415621) (xy 173.482939 -31.437433) (xy 173.530545 -31.466487) (xy 173.573413 -31.502162)
			(xy 173.61063 -31.543699) (xy 173.641403 -31.590212) (xy 173.665075 -31.640709) (xy 173.681143 -31.694116)
			(xy 173.689263 -31.749292) (xy 173.689772 -31.777178) (xy 173.689263 -31.805064) (xy 173.681143 -31.86024)
			(xy 173.665075 -31.913647) (xy 173.641403 -31.964144) (xy 173.61063 -32.010657) (xy 173.573413 -32.052194)
			(xy 173.530545 -32.087869) (xy 173.482939 -32.116923) (xy 173.43161 -32.138735) (xy 173.377653 -32.152841)
			(xy 173.322216 -32.158941) (xy 173.266482 -32.156904) (xy 173.211639 -32.146774) (xy 173.158855 -32.128767)
			(xy 173.109255 -32.103266) (xy 173.063897 -32.070815) (xy 173.023748 -32.032106) (xy 172.989662 -31.987963)
			(xy 172.962366 -31.939328) (xy 172.942443 -31.887237) (xy 172.930317 -31.8328) (xy 172.926246 -31.777178)
			(xy 172.407029 -31.777178) (xy 172.399901 -31.800871) (xy 172.376229 -31.851368) (xy 172.345456 -31.897881)
			(xy 172.308239 -31.939418) (xy 172.265371 -31.975093) (xy 172.217765 -32.004147) (xy 172.166436 -32.025959)
			(xy 172.112479 -32.040065) (xy 172.057042 -32.046165) (xy 172.001308 -32.044128) (xy 171.946465 -32.033998)
			(xy 171.893681 -32.015991) (xy 171.844081 -31.99049) (xy 171.798723 -31.958039) (xy 171.758574 -31.91933)
			(xy 171.724488 -31.875187) (xy 171.697192 -31.826552) (xy 171.677269 -31.774461) (xy 171.665143 -31.720024)
			(xy 171.661072 -31.664402) (xy 171.144531 -31.664402) (xy 171.148501 -31.69138) (xy 171.14901 -31.719266)
			(xy 171.148501 -31.747152) (xy 171.140381 -31.802328) (xy 171.124313 -31.855735) (xy 171.100641 -31.906232)
			(xy 171.069868 -31.952745) (xy 171.032651 -31.994282) (xy 170.989783 -32.029957) (xy 170.942177 -32.059011)
			(xy 170.890848 -32.080823) (xy 170.836891 -32.094929) (xy 170.781454 -32.101029) (xy 170.72572 -32.098992)
			(xy 170.670877 -32.088862) (xy 170.618093 -32.070855) (xy 170.568493 -32.045354) (xy 170.523135 -32.012903)
			(xy 170.482986 -31.974194) (xy 170.4489 -31.930051) (xy 170.421604 -31.881416) (xy 170.401681 -31.829325)
			(xy 170.389555 -31.774888) (xy 170.385484 -31.719266) (xy 169.830539 -31.719266) (xy 169.814171 -31.754298)
			(xy 169.783574 -31.800714) (xy 169.746562 -31.842195) (xy 169.70392 -31.877862) (xy 169.65655 -31.906959)
			(xy 169.605457 -31.92887) (xy 169.551724 -31.94313) (xy 169.524172 -31.94685) (xy 169.52214 -31.947104)
			(xy 169.510591 -31.949509) (xy 169.491382 -31.963152) (xy 169.48531 -31.973266) (xy 169.465498 -32.013652)
			(xy 169.462958 -32.018986) (xy 169.459057 -32.029584) (xy 169.459841 -32.052126) (xy 169.464482 -32.06242)
			(xy 169.867909 -32.722312) (xy 176.706784 -32.722312) (xy 176.706784 -31.858712) (xy 176.707274 -31.828728)
			(xy 176.715102 -31.769272) (xy 176.730623 -31.711347) (xy 176.753572 -31.655943) (xy 176.783556 -31.604009)
			(xy 176.820062 -31.556433) (xy 176.862467 -31.514028) (xy 176.910043 -31.477522) (xy 176.961977 -31.447538)
			(xy 177.017381 -31.424589) (xy 177.075306 -31.409068) (xy 177.134762 -31.40124) (xy 177.19473 -31.40124)
			(xy 177.254186 -31.409068) (xy 177.312111 -31.424589) (xy 177.367515 -31.447538) (xy 177.419449 -31.477522)
			(xy 177.467025 -31.514028) (xy 177.50943 -31.556433) (xy 177.545936 -31.604009) (xy 177.57592 -31.655943)
			(xy 177.598869 -31.711347) (xy 177.61439 -31.769272) (xy 177.622218 -31.828728) (xy 177.622708 -31.858712)
			(xy 177.622708 -32.722312) (xy 177.622218 -32.752296) (xy 177.61439 -32.811752) (xy 177.598869 -32.869677)
			(xy 177.57592 -32.925081) (xy 177.545936 -32.977015) (xy 177.50943 -33.024591) (xy 177.467025 -33.066996)
			(xy 177.419449 -33.103502) (xy 177.367515 -33.133486) (xy 177.312111 -33.156435) (xy 177.254186 -33.171956)
			(xy 177.19473 -33.179784) (xy 177.134762 -33.179784) (xy 177.075306 -33.171956) (xy 177.017381 -33.156435)
			(xy 176.961977 -33.133486) (xy 176.910043 -33.103502) (xy 176.862467 -33.066996) (xy 176.820062 -33.024591)
			(xy 176.783556 -32.977015) (xy 176.753572 -32.925081) (xy 176.730623 -32.869677) (xy 176.715102 -32.811752)
			(xy 176.707274 -32.752296) (xy 176.706784 -32.722312) (xy 169.867909 -32.722312) (xy 170.142916 -33.172146)
			(xy 170.516804 -33.783524) (xy 170.522512 -33.792045) (xy 170.539155 -33.803995) (xy 170.549062 -33.806638)
			(xy 170.551348 -33.807146) (xy 170.577189 -33.812127) (xy 170.627283 -33.828251) (xy 170.674691 -33.851096)
			(xy 170.718516 -33.880231) (xy 170.757927 -33.915105) (xy 170.79218 -33.955057) (xy 170.820626 -33.999332)
			(xy 170.842727 -34.047092) (xy 170.858065 -34.097432) (xy 170.866349 -34.149402) (xy 170.867324 -34.1757)
			(xy 170.86707 -34.189162) (xy 170.866546 -34.208111) (xy 170.862222 -34.245772) (xy 170.858434 -34.264346)
			(xy 170.855894 -34.275776) (xy 170.858434 -34.28619) (xy 170.859838 -34.291634) (xy 170.864701 -34.301768)
			(xy 170.868086 -34.306256) (xy 171.04039 -34.52241) (xy 174.852584 -34.52241) (xy 174.852584 -33.65881)
			(xy 174.853074 -33.628826) (xy 174.860902 -33.56937) (xy 174.876423 -33.511445) (xy 174.899372 -33.456041)
			(xy 174.929356 -33.404107) (xy 174.965862 -33.356531) (xy 175.008267 -33.314126) (xy 175.055843 -33.27762)
			(xy 175.107777 -33.247636) (xy 175.163181 -33.224687) (xy 175.221106 -33.209166) (xy 175.280562 -33.201338)
			(xy 175.34053 -33.201338) (xy 175.399986 -33.209166) (xy 175.457911 -33.224687) (xy 175.513315 -33.247636)
			(xy 175.565249 -33.27762) (xy 175.612825 -33.314126) (xy 175.65523 -33.356531) (xy 175.691736 -33.404107)
			(xy 175.72172 -33.456041) (xy 175.744669 -33.511445) (xy 175.76019 -33.56937) (xy 175.768018 -33.628826)
			(xy 175.768508 -33.65881) (xy 175.768508 -34.52241) (xy 175.768018 -34.552394) (xy 175.76019 -34.61185)
			(xy 175.744669 -34.669775) (xy 175.72172 -34.725179) (xy 175.691736 -34.777113) (xy 175.65523 -34.824689)
			(xy 175.612825 -34.867094) (xy 175.565249 -34.9036) (xy 175.513315 -34.933584) (xy 175.457911 -34.956533)
			(xy 175.399986 -34.972054) (xy 175.34053 -34.979882) (xy 175.280562 -34.979882) (xy 175.221106 -34.972054)
			(xy 175.163181 -34.956533) (xy 175.107777 -34.933584) (xy 175.055843 -34.9036) (xy 175.008267 -34.867094)
			(xy 174.965862 -34.824689) (xy 174.929356 -34.777113) (xy 174.899372 -34.725179) (xy 174.876423 -34.669775)
			(xy 174.860902 -34.61185) (xy 174.853074 -34.552394) (xy 174.852584 -34.52241) (xy 171.04039 -34.52241)
			(xy 171.632215 -35.264852) (xy 172.002448 -35.264852) (xy 172.006519 -35.20923) (xy 172.018645 -35.154793)
			(xy 172.038568 -35.102702) (xy 172.065864 -35.054067) (xy 172.09995 -35.009924) (xy 172.140099 -34.971215)
			(xy 172.185457 -34.938764) (xy 172.235057 -34.913263) (xy 172.287841 -34.895256) (xy 172.342684 -34.885126)
			(xy 172.398418 -34.883089) (xy 172.453855 -34.889189) (xy 172.507812 -34.903295) (xy 172.559141 -34.925107)
			(xy 172.606747 -34.954161) (xy 172.649615 -34.989836) (xy 172.686832 -35.031373) (xy 172.717605 -35.077886)
			(xy 172.741277 -35.128383) (xy 172.757345 -35.18179) (xy 172.765465 -35.236966) (xy 172.765974 -35.264852)
			(xy 172.765465 -35.292738) (xy 172.757345 -35.347914) (xy 172.741277 -35.401321) (xy 172.717605 -35.451818)
			(xy 172.686832 -35.498331) (xy 172.649615 -35.539868) (xy 172.606747 -35.575543) (xy 172.559141 -35.604597)
			(xy 172.507812 -35.626409) (xy 172.453855 -35.640515) (xy 172.398418 -35.646615) (xy 172.342684 -35.644578)
			(xy 172.287841 -35.634448) (xy 172.235057 -35.616441) (xy 172.185457 -35.59094) (xy 172.140099 -35.558489)
			(xy 172.09995 -35.51978) (xy 172.065864 -35.475637) (xy 172.038568 -35.427002) (xy 172.018645 -35.374911)
			(xy 172.006519 -35.320474) (xy 172.002448 -35.264852) (xy 171.632215 -35.264852) (xy 172.446961 -36.286948)
			(xy 173.300388 -36.286948) (xy 173.304459 -36.231326) (xy 173.316585 -36.176889) (xy 173.336508 -36.124798)
			(xy 173.363804 -36.076163) (xy 173.39789 -36.03202) (xy 173.438039 -35.993311) (xy 173.483397 -35.96086)
			(xy 173.532997 -35.935359) (xy 173.585781 -35.917352) (xy 173.640624 -35.907222) (xy 173.696358 -35.905185)
			(xy 173.751795 -35.911285) (xy 173.805752 -35.925391) (xy 173.857081 -35.947203) (xy 173.904687 -35.976257)
			(xy 173.947555 -36.011932) (xy 173.984772 -36.053469) (xy 174.015545 -36.099982) (xy 174.039217 -36.150479)
			(xy 174.055285 -36.203886) (xy 174.063405 -36.259062) (xy 174.063914 -36.286948) (xy 174.063405 -36.314834)
			(xy 174.055285 -36.37001) (xy 174.039217 -36.423417) (xy 174.015545 -36.473914) (xy 173.988 -36.515548)
			(xy 175.114202 -36.515548) (xy 175.118273 -36.459926) (xy 175.130399 -36.405489) (xy 175.150322 -36.353398)
			(xy 175.177618 -36.304763) (xy 175.211704 -36.26062) (xy 175.251853 -36.221911) (xy 175.297211 -36.18946)
			(xy 175.346811 -36.163959) (xy 175.399595 -36.145952) (xy 175.454438 -36.135822) (xy 175.510172 -36.133785)
			(xy 175.565609 -36.139885) (xy 175.619566 -36.153991) (xy 175.670895 -36.175803) (xy 175.718501 -36.204857)
			(xy 175.761369 -36.240532) (xy 175.798586 -36.282069) (xy 175.829359 -36.328582) (xy 175.853031 -36.379079)
			(xy 175.869099 -36.432486) (xy 175.877219 -36.487662) (xy 175.877728 -36.515548) (xy 175.877219 -36.543434)
			(xy 175.869099 -36.59861) (xy 175.868642 -36.60013) (xy 180.098199 -36.60013) (xy 180.102204 -36.512222)
			(xy 180.114187 -36.425042) (xy 180.134047 -36.339313) (xy 180.161622 -36.255745) (xy 180.196681 -36.175031)
			(xy 180.238934 -36.097839) (xy 180.288032 -36.02481) (xy 180.343568 -35.956548) (xy 180.40508 -35.893618)
			(xy 180.472061 -35.836544) (xy 180.543954 -35.785796) (xy 180.620163 -35.741796) (xy 180.700058 -35.704909)
			(xy 180.782977 -35.67544) (xy 180.868232 -35.653633) (xy 180.955116 -35.639669) (xy 181.04291 -35.633663)
			(xy 181.130887 -35.635667) (xy 181.218317 -35.645662) (xy 181.304476 -35.663566) (xy 181.38865 -35.68923)
			(xy 181.470141 -35.722443) (xy 181.548275 -35.762929) (xy 181.622403 -35.810351) (xy 181.691911 -35.864318)
			(xy 181.70521 -35.876738) (xy 186.817252 -35.876738) (xy 186.821323 -35.821116) (xy 186.833449 -35.766679)
			(xy 186.853372 -35.714588) (xy 186.880668 -35.665953) (xy 186.914754 -35.62181) (xy 186.954903 -35.583101)
			(xy 187.000261 -35.55065) (xy 187.049861 -35.525149) (xy 187.102645 -35.507142) (xy 187.157488 -35.497012)
			(xy 187.213222 -35.494975) (xy 187.268659 -35.501075) (xy 187.322616 -35.515181) (xy 187.373945 -35.536993)
			(xy 187.421551 -35.566047) (xy 187.464419 -35.601722) (xy 187.501636 -35.643259) (xy 187.532409 -35.689772)
			(xy 187.556081 -35.740269) (xy 187.572149 -35.793676) (xy 187.580269 -35.848852) (xy 187.580778 -35.876738)
			(xy 187.580269 -35.904624) (xy 187.572149 -35.9598) (xy 187.556081 -36.013207) (xy 187.532409 -36.063704)
			(xy 187.501636 -36.110217) (xy 187.464419 -36.151754) (xy 187.421551 -36.187429) (xy 187.373945 -36.216483)
			(xy 187.322616 -36.238295) (xy 187.268659 -36.252401) (xy 187.213222 -36.258501) (xy 187.157488 -36.256464)
			(xy 187.102645 -36.246334) (xy 187.049861 -36.228327) (xy 187.000261 -36.202826) (xy 186.954903 -36.170375)
			(xy 186.914754 -36.131666) (xy 186.880668 -36.087523) (xy 186.853372 -36.038888) (xy 186.833449 -35.986797)
			(xy 186.821323 -35.93236) (xy 186.817252 -35.876738) (xy 181.70521 -35.876738) (xy 181.756225 -35.924383)
			(xy 181.814809 -35.990047) (xy 181.86718 -36.060766) (xy 181.912903 -36.135954) (xy 181.9516 -36.214989)
			(xy 181.982949 -36.297215) (xy 182.006691 -36.381951) (xy 182.022629 -36.468495) (xy 182.026415 -36.50996)
			(xy 188.71387 -36.50996) (xy 188.717941 -36.454338) (xy 188.730067 -36.399901) (xy 188.74999 -36.34781)
			(xy 188.777286 -36.299175) (xy 188.811372 -36.255032) (xy 188.851521 -36.216323) (xy 188.896879 -36.183872)
			(xy 188.946479 -36.158371) (xy 188.999263 -36.140364) (xy 189.054106 -36.130234) (xy 189.10984 -36.128197)
			(xy 189.165277 -36.134297) (xy 189.219234 -36.148403) (xy 189.270563 -36.170215) (xy 189.318169 -36.199269)
			(xy 189.361037 -36.234944) (xy 189.398254 -36.276481) (xy 189.429027 -36.322994) (xy 189.452699 -36.373491)
			(xy 189.468767 -36.426898) (xy 189.476887 -36.482074) (xy 189.477396 -36.50996) (xy 189.476887 -36.537846)
			(xy 189.468767 -36.593022) (xy 189.452699 -36.646429) (xy 189.429027 -36.696926) (xy 189.398254 -36.743439)
			(xy 189.361037 -36.784976) (xy 189.318169 -36.820651) (xy 189.270563 -36.849705) (xy 189.219234 -36.871517)
			(xy 189.165277 -36.885623) (xy 189.10984 -36.891723) (xy 189.054106 -36.889686) (xy 188.999263 -36.879556)
			(xy 188.946479 -36.861549) (xy 188.896879 -36.836048) (xy 188.851521 -36.803597) (xy 188.811372 -36.764888)
			(xy 188.777286 -36.720745) (xy 188.74999 -36.67211) (xy 188.730067 -36.620019) (xy 188.717941 -36.565582)
			(xy 188.71387 -36.50996) (xy 182.026415 -36.50996) (xy 182.030631 -36.55613) (xy 182.031132 -36.60013)
			(xy 182.030631 -36.64413) (xy 182.022629 -36.731765) (xy 182.006691 -36.818309) (xy 181.982949 -36.903045)
			(xy 181.9516 -36.985271) (xy 181.912903 -37.064306) (xy 181.86718 -37.139494) (xy 181.814809 -37.210213)
			(xy 181.756225 -37.275877) (xy 181.691911 -37.335942) (xy 181.622403 -37.389909) (xy 181.548275 -37.437331)
			(xy 181.475269 -37.47516) (xy 185.859164 -37.47516) (xy 185.863235 -37.419538) (xy 185.875361 -37.365101)
			(xy 185.895284 -37.31301) (xy 185.92258 -37.264375) (xy 185.956666 -37.220232) (xy 185.996815 -37.181523)
			(xy 186.042173 -37.149072) (xy 186.091773 -37.123571) (xy 186.144557 -37.105564) (xy 186.1994 -37.095434)
			(xy 186.255134 -37.093397) (xy 186.310571 -37.099497) (xy 186.364528 -37.113603) (xy 186.415857 -37.135415)
			(xy 186.463463 -37.164469) (xy 186.506331 -37.200144) (xy 186.543548 -37.241681) (xy 186.574321 -37.288194)
			(xy 186.597993 -37.338691) (xy 186.614061 -37.392098) (xy 186.622181 -37.447274) (xy 186.62269 -37.47516)
			(xy 186.622181 -37.503046) (xy 186.614061 -37.558222) (xy 186.597993 -37.611629) (xy 186.574321 -37.662126)
			(xy 186.574168 -37.662358) (xy 188.04839 -37.662358) (xy 188.052461 -37.606736) (xy 188.064587 -37.552299)
			(xy 188.08451 -37.500208) (xy 188.111806 -37.451573) (xy 188.145892 -37.40743) (xy 188.186041 -37.368721)
			(xy 188.231399 -37.33627) (xy 188.280999 -37.310769) (xy 188.333783 -37.292762) (xy 188.388626 -37.282632)
			(xy 188.44436 -37.280595) (xy 188.499797 -37.286695) (xy 188.553754 -37.300801) (xy 188.605083 -37.322613)
			(xy 188.652689 -37.351667) (xy 188.695557 -37.387342) (xy 188.732774 -37.428879) (xy 188.763547 -37.475392)
			(xy 188.787219 -37.525889) (xy 188.803287 -37.579296) (xy 188.811407 -37.634472) (xy 188.811916 -37.662358)
			(xy 188.811407 -37.690244) (xy 188.803287 -37.74542) (xy 188.787219 -37.798827) (xy 188.763547 -37.849324)
			(xy 188.732774 -37.895837) (xy 188.695557 -37.937374) (xy 188.652689 -37.973049) (xy 188.605083 -38.002103)
			(xy 188.553754 -38.023915) (xy 188.499797 -38.038021) (xy 188.44436 -38.044121) (xy 188.388626 -38.042084)
			(xy 188.333783 -38.031954) (xy 188.280999 -38.013947) (xy 188.231399 -37.988446) (xy 188.186041 -37.955995)
			(xy 188.145892 -37.917286) (xy 188.111806 -37.873143) (xy 188.08451 -37.824508) (xy 188.064587 -37.772417)
			(xy 188.052461 -37.71798) (xy 188.04839 -37.662358) (xy 186.574168 -37.662358) (xy 186.543548 -37.708639)
			(xy 186.506331 -37.750176) (xy 186.463463 -37.785851) (xy 186.415857 -37.814905) (xy 186.364528 -37.836717)
			(xy 186.310571 -37.850823) (xy 186.255134 -37.856923) (xy 186.1994 -37.854886) (xy 186.144557 -37.844756)
			(xy 186.091773 -37.826749) (xy 186.042173 -37.801248) (xy 185.996815 -37.768797) (xy 185.956666 -37.730088)
			(xy 185.92258 -37.685945) (xy 185.895284 -37.63731) (xy 185.875361 -37.585219) (xy 185.863235 -37.530782)
			(xy 185.859164 -37.47516) (xy 181.475269 -37.47516) (xy 181.470141 -37.477817) (xy 181.38865 -37.51103)
			(xy 181.304476 -37.536694) (xy 181.218317 -37.554598) (xy 181.130887 -37.564593) (xy 181.04291 -37.566597)
			(xy 180.955116 -37.560591) (xy 180.868232 -37.546627) (xy 180.782977 -37.52482) (xy 180.700058 -37.495351)
			(xy 180.620163 -37.458464) (xy 180.543954 -37.414464) (xy 180.472061 -37.363716) (xy 180.40508 -37.306642)
			(xy 180.343568 -37.243712) (xy 180.288032 -37.17545) (xy 180.238934 -37.102421) (xy 180.196681 -37.025229)
			(xy 180.161622 -36.944515) (xy 180.134047 -36.860947) (xy 180.114187 -36.775218) (xy 180.102204 -36.688038)
			(xy 180.098199 -36.60013) (xy 175.868642 -36.60013) (xy 175.853031 -36.652017) (xy 175.829359 -36.702514)
			(xy 175.798586 -36.749027) (xy 175.761369 -36.790564) (xy 175.718501 -36.826239) (xy 175.670895 -36.855293)
			(xy 175.619566 -36.877105) (xy 175.565609 -36.891211) (xy 175.510172 -36.897311) (xy 175.454438 -36.895274)
			(xy 175.399595 -36.885144) (xy 175.346811 -36.867137) (xy 175.297211 -36.841636) (xy 175.251853 -36.809185)
			(xy 175.211704 -36.770476) (xy 175.177618 -36.726333) (xy 175.150322 -36.677698) (xy 175.130399 -36.625607)
			(xy 175.118273 -36.57117) (xy 175.114202 -36.515548) (xy 173.988 -36.515548) (xy 173.984772 -36.520427)
			(xy 173.947555 -36.561964) (xy 173.904687 -36.597639) (xy 173.857081 -36.626693) (xy 173.805752 -36.648505)
			(xy 173.751795 -36.662611) (xy 173.696358 -36.668711) (xy 173.640624 -36.666674) (xy 173.585781 -36.656544)
			(xy 173.532997 -36.638537) (xy 173.483397 -36.613036) (xy 173.438039 -36.580585) (xy 173.39789 -36.541876)
			(xy 173.363804 -36.497733) (xy 173.336508 -36.449098) (xy 173.316585 -36.397007) (xy 173.304459 -36.34257)
			(xy 173.300388 -36.286948) (xy 172.446961 -36.286948) (xy 173.467014 -37.5666) (xy 173.471984 -37.572409)
			(xy 173.484652 -37.580954) (xy 173.491906 -37.583364) (xy 173.49605 -37.584577) (xy 173.504607 -37.585727)
			(xy 173.508924 -37.58565) (xy 173.581314 -37.582856) (xy 173.591474 -37.582602) (xy 173.602916 -37.58145)
			(xy 173.623031 -37.570349) (xy 173.630082 -37.561266) (xy 173.645355 -37.539368) (xy 173.681043 -37.49966)
			(xy 173.721916 -37.465311) (xy 173.767176 -37.436992) (xy 173.81594 -37.415256) (xy 173.867257 -37.400526)
			(xy 173.920125 -37.39309) (xy 173.94682 -37.39261) (xy 173.97407 -37.393098) (xy 174.028014 -37.400857)
			(xy 174.080306 -37.416214) (xy 174.129879 -37.438856) (xy 174.175726 -37.468323) (xy 174.216912 -37.504015)
			(xy 174.2526 -37.545205) (xy 174.282062 -37.591054) (xy 174.3047 -37.64063) (xy 174.320052 -37.692923)
			(xy 174.327805 -37.746868) (xy 174.328328 -37.774118) (xy 174.327814 -37.80275) (xy 174.319253 -37.859371)
			(xy 174.302326 -37.914077) (xy 174.277414 -37.965639) (xy 174.245075 -38.012898) (xy 174.206037 -38.054793)
			(xy 174.161175 -38.090384) (xy 174.111499 -38.11887) (xy 174.084996 -38.129718) (xy 174.082202 -38.130734)
			(xy 174.072225 -38.136004) (xy 174.057745 -38.153274) (xy 174.054262 -38.164008) (xy 174.032926 -38.242748)
			(xy 174.03191 -38.246812) (xy 174.030445 -38.257669) (xy 174.035839 -38.278878) (xy 174.042324 -38.287706)
			(xy 176.419059 -41.268755) (xy 183.943927 -41.268755) (xy 183.943927 -41.214245) (xy 183.951685 -41.160289)
			(xy 183.967042 -41.107987) (xy 183.989687 -41.058403) (xy 184.019157 -41.012546) (xy 184.054854 -40.97135)
			(xy 184.096051 -40.935654) (xy 184.141908 -40.906184) (xy 184.191493 -40.88354) (xy 184.243795 -40.868183)
			(xy 184.297751 -40.860427) (xy 184.325006 -40.859964) (xy 184.353745 -40.860494) (xy 184.410571 -40.869116)
			(xy 184.465462 -40.886166) (xy 184.517173 -40.911255) (xy 184.564537 -40.943818) (xy 184.585864 -40.963088)
			(xy 184.592722 -40.969692) (xy 184.610756 -40.976804) (xy 184.699656 -40.976804) (xy 184.71769 -40.969692)
			(xy 184.724548 -40.963088) (xy 184.74588 -40.943823) (xy 184.79324 -40.911254) (xy 184.84495 -40.886159)
			(xy 184.89984 -40.869108) (xy 184.956667 -40.860485) (xy 184.985406 -40.859964) (xy 185.012655 -40.860507)
			(xy 185.066598 -40.868263) (xy 185.118888 -40.883618) (xy 185.168461 -40.906258) (xy 185.214307 -40.935722)
			(xy 185.255494 -40.971411) (xy 185.291182 -41.012598) (xy 185.320645 -41.058444) (xy 185.343284 -41.108017)
			(xy 185.358638 -41.160308) (xy 185.366394 -41.214251) (xy 185.366394 -41.268749) (xy 185.358638 -41.322692)
			(xy 185.343284 -41.374983) (xy 185.320645 -41.424556) (xy 185.291182 -41.470402) (xy 185.255494 -41.511589)
			(xy 185.214307 -41.547278) (xy 185.168461 -41.576742) (xy 185.118888 -41.599382) (xy 185.066598 -41.614737)
			(xy 185.012655 -41.622493) (xy 184.985406 -41.62298) (xy 184.956668 -41.622431) (xy 184.899843 -41.613811)
			(xy 184.844953 -41.596766) (xy 184.793241 -41.571681) (xy 184.745877 -41.539123) (xy 184.724548 -41.519856)
			(xy 184.71769 -41.513252) (xy 184.699656 -41.50614) (xy 184.610756 -41.50614) (xy 184.592722 -41.513252)
			(xy 184.585864 -41.519856) (xy 184.564534 -41.539123) (xy 184.517173 -41.57169) (xy 184.465462 -41.596783)
			(xy 184.410572 -41.613835) (xy 184.353745 -41.622459) (xy 184.325006 -41.62298) (xy 184.297751 -41.622573)
			(xy 184.243795 -41.614817) (xy 184.191493 -41.59946) (xy 184.141908 -41.576816) (xy 184.096051 -41.547346)
			(xy 184.054854 -41.51165) (xy 184.019157 -41.470454) (xy 183.989687 -41.424597) (xy 183.967042 -41.375013)
			(xy 183.951685 -41.322711) (xy 183.943927 -41.268755) (xy 176.419059 -41.268755) (xy 178.042697 -43.305222)
			(xy 186.407298 -43.305222) (xy 186.407777 -43.277852) (xy 186.415592 -43.223674) (xy 186.431078 -43.171171)
			(xy 186.453917 -43.121424) (xy 186.483638 -43.075456) (xy 186.501278 -43.054524) (xy 186.501532 -43.05427)
			(xy 186.507099 -43.04717) (xy 186.513356 -43.030263) (xy 186.513724 -43.02125) (xy 186.513724 -42.954194)
			(xy 186.513364 -42.945178) (xy 186.507118 -42.928261) (xy 186.501532 -42.921174) (xy 186.501278 -42.921174)
			(xy 186.501278 -42.92092) (xy 186.483631 -42.899994) (xy 186.453921 -42.854019) (xy 186.431087 -42.80427)
			(xy 186.415598 -42.751768) (xy 186.407771 -42.697592) (xy 186.407298 -42.670222) (xy 186.407836 -42.641484)
			(xy 186.416455 -42.584657) (xy 186.433502 -42.529766) (xy 186.45859 -42.478054) (xy 186.491153 -42.430691)
			(xy 186.510422 -42.409364) (xy 186.517026 -42.402506) (xy 186.524138 -42.384472) (xy 186.524138 -42.295572)
			(xy 186.517026 -42.277538) (xy 186.510422 -42.27068) (xy 186.491173 -42.249334) (xy 186.458607 -42.201975)
			(xy 186.433515 -42.150266) (xy 186.416463 -42.095378) (xy 186.407838 -42.038554) (xy 186.407836 -41.981078)
			(xy 186.416456 -41.924253) (xy 186.433503 -41.869364) (xy 186.458591 -41.817653) (xy 186.491153 -41.770291)
			(xy 186.510422 -41.748964) (xy 186.517026 -41.742106) (xy 186.524138 -41.724072) (xy 186.524138 -41.635172)
			(xy 186.517026 -41.617138) (xy 186.510422 -41.61028) (xy 186.491159 -41.588946) (xy 186.458592 -41.541586)
			(xy 186.433499 -41.489876) (xy 186.416446 -41.434987) (xy 186.407821 -41.37816) (xy 186.407298 -41.349422)
			(xy 186.407784 -41.322171) (xy 186.41554 -41.268223) (xy 186.430895 -41.215928) (xy 186.453537 -41.166351)
			(xy 186.483003 -41.120501) (xy 186.518694 -41.07931) (xy 186.559885 -41.043619) (xy 186.605735 -41.014153)
			(xy 186.655312 -40.991511) (xy 186.707607 -40.976156) (xy 186.761555 -40.9684) (xy 186.816057 -40.9684)
			(xy 186.870005 -40.976156) (xy 186.9223 -40.991511) (xy 186.971877 -41.014153) (xy 187.017727 -41.043619)
			(xy 187.058918 -41.07931) (xy 187.094609 -41.120501) (xy 187.124075 -41.166351) (xy 187.146717 -41.215928)
			(xy 187.162072 -41.268223) (xy 187.169828 -41.322171) (xy 187.170314 -41.349422) (xy 187.1698 -41.378161)
			(xy 187.161174 -41.434989) (xy 187.144122 -41.48988) (xy 187.119028 -41.541591) (xy 187.086461 -41.588953)
			(xy 187.06719 -41.61028) (xy 187.060586 -41.617138) (xy 187.053474 -41.635172) (xy 187.053474 -41.724072)
			(xy 187.060586 -41.742106) (xy 187.06719 -41.748964) (xy 187.086482 -41.770272) (xy 187.119045 -41.817638)
			(xy 187.144135 -41.869353) (xy 187.161183 -41.924247) (xy 187.169803 -41.981076) (xy 187.1698 -42.038556)
			(xy 187.161175 -42.095385) (xy 187.144123 -42.150277) (xy 187.119029 -42.20199) (xy 187.086462 -42.249353)
			(xy 187.06719 -42.27068) (xy 187.060586 -42.277538) (xy 187.053474 -42.295572) (xy 187.053474 -42.384472)
			(xy 187.060586 -42.402506) (xy 187.06719 -42.409364) (xy 187.086476 -42.430678) (xy 187.119039 -42.478044)
			(xy 187.144128 -42.529759) (xy 187.161175 -42.584653) (xy 187.169795 -42.641482) (xy 187.170314 -42.670222)
			(xy 187.169857 -42.697593) (xy 187.162037 -42.751772) (xy 187.146545 -42.804275) (xy 187.125991 -42.849038)
			(xy 188.992 -42.849038) (xy 188.996071 -42.793416) (xy 189.008197 -42.738979) (xy 189.02812 -42.686888)
			(xy 189.055416 -42.638253) (xy 189.089502 -42.59411) (xy 189.129651 -42.555401) (xy 189.175009 -42.52295)
			(xy 189.224609 -42.497449) (xy 189.277393 -42.479442) (xy 189.332236 -42.469312) (xy 189.38797 -42.467275)
			(xy 189.443407 -42.473375) (xy 189.497364 -42.487481) (xy 189.548693 -42.509293) (xy 189.596299 -42.538347)
			(xy 189.639167 -42.574022) (xy 189.676384 -42.615559) (xy 189.707157 -42.662072) (xy 189.730829 -42.712569)
			(xy 189.746897 -42.765976) (xy 189.755017 -42.821152) (xy 189.755526 -42.849038) (xy 189.755017 -42.876924)
			(xy 189.746897 -42.9321) (xy 189.730829 -42.985507) (xy 189.707157 -43.036004) (xy 189.676384 -43.082517)
			(xy 189.639167 -43.124054) (xy 189.596299 -43.159729) (xy 189.548693 -43.188783) (xy 189.497364 -43.210595)
			(xy 189.443407 -43.224701) (xy 189.38797 -43.230801) (xy 189.332236 -43.228764) (xy 189.277393 -43.218634)
			(xy 189.224609 -43.200627) (xy 189.175009 -43.175126) (xy 189.129651 -43.142675) (xy 189.089502 -43.103966)
			(xy 189.055416 -43.059823) (xy 189.02812 -43.011188) (xy 189.008197 -42.959097) (xy 188.996071 -42.90466)
			(xy 188.992 -42.849038) (xy 187.125991 -42.849038) (xy 187.123702 -42.854022) (xy 187.093976 -42.899988)
			(xy 187.076334 -42.92092) (xy 187.07608 -42.921174) (xy 187.070496 -42.928262) (xy 187.064248 -42.945178)
			(xy 187.063888 -42.954194) (xy 187.063888 -43.02125) (xy 187.064271 -43.030264) (xy 187.070501 -43.047181)
			(xy 187.07608 -43.05427) (xy 187.076334 -43.05427) (xy 187.076334 -43.054524) (xy 187.093956 -43.07547)
			(xy 187.123669 -43.121439) (xy 187.146508 -43.171183) (xy 187.162003 -43.223681) (xy 187.169837 -43.277854)
			(xy 187.170314 -43.305222) (xy 187.169828 -43.332473) (xy 187.162072 -43.386421) (xy 187.146717 -43.438716)
			(xy 187.124075 -43.488293) (xy 187.094609 -43.534143) (xy 187.058918 -43.575334) (xy 187.017727 -43.611025)
			(xy 186.971877 -43.640491) (xy 186.9223 -43.663133) (xy 186.870005 -43.678488) (xy 186.816057 -43.686244)
			(xy 186.761555 -43.686244) (xy 186.707607 -43.678488) (xy 186.655312 -43.663133) (xy 186.605735 -43.640491)
			(xy 186.559885 -43.611025) (xy 186.518694 -43.575334) (xy 186.483003 -43.534143) (xy 186.453537 -43.488293)
			(xy 186.430895 -43.438716) (xy 186.41554 -43.386421) (xy 186.407784 -43.332473) (xy 186.407298 -43.305222)
			(xy 178.042697 -43.305222) (xy 178.386356 -43.73626) (xy 188.313058 -43.73626) (xy 188.317129 -43.680638)
			(xy 188.329255 -43.626201) (xy 188.349178 -43.57411) (xy 188.376474 -43.525475) (xy 188.41056 -43.481332)
			(xy 188.450709 -43.442623) (xy 188.496067 -43.410172) (xy 188.545667 -43.384671) (xy 188.598451 -43.366664)
			(xy 188.653294 -43.356534) (xy 188.709028 -43.354497) (xy 188.764465 -43.360597) (xy 188.818422 -43.374703)
			(xy 188.869751 -43.396515) (xy 188.917357 -43.425569) (xy 188.960225 -43.461244) (xy 188.997442 -43.502781)
			(xy 189.028215 -43.549294) (xy 189.051887 -43.599791) (xy 189.067955 -43.653198) (xy 189.076075 -43.708374)
			(xy 189.076584 -43.73626) (xy 189.076075 -43.764146) (xy 189.067955 -43.819322) (xy 189.056646 -43.85691)
			(xy 192.81978 -43.85691) (xy 192.823851 -43.801288) (xy 192.835977 -43.746851) (xy 192.8559 -43.69476)
			(xy 192.883196 -43.646125) (xy 192.917282 -43.601982) (xy 192.957431 -43.563273) (xy 193.002789 -43.530822)
			(xy 193.052389 -43.505321) (xy 193.105173 -43.487314) (xy 193.160016 -43.477184) (xy 193.21575 -43.475147)
			(xy 193.271187 -43.481247) (xy 193.325144 -43.495353) (xy 193.376473 -43.517165) (xy 193.424079 -43.546219)
			(xy 193.466947 -43.581894) (xy 193.504164 -43.623431) (xy 193.534937 -43.669944) (xy 193.558609 -43.720441)
			(xy 193.574677 -43.773848) (xy 193.582797 -43.829024) (xy 193.583306 -43.85691) (xy 193.582797 -43.884796)
			(xy 193.574677 -43.939972) (xy 193.558609 -43.993379) (xy 193.534937 -44.043876) (xy 193.504164 -44.090389)
			(xy 193.466947 -44.131926) (xy 193.424079 -44.167601) (xy 193.376473 -44.196655) (xy 193.325144 -44.218467)
			(xy 193.271187 -44.232573) (xy 193.21575 -44.238673) (xy 193.160016 -44.236636) (xy 193.105173 -44.226506)
			(xy 193.052389 -44.208499) (xy 193.002789 -44.182998) (xy 192.957431 -44.150547) (xy 192.917282 -44.111838)
			(xy 192.883196 -44.067695) (xy 192.8559 -44.01906) (xy 192.835977 -43.966969) (xy 192.823851 -43.912532)
			(xy 192.81978 -43.85691) (xy 189.056646 -43.85691) (xy 189.051887 -43.872729) (xy 189.028215 -43.923226)
			(xy 188.997442 -43.969739) (xy 188.960225 -44.011276) (xy 188.917357 -44.046951) (xy 188.869751 -44.076005)
			(xy 188.818422 -44.097817) (xy 188.764465 -44.111923) (xy 188.709028 -44.118023) (xy 188.653294 -44.115986)
			(xy 188.598451 -44.105856) (xy 188.545667 -44.087849) (xy 188.496067 -44.062348) (xy 188.450709 -44.029897)
			(xy 188.41056 -43.991188) (xy 188.376474 -43.947045) (xy 188.349178 -43.89841) (xy 188.329255 -43.846319)
			(xy 188.317129 -43.791882) (xy 188.313058 -43.73626) (xy 178.386356 -43.73626) (xy 179.485172 -45.114464)
			(xy 188.165484 -45.114464) (xy 188.169555 -45.058842) (xy 188.181681 -45.004405) (xy 188.201604 -44.952314)
			(xy 188.2289 -44.903679) (xy 188.262986 -44.859536) (xy 188.303135 -44.820827) (xy 188.348493 -44.788376)
			(xy 188.398093 -44.762875) (xy 188.450877 -44.744868) (xy 188.50572 -44.734738) (xy 188.561454 -44.732701)
			(xy 188.616891 -44.738801) (xy 188.670848 -44.752907) (xy 188.722177 -44.774719) (xy 188.769783 -44.803773)
			(xy 188.812651 -44.839448) (xy 188.842633 -44.87291) (xy 195.033136 -44.87291) (xy 195.037207 -44.817288)
			(xy 195.049333 -44.762851) (xy 195.069256 -44.71076) (xy 195.096552 -44.662125) (xy 195.130638 -44.617982)
			(xy 195.170787 -44.579273) (xy 195.216145 -44.546822) (xy 195.265745 -44.521321) (xy 195.318529 -44.503314)
			(xy 195.373372 -44.493184) (xy 195.429106 -44.491147) (xy 195.484543 -44.497247) (xy 195.5385 -44.511353)
			(xy 195.589829 -44.533165) (xy 195.637435 -44.562219) (xy 195.680303 -44.597894) (xy 195.71752 -44.639431)
			(xy 195.748293 -44.685944) (xy 195.771965 -44.736441) (xy 195.788033 -44.789848) (xy 195.796153 -44.845024)
			(xy 195.796662 -44.87291) (xy 195.796153 -44.900796) (xy 195.788033 -44.955972) (xy 195.771965 -45.009379)
			(xy 195.748293 -45.059876) (xy 195.71752 -45.106389) (xy 195.680303 -45.147926) (xy 195.637435 -45.183601)
			(xy 195.589829 -45.212655) (xy 195.5385 -45.234467) (xy 195.484543 -45.248573) (xy 195.429106 -45.254673)
			(xy 195.373372 -45.252636) (xy 195.318529 -45.242506) (xy 195.265745 -45.224499) (xy 195.216145 -45.198998)
			(xy 195.170787 -45.166547) (xy 195.130638 -45.127838) (xy 195.096552 -45.083695) (xy 195.069256 -45.03506)
			(xy 195.049333 -44.982969) (xy 195.037207 -44.928532) (xy 195.033136 -44.87291) (xy 188.842633 -44.87291)
			(xy 188.849868 -44.880985) (xy 188.880641 -44.927498) (xy 188.904313 -44.977995) (xy 188.920381 -45.031402)
			(xy 188.928501 -45.086578) (xy 188.92901 -45.114464) (xy 188.928501 -45.14235) (xy 188.920381 -45.197526)
			(xy 188.904313 -45.250933) (xy 188.880641 -45.30143) (xy 188.849868 -45.347943) (xy 188.844226 -45.35424)
			(xy 192.803778 -45.35424) (xy 192.807849 -45.298618) (xy 192.819975 -45.244181) (xy 192.839898 -45.19209)
			(xy 192.867194 -45.143455) (xy 192.90128 -45.099312) (xy 192.941429 -45.060603) (xy 192.986787 -45.028152)
			(xy 193.036387 -45.002651) (xy 193.089171 -44.984644) (xy 193.144014 -44.974514) (xy 193.199748 -44.972477)
			(xy 193.255185 -44.978577) (xy 193.309142 -44.992683) (xy 193.360471 -45.014495) (xy 193.408077 -45.043549)
			(xy 193.450945 -45.079224) (xy 193.488162 -45.120761) (xy 193.518935 -45.167274) (xy 193.542607 -45.217771)
			(xy 193.558675 -45.271178) (xy 193.566795 -45.326354) (xy 193.567304 -45.35424) (xy 193.566795 -45.382126)
			(xy 193.558675 -45.437302) (xy 193.542607 -45.490709) (xy 193.518935 -45.541206) (xy 193.488162 -45.587719)
			(xy 193.450945 -45.629256) (xy 193.408077 -45.664931) (xy 193.360471 -45.693985) (xy 193.309142 -45.715797)
			(xy 193.255185 -45.729903) (xy 193.199748 -45.736003) (xy 193.144014 -45.733966) (xy 193.089171 -45.723836)
			(xy 193.036387 -45.705829) (xy 192.986787 -45.680328) (xy 192.941429 -45.647877) (xy 192.90128 -45.609168)
			(xy 192.867194 -45.565025) (xy 192.839898 -45.51639) (xy 192.819975 -45.464299) (xy 192.807849 -45.409862)
			(xy 192.803778 -45.35424) (xy 188.844226 -45.35424) (xy 188.812651 -45.38948) (xy 188.769783 -45.425155)
			(xy 188.722177 -45.454209) (xy 188.670848 -45.476021) (xy 188.616891 -45.490127) (xy 188.561454 -45.496227)
			(xy 188.50572 -45.49419) (xy 188.450877 -45.48406) (xy 188.398093 -45.466053) (xy 188.348493 -45.440552)
			(xy 188.303135 -45.408101) (xy 188.262986 -45.369392) (xy 188.2289 -45.325249) (xy 188.201604 -45.276614)
			(xy 188.181681 -45.224523) (xy 188.169555 -45.170086) (xy 188.165484 -45.114464) (xy 179.485172 -45.114464)
			(xy 180.256733 -46.082204) (xy 186.152536 -46.082204) (xy 186.152959 -46.054949) (xy 186.160717 -46.000995)
			(xy 186.176075 -45.948693) (xy 186.19872 -45.89911) (xy 186.228191 -45.853255) (xy 186.263889 -45.812061)
			(xy 186.305087 -45.776367) (xy 186.350945 -45.746901) (xy 186.400531 -45.724261) (xy 186.452834 -45.708908)
			(xy 186.506789 -45.701156) (xy 186.534044 -45.700696) (xy 186.560948 -45.701125) (xy 186.614219 -45.708703)
			(xy 186.665898 -45.723688) (xy 186.71496 -45.745783) (xy 186.760432 -45.774551) (xy 186.801413 -45.80942)
			(xy 186.837089 -45.8497) (xy 186.852306 -45.871892) (xy 186.859418 -45.882814) (xy 186.882278 -45.894752)
			(xy 186.994546 -45.89272) (xy 187.016898 -45.879766) (xy 187.023756 -45.86859) (xy 187.038653 -45.844972)
			(xy 187.074336 -45.802021) (xy 187.115899 -45.764729) (xy 187.162453 -45.733893) (xy 187.213004 -45.710172)
			(xy 187.266473 -45.694073) (xy 187.321718 -45.68594) (xy 187.349638 -45.685456) (xy 187.376632 -45.685895)
			(xy 187.430081 -45.693506) (xy 187.481925 -45.708572) (xy 187.531129 -45.730791) (xy 187.576712 -45.75972)
			(xy 187.597542 -45.776896) (xy 187.60567 -45.784008) (xy 187.626244 -45.790104) (xy 187.711588 -45.779182)
			(xy 187.722134 -45.777412) (xy 187.740416 -45.766355) (xy 187.746894 -45.757846) (xy 187.762258 -45.736623)
			(xy 187.797843 -45.69817) (xy 187.838358 -45.664951) (xy 187.88304 -45.637591) (xy 187.931046 -45.616607)
			(xy 187.981473 -45.602392) (xy 188.033372 -45.595214) (xy 188.059568 -45.594778) (xy 188.086821 -45.595267)
			(xy 188.140774 -45.60302) (xy 188.193074 -45.618373) (xy 188.242656 -45.641013) (xy 188.288511 -45.670479)
			(xy 188.329706 -45.706171) (xy 188.365402 -45.747363) (xy 188.394872 -45.793216) (xy 188.417516 -45.842796)
			(xy 188.432873 -45.895095) (xy 188.440631 -45.949047) (xy 188.440631 -46.003553) (xy 188.432873 -46.057505)
			(xy 188.417516 -46.109804) (xy 188.394872 -46.159384) (xy 188.365402 -46.205237) (xy 188.329706 -46.246429)
			(xy 188.288511 -46.282121) (xy 188.242656 -46.311587) (xy 188.193074 -46.334227) (xy 188.140774 -46.34958)
			(xy 188.086821 -46.357333) (xy 188.059568 -46.357794) (xy 188.032575 -46.35734) (xy 187.979127 -46.34973)
			(xy 187.927284 -46.334668) (xy 187.878079 -46.312453) (xy 187.832495 -46.283528) (xy 187.811664 -46.266354)
			(xy 187.803536 -46.259242) (xy 187.782962 -46.253146) (xy 187.697618 -46.264068) (xy 187.687078 -46.265859)
			(xy 187.668794 -46.276903) (xy 187.662312 -46.285404) (xy 187.644694 -46.309701) (xy 187.603102 -46.352962)
			(xy 187.579508 -46.37151) (xy 187.571634 -46.377352) (xy 187.56122 -46.394878) (xy 187.548012 -46.485302)
			(xy 187.552838 -46.504606) (xy 187.55868 -46.51248) (xy 187.55868 -46.512734) (xy 187.576184 -46.537478)
			(xy 187.603986 -46.591331) (xy 187.622922 -46.648903) (xy 187.630125 -46.693836) (xy 192.776348 -46.693836)
			(xy 192.776834 -46.666585) (xy 192.78459 -46.612637) (xy 192.799945 -46.560342) (xy 192.822587 -46.510765)
			(xy 192.852053 -46.464915) (xy 192.887744 -46.423724) (xy 192.928935 -46.388033) (xy 192.974785 -46.358567)
			(xy 193.024362 -46.335925) (xy 193.076657 -46.32057) (xy 193.130605 -46.312814) (xy 193.185107 -46.312814)
			(xy 193.239055 -46.32057) (xy 193.29135 -46.335925) (xy 193.340927 -46.358567) (xy 193.386777 -46.388033)
			(xy 193.427968 -46.423724) (xy 193.463659 -46.464915) (xy 193.493125 -46.510765) (xy 193.515767 -46.560342)
			(xy 193.531122 -46.612637) (xy 193.538878 -46.666585) (xy 193.539364 -46.693836) (xy 193.538896 -46.720264)
			(xy 193.531586 -46.772611) (xy 193.517111 -46.823446) (xy 193.49575 -46.871793) (xy 193.482214 -46.894496)
			(xy 193.48196 -46.89475) (xy 193.476623 -46.904768) (xy 193.474365 -46.927318) (xy 193.477642 -46.938184)
			(xy 193.503804 -47.01286) (xy 193.508165 -47.023388) (xy 193.524269 -47.039471) (xy 193.534792 -47.043848)
			(xy 193.535046 -47.043848) (xy 193.559555 -47.052918) (xy 193.606007 -47.07686) (xy 193.648759 -47.106916)
			(xy 193.687011 -47.142523) (xy 193.720048 -47.183016) (xy 193.747251 -47.227637) (xy 193.768113 -47.275552)
			(xy 193.782243 -47.325866) (xy 193.789377 -47.377636) (xy 193.789808 -47.403766) (xy 193.789322 -47.431017)
			(xy 193.787799 -47.441612) (xy 195.061838 -47.441612) (xy 195.065909 -47.38599) (xy 195.078035 -47.331553)
			(xy 195.097958 -47.279462) (xy 195.125254 -47.230827) (xy 195.15934 -47.186684) (xy 195.199489 -47.147975)
			(xy 195.244847 -47.115524) (xy 195.294447 -47.090023) (xy 195.347231 -47.072016) (xy 195.402074 -47.061886)
			(xy 195.457808 -47.059849) (xy 195.513245 -47.065949) (xy 195.567202 -47.080055) (xy 195.618531 -47.101867)
			(xy 195.666137 -47.130921) (xy 195.709005 -47.166596) (xy 195.746222 -47.208133) (xy 195.776995 -47.254646)
			(xy 195.800667 -47.305143) (xy 195.816735 -47.35855) (xy 195.824855 -47.413726) (xy 195.825364 -47.441612)
			(xy 195.824855 -47.469498) (xy 195.816735 -47.524674) (xy 195.800667 -47.578081) (xy 195.776995 -47.628578)
			(xy 195.746222 -47.675091) (xy 195.709005 -47.716628) (xy 195.666137 -47.752303) (xy 195.618531 -47.781357)
			(xy 195.567202 -47.803169) (xy 195.513245 -47.817275) (xy 195.457808 -47.823375) (xy 195.402074 -47.821338)
			(xy 195.347231 -47.811208) (xy 195.294447 -47.793201) (xy 195.244847 -47.7677) (xy 195.199489 -47.735249)
			(xy 195.15934 -47.69654) (xy 195.125254 -47.652397) (xy 195.097958 -47.603762) (xy 195.078035 -47.551671)
			(xy 195.065909 -47.497234) (xy 195.061838 -47.441612) (xy 193.787799 -47.441612) (xy 193.781566 -47.484965)
			(xy 193.766211 -47.53726) (xy 193.743569 -47.586837) (xy 193.714103 -47.632687) (xy 193.678412 -47.673878)
			(xy 193.637221 -47.709569) (xy 193.591371 -47.739035) (xy 193.541794 -47.761677) (xy 193.489499 -47.777032)
			(xy 193.435551 -47.784788) (xy 193.381049 -47.784788) (xy 193.327101 -47.777032) (xy 193.274806 -47.761677)
			(xy 193.225229 -47.739035) (xy 193.179379 -47.709569) (xy 193.138188 -47.673878) (xy 193.102497 -47.632687)
			(xy 193.073031 -47.586837) (xy 193.050389 -47.53726) (xy 193.035034 -47.484965) (xy 193.027278 -47.431017)
			(xy 193.026792 -47.403766) (xy 193.027267 -47.377339) (xy 193.034576 -47.324991) (xy 193.049049 -47.274156)
			(xy 193.070408 -47.225809) (xy 193.083942 -47.203106) (xy 193.084196 -47.202852) (xy 193.089531 -47.192834)
			(xy 193.091788 -47.170284) (xy 193.088514 -47.159418) (xy 193.062352 -47.084742) (xy 193.057965 -47.074228)
			(xy 193.041879 -47.058139) (xy 193.031364 -47.053754) (xy 193.03111 -47.053754) (xy 193.006593 -47.044708)
			(xy 192.960141 -47.02076) (xy 192.917391 -46.9907) (xy 192.87914 -46.955089) (xy 192.846105 -46.914594)
			(xy 192.818903 -46.86997) (xy 192.798042 -46.822053) (xy 192.783913 -46.771738) (xy 192.776779 -46.719966)
			(xy 192.776348 -46.693836) (xy 187.630125 -46.693836) (xy 187.632515 -46.708745) (xy 187.633102 -46.739048)
			(xy 187.632667 -46.766301) (xy 187.624904 -46.820251) (xy 187.609542 -46.872547) (xy 187.586895 -46.922124)
			(xy 187.557423 -46.967975) (xy 187.521726 -47.009165) (xy 187.480532 -47.044855) (xy 187.434677 -47.074321)
			(xy 187.385096 -47.096961) (xy 187.332798 -47.112315) (xy 187.278847 -47.120071) (xy 187.251594 -47.120556)
			(xy 187.225561 -47.120105) (xy 187.173978 -47.113018) (xy 187.123836 -47.098989) (xy 187.076065 -47.078279)
			(xy 187.03155 -47.051272) (xy 187.011056 -47.035212) (xy 187.003289 -47.029485) (xy 186.984886 -47.023735)
			(xy 186.975242 -47.024036) (xy 186.895486 -47.030386) (xy 186.877706 -47.039022) (xy 186.871356 -47.046388)
			(xy 186.85317 -47.066029) (xy 186.812263 -47.100551) (xy 186.766935 -47.129021) (xy 186.718075 -47.150879)
			(xy 186.66664 -47.165698) (xy 186.613639 -47.173186) (xy 186.586876 -47.173642) (xy 186.559626 -47.173145)
			(xy 186.50568 -47.165386) (xy 186.453388 -47.150029) (xy 186.403813 -47.127388) (xy 186.357964 -47.097922)
			(xy 186.316775 -47.062232) (xy 186.281084 -47.021044) (xy 186.251617 -46.975196) (xy 186.228974 -46.925622)
			(xy 186.213616 -46.87333) (xy 186.205856 -46.819384) (xy 186.205368 -46.792134) (xy 186.205901 -46.76336)
			(xy 186.214551 -46.706467) (xy 186.231646 -46.651517) (xy 186.256797 -46.599757) (xy 186.289435 -46.55236)
			(xy 186.308746 -46.531022) (xy 186.316112 -46.523148) (xy 186.323224 -46.503336) (xy 186.315858 -46.40707)
			(xy 186.305952 -46.388274) (xy 186.29757 -46.38167) (xy 186.275375 -46.363458) (xy 186.236168 -46.321518)
			(xy 186.203685 -46.27418) (xy 186.178659 -46.222509) (xy 186.161654 -46.167674) (xy 186.153054 -46.11091)
			(xy 186.152536 -46.082204) (xy 180.256733 -46.082204) (xy 180.433726 -46.3042) (xy 180.459537 -46.337245)
			(xy 180.506142 -46.406958) (xy 180.546724 -46.48034) (xy 180.580998 -46.556873) (xy 180.59527 -46.5963)
			(xy 181.194664 -48.30699) (xy 192.653918 -48.30699) (xy 192.657989 -48.251368) (xy 192.670115 -48.196931)
			(xy 192.690038 -48.14484) (xy 192.717334 -48.096205) (xy 192.75142 -48.052062) (xy 192.791569 -48.013353)
			(xy 192.836927 -47.980902) (xy 192.886527 -47.955401) (xy 192.939311 -47.937394) (xy 192.994154 -47.927264)
			(xy 193.049888 -47.925227) (xy 193.105325 -47.931327) (xy 193.159282 -47.945433) (xy 193.210611 -47.967245)
			(xy 193.258217 -47.996299) (xy 193.301085 -48.031974) (xy 193.338302 -48.073511) (xy 193.369075 -48.120024)
			(xy 193.392747 -48.170521) (xy 193.408815 -48.223928) (xy 193.416935 -48.279104) (xy 193.417444 -48.30699)
			(xy 193.416935 -48.334876) (xy 193.408815 -48.390052) (xy 193.392747 -48.443459) (xy 193.369075 -48.493956)
			(xy 193.338302 -48.540469) (xy 193.301085 -48.582006) (xy 193.258217 -48.617681) (xy 193.210611 -48.646735)
			(xy 193.159282 -48.668547) (xy 193.105325 -48.682653) (xy 193.049888 -48.688753) (xy 192.994154 -48.686716)
			(xy 192.939311 -48.676586) (xy 192.886527 -48.658579) (xy 192.836927 -48.633078) (xy 192.791569 -48.600627)
			(xy 192.75142 -48.561918) (xy 192.717334 -48.517775) (xy 192.690038 -48.46914) (xy 192.670115 -48.417049)
			(xy 192.657989 -48.362612) (xy 192.653918 -48.30699) (xy 181.194664 -48.30699) (xy 181.350943 -48.753014)
			(xy 189.268352 -48.753014) (xy 189.272423 -48.697392) (xy 189.284549 -48.642955) (xy 189.304472 -48.590864)
			(xy 189.331768 -48.542229) (xy 189.365854 -48.498086) (xy 189.406003 -48.459377) (xy 189.451361 -48.426926)
			(xy 189.500961 -48.401425) (xy 189.553745 -48.383418) (xy 189.608588 -48.373288) (xy 189.664322 -48.371251)
			(xy 189.719759 -48.377351) (xy 189.773716 -48.391457) (xy 189.825045 -48.413269) (xy 189.872651 -48.442323)
			(xy 189.915519 -48.477998) (xy 189.952736 -48.519535) (xy 189.983509 -48.566048) (xy 190.007181 -48.616545)
			(xy 190.023249 -48.669952) (xy 190.031369 -48.725128) (xy 190.031878 -48.753014) (xy 190.031369 -48.7809)
			(xy 190.023249 -48.836076) (xy 190.020805 -48.8442) (xy 190.2874 -48.8442) (xy 190.291471 -48.788578)
			(xy 190.303597 -48.734141) (xy 190.32352 -48.68205) (xy 190.350816 -48.633415) (xy 190.384902 -48.589272)
			(xy 190.425051 -48.550563) (xy 190.470409 -48.518112) (xy 190.520009 -48.492611) (xy 190.572793 -48.474604)
			(xy 190.627636 -48.464474) (xy 190.68337 -48.462437) (xy 190.738807 -48.468537) (xy 190.792764 -48.482643)
			(xy 190.844093 -48.504455) (xy 190.891699 -48.533509) (xy 190.934567 -48.569184) (xy 190.971784 -48.610721)
			(xy 191.002557 -48.657234) (xy 191.026229 -48.707731) (xy 191.042297 -48.761138) (xy 191.050417 -48.816314)
			(xy 191.050926 -48.8442) (xy 191.050417 -48.872086) (xy 191.047419 -48.89246) (xy 191.314068 -48.89246)
			(xy 191.318139 -48.836838) (xy 191.330265 -48.782401) (xy 191.350188 -48.73031) (xy 191.377484 -48.681675)
			(xy 191.41157 -48.637532) (xy 191.451719 -48.598823) (xy 191.497077 -48.566372) (xy 191.546677 -48.540871)
			(xy 191.599461 -48.522864) (xy 191.654304 -48.512734) (xy 191.710038 -48.510697) (xy 191.765475 -48.516797)
			(xy 191.819432 -48.530903) (xy 191.870761 -48.552715) (xy 191.918367 -48.581769) (xy 191.961235 -48.617444)
			(xy 191.998452 -48.658981) (xy 192.029225 -48.705494) (xy 192.052897 -48.755991) (xy 192.068965 -48.809398)
			(xy 192.077085 -48.864574) (xy 192.077594 -48.89246) (xy 192.077085 -48.920346) (xy 192.074647 -48.93691)
			(xy 195.033136 -48.93691) (xy 195.037207 -48.881288) (xy 195.049333 -48.826851) (xy 195.069256 -48.77476)
			(xy 195.096552 -48.726125) (xy 195.130638 -48.681982) (xy 195.170787 -48.643273) (xy 195.216145 -48.610822)
			(xy 195.265745 -48.585321) (xy 195.318529 -48.567314) (xy 195.373372 -48.557184) (xy 195.429106 -48.555147)
			(xy 195.484543 -48.561247) (xy 195.5385 -48.575353) (xy 195.589829 -48.597165) (xy 195.637435 -48.626219)
			(xy 195.680303 -48.661894) (xy 195.71752 -48.703431) (xy 195.748293 -48.749944) (xy 195.771965 -48.800441)
			(xy 195.788033 -48.853848) (xy 195.796153 -48.909024) (xy 195.796662 -48.93691) (xy 195.796153 -48.964796)
			(xy 195.788033 -49.019972) (xy 195.771965 -49.073379) (xy 195.748293 -49.123876) (xy 195.71752 -49.170389)
			(xy 195.680303 -49.211926) (xy 195.637435 -49.247601) (xy 195.589829 -49.276655) (xy 195.5385 -49.298467)
			(xy 195.484543 -49.312573) (xy 195.429106 -49.318673) (xy 195.373372 -49.316636) (xy 195.318529 -49.306506)
			(xy 195.265745 -49.288499) (xy 195.216145 -49.262998) (xy 195.170787 -49.230547) (xy 195.130638 -49.191838)
			(xy 195.096552 -49.147695) (xy 195.069256 -49.09906) (xy 195.049333 -49.046969) (xy 195.037207 -48.992532)
			(xy 195.033136 -48.93691) (xy 192.074647 -48.93691) (xy 192.068965 -48.975522) (xy 192.052897 -49.028929)
			(xy 192.029225 -49.079426) (xy 191.998452 -49.125939) (xy 191.961235 -49.167476) (xy 191.918367 -49.203151)
			(xy 191.870761 -49.232205) (xy 191.819432 -49.254017) (xy 191.765475 -49.268123) (xy 191.710038 -49.274223)
			(xy 191.654304 -49.272186) (xy 191.599461 -49.262056) (xy 191.546677 -49.244049) (xy 191.497077 -49.218548)
			(xy 191.451719 -49.186097) (xy 191.41157 -49.147388) (xy 191.377484 -49.103245) (xy 191.350188 -49.05461)
			(xy 191.330265 -49.002519) (xy 191.318139 -48.948082) (xy 191.314068 -48.89246) (xy 191.047419 -48.89246)
			(xy 191.042297 -48.927262) (xy 191.026229 -48.980669) (xy 191.002557 -49.031166) (xy 190.971784 -49.077679)
			(xy 190.934567 -49.119216) (xy 190.891699 -49.154891) (xy 190.844093 -49.183945) (xy 190.792764 -49.205757)
			(xy 190.738807 -49.219863) (xy 190.68337 -49.225963) (xy 190.627636 -49.223926) (xy 190.572793 -49.213796)
			(xy 190.520009 -49.195789) (xy 190.470409 -49.170288) (xy 190.425051 -49.137837) (xy 190.384902 -49.099128)
			(xy 190.350816 -49.054985) (xy 190.32352 -49.00635) (xy 190.303597 -48.954259) (xy 190.291471 -48.899822)
			(xy 190.2874 -48.8442) (xy 190.020805 -48.8442) (xy 190.007181 -48.889483) (xy 189.983509 -48.93998)
			(xy 189.952736 -48.986493) (xy 189.915519 -49.02803) (xy 189.872651 -49.063705) (xy 189.825045 -49.092759)
			(xy 189.773716 -49.114571) (xy 189.719759 -49.128677) (xy 189.664322 -49.134777) (xy 189.608588 -49.13274)
			(xy 189.553745 -49.12261) (xy 189.500961 -49.104603) (xy 189.451361 -49.079102) (xy 189.406003 -49.046651)
			(xy 189.365854 -49.007942) (xy 189.331768 -48.963799) (xy 189.304472 -48.915164) (xy 189.284549 -48.863073)
			(xy 189.272423 -48.808636) (xy 189.268352 -48.753014) (xy 181.350943 -48.753014) (xy 181.621938 -49.526444)
			(xy 181.636553 -49.569763) (xy 181.658732 -49.658462) (xy 181.672706 -49.748818) (xy 181.67604 -49.794414)
			(xy 181.717425 -50.462434) (xy 190.92621 -50.462434) (xy 190.930281 -50.406812) (xy 190.942407 -50.352375)
			(xy 190.96233 -50.300284) (xy 190.989626 -50.251649) (xy 191.023712 -50.207506) (xy 191.063861 -50.168797)
			(xy 191.109219 -50.136346) (xy 191.158819 -50.110845) (xy 191.211603 -50.092838) (xy 191.266446 -50.082708)
			(xy 191.32218 -50.080671) (xy 191.377617 -50.086771) (xy 191.431574 -50.100877) (xy 191.482903 -50.122689)
			(xy 191.530509 -50.151743) (xy 191.573377 -50.187418) (xy 191.610594 -50.228955) (xy 191.641367 -50.275468)
			(xy 191.665039 -50.325965) (xy 191.681107 -50.379372) (xy 191.689227 -50.434548) (xy 191.689736 -50.462434)
			(xy 191.689227 -50.49032) (xy 191.681107 -50.545496) (xy 191.665039 -50.598903) (xy 191.641367 -50.6494)
			(xy 191.610594 -50.695913) (xy 191.573377 -50.73745) (xy 191.530509 -50.773125) (xy 191.482903 -50.802179)
			(xy 191.431574 -50.823991) (xy 191.377617 -50.838097) (xy 191.32218 -50.844197) (xy 191.266446 -50.84216)
			(xy 191.211603 -50.83203) (xy 191.158819 -50.814023) (xy 191.109219 -50.788522) (xy 191.063861 -50.756071)
			(xy 191.023712 -50.717362) (xy 190.989626 -50.673219) (xy 190.96233 -50.624584) (xy 190.942407 -50.572493)
			(xy 190.930281 -50.518056) (xy 190.92621 -50.462434) (xy 181.717425 -50.462434) (xy 181.751933 -51.019456)
			(xy 192.849498 -51.019456) (xy 192.853569 -50.963834) (xy 192.865695 -50.909397) (xy 192.885618 -50.857306)
			(xy 192.912914 -50.808671) (xy 192.947 -50.764528) (xy 192.987149 -50.725819) (xy 193.032507 -50.693368)
			(xy 193.082107 -50.667867) (xy 193.134891 -50.64986) (xy 193.189734 -50.63973) (xy 193.245468 -50.637693)
			(xy 193.300905 -50.643793) (xy 193.354862 -50.657899) (xy 193.406191 -50.679711) (xy 193.453797 -50.708765)
			(xy 193.496665 -50.74444) (xy 193.533882 -50.785977) (xy 193.564655 -50.83249) (xy 193.588327 -50.882987)
			(xy 193.604395 -50.936394) (xy 193.612515 -50.99157) (xy 193.613024 -51.019456) (xy 193.612515 -51.047342)
			(xy 193.604395 -51.102518) (xy 193.588327 -51.155925) (xy 193.564655 -51.206422) (xy 193.533882 -51.252935)
			(xy 193.496665 -51.294472) (xy 193.453797 -51.330147) (xy 193.406191 -51.359201) (xy 193.354862 -51.381013)
			(xy 193.300905 -51.395119) (xy 193.245468 -51.401219) (xy 193.189734 -51.399182) (xy 193.134891 -51.389052)
			(xy 193.082107 -51.371045) (xy 193.032507 -51.345544) (xy 192.987149 -51.313093) (xy 192.947 -51.274384)
			(xy 192.912914 -51.230241) (xy 192.885618 -51.181606) (xy 192.865695 -51.129515) (xy 192.853569 -51.075078)
			(xy 192.849498 -51.019456) (xy 181.751933 -51.019456) (xy 181.814875 -52.035456) (xy 195.041264 -52.035456)
			(xy 195.045335 -51.979834) (xy 195.057461 -51.925397) (xy 195.077384 -51.873306) (xy 195.10468 -51.824671)
			(xy 195.138766 -51.780528) (xy 195.178915 -51.741819) (xy 195.224273 -51.709368) (xy 195.273873 -51.683867)
			(xy 195.326657 -51.66586) (xy 195.3815 -51.65573) (xy 195.437234 -51.653693) (xy 195.492671 -51.659793)
			(xy 195.546628 -51.673899) (xy 195.597957 -51.695711) (xy 195.645563 -51.724765) (xy 195.688431 -51.76044)
			(xy 195.725648 -51.801977) (xy 195.756421 -51.84849) (xy 195.780093 -51.898987) (xy 195.796161 -51.952394)
			(xy 195.804281 -52.00757) (xy 195.80479 -52.035456) (xy 195.804281 -52.063342) (xy 195.796161 -52.118518)
			(xy 195.780093 -52.171925) (xy 195.756421 -52.222422) (xy 195.725648 -52.268935) (xy 195.688431 -52.310472)
			(xy 195.645563 -52.346147) (xy 195.597957 -52.375201) (xy 195.546628 -52.397013) (xy 195.492671 -52.411119)
			(xy 195.437234 -52.417219) (xy 195.3815 -52.415182) (xy 195.326657 -52.405052) (xy 195.273873 -52.387045)
			(xy 195.224273 -52.361544) (xy 195.178915 -52.329093) (xy 195.138766 -52.290384) (xy 195.10468 -52.246241)
			(xy 195.077384 -52.197606) (xy 195.057461 -52.145515) (xy 195.045335 -52.091078) (xy 195.041264 -52.035456)
			(xy 181.814875 -52.035456) (xy 181.835552 -52.369212) (xy 181.836664 -52.379843) (xy 181.846525 -52.398787)
			(xy 181.854602 -52.405788) (xy 181.897274 -52.439824) (xy 181.904737 -52.445294) (xy 181.922312 -52.451039)
			(xy 181.931564 -52.451) (xy 181.93639 -52.450492) (xy 181.937152 -52.450492) (xy 181.93766 -52.450238)
			(xy 181.937914 -52.450238) (xy 181.939184 -52.449984) (xy 181.954631 -52.447605) (xy 181.985785 -52.445061)
			(xy 182.001414 -52.444904) (xy 182.002176 -52.444904) (xy 182.02943 -52.445366) (xy 182.083383 -52.45312)
			(xy 182.135683 -52.468474) (xy 182.185265 -52.491115) (xy 182.23112 -52.520583) (xy 182.272315 -52.556277)
			(xy 182.30801 -52.59747) (xy 182.337479 -52.643324) (xy 182.360122 -52.692906) (xy 182.375477 -52.745206)
			(xy 182.383233 -52.799158) (xy 182.383684 -52.826412) (xy 182.383259 -52.851923) (xy 182.376463 -52.902491)
			(xy 182.362994 -52.951703) (xy 182.343092 -52.998684) (xy 182.317112 -53.042596) (xy 182.301642 -53.062886)
			(xy 182.299102 -53.065934) (xy 182.298086 -53.067458) (xy 182.294784 -53.074062) (xy 182.292441 -53.079285)
			(xy 182.289876 -53.090438) (xy 182.289704 -53.09616) (xy 182.289704 -53.128164) (xy 182.278528 -53.128164)
			(xy 182.278528 -53.178964) (xy 182.278863 -53.187567) (xy 182.284578 -53.203797) (xy 182.289704 -53.210714)
			(xy 182.290974 -53.212238) (xy 182.308366 -53.233116) (xy 182.337682 -53.278866) (xy 182.360207 -53.328314)
			(xy 182.375487 -53.380458) (xy 182.383211 -53.434244) (xy 182.383684 -53.461412) (xy 182.383259 -53.486923)
			(xy 182.376463 -53.537491) (xy 182.362994 -53.586703) (xy 182.343092 -53.633684) (xy 182.317112 -53.677596)
			(xy 182.301642 -53.697886) (xy 182.299102 -53.700934) (xy 182.298086 -53.702458) (xy 182.294784 -53.709062)
			(xy 182.292441 -53.714285) (xy 182.289876 -53.725438) (xy 182.289704 -53.73116) (xy 182.289704 -53.763164)
			(xy 182.278528 -53.763164) (xy 182.278528 -53.813964) (xy 182.278863 -53.822567) (xy 182.284578 -53.838797)
			(xy 182.289704 -53.845714) (xy 182.290974 -53.847238) (xy 182.308366 -53.868116) (xy 182.337682 -53.913866)
			(xy 182.360207 -53.963314) (xy 182.375487 -54.015458) (xy 182.383211 -54.069244) (xy 182.383684 -54.096412)
			(xy 182.383259 -54.121923) (xy 182.376463 -54.172491) (xy 182.362994 -54.221703) (xy 182.343092 -54.268684)
			(xy 182.317112 -54.312596) (xy 182.301642 -54.332886) (xy 182.299102 -54.335934) (xy 182.298086 -54.337458)
			(xy 182.294784 -54.344062) (xy 182.292441 -54.349285) (xy 182.289876 -54.360438) (xy 182.289704 -54.36616)
			(xy 182.289704 -54.398164) (xy 182.278528 -54.398164) (xy 182.278528 -54.448964) (xy 182.278863 -54.457567)
			(xy 182.284578 -54.473797) (xy 182.289704 -54.480714) (xy 182.290974 -54.482238) (xy 182.308366 -54.503116)
			(xy 182.337682 -54.548866) (xy 182.360207 -54.598314) (xy 182.375487 -54.650458) (xy 182.383211 -54.704244)
			(xy 182.383684 -54.731412) (xy 182.383207 -54.758855) (xy 182.378537 -54.791102) (xy 184.276492 -54.791102)
			(xy 184.276961 -54.763732) (xy 184.284779 -54.709553) (xy 184.300267 -54.65705) (xy 184.323108 -54.607303)
			(xy 184.352831 -54.561336) (xy 184.370472 -54.540404) (xy 184.370726 -54.54015) (xy 184.376301 -54.533055)
			(xy 184.382554 -54.516145) (xy 184.382918 -54.50713) (xy 184.382918 -54.440074) (xy 184.38257 -54.431056)
			(xy 184.376316 -54.41414) (xy 184.370726 -54.407054) (xy 184.370472 -54.407054) (xy 184.370472 -54.4068)
			(xy 184.352831 -54.385867) (xy 184.323103 -54.3399) (xy 184.300255 -54.290154) (xy 184.284757 -54.237652)
			(xy 184.276927 -54.183473) (xy 184.276927 -54.12873) (xy 184.284756 -54.074551) (xy 184.300254 -54.022049)
			(xy 184.323102 -53.972303) (xy 184.35283 -53.926336) (xy 184.370472 -53.905404) (xy 184.370726 -53.90515)
			(xy 184.376301 -53.898055) (xy 184.382554 -53.881145) (xy 184.382918 -53.87213) (xy 184.382918 -53.805074)
			(xy 184.38257 -53.796056) (xy 184.376316 -53.77914) (xy 184.370726 -53.772054) (xy 184.370472 -53.772054)
			(xy 184.370472 -53.7718) (xy 184.352831 -53.750867) (xy 184.323103 -53.7049) (xy 184.300255 -53.655154)
			(xy 184.284757 -53.602652) (xy 184.276927 -53.548473) (xy 184.276927 -53.49373) (xy 184.284756 -53.439551)
			(xy 184.300254 -53.387049) (xy 184.323102 -53.337303) (xy 184.35283 -53.291336) (xy 184.370472 -53.270404)
			(xy 184.370726 -53.27015) (xy 184.376301 -53.263055) (xy 184.382554 -53.246145) (xy 184.382918 -53.23713)
			(xy 184.382918 -53.170074) (xy 184.38257 -53.161056) (xy 184.376316 -53.14414) (xy 184.370726 -53.137054)
			(xy 184.370472 -53.137054) (xy 184.370472 -53.1368) (xy 184.352815 -53.115882) (xy 184.323107 -53.069905)
			(xy 184.300275 -53.020154) (xy 184.284788 -52.96765) (xy 184.276964 -52.913472) (xy 184.276492 -52.886102)
			(xy 184.276978 -52.858851) (xy 184.284734 -52.804903) (xy 184.300089 -52.752608) (xy 184.322731 -52.703031)
			(xy 184.352197 -52.657181) (xy 184.387888 -52.61599) (xy 184.429079 -52.580299) (xy 184.474929 -52.550833)
			(xy 184.524506 -52.528191) (xy 184.576801 -52.512836) (xy 184.630749 -52.50508) (xy 184.685251 -52.50508)
			(xy 184.739199 -52.512836) (xy 184.791494 -52.528191) (xy 184.830594 -52.546048) (xy 189.779696 -52.546048)
			(xy 189.779696 -52.491552) (xy 189.787451 -52.437611) (xy 189.802803 -52.385322) (xy 189.82544 -52.33575)
			(xy 189.854901 -52.289904) (xy 189.890586 -52.248717) (xy 189.931769 -52.213027) (xy 189.977612 -52.183561)
			(xy 190.027181 -52.160919) (xy 190.079468 -52.14556) (xy 190.133408 -52.137799) (xy 190.160656 -52.13731)
			(xy 190.188025 -52.137799) (xy 190.242204 -52.145611) (xy 190.294707 -52.161095) (xy 190.344454 -52.183931)
			(xy 190.390422 -52.213651) (xy 190.411354 -52.23129) (xy 190.411608 -52.231544) (xy 190.418684 -52.237145)
			(xy 190.435609 -52.243382) (xy 190.444628 -52.243736) (xy 190.511684 -52.243736) (xy 190.520699 -52.243363)
			(xy 190.537616 -52.237126) (xy 190.544704 -52.231544) (xy 190.544704 -52.23129) (xy 190.544958 -52.23129)
			(xy 190.565891 -52.213649) (xy 190.611859 -52.183925) (xy 190.661605 -52.161079) (xy 190.714107 -52.145583)
			(xy 190.768285 -52.137754) (xy 190.823027 -52.137754) (xy 190.877205 -52.145583) (xy 190.929707 -52.161079)
			(xy 190.979453 -52.183925) (xy 191.025421 -52.213649) (xy 191.046354 -52.23129) (xy 191.046608 -52.231544)
			(xy 191.053684 -52.237145) (xy 191.070609 -52.243382) (xy 191.079628 -52.243736) (xy 191.146684 -52.243736)
			(xy 191.155699 -52.243363) (xy 191.172616 -52.237126) (xy 191.179704 -52.231544) (xy 191.179704 -52.23129)
			(xy 191.179958 -52.23129) (xy 191.200894 -52.213656) (xy 191.246866 -52.183943) (xy 191.296612 -52.161107)
			(xy 191.349112 -52.145615) (xy 191.403287 -52.137785) (xy 191.430656 -52.13731) (xy 191.457912 -52.137734)
			(xy 191.511871 -52.145486) (xy 191.564176 -52.160839) (xy 191.613764 -52.18348) (xy 191.659625 -52.212948)
			(xy 191.700825 -52.248644) (xy 191.736525 -52.28984) (xy 191.765999 -52.335697) (xy 191.788645 -52.385283)
			(xy 191.804004 -52.437586) (xy 191.811763 -52.491544) (xy 191.811763 -52.546056) (xy 191.805818 -52.587398)
			(xy 192.85534 -52.587398) (xy 192.859411 -52.531776) (xy 192.871537 -52.477339) (xy 192.89146 -52.425248)
			(xy 192.918756 -52.376613) (xy 192.952842 -52.33247) (xy 192.992991 -52.293761) (xy 193.038349 -52.26131)
			(xy 193.087949 -52.235809) (xy 193.140733 -52.217802) (xy 193.195576 -52.207672) (xy 193.25131 -52.205635)
			(xy 193.306747 -52.211735) (xy 193.360704 -52.225841) (xy 193.412033 -52.247653) (xy 193.459639 -52.276707)
			(xy 193.502507 -52.312382) (xy 193.539724 -52.353919) (xy 193.570497 -52.400432) (xy 193.594169 -52.450929)
			(xy 193.610237 -52.504336) (xy 193.617833 -52.555948) (xy 200.683902 -52.555948) (xy 200.683902 -52.501452)
			(xy 200.691658 -52.447509) (xy 200.70701 -52.39522) (xy 200.729648 -52.345647) (xy 200.759111 -52.299801)
			(xy 200.794797 -52.258614) (xy 200.835982 -52.222925) (xy 200.881826 -52.19346) (xy 200.931397 -52.170819)
			(xy 200.983686 -52.155463) (xy 201.037628 -52.147704) (xy 201.064876 -52.147216) (xy 201.092246 -52.147692)
			(xy 201.146425 -52.155507) (xy 201.198928 -52.170994) (xy 201.248675 -52.193833) (xy 201.294642 -52.223556)
			(xy 201.315574 -52.241196) (xy 201.315828 -52.24145) (xy 201.322927 -52.247019) (xy 201.339834 -52.253275)
			(xy 201.348848 -52.253642) (xy 201.415904 -52.253642) (xy 201.424923 -52.253299) (xy 201.44184 -52.247043)
			(xy 201.448924 -52.24145) (xy 201.448924 -52.241196) (xy 201.449178 -52.241196) (xy 201.470107 -52.223553)
			(xy 201.516081 -52.193842) (xy 201.565829 -52.171007) (xy 201.61833 -52.155517) (xy 201.672507 -52.147689)
			(xy 201.699876 -52.147216) (xy 201.727132 -52.147629) (xy 201.781089 -52.155384) (xy 201.833393 -52.170739)
			(xy 201.882979 -52.193381) (xy 201.928838 -52.222851) (xy 201.970036 -52.258547) (xy 202.005735 -52.299743)
			(xy 202.035207 -52.3456) (xy 202.057853 -52.395185) (xy 202.073211 -52.447488) (xy 202.080969 -52.501444)
			(xy 202.080969 -52.555956) (xy 202.073211 -52.609912) (xy 202.057853 -52.662215) (xy 202.035207 -52.7118)
			(xy 202.005735 -52.757657) (xy 201.970036 -52.798853) (xy 201.928838 -52.834549) (xy 201.882979 -52.864019)
			(xy 201.833393 -52.886661) (xy 201.781089 -52.902016) (xy 201.727132 -52.909771) (xy 201.699876 -52.910232)
			(xy 201.672504 -52.909797) (xy 201.618323 -52.901974) (xy 201.565819 -52.886479) (xy 201.516073 -52.86363)
			(xy 201.470108 -52.833897) (xy 201.449178 -52.816252) (xy 201.448924 -52.815998) (xy 201.441835 -52.810415)
			(xy 201.42492 -52.804166) (xy 201.415904 -52.803806) (xy 201.348848 -52.803806) (xy 201.339833 -52.804185)
			(xy 201.322916 -52.810417) (xy 201.315828 -52.815998) (xy 201.315828 -52.816252) (xy 201.315574 -52.816252)
			(xy 201.294619 -52.833862) (xy 201.248653 -52.86358) (xy 201.198912 -52.886422) (xy 201.146416 -52.90192)
			(xy 201.092244 -52.909755) (xy 201.064876 -52.910232) (xy 201.037628 -52.909696) (xy 200.983686 -52.901937)
			(xy 200.931397 -52.886581) (xy 200.881826 -52.86394) (xy 200.835982 -52.834475) (xy 200.794797 -52.798786)
			(xy 200.759111 -52.757599) (xy 200.729648 -52.711753) (xy 200.70701 -52.66218) (xy 200.691658 -52.609891)
			(xy 200.683902 -52.555948) (xy 193.617833 -52.555948) (xy 193.618357 -52.559512) (xy 193.618866 -52.587398)
			(xy 193.618357 -52.615284) (xy 193.610237 -52.67046) (xy 193.594169 -52.723867) (xy 193.570497 -52.774364)
			(xy 193.539724 -52.820877) (xy 193.502507 -52.862414) (xy 193.459639 -52.898089) (xy 193.412033 -52.927143)
			(xy 193.360704 -52.948955) (xy 193.306747 -52.963061) (xy 193.25131 -52.969161) (xy 193.195576 -52.967124)
			(xy 193.140733 -52.956994) (xy 193.087949 -52.938987) (xy 193.038349 -52.913486) (xy 192.992991 -52.881035)
			(xy 192.952842 -52.842326) (xy 192.918756 -52.798183) (xy 192.89146 -52.749548) (xy 192.871537 -52.697457)
			(xy 192.859411 -52.64302) (xy 192.85534 -52.587398) (xy 191.805818 -52.587398) (xy 191.804004 -52.600014)
			(xy 191.788645 -52.652317) (xy 191.765999 -52.701903) (xy 191.736525 -52.74776) (xy 191.700825 -52.788956)
			(xy 191.659625 -52.824652) (xy 191.613764 -52.85412) (xy 191.564176 -52.876761) (xy 191.511871 -52.892114)
			(xy 191.457912 -52.899866) (xy 191.430656 -52.900326) (xy 191.403286 -52.899845) (xy 191.349107 -52.892034)
			(xy 191.296603 -52.876549) (xy 191.246856 -52.85371) (xy 191.200889 -52.823987) (xy 191.179958 -52.806346)
			(xy 191.179704 -52.806092) (xy 191.172621 -52.8005) (xy 191.155701 -52.794257) (xy 191.146684 -52.7939)
			(xy 191.079628 -52.7939) (xy 191.070612 -52.79427) (xy 191.053695 -52.800509) (xy 191.046608 -52.806092)
			(xy 191.046354 -52.806346) (xy 191.025421 -52.823987) (xy 190.979453 -52.853711) (xy 190.929707 -52.876557)
			(xy 190.877205 -52.892053) (xy 190.823027 -52.899882) (xy 190.768285 -52.899882) (xy 190.714107 -52.892053)
			(xy 190.661605 -52.876557) (xy 190.611859 -52.853711) (xy 190.565891 -52.823987) (xy 190.544958 -52.806346)
			(xy 190.544704 -52.806092) (xy 190.537621 -52.8005) (xy 190.520701 -52.794257) (xy 190.511684 -52.7939)
			(xy 190.444628 -52.7939) (xy 190.435612 -52.79427) (xy 190.418695 -52.800509) (xy 190.411608 -52.806092)
			(xy 190.411608 -52.806346) (xy 190.411354 -52.806346) (xy 190.390405 -52.823965) (xy 190.344438 -52.853682)
			(xy 190.294695 -52.876522) (xy 190.242197 -52.892018) (xy 190.188024 -52.89985) (xy 190.160656 -52.900326)
			(xy 190.133408 -52.899801) (xy 190.079468 -52.89204) (xy 190.027181 -52.876681) (xy 189.977612 -52.854039)
			(xy 189.931769 -52.824573) (xy 189.890586 -52.788883) (xy 189.854901 -52.747696) (xy 189.82544 -52.70185)
			(xy 189.802803 -52.652278) (xy 189.787451 -52.599989) (xy 189.779696 -52.546048) (xy 184.830594 -52.546048)
			(xy 184.841071 -52.550833) (xy 184.886921 -52.580299) (xy 184.928112 -52.61599) (xy 184.963803 -52.657181)
			(xy 184.993269 -52.703031) (xy 185.015911 -52.752608) (xy 185.031266 -52.804903) (xy 185.039022 -52.858851)
			(xy 185.039508 -52.886102) (xy 185.039041 -52.913472) (xy 185.031223 -52.967651) (xy 185.015734 -53.020154)
			(xy 184.992893 -53.069901) (xy 184.963169 -53.115868) (xy 184.945528 -53.1368) (xy 184.945274 -53.137054)
			(xy 184.939698 -53.144147) (xy 184.933446 -53.161059) (xy 184.933082 -53.170074) (xy 184.933082 -53.23713)
			(xy 184.933428 -53.246148) (xy 184.939684 -53.263065) (xy 184.945274 -53.27015) (xy 184.945528 -53.27015)
			(xy 184.945528 -53.270404) (xy 184.963173 -53.291334) (xy 184.992901 -53.337301) (xy 185.015749 -53.387048)
			(xy 185.031247 -53.439551) (xy 185.039076 -53.49373) (xy 185.039076 -53.548473) (xy 185.031246 -53.602652)
			(xy 185.015748 -53.655155) (xy 184.992899 -53.704901) (xy 184.963171 -53.750868) (xy 184.946598 -53.77053)
			(xy 185.31078 -53.77053) (xy 185.311289 -53.741612) (xy 185.320016 -53.684439) (xy 185.337274 -53.629239)
			(xy 185.362667 -53.577277) (xy 185.395613 -53.529743) (xy 185.435358 -53.487728) (xy 185.457846 -53.46954)
			(xy 185.466633 -53.461913) (xy 185.476826 -53.441027) (xy 185.477404 -53.429408) (xy 185.477404 -53.349652)
			(xy 185.476877 -53.338019) (xy 185.466679 -53.317109) (xy 185.457846 -53.30952) (xy 185.435361 -53.291331)
			(xy 185.395628 -53.249309) (xy 185.362691 -53.201774) (xy 185.337303 -53.149812) (xy 185.320047 -53.094615)
			(xy 185.311316 -53.037446) (xy 185.31078 -53.00853) (xy 185.311283 -52.981278) (xy 185.319036 -52.92733)
			(xy 185.334387 -52.875033) (xy 185.357026 -52.825454) (xy 185.386489 -52.779601) (xy 185.422179 -52.738409)
			(xy 185.463368 -52.702714) (xy 185.509217 -52.673246) (xy 185.558794 -52.650602) (xy 185.611088 -52.635245)
			(xy 185.665036 -52.627486) (xy 185.692288 -52.627022) (xy 185.718602 -52.62749) (xy 185.770731 -52.634724)
			(xy 185.821374 -52.649042) (xy 185.869573 -52.670175) (xy 185.914416 -52.697721) (xy 185.955056 -52.73116)
			(xy 185.973212 -52.750212) (xy 185.980726 -52.757623) (xy 186.000012 -52.766142) (xy 186.01055 -52.766722)
			(xy 186.085226 -52.766722) (xy 186.095772 -52.76616) (xy 186.115067 -52.757647) (xy 186.122564 -52.750212)
			(xy 186.140698 -52.731135) (xy 186.181332 -52.697679) (xy 186.226177 -52.670123) (xy 186.274382 -52.648988)
			(xy 186.325033 -52.634676) (xy 186.377171 -52.627457) (xy 186.403488 -52.627022) (xy 186.430742 -52.627467)
			(xy 186.484695 -52.635223) (xy 186.536995 -52.650579) (xy 186.586577 -52.673222) (xy 186.632432 -52.702692)
			(xy 186.673625 -52.738387) (xy 186.709319 -52.779583) (xy 186.738787 -52.825439) (xy 186.761428 -52.875022)
			(xy 186.776781 -52.927323) (xy 186.784535 -52.981276) (xy 186.784996 -53.00853) (xy 186.784509 -53.036196)
			(xy 186.782278 -53.051456) (xy 195.041264 -53.051456) (xy 195.045335 -52.995834) (xy 195.057461 -52.941397)
			(xy 195.077384 -52.889306) (xy 195.10468 -52.840671) (xy 195.138766 -52.796528) (xy 195.178915 -52.757819)
			(xy 195.224273 -52.725368) (xy 195.273873 -52.699867) (xy 195.326657 -52.68186) (xy 195.3815 -52.67173)
			(xy 195.437234 -52.669693) (xy 195.492671 -52.675793) (xy 195.546628 -52.689899) (xy 195.597957 -52.711711)
			(xy 195.645563 -52.740765) (xy 195.688431 -52.77644) (xy 195.725648 -52.817977) (xy 195.756421 -52.86449)
			(xy 195.780093 -52.914987) (xy 195.796161 -52.968394) (xy 195.804281 -53.02357) (xy 195.80479 -53.051456)
			(xy 195.804281 -53.079342) (xy 195.796161 -53.134518) (xy 195.780093 -53.187925) (xy 195.756421 -53.238422)
			(xy 195.725648 -53.284935) (xy 195.688431 -53.326472) (xy 195.645563 -53.362147) (xy 195.597957 -53.391201)
			(xy 195.546628 -53.413013) (xy 195.492671 -53.427119) (xy 195.437234 -53.433219) (xy 195.3815 -53.431182)
			(xy 195.326657 -53.421052) (xy 195.273873 -53.403045) (xy 195.224273 -53.377544) (xy 195.178915 -53.345093)
			(xy 195.138766 -53.306384) (xy 195.10468 -53.262241) (xy 195.077384 -53.213606) (xy 195.057461 -53.161515)
			(xy 195.045335 -53.107078) (xy 195.041264 -53.051456) (xy 186.782278 -53.051456) (xy 186.776505 -53.090946)
			(xy 186.760684 -53.143969) (xy 186.737377 -53.194153) (xy 186.707072 -53.240448) (xy 186.670403 -53.281886)
			(xy 186.628139 -53.317598) (xy 186.60491 -53.332634) (xy 186.595211 -53.339244) (xy 186.58278 -53.359125)
			(xy 186.581034 -53.370734) (xy 186.57316 -53.450744) (xy 186.572506 -53.462383) (xy 186.580601 -53.484222)
			(xy 186.588654 -53.492654) (xy 186.588908 -53.492908) (xy 186.607477 -53.511001) (xy 186.640056 -53.551331)
			(xy 186.666871 -53.595702) (xy 186.687425 -53.643298) (xy 186.701342 -53.69324) (xy 186.708362 -53.744608)
			(xy 186.708796 -53.77053) (xy 186.70835 -53.797783) (xy 186.700589 -53.851732) (xy 186.68523 -53.904029)
			(xy 186.662584 -53.953607) (xy 186.633114 -53.999457) (xy 186.597418 -54.040648) (xy 186.556224 -54.076339)
			(xy 186.51037 -54.105804) (xy 186.460789 -54.128444) (xy 186.408491 -54.143798) (xy 186.354541 -54.151553)
			(xy 186.327288 -54.152038) (xy 186.299917 -54.151594) (xy 186.245736 -54.143773) (xy 186.193232 -54.12828)
			(xy 186.143486 -54.105433) (xy 186.09752 -54.075702) (xy 186.07659 -54.058058) (xy 186.076336 -54.057804)
			(xy 186.069243 -54.052227) (xy 186.052331 -54.045974) (xy 186.043316 -54.045612) (xy 185.97626 -54.045612)
			(xy 185.967241 -54.045947) (xy 185.950324 -54.05221) (xy 185.94324 -54.057804) (xy 185.94324 -54.058058)
			(xy 185.942986 -54.058058) (xy 185.922027 -54.075664) (xy 185.876062 -54.105382) (xy 185.826322 -54.128225)
			(xy 185.773827 -54.143724) (xy 185.719655 -54.15156) (xy 185.692288 -54.152038) (xy 185.665038 -54.151533)
			(xy 185.611092 -54.143776) (xy 185.5588 -54.128421) (xy 185.509224 -54.105781) (xy 185.463376 -54.076316)
			(xy 185.422186 -54.040626) (xy 185.386495 -53.999439) (xy 185.357028 -53.953591) (xy 185.334385 -53.904017)
			(xy 185.319028 -53.851725) (xy 185.311268 -53.79778) (xy 185.31078 -53.77053) (xy 184.946598 -53.77053)
			(xy 184.945528 -53.7718) (xy 184.945274 -53.772054) (xy 184.939698 -53.779147) (xy 184.933446 -53.796059)
			(xy 184.933082 -53.805074) (xy 184.933082 -53.87213) (xy 184.933428 -53.881148) (xy 184.939684 -53.898065)
			(xy 184.945274 -53.90515) (xy 184.945528 -53.90515) (xy 184.945528 -53.905404) (xy 184.963173 -53.926334)
			(xy 184.992901 -53.972301) (xy 185.015749 -54.022048) (xy 185.031247 -54.074551) (xy 185.039076 -54.12873)
			(xy 185.039076 -54.183473) (xy 185.031246 -54.237652) (xy 185.015748 -54.290155) (xy 185.001954 -54.320186)
			(xy 187.230512 -54.320186) (xy 187.230967 -54.292815) (xy 187.238787 -54.238636) (xy 187.254279 -54.186132)
			(xy 187.277123 -54.136386) (xy 187.30685 -54.090419) (xy 187.324492 -54.069488) (xy 187.324746 -54.069234)
			(xy 187.33033 -54.062146) (xy 187.336577 -54.04523) (xy 187.336938 -54.036214) (xy 187.336938 -53.969158)
			(xy 187.336545 -53.960145) (xy 187.330322 -53.943228) (xy 187.324746 -53.936138) (xy 187.324492 -53.936138)
			(xy 187.324492 -53.935884) (xy 187.306878 -53.914932) (xy 187.277162 -53.868965) (xy 187.254322 -53.819222)
			(xy 187.238825 -53.766726) (xy 187.23099 -53.712554) (xy 187.230512 -53.685186) (xy 187.230998 -53.657935)
			(xy 187.238754 -53.603987) (xy 187.254109 -53.551692) (xy 187.276751 -53.502115) (xy 187.306217 -53.456265)
			(xy 187.341908 -53.415074) (xy 187.383099 -53.379383) (xy 187.428949 -53.349917) (xy 187.478526 -53.327275)
			(xy 187.530821 -53.31192) (xy 187.584769 -53.304164) (xy 187.639271 -53.304164) (xy 187.693219 -53.31192)
			(xy 187.745514 -53.327275) (xy 187.795091 -53.349917) (xy 187.840941 -53.379383) (xy 187.882132 -53.415074)
			(xy 187.917823 -53.456265) (xy 187.943716 -53.496555) (xy 200.233441 -53.496555) (xy 200.233441 -53.442045)
			(xy 200.241199 -53.388089) (xy 200.256557 -53.335786) (xy 200.279203 -53.286202) (xy 200.308676 -53.240345)
			(xy 200.344374 -53.19915) (xy 200.385573 -53.163455) (xy 200.431432 -53.133987) (xy 200.481018 -53.111346)
			(xy 200.533322 -53.095992) (xy 200.587279 -53.088239) (xy 200.614534 -53.087778) (xy 200.641906 -53.088205)
			(xy 200.696087 -53.096029) (xy 200.748592 -53.111527) (xy 200.798338 -53.134377) (xy 200.844302 -53.164112)
			(xy 200.865232 -53.181758) (xy 200.865486 -53.182012) (xy 200.872571 -53.1876) (xy 200.889489 -53.193846)
			(xy 200.898506 -53.194204) (xy 200.965562 -53.194204) (xy 200.974577 -53.193828) (xy 200.991494 -53.187594)
			(xy 200.998582 -53.182012) (xy 200.998582 -53.181758) (xy 200.998836 -53.181758) (xy 201.019776 -53.164129)
			(xy 201.065747 -53.134417) (xy 201.115493 -53.111579) (xy 201.167991 -53.096086) (xy 201.222165 -53.088254)
			(xy 201.249534 -53.087778) (xy 201.276783 -53.088295) (xy 201.330725 -53.096055) (xy 201.383013 -53.111412)
			(xy 201.432584 -53.134054) (xy 201.478429 -53.163521) (xy 201.519613 -53.199211) (xy 201.5553 -53.240398)
			(xy 201.584762 -53.286245) (xy 201.6074 -53.335819) (xy 201.622753 -53.388109) (xy 201.630508 -53.442051)
			(xy 201.630508 -53.496549) (xy 201.622753 -53.550491) (xy 201.6074 -53.602781) (xy 201.584762 -53.652355)
			(xy 201.5553 -53.698202) (xy 201.519613 -53.739389) (xy 201.478429 -53.775079) (xy 201.432584 -53.804546)
			(xy 201.383013 -53.827188) (xy 201.330725 -53.842545) (xy 201.276783 -53.850305) (xy 201.249534 -53.850794)
			(xy 201.222164 -53.850309) (xy 201.167986 -53.842496) (xy 201.115483 -53.827012) (xy 201.065736 -53.804174)
			(xy 201.019768 -53.774453) (xy 200.998836 -53.756814) (xy 200.998582 -53.75656) (xy 200.991508 -53.750955)
			(xy 200.974581 -53.74472) (xy 200.965562 -53.744368) (xy 200.898506 -53.744368) (xy 200.88949 -53.744735)
			(xy 200.872574 -53.750976) (xy 200.865486 -53.75656) (xy 200.865486 -53.756814) (xy 200.865232 -53.756814)
			(xy 200.8443 -53.774454) (xy 200.798327 -53.804165) (xy 200.74858 -53.827001) (xy 200.696079 -53.842492)
			(xy 200.641903 -53.85032) (xy 200.614534 -53.850794) (xy 200.587279 -53.850361) (xy 200.533322 -53.842608)
			(xy 200.481018 -53.827254) (xy 200.431432 -53.804613) (xy 200.385573 -53.775145) (xy 200.344374 -53.73945)
			(xy 200.308676 -53.698255) (xy 200.279203 -53.652398) (xy 200.256557 -53.602814) (xy 200.241199 -53.550511)
			(xy 200.233441 -53.496555) (xy 187.943716 -53.496555) (xy 187.947289 -53.502115) (xy 187.969931 -53.551692)
			(xy 187.985286 -53.603987) (xy 187.993042 -53.657935) (xy 187.993528 -53.685186) (xy 187.993071 -53.712557)
			(xy 187.985254 -53.766737) (xy 187.969764 -53.819241) (xy 187.946919 -53.868988) (xy 187.917191 -53.914953)
			(xy 187.899548 -53.935884) (xy 187.899294 -53.936138) (xy 187.893727 -53.943238) (xy 187.887469 -53.960144)
			(xy 187.887102 -53.969158) (xy 187.887102 -54.036214) (xy 187.887452 -54.045232) (xy 187.893704 -54.062148)
			(xy 187.899294 -54.069234) (xy 187.899548 -54.069234) (xy 187.899548 -54.069488) (xy 187.917187 -54.09042)
			(xy 187.946901 -54.136392) (xy 187.969737 -54.18614) (xy 187.985228 -54.238641) (xy 187.993055 -54.292817)
			(xy 187.993528 -54.320186) (xy 187.993042 -54.347437) (xy 187.985286 -54.401385) (xy 187.969931 -54.45368)
			(xy 187.947289 -54.503257) (xy 187.917823 -54.549107) (xy 187.882132 -54.590298) (xy 187.840941 -54.625989)
			(xy 187.795091 -54.655455) (xy 187.745514 -54.678097) (xy 187.693219 -54.693452) (xy 187.639271 -54.701208)
			(xy 187.584769 -54.701208) (xy 187.530821 -54.693452) (xy 187.478526 -54.678097) (xy 187.428949 -54.655455)
			(xy 187.383099 -54.625989) (xy 187.341908 -54.590298) (xy 187.306217 -54.549107) (xy 187.276751 -54.503257)
			(xy 187.254109 -54.45368) (xy 187.238754 -54.401385) (xy 187.230998 -54.347437) (xy 187.230512 -54.320186)
			(xy 185.001954 -54.320186) (xy 184.992899 -54.339901) (xy 184.963171 -54.385868) (xy 184.945528 -54.4068)
			(xy 184.945274 -54.407054) (xy 184.939698 -54.414147) (xy 184.933446 -54.431059) (xy 184.933082 -54.440074)
			(xy 184.933082 -54.50713) (xy 184.933428 -54.516148) (xy 184.939684 -54.533065) (xy 184.945274 -54.54015)
			(xy 184.945528 -54.54015) (xy 184.945528 -54.540404) (xy 184.963187 -54.56132) (xy 184.992895 -54.607298)
			(xy 185.015726 -54.657049) (xy 185.031213 -54.709553) (xy 185.039036 -54.763732) (xy 185.039153 -54.770528)
			(xy 188.171074 -54.770528) (xy 188.171538 -54.743158) (xy 188.179354 -54.688978) (xy 188.194842 -54.636474)
			(xy 188.217685 -54.586727) (xy 188.247411 -54.540761) (xy 188.265054 -54.51983) (xy 188.265308 -54.519576)
			(xy 188.270912 -54.512501) (xy 188.277148 -54.495575) (xy 188.2775 -54.486556) (xy 188.2775 -54.4195)
			(xy 188.277143 -54.410483) (xy 188.270895 -54.393566) (xy 188.265308 -54.38648) (xy 188.265054 -54.38648)
			(xy 188.265054 -54.386226) (xy 188.247422 -54.365288) (xy 188.217707 -54.319318) (xy 188.194869 -54.269572)
			(xy 188.179377 -54.217072) (xy 188.171548 -54.162897) (xy 188.171074 -54.135528) (xy 188.17156 -54.108277)
			(xy 188.179316 -54.054329) (xy 188.194671 -54.002034) (xy 188.217313 -53.952457) (xy 188.246779 -53.906607)
			(xy 188.28247 -53.865416) (xy 188.323661 -53.829725) (xy 188.369511 -53.800259) (xy 188.419088 -53.777617)
			(xy 188.471383 -53.762262) (xy 188.525331 -53.754506) (xy 188.579833 -53.754506) (xy 188.633781 -53.762262)
			(xy 188.686076 -53.777617) (xy 188.735653 -53.800259) (xy 188.781503 -53.829725) (xy 188.822694 -53.865416)
			(xy 188.858385 -53.906607) (xy 188.887851 -53.952457) (xy 188.892926 -53.96357) (xy 192.872104 -53.96357)
			(xy 192.876175 -53.907948) (xy 192.888301 -53.853511) (xy 192.908224 -53.80142) (xy 192.93552 -53.752785)
			(xy 192.969606 -53.708642) (xy 193.009755 -53.669933) (xy 193.055113 -53.637482) (xy 193.104713 -53.611981)
			(xy 193.157497 -53.593974) (xy 193.21234 -53.583844) (xy 193.268074 -53.581807) (xy 193.323511 -53.587907)
			(xy 193.377468 -53.602013) (xy 193.428797 -53.623825) (xy 193.476403 -53.652879) (xy 193.519271 -53.688554)
			(xy 193.556488 -53.730091) (xy 193.587261 -53.776604) (xy 193.610933 -53.827101) (xy 193.627001 -53.880508)
			(xy 193.635121 -53.935684) (xy 193.63563 -53.96357) (xy 193.635121 -53.991456) (xy 193.627001 -54.046632)
			(xy 193.610933 -54.100039) (xy 193.587261 -54.150536) (xy 193.556488 -54.197049) (xy 193.519271 -54.238586)
			(xy 193.476403 -54.274261) (xy 193.428797 -54.303315) (xy 193.377468 -54.325127) (xy 193.323511 -54.339233)
			(xy 193.268074 -54.345333) (xy 193.21234 -54.343296) (xy 193.157497 -54.333166) (xy 193.104713 -54.315159)
			(xy 193.055113 -54.289658) (xy 193.009755 -54.257207) (xy 192.969606 -54.218498) (xy 192.93552 -54.174355)
			(xy 192.908224 -54.12572) (xy 192.888301 -54.073629) (xy 192.876175 -54.019192) (xy 192.872104 -53.96357)
			(xy 188.892926 -53.96357) (xy 188.910493 -54.002034) (xy 188.925848 -54.054329) (xy 188.933604 -54.108277)
			(xy 188.93409 -54.135528) (xy 188.933643 -54.162899) (xy 188.925821 -54.217079) (xy 188.910327 -54.269582)
			(xy 188.887481 -54.319329) (xy 188.857753 -54.365295) (xy 188.84011 -54.386226) (xy 188.839856 -54.38648)
			(xy 188.834266 -54.393564) (xy 188.828023 -54.410483) (xy 188.827664 -54.4195) (xy 188.827664 -54.486556)
			(xy 188.82805 -54.49557) (xy 188.834278 -54.512487) (xy 188.839856 -54.519576) (xy 188.84011 -54.519576)
			(xy 188.84011 -54.51983) (xy 188.857731 -54.540776) (xy 188.887445 -54.586745) (xy 188.910285 -54.636489)
			(xy 188.92578 -54.688987) (xy 188.933613 -54.74316) (xy 188.93409 -54.770528) (xy 188.933604 -54.797779)
			(xy 188.925848 -54.851727) (xy 188.910493 -54.904022) (xy 188.887851 -54.953599) (xy 188.865065 -54.989055)
			(xy 198.001045 -54.989055) (xy 198.001045 -54.934545) (xy 198.008803 -54.88059) (xy 198.024161 -54.828289)
			(xy 198.046806 -54.778705) (xy 198.076277 -54.73285) (xy 198.111975 -54.691655) (xy 198.153172 -54.655961)
			(xy 198.19903 -54.626492) (xy 198.248615 -54.603851) (xy 198.300918 -54.588497) (xy 198.354873 -54.580743)
			(xy 198.382128 -54.580282) (xy 198.41022 -54.580755) (xy 198.465799 -54.588986) (xy 198.519568 -54.605281)
			(xy 198.570366 -54.629287) (xy 198.617092 -54.660485) (xy 198.658737 -54.6982) (xy 198.694398 -54.741616)
			(xy 198.70928 -54.765448) (xy 198.714614 -54.774338) (xy 198.731632 -54.78653) (xy 198.82485 -54.80685)
			(xy 198.845424 -54.802532) (xy 198.85406 -54.79669) (xy 198.878132 -54.780704) (xy 198.930061 -54.755358)
			(xy 198.985216 -54.738129) (xy 199.042338 -54.729409) (xy 199.07123 -54.728872) (xy 199.098481 -54.72935)
			(xy 199.152428 -54.73711) (xy 199.204722 -54.752468) (xy 199.254298 -54.775111) (xy 199.300147 -54.804579)
			(xy 199.341336 -54.840271) (xy 199.377027 -54.881461) (xy 199.406494 -54.927311) (xy 199.429136 -54.976888)
			(xy 199.444492 -55.029182) (xy 199.452251 -55.083129) (xy 199.452738 -55.11038) (xy 199.452275 -55.137751)
			(xy 199.444459 -55.19193) (xy 199.42897 -55.244434) (xy 199.406127 -55.294181) (xy 199.3764 -55.340147)
			(xy 199.358758 -55.361078) (xy 199.358504 -55.361332) (xy 199.35294 -55.368434) (xy 199.34668 -55.385339)
			(xy 199.346312 -55.394352) (xy 199.346312 -55.461408) (xy 199.346663 -55.470426) (xy 199.352914 -55.487343)
			(xy 199.358504 -55.494428) (xy 199.358758 -55.494428) (xy 199.358758 -55.494682) (xy 199.37638 -55.51563)
			(xy 199.406106 -55.561595) (xy 199.428954 -55.611339) (xy 199.444452 -55.663838) (xy 199.452283 -55.718015)
			(xy 199.452285 -55.772755) (xy 199.444459 -55.826932) (xy 199.428965 -55.879433) (xy 199.406121 -55.929179)
			(xy 199.376398 -55.975146) (xy 199.358758 -55.996078) (xy 199.358504 -55.996332) (xy 199.35294 -56.003434)
			(xy 199.34668 -56.020339) (xy 199.346312 -56.029352) (xy 199.346312 -56.096408) (xy 199.346663 -56.105426)
			(xy 199.352914 -56.122343) (xy 199.358504 -56.129428) (xy 199.358758 -56.129428) (xy 199.358758 -56.129682)
			(xy 199.376396 -56.150615) (xy 199.406109 -56.196587) (xy 199.428946 -56.246334) (xy 199.444437 -56.298835)
			(xy 199.452265 -56.353011) (xy 199.452738 -56.38038) (xy 199.452252 -56.407631) (xy 199.444496 -56.461579)
			(xy 199.429141 -56.513874) (xy 199.406499 -56.563451) (xy 199.377033 -56.609301) (xy 199.341342 -56.650492)
			(xy 199.300151 -56.686183) (xy 199.254301 -56.715649) (xy 199.204724 -56.738291) (xy 199.152429 -56.753646)
			(xy 199.098481 -56.761402) (xy 199.043979 -56.761402) (xy 198.990031 -56.753646) (xy 198.937736 -56.738291)
			(xy 198.888159 -56.715649) (xy 198.842309 -56.686183) (xy 198.801118 -56.650492) (xy 198.765427 -56.609301)
			(xy 198.735961 -56.563451) (xy 198.713319 -56.513874) (xy 198.697964 -56.461579) (xy 198.690208 -56.407631)
			(xy 198.689722 -56.38038) (xy 198.690171 -56.353009) (xy 198.697992 -56.298829) (xy 198.713485 -56.246326)
			(xy 198.736331 -56.196579) (xy 198.766059 -56.150613) (xy 198.783702 -56.129682) (xy 198.783956 -56.129428)
			(xy 198.789544 -56.122342) (xy 198.795788 -56.105425) (xy 198.796148 -56.096408) (xy 198.796148 -56.029352)
			(xy 198.795777 -56.020336) (xy 198.789541 -56.003419) (xy 198.783956 -55.996332) (xy 198.783702 -55.996332)
			(xy 198.783702 -55.996078) (xy 198.766043 -55.975161) (xy 198.736321 -55.92919) (xy 198.713478 -55.879441)
			(xy 198.697984 -55.826936) (xy 198.690158 -55.772756) (xy 198.69016 -55.718014) (xy 198.697991 -55.663834)
			(xy 198.713489 -55.611331) (xy 198.736335 -55.561584) (xy 198.766061 -55.515615) (xy 198.783702 -55.494682)
			(xy 198.783956 -55.494428) (xy 198.789544 -55.487342) (xy 198.795788 -55.470425) (xy 198.796148 -55.461408)
			(xy 198.796148 -55.394352) (xy 198.795777 -55.385336) (xy 198.789541 -55.368419) (xy 198.783956 -55.361332)
			(xy 198.783702 -55.360824) (xy 198.772759 -55.348089) (xy 198.752917 -55.320998) (xy 198.744078 -55.306722)
			(xy 198.738744 -55.297832) (xy 198.721726 -55.28564) (xy 198.628508 -55.26532) (xy 198.607934 -55.269638)
			(xy 198.599298 -55.27548) (xy 198.575235 -55.291481) (xy 198.523303 -55.316824) (xy 198.468145 -55.334049)
			(xy 198.411021 -55.342764) (xy 198.382128 -55.343298) (xy 198.354873 -55.342857) (xy 198.300918 -55.335103)
			(xy 198.248615 -55.319749) (xy 198.19903 -55.297108) (xy 198.153172 -55.267639) (xy 198.111975 -55.231945)
			(xy 198.076277 -55.19075) (xy 198.046806 -55.144895) (xy 198.024161 -55.095311) (xy 198.008803 -55.04301)
			(xy 198.001045 -54.989055) (xy 188.865065 -54.989055) (xy 188.858385 -54.999449) (xy 188.822694 -55.04064)
			(xy 188.781503 -55.076331) (xy 188.735653 -55.105797) (xy 188.686076 -55.128439) (xy 188.633781 -55.143794)
			(xy 188.579833 -55.15155) (xy 188.525331 -55.15155) (xy 188.471383 -55.143794) (xy 188.419088 -55.128439)
			(xy 188.369511 -55.105797) (xy 188.323661 -55.076331) (xy 188.28247 -55.04064) (xy 188.246779 -54.999449)
			(xy 188.217313 -54.953599) (xy 188.194671 -54.904022) (xy 188.179316 -54.851727) (xy 188.17156 -54.797779)
			(xy 188.171074 -54.770528) (xy 185.039153 -54.770528) (xy 185.039508 -54.791102) (xy 185.039022 -54.818353)
			(xy 185.031266 -54.872301) (xy 185.015911 -54.924596) (xy 184.993269 -54.974173) (xy 184.963803 -55.020023)
			(xy 184.928112 -55.061214) (xy 184.886921 -55.096905) (xy 184.841071 -55.126371) (xy 184.791494 -55.149013)
			(xy 184.739199 -55.164368) (xy 184.685251 -55.172124) (xy 184.630749 -55.172124) (xy 184.576801 -55.164368)
			(xy 184.524506 -55.149013) (xy 184.474929 -55.126371) (xy 184.429079 -55.096905) (xy 184.387888 -55.061214)
			(xy 184.352197 -55.020023) (xy 184.322731 -54.974173) (xy 184.300089 -54.924596) (xy 184.284734 -54.872301)
			(xy 184.276978 -54.818353) (xy 184.276492 -54.791102) (xy 182.378537 -54.791102) (xy 182.375341 -54.813176)
			(xy 182.359774 -54.865809) (xy 182.336826 -54.915668) (xy 182.306971 -54.961725) (xy 182.270825 -55.00303)
			(xy 182.229135 -55.038729) (xy 182.182759 -55.068087) (xy 182.132656 -55.090498) (xy 182.079859 -55.105499)
			(xy 182.052722 -55.109618) (xy 182.046626 -55.11038) (xy 182.042816 -55.110888) (xy 182.026306 -55.120286)
			(xy 182.02021 -55.127652) (xy 182.014466 -55.135274) (xy 182.008584 -55.153416) (xy 182.00878 -55.162958)
			(xy 182.043324 -55.721758) (xy 182.043355 -55.722266) (xy 193.934078 -55.722266) (xy 193.938149 -55.666644)
			(xy 193.950275 -55.612207) (xy 193.970198 -55.560116) (xy 193.997494 -55.511481) (xy 194.03158 -55.467338)
			(xy 194.071729 -55.428629) (xy 194.117087 -55.396178) (xy 194.166687 -55.370677) (xy 194.219471 -55.35267)
			(xy 194.274314 -55.34254) (xy 194.330048 -55.340503) (xy 194.385485 -55.346603) (xy 194.439442 -55.360709)
			(xy 194.490771 -55.382521) (xy 194.538377 -55.411575) (xy 194.549528 -55.420855) (xy 196.324645 -55.420855)
			(xy 196.324645 -55.366345) (xy 196.332403 -55.31239) (xy 196.347761 -55.260089) (xy 196.370406 -55.210505)
			(xy 196.399877 -55.16465) (xy 196.435575 -55.123455) (xy 196.476772 -55.087761) (xy 196.52263 -55.058292)
			(xy 196.572215 -55.035651) (xy 196.624518 -55.020297) (xy 196.678473 -55.012543) (xy 196.705728 -55.012082)
			(xy 196.732042 -55.012537) (xy 196.784171 -55.019775) (xy 196.834814 -55.034097) (xy 196.883013 -55.055232)
			(xy 196.927856 -55.08278) (xy 196.968495 -55.11622) (xy 196.986652 -55.135272) (xy 196.994156 -55.142695)
			(xy 197.013449 -55.151208) (xy 197.02399 -55.151782) (xy 197.098666 -55.151782) (xy 197.109216 -55.151253)
			(xy 197.128512 -55.142719) (xy 197.136004 -55.135272) (xy 197.154159 -55.116216) (xy 197.19479 -55.08276)
			(xy 197.23963 -55.055202) (xy 197.287831 -55.034064) (xy 197.338478 -55.019746) (xy 197.390612 -55.012521)
			(xy 197.416928 -55.012082) (xy 197.444177 -55.01259) (xy 197.49812 -55.02035) (xy 197.55041 -55.035707)
			(xy 197.599983 -55.058349) (xy 197.645828 -55.087815) (xy 197.687014 -55.123506) (xy 197.722702 -55.164694)
			(xy 197.752164 -55.210542) (xy 197.774803 -55.260116) (xy 197.790156 -55.312407) (xy 197.797912 -55.366351)
			(xy 197.797912 -55.420849) (xy 197.790156 -55.474793) (xy 197.774803 -55.527084) (xy 197.752164 -55.576658)
			(xy 197.722702 -55.622506) (xy 197.687014 -55.663694) (xy 197.645828 -55.699385) (xy 197.599983 -55.728851)
			(xy 197.55041 -55.751493) (xy 197.49812 -55.76685) (xy 197.444177 -55.77461) (xy 197.416928 -55.775098)
			(xy 197.390612 -55.774679) (xy 197.338482 -55.767435) (xy 197.287838 -55.753106) (xy 197.239639 -55.731964)
			(xy 197.194797 -55.70441) (xy 197.154159 -55.670963) (xy 197.136004 -55.651908) (xy 197.128482 -55.644507)
			(xy 197.109202 -55.635982) (xy 197.098666 -55.635398) (xy 197.02399 -55.635398) (xy 197.013438 -55.635909)
			(xy 196.994143 -55.644457) (xy 196.986652 -55.651908) (xy 196.968514 -55.670981) (xy 196.927881 -55.704437)
			(xy 196.883037 -55.731993) (xy 196.834832 -55.753128) (xy 196.784182 -55.767442) (xy 196.732045 -55.774662)
			(xy 196.705728 -55.775098) (xy 196.678473 -55.774657) (xy 196.624518 -55.766903) (xy 196.572215 -55.751549)
			(xy 196.52263 -55.728908) (xy 196.476772 -55.699439) (xy 196.435575 -55.663745) (xy 196.399877 -55.62255)
			(xy 196.370406 -55.576695) (xy 196.347761 -55.527111) (xy 196.332403 -55.47481) (xy 196.324645 -55.420855)
			(xy 194.549528 -55.420855) (xy 194.581245 -55.44725) (xy 194.618462 -55.488787) (xy 194.649235 -55.5353)
			(xy 194.672907 -55.585797) (xy 194.688975 -55.639204) (xy 194.697095 -55.69438) (xy 194.697604 -55.722266)
			(xy 194.697095 -55.750152) (xy 194.688975 -55.805328) (xy 194.672907 -55.858735) (xy 194.649235 -55.909232)
			(xy 194.618462 -55.955745) (xy 194.581245 -55.997282) (xy 194.538377 -56.032957) (xy 194.490771 -56.062011)
			(xy 194.439442 -56.083823) (xy 194.385485 -56.097929) (xy 194.330048 -56.104029) (xy 194.274314 -56.101992)
			(xy 194.219471 -56.091862) (xy 194.166687 -56.073855) (xy 194.117087 -56.048354) (xy 194.071729 -56.015903)
			(xy 194.03158 -55.977194) (xy 193.997494 -55.933051) (xy 193.970198 -55.884416) (xy 193.950275 -55.832325)
			(xy 193.938149 -55.777888) (xy 193.934078 -55.722266) (xy 182.043355 -55.722266) (xy 182.068724 -56.133746)
			(xy 182.08625 -56.416448) (xy 182.08718 -56.423837) (xy 182.09273 -56.437649) (xy 182.097172 -56.443626)
			(xy 182.101744 -56.449214) (xy 182.12308 -56.464454) (xy 182.129938 -56.466994) (xy 182.157097 -56.477231)
			(xy 182.208201 -56.504739) (xy 182.254553 -56.539667) (xy 182.295082 -56.581209) (xy 182.328854 -56.628409)
			(xy 182.355092 -56.680177) (xy 182.37319 -56.735321) (xy 182.38273 -56.792569) (xy 182.383684 -56.821578)
			(xy 182.383684 -56.826658) (xy 182.383271 -56.852274) (xy 182.376411 -56.903045) (xy 182.362808 -56.952438)
			(xy 182.34271 -56.999563) (xy 182.3407 -57.002934) (xy 189.663578 -57.002934) (xy 189.664102 -56.974843)
			(xy 189.672324 -56.919268) (xy 189.68861 -56.8655) (xy 189.712608 -56.814702) (xy 189.743798 -56.767975)
			(xy 189.781506 -56.726329) (xy 189.824915 -56.690665) (xy 189.848744 -56.675782) (xy 189.857634 -56.670448)
			(xy 189.869826 -56.65343) (xy 189.890146 -56.560212) (xy 189.885828 -56.539638) (xy 189.879986 -56.531002)
			(xy 189.863983 -56.50694) (xy 189.838641 -56.455008) (xy 189.821417 -56.399849) (xy 189.812702 -56.342725)
			(xy 189.812168 -56.313832) (xy 189.812685 -56.286581) (xy 189.820437 -56.232633) (xy 189.835788 -56.180338)
			(xy 189.858425 -56.130759) (xy 189.887887 -56.084907) (xy 189.923575 -56.043715) (xy 189.964762 -56.008021)
			(xy 190.01061 -55.978552) (xy 190.060185 -55.955907) (xy 190.112478 -55.940549) (xy 190.166425 -55.932789)
			(xy 190.193676 -55.932324) (xy 190.221046 -55.932798) (xy 190.275225 -55.940613) (xy 190.327728 -55.9561)
			(xy 190.377475 -55.97894) (xy 190.423442 -56.008663) (xy 190.444374 -56.026304) (xy 190.444628 -56.026558)
			(xy 190.451726 -56.032127) (xy 190.468634 -56.038383) (xy 190.477648 -56.03875) (xy 190.544704 -56.03875)
			(xy 190.553722 -56.038406) (xy 190.57064 -56.03215) (xy 190.577724 -56.026558) (xy 190.577724 -56.026304)
			(xy 190.577978 -56.026304) (xy 190.598911 -56.008663) (xy 190.644879 -55.978939) (xy 190.694625 -55.956093)
			(xy 190.747127 -55.940597) (xy 190.801305 -55.932768) (xy 190.856047 -55.932768) (xy 190.910225 -55.940597)
			(xy 190.962727 -55.956093) (xy 191.012473 -55.978939) (xy 191.058441 -56.008663) (xy 191.079374 -56.026304)
			(xy 191.079628 -56.026558) (xy 191.086726 -56.032127) (xy 191.103634 -56.038383) (xy 191.112648 -56.03875)
			(xy 191.179704 -56.03875) (xy 191.188722 -56.038406) (xy 191.20564 -56.03215) (xy 191.212724 -56.026558)
			(xy 191.212724 -56.026304) (xy 191.212978 -56.026304) (xy 191.233908 -56.008662) (xy 191.279881 -55.978951)
			(xy 191.329629 -55.956115) (xy 191.382131 -55.940625) (xy 191.436307 -55.932797) (xy 191.463676 -55.932324)
			(xy 191.490932 -55.932721) (xy 191.54489 -55.940476) (xy 191.597196 -55.955831) (xy 191.646783 -55.978474)
			(xy 191.692643 -56.007944) (xy 191.733842 -56.043641) (xy 191.769541 -56.084838) (xy 191.799014 -56.130696)
			(xy 191.82166 -56.180282) (xy 191.837019 -56.232586) (xy 191.844777 -56.286544) (xy 191.844777 -56.297068)
			(xy 192.186558 -56.297068) (xy 192.190629 -56.241446) (xy 192.202755 -56.187009) (xy 192.222678 -56.134918)
			(xy 192.249974 -56.086283) (xy 192.28406 -56.04214) (xy 192.324209 -56.003431) (xy 192.369567 -55.97098)
			(xy 192.419167 -55.945479) (xy 192.471951 -55.927472) (xy 192.526794 -55.917342) (xy 192.582528 -55.915305)
			(xy 192.637965 -55.921405) (xy 192.691922 -55.935511) (xy 192.743251 -55.957323) (xy 192.790857 -55.986377)
			(xy 192.833725 -56.022052) (xy 192.870942 -56.063589) (xy 192.901715 -56.110102) (xy 192.925387 -56.160599)
			(xy 192.941455 -56.214006) (xy 192.949575 -56.269182) (xy 192.950084 -56.297068) (xy 192.949575 -56.324954)
			(xy 192.941455 -56.38013) (xy 192.925387 -56.433537) (xy 192.901715 -56.484034) (xy 192.870942 -56.530547)
			(xy 192.833725 -56.572084) (xy 192.790857 -56.607759) (xy 192.743251 -56.636813) (xy 192.691922 -56.658625)
			(xy 192.637965 -56.672731) (xy 192.582528 -56.678831) (xy 192.526794 -56.676794) (xy 192.471951 -56.666664)
			(xy 192.419167 -56.648657) (xy 192.369567 -56.623156) (xy 192.324209 -56.590705) (xy 192.28406 -56.551996)
			(xy 192.249974 -56.507853) (xy 192.222678 -56.459218) (xy 192.202755 -56.407127) (xy 192.190629 -56.35269)
			(xy 192.186558 -56.297068) (xy 191.844777 -56.297068) (xy 191.844777 -56.341056) (xy 191.837019 -56.395014)
			(xy 191.82166 -56.447318) (xy 191.799014 -56.496904) (xy 191.769541 -56.542762) (xy 191.733842 -56.583959)
			(xy 191.692643 -56.619656) (xy 191.646783 -56.649126) (xy 191.597196 -56.671769) (xy 191.54489 -56.687124)
			(xy 191.490932 -56.694879) (xy 191.463676 -56.69534) (xy 191.436305 -56.694903) (xy 191.382124 -56.68708)
			(xy 191.32962 -56.671585) (xy 191.279873 -56.648737) (xy 191.233908 -56.619005) (xy 191.212978 -56.60136)
			(xy 191.212724 -56.601106) (xy 191.205634 -56.595524) (xy 191.18872 -56.589274) (xy 191.179704 -56.588914)
			(xy 191.112648 -56.588914) (xy 191.103633 -56.589291) (xy 191.086716 -56.595524) (xy 191.079628 -56.601106)
			(xy 191.079628 -56.60136) (xy 191.079374 -56.60136) (xy 191.058441 -56.619001) (xy 191.012473 -56.648725)
			(xy 190.962727 -56.671571) (xy 190.910225 -56.687067) (xy 190.856047 -56.694896) (xy 190.801305 -56.694896)
			(xy 190.747127 -56.687067) (xy 190.694625 -56.671571) (xy 190.644879 -56.648725) (xy 190.598911 -56.619001)
			(xy 190.577978 -56.60136) (xy 190.577724 -56.601106) (xy 190.570634 -56.595524) (xy 190.55372 -56.589274)
			(xy 190.544704 -56.588914) (xy 190.477648 -56.588914) (xy 190.468633 -56.589291) (xy 190.451716 -56.595524)
			(xy 190.444628 -56.601106) (xy 190.44412 -56.60136) (xy 190.431388 -56.612307) (xy 190.404295 -56.632146)
			(xy 190.390018 -56.640984) (xy 190.381128 -56.646318) (xy 190.368936 -56.663336) (xy 190.348616 -56.756554)
			(xy 190.352934 -56.777128) (xy 190.358776 -56.785764) (xy 190.37476 -56.809838) (xy 190.400107 -56.861766)
			(xy 190.417337 -56.91692) (xy 190.426057 -56.974042) (xy 190.426594 -57.002934) (xy 190.426108 -57.030185)
			(xy 190.425826 -57.032144) (xy 193.585844 -57.032144) (xy 193.589915 -56.976522) (xy 193.602041 -56.922085)
			(xy 193.621964 -56.869994) (xy 193.64926 -56.821359) (xy 193.683346 -56.777216) (xy 193.723495 -56.738507)
			(xy 193.768853 -56.706056) (xy 193.818453 -56.680555) (xy 193.871237 -56.662548) (xy 193.92608 -56.652418)
			(xy 193.981814 -56.650381) (xy 194.037251 -56.656481) (xy 194.091208 -56.670587) (xy 194.142537 -56.692399)
			(xy 194.190143 -56.721453) (xy 194.233011 -56.757128) (xy 194.270228 -56.798665) (xy 194.301001 -56.845178)
			(xy 194.324673 -56.895675) (xy 194.340741 -56.949082) (xy 194.348861 -57.004258) (xy 194.34937 -57.032144)
			(xy 194.348861 -57.06003) (xy 194.340741 -57.115206) (xy 194.324673 -57.168613) (xy 194.301001 -57.21911)
			(xy 194.270228 -57.265623) (xy 194.233011 -57.30716) (xy 194.190143 -57.342835) (xy 194.142537 -57.371889)
			(xy 194.091208 -57.393701) (xy 194.037251 -57.407807) (xy 193.981814 -57.413907) (xy 193.92608 -57.41187)
			(xy 193.871237 -57.40174) (xy 193.818453 -57.383733) (xy 193.768853 -57.358232) (xy 193.723495 -57.325781)
			(xy 193.683346 -57.287072) (xy 193.64926 -57.242929) (xy 193.621964 -57.194294) (xy 193.602041 -57.142203)
			(xy 193.589915 -57.087766) (xy 193.585844 -57.032144) (xy 190.425826 -57.032144) (xy 190.418352 -57.084133)
			(xy 190.402997 -57.136428) (xy 190.380355 -57.186005) (xy 190.350889 -57.231855) (xy 190.315198 -57.273046)
			(xy 190.274007 -57.308737) (xy 190.228157 -57.338203) (xy 190.17858 -57.360845) (xy 190.126285 -57.3762)
			(xy 190.072337 -57.383956) (xy 190.017835 -57.383956) (xy 189.963887 -57.3762) (xy 189.911592 -57.360845)
			(xy 189.862015 -57.338203) (xy 189.816165 -57.308737) (xy 189.774974 -57.273046) (xy 189.739283 -57.231855)
			(xy 189.709817 -57.186005) (xy 189.687175 -57.136428) (xy 189.67182 -57.084133) (xy 189.664064 -57.030185)
			(xy 189.663578 -57.002934) (xy 182.3407 -57.002934) (xy 182.316477 -57.043569) (xy 182.30088 -57.063894)
			(xy 182.295546 -57.070498) (xy 182.292244 -57.079642) (xy 182.29072 -57.085484) (xy 182.289704 -57.09539)
			(xy 182.289704 -57.128156) (xy 182.278528 -57.128156) (xy 182.278528 -57.178956) (xy 182.278862 -57.18756)
			(xy 182.284574 -57.203791) (xy 182.289704 -57.210706) (xy 182.290974 -57.21223) (xy 182.308367 -57.233107)
			(xy 182.337683 -57.278858) (xy 182.360209 -57.328306) (xy 182.37549 -57.38045) (xy 182.383215 -57.434235)
			(xy 182.383684 -57.461404) (xy 182.383302 -57.48528) (xy 198.705976 -57.48528) (xy 198.710047 -57.429658)
			(xy 198.722173 -57.375221) (xy 198.742096 -57.32313) (xy 198.769392 -57.274495) (xy 198.803478 -57.230352)
			(xy 198.843627 -57.191643) (xy 198.888985 -57.159192) (xy 198.938585 -57.133691) (xy 198.991369 -57.115684)
			(xy 199.046212 -57.105554) (xy 199.101946 -57.103517) (xy 199.157383 -57.109617) (xy 199.21134 -57.123723)
			(xy 199.262669 -57.145535) (xy 199.310275 -57.174589) (xy 199.353143 -57.210264) (xy 199.39036 -57.251801)
			(xy 199.421133 -57.298314) (xy 199.444805 -57.348811) (xy 199.460873 -57.402218) (xy 199.468993 -57.457394)
			(xy 199.469502 -57.48528) (xy 199.468993 -57.513166) (xy 199.460873 -57.568342) (xy 199.444805 -57.621749)
			(xy 199.421133 -57.672246) (xy 199.39036 -57.718759) (xy 199.353143 -57.760296) (xy 199.310275 -57.795971)
			(xy 199.262669 -57.825025) (xy 199.21134 -57.846837) (xy 199.157383 -57.860943) (xy 199.101946 -57.867043)
			(xy 199.046212 -57.865006) (xy 198.991369 -57.854876) (xy 198.938585 -57.836869) (xy 198.888985 -57.811368)
			(xy 198.843627 -57.778917) (xy 198.803478 -57.740208) (xy 198.769392 -57.696065) (xy 198.742096 -57.64743)
			(xy 198.722173 -57.595339) (xy 198.710047 -57.540902) (xy 198.705976 -57.48528) (xy 182.383302 -57.48528)
			(xy 182.383274 -57.487021) (xy 182.376421 -57.537795) (xy 182.362824 -57.587192) (xy 182.34273 -57.634322)
			(xy 182.316502 -57.678333) (xy 182.30088 -57.69864) (xy 182.300626 -57.698894) (xy 182.299102 -57.700672)
			(xy 182.294801 -57.7072) (xy 182.290009 -57.722071) (xy 182.289704 -57.729882) (xy 182.289704 -57.763156)
			(xy 182.278528 -57.763156) (xy 182.278528 -57.813956) (xy 182.278862 -57.82256) (xy 182.284574 -57.838791)
			(xy 182.289704 -57.845706) (xy 182.290974 -57.84723) (xy 182.308367 -57.868107) (xy 182.337683 -57.913858)
			(xy 182.360209 -57.963306) (xy 182.37549 -58.01545) (xy 182.383215 -58.069235) (xy 182.383684 -58.096404)
			(xy 182.383274 -58.122021) (xy 182.376421 -58.172795) (xy 182.362824 -58.222192) (xy 182.34273 -58.269322)
			(xy 182.316502 -58.313333) (xy 182.30088 -58.33364) (xy 182.300626 -58.333894) (xy 182.299102 -58.335672)
			(xy 182.294801 -58.3422) (xy 182.290009 -58.357071) (xy 182.289704 -58.364882) (xy 182.289704 -58.398156)
			(xy 182.278528 -58.398156) (xy 182.278528 -58.448956) (xy 182.278862 -58.45756) (xy 182.284574 -58.473791)
			(xy 182.289704 -58.480706) (xy 182.290974 -58.48223) (xy 182.308367 -58.503107) (xy 182.337683 -58.548858)
			(xy 182.360209 -58.598306) (xy 182.37549 -58.65045) (xy 182.379639 -58.679334) (xy 190.095378 -58.679334)
			(xy 190.095808 -58.653019) (xy 190.103052 -58.600889) (xy 190.117379 -58.550246) (xy 190.138518 -58.502047)
			(xy 190.16607 -58.457205) (xy 190.199514 -58.416566) (xy 190.218568 -58.39841) (xy 190.225963 -58.390882)
			(xy 190.234492 -58.371607) (xy 190.235078 -58.361072) (xy 190.235078 -58.286396) (xy 190.234571 -58.275844)
			(xy 190.226021 -58.256548) (xy 190.218568 -58.249058) (xy 190.199493 -58.230922) (xy 190.166039 -58.190287)
			(xy 190.138483 -58.145443) (xy 190.117348 -58.097238) (xy 190.103035 -58.046588) (xy 190.095814 -57.994451)
			(xy 190.095378 -57.968134) (xy 190.095864 -57.940883) (xy 190.10362 -57.886935) (xy 190.118975 -57.83464)
			(xy 190.141617 -57.785063) (xy 190.171083 -57.739213) (xy 190.206774 -57.698022) (xy 190.247965 -57.662331)
			(xy 190.293815 -57.632865) (xy 190.343392 -57.610223) (xy 190.395687 -57.594868) (xy 190.449635 -57.587112)
			(xy 190.504137 -57.587112) (xy 190.558085 -57.594868) (xy 190.61038 -57.610223) (xy 190.659957 -57.632865)
			(xy 190.705807 -57.662331) (xy 190.746998 -57.698022) (xy 190.782689 -57.739213) (xy 190.812155 -57.785063)
			(xy 190.834797 -57.83464) (xy 190.850152 -57.886935) (xy 190.857908 -57.940883) (xy 190.858394 -57.968134)
			(xy 190.857951 -57.994449) (xy 190.850712 -58.046578) (xy 190.842367 -58.076084) (xy 199.45807 -58.076084)
			(xy 199.462141 -58.020462) (xy 199.474267 -57.966025) (xy 199.49419 -57.913934) (xy 199.521486 -57.865299)
			(xy 199.555572 -57.821156) (xy 199.595721 -57.782447) (xy 199.641079 -57.749996) (xy 199.690679 -57.724495)
			(xy 199.743463 -57.706488) (xy 199.798306 -57.696358) (xy 199.85404 -57.694321) (xy 199.909477 -57.700421)
			(xy 199.963434 -57.714527) (xy 200.014763 -57.736339) (xy 200.062369 -57.765393) (xy 200.105237 -57.801068)
			(xy 200.142454 -57.842605) (xy 200.15879 -57.867296) (xy 201.743054 -57.867296) (xy 201.747125 -57.811674)
			(xy 201.759251 -57.757237) (xy 201.779174 -57.705146) (xy 201.80647 -57.656511) (xy 201.840556 -57.612368)
			(xy 201.880705 -57.573659) (xy 201.926063 -57.541208) (xy 201.975663 -57.515707) (xy 202.028447 -57.4977)
			(xy 202.08329 -57.48757) (xy 202.139024 -57.485533) (xy 202.194461 -57.491633) (xy 202.248418 -57.505739)
			(xy 202.299747 -57.527551) (xy 202.347353 -57.556605) (xy 202.390221 -57.59228) (xy 202.427438 -57.633817)
			(xy 202.458211 -57.68033) (xy 202.481883 -57.730827) (xy 202.497951 -57.784234) (xy 202.506071 -57.83941)
			(xy 202.50658 -57.867296) (xy 202.506071 -57.895182) (xy 202.497951 -57.950358) (xy 202.481883 -58.003765)
			(xy 202.458211 -58.054262) (xy 202.427438 -58.100775) (xy 202.390221 -58.142312) (xy 202.347353 -58.177987)
			(xy 202.299747 -58.207041) (xy 202.248418 -58.228853) (xy 202.194461 -58.242959) (xy 202.139024 -58.249059)
			(xy 202.08329 -58.247022) (xy 202.028447 -58.236892) (xy 201.975663 -58.218885) (xy 201.926063 -58.193384)
			(xy 201.880705 -58.160933) (xy 201.840556 -58.122224) (xy 201.80647 -58.078081) (xy 201.779174 -58.029446)
			(xy 201.759251 -57.977355) (xy 201.747125 -57.922918) (xy 201.743054 -57.867296) (xy 200.15879 -57.867296)
			(xy 200.173227 -57.889118) (xy 200.196899 -57.939615) (xy 200.212967 -57.993022) (xy 200.221087 -58.048198)
			(xy 200.221596 -58.076084) (xy 200.221087 -58.10397) (xy 200.212967 -58.159146) (xy 200.196899 -58.212553)
			(xy 200.173227 -58.26305) (xy 200.142454 -58.309563) (xy 200.105237 -58.3511) (xy 200.062369 -58.386775)
			(xy 200.014763 -58.415829) (xy 199.963434 -58.437641) (xy 199.909477 -58.451747) (xy 199.85404 -58.457847)
			(xy 199.798306 -58.45581) (xy 199.743463 -58.44568) (xy 199.690679 -58.427673) (xy 199.641079 -58.402172)
			(xy 199.595721 -58.369721) (xy 199.555572 -58.331012) (xy 199.521486 -58.286869) (xy 199.49419 -58.238234)
			(xy 199.474267 -58.186143) (xy 199.462141 -58.131706) (xy 199.45807 -58.076084) (xy 190.842367 -58.076084)
			(xy 190.836388 -58.097222) (xy 190.815251 -58.145421) (xy 190.7877 -58.190264) (xy 190.754257 -58.230902)
			(xy 190.735204 -58.249058) (xy 190.72782 -58.256594) (xy 190.719285 -58.275863) (xy 190.718694 -58.286396)
			(xy 190.718694 -58.361072) (xy 190.719227 -58.371621) (xy 190.72776 -58.390916) (xy 190.735204 -58.39841)
			(xy 190.754258 -58.416567) (xy 190.787715 -58.457196) (xy 190.815274 -58.502036) (xy 190.836413 -58.550237)
			(xy 190.839519 -58.561224) (xy 200.662284 -58.561224) (xy 200.666355 -58.505602) (xy 200.678481 -58.451165)
			(xy 200.698404 -58.399074) (xy 200.7257 -58.350439) (xy 200.759786 -58.306296) (xy 200.799935 -58.267587)
			(xy 200.845293 -58.235136) (xy 200.894893 -58.209635) (xy 200.947677 -58.191628) (xy 201.00252 -58.181498)
			(xy 201.058254 -58.179461) (xy 201.113691 -58.185561) (xy 201.167648 -58.199667) (xy 201.218977 -58.221479)
			(xy 201.266583 -58.250533) (xy 201.309451 -58.286208) (xy 201.346668 -58.327745) (xy 201.377441 -58.374258)
			(xy 201.401113 -58.424755) (xy 201.417181 -58.478162) (xy 201.425301 -58.533338) (xy 201.42581 -58.561224)
			(xy 201.425301 -58.58911) (xy 201.417181 -58.644286) (xy 201.401113 -58.697693) (xy 201.377441 -58.74819)
			(xy 201.346668 -58.794703) (xy 201.309451 -58.83624) (xy 201.266583 -58.871915) (xy 201.218977 -58.900969)
			(xy 201.167648 -58.922781) (xy 201.113691 -58.936887) (xy 201.058254 -58.942987) (xy 201.00252 -58.94095)
			(xy 200.947677 -58.93082) (xy 200.894893 -58.912813) (xy 200.845293 -58.887312) (xy 200.799935 -58.854861)
			(xy 200.759786 -58.816152) (xy 200.7257 -58.772009) (xy 200.698404 -58.723374) (xy 200.678481 -58.671283)
			(xy 200.666355 -58.616846) (xy 200.662284 -58.561224) (xy 190.839519 -58.561224) (xy 190.850731 -58.600884)
			(xy 190.857955 -58.653018) (xy 190.858394 -58.679334) (xy 190.857908 -58.706585) (xy 190.850152 -58.760533)
			(xy 190.834797 -58.812828) (xy 190.812155 -58.862405) (xy 190.782689 -58.908255) (xy 190.746998 -58.949446)
			(xy 190.705807 -58.985137) (xy 190.659957 -59.014603) (xy 190.61038 -59.037245) (xy 190.558085 -59.0526)
			(xy 190.504137 -59.060356) (xy 190.449635 -59.060356) (xy 190.395687 -59.0526) (xy 190.343392 -59.037245)
			(xy 190.293815 -59.014603) (xy 190.247965 -58.985137) (xy 190.206774 -58.949446) (xy 190.171083 -58.908255)
			(xy 190.141617 -58.862405) (xy 190.118975 -58.812828) (xy 190.10362 -58.760533) (xy 190.095864 -58.706585)
			(xy 190.095378 -58.679334) (xy 182.379639 -58.679334) (xy 182.383215 -58.704235) (xy 182.383684 -58.731404)
			(xy 182.383684 -58.739024) (xy 182.382508 -58.769203) (xy 182.37181 -58.828641) (xy 182.351888 -58.885653)
			(xy 182.323237 -58.938817) (xy 182.286574 -58.986808) (xy 182.265066 -59.00801) (xy 182.262272 -59.01055)
			(xy 182.255798 -59.018432) (xy 182.249126 -59.037689) (xy 182.249318 -59.047888) (xy 182.257153 -59.174634)
			(xy 199.193148 -59.174634) (xy 199.197219 -59.119012) (xy 199.209345 -59.064575) (xy 199.229268 -59.012484)
			(xy 199.256564 -58.963849) (xy 199.29065 -58.919706) (xy 199.330799 -58.880997) (xy 199.376157 -58.848546)
			(xy 199.425757 -58.823045) (xy 199.478541 -58.805038) (xy 199.533384 -58.794908) (xy 199.589118 -58.792871)
			(xy 199.644555 -58.798971) (xy 199.698512 -58.813077) (xy 199.749841 -58.834889) (xy 199.797447 -58.863943)
			(xy 199.840315 -58.899618) (xy 199.877532 -58.941155) (xy 199.908305 -58.987668) (xy 199.931977 -59.038165)
			(xy 199.948045 -59.091572) (xy 199.956165 -59.146748) (xy 199.956674 -59.174634) (xy 199.956165 -59.20252)
			(xy 199.948045 -59.257696) (xy 199.931977 -59.311103) (xy 199.908305 -59.3616) (xy 199.877532 -59.408113)
			(xy 199.840315 -59.44965) (xy 199.797447 -59.485325) (xy 199.749841 -59.514379) (xy 199.698512 -59.536191)
			(xy 199.644555 -59.550297) (xy 199.589118 -59.556397) (xy 199.533384 -59.55436) (xy 199.478541 -59.54423)
			(xy 199.425757 -59.526223) (xy 199.376157 -59.500722) (xy 199.330799 -59.468271) (xy 199.29065 -59.429562)
			(xy 199.256564 -59.385419) (xy 199.229268 -59.336784) (xy 199.209345 -59.284693) (xy 199.197219 -59.230256)
			(xy 199.193148 -59.174634) (xy 182.257153 -59.174634) (xy 182.309368 -60.019254) (xy 190.235761 -60.019254)
			(xy 190.235761 -59.964746) (xy 190.243519 -59.910792) (xy 190.258877 -59.858492) (xy 190.281522 -59.80891)
			(xy 190.310993 -59.763056) (xy 190.346691 -59.721863) (xy 190.387888 -59.686169) (xy 190.433745 -59.656703)
			(xy 190.483329 -59.634063) (xy 190.535631 -59.618711) (xy 190.589586 -59.610959) (xy 190.61684 -59.610498)
			(xy 190.644209 -59.611) (xy 190.698386 -59.618809) (xy 190.750889 -59.63429) (xy 190.800637 -59.657124)
			(xy 190.846605 -59.68684) (xy 190.867538 -59.704478) (xy 190.867792 -59.704732) (xy 190.874874 -59.710325)
			(xy 190.891794 -59.716567) (xy 190.900812 -59.716924) (xy 190.967868 -59.716924) (xy 190.976883 -59.716546)
			(xy 190.9938 -59.710313) (xy 191.000888 -59.704732) (xy 191.000888 -59.704478) (xy 191.001142 -59.704478)
			(xy 191.022075 -59.686837) (xy 191.068043 -59.657113) (xy 191.117789 -59.634267) (xy 191.170291 -59.618771)
			(xy 191.224469 -59.610942) (xy 191.279211 -59.610942) (xy 191.333389 -59.618771) (xy 191.385891 -59.634267)
			(xy 191.435637 -59.657113) (xy 191.481605 -59.686837) (xy 191.502538 -59.704478) (xy 191.502792 -59.704732)
			(xy 191.509874 -59.710325) (xy 191.526794 -59.716567) (xy 191.535812 -59.716924) (xy 191.602868 -59.716924)
			(xy 191.611883 -59.716546) (xy 191.6288 -59.710313) (xy 191.635888 -59.704732) (xy 191.635888 -59.704478)
			(xy 191.636142 -59.704478) (xy 191.657082 -59.686849) (xy 191.703053 -59.657137) (xy 191.752799 -59.634299)
			(xy 191.805297 -59.618805) (xy 191.859471 -59.610974) (xy 191.88684 -59.610498) (xy 191.91409 -59.610975)
			(xy 191.968034 -59.618736) (xy 192.020325 -59.634095) (xy 192.069898 -59.656738) (xy 192.115744 -59.686206)
			(xy 192.15693 -59.721898) (xy 192.192618 -59.763088) (xy 192.222081 -59.808937) (xy 192.244719 -59.858513)
			(xy 192.260073 -59.910805) (xy 192.267828 -59.96475) (xy 192.267828 -60.01925) (xy 192.260073 -60.073195)
			(xy 192.244719 -60.125487) (xy 192.222081 -60.175063) (xy 192.192618 -60.220912) (xy 192.15693 -60.262102)
			(xy 192.115744 -60.297794) (xy 192.069898 -60.327262) (xy 192.020325 -60.349905) (xy 191.968034 -60.365264)
			(xy 191.91409 -60.373025) (xy 191.88684 -60.373514) (xy 191.859471 -60.373021) (xy 191.805293 -60.365209)
			(xy 191.75279 -60.349726) (xy 191.703043 -60.326891) (xy 191.657075 -60.297172) (xy 191.636142 -60.279534)
			(xy 191.635888 -60.27928) (xy 191.628811 -60.27368) (xy 191.611887 -60.267442) (xy 191.602868 -60.267088)
			(xy 191.535812 -60.267088) (xy 191.526796 -60.267453) (xy 191.509879 -60.273695) (xy 191.502792 -60.27928)
			(xy 191.502538 -60.279534) (xy 191.481605 -60.297175) (xy 191.435637 -60.326899) (xy 191.385891 -60.349745)
			(xy 191.333389 -60.365241) (xy 191.279211 -60.37307) (xy 191.224469 -60.37307) (xy 191.170291 -60.365241)
			(xy 191.117789 -60.349745) (xy 191.068043 -60.326899) (xy 191.022075 -60.297175) (xy 191.001142 -60.279534)
			(xy 191.000888 -60.27928) (xy 190.993811 -60.27368) (xy 190.976887 -60.267442) (xy 190.967868 -60.267088)
			(xy 190.900812 -60.267088) (xy 190.891796 -60.267453) (xy 190.874879 -60.273695) (xy 190.867792 -60.27928)
			(xy 190.867792 -60.279534) (xy 190.867538 -60.279534) (xy 190.846607 -60.297174) (xy 190.800633 -60.326885)
			(xy 190.750885 -60.34972) (xy 190.698385 -60.365211) (xy 190.644209 -60.373039) (xy 190.61684 -60.373514)
			(xy 190.589586 -60.373041) (xy 190.535631 -60.365289) (xy 190.483329 -60.349937) (xy 190.433745 -60.327297)
			(xy 190.387888 -60.297831) (xy 190.346691 -60.262137) (xy 190.310993 -60.220944) (xy 190.281522 -60.17509)
			(xy 190.258877 -60.125508) (xy 190.243519 -60.073208) (xy 190.235761 -60.019254) (xy 182.309368 -60.019254)
			(xy 182.341774 -60.54344) (xy 182.342028 -60.546488) (xy 182.343552 -60.604908) (xy 182.343552 -60.605416)
			(xy 182.342948 -60.633356) (xy 201.896978 -60.633356) (xy 201.901049 -60.577734) (xy 201.913175 -60.523297)
			(xy 201.933098 -60.471206) (xy 201.960394 -60.422571) (xy 201.99448 -60.378428) (xy 202.034629 -60.339719)
			(xy 202.079987 -60.307268) (xy 202.129587 -60.281767) (xy 202.182371 -60.26376) (xy 202.237214 -60.25363)
			(xy 202.292948 -60.251593) (xy 202.348385 -60.257693) (xy 202.402342 -60.271799) (xy 202.453671 -60.293611)
			(xy 202.501277 -60.322665) (xy 202.544145 -60.35834) (xy 202.581362 -60.399877) (xy 202.612135 -60.44639)
			(xy 202.635807 -60.496887) (xy 202.651875 -60.550294) (xy 202.659995 -60.60547) (xy 202.660504 -60.633356)
			(xy 202.659995 -60.661242) (xy 202.651875 -60.716418) (xy 202.635807 -60.769825) (xy 202.612135 -60.820322)
			(xy 202.581362 -60.866835) (xy 202.544145 -60.908372) (xy 202.501277 -60.944047) (xy 202.453671 -60.973101)
			(xy 202.402342 -60.994913) (xy 202.348385 -61.009019) (xy 202.292948 -61.015119) (xy 202.237214 -61.013082)
			(xy 202.182371 -61.002952) (xy 202.129587 -60.984945) (xy 202.079987 -60.959444) (xy 202.034629 -60.926993)
			(xy 201.99448 -60.888284) (xy 201.960394 -60.844141) (xy 201.933098 -60.795506) (xy 201.913175 -60.743415)
			(xy 201.901049 -60.688978) (xy 201.896978 -60.633356) (xy 182.342948 -60.633356) (xy 182.342536 -60.652406)
			(xy 182.302867 -61.487812) (xy 200.404474 -61.487812) (xy 200.408545 -61.43219) (xy 200.420671 -61.377753)
			(xy 200.440594 -61.325662) (xy 200.46789 -61.277027) (xy 200.501976 -61.232884) (xy 200.542125 -61.194175)
			(xy 200.587483 -61.161724) (xy 200.637083 -61.136223) (xy 200.689867 -61.118216) (xy 200.74471 -61.108086)
			(xy 200.800444 -61.106049) (xy 200.855881 -61.112149) (xy 200.909838 -61.126255) (xy 200.961167 -61.148067)
			(xy 201.008773 -61.177121) (xy 201.051641 -61.212796) (xy 201.088858 -61.254333) (xy 201.119631 -61.300846)
			(xy 201.143303 -61.351343) (xy 201.159371 -61.40475) (xy 201.167491 -61.459926) (xy 201.168 -61.487812)
			(xy 201.167491 -61.515698) (xy 201.159371 -61.570874) (xy 201.143303 -61.624281) (xy 201.119631 -61.674778)
			(xy 201.088858 -61.721291) (xy 201.051641 -61.762828) (xy 201.008773 -61.798503) (xy 200.961167 -61.827557)
			(xy 200.909838 -61.849369) (xy 200.855881 -61.863475) (xy 200.800444 -61.869575) (xy 200.74471 -61.867538)
			(xy 200.689867 -61.857408) (xy 200.637083 -61.839401) (xy 200.587483 -61.8139) (xy 200.542125 -61.781449)
			(xy 200.501976 -61.74274) (xy 200.46789 -61.698597) (xy 200.440594 -61.649962) (xy 200.420671 -61.597871)
			(xy 200.408545 -61.543434) (xy 200.404474 -61.487812) (xy 182.302867 -61.487812) (xy 182.272799 -62.121034)
			(xy 198.342248 -62.121034) (xy 198.346319 -62.065412) (xy 198.358445 -62.010975) (xy 198.378368 -61.958884)
			(xy 198.405664 -61.910249) (xy 198.43975 -61.866106) (xy 198.479899 -61.827397) (xy 198.525257 -61.794946)
			(xy 198.574857 -61.769445) (xy 198.627641 -61.751438) (xy 198.682484 -61.741308) (xy 198.738218 -61.739271)
			(xy 198.793655 -61.745371) (xy 198.847612 -61.759477) (xy 198.898941 -61.781289) (xy 198.946547 -61.810343)
			(xy 198.989415 -61.846018) (xy 199.026632 -61.887555) (xy 199.057405 -61.934068) (xy 199.081077 -61.984565)
			(xy 199.097145 -62.037972) (xy 199.105265 -62.093148) (xy 199.105774 -62.121034) (xy 199.105265 -62.14892)
			(xy 199.097145 -62.204096) (xy 199.081077 -62.257503) (xy 199.057405 -62.308) (xy 199.026632 -62.354513)
			(xy 198.989415 -62.39605) (xy 198.946547 -62.431725) (xy 198.898941 -62.460779) (xy 198.847612 -62.482591)
			(xy 198.793655 -62.496697) (xy 198.738218 -62.502797) (xy 198.682484 -62.50076) (xy 198.627641 -62.49063)
			(xy 198.574857 -62.472623) (xy 198.525257 -62.447122) (xy 198.479899 -62.414671) (xy 198.43975 -62.375962)
			(xy 198.405664 -62.331819) (xy 198.378368 -62.283184) (xy 198.358445 -62.231093) (xy 198.346319 -62.176656)
			(xy 198.342248 -62.121034) (xy 182.272799 -62.121034) (xy 182.220921 -63.213548) (xy 190.220888 -63.213548)
			(xy 190.220888 -63.159052) (xy 190.228643 -63.105109) (xy 190.243996 -63.05282) (xy 190.266633 -63.003247)
			(xy 190.296094 -62.9574) (xy 190.33178 -62.916212) (xy 190.372963 -62.880522) (xy 190.418807 -62.851055)
			(xy 190.468377 -62.828412) (xy 190.520664 -62.813053) (xy 190.574606 -62.805291) (xy 190.601854 -62.804802)
			(xy 190.629223 -62.805295) (xy 190.683401 -62.813106) (xy 190.735904 -62.828589) (xy 190.785651 -62.851425)
			(xy 190.831619 -62.881143) (xy 190.852552 -62.898782) (xy 190.852806 -62.899036) (xy 190.859884 -62.904635)
			(xy 190.876807 -62.910873) (xy 190.885826 -62.911228) (xy 190.952882 -62.911228) (xy 190.961897 -62.910856)
			(xy 190.978814 -62.904618) (xy 190.985902 -62.899036) (xy 190.985902 -62.898782) (xy 190.986156 -62.898782)
			(xy 191.007089 -62.881141) (xy 191.053057 -62.851417) (xy 191.102803 -62.828571) (xy 191.155305 -62.813075)
			(xy 191.209483 -62.805246) (xy 191.264225 -62.805246) (xy 191.318403 -62.813075) (xy 191.370905 -62.828571)
			(xy 191.420651 -62.851417) (xy 191.466619 -62.881141) (xy 191.487552 -62.898782) (xy 191.487806 -62.899036)
			(xy 191.494884 -62.904635) (xy 191.511807 -62.910873) (xy 191.520826 -62.911228) (xy 191.587882 -62.911228)
			(xy 191.596897 -62.910856) (xy 191.613814 -62.904618) (xy 191.620902 -62.899036) (xy 191.620902 -62.898782)
			(xy 191.621156 -62.898782) (xy 191.642092 -62.881147) (xy 191.688064 -62.851435) (xy 191.73781 -62.828599)
			(xy 191.79031 -62.813107) (xy 191.844485 -62.805277) (xy 191.871854 -62.804802) (xy 191.89911 -62.805242)
			(xy 191.953067 -62.812994) (xy 192.005372 -62.828346) (xy 192.054959 -62.850987) (xy 192.100819 -62.880454)
			(xy 192.142019 -62.916149) (xy 192.177718 -62.957344) (xy 192.207191 -63.0032) (xy 192.229838 -63.052785)
			(xy 192.23966 -63.086234) (xy 195.487542 -63.086234) (xy 195.491613 -63.030612) (xy 195.503739 -62.976175)
			(xy 195.523662 -62.924084) (xy 195.550958 -62.875449) (xy 195.585044 -62.831306) (xy 195.625193 -62.792597)
			(xy 195.670551 -62.760146) (xy 195.720151 -62.734645) (xy 195.772935 -62.716638) (xy 195.827778 -62.706508)
			(xy 195.883512 -62.704471) (xy 195.938949 -62.710571) (xy 195.992906 -62.724677) (xy 196.044235 -62.746489)
			(xy 196.091841 -62.775543) (xy 196.134709 -62.811218) (xy 196.171926 -62.852755) (xy 196.202699 -62.899268)
			(xy 196.226371 -62.949765) (xy 196.242439 -63.003172) (xy 196.250559 -63.058348) (xy 196.251068 -63.086234)
			(xy 196.250559 -63.11412) (xy 196.242439 -63.169296) (xy 196.226371 -63.222703) (xy 196.202699 -63.2732)
			(xy 196.202546 -63.273432) (xy 197.676768 -63.273432) (xy 197.680839 -63.21781) (xy 197.692965 -63.163373)
			(xy 197.712888 -63.111282) (xy 197.740184 -63.062647) (xy 197.77427 -63.018504) (xy 197.814419 -62.979795)
			(xy 197.859777 -62.947344) (xy 197.909377 -62.921843) (xy 197.962161 -62.903836) (xy 198.017004 -62.893706)
			(xy 198.072738 -62.891669) (xy 198.128175 -62.897769) (xy 198.182132 -62.911875) (xy 198.233461 -62.933687)
			(xy 198.281067 -62.962741) (xy 198.323935 -62.998416) (xy 198.361152 -63.039953) (xy 198.391925 -63.086466)
			(xy 198.415597 -63.136963) (xy 198.431665 -63.19037) (xy 198.439785 -63.245546) (xy 198.440294 -63.273432)
			(xy 198.439785 -63.301318) (xy 198.431665 -63.356494) (xy 198.415597 -63.409901) (xy 198.391925 -63.460398)
			(xy 198.361152 -63.506911) (xy 198.323935 -63.548448) (xy 198.281067 -63.584123) (xy 198.233461 -63.613177)
			(xy 198.182132 -63.634989) (xy 198.128175 -63.649095) (xy 198.072738 -63.655195) (xy 198.017004 -63.653158)
			(xy 197.962161 -63.643028) (xy 197.909377 -63.625021) (xy 197.859777 -63.59952) (xy 197.814419 -63.567069)
			(xy 197.77427 -63.52836) (xy 197.740184 -63.484217) (xy 197.712888 -63.435582) (xy 197.692965 -63.383491)
			(xy 197.680839 -63.329054) (xy 197.676768 -63.273432) (xy 196.202546 -63.273432) (xy 196.171926 -63.319713)
			(xy 196.134709 -63.36125) (xy 196.091841 -63.396925) (xy 196.044235 -63.425979) (xy 195.992906 -63.447791)
			(xy 195.938949 -63.461897) (xy 195.883512 -63.467997) (xy 195.827778 -63.46596) (xy 195.772935 -63.45583)
			(xy 195.720151 -63.437823) (xy 195.670551 -63.412322) (xy 195.625193 -63.379871) (xy 195.585044 -63.341162)
			(xy 195.550958 -63.297019) (xy 195.523662 -63.248384) (xy 195.503739 -63.196293) (xy 195.491613 -63.141856)
			(xy 195.487542 -63.086234) (xy 192.23966 -63.086234) (xy 192.245197 -63.105088) (xy 192.252955 -63.159044)
			(xy 192.252955 -63.213556) (xy 192.245197 -63.267512) (xy 192.229838 -63.319815) (xy 192.207191 -63.3694)
			(xy 192.177718 -63.415256) (xy 192.142019 -63.456451) (xy 192.100819 -63.492146) (xy 192.054959 -63.521613)
			(xy 192.005372 -63.544254) (xy 191.953067 -63.559606) (xy 191.89911 -63.567358) (xy 191.871854 -63.567818)
			(xy 191.844484 -63.56734) (xy 191.790305 -63.559528) (xy 191.737801 -63.544043) (xy 191.688054 -63.521203)
			(xy 191.642087 -63.491479) (xy 191.621156 -63.473838) (xy 191.620902 -63.473584) (xy 191.61382 -63.46799)
			(xy 191.5969 -63.461748) (xy 191.587882 -63.461392) (xy 191.520826 -63.461392) (xy 191.511811 -63.461763)
			(xy 191.494894 -63.468001) (xy 191.487806 -63.473584) (xy 191.487552 -63.473838) (xy 191.466619 -63.491479)
			(xy 191.420651 -63.521203) (xy 191.370905 -63.544049) (xy 191.318403 -63.559545) (xy 191.264225 -63.567374)
			(xy 191.209483 -63.567374) (xy 191.155305 -63.559545) (xy 191.102803 -63.544049) (xy 191.053057 -63.521203)
			(xy 191.007089 -63.491479) (xy 190.986156 -63.473838) (xy 190.985902 -63.473584) (xy 190.97882 -63.46799)
			(xy 190.9619 -63.461748) (xy 190.952882 -63.461392) (xy 190.885826 -63.461392) (xy 190.876811 -63.461763)
			(xy 190.859894 -63.468001) (xy 190.852806 -63.473584) (xy 190.852806 -63.473838) (xy 190.852552 -63.473838)
			(xy 190.831616 -63.491472) (xy 190.785644 -63.521184) (xy 190.735897 -63.54402) (xy 190.683398 -63.559513)
			(xy 190.629223 -63.567343) (xy 190.601854 -63.567818) (xy 190.574606 -63.567309) (xy 190.520664 -63.559547)
			(xy 190.468377 -63.544188) (xy 190.418807 -63.521545) (xy 190.372963 -63.492078) (xy 190.33178 -63.456388)
			(xy 190.296094 -63.4152) (xy 190.266633 -63.369353) (xy 190.243996 -63.31978) (xy 190.228643 -63.267491)
			(xy 190.220888 -63.213548) (xy 182.220921 -63.213548) (xy 182.131298 -65.100962) (xy 188.23254 -65.100962)
			(xy 188.236611 -65.04534) (xy 188.248737 -64.990903) (xy 188.26866 -64.938812) (xy 188.295956 -64.890177)
			(xy 188.330042 -64.846034) (xy 188.370191 -64.807325) (xy 188.415549 -64.774874) (xy 188.465149 -64.749373)
			(xy 188.517933 -64.731366) (xy 188.572776 -64.721236) (xy 188.62851 -64.719199) (xy 188.683947 -64.725299)
			(xy 188.737904 -64.739405) (xy 188.789233 -64.761217) (xy 188.836839 -64.790271) (xy 188.879707 -64.825946)
			(xy 188.916924 -64.867483) (xy 188.947697 -64.913996) (xy 188.971369 -64.964493) (xy 188.987437 -65.0179)
			(xy 188.995557 -65.073076) (xy 188.996066 -65.100962) (xy 188.995557 -65.128848) (xy 188.987437 -65.184024)
			(xy 188.971369 -65.237431) (xy 188.947697 -65.287928) (xy 188.916924 -65.334441) (xy 188.879707 -65.375978)
			(xy 188.836839 -65.411653) (xy 188.789233 -65.440707) (xy 188.737904 -65.462519) (xy 188.683947 -65.476625)
			(xy 188.62851 -65.482725) (xy 188.572776 -65.480688) (xy 188.517933 -65.470558) (xy 188.465149 -65.452551)
			(xy 188.415549 -65.42705) (xy 188.370191 -65.394599) (xy 188.330042 -65.35589) (xy 188.295956 -65.311747)
			(xy 188.26866 -65.263112) (xy 188.248737 -65.211021) (xy 188.236611 -65.156584) (xy 188.23254 -65.100962)
			(xy 182.131298 -65.100962) (xy 182.100217 -65.75552) (xy 182.446674 -65.75552) (xy 182.450745 -65.699898)
			(xy 182.462871 -65.645461) (xy 182.482794 -65.59337) (xy 182.51009 -65.544735) (xy 182.544176 -65.500592)
			(xy 182.584325 -65.461883) (xy 182.629683 -65.429432) (xy 182.679283 -65.403931) (xy 182.732067 -65.385924)
			(xy 182.78691 -65.375794) (xy 182.842644 -65.373757) (xy 182.898081 -65.379857) (xy 182.952038 -65.393963)
			(xy 183.003367 -65.415775) (xy 183.050973 -65.444829) (xy 183.093841 -65.480504) (xy 183.131058 -65.522041)
			(xy 183.161831 -65.568554) (xy 183.185503 -65.619051) (xy 183.201571 -65.672458) (xy 183.209691 -65.727634)
			(xy 183.2102 -65.75552) (xy 183.209691 -65.783406) (xy 183.201571 -65.838582) (xy 183.185503 -65.891989)
			(xy 183.161831 -65.942486) (xy 183.131058 -65.988999) (xy 183.093841 -66.030536) (xy 183.050973 -66.066211)
			(xy 183.003367 -66.095265) (xy 182.952038 -66.117077) (xy 182.898081 -66.131183) (xy 182.842644 -66.137283)
			(xy 182.78691 -66.135246) (xy 182.732067 -66.125116) (xy 182.679283 -66.107109) (xy 182.629683 -66.081608)
			(xy 182.584325 -66.049157) (xy 182.544176 -66.010448) (xy 182.51009 -65.966305) (xy 182.482794 -65.91767)
			(xy 182.462871 -65.865579) (xy 182.450745 -65.811142) (xy 182.446674 -65.75552) (xy 182.100217 -65.75552)
			(xy 182.035 -67.128953) (xy 182.466675 -67.128953) (xy 182.466675 -67.074447) (xy 182.474433 -67.020495)
			(xy 182.48979 -66.968196) (xy 182.512435 -66.918616) (xy 182.541905 -66.872763) (xy 182.577601 -66.831572)
			(xy 182.618797 -66.79588) (xy 182.664653 -66.766415) (xy 182.714236 -66.743776) (xy 182.766536 -66.728424)
			(xy 182.820489 -66.720672) (xy 182.847742 -66.720212) (xy 182.875111 -66.720709) (xy 182.929289 -66.728519)
			(xy 182.981792 -66.744001) (xy 183.031539 -66.766836) (xy 183.077507 -66.796554) (xy 183.09844 -66.814192)
			(xy 183.098694 -66.814446) (xy 183.105774 -66.820042) (xy 183.122696 -66.826282) (xy 183.131714 -66.826638)
			(xy 183.19877 -66.826638) (xy 183.207784 -66.826258) (xy 183.224701 -66.820026) (xy 183.23179 -66.814446)
			(xy 183.23179 -66.814192) (xy 183.232044 -66.814192) (xy 183.252985 -66.796564) (xy 183.298956 -66.766851)
			(xy 183.348701 -66.744013) (xy 183.401199 -66.728519) (xy 183.455373 -66.720688) (xy 183.482742 -66.720212)
			(xy 183.509993 -66.720661) (xy 183.563939 -66.728422) (xy 183.616231 -66.743782) (xy 183.665806 -66.766427)
			(xy 183.711653 -66.795896) (xy 183.752841 -66.831589) (xy 183.788529 -66.87278) (xy 183.817993 -66.918631)
			(xy 183.840633 -66.968208) (xy 183.855986 -67.020502) (xy 183.863742 -67.074449) (xy 183.863742 -67.128951)
			(xy 183.855986 -67.182898) (xy 183.840633 -67.235192) (xy 183.817993 -67.284769) (xy 183.788529 -67.33062)
			(xy 183.752841 -67.371811) (xy 183.711653 -67.407504) (xy 183.665806 -67.436973) (xy 183.616231 -67.459618)
			(xy 183.563939 -67.474978) (xy 183.509993 -67.482739) (xy 183.482742 -67.483228) (xy 183.455372 -67.482755)
			(xy 183.401192 -67.474941) (xy 183.348689 -67.459455) (xy 183.298942 -67.436614) (xy 183.252975 -67.40689)
			(xy 183.232044 -67.389248) (xy 183.23179 -67.388994) (xy 183.224711 -67.383396) (xy 183.207788 -67.377157)
			(xy 183.19877 -67.376802) (xy 183.131714 -67.376802) (xy 183.122698 -67.377165) (xy 183.105781 -67.383408)
			(xy 183.098694 -67.388994) (xy 183.098694 -67.389248) (xy 183.09844 -67.389248) (xy 183.077497 -67.406874)
			(xy 183.031528 -67.436589) (xy 182.981783 -67.459429) (xy 182.929285 -67.474923) (xy 182.875111 -67.482753)
			(xy 182.847742 -67.483228) (xy 182.820489 -67.482728) (xy 182.766536 -67.474976) (xy 182.714236 -67.459624)
			(xy 182.664653 -67.436985) (xy 182.618797 -67.40752) (xy 182.577601 -67.371828) (xy 182.541905 -67.330637)
			(xy 182.512435 -67.284784) (xy 182.48979 -67.235204) (xy 182.474433 -67.182905) (xy 182.466675 -67.128953)
			(xy 182.035 -67.128953) (xy 182.017948 -67.488054) (xy 186.879228 -67.488054) (xy 186.883299 -67.432432)
			(xy 186.895425 -67.377995) (xy 186.915348 -67.325904) (xy 186.942644 -67.277269) (xy 186.97673 -67.233126)
			(xy 187.016879 -67.194417) (xy 187.062237 -67.161966) (xy 187.111837 -67.136465) (xy 187.164621 -67.118458)
			(xy 187.219464 -67.108328) (xy 187.275198 -67.106291) (xy 187.330635 -67.112391) (xy 187.384592 -67.126497)
			(xy 187.435921 -67.148309) (xy 187.483527 -67.177363) (xy 187.526395 -67.213038) (xy 187.563612 -67.254575)
			(xy 187.594385 -67.301088) (xy 187.618057 -67.351585) (xy 187.634125 -67.404992) (xy 187.642245 -67.460168)
			(xy 187.642754 -67.488054) (xy 187.642245 -67.51594) (xy 187.63906 -67.537584) (xy 188.171326 -67.537584)
			(xy 188.175397 -67.481962) (xy 188.187523 -67.427525) (xy 188.207446 -67.375434) (xy 188.234742 -67.326799)
			(xy 188.268828 -67.282656) (xy 188.308977 -67.243947) (xy 188.354335 -67.211496) (xy 188.403935 -67.185995)
			(xy 188.456719 -67.167988) (xy 188.511562 -67.157858) (xy 188.567296 -67.155821) (xy 188.622733 -67.161921)
			(xy 188.67669 -67.176027) (xy 188.728019 -67.197839) (xy 188.775625 -67.226893) (xy 188.818493 -67.262568)
			(xy 188.85571 -67.304105) (xy 188.886483 -67.350618) (xy 188.910155 -67.401115) (xy 188.926223 -67.454522)
			(xy 188.934343 -67.509698) (xy 188.934852 -67.537584) (xy 188.934343 -67.56547) (xy 188.930298 -67.592956)
			(xy 189.44539 -67.592956) (xy 189.449461 -67.537334) (xy 189.461587 -67.482897) (xy 189.48151 -67.430806)
			(xy 189.508806 -67.382171) (xy 189.542892 -67.338028) (xy 189.583041 -67.299319) (xy 189.628399 -67.266868)
			(xy 189.677999 -67.241367) (xy 189.730783 -67.22336) (xy 189.785626 -67.21323) (xy 189.84136 -67.211193)
			(xy 189.896797 -67.217293) (xy 189.950754 -67.231399) (xy 190.002083 -67.253211) (xy 190.049689 -67.282265)
			(xy 190.092557 -67.31794) (xy 190.129774 -67.359477) (xy 190.160547 -67.40599) (xy 190.184219 -67.456487)
			(xy 190.200287 -67.509894) (xy 190.208404 -67.565052) (xy 192.546693 -67.565052) (xy 192.546693 -67.510548)
			(xy 192.55445 -67.4566) (xy 192.569806 -67.404305) (xy 192.592449 -67.354728) (xy 192.621917 -67.308877)
			(xy 192.657611 -67.267688) (xy 192.698803 -67.231998) (xy 192.744656 -67.202534) (xy 192.794235 -67.179895)
			(xy 192.846531 -67.164544) (xy 192.90048 -67.156791) (xy 192.927732 -67.15633) (xy 192.955103 -67.15677)
			(xy 193.009284 -67.164593) (xy 193.061787 -67.180088) (xy 193.111534 -67.202935) (xy 193.157499 -67.232666)
			(xy 193.17843 -67.25031) (xy 193.178684 -67.250564) (xy 193.185765 -67.256158) (xy 193.202686 -67.262398)
			(xy 193.211704 -67.262756) (xy 193.27876 -67.262756) (xy 193.287776 -67.262389) (xy 193.304694 -67.25615)
			(xy 193.31178 -67.250564) (xy 193.31178 -67.25031) (xy 193.312034 -67.25031) (xy 193.332981 -67.23269)
			(xy 193.37895 -67.202975) (xy 193.428693 -67.180135) (xy 193.481191 -67.16464) (xy 193.535364 -67.156807)
			(xy 193.562732 -67.15633) (xy 193.589984 -67.156742) (xy 193.643934 -67.164503) (xy 193.69623 -67.179862)
			(xy 193.745808 -67.202508) (xy 193.791659 -67.231978) (xy 193.83285 -67.267673) (xy 193.868541 -67.308866)
			(xy 193.898008 -67.35472) (xy 193.920649 -67.4043) (xy 193.936004 -67.456597) (xy 193.94376 -67.510547)
			(xy 193.94376 -67.565053) (xy 193.936004 -67.619003) (xy 193.920649 -67.6713) (xy 193.898008 -67.72088)
			(xy 193.868541 -67.766734) (xy 193.83285 -67.807927) (xy 193.791659 -67.843622) (xy 193.745808 -67.873092)
			(xy 193.69623 -67.895738) (xy 193.643934 -67.911097) (xy 193.589984 -67.918858) (xy 193.562732 -67.919346)
			(xy 193.535362 -67.918874) (xy 193.481182 -67.91106) (xy 193.428679 -67.895573) (xy 193.378932 -67.872732)
			(xy 193.332965 -67.843007) (xy 193.312034 -67.825366) (xy 193.31178 -67.825112) (xy 193.304702 -67.819512)
			(xy 193.287779 -67.813273) (xy 193.27876 -67.81292) (xy 193.211704 -67.81292) (xy 193.202687 -67.813274)
			(xy 193.18577 -67.819523) (xy 193.178684 -67.825112) (xy 193.178684 -67.825366) (xy 193.17843 -67.825366)
			(xy 193.157493 -67.842999) (xy 193.111522 -67.872713) (xy 193.061776 -67.895551) (xy 193.009276 -67.911043)
			(xy 192.955101 -67.918872) (xy 192.927732 -67.919346) (xy 192.90048 -67.918809) (xy 192.846531 -67.911056)
			(xy 192.794235 -67.895705) (xy 192.744656 -67.873066) (xy 192.698803 -67.843602) (xy 192.657611 -67.807912)
			(xy 192.621917 -67.766723) (xy 192.592449 -67.720872) (xy 192.569806 -67.671295) (xy 192.55445 -67.619)
			(xy 192.546693 -67.565052) (xy 190.208404 -67.565052) (xy 190.208407 -67.56507) (xy 190.208916 -67.592956)
			(xy 190.208407 -67.620842) (xy 190.200287 -67.676018) (xy 190.184219 -67.729425) (xy 190.160547 -67.779922)
			(xy 190.129774 -67.826435) (xy 190.092557 -67.867972) (xy 190.049689 -67.903647) (xy 190.002083 -67.932701)
			(xy 189.950754 -67.954513) (xy 189.896797 -67.968619) (xy 189.84136 -67.974719) (xy 189.785626 -67.972682)
			(xy 189.730783 -67.962552) (xy 189.677999 -67.944545) (xy 189.628399 -67.919044) (xy 189.583041 -67.886593)
			(xy 189.542892 -67.847884) (xy 189.508806 -67.803741) (xy 189.48151 -67.755106) (xy 189.461587 -67.703015)
			(xy 189.449461 -67.648578) (xy 189.44539 -67.592956) (xy 188.930298 -67.592956) (xy 188.926223 -67.620646)
			(xy 188.910155 -67.674053) (xy 188.886483 -67.72455) (xy 188.85571 -67.771063) (xy 188.818493 -67.8126)
			(xy 188.775625 -67.848275) (xy 188.728019 -67.877329) (xy 188.67669 -67.899141) (xy 188.622733 -67.913247)
			(xy 188.567296 -67.919347) (xy 188.511562 -67.91731) (xy 188.456719 -67.90718) (xy 188.403935 -67.889173)
			(xy 188.354335 -67.863672) (xy 188.308977 -67.831221) (xy 188.268828 -67.792512) (xy 188.234742 -67.748369)
			(xy 188.207446 -67.699734) (xy 188.187523 -67.647643) (xy 188.175397 -67.593206) (xy 188.171326 -67.537584)
			(xy 187.63906 -67.537584) (xy 187.634125 -67.571116) (xy 187.618057 -67.624523) (xy 187.594385 -67.67502)
			(xy 187.563612 -67.721533) (xy 187.526395 -67.76307) (xy 187.483527 -67.798745) (xy 187.435921 -67.827799)
			(xy 187.384592 -67.849611) (xy 187.330635 -67.863717) (xy 187.275198 -67.869817) (xy 187.219464 -67.86778)
			(xy 187.164621 -67.85765) (xy 187.111837 -67.839643) (xy 187.062237 -67.814142) (xy 187.016879 -67.781691)
			(xy 186.97673 -67.742982) (xy 186.942644 -67.698839) (xy 186.915348 -67.650204) (xy 186.895425 -67.598113)
			(xy 186.883299 -67.543676) (xy 186.879228 -67.488054) (xy 182.017948 -67.488054) (xy 181.965784 -68.586604)
			(xy 184.72531 -68.586604) (xy 184.725776 -68.559234) (xy 184.733593 -68.505055) (xy 184.749082 -68.452551)
			(xy 184.771924 -68.402804) (xy 184.801649 -68.356838) (xy 184.81929 -68.335906) (xy 184.819544 -68.335652)
			(xy 184.82512 -68.328559) (xy 184.831372 -68.311647) (xy 184.831736 -68.302632) (xy 184.831736 -68.235576)
			(xy 184.831383 -68.226559) (xy 184.825132 -68.209642) (xy 184.819544 -68.202556) (xy 184.81929 -68.202556)
			(xy 184.81929 -68.202302) (xy 184.801637 -68.181381) (xy 184.771927 -68.135405) (xy 184.749094 -68.085655)
			(xy 184.733607 -68.033152) (xy 184.725782 -67.978974) (xy 184.72531 -67.951604) (xy 184.725759 -67.92435)
			(xy 184.733516 -67.870398) (xy 184.748872 -67.818099) (xy 184.771516 -67.768518) (xy 184.800985 -67.722664)
			(xy 184.83668 -67.68147) (xy 184.877875 -67.645777) (xy 184.92373 -67.616309) (xy 184.973312 -67.593668)
			(xy 185.025612 -67.578313) (xy 185.079564 -67.570558) (xy 185.106818 -67.570096) (xy 185.133132 -67.570553)
			(xy 185.185261 -67.57779) (xy 185.235904 -67.592111) (xy 185.284103 -67.613246) (xy 185.328946 -67.640794)
			(xy 185.369586 -67.674234) (xy 185.387742 -67.693286) (xy 185.395248 -67.700706) (xy 185.41454 -67.70922)
			(xy 185.42508 -67.709796) (xy 185.499756 -67.709796) (xy 185.510305 -67.709258) (xy 185.5296 -67.700729)
			(xy 185.537094 -67.693286) (xy 185.555257 -67.674238) (xy 185.595885 -67.64078) (xy 185.640724 -67.613221)
			(xy 185.688923 -67.592081) (xy 185.739569 -67.577762) (xy 185.791702 -67.570536) (xy 185.818018 -67.570096)
			(xy 185.845389 -67.570552) (xy 185.899568 -67.578373) (xy 185.952071 -67.593864) (xy 186.001818 -67.616708)
			(xy 186.047784 -67.646434) (xy 186.068716 -67.664076) (xy 186.06897 -67.66433) (xy 186.076059 -67.669913)
			(xy 186.092974 -67.676161) (xy 186.10199 -67.676522) (xy 186.169046 -67.676522) (xy 186.17806 -67.676135)
			(xy 186.194977 -67.669908) (xy 186.202066 -67.66433) (xy 186.202066 -67.664076) (xy 186.20232 -67.664076)
			(xy 186.223268 -67.646457) (xy 186.269237 -67.616743) (xy 186.31898 -67.593904) (xy 186.371477 -67.578408)
			(xy 186.42565 -67.570573) (xy 186.453018 -67.570096) (xy 186.48027 -67.570561) (xy 186.534219 -67.57832)
			(xy 186.586514 -67.593678) (xy 186.636091 -67.616321) (xy 186.681942 -67.64579) (xy 186.723132 -67.681483)
			(xy 186.758823 -67.722676) (xy 186.788289 -67.768528) (xy 186.81093 -67.818107) (xy 186.826285 -67.870403)
			(xy 186.834041 -67.924352) (xy 186.834526 -67.951604) (xy 186.83408 -67.978975) (xy 186.82626 -68.033156)
			(xy 186.810767 -68.08566) (xy 186.787921 -68.135406) (xy 186.75819 -68.181372) (xy 186.740546 -68.202302)
			(xy 186.740292 -68.202556) (xy 186.734717 -68.20965) (xy 186.728464 -68.226561) (xy 186.7281 -68.235576)
			(xy 186.7281 -68.302632) (xy 186.728442 -68.31165) (xy 186.7347 -68.328567) (xy 186.740292 -68.335652)
			(xy 186.740546 -68.335652) (xy 186.740546 -68.335906) (xy 186.758193 -68.356832) (xy 186.787905 -68.402806)
			(xy 186.810741 -68.452555) (xy 186.82623 -68.505057) (xy 186.834054 -68.559234) (xy 186.834526 -68.586604)
			(xy 186.834026 -68.613855) (xy 186.826269 -68.667801) (xy 186.810915 -68.720094) (xy 186.794275 -68.75653)
			(xy 190.270384 -68.75653) (xy 190.270847 -68.729159) (xy 190.278663 -68.674979) (xy 190.294151 -68.622475)
			(xy 190.316994 -68.572729) (xy 190.346721 -68.526763) (xy 190.364364 -68.505832) (xy 190.364618 -68.505578)
			(xy 190.370222 -68.498503) (xy 190.376458 -68.481577) (xy 190.37681 -68.472558) (xy 190.37681 -68.405502)
			(xy 190.37645 -68.396486) (xy 190.370204 -68.379569) (xy 190.364618 -68.372482) (xy 190.364364 -68.372482)
			(xy 190.364364 -68.372228) (xy 190.346719 -68.351301) (xy 190.317009 -68.305326) (xy 190.294175 -68.255577)
			(xy 190.278685 -68.203076) (xy 190.270858 -68.148899) (xy 190.270384 -68.12153) (xy 190.270883 -68.094278)
			(xy 190.278636 -68.040329) (xy 190.293988 -67.988032) (xy 190.316626 -67.938453) (xy 190.34609 -67.8926)
			(xy 190.38178 -67.851407) (xy 190.422969 -67.815713) (xy 190.468819 -67.786244) (xy 190.518397 -67.763601)
			(xy 190.570692 -67.748244) (xy 190.62464 -67.740486) (xy 190.651892 -67.740022) (xy 190.679262 -67.740487)
			(xy 190.733442 -67.748305) (xy 190.785945 -67.763794) (xy 190.835692 -67.786636) (xy 190.881658 -67.81636)
			(xy 190.90259 -67.834002) (xy 190.902844 -67.834256) (xy 190.909938 -67.839832) (xy 190.926849 -67.846084)
			(xy 190.935864 -67.846448) (xy 191.00292 -67.846448) (xy 191.011939 -67.846112) (xy 191.028857 -67.839851)
			(xy 191.03594 -67.834256) (xy 191.03594 -67.834002) (xy 191.036194 -67.834002) (xy 191.057118 -67.816353)
			(xy 191.103093 -67.786642) (xy 191.152842 -67.763808) (xy 191.205345 -67.74832) (xy 191.259522 -67.740494)
			(xy 191.286892 -67.740022) (xy 191.313206 -67.740488) (xy 191.365335 -67.747722) (xy 191.415978 -67.762041)
			(xy 191.464177 -67.783174) (xy 191.509021 -67.81072) (xy 191.54966 -67.84416) (xy 191.567816 -67.863212)
			(xy 191.575328 -67.870625) (xy 191.594615 -67.879142) (xy 191.605154 -67.879722) (xy 191.67983 -67.879722)
			(xy 191.690376 -67.879162) (xy 191.709671 -67.870648) (xy 191.717168 -67.863212) (xy 191.7353 -67.844133)
			(xy 191.775934 -67.810677) (xy 191.82078 -67.783121) (xy 191.868985 -67.761987) (xy 191.919637 -67.747675)
			(xy 191.971774 -67.740457) (xy 191.998092 -67.740022) (xy 192.025346 -67.740463) (xy 192.079299 -67.74822)
			(xy 192.131599 -67.763576) (xy 192.181182 -67.78622) (xy 192.227036 -67.81569) (xy 192.26823 -67.851386)
			(xy 192.303923 -67.892582) (xy 192.333391 -67.938438) (xy 192.356032 -67.988021) (xy 192.371385 -68.040322)
			(xy 192.379139 -68.094276) (xy 192.3796 -68.12153) (xy 192.379152 -68.148901) (xy 192.371329 -68.203081)
			(xy 192.355836 -68.255584) (xy 192.332991 -68.305331) (xy 192.303263 -68.351297) (xy 192.28562 -68.372228)
			(xy 192.285366 -68.372482) (xy 192.279777 -68.379567) (xy 192.273533 -68.396485) (xy 192.273174 -68.405502)
			(xy 192.273174 -68.472558) (xy 192.273557 -68.481572) (xy 192.279787 -68.498489) (xy 192.285366 -68.505578)
			(xy 192.28562 -68.505578) (xy 192.28562 -68.505832) (xy 192.303244 -68.526776) (xy 192.332957 -68.572746)
			(xy 192.355796 -68.622491) (xy 192.371291 -68.674988) (xy 192.379123 -68.729162) (xy 192.3796 -68.75653)
			(xy 192.37915 -68.783782) (xy 192.371389 -68.837732) (xy 192.35603 -68.890028) (xy 192.333385 -68.939606)
			(xy 192.303915 -68.985456) (xy 192.268219 -69.026646) (xy 192.227026 -69.062337) (xy 192.181172 -69.091803)
			(xy 192.131592 -69.114443) (xy 192.079295 -69.129797) (xy 192.025344 -69.137553) (xy 191.998092 -69.138038)
			(xy 191.971777 -69.137596) (xy 191.919647 -69.130358) (xy 191.869003 -69.116036) (xy 191.820803 -69.094899)
			(xy 191.77596 -69.067347) (xy 191.735323 -69.033903) (xy 191.717168 -69.014848) (xy 191.709654 -69.007437)
			(xy 191.690368 -68.998917) (xy 191.67983 -68.998338) (xy 191.605154 -68.998338) (xy 191.594605 -68.998872)
			(xy 191.575308 -69.007402) (xy 191.567816 -69.014848) (xy 191.549655 -69.033898) (xy 191.509025 -69.067354)
			(xy 191.464186 -69.094912) (xy 191.415986 -69.116051) (xy 191.36534 -69.13037) (xy 191.313208 -69.137598)
			(xy 191.286892 -69.138038) (xy 191.259521 -69.137592) (xy 191.20534 -69.129771) (xy 191.152836 -69.114279)
			(xy 191.10309 -69.091432) (xy 191.057124 -69.061702) (xy 191.036194 -69.044058) (xy 191.03594 -69.043804)
			(xy 191.028846 -69.038228) (xy 191.011935 -69.031975) (xy 191.00292 -69.031612) (xy 190.935864 -69.031612)
			(xy 190.926845 -69.031949) (xy 190.909928 -69.03821) (xy 190.902844 -69.043804) (xy 190.902844 -69.044058)
			(xy 190.90259 -69.044058) (xy 190.881667 -69.061709) (xy 190.835692 -69.09142) (xy 190.785943 -69.114255)
			(xy 190.73344 -69.129743) (xy 190.679262 -69.137567) (xy 190.651892 -69.138038) (xy 190.624642 -69.13753)
			(xy 190.570697 -69.129773) (xy 190.518404 -69.114418) (xy 190.468829 -69.091778) (xy 190.42298 -69.062314)
			(xy 190.381791 -69.026625) (xy 190.346099 -68.985438) (xy 190.316632 -68.939591) (xy 190.293989 -68.890017)
			(xy 190.278632 -68.837725) (xy 190.270872 -68.78378) (xy 190.270384 -68.75653) (xy 186.794275 -68.75653)
			(xy 186.788274 -68.76967) (xy 186.758809 -68.81552) (xy 186.723119 -68.856709) (xy 186.681931 -68.892401)
			(xy 186.636083 -68.921868) (xy 186.586507 -68.94451) (xy 186.534215 -68.959866) (xy 186.480269 -68.967625)
			(xy 186.453018 -68.968112) (xy 186.425648 -68.967632) (xy 186.37147 -68.959817) (xy 186.318967 -68.944331)
			(xy 186.26922 -68.921493) (xy 186.223252 -68.891772) (xy 186.20232 -68.874132) (xy 186.202066 -68.873878)
			(xy 186.194966 -68.86831) (xy 186.17806 -68.862053) (xy 186.169046 -68.861686) (xy 186.10199 -68.861686)
			(xy 186.092973 -68.862041) (xy 186.076056 -68.868291) (xy 186.06897 -68.873878) (xy 186.06897 -68.874132)
			(xy 186.068716 -68.874132) (xy 186.047793 -68.891782) (xy 186.001817 -68.921491) (xy 185.952067 -68.944324)
			(xy 185.899565 -68.959813) (xy 185.845388 -68.967639) (xy 185.818018 -68.968112) (xy 185.791705 -68.967629)
			(xy 185.739577 -68.960397) (xy 185.688935 -68.94608) (xy 185.640736 -68.924951) (xy 185.595892 -68.897408)
			(xy 185.555251 -68.863972) (xy 185.537094 -68.844922) (xy 185.529574 -68.837519) (xy 185.510293 -68.828995)
			(xy 185.499756 -68.828412) (xy 185.42508 -68.828412) (xy 185.414533 -68.828967) (xy 185.395237 -68.837484)
			(xy 185.387742 -68.844922) (xy 185.369612 -68.864003) (xy 185.328976 -68.897457) (xy 185.28413 -68.925012)
			(xy 185.235925 -68.946146) (xy 185.185273 -68.960458) (xy 185.133136 -68.967677) (xy 185.106818 -68.968112)
			(xy 185.079566 -68.967628) (xy 185.025616 -68.959874) (xy 184.973319 -68.94452) (xy 184.923739 -68.92188)
			(xy 184.877886 -68.892414) (xy 184.836693 -68.856723) (xy 184.800999 -68.815532) (xy 184.771531 -68.769681)
			(xy 184.748888 -68.720102) (xy 184.733531 -68.667806) (xy 184.725774 -68.613856) (xy 184.72531 -68.586604)
			(xy 181.965784 -68.586604) (xy 181.915562 -69.64426) (xy 181.914395 -69.666429) (xy 181.910328 -69.710642)
			(xy 181.907434 -69.732652) (xy 181.905656 -69.745606) (xy 181.901846 -69.771514) (xy 181.901846 -69.771768)
			(xy 181.901084 -69.775832) (xy 181.901084 -69.77634) (xy 181.64877 -71.555864) (xy 187.294518 -71.555864)
			(xy 187.298589 -71.500242) (xy 187.310715 -71.445805) (xy 187.330638 -71.393714) (xy 187.357934 -71.345079)
			(xy 187.39202 -71.300936) (xy 187.432169 -71.262227) (xy 187.477527 -71.229776) (xy 187.527127 -71.204275)
			(xy 187.579911 -71.186268) (xy 187.634754 -71.176138) (xy 187.690488 -71.174101) (xy 187.745925 -71.180201)
			(xy 187.799882 -71.194307) (xy 187.851211 -71.216119) (xy 187.898817 -71.245173) (xy 187.941685 -71.280848)
			(xy 187.978902 -71.322385) (xy 188.009675 -71.368898) (xy 188.033347 -71.419395) (xy 188.049415 -71.472802)
			(xy 188.057535 -71.527978) (xy 188.058044 -71.555864) (xy 188.057535 -71.58375) (xy 188.051696 -71.623428)
			(xy 188.803532 -71.623428) (xy 188.807603 -71.567806) (xy 188.819729 -71.513369) (xy 188.839652 -71.461278)
			(xy 188.866948 -71.412643) (xy 188.901034 -71.3685) (xy 188.941183 -71.329791) (xy 188.986541 -71.29734)
			(xy 189.036141 -71.271839) (xy 189.088925 -71.253832) (xy 189.143768 -71.243702) (xy 189.199502 -71.241665)
			(xy 189.254939 -71.247765) (xy 189.308896 -71.261871) (xy 189.360225 -71.283683) (xy 189.407831 -71.312737)
			(xy 189.450699 -71.348412) (xy 189.487916 -71.389949) (xy 189.518689 -71.436462) (xy 189.542361 -71.486959)
			(xy 189.558429 -71.540366) (xy 189.566549 -71.595542) (xy 189.567058 -71.623428) (xy 189.566549 -71.651314)
			(xy 189.558429 -71.70649) (xy 189.542361 -71.759897) (xy 189.518689 -71.810394) (xy 189.487916 -71.856907)
			(xy 189.450699 -71.898444) (xy 189.407831 -71.934119) (xy 189.360225 -71.963173) (xy 189.308896 -71.984985)
			(xy 189.254939 -71.999091) (xy 189.199502 -72.005191) (xy 189.143768 -72.003154) (xy 189.088925 -71.993024)
			(xy 189.036141 -71.975017) (xy 188.986541 -71.949516) (xy 188.941183 -71.917065) (xy 188.901034 -71.878356)
			(xy 188.866948 -71.834213) (xy 188.839652 -71.785578) (xy 188.819729 -71.733487) (xy 188.807603 -71.67905)
			(xy 188.803532 -71.623428) (xy 188.051696 -71.623428) (xy 188.049415 -71.638926) (xy 188.033347 -71.692333)
			(xy 188.009675 -71.74283) (xy 187.978902 -71.789343) (xy 187.941685 -71.83088) (xy 187.898817 -71.866555)
			(xy 187.851211 -71.895609) (xy 187.799882 -71.917421) (xy 187.745925 -71.931527) (xy 187.690488 -71.937627)
			(xy 187.634754 -71.93559) (xy 187.579911 -71.92546) (xy 187.527127 -71.907453) (xy 187.477527 -71.881952)
			(xy 187.432169 -71.849501) (xy 187.39202 -71.810792) (xy 187.357934 -71.766649) (xy 187.330638 -71.718014)
			(xy 187.310715 -71.665923) (xy 187.298589 -71.611486) (xy 187.294518 -71.555864) (xy 181.64877 -71.555864)
			(xy 180.800423 -77.539088) (xy 182.075834 -77.539088) (xy 182.079905 -77.483466) (xy 182.092031 -77.429029)
			(xy 182.111954 -77.376938) (xy 182.13925 -77.328303) (xy 182.173336 -77.28416) (xy 182.213485 -77.245451)
			(xy 182.258843 -77.213) (xy 182.308443 -77.187499) (xy 182.361227 -77.169492) (xy 182.41607 -77.159362)
			(xy 182.471804 -77.157325) (xy 182.527241 -77.163425) (xy 182.581198 -77.177531) (xy 182.632527 -77.199343)
			(xy 182.680133 -77.228397) (xy 182.723001 -77.264072) (xy 182.760218 -77.305609) (xy 182.790991 -77.352122)
			(xy 182.814663 -77.402619) (xy 182.830731 -77.456026) (xy 182.838851 -77.511202) (xy 182.83936 -77.539088)
			(xy 182.838851 -77.566974) (xy 182.830731 -77.62215) (xy 182.814663 -77.675557) (xy 182.790991 -77.726054)
			(xy 182.760218 -77.772567) (xy 182.723001 -77.814104) (xy 182.680133 -77.849779) (xy 182.632527 -77.878833)
			(xy 182.581198 -77.900645) (xy 182.527241 -77.914751) (xy 182.471804 -77.920851) (xy 182.41607 -77.918814)
			(xy 182.361227 -77.908684) (xy 182.308443 -77.890677) (xy 182.258843 -77.865176) (xy 182.213485 -77.832725)
			(xy 182.173336 -77.794016) (xy 182.13925 -77.749873) (xy 182.111954 -77.701238) (xy 182.092031 -77.649147)
			(xy 182.079905 -77.59471) (xy 182.075834 -77.539088) (xy 180.800423 -77.539088) (xy 180.669692 -78.461108)
			(xy 178.565302 -93.306392) (xy 178.564339 -93.316238) (xy 178.569054 -93.335434) (xy 178.574446 -93.34373)
			(xy 178.57724 -93.347032) (xy 178.580968 -93.351074) (xy 178.589808 -93.357608) (xy 178.594766 -93.359986)
			(xy 178.604164 -93.364304) (xy 179.253134 -93.364304) (xy 179.264003 -93.363732) (xy 179.283763 -93.354654)
			(xy 179.298037 -93.33825) (xy 179.301648 -93.327982) (xy 179.380896 -92.980256) (xy 179.497228 -92.470732)
			(xy 179.50724 -92.428966) (xy 179.53349 -92.347182) (xy 179.56667 -92.267957) (xy 179.606534 -92.191875)
			(xy 179.652789 -92.1195) (xy 179.678584 -92.08516) (xy 180.650134 -90.819478) (xy 180.66004 -90.806524)
			(xy 180.663884 -90.801267) (xy 180.669033 -90.789309) (xy 180.6702 -90.782902) (xy 180.671978 -90.770202)
			(xy 180.667152 -90.757756) (xy 180.659272 -90.736109) (xy 180.648204 -90.69139) (xy 180.642615 -90.645662)
			(xy 180.64226 -90.622628) (xy 180.64226 -90.621866) (xy 180.642748 -90.594616) (xy 180.650508 -90.54067)
			(xy 180.665866 -90.488377) (xy 180.688509 -90.438802) (xy 180.717975 -90.392954) (xy 180.753666 -90.351765)
			(xy 180.794855 -90.316074) (xy 180.840704 -90.286608) (xy 180.890279 -90.263965) (xy 180.942572 -90.248608)
			(xy 180.996518 -90.240848) (xy 181.023768 -90.240358) (xy 181.033565 -90.240427) (xy 181.053133 -90.241442)
			(xy 181.062884 -90.24239) (xy 181.076092 -90.24366) (xy 181.08803 -90.23858) (xy 181.093927 -90.235827)
			(xy 181.104204 -90.227849) (xy 181.10835 -90.222832) (xy 188.26226 -80.905604) (xy 188.2675 -80.89824)
			(xy 188.272882 -80.881) (xy 188.271902 -80.862966) (xy 188.26861 -80.85455) (xy 188.25083 -80.813656)
			(xy 188.232796 -80.772254) (xy 188.228788 -80.764223) (xy 188.216234 -80.751411) (xy 188.200039 -80.743699)
			(xy 188.19114 -80.742536) (xy 188.163132 -80.739385) (xy 188.108409 -80.725893) (xy 188.056265 -80.7045)
			(xy 188.007836 -80.67567) (xy 187.964173 -80.640031) (xy 187.926227 -80.598357) (xy 187.894823 -80.551556)
			(xy 187.870644 -80.500644) (xy 187.854216 -80.44673) (xy 187.845896 -80.390986) (xy 187.845446 -80.362806)
			(xy 187.845931 -80.335553) (xy 187.853687 -80.281602) (xy 187.869041 -80.229304) (xy 187.891681 -80.179723)
			(xy 187.921147 -80.133869) (xy 187.956837 -80.092674) (xy 187.998027 -80.056978) (xy 188.043878 -80.027506)
			(xy 188.093456 -80.004859) (xy 188.145752 -79.989498) (xy 188.199701 -79.981735) (xy 188.226954 -79.981298)
			(xy 188.255945 -79.981834) (xy 188.31326 -79.990601) (xy 188.368588 -80.00794) (xy 188.420655 -80.033452)
			(xy 188.468262 -80.066548) (xy 188.510313 -80.106468) (xy 188.545839 -80.152291) (xy 188.574022 -80.202962)
			(xy 188.584586 -80.229964) (xy 188.587115 -80.23637) (xy 188.595101 -80.247585) (xy 188.600334 -80.252062)
			(xy 188.605414 -80.256126) (xy 188.617606 -80.26146) (xy 188.712602 -80.275938) (xy 188.721629 -80.276929)
			(xy 188.739398 -80.273233) (xy 188.754778 -80.263597) (xy 188.760608 -80.256634) (xy 200.229978 -65.318894)
			(xy 200.233822 -65.313517) (xy 200.238827 -65.301289) (xy 200.239884 -65.294764) (xy 200.241662 -65.28181)
			(xy 200.236328 -65.26911) (xy 200.227329 -65.246089) (xy 200.214668 -65.198311) (xy 200.208279 -65.149298)
			(xy 200.20788 -65.124584) (xy 200.20788 -65.115948) (xy 200.208908 -65.089077) (xy 200.217583 -65.036008)
			(xy 200.233627 -64.984683) (xy 200.25672 -64.936121) (xy 200.286406 -64.891283) (xy 200.322094 -64.85106)
			(xy 200.363079 -64.816249) (xy 200.408547 -64.787539) (xy 200.457597 -64.7655) (xy 200.509257 -64.750569)
			(xy 200.562501 -64.743042) (xy 200.589388 -64.742568) (xy 200.590404 -64.742568) (xy 200.602438 -64.742673)
			(xy 200.626459 -64.744199) (xy 200.63841 -64.745616) (xy 200.639172 -64.745616) (xy 200.645693 -64.746271)
			(xy 200.658686 -64.744605) (xy 200.664826 -64.742314) (xy 200.67016 -64.740028) (xy 200.680574 -64.732154)
			(xy 201.112882 -64.169036) (xy 201.219562 -64.030098) (xy 201.596244 -63.538862) (xy 201.600308 -63.53302)
			(xy 201.633836 -63.473584) (xy 201.851006 -63.088012) (xy 201.883264 -63.0301) (xy 201.887895 -63.019622)
			(xy 201.888163 -62.996739) (xy 201.883772 -62.986158) (xy 201.880216 -62.978538) (xy 201.873866 -62.972188)
			(xy 201.853689 -62.95069) (xy 201.819535 -62.902634) (xy 201.793182 -62.849895) (xy 201.775257 -62.793729)
			(xy 201.766187 -62.735474) (xy 201.765662 -62.705996) (xy 201.766148 -62.678744) (xy 201.773905 -62.624795)
			(xy 201.78926 -62.572499) (xy 201.811901 -62.522921) (xy 201.841367 -62.477069) (xy 201.877058 -62.435876)
			(xy 201.918248 -62.400182) (xy 201.964098 -62.370713) (xy 202.013675 -62.348069) (xy 202.06597 -62.33271)
			(xy 202.119918 -62.32495) (xy 202.14717 -62.324488) (xy 202.169083 -62.324764) (xy 202.212626 -62.329728)
			(xy 202.234038 -62.334394) (xy 202.244838 -62.336327) (xy 202.266307 -62.331917) (xy 202.284024 -62.319013)
			(xy 202.289918 -62.309756) (xy 202.32497 -62.247526) (xy 202.344782 -62.211966) (xy 202.347481 -62.206754)
			(xy 202.350689 -62.195467) (xy 202.351132 -62.189614) (xy 202.35164 -62.179708) (xy 202.348592 -62.170818)
			(xy 202.340028 -62.143005) (xy 202.330459 -62.085605) (xy 202.329542 -62.056518) (xy 202.329542 -62.051438)
			(xy 202.330037 -62.023716) (xy 202.33806 -61.968856) (xy 202.353943 -61.915737) (xy 202.37735 -61.865477)
			(xy 202.407788 -61.819136) (xy 202.444617 -61.777692) (xy 202.487058 -61.742017) (xy 202.534218 -61.712864)
			(xy 202.585103 -61.690847) (xy 202.611736 -61.683138) (xy 202.61199 -61.683138) (xy 202.614784 -61.682376)
			(xy 202.623606 -61.678987) (xy 202.638201 -61.667007) (xy 202.643232 -61.659008) (xy 202.671426 -61.60262)
			(xy 202.674982 -61.592968) (xy 202.730862 -61.382148) (xy 202.740768 -61.34481) (xy 202.916536 -60.682124)
			(xy 202.91552 -60.672726) (xy 202.913488 -60.634118) (xy 202.913488 -60.632848) (xy 202.914068 -60.60321)
			(xy 202.92327 -60.544653) (xy 202.941413 -60.488222) (xy 202.968061 -60.435274) (xy 202.984862 -60.410852)
			(xy 202.99045 -60.403486) (xy 203.096114 -60.004706) (xy 203.097892 -59.991752) (xy 203.097892 -58.819288)
			(xy 203.097747 -58.81307) (xy 203.094795 -58.800993) (xy 203.09205 -58.795412) (xy 203.081382 -58.7756)
			(xy 203.078538 -58.770574) (xy 203.07097 -58.761854) (xy 203.066396 -58.758328) (xy 203.044553 -58.741871)
			(xy 203.005357 -58.70373) (xy 202.972006 -58.660386) (xy 202.945184 -58.612725) (xy 202.925439 -58.561723)
			(xy 202.913176 -58.508426) (xy 202.91044 -58.481214) (xy 202.910186 -58.478674) (xy 202.909202 -58.46319)
			(xy 202.909457 -58.432163) (xy 202.910694 -58.416698) (xy 202.911964 -58.405014) (xy 202.915593 -58.37836)
			(xy 202.929377 -58.326363) (xy 202.950329 -58.276819) (xy 202.978032 -58.230709) (xy 203.011939 -58.188947)
			(xy 203.031344 -58.170318) (xy 203.031852 -58.16981) (xy 203.032106 -58.169556) (xy 203.036129 -58.165527)
			(xy 203.042412 -58.156036) (xy 203.044552 -58.15076) (xy 203.046584 -58.145426) (xy 203.048362 -58.133742)
			(xy 202.75931 -55.372762) (xy 202.677776 -54.592474) (xy 202.677023 -54.586971) (xy 202.673431 -54.576463)
			(xy 202.670664 -54.571646) (xy 202.667723 -54.56696) (xy 202.660163 -54.558884) (xy 202.655678 -54.555644)
			(xy 202.655424 -54.555644) (xy 202.633498 -54.540388) (xy 202.593733 -54.504726) (xy 202.55933 -54.463866)
			(xy 202.530961 -54.418608) (xy 202.509181 -54.369836) (xy 202.494414 -54.318503) (xy 202.486951 -54.265613)
			(xy 202.486514 -54.238906) (xy 202.486592 -54.226168) (xy 202.488245 -54.200747) (xy 202.489816 -54.188106)
			(xy 202.494452 -54.158019) (xy 202.512036 -54.099742) (xy 202.538669 -54.045005) (xy 202.573671 -53.995203)
			(xy 202.594464 -53.972968) (xy 202.598528 -53.968904) (xy 202.604116 -53.959506) (xy 202.606148 -53.954172)
			(xy 202.60785 -53.948887) (xy 202.609139 -53.937862) (xy 202.608688 -53.932328) (xy 202.603354 -53.881528)
			(xy 202.450192 -52.416964) (xy 202.37958 -51.742086) (xy 202.377415 -51.731469) (xy 202.365559 -51.713358)
			(xy 202.347291 -51.701744) (xy 202.336654 -51.699668) (xy 202.334622 -51.699414) (xy 202.306074 -51.695731)
			(xy 202.25046 -51.680887) (xy 202.197705 -51.657863) (xy 202.149004 -51.627182) (xy 202.105459 -51.589539)
			(xy 202.068058 -51.545785) (xy 202.052428 -51.521614) (xy 202.051412 -51.520344) (xy 202.044676 -51.51134)
			(xy 202.025436 -51.49975) (xy 202.014328 -51.497992) (xy 201.974704 -51.493928) (xy 201.974196 -51.493928)
			(xy 201.950574 -51.491388) (xy 201.950066 -51.491388) (xy 201.934318 -51.489864) (xy 201.922688 -51.489278)
			(xy 201.900874 -51.49736) (xy 201.892408 -51.505358) (xy 201.892154 -51.505612) (xy 201.874059 -51.524176)
			(xy 201.833721 -51.556741) (xy 201.789347 -51.583546) (xy 201.741753 -51.604098) (xy 201.691815 -51.61802)
			(xy 201.640453 -51.625054) (xy 201.614532 -51.6255) (xy 201.587278 -51.625039) (xy 201.533324 -51.617286)
			(xy 201.481023 -51.601932) (xy 201.431439 -51.579291) (xy 201.385582 -51.549824) (xy 201.344387 -51.51413)
			(xy 201.30869 -51.472937) (xy 201.27922 -51.427082) (xy 201.256576 -51.3775) (xy 201.24122 -51.3252)
			(xy 201.233463 -51.271246) (xy 201.233024 -51.243992) (xy 201.233449 -51.218481) (xy 201.240245 -51.167913)
			(xy 201.253713 -51.1187) (xy 201.273615 -51.07172) (xy 201.299596 -51.027808) (xy 201.315066 -51.007518)
			(xy 201.317606 -51.00447) (xy 201.318622 -51.002946) (xy 201.321924 -50.996342) (xy 201.324267 -50.991119)
			(xy 201.326833 -50.979966) (xy 201.327004 -50.974244) (xy 201.327004 -50.94224) (xy 201.33818 -50.94224)
			(xy 201.33818 -50.89144) (xy 201.337845 -50.882836) (xy 201.332133 -50.866606) (xy 201.327004 -50.85969)
			(xy 201.325734 -50.858166) (xy 201.308341 -50.837289) (xy 201.279025 -50.791538) (xy 201.256498 -50.74209)
			(xy 201.241218 -50.689946) (xy 201.233493 -50.636161) (xy 201.233024 -50.608992) (xy 201.233488 -50.58174)
			(xy 201.241246 -50.527792) (xy 201.256603 -50.475497) (xy 201.279246 -50.42592) (xy 201.308715 -50.38007)
			(xy 201.344409 -50.338881) (xy 201.385602 -50.303191) (xy 201.431455 -50.273727) (xy 201.481034 -50.251089)
			(xy 201.533331 -50.235737) (xy 201.58728 -50.227985) (xy 201.614532 -50.227484) (xy 201.642572 -50.227982)
			(xy 201.698048 -50.236199) (xy 201.751722 -50.25245) (xy 201.802438 -50.276386) (xy 201.849103 -50.30749)
			(xy 201.89071 -50.345092) (xy 201.908918 -50.366422) (xy 201.909172 -50.366676) (xy 201.91603 -50.374804)
			(xy 201.939652 -50.386488) (xy 201.946002 -50.389536) (xy 201.950894 -50.39161) (xy 201.961266 -50.393905)
			(xy 201.966576 -50.394108) (xy 202.024234 -50.394108) (xy 202.034648 -50.393092) (xy 202.046332 -50.389028)
			(xy 202.065636 -50.379376) (xy 202.069815 -50.377215) (xy 202.077349 -50.371581) (xy 202.080622 -50.3682)
			(xy 202.082146 -50.366168) (xy 202.09664 -50.349113) (xy 202.12898 -50.318168) (xy 202.146662 -50.304446)
			(xy 202.158082 -50.295986) (xy 202.181984 -50.280604) (xy 202.194414 -50.273712) (xy 202.202796 -50.269394)
			(xy 202.207876 -50.2666) (xy 202.214988 -50.25263) (xy 202.218211 -50.245932) (xy 202.221039 -50.231347)
			(xy 202.220576 -50.223928) (xy 202.195938 -49.98847) (xy 202.193978 -49.976037) (xy 202.179854 -49.955241)
			(xy 202.169014 -49.948846) (xy 202.131676 -49.929288) (xy 202.093322 -49.908968) (xy 202.082058 -49.903966)
			(xy 202.057441 -49.904386) (xy 202.046332 -49.90973) (xy 202.018175 -49.924336) (xy 201.958221 -49.945036)
			(xy 201.895673 -49.95556) (xy 201.86396 -49.956212) (xy 201.838449 -49.955785) (xy 201.787883 -49.948986)
			(xy 201.738672 -49.935515) (xy 201.691693 -49.915612) (xy 201.647782 -49.889631) (xy 201.627486 -49.87417)
			(xy 201.624438 -49.87163) (xy 201.622914 -49.870614) (xy 201.61631 -49.867312) (xy 201.611087 -49.86497)
			(xy 201.599933 -49.86241) (xy 201.594212 -49.862232) (xy 201.562208 -49.862232) (xy 201.562208 -49.851056)
			(xy 201.511408 -49.851056) (xy 201.502807 -49.851396) (xy 201.486585 -49.85712) (xy 201.479658 -49.862232)
			(xy 201.478134 -49.863502) (xy 201.457257 -49.880896) (xy 201.411508 -49.910213) (xy 201.36206 -49.932739)
			(xy 201.309914 -49.948018) (xy 201.256129 -49.95574) (xy 201.22896 -49.956212) (xy 201.203449 -49.955785)
			(xy 201.152883 -49.948986) (xy 201.103672 -49.935515) (xy 201.056693 -49.915612) (xy 201.012782 -49.889631)
			(xy 200.992486 -49.87417) (xy 200.989438 -49.87163) (xy 200.987914 -49.870614) (xy 200.98131 -49.867312)
			(xy 200.976087 -49.86497) (xy 200.964933 -49.86241) (xy 200.959212 -49.862232) (xy 200.927208 -49.862232)
			(xy 200.927208 -49.851056) (xy 200.876408 -49.851056) (xy 200.867807 -49.851396) (xy 200.851585 -49.85712)
			(xy 200.844658 -49.862232) (xy 200.843134 -49.863502) (xy 200.822257 -49.880896) (xy 200.776508 -49.910213)
			(xy 200.72706 -49.932739) (xy 200.674914 -49.948018) (xy 200.621129 -49.95574) (xy 200.59396 -49.956212)
			(xy 200.56671 -49.955723) (xy 200.512766 -49.947962) (xy 200.460476 -49.932604) (xy 200.410903 -49.90996)
			(xy 200.365057 -49.880492) (xy 200.323871 -49.8448) (xy 200.288184 -49.803611) (xy 200.258721 -49.757762)
			(xy 200.236082 -49.708187) (xy 200.220729 -49.655894) (xy 200.212974 -49.60195) (xy 200.212974 -49.54745)
			(xy 200.220729 -49.493506) (xy 200.236082 -49.441213) (xy 200.258721 -49.391638) (xy 200.288184 -49.345789)
			(xy 200.323871 -49.3046) (xy 200.365057 -49.268908) (xy 200.410903 -49.23944) (xy 200.460476 -49.216796)
			(xy 200.512766 -49.201438) (xy 200.56671 -49.193677) (xy 200.59396 -49.193196) (xy 200.61947 -49.193625)
			(xy 200.670035 -49.200426) (xy 200.719244 -49.213899) (xy 200.766222 -49.233804) (xy 200.81013 -49.259788)
			(xy 200.830434 -49.275238) (xy 200.833482 -49.277778) (xy 200.835006 -49.278794) (xy 200.84161 -49.282096)
			(xy 200.846834 -49.284435) (xy 200.857987 -49.286991) (xy 200.863708 -49.287176) (xy 200.895712 -49.287176)
			(xy 200.895712 -49.298352) (xy 200.946512 -49.298352) (xy 200.955118 -49.298025) (xy 200.971357 -49.292322)
			(xy 200.978262 -49.287176) (xy 200.979786 -49.285906) (xy 201.000663 -49.268513) (xy 201.046413 -49.239198)
			(xy 201.095861 -49.216674) (xy 201.148006 -49.201397) (xy 201.201792 -49.193678) (xy 201.22896 -49.193196)
			(xy 201.25447 -49.193625) (xy 201.305035 -49.200426) (xy 201.354244 -49.213899) (xy 201.401222 -49.233804)
			(xy 201.44513 -49.259788) (xy 201.465434 -49.275238) (xy 201.468482 -49.277778) (xy 201.470006 -49.278794)
			(xy 201.47661 -49.282096) (xy 201.481834 -49.284435) (xy 201.492987 -49.286991) (xy 201.498708 -49.287176)
			(xy 201.530712 -49.287176) (xy 201.530712 -49.298352) (xy 201.581512 -49.298352) (xy 201.590118 -49.298025)
			(xy 201.606357 -49.292322) (xy 201.613262 -49.287176) (xy 201.614786 -49.285906) (xy 201.622152 -49.279302)
			(xy 201.623168 -49.278794) (xy 201.624438 -49.277778) (xy 201.624946 -49.27727) (xy 201.647044 -49.26076)
			(xy 201.647298 -49.260506) (xy 201.647806 -49.260252) (xy 201.670666 -49.24552) (xy 201.671682 -49.245012)
			(xy 201.68235 -49.23917) (xy 201.689462 -49.235106) (xy 201.695812 -49.226216) (xy 201.699038 -49.221377)
			(xy 201.703413 -49.210603) (xy 201.704448 -49.20488) (xy 201.715878 -49.134522) (xy 201.716475 -49.123978)
			(xy 201.710054 -49.103885) (xy 201.703432 -49.09566) (xy 195.877942 -42.736516) (xy 195.870752 -42.729955)
			(xy 195.852852 -42.722351) (xy 195.833407 -42.721991) (xy 195.815238 -42.728925) (xy 195.807838 -42.735246)
			(xy 195.804282 -42.738548) (xy 195.798186 -42.744136) (xy 195.789804 -42.768012) (xy 195.791836 -42.780712)
			(xy 195.79402 -42.79522) (xy 195.796436 -42.824462) (xy 195.796662 -42.839132) (xy 195.796662 -42.84091)
			(xy 195.796175 -42.868157) (xy 195.788419 -42.922096) (xy 195.773065 -42.974383) (xy 195.750427 -43.023952)
			(xy 195.720965 -43.069795) (xy 195.685278 -43.110979) (xy 195.644094 -43.146665) (xy 195.598251 -43.176127)
			(xy 195.548682 -43.198765) (xy 195.496395 -43.214119) (xy 195.442456 -43.221875) (xy 195.387962 -43.221877)
			(xy 195.334022 -43.214123) (xy 195.281735 -43.198772) (xy 195.232164 -43.176136) (xy 195.18632 -43.146676)
			(xy 195.145134 -43.110991) (xy 195.109446 -43.069809) (xy 195.079982 -43.023967) (xy 195.057341 -42.974399)
			(xy 195.041985 -42.922113) (xy 195.034226 -42.868174) (xy 195.034222 -42.81368) (xy 195.041973 -42.75974)
			(xy 195.057322 -42.707452) (xy 195.079955 -42.657881) (xy 195.109413 -42.612035) (xy 195.145095 -42.570847)
			(xy 195.186276 -42.535157) (xy 195.232116 -42.505691) (xy 195.281683 -42.483048) (xy 195.333968 -42.467689)
			(xy 195.387907 -42.459927) (xy 195.415154 -42.459402) (xy 195.438248 -42.459753) (xy 195.484096 -42.465354)
			(xy 195.506594 -42.470578) (xy 195.514214 -42.472356) (xy 195.5292 -42.471594) (xy 195.54317 -42.466514)
			(xy 195.555108 -42.45737) (xy 195.557648 -42.453814) (xy 195.597526 -42.39895) (xy 195.603113 -42.390617)
			(xy 195.607836 -42.371134) (xy 195.604681 -42.351336) (xy 195.599812 -42.342562) (xy 195.25996 -41.787064)
			(xy 194.999102 -41.360344) (xy 194.99653 -41.356346) (xy 194.990143 -41.349306) (xy 194.986402 -41.346374)
			(xy 194.979036 -41.340786) (xy 194.96913 -41.337992) (xy 194.943064 -41.329899) (xy 194.893386 -41.307298)
			(xy 194.847435 -41.277848) (xy 194.806151 -41.24215) (xy 194.770376 -41.200932) (xy 194.740841 -41.155036)
			(xy 194.718148 -41.1054) (xy 194.70276 -41.053036) (xy 194.694993 -40.999013) (xy 194.694556 -40.971724)
			(xy 194.694556 -40.969692) (xy 194.694831 -40.951928) (xy 194.698262 -40.916564) (xy 194.701414 -40.89908)
			(xy 194.701922 -40.896032) (xy 194.703192 -40.889936) (xy 194.701668 -40.881046) (xy 194.700695 -40.876409)
			(xy 194.697245 -40.867584) (xy 194.69481 -40.86352) (xy 194.397122 -40.37711) (xy 194.393745 -40.371994)
			(xy 194.385017 -40.363391) (xy 194.37985 -40.360092) (xy 194.369182 -40.353742) (xy 194.362324 -40.353234)
			(xy 194.356482 -40.35298) (xy 194.327967 -40.350874) (xy 194.271994 -40.339198) (xy 194.218391 -40.319301)
			(xy 194.168356 -40.291629) (xy 194.123011 -40.256801) (xy 194.083369 -40.215597) (xy 194.050319 -40.16894)
			(xy 194.0246 -40.117873) (xy 194.006789 -40.063541) (xy 193.997283 -40.00716) (xy 193.99631 -39.978584)
			(xy 193.99631 -39.971472) (xy 193.996745 -39.946615) (xy 194.003269 -39.89733) (xy 194.016139 -39.849309)
			(xy 194.025266 -39.826184) (xy 194.029076 -39.816786) (xy 194.031616 -39.811452) (xy 194.033648 -39.79926)
			(xy 194.033394 -39.793418) (xy 194.032748 -39.787443) (xy 194.029026 -39.77602) (xy 194.026028 -39.770812)
			(xy 193.668142 -39.186104) (xy 193.659506 -39.180008) (xy 193.621248 -39.152731) (xy 193.549495 -39.092058)
			(xy 193.483755 -39.024917) (xy 193.453766 -38.988746) (xy 193.453258 -38.988238) (xy 193.449956 -38.984174)
			(xy 193.44132 -38.977316) (xy 193.417444 -38.965886) (xy 193.412118 -38.963427) (xy 193.400702 -38.960738)
			(xy 193.394838 -38.960552) (xy 193.326512 -38.961314) (xy 193.320566 -38.961502) (xy 193.309012 -38.964323)
			(xy 193.303652 -38.966902) (xy 193.303398 -38.966902) (xy 193.29848 -38.969661) (xy 193.289894 -38.976969)
			(xy 193.28638 -38.98138) (xy 193.286126 -38.981634) (xy 193.270322 -39.001755) (xy 193.234203 -39.037993)
			(xy 193.193566 -39.069079) (xy 193.149139 -39.094457) (xy 193.101719 -39.113669) (xy 193.052157 -39.126373)
			(xy 193.026792 -39.129716) (xy 193.018156 -39.130732) (xy 192.982088 -39.132256) (xy 192.954604 -39.131777)
			(xy 192.900205 -39.123896) (xy 192.847498 -39.108299) (xy 192.79757 -39.085307) (xy 192.751454 -39.055396)
			(xy 192.710102 -39.019183) (xy 192.674368 -38.977416) (xy 192.659254 -38.954456) (xy 192.659254 -38.954202)
			(xy 192.656714 -38.950138) (xy 192.655952 -38.949122) (xy 192.651888 -38.945058) (xy 192.642998 -38.938454)
			(xy 192.62344 -38.926262) (xy 192.618112 -38.923226) (xy 192.606428 -38.91951) (xy 192.600326 -38.918896)
			(xy 192.529714 -38.914324) (xy 192.51887 -38.914102) (xy 192.498585 -38.921721) (xy 192.490598 -38.929056)
			(xy 192.486788 -38.932866) (xy 192.48501 -38.935152) (xy 192.484248 -38.936168) (xy 192.466249 -38.958589)
			(xy 192.424648 -38.998275) (xy 192.377563 -39.031268) (xy 192.32606 -39.056822) (xy 192.271306 -39.074357)
			(xy 192.214539 -39.083477) (xy 192.185798 -39.08425) (xy 192.181988 -39.08425) (xy 192.154734 -39.083763)
			(xy 192.100782 -39.076005) (xy 192.048483 -39.060647) (xy 191.998902 -39.038002) (xy 191.953048 -39.008533)
			(xy 191.911854 -38.972837) (xy 191.87616 -38.931643) (xy 191.846692 -38.885788) (xy 191.824049 -38.836206)
			(xy 191.808693 -38.783906) (xy 191.800936 -38.729954) (xy 191.800936 -38.675446) (xy 191.808693 -38.621494)
			(xy 191.824049 -38.569194) (xy 191.846692 -38.519612) (xy 191.87616 -38.473757) (xy 191.911854 -38.432563)
			(xy 191.953048 -38.396867) (xy 191.998902 -38.367398) (xy 192.048483 -38.344753) (xy 192.100782 -38.329395)
			(xy 192.154734 -38.321637) (xy 192.181988 -38.321234) (xy 192.209472 -38.321711) (xy 192.263874 -38.329589)
			(xy 192.316584 -38.345184) (xy 192.366515 -38.368173) (xy 192.412634 -38.398083) (xy 192.45399 -38.434295)
			(xy 192.489728 -38.47606) (xy 192.504822 -38.499034) (xy 192.504822 -38.499288) (xy 192.507362 -38.503352)
			(xy 192.508124 -38.504368) (xy 192.512188 -38.508432) (xy 192.521078 -38.515036) (xy 192.540636 -38.527228)
			(xy 192.546013 -38.530312) (xy 192.55783 -38.534044) (xy 192.564004 -38.534594) (xy 192.63487 -38.539166)
			(xy 192.638172 -38.539166) (xy 192.678558 -38.5191) (xy 192.68059 -38.51656) (xy 192.688354 -38.506685)
			(xy 192.705001 -38.48787) (xy 192.713864 -38.478968) (xy 192.734347 -38.459463) (xy 192.780017 -38.4261)
			(xy 192.830113 -38.399846) (xy 192.883536 -38.381277) (xy 192.939116 -38.370799) (xy 192.967356 -38.36924)
			(xy 192.979294 -38.368732) (xy 193.000122 -38.357302) (xy 193.00444 -38.351206) (xy 193.026538 -38.319202)
			(xy 193.030127 -38.313121) (xy 193.034138 -38.299587) (xy 193.034412 -38.292532) (xy 193.031364 -38.275514)
			(xy 193.02984 -38.27145) (xy 193.020899 -38.245609) (xy 193.005521 -38.193129) (xy 192.999106 -38.166548)
			(xy 192.997328 -38.158674) (xy 192.98031 -38.130988) (xy 192.974214 -38.125654) (xy 192.941194 -38.096444)
			(xy 192.908073 -38.065096) (xy 192.847068 -37.997302) (xy 192.792494 -37.92423) (xy 192.76822 -37.885624)
			(xy 192.509394 -37.462968) (xy 192.493529 -37.436649) (xy 192.464679 -37.382382) (xy 192.451736 -37.35451)
			(xy 192.43548 -37.31641) (xy 192.433956 -37.3126) (xy 192.34531 -37.168328) (xy 192.323778 -37.132477)
			(xy 192.286137 -37.05779) (xy 192.254934 -36.980193) (xy 192.23039 -36.90024) (xy 192.221104 -36.859464)
			(xy 192.212468 -36.814252) (xy 192.210944 -36.8046) (xy 192.184274 -36.760912) (xy 192.176908 -36.755324)
			(xy 192.156769 -36.739192) (xy 192.120603 -36.702386) (xy 192.08974 -36.661033) (xy 192.064743 -36.615891)
			(xy 192.054988 -36.592002) (xy 192.051178 -36.582096) (xy 191.616076 -36.143438) (xy 191.608831 -36.137531)
			(xy 191.591379 -36.130878) (xy 191.58204 -36.130484) (xy 191.577722 -36.130484) (xy 191.56776 -36.130972)
			(xy 191.549338 -36.138561) (xy 191.541908 -36.145216) (xy 191.541654 -36.14547) (xy 191.520029 -36.166449)
			(xy 191.471395 -36.202006) (xy 191.417777 -36.229481) (xy 191.360509 -36.248191) (xy 191.301013 -36.25767)
			(xy 191.27089 -36.258246) (xy 191.258152 -36.258167) (xy 191.232731 -36.256513) (xy 191.22009 -36.254944)
			(xy 191.192411 -36.250729) (xy 191.138609 -36.235244) (xy 191.087647 -36.212063) (xy 191.040619 -36.181683)
			(xy 190.998536 -36.144757) (xy 190.962301 -36.102077) (xy 190.932693 -36.054561) (xy 190.910346 -36.003227)
			(xy 190.895741 -35.949179) (xy 190.891922 -35.921442) (xy 190.890144 -35.906202) (xy 190.889128 -35.876738)
			(xy 190.889763 -35.845715) (xy 190.899852 -35.784494) (xy 190.919706 -35.725709) (xy 190.948802 -35.670908)
			(xy 190.967106 -35.645852) (xy 190.968122 -35.644582) (xy 190.971678 -35.639248) (xy 190.974818 -35.63337)
			(xy 190.978288 -35.620508) (xy 190.978536 -35.613848) (xy 190.976758 -35.57905) (xy 190.975696 -35.57072)
			(xy 190.968803 -35.555419) (xy 190.963296 -35.549078) (xy 190.9318 -35.517074) (xy 190.931292 -35.516566)
			(xy 190.777876 -35.363404) (xy 190.740538 -35.32378) (xy 190.738506 -35.321494) (xy 190.732156 -35.314382)
			(xy 190.723774 -35.310064) (xy 190.719347 -35.307876) (xy 190.709881 -35.305072) (xy 190.704978 -35.304476)
			(xy 190.68796 -35.302952) (xy 190.683409 -35.30269) (xy 190.674338 -35.303585) (xy 190.669926 -35.30473)
			(xy 190.66129 -35.307016) (xy 190.653162 -35.313366) (xy 190.615883 -35.341183) (xy 190.537038 -35.390542)
			(xy 190.453941 -35.432349) (xy 190.367313 -35.46624) (xy 190.277907 -35.49192) (xy 190.186499 -35.509168)
			(xy 190.093882 -35.517832) (xy 190.047372 -35.518344) (xy 190.024512 -35.51809) (xy 190.02375 -35.51809)
			(xy 189.977599 -35.516465) (xy 189.885873 -35.505726) (xy 189.795533 -35.486551) (xy 189.707353 -35.459102)
			(xy 189.62209 -35.423617) (xy 189.540474 -35.380398) (xy 189.463205 -35.329816) (xy 189.390945 -35.272305)
			(xy 189.357254 -35.240722) (xy 189.326151 -35.210266) (xy 189.2688 -35.144768) (xy 189.217381 -35.074518)
			(xy 189.19444 -35.037522) (xy 189.1919 -35.033712) (xy 189.181486 -35.021774) (xy 189.179962 -35.020504)
			(xy 189.157337 -35.002319) (xy 189.117333 -34.960262) (xy 189.084161 -34.912631) (xy 189.058586 -34.860525)
			(xy 189.041198 -34.805147) (xy 189.032398 -34.747774) (xy 189.03188 -34.718752) (xy 189.03188 -34.718498)
			(xy 189.032343 -34.689997) (xy 189.040761 -34.633623) (xy 189.048644 -34.60623) (xy 189.050168 -34.599118)
			(xy 189.051946 -34.588196) (xy 189.051946 -34.58464) (xy 189.051692 -34.581846) (xy 189.051184 -34.567622)
			(xy 189.051184 -34.566606) (xy 189.050168 -34.520886) (xy 189.050603 -34.4783) (xy 189.057844 -34.393435)
			(xy 189.072298 -34.309498) (xy 189.093858 -34.227099) (xy 189.122369 -34.14684) (xy 189.139576 -34.107882)
			(xy 189.142754 -34.098749) (xy 189.14275 -34.079426) (xy 189.139576 -34.07029) (xy 189.122367 -34.031334)
			(xy 189.093874 -33.95107) (xy 189.072322 -33.86867) (xy 189.05787 -33.784734) (xy 189.050623 -33.699872)
			(xy 189.050168 -33.657286) (xy 189.051946 -33.595818) (xy 189.052708 -33.583626) (xy 189.050676 -33.578038)
			(xy 189.044326 -33.565846) (xy 189.040262 -33.560258) (xy 189.017402 -33.536128) (xy 189.01022 -33.529914)
			(xy 188.992599 -33.522864) (xy 188.983112 -33.522412) (xy 188.60135 -33.522412) (xy 188.555723 -33.521854)
			(xy 188.464857 -33.513426) (xy 188.375141 -33.496738) (xy 188.331094 -33.48482) (xy 188.29317 -33.473752)
			(xy 188.219042 -33.446414) (xy 188.183012 -33.43021) (xy 188.172852 -33.425638) (xy 188.162692 -33.420812)
			(xy 188.129672 -33.420812) (xy 188.12004 -33.421281) (xy 188.102162 -33.428466) (xy 188.094874 -33.434782)
			(xy 188.064016 -33.463685) (xy 187.998188 -33.516752) (xy 187.928103 -33.564053) (xy 187.854263 -33.605249)
			(xy 187.7772 -33.640044) (xy 187.697467 -33.668188) (xy 187.615637 -33.689479) (xy 187.532298 -33.703763)
			(xy 187.448049 -33.710938) (xy 187.405772 -33.711388) (xy 187.405518 -33.711388) (xy 187.405518 -33.711642)
			(xy 187.405264 -33.711642) (xy 187.358782 -33.71111) (xy 187.266222 -33.702462) (xy 187.174869 -33.685236)
			(xy 187.085516 -33.659581) (xy 186.998939 -33.62572) (xy 186.91589 -33.583946) (xy 186.837091 -33.534624)
			(xy 186.763224 -33.47818) (xy 186.694933 -33.415105) (xy 186.632809 -33.345947) (xy 186.577393 -33.271307)
			(xy 186.55284 -33.231836) (xy 186.5503 -33.227772) (xy 186.537854 -33.214056) (xy 186.534552 -33.211516)
			(xy 186.512351 -33.193282) (xy 186.47315 -33.151288) (xy 186.440671 -33.103903) (xy 186.415647 -33.052192)
			(xy 186.398639 -32.997319) (xy 186.390031 -32.94052) (xy 186.389518 -32.911796) (xy 186.391042 -32.879284)
			(xy 186.392312 -32.867092) (xy 186.39452 -32.849945) (xy 186.401647 -32.816112) (xy 186.406536 -32.799528)
			(xy 186.40806 -32.792416) (xy 186.409838 -32.781494) (xy 186.409838 -32.777938) (xy 186.409584 -32.775144)
			(xy 186.409076 -32.76092) (xy 186.409076 -32.759904) (xy 186.40806 -32.714184) (xy 186.408495 -32.671598)
			(xy 186.415736 -32.586733) (xy 186.43019 -32.502796) (xy 186.45175 -32.420397) (xy 186.480261 -32.340138)
			(xy 186.497468 -32.30118) (xy 186.500646 -32.292047) (xy 186.50064 -32.272724) (xy 186.497468 -32.263588)
			(xy 186.48026 -32.224632) (xy 186.451766 -32.144368) (xy 186.430215 -32.061968) (xy 186.415764 -31.978032)
			(xy 186.408516 -31.89317) (xy 186.40806 -31.850584) (xy 186.409076 -31.804864) (xy 186.409076 -31.803848)
			(xy 186.409584 -31.789624) (xy 186.409838 -31.78683) (xy 186.409838 -31.783274) (xy 186.40806 -31.772352)
			(xy 186.406536 -31.76524) (xy 186.3979 -31.731712) (xy 186.392312 -31.697676) (xy 186.391042 -31.685484)
			(xy 186.389518 -31.652972) (xy 186.390064 -31.62392) (xy 186.398875 -31.566488) (xy 186.416289 -31.511055)
			(xy 186.441904 -31.458902) (xy 186.475127 -31.411234) (xy 186.515192 -31.369152) (xy 186.537854 -31.350966)
			(xy 186.541516 -31.348005) (xy 186.547776 -31.340972) (xy 186.5503 -31.336996) (xy 186.551316 -31.335218)
			(xy 186.55284 -31.332932) (xy 186.577416 -31.293483) (xy 186.632841 -31.218865) (xy 186.69497 -31.14973)
			(xy 186.763266 -31.086679) (xy 186.837134 -31.030259) (xy 186.915933 -30.980959) (xy 186.998979 -30.939209)
			(xy 187.08555 -30.90537) (xy 187.174896 -30.879737) (xy 187.26624 -30.862532) (xy 187.358789 -30.853904)
			(xy 187.405264 -30.85338) (xy 187.405518 -30.85338) (xy 187.447969 -30.853818) (xy 187.532564 -30.861031)
			(xy 187.616239 -30.875412) (xy 187.698387 -30.896856) (xy 187.778415 -30.925209) (xy 187.855742 -30.960264)
			(xy 187.929808 -31.001768) (xy 188.000076 -31.04942) (xy 188.066037 -31.102875) (xy 188.096906 -31.132018)
			(xy 188.103652 -31.137272) (xy 188.119618 -31.14336) (xy 188.128148 -31.143956) (xy 188.976762 -31.143956)
			(xy 188.983112 -31.143448) (xy 188.99161 -31.142076) (xy 189.007032 -31.134454) (xy 189.019052 -31.122147)
			(xy 189.02299 -31.114492) (xy 189.032642 -31.091124) (xy 189.033404 -31.083504) (xy 189.033658 -31.081218)
			(xy 189.033658 -31.080456) (xy 189.035942 -31.060694) (xy 189.044088 -31.021753) (xy 189.049914 -31.002732)
			(xy 189.051168 -30.998274) (xy 189.052188 -30.989069) (xy 189.051946 -30.984444) (xy 189.051946 -30.983936)
			(xy 189.05106 -30.96814) (xy 189.05017 -30.936511) (xy 189.050168 -30.92069) (xy 189.050603 -30.878103)
			(xy 189.057844 -30.793239) (xy 189.072297 -30.709301) (xy 189.093857 -30.626903) (xy 189.122368 -30.546643)
			(xy 189.139576 -30.507686) (xy 189.142755 -30.498553) (xy 189.142752 -30.479229) (xy 189.139576 -30.470094)
			(xy 189.122367 -30.431138) (xy 189.093873 -30.350874) (xy 189.072322 -30.268474) (xy 189.057869 -30.184538)
			(xy 189.050622 -30.099676) (xy 189.050168 -30.05709) (xy 189.050422 -30.030166) (xy 189.050422 -30.029912)
			(xy 189.050244 -30.020569) (xy 189.044 -30.002972) (xy 189.03823 -29.995622) (xy 188.991748 -29.948124)
			(xy 188.984575 -29.942073) (xy 188.967089 -29.935294) (xy 188.957712 -29.934916) (xy 188.945774 -29.934916)
			(xy 188.899052 -29.934341) (xy 188.806032 -29.925458) (xy 188.714265 -29.907829) (xy 188.624574 -29.881614)
			(xy 188.53776 -29.847045) (xy 188.49594 -29.826204) (xy 188.490513 -29.823622) (xy 188.478833 -29.820802)
			(xy 188.472826 -29.820616) (xy 188.139324 -29.820616) (xy 188.134434 -29.820755) (xy 188.124843 -29.822678)
			(xy 188.120274 -29.824426) (xy 188.094874 -29.834586) (xy 188.09462 -29.83484) (xy 188.09335 -29.83611)
			(xy 188.088016 -29.84119) (xy 188.053453 -29.872924) (xy 187.979332 -29.930468) (xy 187.900133 -29.980795)
			(xy 187.816557 -30.023461) (xy 187.729344 -30.058089) (xy 187.639263 -30.084372) (xy 187.547112 -30.102077)
			(xy 187.453705 -30.111049) (xy 187.406788 -30.1117) (xy 187.405264 -30.1117) (xy 187.358736 -30.111148)
			(xy 187.266088 -30.10245) (xy 187.174653 -30.085161) (xy 187.085225 -30.059431) (xy 186.998582 -30.025484)
			(xy 186.915478 -29.983615) (xy 186.836634 -29.934188) (xy 186.762737 -29.877632) (xy 186.694428 -29.81444)
			(xy 186.632301 -29.745161) (xy 186.576897 -29.670396) (xy 186.552332 -29.630878) (xy 186.549792 -29.627068)
			(xy 186.539378 -29.61513) (xy 186.537854 -29.61386) (xy 186.515232 -29.595674) (xy 186.475234 -29.553615)
			(xy 186.442067 -29.505983) (xy 186.416499 -29.453878) (xy 186.399117 -29.3985) (xy 186.390325 -29.341129)
			(xy 186.389772 -29.312108) (xy 186.389772 -29.311854) (xy 186.390239 -29.283354) (xy 186.398662 -29.226981)
			(xy 186.406536 -29.199586) (xy 186.40806 -29.192474) (xy 186.409838 -29.181552) (xy 186.409838 -29.177996)
			(xy 186.409584 -29.175202) (xy 186.409076 -29.160978) (xy 186.409076 -29.159962) (xy 186.40806 -29.114242)
			(xy 186.408493 -29.071655) (xy 186.415729 -28.986789) (xy 186.430178 -28.90285) (xy 186.451734 -28.820449)
			(xy 186.480241 -28.740188) (xy 186.497468 -28.701238) (xy 186.500657 -28.692104) (xy 186.500672 -28.672773)
			(xy 186.497468 -28.663646) (xy 186.480257 -28.62469) (xy 186.451759 -28.544427) (xy 186.430204 -28.462027)
			(xy 186.415747 -28.378091) (xy 186.408495 -28.293228) (xy 186.40806 -28.250642) (xy 186.409076 -28.204922)
			(xy 186.409076 -28.203906) (xy 186.409584 -28.189682) (xy 186.409838 -28.186888) (xy 186.409838 -28.183332)
			(xy 186.40806 -28.17241) (xy 186.406536 -28.165298) (xy 186.3979 -28.13177) (xy 186.392312 -28.097734)
			(xy 186.391042 -28.085542) (xy 186.389518 -28.05303) (xy 186.390034 -28.024324) (xy 186.398631 -27.967559)
			(xy 186.415634 -27.912722) (xy 186.440661 -27.861052) (xy 186.473147 -27.813714) (xy 186.512358 -27.771778)
			(xy 186.534552 -27.753564) (xy 186.540394 -27.747976) (xy 186.5503 -27.737054) (xy 186.55284 -27.732736)
			(xy 186.577426 -27.693295) (xy 186.632867 -27.618693) (xy 186.695006 -27.549571) (xy 186.763306 -27.486529)
			(xy 186.837175 -27.430114) (xy 186.91597 -27.380815) (xy 186.99901 -27.33906) (xy 187.085574 -27.305209)
			(xy 187.174912 -27.279558) (xy 187.266248 -27.262329) (xy 187.358791 -27.25367) (xy 187.405264 -27.253184)
			(xy 187.452278 -27.253739) (xy 187.545886 -27.262612) (xy 187.638243 -27.280255) (xy 187.728531 -27.30651)
			(xy 187.815947 -27.341145) (xy 187.899716 -27.383853) (xy 187.979094 -27.434255) (xy 188.053377 -27.491902)
			(xy 188.088016 -27.523694) (xy 188.09335 -27.528774) (xy 188.09462 -27.530044) (xy 188.094874 -27.530298)
			(xy 188.120274 -27.540458) (xy 188.12484 -27.542216) (xy 188.134433 -27.544139) (xy 188.139324 -27.544268)
			(xy 190.073026 -27.544268) (xy 190.121942 -27.544891) (xy 190.219299 -27.554518) (xy 190.315246 -27.573628)
			(xy 190.408863 -27.602037) (xy 190.45428 -27.620214) (xy 191.901318 -28.220924) (xy 191.910793 -28.223965)
			(xy 191.930662 -28.22332) (xy 191.948784 -28.215149) (xy 191.955928 -28.208224) (xy 191.956182 -28.20797)
			(xy 191.974307 -28.189322) (xy 192.014731 -28.156608) (xy 192.05922 -28.129681) (xy 192.106951 -28.109041)
			(xy 192.157041 -28.095067) (xy 192.208564 -28.08802) (xy 192.234566 -28.087574) (xy 192.261821 -28.088035)
			(xy 192.315777 -28.095787) (xy 192.36808 -28.11114) (xy 192.417665 -28.133781) (xy 192.425999 -28.139136)
			(xy 196.497954 -28.139136) (xy 196.502025 -28.083514) (xy 196.514151 -28.029077) (xy 196.534074 -27.976986)
			(xy 196.56137 -27.928351) (xy 196.595456 -27.884208) (xy 196.635605 -27.845499) (xy 196.680963 -27.813048)
			(xy 196.730563 -27.787547) (xy 196.783347 -27.76954) (xy 196.83819 -27.75941) (xy 196.893924 -27.757373)
			(xy 196.949361 -27.763473) (xy 197.003318 -27.777579) (xy 197.054647 -27.799391) (xy 197.102253 -27.828445)
			(xy 197.145121 -27.86412) (xy 197.182338 -27.905657) (xy 197.213111 -27.95217) (xy 197.236783 -28.002667)
			(xy 197.252851 -28.056074) (xy 197.260971 -28.11125) (xy 197.26148 -28.139136) (xy 197.767954 -28.139136)
			(xy 197.772025 -28.083514) (xy 197.784151 -28.029077) (xy 197.804074 -27.976986) (xy 197.83137 -27.928351)
			(xy 197.865456 -27.884208) (xy 197.905605 -27.845499) (xy 197.950963 -27.813048) (xy 198.000563 -27.787547)
			(xy 198.053347 -27.76954) (xy 198.10819 -27.75941) (xy 198.163924 -27.757373) (xy 198.219361 -27.763473)
			(xy 198.273318 -27.777579) (xy 198.324647 -27.799391) (xy 198.372253 -27.828445) (xy 198.415121 -27.86412)
			(xy 198.452338 -27.905657) (xy 198.483111 -27.95217) (xy 198.506783 -28.002667) (xy 198.522851 -28.056074)
			(xy 198.530971 -28.11125) (xy 198.53148 -28.139136) (xy 198.530971 -28.167022) (xy 198.522851 -28.222198)
			(xy 198.506783 -28.275605) (xy 198.483111 -28.326102) (xy 198.452338 -28.372615) (xy 198.415121 -28.414152)
			(xy 198.372253 -28.449827) (xy 198.324647 -28.478881) (xy 198.273318 -28.500693) (xy 198.219361 -28.514799)
			(xy 198.163924 -28.520899) (xy 198.10819 -28.518862) (xy 198.053347 -28.508732) (xy 198.000563 -28.490725)
			(xy 197.950963 -28.465224) (xy 197.905605 -28.432773) (xy 197.865456 -28.394064) (xy 197.83137 -28.349921)
			(xy 197.804074 -28.301286) (xy 197.784151 -28.249195) (xy 197.772025 -28.194758) (xy 197.767954 -28.139136)
			(xy 197.26148 -28.139136) (xy 197.260971 -28.167022) (xy 197.252851 -28.222198) (xy 197.236783 -28.275605)
			(xy 197.213111 -28.326102) (xy 197.182338 -28.372615) (xy 197.145121 -28.414152) (xy 197.102253 -28.449827)
			(xy 197.054647 -28.478881) (xy 197.003318 -28.500693) (xy 196.949361 -28.514799) (xy 196.893924 -28.520899)
			(xy 196.83819 -28.518862) (xy 196.783347 -28.508732) (xy 196.730563 -28.490725) (xy 196.680963 -28.465224)
			(xy 196.635605 -28.432773) (xy 196.595456 -28.394064) (xy 196.56137 -28.349921) (xy 196.534074 -28.301286)
			(xy 196.514151 -28.249195) (xy 196.502025 -28.194758) (xy 196.497954 -28.139136) (xy 192.425999 -28.139136)
			(xy 192.463524 -28.163248) (xy 192.504722 -28.198941) (xy 192.540421 -28.240134) (xy 192.569894 -28.285989)
			(xy 192.592541 -28.335572) (xy 192.607901 -28.387873) (xy 192.615662 -28.441827) (xy 192.616074 -28.469082)
			(xy 192.616074 -28.480004) (xy 192.614724 -28.508516) (xy 192.604621 -28.564692) (xy 192.58628 -28.618742)
			(xy 192.573656 -28.644342) (xy 192.571624 -28.648406) (xy 192.568289 -28.657795) (xy 192.568308 -28.677701)
			(xy 192.575892 -28.696106) (xy 192.582546 -28.703524) (xy 193.001392 -29.12237) (xy 202.706732 -29.12237)
			(xy 202.706732 -28.25877) (xy 202.707222 -28.228786) (xy 202.71505 -28.16933) (xy 202.730571 -28.111405)
			(xy 202.75352 -28.056001) (xy 202.783504 -28.004067) (xy 202.82001 -27.956491) (xy 202.862415 -27.914086)
			(xy 202.909991 -27.87758) (xy 202.961925 -27.847596) (xy 203.017329 -27.824647) (xy 203.075254 -27.809126)
			(xy 203.13471 -27.801298) (xy 203.194678 -27.801298) (xy 203.254134 -27.809126) (xy 203.312059 -27.824647)
			(xy 203.367463 -27.847596) (xy 203.419397 -27.87758) (xy 203.466973 -27.914086) (xy 203.509378 -27.956491)
			(xy 203.545884 -28.004067) (xy 203.575868 -28.056001) (xy 203.598817 -28.111405) (xy 203.614338 -28.16933)
			(xy 203.622166 -28.228786) (xy 203.622656 -28.25877) (xy 203.622656 -29.12237) (xy 203.622166 -29.152354)
			(xy 203.614338 -29.21181) (xy 203.598817 -29.269735) (xy 203.575868 -29.325139) (xy 203.545884 -29.377073)
			(xy 203.509378 -29.424649) (xy 203.466973 -29.467054) (xy 203.419397 -29.50356) (xy 203.367463 -29.533544)
			(xy 203.312059 -29.556493) (xy 203.254134 -29.572014) (xy 203.194678 -29.579842) (xy 203.13471 -29.579842)
			(xy 203.075254 -29.572014) (xy 203.017329 -29.556493) (xy 202.961925 -29.533544) (xy 202.909991 -29.50356)
			(xy 202.862415 -29.467054) (xy 202.82001 -29.424649) (xy 202.783504 -29.377073) (xy 202.75352 -29.325139)
			(xy 202.730571 -29.269735) (xy 202.71505 -29.21181) (xy 202.707222 -29.152354) (xy 202.706732 -29.12237)
			(xy 193.001392 -29.12237) (xy 193.285618 -29.406596) (xy 193.292302 -29.412721) (xy 193.308793 -29.420218)
			(xy 193.326864 -29.421502) (xy 193.335656 -29.419296) (xy 193.346324 -29.41447) (xy 193.352928 -29.41066)
			(xy 193.376515 -29.395535) (xy 193.427187 -29.371621) (xy 193.480814 -29.355384) (xy 193.53624 -29.347174)
			(xy 193.564256 -29.346652) (xy 193.569082 -29.346652) (xy 193.595913 -29.347431) (xy 193.648967 -29.355591)
			(xy 193.700353 -29.371106) (xy 193.749057 -29.393669) (xy 193.794119 -29.422836) (xy 193.834649 -29.45803)
			(xy 193.869846 -29.498557) (xy 193.899016 -29.543616) (xy 193.921583 -29.592319) (xy 193.937102 -29.643704)
			(xy 193.945267 -29.696756) (xy 193.946018 -29.723588) (xy 193.946018 -29.728414) (xy 193.945469 -29.756887)
			(xy 193.936972 -29.813196) (xy 193.920212 -29.86762) (xy 193.89556 -29.918954) (xy 193.879978 -29.94279)
			(xy 193.874136 -29.954728) (xy 193.87088 -29.966035) (xy 193.873934 -29.989336) (xy 193.879978 -29.999432)
			(xy 193.886074 -30.007052) (xy 194.255818 -30.376876) (xy 194.988942 -30.376876) (xy 194.989499 -30.34796)
			(xy 194.998218 -30.29079) (xy 195.015467 -30.235592) (xy 195.040851 -30.183629) (xy 195.073789 -30.136095)
			(xy 195.113525 -30.094077) (xy 195.136008 -30.075886) (xy 195.144813 -30.068276) (xy 195.154997 -30.047378)
			(xy 195.155566 -30.035754) (xy 195.155566 -29.955998) (xy 195.155026 -29.944366) (xy 195.144839 -29.923456)
			(xy 195.136008 -29.915866) (xy 195.11351 -29.897692) (xy 195.073775 -29.855669) (xy 195.040838 -29.808131)
			(xy 195.015452 -29.756166) (xy 194.998199 -29.700965) (xy 194.989474 -29.643793) (xy 194.988942 -29.614876)
			(xy 194.989428 -29.587625) (xy 194.997184 -29.533677) (xy 195.012539 -29.481382) (xy 195.035181 -29.431805)
			(xy 195.064647 -29.385955) (xy 195.100338 -29.344764) (xy 195.141529 -29.309073) (xy 195.187379 -29.279607)
			(xy 195.236956 -29.256965) (xy 195.289251 -29.24161) (xy 195.343199 -29.233854) (xy 195.397701 -29.233854)
			(xy 195.451649 -29.24161) (xy 195.503944 -29.256965) (xy 195.553521 -29.279607) (xy 195.599371 -29.309073)
			(xy 195.640562 -29.344764) (xy 195.676253 -29.385955) (xy 195.705719 -29.431805) (xy 195.728361 -29.481382)
			(xy 195.743716 -29.533677) (xy 195.751472 -29.587625) (xy 195.751958 -29.614876) (xy 195.751438 -29.643793)
			(xy 195.742712 -29.700965) (xy 195.725455 -29.756164) (xy 195.700064 -29.808126) (xy 195.66712 -29.85566)
			(xy 195.627378 -29.897676) (xy 195.604892 -29.915866) (xy 195.596109 -29.923497) (xy 195.585912 -29.944379)
			(xy 195.585334 -29.955998) (xy 195.585334 -30.035754) (xy 195.585845 -30.04739) (xy 195.596053 -30.0683)
			(xy 195.604892 -30.075886) (xy 195.627367 -30.094087) (xy 195.667103 -30.136104) (xy 195.700043 -30.183637)
			(xy 195.725433 -30.235597) (xy 195.742691 -30.290792) (xy 195.751422 -30.347961) (xy 195.751958 -30.376876)
			(xy 198.029068 -30.376876) (xy 198.029615 -30.34796) (xy 198.038335 -30.290789) (xy 198.055585 -30.23559)
			(xy 198.080971 -30.183627) (xy 198.113911 -30.136093) (xy 198.15365 -30.094076) (xy 198.176134 -30.075886)
			(xy 198.184943 -30.068281) (xy 198.195124 -30.047378) (xy 198.195692 -30.035754) (xy 198.195692 -29.955998)
			(xy 198.195143 -29.944367) (xy 198.184961 -29.923457) (xy 198.176134 -29.915866) (xy 198.153641 -29.897686)
			(xy 198.113905 -29.855665) (xy 198.080966 -29.808128) (xy 198.055579 -29.756164) (xy 198.038325 -29.700964)
			(xy 198.0296 -29.643793) (xy 198.029068 -29.614876) (xy 198.029554 -29.587625) (xy 198.03731 -29.533677)
			(xy 198.052665 -29.481382) (xy 198.075307 -29.431805) (xy 198.104773 -29.385955) (xy 198.140464 -29.344764)
			(xy 198.181655 -29.309073) (xy 198.227505 -29.279607) (xy 198.277082 -29.256965) (xy 198.329377 -29.24161)
			(xy 198.383325 -29.233854) (xy 198.437827 -29.233854) (xy 198.491775 -29.24161) (xy 198.54407 -29.256965)
			(xy 198.593647 -29.279607) (xy 198.639497 -29.309073) (xy 198.680688 -29.344764) (xy 198.716379 -29.385955)
			(xy 198.745845 -29.431805) (xy 198.768487 -29.481382) (xy 198.783842 -29.533677) (xy 198.791598 -29.587625)
			(xy 198.792084 -29.614876) (xy 198.791554 -29.643793) (xy 198.782829 -29.700964) (xy 198.765573 -29.756162)
			(xy 198.740184 -29.808124) (xy 198.707242 -29.855658) (xy 198.667503 -29.897676) (xy 198.645018 -29.915866)
			(xy 198.636222 -29.923484) (xy 198.626036 -29.944377) (xy 198.62546 -29.955998) (xy 198.62546 -30.035754)
			(xy 198.625961 -30.047391) (xy 198.636175 -30.068302) (xy 198.645018 -30.075886) (xy 198.667499 -30.09408)
			(xy 198.707233 -30.1361) (xy 198.740172 -30.183634) (xy 198.765561 -30.235595) (xy 198.782818 -30.290792)
			(xy 198.791548 -30.34796) (xy 198.792084 -30.376876) (xy 198.791598 -30.404127) (xy 198.783842 -30.458075)
			(xy 198.768487 -30.51037) (xy 198.745845 -30.559947) (xy 198.716379 -30.605797) (xy 198.680688 -30.646988)
			(xy 198.639497 -30.682679) (xy 198.593647 -30.712145) (xy 198.54407 -30.734787) (xy 198.491775 -30.750142)
			(xy 198.437827 -30.757898) (xy 198.383325 -30.757898) (xy 198.329377 -30.750142) (xy 198.277082 -30.734787)
			(xy 198.227505 -30.712145) (xy 198.181655 -30.682679) (xy 198.140464 -30.646988) (xy 198.104773 -30.605797)
			(xy 198.075307 -30.559947) (xy 198.052665 -30.51037) (xy 198.03731 -30.458075) (xy 198.029554 -30.404127)
			(xy 198.029068 -30.376876) (xy 195.751958 -30.376876) (xy 195.751472 -30.404127) (xy 195.743716 -30.458075)
			(xy 195.728361 -30.51037) (xy 195.705719 -30.559947) (xy 195.676253 -30.605797) (xy 195.640562 -30.646988)
			(xy 195.599371 -30.682679) (xy 195.553521 -30.712145) (xy 195.503944 -30.734787) (xy 195.451649 -30.750142)
			(xy 195.397701 -30.757898) (xy 195.343199 -30.757898) (xy 195.289251 -30.750142) (xy 195.236956 -30.734787)
			(xy 195.187379 -30.712145) (xy 195.141529 -30.682679) (xy 195.100338 -30.646988) (xy 195.064647 -30.605797)
			(xy 195.035181 -30.559947) (xy 195.012539 -30.51037) (xy 194.997184 -30.458075) (xy 194.989428 -30.404127)
			(xy 194.988942 -30.376876) (xy 194.255818 -30.376876) (xy 194.801292 -30.922468) (xy 200.852532 -30.922468)
			(xy 200.852532 -30.058868) (xy 200.853022 -30.028884) (xy 200.86085 -29.969428) (xy 200.876371 -29.911503)
			(xy 200.89932 -29.856099) (xy 200.929304 -29.804165) (xy 200.96581 -29.756589) (xy 201.008215 -29.714184)
			(xy 201.055791 -29.677678) (xy 201.107725 -29.647694) (xy 201.163129 -29.624745) (xy 201.221054 -29.609224)
			(xy 201.28051 -29.601396) (xy 201.340478 -29.601396) (xy 201.399934 -29.609224) (xy 201.457859 -29.624745)
			(xy 201.513263 -29.647694) (xy 201.565197 -29.677678) (xy 201.612773 -29.714184) (xy 201.655178 -29.756589)
			(xy 201.691684 -29.804165) (xy 201.721668 -29.856099) (xy 201.744617 -29.911503) (xy 201.760138 -29.969428)
			(xy 201.767966 -30.028884) (xy 201.768456 -30.058868) (xy 201.768456 -30.922468) (xy 201.767966 -30.952452)
			(xy 201.760138 -31.011908) (xy 201.744617 -31.069833) (xy 201.721668 -31.125237) (xy 201.691684 -31.177171)
			(xy 201.655178 -31.224747) (xy 201.612773 -31.267152) (xy 201.565197 -31.303658) (xy 201.513263 -31.333642)
			(xy 201.457859 -31.356591) (xy 201.399934 -31.372112) (xy 201.340478 -31.37994) (xy 201.28051 -31.37994)
			(xy 201.221054 -31.372112) (xy 201.163129 -31.356591) (xy 201.107725 -31.333642) (xy 201.055791 -31.303658)
			(xy 201.008215 -31.267152) (xy 200.96581 -31.224747) (xy 200.929304 -31.177171) (xy 200.89932 -31.125237)
			(xy 200.876371 -31.069833) (xy 200.86085 -31.011908) (xy 200.853022 -30.952452) (xy 200.852532 -30.922468)
			(xy 194.801292 -30.922468) (xy 195.0593 -31.180532) (xy 195.07327 -31.194756) (xy 195.084608 -31.206691)
			(xy 195.106584 -31.231207) (xy 195.117212 -31.243778) (xy 195.123816 -31.251398) (xy 195.131436 -31.255462)
			(xy 195.135772 -31.257782) (xy 195.145112 -31.260853) (xy 195.149978 -31.261558) (xy 195.21932 -31.269686)
			(xy 195.224114 -31.270112) (xy 195.233705 -31.269345) (xy 195.23837 -31.268162) (xy 195.24218 -31.267146)
			(xy 195.251324 -31.262828) (xy 195.251832 -31.262574) (xy 195.276363 -31.244919) (xy 195.329839 -31.216759)
			(xy 195.387083 -31.197373) (xy 195.446665 -31.187243) (xy 195.476876 -31.186374) (xy 195.480686 -31.186374)
			(xy 195.507938 -31.186859) (xy 195.561889 -31.194614) (xy 195.614186 -31.209967) (xy 195.663766 -31.232607)
			(xy 195.70962 -31.262073) (xy 195.750813 -31.297764) (xy 195.786508 -31.338955) (xy 195.815977 -31.384806)
			(xy 195.838621 -31.434384) (xy 195.85398 -31.48668) (xy 195.861739 -31.54063) (xy 195.862194 -31.567882)
			(xy 195.861681 -31.596544) (xy 195.853109 -31.653222) (xy 195.836156 -31.707981) (xy 195.830699 -31.719266)
			(xy 196.385432 -31.719266) (xy 196.389503 -31.663644) (xy 196.401629 -31.609207) (xy 196.421552 -31.557116)
			(xy 196.448848 -31.508481) (xy 196.482934 -31.464338) (xy 196.523083 -31.425629) (xy 196.568441 -31.393178)
			(xy 196.618041 -31.367677) (xy 196.670825 -31.34967) (xy 196.725668 -31.33954) (xy 196.781402 -31.337503)
			(xy 196.836839 -31.343603) (xy 196.890796 -31.357709) (xy 196.942125 -31.379521) (xy 196.989731 -31.408575)
			(xy 197.032599 -31.44425) (xy 197.069816 -31.485787) (xy 197.100589 -31.5323) (xy 197.124261 -31.582797)
			(xy 197.140329 -31.636204) (xy 197.144479 -31.664402) (xy 197.66102 -31.664402) (xy 197.665091 -31.60878)
			(xy 197.677217 -31.554343) (xy 197.69714 -31.502252) (xy 197.724436 -31.453617) (xy 197.758522 -31.409474)
			(xy 197.798671 -31.370765) (xy 197.844029 -31.338314) (xy 197.893629 -31.312813) (xy 197.946413 -31.294806)
			(xy 198.001256 -31.284676) (xy 198.05699 -31.282639) (xy 198.112427 -31.288739) (xy 198.166384 -31.302845)
			(xy 198.217713 -31.324657) (xy 198.265319 -31.353711) (xy 198.308187 -31.389386) (xy 198.345404 -31.430923)
			(xy 198.376177 -31.477436) (xy 198.399849 -31.527933) (xy 198.415917 -31.58134) (xy 198.424037 -31.636516)
			(xy 198.424546 -31.664402) (xy 198.424037 -31.692288) (xy 198.415917 -31.747464) (xy 198.406977 -31.777178)
			(xy 198.926194 -31.777178) (xy 198.930265 -31.721556) (xy 198.942391 -31.667119) (xy 198.962314 -31.615028)
			(xy 198.98961 -31.566393) (xy 199.023696 -31.52225) (xy 199.063845 -31.483541) (xy 199.109203 -31.45109)
			(xy 199.158803 -31.425589) (xy 199.211587 -31.407582) (xy 199.26643 -31.397452) (xy 199.322164 -31.395415)
			(xy 199.377601 -31.401515) (xy 199.431558 -31.415621) (xy 199.482887 -31.437433) (xy 199.530493 -31.466487)
			(xy 199.573361 -31.502162) (xy 199.610578 -31.543699) (xy 199.641351 -31.590212) (xy 199.665023 -31.640709)
			(xy 199.681091 -31.694116) (xy 199.689211 -31.749292) (xy 199.68972 -31.777178) (xy 199.689211 -31.805064)
			(xy 199.681091 -31.86024) (xy 199.665023 -31.913647) (xy 199.641351 -31.964144) (xy 199.610578 -32.010657)
			(xy 199.573361 -32.052194) (xy 199.530493 -32.087869) (xy 199.482887 -32.116923) (xy 199.431558 -32.138735)
			(xy 199.377601 -32.152841) (xy 199.322164 -32.158941) (xy 199.26643 -32.156904) (xy 199.211587 -32.146774)
			(xy 199.158803 -32.128767) (xy 199.109203 -32.103266) (xy 199.063845 -32.070815) (xy 199.023696 -32.032106)
			(xy 198.98961 -31.987963) (xy 198.962314 -31.939328) (xy 198.942391 -31.887237) (xy 198.930265 -31.8328)
			(xy 198.926194 -31.777178) (xy 198.406977 -31.777178) (xy 198.399849 -31.800871) (xy 198.376177 -31.851368)
			(xy 198.345404 -31.897881) (xy 198.308187 -31.939418) (xy 198.265319 -31.975093) (xy 198.217713 -32.004147)
			(xy 198.166384 -32.025959) (xy 198.112427 -32.040065) (xy 198.05699 -32.046165) (xy 198.001256 -32.044128)
			(xy 197.946413 -32.033998) (xy 197.893629 -32.015991) (xy 197.844029 -31.99049) (xy 197.798671 -31.958039)
			(xy 197.758522 -31.91933) (xy 197.724436 -31.875187) (xy 197.69714 -31.826552) (xy 197.677217 -31.774461)
			(xy 197.665091 -31.720024) (xy 197.66102 -31.664402) (xy 197.144479 -31.664402) (xy 197.148449 -31.69138)
			(xy 197.148958 -31.719266) (xy 197.148449 -31.747152) (xy 197.140329 -31.802328) (xy 197.124261 -31.855735)
			(xy 197.100589 -31.906232) (xy 197.069816 -31.952745) (xy 197.032599 -31.994282) (xy 196.989731 -32.029957)
			(xy 196.942125 -32.059011) (xy 196.890796 -32.080823) (xy 196.836839 -32.094929) (xy 196.781402 -32.101029)
			(xy 196.725668 -32.098992) (xy 196.670825 -32.088862) (xy 196.618041 -32.070855) (xy 196.568441 -32.045354)
			(xy 196.523083 -32.012903) (xy 196.482934 -31.974194) (xy 196.448848 -31.930051) (xy 196.421552 -31.881416)
			(xy 196.401629 -31.829325) (xy 196.389503 -31.774888) (xy 196.385432 -31.719266) (xy 195.830699 -31.719266)
			(xy 195.811203 -31.759588) (xy 195.778812 -31.806882) (xy 195.739711 -31.848799) (xy 195.69478 -31.884396)
			(xy 195.67017 -31.899098) (xy 195.662804 -31.903162) (xy 195.661026 -31.904178) (xy 195.654676 -31.91256)
			(xy 195.651752 -31.916662) (xy 195.647392 -31.925742) (xy 195.64604 -31.930594) (xy 195.627752 -32.002222)
			(xy 195.626225 -32.010803) (xy 195.628439 -32.028079) (xy 195.63207 -32.036004) (xy 196.069099 -32.722312)
			(xy 202.706732 -32.722312) (xy 202.706732 -31.858712) (xy 202.707222 -31.828728) (xy 202.71505 -31.769272)
			(xy 202.730571 -31.711347) (xy 202.75352 -31.655943) (xy 202.783504 -31.604009) (xy 202.82001 -31.556433)
			(xy 202.862415 -31.514028) (xy 202.909991 -31.477522) (xy 202.961925 -31.447538) (xy 203.017329 -31.424589)
			(xy 203.075254 -31.409068) (xy 203.13471 -31.40124) (xy 203.194678 -31.40124) (xy 203.254134 -31.409068)
			(xy 203.312059 -31.424589) (xy 203.367463 -31.447538) (xy 203.419397 -31.477522) (xy 203.466973 -31.514028)
			(xy 203.509378 -31.556433) (xy 203.545884 -31.604009) (xy 203.575868 -31.655943) (xy 203.598817 -31.711347)
			(xy 203.614338 -31.769272) (xy 203.622166 -31.828728) (xy 203.622656 -31.858712) (xy 203.622656 -32.722312)
			(xy 203.622166 -32.752296) (xy 203.614338 -32.811752) (xy 203.598817 -32.869677) (xy 203.575868 -32.925081)
			(xy 203.545884 -32.977015) (xy 203.509378 -33.024591) (xy 203.466973 -33.066996) (xy 203.419397 -33.103502)
			(xy 203.367463 -33.133486) (xy 203.312059 -33.156435) (xy 203.254134 -33.171956) (xy 203.194678 -33.179784)
			(xy 203.13471 -33.179784) (xy 203.075254 -33.171956) (xy 203.017329 -33.156435) (xy 202.961925 -33.133486)
			(xy 202.909991 -33.103502) (xy 202.862415 -33.066996) (xy 202.82001 -33.024591) (xy 202.783504 -32.977015)
			(xy 202.75352 -32.925081) (xy 202.730571 -32.869677) (xy 202.71505 -32.811752) (xy 202.707222 -32.752296)
			(xy 202.706732 -32.722312) (xy 196.069099 -32.722312) (xy 196.158866 -32.863282) (xy 196.162168 -32.868616)
			(xy 196.176392 -32.879538) (xy 196.185536 -32.882078) (xy 196.211674 -32.890256) (xy 196.261467 -32.913062)
			(xy 196.307487 -32.942752) (xy 196.348789 -32.978718) (xy 196.384524 -33.02022) (xy 196.413957 -33.066405)
			(xy 196.436484 -33.116324) (xy 196.451642 -33.168952) (xy 196.455792 -33.196022) (xy 196.457382 -33.208281)
			(xy 196.459161 -33.232938) (xy 196.459348 -33.245298) (xy 196.459348 -33.250886) (xy 196.459123 -33.264593)
			(xy 196.456965 -33.291924) (xy 196.45503 -33.305496) (xy 196.454522 -33.310068) (xy 196.45376 -33.31464)
			(xy 196.455538 -33.322768) (xy 196.456563 -33.327269) (xy 196.46002 -33.335827) (xy 196.462396 -33.339786)
			(xy 197.215319 -34.52241) (xy 200.852532 -34.52241) (xy 200.852532 -33.65881) (xy 200.853022 -33.628826)
			(xy 200.86085 -33.56937) (xy 200.876371 -33.511445) (xy 200.89932 -33.456041) (xy 200.929304 -33.404107)
			(xy 200.96581 -33.356531) (xy 201.008215 -33.314126) (xy 201.055791 -33.27762) (xy 201.107725 -33.247636)
			(xy 201.163129 -33.224687) (xy 201.221054 -33.209166) (xy 201.28051 -33.201338) (xy 201.340478 -33.201338)
			(xy 201.399934 -33.209166) (xy 201.457859 -33.224687) (xy 201.513263 -33.247636) (xy 201.565197 -33.27762)
			(xy 201.612773 -33.314126) (xy 201.655178 -33.356531) (xy 201.691684 -33.404107) (xy 201.721668 -33.456041)
			(xy 201.744617 -33.511445) (xy 201.760138 -33.56937) (xy 201.767966 -33.628826) (xy 201.768456 -33.65881)
			(xy 201.768456 -34.52241) (xy 201.767966 -34.552394) (xy 201.760138 -34.61185) (xy 201.744617 -34.669775)
			(xy 201.721668 -34.725179) (xy 201.691684 -34.777113) (xy 201.655178 -34.824689) (xy 201.612773 -34.867094)
			(xy 201.565197 -34.9036) (xy 201.513263 -34.933584) (xy 201.457859 -34.956533) (xy 201.399934 -34.972054)
			(xy 201.340478 -34.979882) (xy 201.28051 -34.979882) (xy 201.221054 -34.972054) (xy 201.163129 -34.956533)
			(xy 201.107725 -34.933584) (xy 201.055791 -34.9036) (xy 201.008215 -34.867094) (xy 200.96581 -34.824689)
			(xy 200.929304 -34.777113) (xy 200.89932 -34.725179) (xy 200.876371 -34.669775) (xy 200.86085 -34.61185)
			(xy 200.853022 -34.552394) (xy 200.852532 -34.52241) (xy 197.215319 -34.52241) (xy 197.687998 -35.264852)
			(xy 198.002396 -35.264852) (xy 198.006467 -35.20923) (xy 198.018593 -35.154793) (xy 198.038516 -35.102702)
			(xy 198.065812 -35.054067) (xy 198.099898 -35.009924) (xy 198.140047 -34.971215) (xy 198.185405 -34.938764)
			(xy 198.235005 -34.913263) (xy 198.287789 -34.895256) (xy 198.342632 -34.885126) (xy 198.398366 -34.883089)
			(xy 198.453803 -34.889189) (xy 198.50776 -34.903295) (xy 198.559089 -34.925107) (xy 198.606695 -34.954161)
			(xy 198.649563 -34.989836) (xy 198.68678 -35.031373) (xy 198.717553 -35.077886) (xy 198.741225 -35.128383)
			(xy 198.757293 -35.18179) (xy 198.765413 -35.236966) (xy 198.765922 -35.264852) (xy 198.765413 -35.292738)
			(xy 198.757293 -35.347914) (xy 198.741225 -35.401321) (xy 198.717553 -35.451818) (xy 198.68678 -35.498331)
			(xy 198.649563 -35.539868) (xy 198.606695 -35.575543) (xy 198.559089 -35.604597) (xy 198.50776 -35.626409)
			(xy 198.453803 -35.640515) (xy 198.398366 -35.646615) (xy 198.342632 -35.644578) (xy 198.287789 -35.634448)
			(xy 198.235005 -35.616441) (xy 198.185405 -35.59094) (xy 198.140047 -35.558489) (xy 198.099898 -35.51978)
			(xy 198.065812 -35.475637) (xy 198.038516 -35.427002) (xy 198.018593 -35.374911) (xy 198.006467 -35.320474)
			(xy 198.002396 -35.264852) (xy 197.687998 -35.264852) (xy 198.338721 -36.286948) (xy 199.300336 -36.286948)
			(xy 199.304407 -36.231326) (xy 199.316533 -36.176889) (xy 199.336456 -36.124798) (xy 199.363752 -36.076163)
			(xy 199.397838 -36.03202) (xy 199.437987 -35.993311) (xy 199.483345 -35.96086) (xy 199.532945 -35.935359)
			(xy 199.585729 -35.917352) (xy 199.640572 -35.907222) (xy 199.696306 -35.905185) (xy 199.751743 -35.911285)
			(xy 199.8057 -35.925391) (xy 199.857029 -35.947203) (xy 199.904635 -35.976257) (xy 199.947503 -36.011932)
			(xy 199.98472 -36.053469) (xy 200.015493 -36.099982) (xy 200.039165 -36.150479) (xy 200.055233 -36.203886)
			(xy 200.063353 -36.259062) (xy 200.063862 -36.286948) (xy 200.063353 -36.314834) (xy 200.055233 -36.37001)
			(xy 200.039165 -36.423417) (xy 200.015493 -36.473914) (xy 199.987948 -36.515548) (xy 201.11415 -36.515548)
			(xy 201.118221 -36.459926) (xy 201.130347 -36.405489) (xy 201.15027 -36.353398) (xy 201.177566 -36.304763)
			(xy 201.211652 -36.26062) (xy 201.251801 -36.221911) (xy 201.297159 -36.18946) (xy 201.346759 -36.163959)
			(xy 201.399543 -36.145952) (xy 201.454386 -36.135822) (xy 201.51012 -36.133785) (xy 201.565557 -36.139885)
			(xy 201.619514 -36.153991) (xy 201.670843 -36.175803) (xy 201.718449 -36.204857) (xy 201.761317 -36.240532)
			(xy 201.798534 -36.282069) (xy 201.829307 -36.328582) (xy 201.852979 -36.379079) (xy 201.869047 -36.432486)
			(xy 201.877167 -36.487662) (xy 201.877676 -36.515548) (xy 201.877167 -36.543434) (xy 201.869047 -36.59861)
			(xy 201.86859 -36.60013) (xy 206.098655 -36.60013) (xy 206.102659 -36.512245) (xy 206.114639 -36.425088)
			(xy 206.134494 -36.339381) (xy 206.162061 -36.255836) (xy 206.197111 -36.175143) (xy 206.239353 -36.097971)
			(xy 206.288438 -36.024961) (xy 206.343959 -35.956717) (xy 206.405456 -35.893804) (xy 206.472418 -35.836744)
			(xy 206.544292 -35.78601) (xy 206.620482 -35.742022) (xy 206.700356 -35.705144) (xy 206.783253 -35.675683)
			(xy 206.868485 -35.653881) (xy 206.955347 -35.639921) (xy 207.043118 -35.633917) (xy 207.131072 -35.63592)
			(xy 207.218479 -35.645912) (xy 207.304615 -35.663812) (xy 207.388767 -35.68947) (xy 207.470237 -35.722674)
			(xy 207.54835 -35.763148) (xy 207.622458 -35.810559) (xy 207.691949 -35.864512) (xy 207.756245 -35.92456)
			(xy 207.814814 -35.990207) (xy 207.867171 -36.060907) (xy 207.912883 -36.136076) (xy 207.951569 -36.21509)
			(xy 207.98291 -36.297295) (xy 208.006645 -36.382009) (xy 208.022579 -36.46853) (xy 208.030579 -36.556142)
			(xy 208.03108 -36.60013) (xy 208.030579 -36.644118) (xy 208.022579 -36.73173) (xy 208.006645 -36.818251)
			(xy 207.98291 -36.902965) (xy 207.951569 -36.98517) (xy 207.912883 -37.064184) (xy 207.867171 -37.139353)
			(xy 207.814814 -37.210053) (xy 207.756245 -37.2757) (xy 207.691949 -37.335748) (xy 207.622458 -37.389701)
			(xy 207.54835 -37.437112) (xy 207.470237 -37.477586) (xy 207.388767 -37.51079) (xy 207.304615 -37.536448)
			(xy 207.218479 -37.554348) (xy 207.131072 -37.56434) (xy 207.043118 -37.566343) (xy 206.955347 -37.560339)
			(xy 206.868485 -37.546379) (xy 206.783253 -37.524577) (xy 206.700356 -37.495116) (xy 206.620482 -37.458238)
			(xy 206.544292 -37.41425) (xy 206.472418 -37.363516) (xy 206.405456 -37.306456) (xy 206.343959 -37.243543)
			(xy 206.288438 -37.175299) (xy 206.239353 -37.102289) (xy 206.197111 -37.025117) (xy 206.162061 -36.944424)
			(xy 206.134494 -36.860879) (xy 206.114639 -36.775172) (xy 206.102659 -36.688015) (xy 206.098655 -36.60013)
			(xy 201.86859 -36.60013) (xy 201.852979 -36.652017) (xy 201.829307 -36.702514) (xy 201.798534 -36.749027)
			(xy 201.761317 -36.790564) (xy 201.718449 -36.826239) (xy 201.670843 -36.855293) (xy 201.619514 -36.877105)
			(xy 201.565557 -36.891211) (xy 201.51012 -36.897311) (xy 201.454386 -36.895274) (xy 201.399543 -36.885144)
			(xy 201.346759 -36.867137) (xy 201.297159 -36.841636) (xy 201.251801 -36.809185) (xy 201.211652 -36.770476)
			(xy 201.177566 -36.726333) (xy 201.15027 -36.677698) (xy 201.130347 -36.625607) (xy 201.118221 -36.57117)
			(xy 201.11415 -36.515548) (xy 199.987948 -36.515548) (xy 199.98472 -36.520427) (xy 199.947503 -36.561964)
			(xy 199.904635 -36.597639) (xy 199.857029 -36.626693) (xy 199.8057 -36.648505) (xy 199.751743 -36.662611)
			(xy 199.696306 -36.668711) (xy 199.640572 -36.666674) (xy 199.585729 -36.656544) (xy 199.532945 -36.638537)
			(xy 199.483345 -36.613036) (xy 199.437987 -36.580585) (xy 199.397838 -36.541876) (xy 199.363752 -36.497733)
			(xy 199.336456 -36.449098) (xy 199.316533 -36.397007) (xy 199.304407 -36.34257) (xy 199.300336 -36.286948)
			(xy 198.338721 -36.286948) (xy 199.13854 -37.543232) (xy 199.285555 -37.774118) (xy 199.56475 -37.774118)
			(xy 199.568821 -37.718496) (xy 199.580947 -37.664059) (xy 199.60087 -37.611968) (xy 199.628166 -37.563333)
			(xy 199.662252 -37.51919) (xy 199.702401 -37.480481) (xy 199.747759 -37.44803) (xy 199.797359 -37.422529)
			(xy 199.850143 -37.404522) (xy 199.904986 -37.394392) (xy 199.96072 -37.392355) (xy 200.016157 -37.398455)
			(xy 200.070114 -37.412561) (xy 200.121443 -37.434373) (xy 200.169049 -37.463427) (xy 200.211917 -37.499102)
			(xy 200.249134 -37.540639) (xy 200.279907 -37.587152) (xy 200.303579 -37.637649) (xy 200.319647 -37.691056)
			(xy 200.327767 -37.746232) (xy 200.328276 -37.774118) (xy 200.327767 -37.802004) (xy 200.319647 -37.85718)
			(xy 200.303579 -37.910587) (xy 200.279907 -37.961084) (xy 200.249134 -38.007597) (xy 200.211917 -38.049134)
			(xy 200.169049 -38.084809) (xy 200.121443 -38.113863) (xy 200.070114 -38.135675) (xy 200.016157 -38.149781)
			(xy 199.96072 -38.155881) (xy 199.904986 -38.153844) (xy 199.850143 -38.143714) (xy 199.797359 -38.125707)
			(xy 199.747759 -38.100206) (xy 199.702401 -38.067755) (xy 199.662252 -38.029046) (xy 199.628166 -37.984903)
			(xy 199.60087 -37.936268) (xy 199.580947 -37.884177) (xy 199.568821 -37.82974) (xy 199.56475 -37.774118)
			(xy 199.285555 -37.774118) (xy 200.14565 -39.12489) (xy 200.150222 -39.130986) (xy 202.02199 -41.268751)
			(xy 209.94395 -41.268751) (xy 209.94395 -41.214249) (xy 209.951706 -41.160301) (xy 209.96706 -41.108006)
			(xy 209.989699 -41.058428) (xy 210.019163 -41.012577) (xy 210.054852 -40.971385) (xy 210.09604 -40.935691)
			(xy 210.141888 -40.906221) (xy 210.191463 -40.883576) (xy 210.243756 -40.868215) (xy 210.297703 -40.860453)
			(xy 210.324954 -40.859964) (xy 210.353694 -40.860465) (xy 210.410522 -40.869094) (xy 210.465412 -40.88615)
			(xy 210.517124 -40.911247) (xy 210.564485 -40.943816) (xy 210.585812 -40.963088) (xy 210.59267 -40.969692)
			(xy 210.610704 -40.976804) (xy 210.699604 -40.976804) (xy 210.717638 -40.969692) (xy 210.724496 -40.963088)
			(xy 210.745808 -40.9438) (xy 210.793173 -40.911234) (xy 210.844889 -40.886144) (xy 210.899783 -40.869098)
			(xy 210.956614 -40.860481) (xy 210.985354 -40.859964) (xy 211.012607 -40.86048) (xy 211.066559 -40.868231)
			(xy 211.118858 -40.883582) (xy 211.168441 -40.90622) (xy 211.214296 -40.935685) (xy 211.255491 -40.971376)
			(xy 211.291187 -41.012567) (xy 211.320658 -41.058419) (xy 211.343302 -41.107998) (xy 211.358659 -41.160296)
			(xy 211.366417 -41.214247) (xy 211.366417 -41.268753) (xy 211.358659 -41.322704) (xy 211.343302 -41.375002)
			(xy 211.320658 -41.424581) (xy 211.291187 -41.470433) (xy 211.255491 -41.511624) (xy 211.214296 -41.547315)
			(xy 211.168441 -41.57678) (xy 211.118858 -41.599418) (xy 211.066559 -41.614769) (xy 211.012607 -41.62252)
			(xy 210.985354 -41.62298) (xy 210.956615 -41.622463) (xy 210.899788 -41.613835) (xy 210.844898 -41.596783)
			(xy 210.793187 -41.57169) (xy 210.745824 -41.539126) (xy 210.724496 -41.519856) (xy 210.717638 -41.513252)
			(xy 210.699604 -41.50614) (xy 210.610704 -41.50614) (xy 210.59267 -41.513252) (xy 210.585812 -41.519856)
			(xy 210.564503 -41.539148) (xy 210.517136 -41.571711) (xy 210.46542 -41.5968) (xy 210.410525 -41.613845)
			(xy 210.353694 -41.622462) (xy 210.324954 -41.62298) (xy 210.297703 -41.622547) (xy 210.243756 -41.614785)
			(xy 210.191463 -41.599424) (xy 210.141888 -41.576779) (xy 210.09604 -41.547309) (xy 210.054852 -41.511615)
			(xy 210.019163 -41.470423) (xy 209.989699 -41.424572) (xy 209.96706 -41.374994) (xy 209.951706 -41.322699)
			(xy 209.94395 -41.268751) (xy 202.02199 -41.268751) (xy 203.805068 -43.305222) (xy 212.407246 -43.305222)
			(xy 212.407714 -43.277852) (xy 212.415529 -43.223672) (xy 212.431018 -43.171169) (xy 212.453859 -43.121422)
			(xy 212.483584 -43.075455) (xy 212.501226 -43.054524) (xy 212.50148 -43.05427) (xy 212.507053 -43.047174)
			(xy 212.513306 -43.030264) (xy 212.513672 -43.02125) (xy 212.513672 -42.954194) (xy 212.513324 -42.945176)
			(xy 212.507071 -42.928259) (xy 212.50148 -42.921174) (xy 212.501226 -42.921174) (xy 212.501226 -42.92092)
			(xy 212.483587 -42.899988) (xy 212.453874 -42.854015) (xy 212.431038 -42.804268) (xy 212.415547 -42.751767)
			(xy 212.407719 -42.697591) (xy 212.407246 -42.670222) (xy 212.407798 -42.641484) (xy 212.416416 -42.584659)
			(xy 212.43346 -42.529769) (xy 212.458545 -42.478057) (xy 212.491103 -42.430692) (xy 212.51037 -42.409364)
			(xy 212.516974 -42.402506) (xy 212.524086 -42.384472) (xy 212.524086 -42.295572) (xy 212.516974 -42.277538)
			(xy 212.51037 -42.27068) (xy 212.491123 -42.249333) (xy 212.458562 -42.201973) (xy 212.433473 -42.150264)
			(xy 212.416424 -42.095377) (xy 212.4078 -42.038553) (xy 212.407798 -41.981079) (xy 212.416417 -41.924255)
			(xy 212.433461 -41.869366) (xy 212.458546 -41.817655) (xy 212.491103 -41.770292) (xy 212.51037 -41.748964)
			(xy 212.516974 -41.742106) (xy 212.524086 -41.724072) (xy 212.524086 -41.635172) (xy 212.516974 -41.617138)
			(xy 212.51037 -41.61028) (xy 212.491115 -41.588939) (xy 212.458545 -41.541582) (xy 212.433449 -41.489873)
			(xy 212.416395 -41.434986) (xy 212.407769 -41.37816) (xy 212.407246 -41.349422) (xy 212.407732 -41.322171)
			(xy 212.415488 -41.268223) (xy 212.430843 -41.215928) (xy 212.453485 -41.166351) (xy 212.482951 -41.120501)
			(xy 212.518642 -41.07931) (xy 212.559833 -41.043619) (xy 212.605683 -41.014153) (xy 212.65526 -40.991511)
			(xy 212.707555 -40.976156) (xy 212.761503 -40.9684) (xy 212.816005 -40.9684) (xy 212.869953 -40.976156)
			(xy 212.922248 -40.991511) (xy 212.971825 -41.014153) (xy 213.017675 -41.043619) (xy 213.058866 -41.07931)
			(xy 213.094557 -41.120501) (xy 213.124023 -41.166351) (xy 213.146665 -41.215928) (xy 213.16202 -41.268223)
			(xy 213.169776 -41.322171) (xy 213.170262 -41.349422) (xy 213.169735 -41.378161) (xy 213.161111 -41.434987)
			(xy 213.14406 -41.489877) (xy 213.11897 -41.541589) (xy 213.086407 -41.588952) (xy 213.067138 -41.61028)
			(xy 213.060534 -41.617138) (xy 213.053422 -41.635172) (xy 213.053422 -41.724072) (xy 213.060534 -41.742106)
			(xy 213.067138 -41.748964) (xy 213.086432 -41.770271) (xy 213.119 -41.817636) (xy 213.144093 -41.869351)
			(xy 213.161143 -41.924245) (xy 213.169765 -41.981075) (xy 213.169762 -42.038557) (xy 213.161136 -42.095387)
			(xy 213.144081 -42.150279) (xy 213.118984 -42.201992) (xy 213.086412 -42.249354) (xy 213.067138 -42.27068)
			(xy 213.060534 -42.277538) (xy 213.053422 -42.295572) (xy 213.053422 -42.384472) (xy 213.060534 -42.402506)
			(xy 213.067138 -42.409364) (xy 213.086415 -42.430686) (xy 213.118981 -42.478049) (xy 213.144073 -42.529762)
			(xy 213.161122 -42.584654) (xy 213.169743 -42.641483) (xy 213.170262 -42.670222) (xy 213.169818 -42.697593)
			(xy 213.161996 -42.751774) (xy 213.146503 -42.804277) (xy 213.125946 -42.849038) (xy 214.991948 -42.849038)
			(xy 214.996019 -42.793416) (xy 215.008145 -42.738979) (xy 215.028068 -42.686888) (xy 215.055364 -42.638253)
			(xy 215.08945 -42.59411) (xy 215.129599 -42.555401) (xy 215.174957 -42.52295) (xy 215.224557 -42.497449)
			(xy 215.277341 -42.479442) (xy 215.332184 -42.469312) (xy 215.387918 -42.467275) (xy 215.443355 -42.473375)
			(xy 215.497312 -42.487481) (xy 215.548641 -42.509293) (xy 215.596247 -42.538347) (xy 215.639115 -42.574022)
			(xy 215.676332 -42.615559) (xy 215.707105 -42.662072) (xy 215.730777 -42.712569) (xy 215.746845 -42.765976)
			(xy 215.754965 -42.821152) (xy 215.755474 -42.849038) (xy 215.754965 -42.876924) (xy 215.746845 -42.9321)
			(xy 215.730777 -42.985507) (xy 215.707105 -43.036004) (xy 215.676332 -43.082517) (xy 215.639115 -43.124054)
			(xy 215.596247 -43.159729) (xy 215.548641 -43.188783) (xy 215.497312 -43.210595) (xy 215.443355 -43.224701)
			(xy 215.387918 -43.230801) (xy 215.332184 -43.228764) (xy 215.277341 -43.218634) (xy 215.224557 -43.200627)
			(xy 215.174957 -43.175126) (xy 215.129599 -43.142675) (xy 215.08945 -43.103966) (xy 215.055364 -43.059823)
			(xy 215.028068 -43.011188) (xy 215.008145 -42.959097) (xy 214.996019 -42.90466) (xy 214.991948 -42.849038)
			(xy 213.125946 -42.849038) (xy 213.123656 -42.854024) (xy 213.093926 -42.899989) (xy 213.076282 -42.92092)
			(xy 213.076028 -42.921174) (xy 213.070438 -42.928258) (xy 213.064195 -42.945177) (xy 213.063836 -42.954194)
			(xy 213.063836 -43.02125) (xy 213.064209 -43.030265) (xy 213.070445 -43.047183) (xy 213.076028 -43.05427)
			(xy 213.076282 -43.05427) (xy 213.076282 -43.054524) (xy 213.093896 -43.075476) (xy 213.123612 -43.121443)
			(xy 213.146453 -43.171186) (xy 213.16195 -43.223682) (xy 213.169785 -43.277854) (xy 213.170262 -43.305222)
			(xy 213.169776 -43.332473) (xy 213.16202 -43.386421) (xy 213.146665 -43.438716) (xy 213.124023 -43.488293)
			(xy 213.094557 -43.534143) (xy 213.058866 -43.575334) (xy 213.017675 -43.611025) (xy 212.971825 -43.640491)
			(xy 212.922248 -43.663133) (xy 212.869953 -43.678488) (xy 212.816005 -43.686244) (xy 212.761503 -43.686244)
			(xy 212.707555 -43.678488) (xy 212.65526 -43.663133) (xy 212.605683 -43.640491) (xy 212.559833 -43.611025)
			(xy 212.518642 -43.575334) (xy 212.482951 -43.534143) (xy 212.453485 -43.488293) (xy 212.430843 -43.438716)
			(xy 212.415488 -43.386421) (xy 212.407732 -43.332473) (xy 212.407246 -43.305222) (xy 203.805068 -43.305222)
			(xy 204.182473 -43.73626) (xy 214.313006 -43.73626) (xy 214.317077 -43.680638) (xy 214.329203 -43.626201)
			(xy 214.349126 -43.57411) (xy 214.376422 -43.525475) (xy 214.410508 -43.481332) (xy 214.450657 -43.442623)
			(xy 214.496015 -43.410172) (xy 214.545615 -43.384671) (xy 214.598399 -43.366664) (xy 214.653242 -43.356534)
			(xy 214.708976 -43.354497) (xy 214.764413 -43.360597) (xy 214.81837 -43.374703) (xy 214.869699 -43.396515)
			(xy 214.917305 -43.425569) (xy 214.960173 -43.461244) (xy 214.99739 -43.502781) (xy 215.028163 -43.549294)
			(xy 215.051835 -43.599791) (xy 215.067903 -43.653198) (xy 215.076023 -43.708374) (xy 215.076532 -43.73626)
			(xy 215.076023 -43.764146) (xy 215.067903 -43.819322) (xy 215.056594 -43.85691) (xy 218.819728 -43.85691)
			(xy 218.823799 -43.801288) (xy 218.835925 -43.746851) (xy 218.855848 -43.69476) (xy 218.883144 -43.646125)
			(xy 218.91723 -43.601982) (xy 218.957379 -43.563273) (xy 219.002737 -43.530822) (xy 219.052337 -43.505321)
			(xy 219.105121 -43.487314) (xy 219.159964 -43.477184) (xy 219.215698 -43.475147) (xy 219.271135 -43.481247)
			(xy 219.325092 -43.495353) (xy 219.376421 -43.517165) (xy 219.424027 -43.546219) (xy 219.466895 -43.581894)
			(xy 219.504112 -43.623431) (xy 219.534885 -43.669944) (xy 219.558557 -43.720441) (xy 219.574625 -43.773848)
			(xy 219.582745 -43.829024) (xy 219.583254 -43.85691) (xy 219.582745 -43.884796) (xy 219.574625 -43.939972)
			(xy 219.558557 -43.993379) (xy 219.534885 -44.043876) (xy 219.504112 -44.090389) (xy 219.466895 -44.131926)
			(xy 219.424027 -44.167601) (xy 219.376421 -44.196655) (xy 219.325092 -44.218467) (xy 219.271135 -44.232573)
			(xy 219.215698 -44.238673) (xy 219.159964 -44.236636) (xy 219.105121 -44.226506) (xy 219.052337 -44.208499)
			(xy 219.002737 -44.182998) (xy 218.957379 -44.150547) (xy 218.91723 -44.111838) (xy 218.883144 -44.067695)
			(xy 218.855848 -44.01906) (xy 218.835925 -43.966969) (xy 218.823799 -43.912532) (xy 218.819728 -43.85691)
			(xy 215.056594 -43.85691) (xy 215.051835 -43.872729) (xy 215.028163 -43.923226) (xy 214.99739 -43.969739)
			(xy 214.960173 -44.011276) (xy 214.917305 -44.046951) (xy 214.869699 -44.076005) (xy 214.81837 -44.097817)
			(xy 214.764413 -44.111923) (xy 214.708976 -44.118023) (xy 214.653242 -44.115986) (xy 214.598399 -44.105856)
			(xy 214.545615 -44.087849) (xy 214.496015 -44.062348) (xy 214.450657 -44.029897) (xy 214.410508 -43.991188)
			(xy 214.376422 -43.947045) (xy 214.349126 -43.89841) (xy 214.329203 -43.846319) (xy 214.317077 -43.791882)
			(xy 214.313006 -43.73626) (xy 204.182473 -43.73626) (xy 205.38919 -45.114464) (xy 214.165432 -45.114464)
			(xy 214.169503 -45.058842) (xy 214.181629 -45.004405) (xy 214.201552 -44.952314) (xy 214.228848 -44.903679)
			(xy 214.262934 -44.859536) (xy 214.303083 -44.820827) (xy 214.348441 -44.788376) (xy 214.398041 -44.762875)
			(xy 214.450825 -44.744868) (xy 214.505668 -44.734738) (xy 214.561402 -44.732701) (xy 214.616839 -44.738801)
			(xy 214.670796 -44.752907) (xy 214.722125 -44.774719) (xy 214.769731 -44.803773) (xy 214.812599 -44.839448)
			(xy 214.849816 -44.880985) (xy 214.880589 -44.927498) (xy 214.904261 -44.977995) (xy 214.920329 -45.031402)
			(xy 214.928449 -45.086578) (xy 214.928958 -45.114464) (xy 214.928449 -45.14235) (xy 214.920329 -45.197526)
			(xy 214.904261 -45.250933) (xy 214.880589 -45.30143) (xy 214.849816 -45.347943) (xy 214.844174 -45.35424)
			(xy 218.803726 -45.35424) (xy 218.807797 -45.298618) (xy 218.819923 -45.244181) (xy 218.839846 -45.19209)
			(xy 218.867142 -45.143455) (xy 218.901228 -45.099312) (xy 218.941377 -45.060603) (xy 218.986735 -45.028152)
			(xy 219.036335 -45.002651) (xy 219.089119 -44.984644) (xy 219.143962 -44.974514) (xy 219.199696 -44.972477)
			(xy 219.255133 -44.978577) (xy 219.30909 -44.992683) (xy 219.360419 -45.014495) (xy 219.408025 -45.043549)
			(xy 219.450893 -45.079224) (xy 219.48811 -45.120761) (xy 219.518883 -45.167274) (xy 219.542555 -45.217771)
			(xy 219.558623 -45.271178) (xy 219.566743 -45.326354) (xy 219.567252 -45.35424) (xy 219.566743 -45.382126)
			(xy 219.558623 -45.437302) (xy 219.542555 -45.490709) (xy 219.518883 -45.541206) (xy 219.48811 -45.587719)
			(xy 219.450893 -45.629256) (xy 219.408025 -45.664931) (xy 219.360419 -45.693985) (xy 219.30909 -45.715797)
			(xy 219.255133 -45.729903) (xy 219.199696 -45.736003) (xy 219.143962 -45.733966) (xy 219.089119 -45.723836)
			(xy 219.036335 -45.705829) (xy 218.986735 -45.680328) (xy 218.941377 -45.647877) (xy 218.901228 -45.609168)
			(xy 218.867142 -45.565025) (xy 218.839846 -45.51639) (xy 218.819923 -45.464299) (xy 218.807797 -45.409862)
			(xy 218.803726 -45.35424) (xy 214.844174 -45.35424) (xy 214.812599 -45.38948) (xy 214.769731 -45.425155)
			(xy 214.722125 -45.454209) (xy 214.670796 -45.476021) (xy 214.616839 -45.490127) (xy 214.561402 -45.496227)
			(xy 214.505668 -45.49419) (xy 214.450825 -45.48406) (xy 214.398041 -45.466053) (xy 214.348441 -45.440552)
			(xy 214.303083 -45.408101) (xy 214.262934 -45.369392) (xy 214.228848 -45.325249) (xy 214.201552 -45.276614)
			(xy 214.181629 -45.224523) (xy 214.169503 -45.170086) (xy 214.165432 -45.114464) (xy 205.38919 -45.114464)
			(xy 206.236517 -46.082204) (xy 212.152484 -46.082204) (xy 212.152981 -46.054953) (xy 212.160737 -46.001006)
			(xy 212.176091 -45.948712) (xy 212.198732 -45.899136) (xy 212.228197 -45.853286) (xy 212.263887 -45.812095)
			(xy 212.305076 -45.776404) (xy 212.350925 -45.746937) (xy 212.400501 -45.724296) (xy 212.452795 -45.70894)
			(xy 212.506741 -45.701182) (xy 212.533992 -45.700696) (xy 212.560894 -45.701164) (xy 212.614164 -45.708735)
			(xy 212.665842 -45.723713) (xy 212.714904 -45.745802) (xy 212.760376 -45.774564) (xy 212.801358 -45.809428)
			(xy 212.837036 -45.849703) (xy 212.852254 -45.871892) (xy 212.859366 -45.882814) (xy 212.882226 -45.894752)
			(xy 212.994494 -45.89272) (xy 213.016846 -45.879766) (xy 213.023704 -45.86859) (xy 213.038636 -45.844996)
			(xy 213.074314 -45.802044) (xy 213.11587 -45.764751) (xy 213.162418 -45.733912) (xy 213.212964 -45.710188)
			(xy 213.266428 -45.694083) (xy 213.321668 -45.685943) (xy 213.349586 -45.685456) (xy 213.376579 -45.685925)
			(xy 213.430027 -45.693529) (xy 213.48187 -45.708588) (xy 213.531075 -45.7308) (xy 213.576659 -45.759723)
			(xy 213.59749 -45.776896) (xy 213.605618 -45.784008) (xy 213.626192 -45.790104) (xy 213.711536 -45.779182)
			(xy 213.722087 -45.777435) (xy 213.740367 -45.766361) (xy 213.746842 -45.757846) (xy 213.762176 -45.736601)
			(xy 213.797766 -45.698148) (xy 213.838287 -45.664931) (xy 213.882973 -45.637574) (xy 213.930984 -45.616593)
			(xy 213.981416 -45.602383) (xy 214.033318 -45.595211) (xy 214.059516 -45.594778) (xy 214.086765 -45.595293)
			(xy 214.140709 -45.603051) (xy 214.193 -45.618407) (xy 214.242574 -45.641049) (xy 214.28842 -45.670514)
			(xy 214.329607 -45.706204) (xy 214.365295 -45.747393) (xy 214.394759 -45.79324) (xy 214.417398 -45.842815)
			(xy 214.432752 -45.895106) (xy 214.440508 -45.949051) (xy 214.440508 -46.003549) (xy 214.432752 -46.057494)
			(xy 214.417398 -46.109785) (xy 214.394759 -46.15936) (xy 214.365295 -46.205207) (xy 214.329607 -46.246396)
			(xy 214.28842 -46.282086) (xy 214.242574 -46.311551) (xy 214.193 -46.334193) (xy 214.140709 -46.349549)
			(xy 214.086765 -46.357307) (xy 214.059516 -46.357794) (xy 214.032524 -46.357312) (xy 213.979077 -46.349709)
			(xy 213.927234 -46.334653) (xy 213.878029 -46.312444) (xy 213.832444 -46.283525) (xy 213.811612 -46.266354)
			(xy 213.803484 -46.259242) (xy 213.78291 -46.253146) (xy 213.697566 -46.264068) (xy 213.68702 -46.265833)
			(xy 213.668739 -46.276896) (xy 213.66226 -46.285404) (xy 213.644649 -46.309706) (xy 213.603052 -46.352965)
			(xy 213.579456 -46.37151) (xy 213.571582 -46.377352) (xy 213.561168 -46.394878) (xy 213.54796 -46.485302)
			(xy 213.552786 -46.504606) (xy 213.558628 -46.51248) (xy 213.558628 -46.512734) (xy 213.576125 -46.537482)
			(xy 213.603931 -46.591333) (xy 213.622869 -46.648904) (xy 213.630072 -46.693836) (xy 218.776296 -46.693836)
			(xy 218.776782 -46.666585) (xy 218.784538 -46.612637) (xy 218.799893 -46.560342) (xy 218.822535 -46.510765)
			(xy 218.852001 -46.464915) (xy 218.887692 -46.423724) (xy 218.928883 -46.388033) (xy 218.974733 -46.358567)
			(xy 219.02431 -46.335925) (xy 219.076605 -46.32057) (xy 219.130553 -46.312814) (xy 219.185055 -46.312814)
			(xy 219.239003 -46.32057) (xy 219.291298 -46.335925) (xy 219.340875 -46.358567) (xy 219.386725 -46.388033)
			(xy 219.427916 -46.423724) (xy 219.463607 -46.464915) (xy 219.493073 -46.510765) (xy 219.515715 -46.560342)
			(xy 219.53107 -46.612637) (xy 219.538826 -46.666585) (xy 219.539312 -46.693836) (xy 219.538838 -46.720263)
			(xy 219.531528 -46.772611) (xy 219.517056 -46.823446) (xy 219.495696 -46.871793) (xy 219.482162 -46.894496)
			(xy 219.481908 -46.89475) (xy 219.476571 -46.904768) (xy 219.474316 -46.927318) (xy 219.47759 -46.938184)
			(xy 219.503752 -47.01286) (xy 219.508136 -47.023375) (xy 219.524225 -47.039464) (xy 219.53474 -47.043848)
			(xy 219.534994 -47.043848) (xy 219.559513 -47.052891) (xy 219.605964 -47.076839) (xy 219.648715 -47.106899)
			(xy 219.686965 -47.142511) (xy 219.72 -47.183007) (xy 219.747202 -47.227631) (xy 219.768063 -47.275548)
			(xy 219.782192 -47.325863) (xy 219.789325 -47.377635) (xy 219.789756 -47.403766) (xy 219.78927 -47.431017)
			(xy 219.781514 -47.484965) (xy 219.766159 -47.53726) (xy 219.743517 -47.586837) (xy 219.714051 -47.632687)
			(xy 219.67836 -47.673878) (xy 219.637169 -47.709569) (xy 219.591319 -47.739035) (xy 219.541742 -47.761677)
			(xy 219.489447 -47.777032) (xy 219.435499 -47.784788) (xy 219.380997 -47.784788) (xy 219.327049 -47.777032)
			(xy 219.274754 -47.761677) (xy 219.225177 -47.739035) (xy 219.179327 -47.709569) (xy 219.138136 -47.673878)
			(xy 219.102445 -47.632687) (xy 219.072979 -47.586837) (xy 219.050337 -47.53726) (xy 219.034982 -47.484965)
			(xy 219.027226 -47.431017) (xy 219.02674 -47.403766) (xy 219.027208 -47.377338) (xy 219.034518 -47.324991)
			(xy 219.048993 -47.274155) (xy 219.070354 -47.225809) (xy 219.08389 -47.203106) (xy 219.084144 -47.202852)
			(xy 219.089479 -47.192833) (xy 219.091738 -47.170284) (xy 219.088462 -47.159418) (xy 219.0623 -47.084742)
			(xy 219.057937 -47.074216) (xy 219.041834 -47.058131) (xy 219.031312 -47.053754) (xy 219.031058 -47.053754)
			(xy 219.006551 -47.04468) (xy 218.960098 -47.020739) (xy 218.917346 -46.990683) (xy 218.879094 -46.955077)
			(xy 218.846057 -46.914584) (xy 218.818854 -46.869964) (xy 218.797991 -46.822049) (xy 218.783861 -46.771736)
			(xy 218.776727 -46.719966) (xy 218.776296 -46.693836) (xy 213.630072 -46.693836) (xy 213.632462 -46.708745)
			(xy 213.63305 -46.739048) (xy 213.632567 -46.766299) (xy 213.624805 -46.820244) (xy 213.609446 -46.872536)
			(xy 213.586802 -46.922111) (xy 213.557335 -46.967959) (xy 213.521643 -47.009148) (xy 213.480454 -47.044838)
			(xy 213.434606 -47.074305) (xy 213.385031 -47.096948) (xy 213.332738 -47.112306) (xy 213.278793 -47.120067)
			(xy 213.251542 -47.120556) (xy 213.225508 -47.120134) (xy 213.173924 -47.11304) (xy 213.123782 -47.099005)
			(xy 213.076011 -47.078288) (xy 213.031498 -47.051275) (xy 213.011004 -47.035212) (xy 213.003253 -47.029461)
			(xy 212.984838 -47.023726) (xy 212.97519 -47.024036) (xy 212.895434 -47.030386) (xy 212.877654 -47.039022)
			(xy 212.871304 -47.046388) (xy 212.853144 -47.066054) (xy 212.812232 -47.100574) (xy 212.766898 -47.129041)
			(xy 212.718033 -47.150895) (xy 212.666593 -47.165708) (xy 212.613589 -47.17319) (xy 212.586824 -47.173642)
			(xy 212.559575 -47.1731) (xy 212.505631 -47.165347) (xy 212.453339 -47.149997) (xy 212.403765 -47.127361)
			(xy 212.357916 -47.0979) (xy 212.316726 -47.062215) (xy 212.281034 -47.021031) (xy 212.251567 -46.975186)
			(xy 212.228923 -46.925615) (xy 212.213565 -46.873326) (xy 212.205805 -46.819383) (xy 212.205316 -46.792134)
			(xy 212.205836 -46.76336) (xy 212.214488 -46.706465) (xy 212.231585 -46.651515) (xy 212.256739 -46.599754)
			(xy 212.289381 -46.552359) (xy 212.308694 -46.531022) (xy 212.31606 -46.523148) (xy 212.323172 -46.503336)
			(xy 212.315806 -46.40707) (xy 212.3059 -46.388274) (xy 212.297518 -46.38167) (xy 212.275333 -46.363446)
			(xy 212.236123 -46.32151) (xy 212.203638 -46.274174) (xy 212.178609 -46.222506) (xy 212.161603 -46.167672)
			(xy 212.153002 -46.110909) (xy 212.152484 -46.082204) (xy 206.236517 -46.082204) (xy 206.997554 -46.951392)
			(xy 207.026092 -46.984709) (xy 207.077861 -47.055537) (xy 207.123207 -47.13064) (xy 207.16178 -47.209437)
			(xy 207.193279 -47.291318) (xy 207.217463 -47.375649) (xy 207.234144 -47.46178) (xy 207.239108 -47.505366)
			(xy 207.260952 -47.713646) (xy 207.322678 -48.30699) (xy 218.653866 -48.30699) (xy 218.657937 -48.251368)
			(xy 218.670063 -48.196931) (xy 218.689986 -48.14484) (xy 218.717282 -48.096205) (xy 218.751368 -48.052062)
			(xy 218.791517 -48.013353) (xy 218.836875 -47.980902) (xy 218.886475 -47.955401) (xy 218.939259 -47.937394)
			(xy 218.994102 -47.927264) (xy 219.049836 -47.925227) (xy 219.105273 -47.931327) (xy 219.15923 -47.945433)
			(xy 219.210559 -47.967245) (xy 219.258165 -47.996299) (xy 219.301033 -48.031974) (xy 219.33825 -48.073511)
			(xy 219.369023 -48.120024) (xy 219.392695 -48.170521) (xy 219.408763 -48.223928) (xy 219.416883 -48.279104)
			(xy 219.417392 -48.30699) (xy 219.416883 -48.334876) (xy 219.408763 -48.390052) (xy 219.392695 -48.443459)
			(xy 219.369023 -48.493956) (xy 219.33825 -48.540469) (xy 219.301033 -48.582006) (xy 219.258165 -48.617681)
			(xy 219.210559 -48.646735) (xy 219.15923 -48.668547) (xy 219.105273 -48.682653) (xy 219.049836 -48.688753)
			(xy 218.994102 -48.686716) (xy 218.939259 -48.676586) (xy 218.886475 -48.658579) (xy 218.836875 -48.633078)
			(xy 218.791517 -48.600627) (xy 218.751368 -48.561918) (xy 218.717282 -48.517775) (xy 218.689986 -48.46914)
			(xy 218.670063 -48.417049) (xy 218.657937 -48.362612) (xy 218.653866 -48.30699) (xy 207.322678 -48.30699)
			(xy 207.350106 -48.570642) (xy 207.369129 -48.753014) (xy 215.2683 -48.753014) (xy 215.272371 -48.697392)
			(xy 215.284497 -48.642955) (xy 215.30442 -48.590864) (xy 215.331716 -48.542229) (xy 215.365802 -48.498086)
			(xy 215.405951 -48.459377) (xy 215.451309 -48.426926) (xy 215.500909 -48.401425) (xy 215.553693 -48.383418)
			(xy 215.608536 -48.373288) (xy 215.66427 -48.371251) (xy 215.719707 -48.377351) (xy 215.773664 -48.391457)
			(xy 215.824993 -48.413269) (xy 215.872599 -48.442323) (xy 215.915467 -48.477998) (xy 215.952684 -48.519535)
			(xy 215.983457 -48.566048) (xy 216.007129 -48.616545) (xy 216.023197 -48.669952) (xy 216.031317 -48.725128)
			(xy 216.031826 -48.753014) (xy 216.031317 -48.7809) (xy 216.023197 -48.836076) (xy 216.020753 -48.8442)
			(xy 216.287348 -48.8442) (xy 216.291419 -48.788578) (xy 216.303545 -48.734141) (xy 216.323468 -48.68205)
			(xy 216.350764 -48.633415) (xy 216.38485 -48.589272) (xy 216.424999 -48.550563) (xy 216.470357 -48.518112)
			(xy 216.519957 -48.492611) (xy 216.572741 -48.474604) (xy 216.627584 -48.464474) (xy 216.683318 -48.462437)
			(xy 216.738755 -48.468537) (xy 216.792712 -48.482643) (xy 216.844041 -48.504455) (xy 216.891647 -48.533509)
			(xy 216.934515 -48.569184) (xy 216.971732 -48.610721) (xy 217.002505 -48.657234) (xy 217.026177 -48.707731)
			(xy 217.042245 -48.761138) (xy 217.050365 -48.816314) (xy 217.050874 -48.8442) (xy 217.050365 -48.872086)
			(xy 217.047367 -48.89246) (xy 217.314016 -48.89246) (xy 217.318087 -48.836838) (xy 217.330213 -48.782401)
			(xy 217.350136 -48.73031) (xy 217.377432 -48.681675) (xy 217.411518 -48.637532) (xy 217.451667 -48.598823)
			(xy 217.497025 -48.566372) (xy 217.546625 -48.540871) (xy 217.599409 -48.522864) (xy 217.654252 -48.512734)
			(xy 217.709986 -48.510697) (xy 217.765423 -48.516797) (xy 217.81938 -48.530903) (xy 217.870709 -48.552715)
			(xy 217.918315 -48.581769) (xy 217.961183 -48.617444) (xy 217.9984 -48.658981) (xy 218.029173 -48.705494)
			(xy 218.052845 -48.755991) (xy 218.068913 -48.809398) (xy 218.077033 -48.864574) (xy 218.077542 -48.89246)
			(xy 218.077033 -48.920346) (xy 218.068913 -48.975522) (xy 218.052845 -49.028929) (xy 218.029173 -49.079426)
			(xy 217.9984 -49.125939) (xy 217.961183 -49.167476) (xy 217.918315 -49.203151) (xy 217.870709 -49.232205)
			(xy 217.81938 -49.254017) (xy 217.765423 -49.268123) (xy 217.709986 -49.274223) (xy 217.654252 -49.272186)
			(xy 217.599409 -49.262056) (xy 217.546625 -49.244049) (xy 217.497025 -49.218548) (xy 217.451667 -49.186097)
			(xy 217.411518 -49.147388) (xy 217.377432 -49.103245) (xy 217.350136 -49.05461) (xy 217.330213 -49.002519)
			(xy 217.318087 -48.948082) (xy 217.314016 -48.89246) (xy 217.047367 -48.89246) (xy 217.042245 -48.927262)
			(xy 217.026177 -48.980669) (xy 217.002505 -49.031166) (xy 216.971732 -49.077679) (xy 216.934515 -49.119216)
			(xy 216.891647 -49.154891) (xy 216.844041 -49.183945) (xy 216.792712 -49.205757) (xy 216.738755 -49.219863)
			(xy 216.683318 -49.225963) (xy 216.627584 -49.223926) (xy 216.572741 -49.213796) (xy 216.519957 -49.195789)
			(xy 216.470357 -49.170288) (xy 216.424999 -49.137837) (xy 216.38485 -49.099128) (xy 216.350764 -49.054985)
			(xy 216.323468 -49.00635) (xy 216.303545 -48.954259) (xy 216.291419 -48.899822) (xy 216.287348 -48.8442)
			(xy 216.020753 -48.8442) (xy 216.007129 -48.889483) (xy 215.983457 -48.93998) (xy 215.952684 -48.986493)
			(xy 215.915467 -49.02803) (xy 215.872599 -49.063705) (xy 215.824993 -49.092759) (xy 215.773664 -49.114571)
			(xy 215.719707 -49.128677) (xy 215.66427 -49.134777) (xy 215.608536 -49.13274) (xy 215.553693 -49.12261)
			(xy 215.500909 -49.104603) (xy 215.451309 -49.079102) (xy 215.405951 -49.046651) (xy 215.365802 -49.007942)
			(xy 215.331716 -48.963799) (xy 215.30442 -48.915164) (xy 215.284497 -48.863073) (xy 215.272371 -48.808636)
			(xy 215.2683 -48.753014) (xy 207.369129 -48.753014) (xy 207.417162 -49.213516) (xy 207.419702 -49.224946)
			(xy 207.622902 -49.81067) (xy 207.637126 -49.853106) (xy 207.65875 -49.939962) (xy 207.672422 -50.028418)
			(xy 207.675734 -50.073052) (xy 207.68437 -50.210212) (xy 207.735139 -51.019456) (xy 218.849446 -51.019456)
			(xy 218.853517 -50.963834) (xy 218.865643 -50.909397) (xy 218.885566 -50.857306) (xy 218.912862 -50.808671)
			(xy 218.946948 -50.764528) (xy 218.987097 -50.725819) (xy 219.032455 -50.693368) (xy 219.082055 -50.667867)
			(xy 219.134839 -50.64986) (xy 219.189682 -50.63973) (xy 219.245416 -50.637693) (xy 219.300853 -50.643793)
			(xy 219.35481 -50.657899) (xy 219.406139 -50.679711) (xy 219.453745 -50.708765) (xy 219.496613 -50.74444)
			(xy 219.53383 -50.785977) (xy 219.564603 -50.83249) (xy 219.588275 -50.882987) (xy 219.604343 -50.936394)
			(xy 219.612463 -50.99157) (xy 219.612972 -51.019456) (xy 219.612463 -51.047342) (xy 219.604343 -51.102518)
			(xy 219.588275 -51.155925) (xy 219.564603 -51.206422) (xy 219.53383 -51.252935) (xy 219.496613 -51.294472)
			(xy 219.453745 -51.330147) (xy 219.406139 -51.359201) (xy 219.35481 -51.381013) (xy 219.300853 -51.395119)
			(xy 219.245416 -51.401219) (xy 219.189682 -51.399182) (xy 219.134839 -51.389052) (xy 219.082055 -51.371045)
			(xy 219.032455 -51.345544) (xy 218.987097 -51.313093) (xy 218.946948 -51.274384) (xy 218.912862 -51.230241)
			(xy 218.885566 -51.181606) (xy 218.865643 -51.129515) (xy 218.853517 -51.075078) (xy 218.849446 -51.019456)
			(xy 207.735139 -51.019456) (xy 207.81899 -52.356004) (xy 207.820514 -52.36591) (xy 207.822969 -52.373763)
			(xy 207.832046 -52.387478) (xy 207.838294 -52.392834) (xy 207.859122 -52.409344) (xy 207.869028 -52.415694)
			(xy 207.87703 -52.419079) (xy 207.894309 -52.420785) (xy 207.90281 -52.418996) (xy 207.927196 -52.413426)
			(xy 207.976859 -52.407443) (xy 208.00187 -52.407058) (xy 208.002124 -52.407058) (xy 208.032077 -52.407594)
			(xy 208.091373 -52.416123) (xy 208.148852 -52.433003) (xy 208.203344 -52.457892) (xy 208.253739 -52.490282)
			(xy 208.299011 -52.529515) (xy 208.338239 -52.57479) (xy 208.370625 -52.625188) (xy 208.395509 -52.679682)
			(xy 208.412385 -52.737162) (xy 208.420909 -52.796459) (xy 208.421478 -52.826412) (xy 208.42103 -52.853854)
			(xy 208.41387 -52.908269) (xy 208.399675 -52.961286) (xy 208.378687 -53.011998) (xy 208.351264 -53.05954)
			(xy 208.317874 -53.1031) (xy 208.298796 -53.12283) (xy 208.29397 -53.12791) (xy 208.278476 -53.164232)
			(xy 208.278476 -53.178964) (xy 208.278842 -53.186999) (xy 208.283893 -53.202261) (xy 208.288382 -53.208936)
			(xy 208.290922 -53.211984) (xy 208.308323 -53.232855) (xy 208.33765 -53.2786) (xy 208.360177 -53.328049)
			(xy 208.375446 -53.380199) (xy 208.383148 -53.433989) (xy 208.383632 -53.461158) (xy 208.383632 -53.461412)
			(xy 208.383206 -53.486923) (xy 208.37641 -53.53749) (xy 208.36294 -53.586701) (xy 208.343036 -53.633681)
			(xy 208.317052 -53.67759) (xy 208.30159 -53.697886) (xy 208.29905 -53.700934) (xy 208.298034 -53.702458)
			(xy 208.294732 -53.709062) (xy 208.292387 -53.714284) (xy 208.289819 -53.725438) (xy 208.289652 -53.73116)
			(xy 208.289652 -53.763164) (xy 208.278476 -53.763164) (xy 208.278476 -53.813964) (xy 208.27881 -53.822568)
			(xy 208.28452 -53.838801) (xy 208.289652 -53.845714) (xy 208.290922 -53.847238) (xy 208.308316 -53.868115)
			(xy 208.337636 -53.913864) (xy 208.360164 -53.963312) (xy 208.375446 -54.015457) (xy 208.383171 -54.069243)
			(xy 208.383632 -54.096412) (xy 208.383206 -54.121923) (xy 208.37641 -54.17249) (xy 208.36294 -54.221701)
			(xy 208.343036 -54.268681) (xy 208.317052 -54.31259) (xy 208.30159 -54.332886) (xy 208.29905 -54.335934)
			(xy 208.298034 -54.337458) (xy 208.294732 -54.344062) (xy 208.292387 -54.349284) (xy 208.289819 -54.360438)
			(xy 208.289652 -54.36616) (xy 208.289652 -54.398164) (xy 208.278476 -54.398164) (xy 208.278476 -54.448964)
			(xy 208.27881 -54.457568) (xy 208.28452 -54.473801) (xy 208.289652 -54.480714) (xy 208.290922 -54.482238)
			(xy 208.308316 -54.503115) (xy 208.337636 -54.548864) (xy 208.360164 -54.598312) (xy 208.375446 -54.650457)
			(xy 208.383171 -54.704243) (xy 208.383632 -54.731412) (xy 208.383079 -54.760555) (xy 208.378376 -54.791102)
			(xy 210.27644 -54.791102) (xy 210.276897 -54.763731) (xy 210.284716 -54.709552) (xy 210.300206 -54.657048)
			(xy 210.32305 -54.607301) (xy 210.352777 -54.561335) (xy 210.37042 -54.540404) (xy 210.370674 -54.54015)
			(xy 210.376254 -54.53306) (xy 210.382503 -54.516145) (xy 210.382866 -54.50713) (xy 210.382866 -54.440074)
			(xy 210.382529 -54.431055) (xy 210.376268 -54.414138) (xy 210.370674 -54.407054) (xy 210.37042 -54.407054)
			(xy 210.37042 -54.4068) (xy 210.352782 -54.385866) (xy 210.323057 -54.339898) (xy 210.300212 -54.290152)
			(xy 210.284716 -54.23765) (xy 210.276887 -54.183472) (xy 210.276887 -54.128731) (xy 210.284715 -54.074553)
			(xy 210.300211 -54.022051) (xy 210.323056 -53.972305) (xy 210.35278 -53.926337) (xy 210.37042 -53.905404)
			(xy 210.370674 -53.90515) (xy 210.376254 -53.89806) (xy 210.382503 -53.881145) (xy 210.382866 -53.87213)
			(xy 210.382866 -53.805074) (xy 210.382529 -53.796055) (xy 210.376268 -53.779138) (xy 210.370674 -53.772054)
			(xy 210.37042 -53.772054) (xy 210.37042 -53.7718) (xy 210.352782 -53.750866) (xy 210.323057 -53.704898)
			(xy 210.300212 -53.655152) (xy 210.284716 -53.60265) (xy 210.276887 -53.548472) (xy 210.276887 -53.493731)
			(xy 210.284715 -53.439553) (xy 210.300211 -53.387051) (xy 210.323056 -53.337305) (xy 210.35278 -53.291337)
			(xy 210.37042 -53.270404) (xy 210.370674 -53.27015) (xy 210.376254 -53.26306) (xy 210.382503 -53.246145)
			(xy 210.382866 -53.23713) (xy 210.382866 -53.170074) (xy 210.382529 -53.161055) (xy 210.376268 -53.144138)
			(xy 210.370674 -53.137054) (xy 210.37042 -53.137054) (xy 210.37042 -53.1368) (xy 210.352771 -53.115876)
			(xy 210.32306 -53.069901) (xy 210.300225 -53.020152) (xy 210.284737 -52.967649) (xy 210.276912 -52.913472)
			(xy 210.27644 -52.886102) (xy 210.276926 -52.858851) (xy 210.284682 -52.804903) (xy 210.300037 -52.752608)
			(xy 210.322679 -52.703031) (xy 210.352145 -52.657181) (xy 210.387836 -52.61599) (xy 210.429027 -52.580299)
			(xy 210.474877 -52.550833) (xy 210.524454 -52.528191) (xy 210.576749 -52.512836) (xy 210.630697 -52.50508)
			(xy 210.685199 -52.50508) (xy 210.739147 -52.512836) (xy 210.791442 -52.528191) (xy 210.830551 -52.546052)
			(xy 215.779573 -52.546052) (xy 215.779573 -52.491548) (xy 215.78733 -52.4376) (xy 215.802686 -52.385304)
			(xy 215.825327 -52.335726) (xy 215.854794 -52.289875) (xy 215.890487 -52.248684) (xy 215.931678 -52.212992)
			(xy 215.977529 -52.183525) (xy 216.027108 -52.160884) (xy 216.079403 -52.145529) (xy 216.133352 -52.137773)
			(xy 216.160604 -52.13731) (xy 216.187974 -52.137771) (xy 216.242154 -52.14559) (xy 216.294657 -52.16108)
			(xy 216.344404 -52.183923) (xy 216.39037 -52.213648) (xy 216.411302 -52.23129) (xy 216.411556 -52.231544)
			(xy 216.418647 -52.237124) (xy 216.435561 -52.243373) (xy 216.444576 -52.243736) (xy 216.511632 -52.243736)
			(xy 216.520649 -52.243387) (xy 216.537566 -52.237133) (xy 216.544652 -52.231544) (xy 216.544652 -52.23129)
			(xy 216.544906 -52.23129) (xy 216.565839 -52.213649) (xy 216.611807 -52.183925) (xy 216.661553 -52.161079)
			(xy 216.714055 -52.145583) (xy 216.768233 -52.137754) (xy 216.822975 -52.137754) (xy 216.877153 -52.145583)
			(xy 216.929655 -52.161079) (xy 216.979401 -52.183925) (xy 217.025369 -52.213649) (xy 217.046302 -52.23129)
			(xy 217.046556 -52.231544) (xy 217.053647 -52.237124) (xy 217.070561 -52.243373) (xy 217.079576 -52.243736)
			(xy 217.146632 -52.243736) (xy 217.155649 -52.243387) (xy 217.172566 -52.237133) (xy 217.179652 -52.231544)
			(xy 217.179652 -52.23129) (xy 217.179906 -52.23129) (xy 217.200824 -52.213633) (xy 217.246801 -52.183924)
			(xy 217.296552 -52.161092) (xy 217.349056 -52.145605) (xy 217.403234 -52.137782) (xy 217.430604 -52.13731)
			(xy 217.457856 -52.13776) (xy 217.511806 -52.145517) (xy 217.564103 -52.160874) (xy 217.613682 -52.183516)
			(xy 217.659534 -52.212984) (xy 217.700726 -52.248677) (xy 217.736419 -52.289869) (xy 217.765886 -52.335722)
			(xy 217.788528 -52.385301) (xy 217.803883 -52.437598) (xy 217.81164 -52.491548) (xy 217.81164 -52.546052)
			(xy 217.805695 -52.587398) (xy 218.855288 -52.587398) (xy 218.859359 -52.531776) (xy 218.871485 -52.477339)
			(xy 218.891408 -52.425248) (xy 218.918704 -52.376613) (xy 218.95279 -52.33247) (xy 218.992939 -52.293761)
			(xy 219.038297 -52.26131) (xy 219.087897 -52.235809) (xy 219.140681 -52.217802) (xy 219.195524 -52.207672)
			(xy 219.251258 -52.205635) (xy 219.306695 -52.211735) (xy 219.360652 -52.225841) (xy 219.411981 -52.247653)
			(xy 219.459587 -52.276707) (xy 219.502455 -52.312382) (xy 219.539672 -52.353919) (xy 219.570445 -52.400432)
			(xy 219.594117 -52.450929) (xy 219.610185 -52.504336) (xy 219.618305 -52.559512) (xy 219.618814 -52.587398)
			(xy 219.618305 -52.615284) (xy 219.610185 -52.67046) (xy 219.594117 -52.723867) (xy 219.570445 -52.774364)
			(xy 219.539672 -52.820877) (xy 219.502455 -52.862414) (xy 219.459587 -52.898089) (xy 219.411981 -52.927143)
			(xy 219.360652 -52.948955) (xy 219.306695 -52.963061) (xy 219.251258 -52.969161) (xy 219.195524 -52.967124)
			(xy 219.140681 -52.956994) (xy 219.087897 -52.938987) (xy 219.038297 -52.913486) (xy 218.992939 -52.881035)
			(xy 218.95279 -52.842326) (xy 218.918704 -52.798183) (xy 218.891408 -52.749548) (xy 218.871485 -52.697457)
			(xy 218.859359 -52.64302) (xy 218.855288 -52.587398) (xy 217.805695 -52.587398) (xy 217.803883 -52.600002)
			(xy 217.788528 -52.652299) (xy 217.765886 -52.701878) (xy 217.736419 -52.747731) (xy 217.700726 -52.788923)
			(xy 217.659534 -52.824616) (xy 217.613682 -52.854084) (xy 217.564103 -52.876726) (xy 217.511806 -52.892083)
			(xy 217.457856 -52.89984) (xy 217.430604 -52.900326) (xy 217.403233 -52.899876) (xy 217.349053 -52.892057)
			(xy 217.296549 -52.876565) (xy 217.246802 -52.853719) (xy 217.200836 -52.82399) (xy 217.179906 -52.806346)
			(xy 217.179652 -52.806092) (xy 217.172555 -52.80052) (xy 217.155646 -52.794265) (xy 217.146632 -52.7939)
			(xy 217.079576 -52.7939) (xy 217.070558 -52.794246) (xy 217.053641 -52.800501) (xy 217.046556 -52.806092)
			(xy 217.046302 -52.806346) (xy 217.025369 -52.823987) (xy 216.979401 -52.853711) (xy 216.929655 -52.876557)
			(xy 216.877153 -52.892053) (xy 216.822975 -52.899882) (xy 216.768233 -52.899882) (xy 216.714055 -52.892053)
			(xy 216.661553 -52.876557) (xy 216.611807 -52.853711) (xy 216.565839 -52.823987) (xy 216.544906 -52.806346)
			(xy 216.544652 -52.806092) (xy 216.537555 -52.80052) (xy 216.520646 -52.794265) (xy 216.511632 -52.7939)
			(xy 216.444576 -52.7939) (xy 216.435558 -52.794246) (xy 216.418641 -52.800501) (xy 216.411556 -52.806092)
			(xy 216.411556 -52.806346) (xy 216.411302 -52.806346) (xy 216.390373 -52.823989) (xy 216.3444 -52.853702)
			(xy 216.294652 -52.876538) (xy 216.24215 -52.892028) (xy 216.187974 -52.899854) (xy 216.160604 -52.900326)
			(xy 216.133352 -52.899827) (xy 216.079403 -52.892071) (xy 216.027108 -52.876716) (xy 215.977529 -52.854075)
			(xy 215.931678 -52.824608) (xy 215.890487 -52.788916) (xy 215.854794 -52.747725) (xy 215.825327 -52.701874)
			(xy 215.802686 -52.652296) (xy 215.78733 -52.6) (xy 215.779573 -52.546052) (xy 210.830551 -52.546052)
			(xy 210.841019 -52.550833) (xy 210.886869 -52.580299) (xy 210.92806 -52.61599) (xy 210.963751 -52.657181)
			(xy 210.993217 -52.703031) (xy 211.015859 -52.752608) (xy 211.031214 -52.804903) (xy 211.03897 -52.858851)
			(xy 211.039456 -52.886102) (xy 211.039002 -52.913473) (xy 211.031183 -52.967653) (xy 211.015692 -53.020156)
			(xy 210.992847 -53.069903) (xy 210.963119 -53.115869) (xy 210.945476 -53.1368) (xy 210.945222 -53.137054)
			(xy 210.939639 -53.144143) (xy 210.933392 -53.161058) (xy 210.93303 -53.170074) (xy 210.93303 -53.23713)
			(xy 210.933366 -53.246149) (xy 210.939627 -53.263066) (xy 210.945222 -53.27015) (xy 210.945476 -53.27015)
			(xy 210.945476 -53.270404) (xy 210.963119 -53.291335) (xy 210.992843 -53.337303) (xy 211.015688 -53.38705)
			(xy 211.031184 -53.439552) (xy 211.039012 -53.493731) (xy 211.039012 -53.548472) (xy 211.031183 -53.602651)
			(xy 211.015687 -53.655153) (xy 210.992842 -53.704899) (xy 210.963117 -53.750867) (xy 210.946546 -53.77053)
			(xy 211.310728 -53.77053) (xy 211.311257 -53.741613) (xy 211.319983 -53.684442) (xy 211.337238 -53.629243)
			(xy 211.362627 -53.577281) (xy 211.395569 -53.529747) (xy 211.435309 -53.48773) (xy 211.457794 -53.46954)
			(xy 211.466572 -53.461905) (xy 211.476772 -53.441025) (xy 211.477352 -53.429408) (xy 211.477352 -53.349652)
			(xy 211.476843 -53.338016) (xy 211.466635 -53.317106) (xy 211.457794 -53.30952) (xy 211.435319 -53.291319)
			(xy 211.395583 -53.249301) (xy 211.362644 -53.201768) (xy 211.337254 -53.149809) (xy 211.319996 -53.094613)
			(xy 211.311264 -53.037445) (xy 211.310728 -53.00853) (xy 211.311183 -52.981276) (xy 211.318937 -52.927323)
			(xy 211.334291 -52.875023) (xy 211.356933 -52.825441) (xy 211.386401 -52.779586) (xy 211.422096 -52.738392)
			(xy 211.46329 -52.702697) (xy 211.509146 -52.67323) (xy 211.558729 -52.650589) (xy 211.611029 -52.635236)
			(xy 211.664982 -52.627483) (xy 211.692236 -52.627022) (xy 211.718551 -52.627458) (xy 211.770681 -52.634699)
			(xy 211.821325 -52.649023) (xy 211.869524 -52.670162) (xy 211.914367 -52.697713) (xy 211.955005 -52.731158)
			(xy 211.97316 -52.750212) (xy 211.980693 -52.7576) (xy 211.999964 -52.766132) (xy 212.010498 -52.766722)
			(xy 212.085174 -52.766722) (xy 212.095723 -52.766186) (xy 212.115018 -52.757655) (xy 212.122512 -52.750212)
			(xy 212.140671 -52.73116) (xy 212.1813 -52.697702) (xy 212.226139 -52.670142) (xy 212.274339 -52.649003)
			(xy 212.324986 -52.634685) (xy 212.37712 -52.62746) (xy 212.403436 -52.627022) (xy 212.43069 -52.627444)
			(xy 212.484641 -52.635207) (xy 212.536939 -52.650568) (xy 212.586518 -52.673215) (xy 212.63237 -52.702688)
			(xy 212.67356 -52.738386) (xy 212.709251 -52.779583) (xy 212.738716 -52.82544) (xy 212.761355 -52.875023)
			(xy 212.776707 -52.927324) (xy 212.78446 -52.981276) (xy 212.784944 -53.00853) (xy 212.784481 -53.036197)
			(xy 212.776476 -53.09095) (xy 212.760653 -53.143974) (xy 212.737342 -53.194159) (xy 212.707033 -53.240454)
			(xy 212.670359 -53.28189) (xy 212.628089 -53.317599) (xy 212.604858 -53.332634) (xy 212.595169 -53.339256)
			(xy 212.58273 -53.359128) (xy 212.580982 -53.370734) (xy 212.573108 -53.450744) (xy 212.572469 -53.462382)
			(xy 212.580556 -53.484219) (xy 212.588602 -53.492654) (xy 212.588856 -53.492908) (xy 212.607415 -53.511011)
			(xy 212.639997 -53.551337) (xy 212.666814 -53.595707) (xy 212.687371 -53.643301) (xy 212.701289 -53.693242)
			(xy 212.70831 -53.744608) (xy 212.708744 -53.77053) (xy 212.70825 -53.79778) (xy 212.700491 -53.851726)
			(xy 212.685133 -53.904018) (xy 212.662491 -53.953593) (xy 212.633025 -53.999442) (xy 212.597335 -54.040631)
			(xy 212.556147 -54.076322) (xy 212.510299 -54.105789) (xy 212.460724 -54.128431) (xy 212.408432 -54.143789)
			(xy 212.354486 -54.15155) (xy 212.327236 -54.152038) (xy 212.299866 -54.151566) (xy 212.245686 -54.143752)
			(xy 212.193183 -54.128265) (xy 212.143436 -54.105424) (xy 212.097469 -54.0757) (xy 212.076538 -54.058058)
			(xy 212.076284 -54.057804) (xy 212.069206 -54.052205) (xy 212.052283 -54.045966) (xy 212.043264 -54.045612)
			(xy 211.976208 -54.045612) (xy 211.967191 -54.04597) (xy 211.950274 -54.052217) (xy 211.943188 -54.057804)
			(xy 211.943188 -54.058058) (xy 211.942934 -54.058058) (xy 211.921995 -54.075688) (xy 211.876024 -54.105403)
			(xy 211.826279 -54.128241) (xy 211.77378 -54.143734) (xy 211.719605 -54.151564) (xy 211.692236 -54.152038)
			(xy 211.664985 -54.151511) (xy 211.611038 -54.14376) (xy 211.558743 -54.12841) (xy 211.509165 -54.105774)
			(xy 211.463314 -54.076312) (xy 211.422121 -54.040625) (xy 211.386427 -53.999439) (xy 211.356958 -53.953593)
			(xy 211.334313 -53.904018) (xy 211.318954 -53.851726) (xy 211.311193 -53.797781) (xy 211.310728 -53.77053)
			(xy 210.946546 -53.77053) (xy 210.945476 -53.7718) (xy 210.945222 -53.772054) (xy 210.939639 -53.779143)
			(xy 210.933392 -53.796058) (xy 210.93303 -53.805074) (xy 210.93303 -53.87213) (xy 210.933366 -53.881149)
			(xy 210.939627 -53.898066) (xy 210.945222 -53.90515) (xy 210.945476 -53.90515) (xy 210.945476 -53.905404)
			(xy 210.963119 -53.926335) (xy 210.992843 -53.972303) (xy 211.015688 -54.02205) (xy 211.031184 -54.074552)
			(xy 211.039012 -54.128731) (xy 211.039012 -54.183472) (xy 211.031183 -54.237651) (xy 211.015687 -54.290153)
			(xy 211.001895 -54.320186) (xy 213.23046 -54.320186) (xy 213.230903 -54.292815) (xy 213.238724 -54.238634)
			(xy 213.254218 -54.18613) (xy 213.277065 -54.136384) (xy 213.306796 -54.090418) (xy 213.32444 -54.069488)
			(xy 213.324694 -54.069234) (xy 213.330272 -54.062141) (xy 213.336524 -54.045229) (xy 213.336886 -54.036214)
			(xy 213.336886 -53.969158) (xy 213.336504 -53.960144) (xy 213.330274 -53.943226) (xy 213.324694 -53.936138)
			(xy 213.32444 -53.936138) (xy 213.32444 -53.935884) (xy 213.306833 -53.914926) (xy 213.277115 -53.868961)
			(xy 213.254272 -53.81922) (xy 213.238774 -53.766725) (xy 213.230938 -53.712553) (xy 213.23046 -53.685186)
			(xy 213.230946 -53.657935) (xy 213.238702 -53.603987) (xy 213.254057 -53.551692) (xy 213.276699 -53.502115)
			(xy 213.306165 -53.456265) (xy 213.341856 -53.415074) (xy 213.383047 -53.379383) (xy 213.428897 -53.349917)
			(xy 213.478474 -53.327275) (xy 213.530769 -53.31192) (xy 213.584717 -53.304164) (xy 213.639219 -53.304164)
			(xy 213.693167 -53.31192) (xy 213.745462 -53.327275) (xy 213.795039 -53.349917) (xy 213.840889 -53.379383)
			(xy 213.88208 -53.415074) (xy 213.917771 -53.456265) (xy 213.947237 -53.502115) (xy 213.969879 -53.551692)
			(xy 213.985234 -53.603987) (xy 213.99299 -53.657935) (xy 213.993476 -53.685186) (xy 213.993008 -53.712556)
			(xy 213.985191 -53.766735) (xy 213.969703 -53.819239) (xy 213.946862 -53.868986) (xy 213.917137 -53.914952)
			(xy 213.899496 -53.935884) (xy 213.899242 -53.936138) (xy 213.893668 -53.943233) (xy 213.887415 -53.960144)
			(xy 213.88705 -53.969158) (xy 213.88705 -54.036214) (xy 213.88739 -54.045233) (xy 213.893648 -54.06215)
			(xy 213.899242 -54.069234) (xy 213.899496 -54.069234) (xy 213.899496 -54.069488) (xy 213.917142 -54.090414)
			(xy 213.946853 -54.136389) (xy 213.969688 -54.186138) (xy 213.985177 -54.23864) (xy 213.993003 -54.292816)
			(xy 213.993476 -54.320186) (xy 213.99299 -54.347437) (xy 213.985234 -54.401385) (xy 213.969879 -54.45368)
			(xy 213.947237 -54.503257) (xy 213.917771 -54.549107) (xy 213.88208 -54.590298) (xy 213.840889 -54.625989)
			(xy 213.795039 -54.655455) (xy 213.745462 -54.678097) (xy 213.693167 -54.693452) (xy 213.639219 -54.701208)
			(xy 213.584717 -54.701208) (xy 213.530769 -54.693452) (xy 213.478474 -54.678097) (xy 213.428897 -54.655455)
			(xy 213.383047 -54.625989) (xy 213.341856 -54.590298) (xy 213.306165 -54.549107) (xy 213.276699 -54.503257)
			(xy 213.254057 -54.45368) (xy 213.238702 -54.401385) (xy 213.230946 -54.347437) (xy 213.23046 -54.320186)
			(xy 211.001895 -54.320186) (xy 210.992842 -54.339899) (xy 210.963117 -54.385867) (xy 210.945476 -54.4068)
			(xy 210.945222 -54.407054) (xy 210.939639 -54.414143) (xy 210.933392 -54.431058) (xy 210.93303 -54.440074)
			(xy 210.93303 -54.50713) (xy 210.933366 -54.516149) (xy 210.939627 -54.533066) (xy 210.945222 -54.54015)
			(xy 210.945476 -54.54015) (xy 210.945476 -54.540404) (xy 210.963127 -54.561327) (xy 210.992838 -54.607302)
			(xy 211.015672 -54.657052) (xy 211.03116 -54.709554) (xy 211.038984 -54.763732) (xy 211.039101 -54.770528)
			(xy 214.171022 -54.770528) (xy 214.171499 -54.743158) (xy 214.179313 -54.688979) (xy 214.1948 -54.636476)
			(xy 214.217639 -54.586729) (xy 214.247362 -54.540762) (xy 214.265002 -54.51983) (xy 214.265256 -54.519576)
			(xy 214.270865 -54.512505) (xy 214.277097 -54.495576) (xy 214.277448 -54.486556) (xy 214.277448 -54.4195)
			(xy 214.277102 -54.410482) (xy 214.270848 -54.393564) (xy 214.265256 -54.38648) (xy 214.265002 -54.38648)
			(xy 214.265002 -54.386226) (xy 214.247362 -54.365295) (xy 214.21765 -54.319322) (xy 214.194814 -54.269574)
			(xy 214.179324 -54.217073) (xy 214.171496 -54.162897) (xy 214.171022 -54.135528) (xy 214.171508 -54.108277)
			(xy 214.179264 -54.054329) (xy 214.194619 -54.002034) (xy 214.217261 -53.952457) (xy 214.246727 -53.906607)
			(xy 214.282418 -53.865416) (xy 214.323609 -53.829725) (xy 214.369459 -53.800259) (xy 214.419036 -53.777617)
			(xy 214.471331 -53.762262) (xy 214.525279 -53.754506) (xy 214.579781 -53.754506) (xy 214.633729 -53.762262)
			(xy 214.686024 -53.777617) (xy 214.735601 -53.800259) (xy 214.781451 -53.829725) (xy 214.822642 -53.865416)
			(xy 214.858333 -53.906607) (xy 214.887799 -53.952457) (xy 214.892874 -53.96357) (xy 218.872052 -53.96357)
			(xy 218.876123 -53.907948) (xy 218.888249 -53.853511) (xy 218.908172 -53.80142) (xy 218.935468 -53.752785)
			(xy 218.969554 -53.708642) (xy 219.009703 -53.669933) (xy 219.055061 -53.637482) (xy 219.104661 -53.611981)
			(xy 219.157445 -53.593974) (xy 219.212288 -53.583844) (xy 219.268022 -53.581807) (xy 219.323459 -53.587907)
			(xy 219.377416 -53.602013) (xy 219.428745 -53.623825) (xy 219.476351 -53.652879) (xy 219.519219 -53.688554)
			(xy 219.556436 -53.730091) (xy 219.587209 -53.776604) (xy 219.610881 -53.827101) (xy 219.626949 -53.880508)
			(xy 219.635069 -53.935684) (xy 219.635578 -53.96357) (xy 219.635069 -53.991456) (xy 219.626949 -54.046632)
			(xy 219.610881 -54.100039) (xy 219.587209 -54.150536) (xy 219.556436 -54.197049) (xy 219.519219 -54.238586)
			(xy 219.476351 -54.274261) (xy 219.428745 -54.303315) (xy 219.377416 -54.325127) (xy 219.323459 -54.339233)
			(xy 219.268022 -54.345333) (xy 219.212288 -54.343296) (xy 219.157445 -54.333166) (xy 219.104661 -54.315159)
			(xy 219.055061 -54.289658) (xy 219.009703 -54.257207) (xy 218.969554 -54.218498) (xy 218.935468 -54.174355)
			(xy 218.908172 -54.12572) (xy 218.888249 -54.073629) (xy 218.876123 -54.019192) (xy 218.872052 -53.96357)
			(xy 214.892874 -53.96357) (xy 214.910441 -54.002034) (xy 214.925796 -54.054329) (xy 214.933552 -54.108277)
			(xy 214.934038 -54.135528) (xy 214.933603 -54.1629) (xy 214.92578 -54.217081) (xy 214.910285 -54.269585)
			(xy 214.887436 -54.319331) (xy 214.857703 -54.365296) (xy 214.840058 -54.386226) (xy 214.839804 -54.38648)
			(xy 214.83422 -54.393568) (xy 214.827972 -54.410484) (xy 214.827612 -54.4195) (xy 214.827612 -54.486556)
			(xy 214.827988 -54.495571) (xy 214.834222 -54.512488) (xy 214.839804 -54.519576) (xy 214.840058 -54.519576)
			(xy 214.840058 -54.51983) (xy 214.857671 -54.540783) (xy 214.887388 -54.586749) (xy 214.91023 -54.636492)
			(xy 214.925727 -54.688988) (xy 214.933561 -54.74316) (xy 214.934038 -54.770528) (xy 214.933552 -54.797779)
			(xy 214.925796 -54.851727) (xy 214.910441 -54.904022) (xy 214.887799 -54.953599) (xy 214.858333 -54.999449)
			(xy 214.822642 -55.04064) (xy 214.781451 -55.076331) (xy 214.735601 -55.105797) (xy 214.686024 -55.128439)
			(xy 214.633729 -55.143794) (xy 214.579781 -55.15155) (xy 214.525279 -55.15155) (xy 214.471331 -55.143794)
			(xy 214.419036 -55.128439) (xy 214.369459 -55.105797) (xy 214.323609 -55.076331) (xy 214.282418 -55.04064)
			(xy 214.246727 -54.999449) (xy 214.217261 -54.953599) (xy 214.194619 -54.904022) (xy 214.179264 -54.851727)
			(xy 214.171508 -54.797779) (xy 214.171022 -54.770528) (xy 211.039101 -54.770528) (xy 211.039456 -54.791102)
			(xy 211.03897 -54.818353) (xy 211.031214 -54.872301) (xy 211.015859 -54.924596) (xy 210.993217 -54.974173)
			(xy 210.963751 -55.020023) (xy 210.92806 -55.061214) (xy 210.886869 -55.096905) (xy 210.841019 -55.126371)
			(xy 210.791442 -55.149013) (xy 210.739147 -55.164368) (xy 210.685199 -55.172124) (xy 210.630697 -55.172124)
			(xy 210.576749 -55.164368) (xy 210.524454 -55.149013) (xy 210.474877 -55.126371) (xy 210.429027 -55.096905)
			(xy 210.387836 -55.061214) (xy 210.352145 -55.020023) (xy 210.322679 -54.974173) (xy 210.300037 -54.924596)
			(xy 210.284682 -54.872301) (xy 210.276926 -54.818353) (xy 210.27644 -54.791102) (xy 208.378376 -54.791102)
			(xy 208.374209 -54.818164) (xy 208.356678 -54.873752) (xy 208.330894 -54.926026) (xy 208.297457 -54.973768)
			(xy 208.257145 -55.015867) (xy 208.210898 -55.051344) (xy 208.159791 -55.079371) (xy 208.105016 -55.099296)
			(xy 208.076546 -55.105554) (xy 208.07426 -55.106062) (xy 208.065485 -55.108623) (xy 208.05041 -55.118941)
			(xy 208.039899 -55.133881) (xy 208.03528 -55.151555) (xy 208.035906 -55.160672) (xy 208.06664 -55.455058)
			(xy 208.094476 -55.722266) (xy 219.934026 -55.722266) (xy 219.938097 -55.666644) (xy 219.950223 -55.612207)
			(xy 219.970146 -55.560116) (xy 219.997442 -55.511481) (xy 220.031528 -55.467338) (xy 220.071677 -55.428629)
			(xy 220.117035 -55.396178) (xy 220.166635 -55.370677) (xy 220.219419 -55.35267) (xy 220.274262 -55.34254)
			(xy 220.329996 -55.340503) (xy 220.385433 -55.346603) (xy 220.43939 -55.360709) (xy 220.490719 -55.382521)
			(xy 220.538325 -55.411575) (xy 220.581193 -55.44725) (xy 220.61841 -55.488787) (xy 220.649183 -55.5353)
			(xy 220.672855 -55.585797) (xy 220.688923 -55.639204) (xy 220.697043 -55.69438) (xy 220.697552 -55.722266)
			(xy 220.697043 -55.750152) (xy 220.688923 -55.805328) (xy 220.672855 -55.858735) (xy 220.649183 -55.909232)
			(xy 220.61841 -55.955745) (xy 220.581193 -55.997282) (xy 220.538325 -56.032957) (xy 220.490719 -56.062011)
			(xy 220.43939 -56.083823) (xy 220.385433 -56.097929) (xy 220.329996 -56.104029) (xy 220.274262 -56.101992)
			(xy 220.219419 -56.091862) (xy 220.166635 -56.073855) (xy 220.117035 -56.048354) (xy 220.071677 -56.015903)
			(xy 220.031528 -55.977194) (xy 219.997442 -55.933051) (xy 219.970146 -55.884416) (xy 219.950223 -55.832325)
			(xy 219.938097 -55.777888) (xy 219.934026 -55.722266) (xy 208.094476 -55.722266) (xy 208.171288 -56.459628)
			(xy 208.17208 -56.465356) (xy 208.17594 -56.476254) (xy 208.178908 -56.481218) (xy 208.181702 -56.48579)
			(xy 208.190592 -56.494426) (xy 208.195926 -56.497474) (xy 208.220074 -56.51227) (xy 208.264111 -56.547879)
			(xy 208.302393 -56.589613) (xy 208.334077 -56.636552) (xy 208.358465 -56.687664) (xy 208.375021 -56.741822)
			(xy 208.38338 -56.797834) (xy 208.383886 -56.82615) (xy 208.383886 -56.826658) (xy 208.383378 -56.844438)
			(xy 208.382616 -56.85536) (xy 208.37995 -56.883702) (xy 208.367288 -56.939202) (xy 208.34653 -56.992208)
			(xy 208.340357 -57.002934) (xy 215.663526 -57.002934) (xy 215.664026 -56.974842) (xy 215.67225 -56.919265)
			(xy 215.688538 -56.865495) (xy 215.71254 -56.814696) (xy 215.743734 -56.767969) (xy 215.781447 -56.726325)
			(xy 215.824861 -56.690664) (xy 215.848692 -56.675782) (xy 215.857582 -56.670448) (xy 215.869774 -56.65343)
			(xy 215.890094 -56.560212) (xy 215.885776 -56.539638) (xy 215.879934 -56.531002) (xy 215.863937 -56.506936)
			(xy 215.838592 -56.455006) (xy 215.821366 -56.399848) (xy 215.81265 -56.342724) (xy 215.812116 -56.313832)
			(xy 215.812585 -56.286579) (xy 215.820338 -56.232627) (xy 215.835692 -56.180328) (xy 215.858332 -56.130746)
			(xy 215.887799 -56.084892) (xy 215.923492 -56.043698) (xy 215.964685 -56.008004) (xy 216.010539 -55.978536)
			(xy 216.06012 -55.955894) (xy 216.112419 -55.94054) (xy 216.166371 -55.932786) (xy 216.193624 -55.932324)
			(xy 216.220995 -55.93277) (xy 216.275175 -55.940592) (xy 216.327679 -55.956085) (xy 216.377425 -55.978932)
			(xy 216.423391 -56.008661) (xy 216.444322 -56.026304) (xy 216.444576 -56.026558) (xy 216.45166 -56.032148)
			(xy 216.468579 -56.038391) (xy 216.477596 -56.03875) (xy 216.544652 -56.03875) (xy 216.553668 -56.038381)
			(xy 216.570586 -56.032143) (xy 216.577672 -56.026558) (xy 216.577672 -56.026304) (xy 216.577926 -56.026304)
			(xy 216.598859 -56.008663) (xy 216.644827 -55.978939) (xy 216.694573 -55.956093) (xy 216.747075 -55.940597)
			(xy 216.801253 -55.932768) (xy 216.855995 -55.932768) (xy 216.910173 -55.940597) (xy 216.962675 -55.956093)
			(xy 217.012421 -55.978939) (xy 217.058389 -56.008663) (xy 217.079322 -56.026304) (xy 217.079576 -56.026558)
			(xy 217.08666 -56.032148) (xy 217.103579 -56.038391) (xy 217.112596 -56.03875) (xy 217.179652 -56.03875)
			(xy 217.188668 -56.038381) (xy 217.205586 -56.032143) (xy 217.212672 -56.026558) (xy 217.212672 -56.026304)
			(xy 217.212926 -56.026304) (xy 217.233876 -56.008687) (xy 217.279844 -55.978971) (xy 217.329587 -55.956131)
			(xy 217.382083 -55.940635) (xy 217.436256 -55.932801) (xy 217.463624 -55.932324) (xy 217.490876 -55.932747)
			(xy 217.544826 -55.940507) (xy 217.597122 -55.955866) (xy 217.646701 -55.97851) (xy 217.692552 -56.00798)
			(xy 217.733743 -56.043674) (xy 217.769435 -56.084867) (xy 217.798901 -56.13072) (xy 217.821542 -56.1803)
			(xy 217.836898 -56.232597) (xy 217.844654 -56.286548) (xy 217.844654 -56.297068) (xy 218.186506 -56.297068)
			(xy 218.190577 -56.241446) (xy 218.202703 -56.187009) (xy 218.222626 -56.134918) (xy 218.249922 -56.086283)
			(xy 218.284008 -56.04214) (xy 218.324157 -56.003431) (xy 218.369515 -55.97098) (xy 218.419115 -55.945479)
			(xy 218.471899 -55.927472) (xy 218.526742 -55.917342) (xy 218.582476 -55.915305) (xy 218.637913 -55.921405)
			(xy 218.69187 -55.935511) (xy 218.743199 -55.957323) (xy 218.790805 -55.986377) (xy 218.833673 -56.022052)
			(xy 218.87089 -56.063589) (xy 218.901663 -56.110102) (xy 218.925335 -56.160599) (xy 218.941403 -56.214006)
			(xy 218.949523 -56.269182) (xy 218.950032 -56.297068) (xy 218.949523 -56.324954) (xy 218.941403 -56.38013)
			(xy 218.925335 -56.433537) (xy 218.901663 -56.484034) (xy 218.87089 -56.530547) (xy 218.833673 -56.572084)
			(xy 218.790805 -56.607759) (xy 218.743199 -56.636813) (xy 218.69187 -56.658625) (xy 218.637913 -56.672731)
			(xy 218.582476 -56.678831) (xy 218.526742 -56.676794) (xy 218.471899 -56.666664) (xy 218.419115 -56.648657)
			(xy 218.369515 -56.623156) (xy 218.324157 -56.590705) (xy 218.284008 -56.551996) (xy 218.249922 -56.507853)
			(xy 218.222626 -56.459218) (xy 218.202703 -56.407127) (xy 218.190577 -56.35269) (xy 218.186506 -56.297068)
			(xy 217.844654 -56.297068) (xy 217.844654 -56.341052) (xy 217.836898 -56.395003) (xy 217.821542 -56.4473)
			(xy 217.798901 -56.49688) (xy 217.769435 -56.542733) (xy 217.733743 -56.583926) (xy 217.692552 -56.61962)
			(xy 217.646701 -56.64909) (xy 217.597122 -56.671734) (xy 217.544826 -56.687093) (xy 217.490876 -56.694853)
			(xy 217.463624 -56.69534) (xy 217.436254 -56.694874) (xy 217.382074 -56.687059) (xy 217.32957 -56.67157)
			(xy 217.279823 -56.648728) (xy 217.233857 -56.619002) (xy 217.212926 -56.60136) (xy 217.212672 -56.601106)
			(xy 217.205568 -56.595544) (xy 217.188665 -56.589282) (xy 217.179652 -56.588914) (xy 217.112596 -56.588914)
			(xy 217.103579 -56.589266) (xy 217.086661 -56.595517) (xy 217.079576 -56.601106) (xy 217.079576 -56.60136)
			(xy 217.079322 -56.60136) (xy 217.058389 -56.619001) (xy 217.012421 -56.648725) (xy 216.962675 -56.671571)
			(xy 216.910173 -56.687067) (xy 216.855995 -56.694896) (xy 216.801253 -56.694896) (xy 216.747075 -56.687067)
			(xy 216.694573 -56.671571) (xy 216.644827 -56.648725) (xy 216.598859 -56.619001) (xy 216.577926 -56.60136)
			(xy 216.577672 -56.601106) (xy 216.570568 -56.595544) (xy 216.553665 -56.589282) (xy 216.544652 -56.588914)
			(xy 216.477596 -56.588914) (xy 216.468579 -56.589266) (xy 216.451661 -56.595517) (xy 216.444576 -56.601106)
			(xy 216.444068 -56.60136) (xy 216.431333 -56.612303) (xy 216.404242 -56.632145) (xy 216.389966 -56.640984)
			(xy 216.381076 -56.646318) (xy 216.368884 -56.663336) (xy 216.348564 -56.756554) (xy 216.352882 -56.777128)
			(xy 216.358724 -56.785764) (xy 216.374714 -56.809834) (xy 216.400058 -56.861764) (xy 216.417286 -56.91692)
			(xy 216.426005 -56.974042) (xy 216.426542 -57.002934) (xy 216.426056 -57.030185) (xy 216.425774 -57.032144)
			(xy 219.585792 -57.032144) (xy 219.589863 -56.976522) (xy 219.601989 -56.922085) (xy 219.621912 -56.869994)
			(xy 219.649208 -56.821359) (xy 219.683294 -56.777216) (xy 219.723443 -56.738507) (xy 219.768801 -56.706056)
			(xy 219.818401 -56.680555) (xy 219.871185 -56.662548) (xy 219.926028 -56.652418) (xy 219.981762 -56.650381)
			(xy 220.037199 -56.656481) (xy 220.091156 -56.670587) (xy 220.142485 -56.692399) (xy 220.190091 -56.721453)
			(xy 220.232959 -56.757128) (xy 220.270176 -56.798665) (xy 220.300949 -56.845178) (xy 220.324621 -56.895675)
			(xy 220.340689 -56.949082) (xy 220.348809 -57.004258) (xy 220.349318 -57.032144) (xy 220.348809 -57.06003)
			(xy 220.340689 -57.115206) (xy 220.324621 -57.168613) (xy 220.300949 -57.21911) (xy 220.270176 -57.265623)
			(xy 220.232959 -57.30716) (xy 220.190091 -57.342835) (xy 220.142485 -57.371889) (xy 220.091156 -57.393701)
			(xy 220.037199 -57.407807) (xy 219.981762 -57.413907) (xy 219.926028 -57.41187) (xy 219.871185 -57.40174)
			(xy 219.818401 -57.383733) (xy 219.768801 -57.358232) (xy 219.723443 -57.325781) (xy 219.683294 -57.287072)
			(xy 219.649208 -57.242929) (xy 219.621912 -57.194294) (xy 219.601989 -57.142203) (xy 219.589863 -57.087766)
			(xy 219.585792 -57.032144) (xy 216.425774 -57.032144) (xy 216.4183 -57.084133) (xy 216.402945 -57.136428)
			(xy 216.380303 -57.186005) (xy 216.350837 -57.231855) (xy 216.315146 -57.273046) (xy 216.273955 -57.308737)
			(xy 216.228105 -57.338203) (xy 216.178528 -57.360845) (xy 216.126233 -57.3762) (xy 216.072285 -57.383956)
			(xy 216.017783 -57.383956) (xy 215.963835 -57.3762) (xy 215.91154 -57.360845) (xy 215.861963 -57.338203)
			(xy 215.816113 -57.308737) (xy 215.774922 -57.273046) (xy 215.739231 -57.231855) (xy 215.709765 -57.186005)
			(xy 215.687123 -57.136428) (xy 215.671768 -57.084133) (xy 215.664012 -57.030185) (xy 215.663526 -57.002934)
			(xy 208.340357 -57.002934) (xy 208.318136 -57.041547) (xy 208.300828 -57.064148) (xy 208.295494 -57.070498)
			(xy 208.2927 -57.078372) (xy 208.291291 -57.082551) (xy 208.289762 -57.091235) (xy 208.289652 -57.095644)
			(xy 208.289652 -57.128156) (xy 208.278476 -57.128156) (xy 208.278476 -57.178956) (xy 208.278809 -57.18756)
			(xy 208.284516 -57.203795) (xy 208.289652 -57.210706) (xy 208.290922 -57.21223) (xy 208.308317 -57.233106)
			(xy 208.337637 -57.278856) (xy 208.360167 -57.328303) (xy 208.375449 -57.380448) (xy 208.383176 -57.434235)
			(xy 208.383632 -57.461404) (xy 208.383056 -57.491232) (xy 208.373773 -57.55016) (xy 208.355434 -57.606926)
			(xy 208.328486 -57.660148) (xy 208.311496 -57.68467) (xy 208.305908 -57.69229) (xy 208.303622 -57.70118)
			(xy 208.302473 -57.705721) (xy 208.301697 -57.715055) (xy 208.302098 -57.719722) (xy 208.318354 -57.87517)
			(xy 208.319277 -57.880002) (xy 208.322722 -57.889216) (xy 208.325212 -57.893458) (xy 208.325466 -57.893966)
			(xy 208.339258 -57.916818) (xy 208.361012 -57.96556) (xy 208.375751 -58.01686) (xy 208.383186 -58.069716)
			(xy 208.383632 -58.096404) (xy 208.3829 -58.129944) (xy 208.371139 -58.195985) (xy 208.360264 -58.227722)
			(xy 208.3562 -58.238898) (xy 208.366106 -58.33491) (xy 208.368608 -58.360554) (xy 208.371277 -58.412015)
			(xy 208.37144 -58.43778) (xy 208.37144 -58.636154) (xy 208.372964 -58.641996) (xy 208.377958 -58.66401)
			(xy 208.379785 -58.679334) (xy 216.095326 -58.679334) (xy 216.095741 -58.653018) (xy 216.102985 -58.600887)
			(xy 216.117314 -58.550243) (xy 216.138456 -58.502044) (xy 216.166012 -58.457202) (xy 216.19946 -58.416565)
			(xy 216.218516 -58.39841) (xy 216.225918 -58.390889) (xy 216.234442 -58.371608) (xy 216.235026 -58.361072)
			(xy 216.235026 -58.286396) (xy 216.234505 -58.275846) (xy 216.225963 -58.256551) (xy 216.218516 -58.249058)
			(xy 216.19945 -58.230913) (xy 216.165993 -58.190281) (xy 216.138435 -58.145439) (xy 216.117298 -58.097236)
			(xy 216.102984 -58.046587) (xy 216.095762 -57.994451) (xy 216.095326 -57.968134) (xy 216.095812 -57.940883)
			(xy 216.103568 -57.886935) (xy 216.118923 -57.83464) (xy 216.141565 -57.785063) (xy 216.171031 -57.739213)
			(xy 216.206722 -57.698022) (xy 216.247913 -57.662331) (xy 216.293763 -57.632865) (xy 216.34334 -57.610223)
			(xy 216.395635 -57.594868) (xy 216.449583 -57.587112) (xy 216.504085 -57.587112) (xy 216.558033 -57.594868)
			(xy 216.610328 -57.610223) (xy 216.659905 -57.632865) (xy 216.705755 -57.662331) (xy 216.746946 -57.698022)
			(xy 216.782637 -57.739213) (xy 216.812103 -57.785063) (xy 216.834745 -57.83464) (xy 216.8501 -57.886935)
			(xy 216.857856 -57.940883) (xy 216.858342 -57.968134) (xy 216.857916 -57.99445) (xy 216.850675 -58.046581)
			(xy 216.836349 -58.097225) (xy 216.815209 -58.145424) (xy 216.787655 -58.190266) (xy 216.754208 -58.230903)
			(xy 216.735152 -58.249058) (xy 216.727775 -58.2566) (xy 216.719235 -58.275864) (xy 216.718642 -58.286396)
			(xy 216.718642 -58.361072) (xy 216.719161 -58.371623) (xy 216.727702 -58.390919) (xy 216.735152 -58.39841)
			(xy 216.754215 -58.416558) (xy 216.78767 -58.45719) (xy 216.815226 -58.502032) (xy 216.836363 -58.550235)
			(xy 216.850679 -58.600883) (xy 216.857904 -58.653018) (xy 216.858342 -58.679334) (xy 216.857856 -58.706585)
			(xy 216.8501 -58.760533) (xy 216.834745 -58.812828) (xy 216.812103 -58.862405) (xy 216.782637 -58.908255)
			(xy 216.746946 -58.949446) (xy 216.705755 -58.985137) (xy 216.659905 -59.014603) (xy 216.610328 -59.037245)
			(xy 216.558033 -59.0526) (xy 216.504085 -59.060356) (xy 216.449583 -59.060356) (xy 216.395635 -59.0526)
			(xy 216.34334 -59.037245) (xy 216.293763 -59.014603) (xy 216.247913 -58.985137) (xy 216.206722 -58.949446)
			(xy 216.171031 -58.908255) (xy 216.141565 -58.862405) (xy 216.118923 -58.812828) (xy 216.103568 -58.760533)
			(xy 216.095812 -58.706585) (xy 216.095326 -58.679334) (xy 208.379785 -58.679334) (xy 208.383302 -58.708833)
			(xy 208.383632 -58.731404) (xy 208.383632 -58.741056) (xy 208.382838 -58.761328) (xy 208.377494 -58.801545)
			(xy 208.372964 -58.82132) (xy 208.37144 -58.827162) (xy 208.37144 -60.01925) (xy 216.235784 -60.01925)
			(xy 216.235784 -59.96475) (xy 216.24354 -59.910804) (xy 216.258894 -59.858511) (xy 216.281534 -59.808935)
			(xy 216.310999 -59.763086) (xy 216.346688 -59.721897) (xy 216.387877 -59.686206) (xy 216.433725 -59.65674)
			(xy 216.4833 -59.634098) (xy 216.535592 -59.618742) (xy 216.589538 -59.610985) (xy 216.616788 -59.610498)
			(xy 216.644158 -59.610972) (xy 216.698337 -59.618788) (xy 216.75084 -59.634275) (xy 216.800587 -59.657115)
			(xy 216.846554 -59.686838) (xy 216.867486 -59.704478) (xy 216.86774 -59.704732) (xy 216.874837 -59.710303)
			(xy 216.891746 -59.716558) (xy 216.90076 -59.716924) (xy 216.967816 -59.716924) (xy 216.976833 -59.716569)
			(xy 216.99375 -59.710319) (xy 217.000836 -59.704732) (xy 217.000836 -59.704478) (xy 217.00109 -59.704478)
			(xy 217.022023 -59.686837) (xy 217.067991 -59.657113) (xy 217.117737 -59.634267) (xy 217.170239 -59.618771)
			(xy 217.224417 -59.610942) (xy 217.279159 -59.610942) (xy 217.333337 -59.618771) (xy 217.385839 -59.634267)
			(xy 217.435585 -59.657113) (xy 217.481553 -59.686837) (xy 217.502486 -59.704478) (xy 217.50274 -59.704732)
			(xy 217.509837 -59.710303) (xy 217.526746 -59.716558) (xy 217.53576 -59.716924) (xy 217.602816 -59.716924)
			(xy 217.611833 -59.716569) (xy 217.62875 -59.710319) (xy 217.635836 -59.704732) (xy 217.635836 -59.704478)
			(xy 217.63609 -59.704478) (xy 217.657012 -59.686827) (xy 217.702988 -59.657117) (xy 217.752738 -59.634284)
			(xy 217.805241 -59.618796) (xy 217.859418 -59.610971) (xy 217.886788 -59.610498) (xy 217.914042 -59.610949)
			(xy 217.967995 -59.618704) (xy 218.020295 -59.634059) (xy 218.069877 -59.656702) (xy 218.115733 -59.68617)
			(xy 218.156928 -59.721864) (xy 218.192623 -59.763058) (xy 218.222093 -59.808912) (xy 218.244736 -59.858494)
			(xy 218.260093 -59.910793) (xy 218.267851 -59.964746) (xy 218.267851 -60.019254) (xy 218.260093 -60.073207)
			(xy 218.244736 -60.125506) (xy 218.222093 -60.175088) (xy 218.192623 -60.220942) (xy 218.156928 -60.262136)
			(xy 218.115733 -60.29783) (xy 218.069877 -60.327298) (xy 218.020295 -60.349941) (xy 217.967995 -60.365296)
			(xy 217.914042 -60.373051) (xy 217.886788 -60.373514) (xy 217.859418 -60.373052) (xy 217.805239 -60.365232)
			(xy 217.752736 -60.349742) (xy 217.702989 -60.3269) (xy 217.657022 -60.297175) (xy 217.63609 -60.279534)
			(xy 217.635836 -60.27928) (xy 217.628745 -60.2737) (xy 217.611832 -60.26745) (xy 217.602816 -60.267088)
			(xy 217.53576 -60.267088) (xy 217.526741 -60.267428) (xy 217.509825 -60.273688) (xy 217.50274 -60.27928)
			(xy 217.502486 -60.279534) (xy 217.481553 -60.297175) (xy 217.435585 -60.326899) (xy 217.385839 -60.349745)
			(xy 217.333337 -60.365241) (xy 217.279159 -60.37307) (xy 217.224417 -60.37307) (xy 217.170239 -60.365241)
			(xy 217.117737 -60.349745) (xy 217.067991 -60.326899) (xy 217.022023 -60.297175) (xy 217.00109 -60.279534)
			(xy 217.000836 -60.27928) (xy 216.993745 -60.2737) (xy 216.976832 -60.26745) (xy 216.967816 -60.267088)
			(xy 216.90076 -60.267088) (xy 216.891741 -60.267428) (xy 216.874825 -60.273688) (xy 216.86774 -60.27928)
			(xy 216.86774 -60.279534) (xy 216.867486 -60.279534) (xy 216.846537 -60.297152) (xy 216.800568 -60.326865)
			(xy 216.750825 -60.349705) (xy 216.698328 -60.365201) (xy 216.644156 -60.373036) (xy 216.616788 -60.373514)
			(xy 216.589538 -60.373015) (xy 216.535592 -60.365258) (xy 216.4833 -60.349902) (xy 216.433725 -60.32726)
			(xy 216.387877 -60.297794) (xy 216.346688 -60.262103) (xy 216.310999 -60.220914) (xy 216.281534 -60.175065)
			(xy 216.258894 -60.125489) (xy 216.24354 -60.073196) (xy 216.235784 -60.01925) (xy 208.37144 -60.01925)
			(xy 208.37144 -60.595256) (xy 208.370943 -60.638727) (xy 208.363327 -60.725336) (xy 208.348199 -60.810953)
			(xy 208.337404 -60.853066) (xy 207.702771 -63.213552) (xy 216.220765 -63.213552) (xy 216.220765 -63.159048)
			(xy 216.228522 -63.105098) (xy 216.243878 -63.052801) (xy 216.26652 -63.003222) (xy 216.295987 -62.95737)
			(xy 216.33168 -62.916179) (xy 216.372872 -62.880486) (xy 216.418724 -62.851019) (xy 216.468303 -62.828377)
			(xy 216.5206 -62.813022) (xy 216.57455 -62.805265) (xy 216.601802 -62.804802) (xy 216.629172 -62.805266)
			(xy 216.683351 -62.813085) (xy 216.735855 -62.828574) (xy 216.785601 -62.851416) (xy 216.831568 -62.881141)
			(xy 216.8525 -62.898782) (xy 216.852754 -62.899036) (xy 216.859847 -62.904613) (xy 216.876759 -62.910865)
			(xy 216.885774 -62.911228) (xy 216.95283 -62.911228) (xy 216.961848 -62.910879) (xy 216.978764 -62.904625)
			(xy 216.98585 -62.899036) (xy 216.98585 -62.898782) (xy 216.986104 -62.898782) (xy 217.007037 -62.881141)
			(xy 217.053005 -62.851417) (xy 217.102751 -62.828571) (xy 217.155253 -62.813075) (xy 217.209431 -62.805246)
			(xy 217.264173 -62.805246) (xy 217.318351 -62.813075) (xy 217.370853 -62.828571) (xy 217.420599 -62.851417)
			(xy 217.466567 -62.881141) (xy 217.4875 -62.898782) (xy 217.487754 -62.899036) (xy 217.494847 -62.904613)
			(xy 217.511759 -62.910865) (xy 217.520774 -62.911228) (xy 217.58783 -62.911228) (xy 217.596848 -62.910879)
			(xy 217.613764 -62.904625) (xy 217.62085 -62.899036) (xy 217.62085 -62.898782) (xy 217.621104 -62.898782)
			(xy 217.642021 -62.881125) (xy 217.687999 -62.851416) (xy 217.73775 -62.828584) (xy 217.790254 -62.813097)
			(xy 217.844432 -62.805274) (xy 217.871802 -62.804802) (xy 217.899054 -62.805268) (xy 217.953003 -62.813025)
			(xy 218.005299 -62.828381) (xy 218.054877 -62.851022) (xy 218.100728 -62.88049) (xy 218.141919 -62.916182)
			(xy 218.177612 -62.957373) (xy 218.207079 -63.003225) (xy 218.22972 -63.052803) (xy 218.245076 -63.105099)
			(xy 218.252832 -63.159048) (xy 218.252832 -63.213552) (xy 218.245076 -63.267501) (xy 218.22972 -63.319797)
			(xy 218.207079 -63.369375) (xy 218.177612 -63.415227) (xy 218.141919 -63.456418) (xy 218.100728 -63.49211)
			(xy 218.054877 -63.521578) (xy 218.005299 -63.544219) (xy 217.953003 -63.559575) (xy 217.899054 -63.567332)
			(xy 217.871802 -63.567818) (xy 217.844431 -63.567371) (xy 217.79025 -63.559551) (xy 217.737746 -63.544059)
			(xy 217.687999 -63.521213) (xy 217.642034 -63.491482) (xy 217.621104 -63.473838) (xy 217.62085 -63.473584)
			(xy 217.613755 -63.46801) (xy 217.596845 -63.461756) (xy 217.58783 -63.461392) (xy 217.520774 -63.461392)
			(xy 217.511756 -63.461739) (xy 217.494839 -63.467994) (xy 217.487754 -63.473584) (xy 217.4875 -63.473838)
			(xy 217.466567 -63.491479) (xy 217.420599 -63.521203) (xy 217.370853 -63.544049) (xy 217.318351 -63.559545)
			(xy 217.264173 -63.567374) (xy 217.209431 -63.567374) (xy 217.155253 -63.559545) (xy 217.102751 -63.544049)
			(xy 217.053005 -63.521203) (xy 217.007037 -63.491479) (xy 216.986104 -63.473838) (xy 216.98585 -63.473584)
			(xy 216.978755 -63.46801) (xy 216.961845 -63.461756) (xy 216.95283 -63.461392) (xy 216.885774 -63.461392)
			(xy 216.876756 -63.461739) (xy 216.859839 -63.467994) (xy 216.852754 -63.473584) (xy 216.852754 -63.473838)
			(xy 216.8525 -63.473838) (xy 216.831584 -63.491497) (xy 216.785606 -63.521205) (xy 216.735855 -63.544036)
			(xy 216.683351 -63.559523) (xy 216.629172 -63.567347) (xy 216.601802 -63.567818) (xy 216.57455 -63.567335)
			(xy 216.5206 -63.559578) (xy 216.468303 -63.544223) (xy 216.418724 -63.521581) (xy 216.372872 -63.492114)
			(xy 216.33168 -63.456421) (xy 216.295987 -63.41523) (xy 216.26652 -63.369378) (xy 216.243878 -63.319799)
			(xy 216.228522 -63.267502) (xy 216.220765 -63.213552) (xy 207.702771 -63.213552) (xy 207.690974 -63.25743)
			(xy 207.677602 -63.304893) (xy 207.642745 -63.39714) (xy 207.621378 -63.44158) (xy 206.798619 -65.100962)
			(xy 214.232488 -65.100962) (xy 214.236559 -65.04534) (xy 214.248685 -64.990903) (xy 214.268608 -64.938812)
			(xy 214.295904 -64.890177) (xy 214.32999 -64.846034) (xy 214.370139 -64.807325) (xy 214.415497 -64.774874)
			(xy 214.465097 -64.749373) (xy 214.517881 -64.731366) (xy 214.572724 -64.721236) (xy 214.628458 -64.719199)
			(xy 214.683895 -64.725299) (xy 214.737852 -64.739405) (xy 214.789181 -64.761217) (xy 214.836787 -64.790271)
			(xy 214.879655 -64.825946) (xy 214.916872 -64.867483) (xy 214.947645 -64.913996) (xy 214.971317 -64.964493)
			(xy 214.987385 -65.0179) (xy 214.995505 -65.073076) (xy 214.996014 -65.100962) (xy 214.995505 -65.128848)
			(xy 214.987385 -65.184024) (xy 214.971317 -65.237431) (xy 214.947645 -65.287928) (xy 214.916872 -65.334441)
			(xy 214.879655 -65.375978) (xy 214.836787 -65.411653) (xy 214.789181 -65.440707) (xy 214.737852 -65.462519)
			(xy 214.683895 -65.476625) (xy 214.628458 -65.482725) (xy 214.572724 -65.480688) (xy 214.517881 -65.470558)
			(xy 214.465097 -65.452551) (xy 214.415497 -65.42705) (xy 214.370139 -65.394599) (xy 214.32999 -65.35589)
			(xy 214.295904 -65.311747) (xy 214.268608 -65.263112) (xy 214.248685 -65.211021) (xy 214.236559 -65.156584)
			(xy 214.232488 -65.100962) (xy 206.798619 -65.100962) (xy 206.62646 -65.44818) (xy 206.604559 -65.491088)
			(xy 206.553668 -65.572891) (xy 206.52486 -65.611502) (xy 206.414608 -65.75552) (xy 208.446622 -65.75552)
			(xy 208.450693 -65.699898) (xy 208.462819 -65.645461) (xy 208.482742 -65.59337) (xy 208.510038 -65.544735)
			(xy 208.544124 -65.500592) (xy 208.584273 -65.461883) (xy 208.629631 -65.429432) (xy 208.679231 -65.403931)
			(xy 208.732015 -65.385924) (xy 208.786858 -65.375794) (xy 208.842592 -65.373757) (xy 208.898029 -65.379857)
			(xy 208.951986 -65.393963) (xy 209.003315 -65.415775) (xy 209.050921 -65.444829) (xy 209.093789 -65.480504)
			(xy 209.131006 -65.522041) (xy 209.161779 -65.568554) (xy 209.185451 -65.619051) (xy 209.201519 -65.672458)
			(xy 209.209639 -65.727634) (xy 209.210148 -65.75552) (xy 209.209639 -65.783406) (xy 209.201519 -65.838582)
			(xy 209.185451 -65.891989) (xy 209.161779 -65.942486) (xy 209.131006 -65.988999) (xy 209.093789 -66.030536)
			(xy 209.050921 -66.066211) (xy 209.003315 -66.095265) (xy 208.951986 -66.117077) (xy 208.898029 -66.131183)
			(xy 208.842592 -66.137283) (xy 208.786858 -66.135246) (xy 208.732015 -66.125116) (xy 208.679231 -66.107109)
			(xy 208.629631 -66.081608) (xy 208.584273 -66.049157) (xy 208.544124 -66.010448) (xy 208.510038 -65.966305)
			(xy 208.482742 -65.91767) (xy 208.462819 -65.865579) (xy 208.450693 -65.811142) (xy 208.446622 -65.75552)
			(xy 206.414608 -65.75552) (xy 205.363192 -67.128949) (xy 208.466698 -67.128949) (xy 208.466698 -67.074451)
			(xy 208.474454 -67.020507) (xy 208.489808 -66.968216) (xy 208.512447 -66.918642) (xy 208.541911 -66.872794)
			(xy 208.577599 -66.831606) (xy 208.618786 -66.795917) (xy 208.664633 -66.766452) (xy 208.714206 -66.743811)
			(xy 208.766497 -66.728456) (xy 208.820441 -66.720699) (xy 208.84769 -66.720212) (xy 208.87506 -66.720681)
			(xy 208.929239 -66.728498) (xy 208.981742 -66.743986) (xy 209.031489 -66.766827) (xy 209.077456 -66.796551)
			(xy 209.098388 -66.814192) (xy 209.098642 -66.814446) (xy 209.105737 -66.82002) (xy 209.122647 -66.826273)
			(xy 209.131662 -66.826638) (xy 209.198718 -66.826638) (xy 209.207735 -66.826282) (xy 209.224651 -66.820033)
			(xy 209.231738 -66.814446) (xy 209.231738 -66.814192) (xy 209.231992 -66.814192) (xy 209.252915 -66.796542)
			(xy 209.298891 -66.766832) (xy 209.34864 -66.743998) (xy 209.401143 -66.72851) (xy 209.45532 -66.720684)
			(xy 209.48269 -66.720212) (xy 209.509945 -66.720634) (xy 209.5639 -66.72839) (xy 209.616202 -66.743746)
			(xy 209.665786 -66.76639) (xy 209.711642 -66.795859) (xy 209.752838 -66.831554) (xy 209.788535 -66.87275)
			(xy 209.818006 -66.918606) (xy 209.84065 -66.968189) (xy 209.856007 -67.020491) (xy 209.863765 -67.074445)
			(xy 209.863765 -67.128955) (xy 209.856007 -67.182909) (xy 209.84065 -67.235211) (xy 209.818006 -67.284794)
			(xy 209.788535 -67.33065) (xy 209.752838 -67.371846) (xy 209.711642 -67.407541) (xy 209.665786 -67.43701)
			(xy 209.616202 -67.459654) (xy 209.5639 -67.47501) (xy 209.509945 -67.482766) (xy 209.48269 -67.483228)
			(xy 209.455319 -67.482785) (xy 209.401138 -67.474965) (xy 209.348634 -67.459471) (xy 209.298887 -67.436624)
			(xy 209.252922 -67.406893) (xy 209.231992 -67.389248) (xy 209.231738 -67.388994) (xy 209.224645 -67.383417)
			(xy 209.207733 -67.377165) (xy 209.198718 -67.376802) (xy 209.131662 -67.376802) (xy 209.122643 -67.377141)
			(xy 209.105726 -67.383401) (xy 209.098642 -67.388994) (xy 209.098642 -67.389248) (xy 209.098388 -67.389248)
			(xy 209.077427 -67.406851) (xy 209.031463 -67.43657) (xy 208.981723 -67.459414) (xy 208.929228 -67.474913)
			(xy 208.875057 -67.48275) (xy 208.84769 -67.483228) (xy 208.820441 -67.482701) (xy 208.766497 -67.474944)
			(xy 208.714206 -67.459589) (xy 208.664633 -67.436948) (xy 208.618786 -67.407483) (xy 208.577599 -67.371794)
			(xy 208.541911 -67.330606) (xy 208.512447 -67.284758) (xy 208.489808 -67.235184) (xy 208.474454 -67.182893)
			(xy 208.466698 -67.128949) (xy 205.363192 -67.128949) (xy 205.088282 -67.488054) (xy 212.879176 -67.488054)
			(xy 212.883247 -67.432432) (xy 212.895373 -67.377995) (xy 212.915296 -67.325904) (xy 212.942592 -67.277269)
			(xy 212.976678 -67.233126) (xy 213.016827 -67.194417) (xy 213.062185 -67.161966) (xy 213.111785 -67.136465)
			(xy 213.164569 -67.118458) (xy 213.219412 -67.108328) (xy 213.275146 -67.106291) (xy 213.330583 -67.112391)
			(xy 213.38454 -67.126497) (xy 213.435869 -67.148309) (xy 213.483475 -67.177363) (xy 213.526343 -67.213038)
			(xy 213.56356 -67.254575) (xy 213.594333 -67.301088) (xy 213.618005 -67.351585) (xy 213.634073 -67.404992)
			(xy 213.642193 -67.460168) (xy 213.642702 -67.488054) (xy 213.642193 -67.51594) (xy 213.639008 -67.537584)
			(xy 214.171274 -67.537584) (xy 214.175345 -67.481962) (xy 214.187471 -67.427525) (xy 214.207394 -67.375434)
			(xy 214.23469 -67.326799) (xy 214.268776 -67.282656) (xy 214.308925 -67.243947) (xy 214.354283 -67.211496)
			(xy 214.403883 -67.185995) (xy 214.456667 -67.167988) (xy 214.51151 -67.157858) (xy 214.567244 -67.155821)
			(xy 214.622681 -67.161921) (xy 214.676638 -67.176027) (xy 214.727967 -67.197839) (xy 214.775573 -67.226893)
			(xy 214.818441 -67.262568) (xy 214.855658 -67.304105) (xy 214.886431 -67.350618) (xy 214.910103 -67.401115)
			(xy 214.926171 -67.454522) (xy 214.934291 -67.509698) (xy 214.9348 -67.537584) (xy 214.934291 -67.56547)
			(xy 214.930246 -67.592956) (xy 215.445338 -67.592956) (xy 215.449409 -67.537334) (xy 215.461535 -67.482897)
			(xy 215.481458 -67.430806) (xy 215.508754 -67.382171) (xy 215.54284 -67.338028) (xy 215.582989 -67.299319)
			(xy 215.628347 -67.266868) (xy 215.677947 -67.241367) (xy 215.730731 -67.22336) (xy 215.785574 -67.21323)
			(xy 215.841308 -67.211193) (xy 215.896745 -67.217293) (xy 215.950702 -67.231399) (xy 216.002031 -67.253211)
			(xy 216.049637 -67.282265) (xy 216.092505 -67.31794) (xy 216.129722 -67.359477) (xy 216.160495 -67.40599)
			(xy 216.184167 -67.456487) (xy 216.200235 -67.509894) (xy 216.208355 -67.56507) (xy 216.208864 -67.592956)
			(xy 216.208355 -67.620842) (xy 216.200235 -67.676018) (xy 216.184167 -67.729425) (xy 216.160495 -67.779922)
			(xy 216.129722 -67.826435) (xy 216.092505 -67.867972) (xy 216.049637 -67.903647) (xy 216.002031 -67.932701)
			(xy 215.950702 -67.954513) (xy 215.896745 -67.968619) (xy 215.841308 -67.974719) (xy 215.785574 -67.972682)
			(xy 215.730731 -67.962552) (xy 215.677947 -67.944545) (xy 215.628347 -67.919044) (xy 215.582989 -67.886593)
			(xy 215.54284 -67.847884) (xy 215.508754 -67.803741) (xy 215.481458 -67.755106) (xy 215.461535 -67.703015)
			(xy 215.449409 -67.648578) (xy 215.445338 -67.592956) (xy 214.930246 -67.592956) (xy 214.926171 -67.620646)
			(xy 214.910103 -67.674053) (xy 214.886431 -67.72455) (xy 214.855658 -67.771063) (xy 214.818441 -67.8126)
			(xy 214.775573 -67.848275) (xy 214.727967 -67.877329) (xy 214.676638 -67.899141) (xy 214.622681 -67.913247)
			(xy 214.567244 -67.919347) (xy 214.51151 -67.91731) (xy 214.456667 -67.90718) (xy 214.403883 -67.889173)
			(xy 214.354283 -67.863672) (xy 214.308925 -67.831221) (xy 214.268776 -67.792512) (xy 214.23469 -67.748369)
			(xy 214.207394 -67.699734) (xy 214.187471 -67.647643) (xy 214.175345 -67.593206) (xy 214.171274 -67.537584)
			(xy 213.639008 -67.537584) (xy 213.634073 -67.571116) (xy 213.618005 -67.624523) (xy 213.594333 -67.67502)
			(xy 213.56356 -67.721533) (xy 213.526343 -67.76307) (xy 213.483475 -67.798745) (xy 213.435869 -67.827799)
			(xy 213.38454 -67.849611) (xy 213.330583 -67.863717) (xy 213.275146 -67.869817) (xy 213.219412 -67.86778)
			(xy 213.164569 -67.85765) (xy 213.111785 -67.839643) (xy 213.062185 -67.814142) (xy 213.016827 -67.781691)
			(xy 212.976678 -67.742982) (xy 212.942592 -67.698839) (xy 212.915296 -67.650204) (xy 212.895373 -67.598113)
			(xy 212.883247 -67.543676) (xy 212.879176 -67.488054) (xy 205.088282 -67.488054) (xy 204.247297 -68.586604)
			(xy 210.725258 -68.586604) (xy 210.725712 -68.559233) (xy 210.733531 -68.505053) (xy 210.749022 -68.452549)
			(xy 210.771867 -68.402803) (xy 210.801595 -68.356837) (xy 210.819238 -68.335906) (xy 210.819492 -68.335652)
			(xy 210.825062 -68.328554) (xy 210.831319 -68.311646) (xy 210.831684 -68.302632) (xy 210.831684 -68.235576)
			(xy 210.831342 -68.226558) (xy 210.825084 -68.209641) (xy 210.819492 -68.202556) (xy 210.819238 -68.202556)
			(xy 210.819238 -68.202302) (xy 210.801592 -68.181375) (xy 210.77188 -68.135401) (xy 210.749045 -68.085653)
			(xy 210.733555 -68.033151) (xy 210.72573 -67.978974) (xy 210.725258 -67.951604) (xy 210.725781 -67.924354)
			(xy 210.733536 -67.87041) (xy 210.748889 -67.818118) (xy 210.771528 -67.768543) (xy 210.80099 -67.722694)
			(xy 210.836678 -67.681505) (xy 210.877864 -67.645813) (xy 210.923709 -67.616346) (xy 210.973282 -67.593703)
			(xy 211.025573 -67.578345) (xy 211.079516 -67.570584) (xy 211.106766 -67.570096) (xy 211.133081 -67.570521)
			(xy 211.185212 -67.577764) (xy 211.235855 -67.592092) (xy 211.284054 -67.613233) (xy 211.328896 -67.640786)
			(xy 211.369534 -67.674231) (xy 211.38769 -67.693286) (xy 211.395215 -67.700683) (xy 211.414492 -67.709211)
			(xy 211.425028 -67.709796) (xy 211.499704 -67.709796) (xy 211.510256 -67.709284) (xy 211.529551 -67.700737)
			(xy 211.537042 -67.693286) (xy 211.555181 -67.674214) (xy 211.595815 -67.640759) (xy 211.640659 -67.613203)
			(xy 211.688863 -67.592067) (xy 211.739513 -67.577753) (xy 211.791649 -67.570532) (xy 211.817966 -67.570096)
			(xy 211.845335 -67.570583) (xy 211.899514 -67.578396) (xy 211.952016 -67.59388) (xy 212.001764 -67.616717)
			(xy 212.047732 -67.646437) (xy 212.068664 -67.664076) (xy 212.068918 -67.66433) (xy 212.075993 -67.669934)
			(xy 212.092919 -67.676169) (xy 212.101938 -67.676522) (xy 212.168994 -67.676522) (xy 212.17801 -67.676157)
			(xy 212.194927 -67.669914) (xy 212.202014 -67.66433) (xy 212.202014 -67.664076) (xy 212.202268 -67.664076)
			(xy 212.223198 -67.646435) (xy 212.269172 -67.616724) (xy 212.31892 -67.593889) (xy 212.371421 -67.578398)
			(xy 212.425597 -67.57057) (xy 212.452966 -67.570096) (xy 212.480218 -67.570587) (xy 212.534168 -67.578339)
			(xy 212.586466 -67.593691) (xy 212.636046 -67.61633) (xy 212.6819 -67.645795) (xy 212.723093 -67.681486)
			(xy 212.758787 -67.722676) (xy 212.788255 -67.768527) (xy 212.810898 -67.818106) (xy 212.826254 -67.870402)
			(xy 212.834011 -67.924352) (xy 212.834474 -67.951604) (xy 212.834017 -67.978975) (xy 212.826198 -68.033154)
			(xy 212.810707 -68.085658) (xy 212.787863 -68.135405) (xy 212.758136 -68.181371) (xy 212.740494 -68.202302)
			(xy 212.74024 -68.202556) (xy 212.734659 -68.209646) (xy 212.72841 -68.22656) (xy 212.728048 -68.235576)
			(xy 212.728048 -68.302632) (xy 212.728379 -68.311652) (xy 212.734643 -68.328569) (xy 212.74024 -68.335652)
			(xy 212.740494 -68.335652) (xy 212.740494 -68.335906) (xy 212.758148 -68.356826) (xy 212.787858 -68.402802)
			(xy 212.810691 -68.452552) (xy 212.826179 -68.505056) (xy 212.834002 -68.559234) (xy 212.834474 -68.586604)
			(xy 212.834048 -68.613858) (xy 212.82629 -68.667813) (xy 212.810932 -68.720113) (xy 212.788286 -68.769696)
			(xy 212.758815 -68.81555) (xy 212.723117 -68.856744) (xy 212.68192 -68.892437) (xy 212.636062 -68.921904)
			(xy 212.586478 -68.944545) (xy 212.534175 -68.959898) (xy 212.480221 -68.967651) (xy 212.452966 -68.968112)
			(xy 212.425595 -68.967663) (xy 212.371416 -68.959841) (xy 212.318912 -68.944347) (xy 212.269166 -68.921502)
			(xy 212.223199 -68.891774) (xy 212.202268 -68.874132) (xy 212.202014 -68.873878) (xy 212.194929 -68.868289)
			(xy 212.178011 -68.862044) (xy 212.168994 -68.861686) (xy 212.101938 -68.861686) (xy 212.092923 -68.862064)
			(xy 212.076006 -68.868297) (xy 212.068918 -68.873878) (xy 212.068918 -68.874132) (xy 212.068664 -68.874132)
			(xy 212.047723 -68.89176) (xy 212.001752 -68.921472) (xy 211.952007 -68.94431) (xy 211.899508 -68.959804)
			(xy 211.845334 -68.967636) (xy 211.817966 -68.968112) (xy 211.791651 -68.967663) (xy 211.739522 -68.960424)
			(xy 211.688879 -68.946101) (xy 211.640681 -68.924965) (xy 211.595837 -68.897416) (xy 211.555198 -68.863975)
			(xy 211.537042 -68.844922) (xy 211.529504 -68.83754) (xy 211.510236 -68.829004) (xy 211.499704 -68.828412)
			(xy 211.425028 -68.828412) (xy 211.414478 -68.828939) (xy 211.395182 -68.837475) (xy 211.38769 -68.844922)
			(xy 211.369537 -68.86398) (xy 211.328906 -68.897436) (xy 211.284065 -68.924994) (xy 211.235864 -68.946132)
			(xy 211.185216 -68.960449) (xy 211.133082 -68.967673) (xy 211.106766 -68.968112) (xy 211.079514 -68.967654)
			(xy 211.025566 -68.959893) (xy 210.973271 -68.944534) (xy 210.923693 -68.921889) (xy 210.877843 -68.892419)
			(xy 210.836654 -68.856725) (xy 210.800963 -68.815532) (xy 210.771497 -68.76968) (xy 210.748856 -68.720101)
			(xy 210.733501 -68.667805) (xy 210.725744 -68.613856) (xy 210.725258 -68.586604) (xy 204.247297 -68.586604)
			(xy 201.974207 -71.555864) (xy 213.294466 -71.555864) (xy 213.298537 -71.500242) (xy 213.310663 -71.445805)
			(xy 213.330586 -71.393714) (xy 213.357882 -71.345079) (xy 213.391968 -71.300936) (xy 213.432117 -71.262227)
			(xy 213.477475 -71.229776) (xy 213.527075 -71.204275) (xy 213.579859 -71.186268) (xy 213.634702 -71.176138)
			(xy 213.690436 -71.174101) (xy 213.745873 -71.180201) (xy 213.79983 -71.194307) (xy 213.851159 -71.216119)
			(xy 213.898765 -71.245173) (xy 213.941633 -71.280848) (xy 213.97885 -71.322385) (xy 214.009623 -71.368898)
			(xy 214.033295 -71.419395) (xy 214.049363 -71.472802) (xy 214.057483 -71.527978) (xy 214.057992 -71.555864)
			(xy 214.057483 -71.58375) (xy 214.051644 -71.623428) (xy 214.80348 -71.623428) (xy 214.807551 -71.567806)
			(xy 214.819677 -71.513369) (xy 214.8396 -71.461278) (xy 214.866896 -71.412643) (xy 214.900982 -71.3685)
			(xy 214.941131 -71.329791) (xy 214.986489 -71.29734) (xy 215.036089 -71.271839) (xy 215.088873 -71.253832)
			(xy 215.143716 -71.243702) (xy 215.19945 -71.241665) (xy 215.254887 -71.247765) (xy 215.308844 -71.261871)
			(xy 215.360173 -71.283683) (xy 215.407779 -71.312737) (xy 215.450647 -71.348412) (xy 215.487864 -71.389949)
			(xy 215.518637 -71.436462) (xy 215.542309 -71.486959) (xy 215.558377 -71.540366) (xy 215.566497 -71.595542)
			(xy 215.567006 -71.623428) (xy 215.566497 -71.651314) (xy 215.558377 -71.70649) (xy 215.542309 -71.759897)
			(xy 215.518637 -71.810394) (xy 215.487864 -71.856907) (xy 215.450647 -71.898444) (xy 215.407779 -71.934119)
			(xy 215.360173 -71.963173) (xy 215.308844 -71.984985) (xy 215.254887 -71.999091) (xy 215.19945 -72.005191)
			(xy 215.143716 -72.003154) (xy 215.088873 -71.993024) (xy 215.036089 -71.975017) (xy 214.986489 -71.949516)
			(xy 214.941131 -71.917065) (xy 214.900982 -71.878356) (xy 214.866896 -71.834213) (xy 214.8396 -71.785578)
			(xy 214.819677 -71.733487) (xy 214.807551 -71.67905) (xy 214.80348 -71.623428) (xy 214.051644 -71.623428)
			(xy 214.049363 -71.638926) (xy 214.033295 -71.692333) (xy 214.009623 -71.74283) (xy 213.97885 -71.789343)
			(xy 213.941633 -71.83088) (xy 213.898765 -71.866555) (xy 213.851159 -71.895609) (xy 213.79983 -71.917421)
			(xy 213.745873 -71.931527) (xy 213.690436 -71.937627) (xy 213.634702 -71.93559) (xy 213.579859 -71.92546)
			(xy 213.527075 -71.907453) (xy 213.477475 -71.881952) (xy 213.432117 -71.849501) (xy 213.391968 -71.810792)
			(xy 213.357882 -71.766649) (xy 213.330586 -71.718014) (xy 213.310663 -71.665923) (xy 213.298537 -71.611486)
			(xy 213.294466 -71.555864) (xy 201.974207 -71.555864) (xy 201.060304 -72.749664) (xy 201.055994 -72.755875)
			(xy 201.05083 -72.770075) (xy 201.050144 -72.777604) (xy 201.049636 -72.785478) (xy 201.053446 -72.800464)
			(xy 201.057256 -72.806814) (xy 201.070384 -72.829313) (xy 201.091091 -72.877112) (xy 201.105111 -72.92728)
			(xy 201.112185 -72.978889) (xy 201.112628 -73.004934) (xy 201.112628 -73.012554) (xy 201.111609 -73.039899)
			(xy 201.102708 -73.093892) (xy 201.086186 -73.146059) (xy 201.062383 -73.195331) (xy 201.031785 -73.240698)
			(xy 200.995021 -73.281229) (xy 200.952845 -73.316093) (xy 200.906121 -73.344576) (xy 200.855808 -73.366092)
			(xy 200.802938 -73.380202) (xy 200.775824 -73.383902) (xy 200.761346 -73.385426) (xy 200.732644 -73.386696)
			(xy 200.728834 -73.386696) (xy 200.702502 -73.386111) (xy 200.650373 -73.378585) (xy 200.624948 -73.37171)
			(xy 200.624694 -73.37171) (xy 200.617355 -73.369902) (xy 200.602251 -73.370168) (xy 200.594976 -73.372218)
			(xy 200.58761 -73.374504) (xy 200.575418 -73.383394) (xy 200.556876 -73.407524) (xy 200.552558 -73.414128)
			(xy 200.549764 -73.41997) (xy 200.54824 -73.424796) (xy 200.54622 -73.433358) (xy 200.547487 -73.45089)
			(xy 200.554627 -73.466953) (xy 200.560432 -73.473564) (xy 200.580142 -73.495003) (xy 200.613493 -73.542741)
			(xy 200.639207 -73.594991) (xy 200.656687 -73.65054) (xy 200.665529 -73.708099) (xy 200.666096 -73.737216)
			(xy 200.665618 -73.764328) (xy 200.657938 -73.818005) (xy 200.642735 -73.870054) (xy 200.620316 -73.919425)
			(xy 200.591131 -73.965125) (xy 200.55577 -74.006232) (xy 200.514944 -74.041917) (xy 200.469477 -74.071463)
			(xy 200.420284 -74.094273) (xy 200.368357 -74.109887) (xy 200.314743 -74.117992) (xy 200.287636 -74.118724)
			(xy 200.28408 -74.118724) (xy 200.25241 -74.118053) (xy 200.189949 -74.107518) (xy 200.130077 -74.086837)
			(xy 200.101962 -74.072242) (xy 200.09612 -74.069448) (xy 200.085714 -74.065996) (xy 200.06385 -74.067307)
			(xy 200.044499 -74.077566) (xy 200.037446 -74.085958) (xy 200.037446 -74.086212) (xy 200.029064 -74.097134)
			(xy 200.024651 -74.103763) (xy 200.019721 -74.118896) (xy 200.019412 -74.126852) (xy 200.03389 -74.162158)
			(xy 200.04024 -74.169016) (xy 200.059387 -74.190313) (xy 200.091729 -74.237574) (xy 200.11664 -74.28914)
			(xy 200.133559 -74.343851) (xy 200.142107 -74.400478) (xy 200.142602 -74.429112) (xy 200.142136 -74.456387)
			(xy 200.134365 -74.510381) (xy 200.118982 -74.562718) (xy 200.096301 -74.61233) (xy 200.066786 -74.658205)
			(xy 200.031037 -74.699409) (xy 199.989784 -74.735101) (xy 199.943867 -74.764554) (xy 199.894224 -74.787166)
			(xy 199.841867 -74.802476) (xy 199.787862 -74.810173) (xy 199.760586 -74.81062) (xy 199.757538 -74.81062)
			(xy 199.737726 -74.809858) (xy 199.709242 -74.807584) (xy 199.653361 -74.795652) (xy 199.599877 -74.775544)
			(xy 199.574658 -74.762106) (xy 199.574404 -74.762106) (xy 199.566296 -74.757981) (xy 199.548342 -74.755127)
			(xy 199.539352 -74.756518) (xy 199.530716 -74.758296) (xy 199.515476 -74.767948) (xy 198.093602 -76.62545)
			(xy 204.32979 -76.62545) (xy 204.333861 -76.569828) (xy 204.345987 -76.515391) (xy 204.36591 -76.4633)
			(xy 204.393206 -76.414665) (xy 204.427292 -76.370522) (xy 204.467441 -76.331813) (xy 204.512799 -76.299362)
			(xy 204.562399 -76.273861) (xy 204.615183 -76.255854) (xy 204.670026 -76.245724) (xy 204.72576 -76.243687)
			(xy 204.781197 -76.249787) (xy 204.835154 -76.263893) (xy 204.886483 -76.285705) (xy 204.934089 -76.314759)
			(xy 204.976957 -76.350434) (xy 205.014174 -76.391971) (xy 205.044947 -76.438484) (xy 205.068619 -76.488981)
			(xy 205.084687 -76.542388) (xy 205.092807 -76.597564) (xy 205.093316 -76.62545) (xy 205.092807 -76.653336)
			(xy 205.084687 -76.708512) (xy 205.068619 -76.761919) (xy 205.044947 -76.812416) (xy 205.014174 -76.858929)
			(xy 204.976957 -76.900466) (xy 204.934089 -76.936141) (xy 204.886483 -76.965195) (xy 204.835154 -76.987007)
			(xy 204.781197 -77.001113) (xy 204.72576 -77.007213) (xy 204.670026 -77.005176) (xy 204.615183 -76.995046)
			(xy 204.562399 -76.977039) (xy 204.512799 -76.951538) (xy 204.467441 -76.919087) (xy 204.427292 -76.880378)
			(xy 204.393206 -76.836235) (xy 204.36591 -76.7876) (xy 204.345987 -76.735509) (xy 204.333861 -76.681072)
			(xy 204.32979 -76.62545) (xy 198.093602 -76.62545) (xy 197.648938 -77.206348) (xy 198.783954 -77.206348)
			(xy 198.788025 -77.150726) (xy 198.800151 -77.096289) (xy 198.820074 -77.044198) (xy 198.84737 -76.995563)
			(xy 198.881456 -76.95142) (xy 198.921605 -76.912711) (xy 198.966963 -76.88026) (xy 199.016563 -76.854759)
			(xy 199.069347 -76.836752) (xy 199.12419 -76.826622) (xy 199.179924 -76.824585) (xy 199.235361 -76.830685)
			(xy 199.289318 -76.844791) (xy 199.340647 -76.866603) (xy 199.388253 -76.895657) (xy 199.431121 -76.931332)
			(xy 199.468338 -76.972869) (xy 199.499111 -77.019382) (xy 199.522783 -77.069879) (xy 199.538851 -77.123286)
			(xy 199.546971 -77.178462) (xy 199.54748 -77.206348) (xy 199.546971 -77.234234) (xy 199.538851 -77.28941)
			(xy 199.522783 -77.342817) (xy 199.499111 -77.393314) (xy 199.468338 -77.439827) (xy 199.431121 -77.481364)
			(xy 199.388253 -77.517039) (xy 199.340647 -77.546093) (xy 199.29975 -77.563472) (xy 205.228442 -77.563472)
			(xy 205.232513 -77.50785) (xy 205.244639 -77.453413) (xy 205.264562 -77.401322) (xy 205.291858 -77.352687)
			(xy 205.325944 -77.308544) (xy 205.366093 -77.269835) (xy 205.411451 -77.237384) (xy 205.461051 -77.211883)
			(xy 205.513835 -77.193876) (xy 205.568678 -77.183746) (xy 205.624412 -77.181709) (xy 205.679849 -77.187809)
			(xy 205.733806 -77.201915) (xy 205.785135 -77.223727) (xy 205.832741 -77.252781) (xy 205.875609 -77.288456)
			(xy 205.912826 -77.329993) (xy 205.943599 -77.376506) (xy 205.967271 -77.427003) (xy 205.983339 -77.48041)
			(xy 205.991459 -77.535586) (xy 205.991968 -77.563472) (xy 207.251806 -77.563472) (xy 207.255877 -77.50785)
			(xy 207.268003 -77.453413) (xy 207.287926 -77.401322) (xy 207.315222 -77.352687) (xy 207.349308 -77.308544)
			(xy 207.389457 -77.269835) (xy 207.434815 -77.237384) (xy 207.484415 -77.211883) (xy 207.537199 -77.193876)
			(xy 207.592042 -77.183746) (xy 207.647776 -77.181709) (xy 207.703213 -77.187809) (xy 207.75717 -77.201915)
			(xy 207.808499 -77.223727) (xy 207.856105 -77.252781) (xy 207.898973 -77.288456) (xy 207.93619 -77.329993)
			(xy 207.966963 -77.376506) (xy 207.990635 -77.427003) (xy 208.006703 -77.48041) (xy 208.014823 -77.535586)
			(xy 208.015332 -77.563472) (xy 208.014823 -77.591358) (xy 208.006703 -77.646534) (xy 207.990635 -77.699941)
			(xy 207.966963 -77.750438) (xy 207.93619 -77.796951) (xy 207.898973 -77.838488) (xy 207.856105 -77.874163)
			(xy 207.808499 -77.903217) (xy 207.75717 -77.925029) (xy 207.703213 -77.939135) (xy 207.647776 -77.945235)
			(xy 207.592042 -77.943198) (xy 207.537199 -77.933068) (xy 207.484415 -77.915061) (xy 207.434815 -77.88956)
			(xy 207.389457 -77.857109) (xy 207.349308 -77.8184) (xy 207.315222 -77.774257) (xy 207.287926 -77.725622)
			(xy 207.268003 -77.673531) (xy 207.255877 -77.619094) (xy 207.251806 -77.563472) (xy 205.991968 -77.563472)
			(xy 205.991459 -77.591358) (xy 205.983339 -77.646534) (xy 205.967271 -77.699941) (xy 205.943599 -77.750438)
			(xy 205.912826 -77.796951) (xy 205.875609 -77.838488) (xy 205.832741 -77.874163) (xy 205.785135 -77.903217)
			(xy 205.733806 -77.925029) (xy 205.679849 -77.939135) (xy 205.624412 -77.945235) (xy 205.568678 -77.943198)
			(xy 205.513835 -77.933068) (xy 205.461051 -77.915061) (xy 205.411451 -77.88956) (xy 205.366093 -77.857109)
			(xy 205.325944 -77.8184) (xy 205.291858 -77.774257) (xy 205.264562 -77.725622) (xy 205.244639 -77.673531)
			(xy 205.232513 -77.619094) (xy 205.228442 -77.563472) (xy 199.29975 -77.563472) (xy 199.289318 -77.567905)
			(xy 199.235361 -77.582011) (xy 199.179924 -77.588111) (xy 199.12419 -77.586074) (xy 199.069347 -77.575944)
			(xy 199.016563 -77.557937) (xy 198.966963 -77.532436) (xy 198.921605 -77.499985) (xy 198.881456 -77.461276)
			(xy 198.84737 -77.417133) (xy 198.820074 -77.368498) (xy 198.800151 -77.316407) (xy 198.788025 -77.26197)
			(xy 198.783954 -77.206348) (xy 197.648938 -77.206348) (xy 196.368416 -78.879192) (xy 196.363574 -78.886145)
			(xy 196.361167 -78.893416) (xy 205.222856 -78.893416) (xy 205.223342 -78.866165) (xy 205.231098 -78.812217)
			(xy 205.246453 -78.759922) (xy 205.269095 -78.710345) (xy 205.298561 -78.664495) (xy 205.334252 -78.623304)
			(xy 205.375443 -78.587613) (xy 205.421293 -78.558147) (xy 205.47087 -78.535505) (xy 205.523165 -78.52015)
			(xy 205.577113 -78.512394) (xy 205.631615 -78.512394) (xy 205.685563 -78.52015) (xy 205.737858 -78.535505)
			(xy 205.787435 -78.558147) (xy 205.833285 -78.587613) (xy 205.874476 -78.623304) (xy 205.910167 -78.664495)
			(xy 205.939633 -78.710345) (xy 205.962275 -78.759922) (xy 205.97763 -78.812217) (xy 205.985386 -78.866165)
			(xy 205.985872 -78.893416) (xy 205.985368 -78.920818) (xy 205.977525 -78.975057) (xy 205.962002 -79.027617)
			(xy 205.939119 -79.077414) (xy 205.909346 -79.123425) (xy 205.873296 -79.164703) (xy 205.831712 -79.200399)
			(xy 205.808834 -79.215488) (xy 205.796619 -79.223762) (xy 205.77725 -79.246004) (xy 205.765038 -79.27285)
			(xy 205.761002 -79.302066) (xy 205.765476 -79.331218) (xy 205.778088 -79.357878) (xy 205.797789 -79.379827)
			(xy 205.810104 -79.387954) (xy 205.833506 -79.402938) (xy 205.876109 -79.438611) (xy 205.913087 -79.480087)
			(xy 205.943657 -79.526489) (xy 205.967172 -79.576835) (xy 205.983134 -79.63006) (xy 205.991207 -79.685037)
			(xy 205.991714 -79.71282) (xy 205.991228 -79.740071) (xy 205.983472 -79.794019) (xy 205.968117 -79.846314)
			(xy 205.945475 -79.895891) (xy 205.916009 -79.941741) (xy 205.880318 -79.982932) (xy 205.839127 -80.018623)
			(xy 205.793277 -80.048089) (xy 205.7437 -80.070731) (xy 205.691405 -80.086086) (xy 205.637457 -80.093842)
			(xy 205.582955 -80.093842) (xy 205.529007 -80.086086) (xy 205.476712 -80.070731) (xy 205.427135 -80.048089)
			(xy 205.381285 -80.018623) (xy 205.340094 -79.982932) (xy 205.304403 -79.941741) (xy 205.274937 -79.895891)
			(xy 205.252295 -79.846314) (xy 205.23694 -79.794019) (xy 205.229184 -79.740071) (xy 205.228698 -79.71282)
			(xy 205.22912 -79.685415) (xy 205.236974 -79.63117) (xy 205.252509 -79.578608) (xy 205.275405 -79.528809)
			(xy 205.305191 -79.482798) (xy 205.341254 -79.441523) (xy 205.382852 -79.405833) (xy 205.405736 -79.390748)
			(xy 205.417919 -79.382429) (xy 205.437292 -79.360199) (xy 205.449509 -79.333362) (xy 205.453552 -79.304153)
			(xy 205.449083 -79.275007) (xy 205.436475 -79.248351) (xy 205.416779 -79.226407) (xy 205.404466 -79.218282)
			(xy 205.381051 -79.203317) (xy 205.338444 -79.167644) (xy 205.301465 -79.126165) (xy 205.270895 -79.07976)
			(xy 205.247382 -79.02941) (xy 205.231425 -78.976181) (xy 205.223359 -78.921201) (xy 205.222856 -78.893416)
			(xy 196.361167 -78.893416) (xy 196.358252 -78.902219) (xy 196.358002 -78.910688) (xy 196.358002 -78.91907)
			(xy 196.363844 -78.934818) (xy 196.369432 -78.941676) (xy 196.385453 -78.962157) (xy 196.41239 -79.006635)
			(xy 196.433039 -79.054358) (xy 196.447018 -79.104442) (xy 196.454069 -79.155961) (xy 196.454522 -79.18196)
			(xy 196.454445 -79.194698) (xy 196.452794 -79.22012) (xy 196.45122 -79.23276) (xy 196.446789 -79.261748)
			(xy 196.430183 -79.317987) (xy 196.405159 -79.371019) (xy 196.372307 -79.419592) (xy 196.332403 -79.462559)
			(xy 196.309742 -79.481172) (xy 196.307202 -79.483204) (xy 196.303138 -79.487268) (xy 196.296445 -79.494674)
			(xy 196.288845 -79.513111) (xy 196.288406 -79.523082) (xy 196.290692 -79.558896) (xy 196.290692 -79.559404)
			(xy 196.294248 -79.610458) (xy 196.297042 -79.623666) (xy 196.30263 -79.634842) (xy 196.302884 -79.635096)
			(xy 196.303138 -79.635604) (xy 196.305922 -79.639505) (xy 196.312699 -79.646281) (xy 196.3166 -79.649066)
			(xy 196.322442 -79.652622) (xy 196.323204 -79.65313) (xy 196.323458 -79.65313) (xy 196.347604 -79.667955)
			(xy 196.391632 -79.703615) (xy 196.429905 -79.745392) (xy 196.461582 -79.792368) (xy 196.485968 -79.843509)
			(xy 196.502525 -79.897694) (xy 196.510892 -79.953731) (xy 196.511418 -79.98206) (xy 196.510932 -80.009311)
			(xy 196.503176 -80.063259) (xy 196.487821 -80.115554) (xy 196.465179 -80.165131) (xy 196.435713 -80.210981)
			(xy 196.400022 -80.252172) (xy 196.358831 -80.287863) (xy 196.312981 -80.317329) (xy 196.263404 -80.339971)
			(xy 196.211109 -80.355326) (xy 196.157161 -80.363082) (xy 196.102659 -80.363082) (xy 196.048711 -80.355326)
			(xy 195.996416 -80.339971) (xy 195.946839 -80.317329) (xy 195.900989 -80.287863) (xy 195.859798 -80.252172)
			(xy 195.824107 -80.210981) (xy 195.794641 -80.165131) (xy 195.771999 -80.115554) (xy 195.756644 -80.063259)
			(xy 195.748888 -80.009311) (xy 195.748402 -79.98206) (xy 195.748845 -79.955372) (xy 195.756283 -79.902516)
			(xy 195.771021 -79.851215) (xy 195.792772 -79.802472) (xy 195.806568 -79.779622) (xy 195.807076 -79.779114)
			(xy 195.811394 -79.772002) (xy 195.814696 -79.753968) (xy 195.812918 -79.74457) (xy 195.810847 -79.735501)
			(xy 195.801211 -79.719606) (xy 195.794122 -79.713582) (xy 195.792344 -79.712312) (xy 195.784106 -79.706999)
			(xy 195.765059 -79.702436) (xy 195.745686 -79.705313) (xy 195.728787 -79.715213) (xy 195.722494 -79.722726)
			(xy 195.69049 -79.764636) (xy 195.231258 -80.36433) (xy 195.22834 -80.368435) (xy 195.223994 -80.377518)
			(xy 195.222622 -80.382364) (xy 195.220336 -80.390746) (xy 195.220336 -80.391762) (xy 195.221606 -80.40116)
			(xy 195.222928 -80.412163) (xy 195.224453 -80.434275) (xy 195.224654 -80.445356) (xy 195.224654 -80.45069)
			(xy 195.22412 -80.477543) (xy 195.216441 -80.530699) (xy 195.201387 -80.582254) (xy 195.188173 -80.611472)
			(xy 205.228442 -80.611472) (xy 205.232513 -80.55585) (xy 205.244639 -80.501413) (xy 205.264562 -80.449322)
			(xy 205.291858 -80.400687) (xy 205.325944 -80.356544) (xy 205.366093 -80.317835) (xy 205.411451 -80.285384)
			(xy 205.461051 -80.259883) (xy 205.513835 -80.241876) (xy 205.568678 -80.231746) (xy 205.624412 -80.229709)
			(xy 205.679849 -80.235809) (xy 205.733806 -80.249915) (xy 205.785135 -80.271727) (xy 205.832741 -80.300781)
			(xy 205.875609 -80.336456) (xy 205.912826 -80.377993) (xy 205.943599 -80.424506) (xy 205.967271 -80.475003)
			(xy 205.983339 -80.52841) (xy 205.991459 -80.583586) (xy 205.991968 -80.611472) (xy 205.991459 -80.639358)
			(xy 205.983339 -80.694534) (xy 205.967271 -80.747941) (xy 205.943599 -80.798438) (xy 205.912826 -80.844951)
			(xy 205.875609 -80.886488) (xy 205.832741 -80.922163) (xy 205.785135 -80.951217) (xy 205.733806 -80.973029)
			(xy 205.679849 -80.987135) (xy 205.624412 -80.993235) (xy 205.568678 -80.991198) (xy 205.513835 -80.981068)
			(xy 205.461051 -80.963061) (xy 205.411451 -80.93756) (xy 205.366093 -80.905109) (xy 205.325944 -80.8664)
			(xy 205.291858 -80.822257) (xy 205.264562 -80.773622) (xy 205.244639 -80.721531) (xy 205.232513 -80.667094)
			(xy 205.228442 -80.611472) (xy 195.188173 -80.611472) (xy 195.179255 -80.63119) (xy 195.150483 -80.676541)
			(xy 195.115639 -80.717412) (xy 195.07541 -80.752996) (xy 195.03059 -80.78259) (xy 194.982066 -80.805609)
			(xy 194.930793 -80.821601) (xy 194.90436 -80.826356) (xy 194.894962 -80.82788) (xy 194.870324 -80.842104)
			(xy 194.866102 -80.844751) (xy 194.858684 -80.851403) (xy 194.855592 -80.855312) (xy 194.264462 -81.627472)
			(xy 205.228442 -81.627472) (xy 205.232513 -81.57185) (xy 205.244639 -81.517413) (xy 205.264562 -81.465322)
			(xy 205.291858 -81.416687) (xy 205.325944 -81.372544) (xy 205.366093 -81.333835) (xy 205.411451 -81.301384)
			(xy 205.461051 -81.275883) (xy 205.513835 -81.257876) (xy 205.568678 -81.247746) (xy 205.624412 -81.245709)
			(xy 205.679849 -81.251809) (xy 205.733806 -81.265915) (xy 205.785135 -81.287727) (xy 205.832741 -81.316781)
			(xy 205.875609 -81.352456) (xy 205.912826 -81.393993) (xy 205.943599 -81.440506) (xy 205.967271 -81.491003)
			(xy 205.983339 -81.54441) (xy 205.991459 -81.599586) (xy 205.991968 -81.627472) (xy 205.991459 -81.655358)
			(xy 205.983339 -81.710534) (xy 205.967271 -81.763941) (xy 205.943599 -81.814438) (xy 205.912826 -81.860951)
			(xy 205.875609 -81.902488) (xy 205.832741 -81.938163) (xy 205.785135 -81.967217) (xy 205.733806 -81.989029)
			(xy 205.679849 -82.003135) (xy 205.624412 -82.009235) (xy 205.568678 -82.007198) (xy 205.513835 -81.997068)
			(xy 205.461051 -81.979061) (xy 205.411451 -81.95356) (xy 205.366093 -81.921109) (xy 205.325944 -81.8824)
			(xy 205.291858 -81.838257) (xy 205.264562 -81.789622) (xy 205.244639 -81.737531) (xy 205.232513 -81.683094)
			(xy 205.228442 -81.627472) (xy 194.264462 -81.627472) (xy 193.651942 -82.427572) (xy 195.032628 -82.427572)
			(xy 195.036699 -82.37195) (xy 195.048825 -82.317513) (xy 195.068748 -82.265422) (xy 195.096044 -82.216787)
			(xy 195.13013 -82.172644) (xy 195.170279 -82.133935) (xy 195.215637 -82.101484) (xy 195.265237 -82.075983)
			(xy 195.318021 -82.057976) (xy 195.372864 -82.047846) (xy 195.428598 -82.045809) (xy 195.484035 -82.051909)
			(xy 195.537992 -82.066015) (xy 195.589321 -82.087827) (xy 195.636927 -82.116881) (xy 195.679795 -82.152556)
			(xy 195.717012 -82.194093) (xy 195.747785 -82.240606) (xy 195.771457 -82.291103) (xy 195.787525 -82.34451)
			(xy 195.795645 -82.399686) (xy 195.796154 -82.427572) (xy 195.795645 -82.455458) (xy 195.787525 -82.510634)
			(xy 195.771457 -82.564041) (xy 195.747785 -82.614538) (xy 195.717012 -82.661051) (xy 195.679795 -82.702588)
			(xy 195.636927 -82.738263) (xy 195.589321 -82.767317) (xy 195.587874 -82.767932) (xy 203.09662 -82.767932)
			(xy 203.100691 -82.71231) (xy 203.112817 -82.657873) (xy 203.13274 -82.605782) (xy 203.160036 -82.557147)
			(xy 203.194122 -82.513004) (xy 203.234271 -82.474295) (xy 203.279629 -82.441844) (xy 203.329229 -82.416343)
			(xy 203.382013 -82.398336) (xy 203.436856 -82.388206) (xy 203.49259 -82.386169) (xy 203.548027 -82.392269)
			(xy 203.601984 -82.406375) (xy 203.653313 -82.428187) (xy 203.700919 -82.457241) (xy 203.743787 -82.492916)
			(xy 203.781004 -82.534453) (xy 203.811777 -82.580966) (xy 203.835449 -82.631463) (xy 203.839062 -82.643472)
			(xy 205.228442 -82.643472) (xy 205.232513 -82.58785) (xy 205.244639 -82.533413) (xy 205.264562 -82.481322)
			(xy 205.291858 -82.432687) (xy 205.325944 -82.388544) (xy 205.366093 -82.349835) (xy 205.411451 -82.317384)
			(xy 205.461051 -82.291883) (xy 205.513835 -82.273876) (xy 205.568678 -82.263746) (xy 205.624412 -82.261709)
			(xy 205.679849 -82.267809) (xy 205.733806 -82.281915) (xy 205.785135 -82.303727) (xy 205.832741 -82.332781)
			(xy 205.875609 -82.368456) (xy 205.912826 -82.409993) (xy 205.943599 -82.456506) (xy 205.967271 -82.507003)
			(xy 205.983339 -82.56041) (xy 205.991459 -82.615586) (xy 205.991968 -82.643472) (xy 205.991459 -82.671358)
			(xy 205.983339 -82.726534) (xy 205.967271 -82.779941) (xy 205.943599 -82.830438) (xy 205.912826 -82.876951)
			(xy 205.875609 -82.918488) (xy 205.832741 -82.954163) (xy 205.785135 -82.983217) (xy 205.733806 -83.005029)
			(xy 205.679849 -83.019135) (xy 205.624412 -83.025235) (xy 205.568678 -83.023198) (xy 205.513835 -83.013068)
			(xy 205.461051 -82.995061) (xy 205.411451 -82.96956) (xy 205.366093 -82.937109) (xy 205.325944 -82.8984)
			(xy 205.291858 -82.854257) (xy 205.264562 -82.805622) (xy 205.244639 -82.753531) (xy 205.232513 -82.699094)
			(xy 205.228442 -82.643472) (xy 203.839062 -82.643472) (xy 203.851517 -82.68487) (xy 203.859637 -82.740046)
			(xy 203.860146 -82.767932) (xy 203.859637 -82.795818) (xy 203.851517 -82.850994) (xy 203.835449 -82.904401)
			(xy 203.811777 -82.954898) (xy 203.781004 -83.001411) (xy 203.743787 -83.042948) (xy 203.700919 -83.078623)
			(xy 203.653313 -83.107677) (xy 203.601984 -83.129489) (xy 203.548027 -83.143595) (xy 203.49259 -83.149695)
			(xy 203.436856 -83.147658) (xy 203.382013 -83.137528) (xy 203.329229 -83.119521) (xy 203.279629 -83.09402)
			(xy 203.234271 -83.061569) (xy 203.194122 -83.02286) (xy 203.160036 -82.978717) (xy 203.13274 -82.930082)
			(xy 203.112817 -82.877991) (xy 203.100691 -82.823554) (xy 203.09662 -82.767932) (xy 195.587874 -82.767932)
			(xy 195.537992 -82.789129) (xy 195.484035 -82.803235) (xy 195.428598 -82.809335) (xy 195.372864 -82.807298)
			(xy 195.318021 -82.797168) (xy 195.265237 -82.779161) (xy 195.215637 -82.75366) (xy 195.170279 -82.721209)
			(xy 195.13013 -82.6825) (xy 195.096044 -82.638357) (xy 195.068748 -82.589722) (xy 195.048825 -82.537631)
			(xy 195.036699 -82.483194) (xy 195.032628 -82.427572) (xy 193.651942 -82.427572) (xy 193.06159 -83.198716)
			(xy 193.056445 -83.206152) (xy 193.051244 -83.223457) (xy 193.05143 -83.232498) (xy 193.052446 -83.251294)
			(xy 193.054224 -83.253072) (xy 193.065908 -83.26501) (xy 193.086219 -83.28656) (xy 193.120607 -83.334766)
			(xy 193.147142 -83.387703) (xy 193.165187 -83.444102) (xy 193.17431 -83.50261) (xy 193.174874 -83.532218)
			(xy 193.174375 -83.559957) (xy 193.16634 -83.614851) (xy 193.150443 -83.668004) (xy 193.127017 -83.718294)
			(xy 193.096557 -83.764664) (xy 193.059705 -83.806134) (xy 193.017237 -83.841833) (xy 192.970048 -83.871006)
			(xy 192.919133 -83.893041) (xy 192.865563 -83.907471) (xy 192.83807 -83.911186) (xy 192.823592 -83.91271)
			(xy 192.793366 -83.91398) (xy 192.792858 -83.91398) (xy 192.762097 -83.913359) (xy 192.701383 -83.903418)
			(xy 192.64305 -83.883866) (xy 192.615566 -83.870038) (xy 192.605152 -83.864704) (xy 192.603628 -83.863688)
			(xy 192.598294 -83.86064) (xy 192.580006 -83.857846) (xy 192.571624 -83.859624) (xy 192.562834 -83.861846)
			(xy 192.547493 -83.871484) (xy 192.541652 -83.87842) (xy 192.08393 -84.476336) (xy 195.74713 -84.476336)
			(xy 195.751201 -84.420714) (xy 195.763327 -84.366277) (xy 195.78325 -84.314186) (xy 195.810546 -84.265551)
			(xy 195.844632 -84.221408) (xy 195.884781 -84.182699) (xy 195.930139 -84.150248) (xy 195.979739 -84.124747)
			(xy 196.032523 -84.10674) (xy 196.087366 -84.09661) (xy 196.1431 -84.094573) (xy 196.198537 -84.100673)
			(xy 196.252494 -84.114779) (xy 196.303823 -84.136591) (xy 196.351429 -84.165645) (xy 196.394297 -84.20132)
			(xy 196.431514 -84.242857) (xy 196.462287 -84.28937) (xy 196.485959 -84.339867) (xy 196.502027 -84.393274)
			(xy 196.510147 -84.44845) (xy 196.510656 -84.476336) (xy 196.510147 -84.504222) (xy 196.502027 -84.559398)
			(xy 196.485959 -84.612805) (xy 196.462287 -84.663302) (xy 196.454235 -84.675472) (xy 202.825348 -84.675472)
			(xy 202.829419 -84.61985) (xy 202.841545 -84.565413) (xy 202.861468 -84.513322) (xy 202.888764 -84.464687)
			(xy 202.92285 -84.420544) (xy 202.962999 -84.381835) (xy 203.008357 -84.349384) (xy 203.057957 -84.323883)
			(xy 203.110741 -84.305876) (xy 203.165584 -84.295746) (xy 203.221318 -84.293709) (xy 203.276755 -84.299809)
			(xy 203.330712 -84.313915) (xy 203.382041 -84.335727) (xy 203.429647 -84.364781) (xy 203.472515 -84.400456)
			(xy 203.509732 -84.441993) (xy 203.540505 -84.488506) (xy 203.564177 -84.539003) (xy 203.580245 -84.59241)
			(xy 203.588365 -84.647586) (xy 203.588874 -84.675472) (xy 203.588365 -84.703358) (xy 203.580245 -84.758534)
			(xy 203.564177 -84.811941) (xy 203.540505 -84.862438) (xy 203.509732 -84.908951) (xy 203.472515 -84.950488)
			(xy 203.429647 -84.986163) (xy 203.382041 -85.015217) (xy 203.330712 -85.037029) (xy 203.276755 -85.051135)
			(xy 203.221318 -85.057235) (xy 203.165584 -85.055198) (xy 203.110741 -85.045068) (xy 203.057957 -85.027061)
			(xy 203.008357 -85.00156) (xy 202.962999 -84.969109) (xy 202.92285 -84.9304) (xy 202.888764 -84.886257)
			(xy 202.861468 -84.837622) (xy 202.841545 -84.785531) (xy 202.829419 -84.731094) (xy 202.825348 -84.675472)
			(xy 196.454235 -84.675472) (xy 196.431514 -84.709815) (xy 196.394297 -84.751352) (xy 196.351429 -84.787027)
			(xy 196.303823 -84.816081) (xy 196.252494 -84.837893) (xy 196.198537 -84.851999) (xy 196.1431 -84.858099)
			(xy 196.087366 -84.856062) (xy 196.032523 -84.845932) (xy 195.979739 -84.827925) (xy 195.930139 -84.802424)
			(xy 195.884781 -84.769973) (xy 195.844632 -84.731264) (xy 195.810546 -84.687121) (xy 195.78325 -84.638486)
			(xy 195.763327 -84.586395) (xy 195.751201 -84.531958) (xy 195.74713 -84.476336) (xy 192.08393 -84.476336)
			(xy 191.153707 -85.691472) (xy 202.857352 -85.691472) (xy 202.861423 -85.63585) (xy 202.873549 -85.581413)
			(xy 202.893472 -85.529322) (xy 202.920768 -85.480687) (xy 202.954854 -85.436544) (xy 202.995003 -85.397835)
			(xy 203.040361 -85.365384) (xy 203.089961 -85.339883) (xy 203.142745 -85.321876) (xy 203.197588 -85.311746)
			(xy 203.253322 -85.309709) (xy 203.308759 -85.315809) (xy 203.362716 -85.329915) (xy 203.414045 -85.351727)
			(xy 203.461651 -85.380781) (xy 203.504519 -85.416456) (xy 203.541736 -85.457993) (xy 203.572509 -85.504506)
			(xy 203.596181 -85.555003) (xy 203.612249 -85.60841) (xy 203.620369 -85.663586) (xy 203.620878 -85.691472)
			(xy 203.620369 -85.719358) (xy 203.612249 -85.774534) (xy 203.596181 -85.827941) (xy 203.572509 -85.878438)
			(xy 203.541736 -85.924951) (xy 203.504519 -85.966488) (xy 203.461651 -86.002163) (xy 203.414045 -86.031217)
			(xy 203.362716 -86.053029) (xy 203.308759 -86.067135) (xy 203.253322 -86.073235) (xy 203.197588 -86.071198)
			(xy 203.142745 -86.061068) (xy 203.089961 -86.043061) (xy 203.040361 -86.01756) (xy 202.995003 -85.985109)
			(xy 202.954854 -85.9464) (xy 202.920768 -85.902257) (xy 202.893472 -85.853622) (xy 202.873549 -85.801531)
			(xy 202.861423 -85.747094) (xy 202.857352 -85.691472) (xy 191.153707 -85.691472) (xy 190.727679 -86.247986)
			(xy 191.338452 -86.247986) (xy 191.342523 -86.192364) (xy 191.354649 -86.137927) (xy 191.374572 -86.085836)
			(xy 191.401868 -86.037201) (xy 191.435954 -85.993058) (xy 191.476103 -85.954349) (xy 191.521461 -85.921898)
			(xy 191.571061 -85.896397) (xy 191.623845 -85.87839) (xy 191.678688 -85.86826) (xy 191.734422 -85.866223)
			(xy 191.789859 -85.872323) (xy 191.843816 -85.886429) (xy 191.895145 -85.908241) (xy 191.942751 -85.937295)
			(xy 191.985619 -85.97297) (xy 192.022836 -86.014507) (xy 192.053609 -86.06102) (xy 192.077281 -86.111517)
			(xy 192.093349 -86.164924) (xy 192.101469 -86.2201) (xy 192.101978 -86.247986) (xy 192.101469 -86.275872)
			(xy 192.093349 -86.331048) (xy 192.077281 -86.384455) (xy 192.053609 -86.434952) (xy 192.022836 -86.481465)
			(xy 191.985619 -86.523002) (xy 191.942751 -86.558677) (xy 191.895145 -86.587731) (xy 191.843816 -86.609543)
			(xy 191.789859 -86.623649) (xy 191.734422 -86.629749) (xy 191.678688 -86.627712) (xy 191.623845 -86.617582)
			(xy 191.571061 -86.599575) (xy 191.521461 -86.574074) (xy 191.476103 -86.541623) (xy 191.435954 -86.502914)
			(xy 191.401868 -86.458771) (xy 191.374572 -86.410136) (xy 191.354649 -86.358045) (xy 191.342523 -86.303608)
			(xy 191.338452 -86.247986) (xy 190.727679 -86.247986) (xy 184.47512 -94.41561) (xy 184.469278 -94.428056)
			(xy 184.263538 -95.29318) (xy 184.10682 -95.952818) (xy 184.105296 -95.959422) (xy 184.105296 -95.959676)
			(xy 184.05475 -96.18472) (xy 184.053499 -96.191234) (xy 184.054013 -96.204484) (xy 184.055766 -96.210882)
			(xy 184.056274 -96.21266) (xy 184.057036 -96.213676) (xy 184.073319 -96.237878) (xy 184.099129 -96.290185)
			(xy 184.116676 -96.345811) (xy 184.125551 -96.40346) (xy 184.126124 -96.432624) (xy 184.126124 -96.440244)
			(xy 184.125112 -96.467757) (xy 184.116153 -96.522079) (xy 184.09948 -96.574549) (xy 184.07544 -96.624079)
			(xy 184.044531 -96.669639) (xy 184.007396 -96.710285) (xy 183.964805 -96.745172) (xy 183.941466 -96.759776)
			(xy 183.93664 -96.762824) (xy 183.932867 -96.76532) (xy 183.926223 -96.771456) (xy 183.923432 -96.775016)
			(xy 183.9214 -96.77781) (xy 183.915798 -96.802702) (xy 185.421776 -96.802702) (xy 185.425847 -96.74708)
			(xy 185.437973 -96.692643) (xy 185.457896 -96.640552) (xy 185.485192 -96.591917) (xy 185.519278 -96.547774)
			(xy 185.559427 -96.509065) (xy 185.604785 -96.476614) (xy 185.654385 -96.451113) (xy 185.707169 -96.433106)
			(xy 185.762012 -96.422976) (xy 185.817746 -96.420939) (xy 185.873183 -96.427039) (xy 185.92714 -96.441145)
			(xy 185.978469 -96.462957) (xy 186.026075 -96.492011) (xy 186.068943 -96.527686) (xy 186.10616 -96.569223)
			(xy 186.136933 -96.615736) (xy 186.160605 -96.666233) (xy 186.176673 -96.71964) (xy 186.184793 -96.774816)
			(xy 186.185302 -96.802702) (xy 186.184793 -96.830588) (xy 186.176673 -96.885764) (xy 186.160605 -96.939171)
			(xy 186.136933 -96.989668) (xy 186.10616 -97.036181) (xy 186.068943 -97.077718) (xy 186.026075 -97.113393)
			(xy 185.978469 -97.142447) (xy 185.92714 -97.164259) (xy 185.873183 -97.178365) (xy 185.817746 -97.184465)
			(xy 185.762012 -97.182428) (xy 185.707169 -97.172298) (xy 185.654385 -97.154291) (xy 185.604785 -97.12879)
			(xy 185.559427 -97.096339) (xy 185.519278 -97.05763) (xy 185.485192 -97.013487) (xy 185.457896 -96.964852)
			(xy 185.437973 -96.912761) (xy 185.425847 -96.858324) (xy 185.421776 -96.802702) (xy 183.915798 -96.802702)
			(xy 183.838342 -97.146872) (xy 183.737758 -97.593658) (xy 183.739282 -97.60331) (xy 183.741512 -97.618132)
			(xy 183.743929 -97.648012) (xy 183.744108 -97.663) (xy 183.743598 -97.691622) (xy 183.735054 -97.748224)
			(xy 183.718159 -97.802916) (xy 183.69329 -97.854475) (xy 183.67756 -97.878392) (xy 183.671972 -97.88652)
			(xy 183.562498 -98.373692) (xy 183.411114 -99.0473) (xy 183.41086 -99.050348) (xy 183.410352 -99.054666)
			(xy 183.41056 -99.067225) (xy 183.42163 -99.089738) (xy 183.431434 -99.097592) (xy 183.477916 -99.129342)
			(xy 183.483893 -99.13285) (xy 183.497158 -99.136841) (xy 183.504078 -99.137216) (xy 183.50738 -99.137216)
			(xy 183.528341 -99.120709) (xy 183.573919 -99.092971) (xy 183.622851 -99.071705) (xy 183.674225 -99.057305)
			(xy 183.727083 -99.050042) (xy 183.75376 -99.049586) (xy 183.781651 -99.050057) (xy 183.836866 -99.057991)
			(xy 183.890389 -99.073702) (xy 183.941132 -99.096871) (xy 183.98806 -99.127025) (xy 184.030219 -99.163552)
			(xy 184.066751 -99.205708) (xy 184.09691 -99.252633) (xy 184.120084 -99.303373) (xy 184.135801 -99.356895)
			(xy 184.14374 -99.412109) (xy 184.14374 -99.467891) (xy 184.135801 -99.523105) (xy 184.120084 -99.576627)
			(xy 184.09691 -99.627367) (xy 184.066751 -99.674292) (xy 184.030219 -99.716448) (xy 183.98806 -99.752975)
			(xy 183.941132 -99.783129) (xy 183.890389 -99.806298) (xy 183.836866 -99.822009) (xy 183.781651 -99.829943)
			(xy 183.75376 -99.830382) (xy 183.725689 -99.829892) (xy 183.670126 -99.821846) (xy 183.616288 -99.805925)
			(xy 183.565285 -99.782458) (xy 183.518169 -99.751929) (xy 183.475911 -99.714967) (xy 183.439382 -99.672333)
			(xy 183.409335 -99.624908) (xy 183.397398 -99.599496) (xy 183.394858 -99.597972) (xy 183.388762 -99.594924)
			(xy 183.381396 -99.593654) (xy 183.37761 -99.593094) (xy 183.369958 -99.592963) (xy 183.366156 -99.5934)
			(xy 183.327294 -99.59848) (xy 183.321198 -99.599242) (xy 183.310927 -99.601053) (xy 183.293005 -99.61168)
			(xy 183.280783 -99.628554) (xy 183.278018 -99.638612) (xy 183.200634 -99.982782) (xy 186.221876 -99.982782)
			(xy 186.225947 -99.92716) (xy 186.238073 -99.872723) (xy 186.257996 -99.820632) (xy 186.285292 -99.771997)
			(xy 186.319378 -99.727854) (xy 186.359527 -99.689145) (xy 186.404885 -99.656694) (xy 186.454485 -99.631193)
			(xy 186.507269 -99.613186) (xy 186.562112 -99.603056) (xy 186.617846 -99.601019) (xy 186.673283 -99.607119)
			(xy 186.72724 -99.621225) (xy 186.778569 -99.643037) (xy 186.826175 -99.672091) (xy 186.869043 -99.707766)
			(xy 186.90626 -99.749303) (xy 186.937033 -99.795816) (xy 186.960705 -99.846313) (xy 186.976773 -99.89972)
			(xy 186.984893 -99.954896) (xy 186.985402 -99.982782) (xy 186.984893 -100.010668) (xy 186.976773 -100.065844)
			(xy 186.960705 -100.119251) (xy 186.937033 -100.169748) (xy 186.90626 -100.216261) (xy 186.869043 -100.257798)
			(xy 186.826175 -100.293473) (xy 186.778569 -100.322527) (xy 186.72724 -100.344339) (xy 186.673283 -100.358445)
			(xy 186.617846 -100.364545) (xy 186.562112 -100.362508) (xy 186.507269 -100.352378) (xy 186.454485 -100.334371)
			(xy 186.404885 -100.30887) (xy 186.359527 -100.276419) (xy 186.319378 -100.23771) (xy 186.285292 -100.193567)
			(xy 186.257996 -100.144932) (xy 186.238073 -100.092841) (xy 186.225947 -100.038404) (xy 186.221876 -99.982782)
			(xy 183.200634 -99.982782) (xy 182.917941 -101.240082) (xy 183.371742 -101.240082) (xy 183.375813 -101.18446)
			(xy 183.387939 -101.130023) (xy 183.407862 -101.077932) (xy 183.435158 -101.029297) (xy 183.469244 -100.985154)
			(xy 183.509393 -100.946445) (xy 183.554751 -100.913994) (xy 183.604351 -100.888493) (xy 183.657135 -100.870486)
			(xy 183.711978 -100.860356) (xy 183.767712 -100.858319) (xy 183.823149 -100.864419) (xy 183.877106 -100.878525)
			(xy 183.928435 -100.900337) (xy 183.976041 -100.929391) (xy 184.018909 -100.965066) (xy 184.056126 -101.006603)
			(xy 184.086899 -101.053116) (xy 184.110571 -101.103613) (xy 184.126639 -101.15702) (xy 184.134759 -101.212196)
			(xy 184.135268 -101.240082) (xy 184.134759 -101.267968) (xy 184.126639 -101.323144) (xy 184.110571 -101.376551)
			(xy 184.086899 -101.427048) (xy 184.056126 -101.473561) (xy 184.018909 -101.515098) (xy 183.976041 -101.550773)
			(xy 183.928435 -101.579827) (xy 183.877106 -101.601639) (xy 183.823149 -101.615745) (xy 183.767712 -101.621845)
			(xy 183.711978 -101.619808) (xy 183.657135 -101.609678) (xy 183.604351 -101.591671) (xy 183.554751 -101.56617)
			(xy 183.509393 -101.533719) (xy 183.469244 -101.49501) (xy 183.435158 -101.450867) (xy 183.407862 -101.402232)
			(xy 183.387939 -101.350141) (xy 183.375813 -101.295704) (xy 183.371742 -101.240082) (xy 182.917941 -101.240082)
			(xy 182.602124 -102.644702) (xy 182.60314 -102.653592) (xy 182.60455 -102.665352) (xy 182.606077 -102.688992)
			(xy 182.606188 -102.700836) (xy 182.605724 -102.727824) (xy 182.598121 -102.781261) (xy 182.583058 -102.833092)
			(xy 182.560836 -102.882281) (xy 182.546752 -102.905306) (xy 182.545482 -102.907084) (xy 182.541926 -102.91318)
			(xy 182.323232 -103.885238) (xy 182.3085 -103.95077) (xy 182.299102 -103.992934) (xy 182.297636 -104.001153)
			(xy 182.299448 -104.017739) (xy 182.302658 -104.025446) (xy 182.305198 -104.031034) (xy 182.320184 -104.04602)
			(xy 182.326788 -104.049576) (xy 182.35225 -104.06401) (xy 182.398812 -104.099471) (xy 182.439409 -104.141629)
			(xy 182.473088 -104.189496) (xy 182.499058 -104.241946) (xy 182.51671 -104.297748) (xy 182.525629 -104.355592)
			(xy 182.526178 -104.384856) (xy 182.525713 -104.411459) (xy 182.518313 -104.464148) (xy 182.503665 -104.515298)
			(xy 182.482053 -104.563917) (xy 182.453896 -104.609063) (xy 182.41974 -104.649858) (xy 182.380247 -104.685512)
			(xy 182.336184 -104.715335) (xy 182.288406 -104.738746) (xy 182.237838 -104.755292) (xy 182.185461 -104.764653)
			(xy 182.158894 -104.76611) (xy 182.15864 -104.76611) (xy 182.155592 -104.766364) (xy 182.146194 -104.766872)
			(xy 182.133748 -104.77754) (xy 182.12757 -104.783084) (xy 182.118869 -104.797207) (xy 182.11673 -104.805226)
			(xy 181.769004 -106.350308) (xy 181.610254 -107.056682) (xy 181.61 -107.057444) (xy 181.609492 -107.05973)
			(xy 181.431692 -107.992164) (xy 180.871876 -110.929674) (xy 180.870398 -110.940247) (xy 180.875194 -110.961023)
			(xy 180.887993 -110.978078) (xy 180.897022 -110.983776) (xy 180.901086 -110.985554) (xy 180.925988 -110.997172)
			(xy 180.972454 -111.026503) (xy 181.014233 -111.062196) (xy 181.05046 -111.103513) (xy 181.080385 -111.149599)
			(xy 181.103391 -111.199501) (xy 181.119 -111.252187) (xy 181.12689 -111.306567) (xy 181.1274 -111.334042)
			(xy 181.126886 -111.362395) (xy 181.118501 -111.418477) (xy 181.101907 -111.472699) (xy 181.07747 -111.523869)
			(xy 181.045728 -111.570857) (xy 181.00738 -111.61263) (xy 180.963272 -111.648266) (xy 180.914374 -111.676981)
			(xy 180.861765 -111.698141) (xy 180.806604 -111.711281) (xy 180.778404 -111.71428) (xy 180.770276 -111.715042)
			(xy 180.76291 -111.71809) (xy 180.762402 -111.718344) (xy 180.758928 -111.719817) (xy 180.752423 -111.723643)
			(xy 180.749448 -111.725964) (xy 180.736494 -111.737394) (xy 180.726334 -111.746284) (xy 180.721079 -111.751583)
			(xy 180.713606 -111.764494) (xy 180.711602 -111.771684) (xy 180.693314 -111.867188) (xy 180.612034 -112.294924)
			(xy 180.61178 -112.302798) (xy 180.612288 -112.307878) (xy 180.613025 -112.312677) (xy 180.61609 -112.321888)
			(xy 180.618384 -112.326166) (xy 180.620924 -112.330738) (xy 180.623464 -112.335818) (xy 180.63657 -112.362499)
			(xy 180.655281 -112.418919) (xy 180.665036 -112.477554) (xy 180.66526 -112.485424) (xy 182.750966 -112.485424)
			(xy 182.755037 -112.429802) (xy 182.767163 -112.375365) (xy 182.787086 -112.323274) (xy 182.814382 -112.274639)
			(xy 182.848468 -112.230496) (xy 182.888617 -112.191787) (xy 182.933975 -112.159336) (xy 182.983575 -112.133835)
			(xy 183.036359 -112.115828) (xy 183.091202 -112.105698) (xy 183.146936 -112.103661) (xy 183.202373 -112.109761)
			(xy 183.25633 -112.123867) (xy 183.307659 -112.145679) (xy 183.355265 -112.174733) (xy 183.398133 -112.210408)
			(xy 183.43535 -112.251945) (xy 183.466123 -112.298458) (xy 183.489795 -112.348955) (xy 183.505863 -112.402362)
			(xy 183.513983 -112.457538) (xy 183.514492 -112.485424) (xy 183.513983 -112.51331) (xy 183.505863 -112.568486)
			(xy 183.489795 -112.621893) (xy 183.466123 -112.67239) (xy 183.43535 -112.718903) (xy 183.398133 -112.76044)
			(xy 183.355265 -112.796115) (xy 183.307659 -112.825169) (xy 183.25633 -112.846981) (xy 183.202373 -112.861087)
			(xy 183.146936 -112.867187) (xy 183.091202 -112.86515) (xy 183.036359 -112.85502) (xy 182.983575 -112.837013)
			(xy 182.933975 -112.811512) (xy 182.888617 -112.779061) (xy 182.848468 -112.740352) (xy 182.814382 -112.696209)
			(xy 182.787086 -112.647574) (xy 182.767163 -112.595483) (xy 182.755037 -112.541046) (xy 182.750966 -112.485424)
			(xy 180.66526 -112.485424) (xy 180.665882 -112.507268) (xy 180.665882 -112.510824) (xy 180.66538 -112.538593)
			(xy 180.657323 -112.593543) (xy 180.641384 -112.646744) (xy 180.617898 -112.697071) (xy 180.587363 -112.743461)
			(xy 180.550424 -112.784933) (xy 180.529484 -112.803178) (xy 180.528214 -112.804448) (xy 180.520086 -112.812322)
			(xy 180.51526 -112.818672) (xy 180.510434 -112.8268) (xy 180.506116 -112.850676) (xy 180.505608 -112.85728)
			(xy 180.506059 -112.868677) (xy 180.515549 -112.889386) (xy 180.523896 -112.897158) (xy 180.528468 -112.90046)
			(xy 180.551328 -112.915446) (xy 180.556975 -112.918975) (xy 180.569588 -112.923237) (xy 180.57622 -112.923828)
			(xy 180.579268 -112.923828) (xy 180.603652 -112.917478) (xy 180.603906 -112.917478) (xy 180.630589 -112.90347)
			(xy 180.68731 -112.883117) (xy 180.746524 -112.871927) (xy 180.776626 -112.870488) (xy 180.777134 -112.870488)
			(xy 180.786024 -112.870234) (xy 180.791612 -112.870234) (xy 180.818698 -112.870958) (xy 180.872264 -112.879119)
			(xy 180.924136 -112.894776) (xy 180.973271 -112.917616) (xy 181.018679 -112.947178) (xy 181.059448 -112.982868)
			(xy 181.094757 -113.023968) (xy 181.123895 -113.06965) (xy 181.146276 -113.118995) (xy 181.161449 -113.171011)
			(xy 181.16911 -113.22465) (xy 181.169564 -113.251742) (xy 181.169093 -113.278751) (xy 181.161469 -113.332227)
			(xy 181.146379 -113.384094) (xy 181.124124 -113.433314) (xy 181.12297 -113.43513) (xy 183.03062 -113.43513)
			(xy 183.034691 -113.379508) (xy 183.046817 -113.325071) (xy 183.06674 -113.27298) (xy 183.094036 -113.224345)
			(xy 183.128122 -113.180202) (xy 183.168271 -113.141493) (xy 183.213629 -113.109042) (xy 183.263229 -113.083541)
			(xy 183.316013 -113.065534) (xy 183.370856 -113.055404) (xy 183.42659 -113.053367) (xy 183.482027 -113.059467)
			(xy 183.535984 -113.073573) (xy 183.587313 -113.095385) (xy 183.634919 -113.124439) (xy 183.677787 -113.160114)
			(xy 183.715004 -113.201651) (xy 183.745777 -113.248164) (xy 183.769449 -113.298661) (xy 183.785517 -113.352068)
			(xy 183.793637 -113.407244) (xy 183.794146 -113.43513) (xy 183.793637 -113.463016) (xy 183.785517 -113.518192)
			(xy 183.769449 -113.571599) (xy 183.745777 -113.622096) (xy 183.715004 -113.668609) (xy 183.677787 -113.710146)
			(xy 183.634919 -113.745821) (xy 183.587313 -113.774875) (xy 183.535984 -113.796687) (xy 183.482027 -113.810793)
			(xy 183.42659 -113.816893) (xy 183.370856 -113.814856) (xy 183.316013 -113.804726) (xy 183.263229 -113.786719)
			(xy 183.213629 -113.761218) (xy 183.168271 -113.728767) (xy 183.128122 -113.690058) (xy 183.094036 -113.645915)
			(xy 183.06674 -113.59728) (xy 183.046817 -113.545189) (xy 183.034691 -113.490752) (xy 183.03062 -113.43513)
			(xy 181.12297 -113.43513) (xy 181.095151 -113.478904) (xy 181.060038 -113.519951) (xy 181.019486 -113.555637)
			(xy 180.974307 -113.585246) (xy 180.925404 -113.608188) (xy 180.873753 -113.624003) (xy 180.820389 -113.632376)
			(xy 180.79339 -113.63325) (xy 180.787548 -113.63325) (xy 180.760476 -113.632758) (xy 180.70688 -113.625064)
			(xy 180.654911 -113.609867) (xy 180.605615 -113.587471) (xy 180.559982 -113.558329) (xy 180.539136 -113.541048)
			(xy 180.532532 -113.535206) (xy 180.512212 -113.527332) (xy 180.503867 -113.524369) (xy 180.486178 -113.523863)
			(xy 180.477668 -113.526316) (xy 180.39842 -113.552986) (xy 180.39024 -113.556075) (xy 180.376479 -113.566843)
			(xy 180.367165 -113.581625) (xy 180.364892 -113.59007) (xy 180.175994 -114.581432) (xy 182.39994 -114.581432)
			(xy 182.400426 -114.554181) (xy 182.408182 -114.500233) (xy 182.423537 -114.447938) (xy 182.446179 -114.398361)
			(xy 182.475645 -114.352511) (xy 182.511336 -114.31132) (xy 182.552527 -114.275629) (xy 182.598377 -114.246163)
			(xy 182.647954 -114.223521) (xy 182.700249 -114.208166) (xy 182.754197 -114.20041) (xy 182.808699 -114.20041)
			(xy 182.862647 -114.208166) (xy 182.914942 -114.223521) (xy 182.964519 -114.246163) (xy 183.010369 -114.275629)
			(xy 183.05156 -114.31132) (xy 183.087251 -114.352511) (xy 183.116717 -114.398361) (xy 183.139359 -114.447938)
			(xy 183.154714 -114.500233) (xy 183.16247 -114.554181) (xy 183.162956 -114.581432) (xy 183.16194 -114.607848)
			(xy 183.16194 -114.608102) (xy 183.161795 -114.619898) (xy 183.170928 -114.641618) (xy 183.179466 -114.649758)
			(xy 183.250586 -114.710718) (xy 183.273446 -114.71656) (xy 183.28513 -114.71402) (xy 183.285638 -114.71402)
			(xy 183.316976 -114.707429) (xy 183.380618 -114.700296) (xy 183.412638 -114.699796) (xy 183.717438 -114.699796)
			(xy 183.727513 -114.699418) (xy 183.746112 -114.691667) (xy 183.753506 -114.68481) (xy 184.25033 -114.187986)
			(xy 184.257173 -114.180588) (xy 184.26489 -114.161987) (xy 184.265316 -114.151918) (xy 184.265316 -111.185706)
			(xy 184.265755 -111.152825) (xy 184.273122 -111.087477) (xy 184.287764 -111.023365) (xy 184.309496 -110.961298)
			(xy 184.338044 -110.902055) (xy 184.37305 -110.846385) (xy 184.414073 -110.794986) (xy 184.43702 -110.771432)
			(xy 187.320174 -107.888278) (xy 187.343763 -107.865405) (xy 187.395134 -107.824438) (xy 187.450769 -107.789479)
			(xy 187.509969 -107.76097) (xy 187.571988 -107.739268) (xy 187.636047 -107.724646) (xy 187.701341 -107.717289)
			(xy 187.734194 -107.716828) (xy 188.575696 -107.716828) (xy 188.585768 -107.716419) (xy 188.604366 -107.708689)
			(xy 188.611764 -107.701842) (xy 188.627004 -107.686602) (xy 188.633737 -107.679152) (xy 188.641302 -107.660569)
			(xy 188.641736 -107.650534) (xy 188.641736 -105.929176) (xy 188.64134 -105.919103) (xy 188.633601 -105.900504)
			(xy 188.62675 -105.893108) (xy 188.022738 -105.289096) (xy 187.999843 -105.265528) (xy 187.958879 -105.214152)
			(xy 187.923924 -105.158513) (xy 187.895418 -105.09931) (xy 187.873719 -105.037287) (xy 187.859101 -104.973226)
			(xy 187.851747 -104.90793) (xy 187.851288 -104.875076) (xy 187.851288 -97.650046) (xy 187.851734 -97.617192)
			(xy 187.859102 -97.551899) (xy 187.87373 -97.48784) (xy 187.895432 -97.425819) (xy 187.923936 -97.366616)
			(xy 187.958885 -97.310973) (xy 187.99984 -97.25959) (xy 188.022738 -97.236026) (xy 188.890656 -96.368108)
			(xy 188.897347 -96.360702) (xy 188.904945 -96.342266) (xy 188.904944 -96.322326) (xy 188.897342 -96.303891)
			(xy 188.890656 -96.29648) (xy 188.883036 -96.28886) (xy 188.863224 -96.280986) (xy 188.852556 -96.281494)
			(xy 188.807598 -96.28251) (xy 188.807344 -96.28251) (xy 188.760755 -96.282073) (xy 188.667931 -96.273963)
			(xy 188.576167 -96.257794) (xy 188.486162 -96.233688) (xy 188.3986 -96.201829) (xy 188.314149 -96.162459)
			(xy 188.233451 -96.115877) (xy 188.15712 -96.062439) (xy 188.085737 -96.002551) (xy 188.019846 -95.936669)
			(xy 187.959949 -95.865294) (xy 187.9065 -95.788971) (xy 187.859908 -95.708279) (xy 187.820526 -95.623833)
			(xy 187.788655 -95.536275) (xy 187.764537 -95.446273) (xy 187.748355 -95.354512) (xy 187.740234 -95.261689)
			(xy 187.740234 -95.168511) (xy 187.748355 -95.075688) (xy 187.764537 -94.983927) (xy 187.788655 -94.893925)
			(xy 187.820526 -94.806367) (xy 187.859908 -94.721921) (xy 187.9065 -94.641229) (xy 187.959949 -94.564906)
			(xy 188.019846 -94.493531) (xy 188.085737 -94.427649) (xy 188.15712 -94.367761) (xy 188.233451 -94.314323)
			(xy 188.314149 -94.267741) (xy 188.3986 -94.228371) (xy 188.486162 -94.196512) (xy 188.576167 -94.172406)
			(xy 188.667931 -94.156237) (xy 188.760755 -94.148127) (xy 188.807344 -94.14764) (xy 188.807598 -94.14764)
			(xy 188.856617 -94.148183) (xy 188.954241 -94.157182) (xy 189.050628 -94.175094) (xy 189.144967 -94.201769)
			(xy 189.236463 -94.236982) (xy 189.324344 -94.280436) (xy 189.366398 -94.305628) (xy 189.374246 -94.310052)
			(xy 189.391903 -94.313577) (xy 189.409684 -94.310745) (xy 189.417706 -94.306644) (xy 189.495176 -94.26321)
			(xy 189.502843 -94.258512) (xy 189.514525 -94.244859) (xy 189.520737 -94.227999) (xy 189.521084 -94.219014)
			(xy 189.521084 -93.711268) (xy 189.521573 -93.678388) (xy 189.528932 -93.613042) (xy 189.543566 -93.548932)
			(xy 189.565291 -93.486865) (xy 189.593831 -93.427623) (xy 189.62883 -93.37195) (xy 189.669845 -93.32055)
			(xy 189.692788 -93.296994) (xy 192.672462 -90.31732) (xy 192.679111 -90.309966) (xy 192.686682 -90.291662)
			(xy 192.687194 -90.28176) (xy 192.687702 -90.209878) (xy 192.687263 -90.199907) (xy 192.679663 -90.18147)
			(xy 192.67297 -90.174064) (xy 192.652494 -90.152506) (xy 192.617795 -90.104227) (xy 192.591008 -90.051148)
			(xy 192.572781 -89.994556) (xy 192.563556 -89.935821) (xy 192.562988 -89.906094) (xy 192.563472 -89.878843)
			(xy 192.571229 -89.824895) (xy 192.586585 -89.772601) (xy 192.609227 -89.723024) (xy 192.638693 -89.677174)
			(xy 192.674385 -89.635983) (xy 192.715575 -89.600292) (xy 192.761425 -89.570826) (xy 192.811003 -89.548184)
			(xy 192.863297 -89.532829) (xy 192.917245 -89.525072) (xy 192.944496 -89.524586) (xy 192.974223 -89.525143)
			(xy 193.032957 -89.534378) (xy 193.089547 -89.552609) (xy 193.142626 -89.579397) (xy 193.190908 -89.614091)
			(xy 193.212466 -89.634568) (xy 193.219878 -89.641246) (xy 193.238314 -89.648822) (xy 193.24828 -89.6493)
			(xy 193.320162 -89.648792) (xy 193.330064 -89.648284) (xy 193.348364 -89.640706) (xy 193.355722 -89.63406)
			(xy 195.028058 -87.961724) (xy 195.051639 -87.93881) (xy 195.10305 -87.897816) (xy 195.158723 -87.862829)
			(xy 195.217961 -87.834289) (xy 195.280019 -87.812553) (xy 195.344118 -87.797896) (xy 195.409455 -87.7905)
			(xy 195.442332 -87.79002) (xy 196.306186 -87.79002) (xy 196.339534 -87.790512) (xy 196.4058 -87.798076)
			(xy 196.470778 -87.81312) (xy 196.533626 -87.835448) (xy 196.593531 -87.864772) (xy 196.649716 -87.900711)
			(xy 196.701455 -87.9428) (xy 196.748077 -87.990495) (xy 196.788979 -88.043178) (xy 196.82363 -88.100166)
			(xy 196.851583 -88.160722) (xy 196.872476 -88.224062) (xy 196.879718 -88.256618) (xy 196.883528 -88.274398)
			(xy 196.911214 -88.297004) (xy 196.988684 -88.297004) (xy 196.998756 -88.296596) (xy 197.017355 -88.288866)
			(xy 197.024752 -88.282018) (xy 197.325234 -87.981536) (xy 197.348828 -87.958636) (xy 197.400236 -87.91764)
			(xy 197.455907 -87.882651) (xy 197.515142 -87.854109) (xy 197.577198 -87.832372) (xy 197.641296 -87.817712)
			(xy 197.706632 -87.810313) (xy 197.739508 -87.809832) (xy 197.774915 -87.810382) (xy 197.845212 -87.818921)
			(xy 197.913967 -87.835872) (xy 197.980177 -87.860989) (xy 198.042876 -87.893906) (xy 198.101149 -87.934141)
			(xy 198.154146 -87.981109) (xy 198.201094 -88.034123) (xy 198.241307 -88.092411) (xy 198.2742 -88.155122)
			(xy 198.299293 -88.221341) (xy 198.316219 -88.290102) (xy 198.324731 -88.360403) (xy 198.325232 -88.39581)
			(xy 198.3248 -88.428682) (xy 198.317451 -88.494014) (xy 198.302835 -88.558113) (xy 198.281136 -88.620173)
			(xy 198.252627 -88.679414) (xy 198.217666 -88.735092) (xy 198.176692 -88.786506) (xy 198.153782 -88.810084)
			(xy 197.66661 -89.297256) (xy 197.64304 -89.320182) (xy 197.591628 -89.361176) (xy 197.535952 -89.396162)
			(xy 197.476713 -89.424701) (xy 197.414653 -89.446434) (xy 197.350552 -89.461089) (xy 197.285213 -89.468482)
			(xy 197.252336 -89.46896) (xy 197.13702 -89.46896) (xy 197.128401 -89.469245) (xy 197.112127 -89.47492)
			(xy 197.098677 -89.485696) (xy 197.09384 -89.492836) (xy 197.041262 -89.577164) (xy 197.039738 -89.602818)
			(xy 197.04558 -89.614756) (xy 197.057683 -89.640847) (xy 197.074776 -89.695762) (xy 197.083414 -89.752623)
			(xy 197.083934 -89.78138) (xy 197.083448 -89.808631) (xy 197.075692 -89.862579) (xy 197.060337 -89.914874)
			(xy 197.037695 -89.964451) (xy 197.008229 -90.010301) (xy 196.972538 -90.051492) (xy 196.931347 -90.087183)
			(xy 196.885497 -90.116649) (xy 196.83592 -90.139291) (xy 196.783625 -90.154646) (xy 196.729677 -90.162402)
			(xy 196.675175 -90.162402) (xy 196.621227 -90.154646) (xy 196.568932 -90.139291) (xy 196.519355 -90.116649)
			(xy 196.473505 -90.087183) (xy 196.432314 -90.051492) (xy 196.396623 -90.010301) (xy 196.367157 -89.964451)
			(xy 196.344515 -89.914874) (xy 196.32916 -89.862579) (xy 196.321404 -89.808631) (xy 196.320918 -89.78138)
			(xy 196.321465 -89.752625) (xy 196.330115 -89.69577) (xy 196.347186 -89.640853) (xy 196.359272 -89.614756)
			(xy 196.365114 -89.602818) (xy 196.36359 -89.577164) (xy 196.311012 -89.492836) (xy 196.306118 -89.48575)
			(xy 196.292668 -89.475018) (xy 196.276435 -89.469311) (xy 196.267832 -89.46896) (xy 196.171312 -89.46896)
			(xy 196.161241 -89.469376) (xy 196.142643 -89.477102) (xy 196.135244 -89.483946) (xy 191.39535 -94.22384)
			(xy 191.388507 -94.231238) (xy 191.380787 -94.249839) (xy 191.380364 -94.259908) (xy 191.380364 -95.989648)
			(xy 191.663826 -95.989648) (xy 191.667897 -95.934026) (xy 191.680023 -95.879589) (xy 191.699946 -95.827498)
			(xy 191.727242 -95.778863) (xy 191.761328 -95.73472) (xy 191.801477 -95.696011) (xy 191.846835 -95.66356)
			(xy 191.896435 -95.638059) (xy 191.949219 -95.620052) (xy 192.004062 -95.609922) (xy 192.059796 -95.607885)
			(xy 192.115233 -95.613985) (xy 192.16919 -95.628091) (xy 192.220519 -95.649903) (xy 192.268125 -95.678957)
			(xy 192.310993 -95.714632) (xy 192.34821 -95.756169) (xy 192.378983 -95.802682) (xy 192.402655 -95.853179)
			(xy 192.418723 -95.906586) (xy 192.426843 -95.961762) (xy 192.427352 -95.989648) (xy 194.269358 -95.989648)
			(xy 194.273429 -95.934026) (xy 194.285555 -95.879589) (xy 194.305478 -95.827498) (xy 194.332774 -95.778863)
			(xy 194.36686 -95.73472) (xy 194.407009 -95.696011) (xy 194.452367 -95.66356) (xy 194.501967 -95.638059)
			(xy 194.554751 -95.620052) (xy 194.609594 -95.609922) (xy 194.665328 -95.607885) (xy 194.720765 -95.613985)
			(xy 194.774722 -95.628091) (xy 194.826051 -95.649903) (xy 194.873657 -95.678957) (xy 194.916525 -95.714632)
			(xy 194.953742 -95.756169) (xy 194.984515 -95.802682) (xy 195.008187 -95.853179) (xy 195.024255 -95.906586)
			(xy 195.032375 -95.961762) (xy 195.032884 -95.989648) (xy 195.032375 -96.017534) (xy 195.024255 -96.07271)
			(xy 195.008187 -96.126117) (xy 194.984515 -96.176614) (xy 194.953742 -96.223127) (xy 194.916525 -96.264664)
			(xy 194.873657 -96.300339) (xy 194.826051 -96.329393) (xy 194.774722 -96.351205) (xy 194.720765 -96.365311)
			(xy 194.665328 -96.371411) (xy 194.609594 -96.369374) (xy 194.554751 -96.359244) (xy 194.501967 -96.341237)
			(xy 194.452367 -96.315736) (xy 194.407009 -96.283285) (xy 194.36686 -96.244576) (xy 194.332774 -96.200433)
			(xy 194.305478 -96.151798) (xy 194.285555 -96.099707) (xy 194.273429 -96.04527) (xy 194.269358 -95.989648)
			(xy 192.427352 -95.989648) (xy 192.426843 -96.017534) (xy 192.418723 -96.07271) (xy 192.402655 -96.126117)
			(xy 192.378983 -96.176614) (xy 192.34821 -96.223127) (xy 192.310993 -96.264664) (xy 192.268125 -96.300339)
			(xy 192.220519 -96.329393) (xy 192.16919 -96.351205) (xy 192.115233 -96.365311) (xy 192.059796 -96.371411)
			(xy 192.004062 -96.369374) (xy 191.949219 -96.359244) (xy 191.896435 -96.341237) (xy 191.846835 -96.315736)
			(xy 191.801477 -96.283285) (xy 191.761328 -96.244576) (xy 191.727242 -96.200433) (xy 191.699946 -96.151798)
			(xy 191.680023 -96.099707) (xy 191.667897 -96.04527) (xy 191.663826 -95.989648) (xy 191.380364 -95.989648)
			(xy 191.380364 -96.264984) (xy 191.379758 -96.301735) (xy 191.370522 -96.374655) (xy 191.35223 -96.445845)
			(xy 191.325171 -96.514185) (xy 191.307974 -96.54667) (xy 191.30772 -96.546924) (xy 191.303181 -96.556441)
			(xy 191.301485 -96.577436) (xy 191.304418 -96.587564) (xy 191.329056 -96.658938) (xy 191.332992 -96.668899)
			(xy 191.347585 -96.684549) (xy 191.35725 -96.689164) (xy 191.382644 -96.700582) (xy 191.430131 -96.729647)
			(xy 191.472887 -96.765309) (xy 191.510001 -96.80681) (xy 191.540685 -96.853267) (xy 191.564286 -96.903693)
			(xy 191.580303 -96.957015) (xy 191.587447 -97.005648) (xy 194.269358 -97.005648) (xy 194.273429 -96.950026)
			(xy 194.285555 -96.895589) (xy 194.305478 -96.843498) (xy 194.332774 -96.794863) (xy 194.36686 -96.75072)
			(xy 194.407009 -96.712011) (xy 194.452367 -96.67956) (xy 194.501967 -96.654059) (xy 194.554751 -96.636052)
			(xy 194.609594 -96.625922) (xy 194.665328 -96.623885) (xy 194.720765 -96.629985) (xy 194.774722 -96.644091)
			(xy 194.826051 -96.665903) (xy 194.873657 -96.694957) (xy 194.916525 -96.730632) (xy 194.953742 -96.772169)
			(xy 194.984515 -96.818682) (xy 195.008187 -96.869179) (xy 195.024255 -96.922586) (xy 195.032375 -96.977762)
			(xy 195.032884 -97.005648) (xy 195.032375 -97.033534) (xy 195.024255 -97.08871) (xy 195.008187 -97.142117)
			(xy 194.984515 -97.192614) (xy 194.953742 -97.239127) (xy 194.916525 -97.280664) (xy 194.873657 -97.316339)
			(xy 194.826051 -97.345393) (xy 194.774722 -97.367205) (xy 194.720765 -97.381311) (xy 194.665328 -97.387411)
			(xy 194.609594 -97.385374) (xy 194.554751 -97.375244) (xy 194.501967 -97.357237) (xy 194.452367 -97.331736)
			(xy 194.407009 -97.299285) (xy 194.36686 -97.260576) (xy 194.332774 -97.216433) (xy 194.305478 -97.167798)
			(xy 194.285555 -97.115707) (xy 194.273429 -97.06127) (xy 194.269358 -97.005648) (xy 191.587447 -97.005648)
			(xy 191.588395 -97.0121) (xy 191.588898 -97.039938) (xy 191.588457 -97.067191) (xy 191.580696 -97.121141)
			(xy 191.565335 -97.173437) (xy 191.542689 -97.223015) (xy 191.513218 -97.268865) (xy 191.477521 -97.310055)
			(xy 191.436327 -97.345746) (xy 191.390473 -97.375212) (xy 191.340892 -97.397852) (xy 191.288594 -97.413206)
			(xy 191.234643 -97.420961) (xy 191.20739 -97.421446) (xy 191.180989 -97.421031) (xy 191.128695 -97.413724)
			(xy 191.077908 -97.399279) (xy 191.029596 -97.377971) (xy 190.984682 -97.350207) (xy 190.944024 -97.316518)
			(xy 190.908398 -97.277546) (xy 190.878483 -97.234035) (xy 190.866268 -97.210626) (xy 190.860257 -97.200222)
			(xy 190.840917 -97.186027) (xy 190.829184 -97.183448) (xy 190.74765 -97.169986) (xy 190.735648 -97.168801)
			(xy 190.712731 -97.176209) (xy 190.703708 -97.18421) (xy 190.665354 -97.222564) (xy 190.658548 -97.230046)
			(xy 190.650956 -97.248777) (xy 190.650622 -97.258886) (xy 190.650876 -97.331022) (xy 190.651366 -97.341054)
			(xy 190.659234 -97.359519) (xy 190.666116 -97.366836) (xy 190.66637 -97.36709) (xy 190.684258 -97.385084)
			(xy 190.715551 -97.425025) (xy 190.741273 -97.468761) (xy 190.760971 -97.51552) (xy 190.774298 -97.564478)
			(xy 190.781018 -97.61477) (xy 190.781432 -97.64014) (xy 190.780959 -97.667391) (xy 190.773198 -97.721338)
			(xy 190.757839 -97.773632) (xy 190.735195 -97.823207) (xy 190.705727 -97.869056) (xy 190.670034 -97.910246)
			(xy 190.628844 -97.945936) (xy 190.582993 -97.975403) (xy 190.533417 -97.998045) (xy 190.481122 -98.013402)
			(xy 190.427175 -98.021161) (xy 190.399924 -98.021648) (xy 190.374555 -98.021236) (xy 190.324265 -98.014513)
			(xy 190.27531 -98.001182) (xy 190.228554 -97.981479) (xy 190.184823 -97.955751) (xy 190.144889 -97.924453)
			(xy 190.126874 -97.906586) (xy 190.12662 -97.906332) (xy 190.119269 -97.899508) (xy 190.100821 -97.891676)
			(xy 190.090806 -97.891092) (xy 190.01867 -97.890838) (xy 190.008557 -97.891143) (xy 189.989825 -97.898752)
			(xy 189.982348 -97.90557) (xy 189.716744 -98.171) (xy 191.663826 -98.171) (xy 191.667897 -98.115378)
			(xy 191.680023 -98.060941) (xy 191.699946 -98.00885) (xy 191.727242 -97.960215) (xy 191.761328 -97.916072)
			(xy 191.801477 -97.877363) (xy 191.846835 -97.844912) (xy 191.896435 -97.819411) (xy 191.949219 -97.801404)
			(xy 192.004062 -97.791274) (xy 192.059796 -97.789237) (xy 192.115233 -97.795337) (xy 192.16919 -97.809443)
			(xy 192.220519 -97.831255) (xy 192.268125 -97.860309) (xy 192.310993 -97.895984) (xy 192.34821 -97.937521)
			(xy 192.378983 -97.984034) (xy 192.402655 -98.034531) (xy 192.418723 -98.087938) (xy 192.426843 -98.143114)
			(xy 192.427352 -98.171) (xy 192.426843 -98.198886) (xy 192.418723 -98.254062) (xy 192.402655 -98.307469)
			(xy 192.378983 -98.357966) (xy 192.34821 -98.404479) (xy 192.310993 -98.446016) (xy 192.268125 -98.481691)
			(xy 192.220519 -98.510745) (xy 192.16919 -98.532557) (xy 192.115233 -98.546663) (xy 192.059796 -98.552763)
			(xy 192.004062 -98.550726) (xy 191.949219 -98.540596) (xy 191.896435 -98.522589) (xy 191.846835 -98.497088)
			(xy 191.801477 -98.464637) (xy 191.761328 -98.425928) (xy 191.727242 -98.381785) (xy 191.699946 -98.33315)
			(xy 191.680023 -98.281059) (xy 191.667897 -98.226622) (xy 191.663826 -98.171) (xy 189.716744 -98.171)
			(xy 189.59449 -98.293174) (xy 189.587668 -98.300588) (xy 189.579938 -98.319177) (xy 189.579504 -98.329242)
			(xy 189.579504 -99.439984) (xy 191.409826 -99.439984) (xy 191.413897 -99.384362) (xy 191.426023 -99.329925)
			(xy 191.445946 -99.277834) (xy 191.473242 -99.229199) (xy 191.507328 -99.185056) (xy 191.547477 -99.146347)
			(xy 191.592835 -99.113896) (xy 191.642435 -99.088395) (xy 191.695219 -99.070388) (xy 191.750062 -99.060258)
			(xy 191.805796 -99.058221) (xy 191.861233 -99.064321) (xy 191.91519 -99.078427) (xy 191.966519 -99.100239)
			(xy 192.014125 -99.129293) (xy 192.056993 -99.164968) (xy 192.09421 -99.206505) (xy 192.124983 -99.253018)
			(xy 192.148655 -99.303515) (xy 192.164723 -99.356922) (xy 192.172843 -99.412098) (xy 192.173352 -99.439984)
			(xy 192.172843 -99.46787) (xy 192.164723 -99.523046) (xy 192.148655 -99.576453) (xy 192.124983 -99.62695)
			(xy 192.09421 -99.673463) (xy 192.056993 -99.715) (xy 192.014125 -99.750675) (xy 191.966519 -99.779729)
			(xy 191.91519 -99.801541) (xy 191.861233 -99.815647) (xy 191.805796 -99.821747) (xy 191.750062 -99.81971)
			(xy 191.695219 -99.80958) (xy 191.642435 -99.791573) (xy 191.592835 -99.766072) (xy 191.547477 -99.733621)
			(xy 191.507328 -99.694912) (xy 191.473242 -99.650769) (xy 191.445946 -99.602134) (xy 191.426023 -99.550043)
			(xy 191.413897 -99.495606) (xy 191.409826 -99.439984) (xy 189.579504 -99.439984) (xy 189.579504 -100.039932)
			(xy 189.976758 -100.039932) (xy 189.980829 -99.98431) (xy 189.992955 -99.929873) (xy 190.012878 -99.877782)
			(xy 190.040174 -99.829147) (xy 190.07426 -99.785004) (xy 190.114409 -99.746295) (xy 190.159767 -99.713844)
			(xy 190.209367 -99.688343) (xy 190.262151 -99.670336) (xy 190.316994 -99.660206) (xy 190.372728 -99.658169)
			(xy 190.428165 -99.664269) (xy 190.482122 -99.678375) (xy 190.533451 -99.700187) (xy 190.581057 -99.729241)
			(xy 190.623925 -99.764916) (xy 190.661142 -99.806453) (xy 190.691915 -99.852966) (xy 190.715587 -99.903463)
			(xy 190.731655 -99.95687) (xy 190.739775 -100.012046) (xy 190.740284 -100.039932) (xy 190.739775 -100.067818)
			(xy 190.731655 -100.122994) (xy 190.715587 -100.176401) (xy 190.691915 -100.226898) (xy 190.661142 -100.273411)
			(xy 190.623925 -100.314948) (xy 190.581057 -100.350623) (xy 190.533451 -100.379677) (xy 190.482122 -100.401489)
			(xy 190.428165 -100.415595) (xy 190.372728 -100.421695) (xy 190.316994 -100.419658) (xy 190.262151 -100.409528)
			(xy 190.209367 -100.391521) (xy 190.159767 -100.36602) (xy 190.114409 -100.333569) (xy 190.07426 -100.29486)
			(xy 190.040174 -100.250717) (xy 190.012878 -100.202082) (xy 189.992955 -100.149991) (xy 189.980829 -100.095554)
			(xy 189.976758 -100.039932) (xy 189.579504 -100.039932) (xy 189.579504 -101.240082) (xy 190.393826 -101.240082)
			(xy 190.397897 -101.18446) (xy 190.410023 -101.130023) (xy 190.429946 -101.077932) (xy 190.457242 -101.029297)
			(xy 190.491328 -100.985154) (xy 190.531477 -100.946445) (xy 190.576835 -100.913994) (xy 190.626435 -100.888493)
			(xy 190.679219 -100.870486) (xy 190.734062 -100.860356) (xy 190.789796 -100.858319) (xy 190.845233 -100.864419)
			(xy 190.89919 -100.878525) (xy 190.950519 -100.900337) (xy 190.998125 -100.929391) (xy 191.040993 -100.965066)
			(xy 191.07821 -101.006603) (xy 191.108983 -101.053116) (xy 191.116733 -101.069648) (xy 191.686178 -101.069648)
			(xy 191.690249 -101.014026) (xy 191.702375 -100.959589) (xy 191.722298 -100.907498) (xy 191.749594 -100.858863)
			(xy 191.78368 -100.81472) (xy 191.823829 -100.776011) (xy 191.869187 -100.74356) (xy 191.918787 -100.718059)
			(xy 191.971571 -100.700052) (xy 192.026414 -100.689922) (xy 192.082148 -100.687885) (xy 192.137585 -100.693985)
			(xy 192.191542 -100.708091) (xy 192.242871 -100.729903) (xy 192.290477 -100.758957) (xy 192.333345 -100.794632)
			(xy 192.370562 -100.836169) (xy 192.401335 -100.882682) (xy 192.425007 -100.933179) (xy 192.441075 -100.986586)
			(xy 192.449195 -101.041762) (xy 192.449704 -101.069648) (xy 194.269358 -101.069648) (xy 194.273429 -101.014026)
			(xy 194.285555 -100.959589) (xy 194.305478 -100.907498) (xy 194.332774 -100.858863) (xy 194.36686 -100.81472)
			(xy 194.407009 -100.776011) (xy 194.452367 -100.74356) (xy 194.501967 -100.718059) (xy 194.554751 -100.700052)
			(xy 194.609594 -100.689922) (xy 194.665328 -100.687885) (xy 194.720765 -100.693985) (xy 194.774722 -100.708091)
			(xy 194.826051 -100.729903) (xy 194.873657 -100.758957) (xy 194.916525 -100.794632) (xy 194.953742 -100.836169)
			(xy 194.984515 -100.882682) (xy 195.008187 -100.933179) (xy 195.024255 -100.986586) (xy 195.032375 -101.041762)
			(xy 195.032884 -101.069648) (xy 195.032375 -101.097534) (xy 195.024255 -101.15271) (xy 195.008187 -101.206117)
			(xy 194.984515 -101.256614) (xy 194.953742 -101.303127) (xy 194.916525 -101.344664) (xy 194.873657 -101.380339)
			(xy 194.826051 -101.409393) (xy 194.774722 -101.431205) (xy 194.720765 -101.445311) (xy 194.665328 -101.451411)
			(xy 194.609594 -101.449374) (xy 194.554751 -101.439244) (xy 194.501967 -101.421237) (xy 194.452367 -101.395736)
			(xy 194.407009 -101.363285) (xy 194.36686 -101.324576) (xy 194.332774 -101.280433) (xy 194.305478 -101.231798)
			(xy 194.285555 -101.179707) (xy 194.273429 -101.12527) (xy 194.269358 -101.069648) (xy 192.449704 -101.069648)
			(xy 192.449195 -101.097534) (xy 192.441075 -101.15271) (xy 192.425007 -101.206117) (xy 192.401335 -101.256614)
			(xy 192.370562 -101.303127) (xy 192.333345 -101.344664) (xy 192.290477 -101.380339) (xy 192.242871 -101.409393)
			(xy 192.191542 -101.431205) (xy 192.137585 -101.445311) (xy 192.082148 -101.451411) (xy 192.026414 -101.449374)
			(xy 191.971571 -101.439244) (xy 191.918787 -101.421237) (xy 191.869187 -101.395736) (xy 191.823829 -101.363285)
			(xy 191.78368 -101.324576) (xy 191.749594 -101.280433) (xy 191.722298 -101.231798) (xy 191.702375 -101.179707)
			(xy 191.690249 -101.12527) (xy 191.686178 -101.069648) (xy 191.116733 -101.069648) (xy 191.132655 -101.103613)
			(xy 191.148723 -101.15702) (xy 191.156843 -101.212196) (xy 191.157352 -101.240082) (xy 191.156843 -101.267968)
			(xy 191.148723 -101.323144) (xy 191.132655 -101.376551) (xy 191.108983 -101.427048) (xy 191.07821 -101.473561)
			(xy 191.040993 -101.515098) (xy 190.998125 -101.550773) (xy 190.950519 -101.579827) (xy 190.89919 -101.601639)
			(xy 190.845233 -101.615745) (xy 190.789796 -101.621845) (xy 190.734062 -101.619808) (xy 190.679219 -101.609678)
			(xy 190.626435 -101.591671) (xy 190.576835 -101.56617) (xy 190.531477 -101.533719) (xy 190.491328 -101.49501)
			(xy 190.457242 -101.450867) (xy 190.429946 -101.402232) (xy 190.410023 -101.350141) (xy 190.397897 -101.295704)
			(xy 190.393826 -101.240082) (xy 189.579504 -101.240082) (xy 189.579504 -102.489) (xy 190.901826 -102.489)
			(xy 190.905897 -102.433378) (xy 190.918023 -102.378941) (xy 190.937946 -102.32685) (xy 190.965242 -102.278215)
			(xy 190.999328 -102.234072) (xy 191.039477 -102.195363) (xy 191.084835 -102.162912) (xy 191.134435 -102.137411)
			(xy 191.187219 -102.119404) (xy 191.242062 -102.109274) (xy 191.297796 -102.107237) (xy 191.353233 -102.113337)
			(xy 191.40719 -102.127443) (xy 191.458519 -102.149255) (xy 191.506125 -102.178309) (xy 191.548993 -102.213984)
			(xy 191.58621 -102.255521) (xy 191.616983 -102.302034) (xy 191.640655 -102.352531) (xy 191.656723 -102.405938)
			(xy 191.664843 -102.461114) (xy 191.665352 -102.489) (xy 191.664843 -102.516886) (xy 191.656723 -102.572062)
			(xy 191.640655 -102.625469) (xy 191.616983 -102.675966) (xy 191.58621 -102.722479) (xy 191.548993 -102.764016)
			(xy 191.506125 -102.799691) (xy 191.458519 -102.828745) (xy 191.40719 -102.850557) (xy 191.353233 -102.864663)
			(xy 191.297796 -102.870763) (xy 191.242062 -102.868726) (xy 191.187219 -102.858596) (xy 191.134435 -102.840589)
			(xy 191.084835 -102.815088) (xy 191.039477 -102.782637) (xy 190.999328 -102.743928) (xy 190.965242 -102.699785)
			(xy 190.937946 -102.65115) (xy 190.918023 -102.599059) (xy 190.905897 -102.544622) (xy 190.901826 -102.489)
			(xy 189.579504 -102.489) (xy 189.579504 -103.886) (xy 191.409826 -103.886) (xy 191.413897 -103.830378)
			(xy 191.426023 -103.775941) (xy 191.445946 -103.72385) (xy 191.473242 -103.675215) (xy 191.507328 -103.631072)
			(xy 191.547477 -103.592363) (xy 191.592835 -103.559912) (xy 191.642435 -103.534411) (xy 191.695219 -103.516404)
			(xy 191.750062 -103.506274) (xy 191.805796 -103.504237) (xy 191.861233 -103.510337) (xy 191.91519 -103.524443)
			(xy 191.966519 -103.546255) (xy 192.014125 -103.575309) (xy 192.056993 -103.610984) (xy 192.09421 -103.652521)
			(xy 192.124983 -103.699034) (xy 192.148655 -103.749531) (xy 192.164723 -103.802938) (xy 192.172843 -103.858114)
			(xy 192.173352 -103.886) (xy 192.172843 -103.913886) (xy 192.164723 -103.969062) (xy 192.148655 -104.022469)
			(xy 192.124983 -104.072966) (xy 192.09421 -104.119479) (xy 192.056993 -104.161016) (xy 192.014125 -104.196691)
			(xy 191.966519 -104.225745) (xy 191.91519 -104.247557) (xy 191.861233 -104.261663) (xy 191.805796 -104.267763)
			(xy 191.750062 -104.265726) (xy 191.695219 -104.255596) (xy 191.642435 -104.237589) (xy 191.592835 -104.212088)
			(xy 191.547477 -104.179637) (xy 191.507328 -104.140928) (xy 191.473242 -104.096785) (xy 191.445946 -104.04815)
			(xy 191.426023 -103.996059) (xy 191.413897 -103.941622) (xy 191.409826 -103.886) (xy 189.579504 -103.886)
			(xy 189.579504 -104.356154) (xy 189.579926 -104.366224) (xy 189.587646 -104.384824) (xy 189.59449 -104.392222)
			(xy 190.21806 -105.015538) (xy 190.240961 -105.039131) (xy 190.281957 -105.090539) (xy 190.316946 -105.14621)
			(xy 190.345488 -105.205446) (xy 190.367225 -105.267502) (xy 190.381885 -105.3316) (xy 190.389283 -105.396936)
			(xy 190.389764 -105.429812) (xy 190.389764 -108.12145) (xy 190.389302 -108.154331) (xy 190.38194 -108.219678)
			(xy 190.367302 -108.283789) (xy 190.345574 -108.345857) (xy 190.317029 -108.405099) (xy 190.282026 -108.460771)
			(xy 190.241006 -108.51217) (xy 190.21806 -108.535724) (xy 189.573154 -109.18063) (xy 189.54961 -109.203551)
			(xy 189.498231 -109.244517) (xy 189.442588 -109.279472) (xy 189.383381 -109.307978) (xy 189.321355 -109.329674)
			(xy 189.257289 -109.34429) (xy 189.19199 -109.35164) (xy 189.159134 -109.35208) (xy 188.236098 -109.35208)
			(xy 188.226026 -109.352483) (xy 188.207427 -109.360217) (xy 188.20003 -109.367066) (xy 185.948574 -111.618776)
			(xy 185.941748 -111.626187) (xy 185.934021 -111.644778) (xy 185.933588 -111.654844) (xy 185.933588 -111.980726)
			(xy 190.001398 -111.980726) (xy 190.001938 -111.951988) (xy 190.010557 -111.895161) (xy 190.027603 -111.840271)
			(xy 190.052691 -111.788559) (xy 190.085253 -111.741195) (xy 190.104522 -111.719868) (xy 190.111126 -111.71301)
			(xy 190.118238 -111.694976) (xy 190.118238 -111.606076) (xy 190.111126 -111.588042) (xy 190.104522 -111.581184)
			(xy 190.085277 -111.559835) (xy 190.052711 -111.512476) (xy 190.027618 -111.460768) (xy 190.010566 -111.405881)
			(xy 190.001941 -111.349056) (xy 190.001939 -111.291581) (xy 190.010558 -111.234756) (xy 190.027604 -111.179867)
			(xy 190.052692 -111.128157) (xy 190.085253 -111.080795) (xy 190.104522 -111.059468) (xy 190.111126 -111.05261)
			(xy 190.118238 -111.034576) (xy 190.118238 -110.945676) (xy 190.111126 -110.927642) (xy 190.104522 -110.920784)
			(xy 190.085277 -110.899435) (xy 190.052711 -110.852076) (xy 190.027618 -110.800368) (xy 190.010566 -110.745481)
			(xy 190.001941 -110.688656) (xy 190.001939 -110.631181) (xy 190.010558 -110.574356) (xy 190.027604 -110.519467)
			(xy 190.052692 -110.467757) (xy 190.085253 -110.420395) (xy 190.104522 -110.399068) (xy 190.111126 -110.39221)
			(xy 190.118238 -110.374176) (xy 190.118238 -110.285276) (xy 190.111126 -110.267242) (xy 190.104522 -110.260384)
			(xy 190.085277 -110.239035) (xy 190.052711 -110.191676) (xy 190.027618 -110.139968) (xy 190.010566 -110.085081)
			(xy 190.001941 -110.028256) (xy 190.001939 -109.970781) (xy 190.010558 -109.913956) (xy 190.027604 -109.859067)
			(xy 190.052692 -109.807357) (xy 190.085253 -109.759995) (xy 190.104522 -109.738668) (xy 190.111126 -109.73181)
			(xy 190.118238 -109.713776) (xy 190.118238 -109.624876) (xy 190.111126 -109.606842) (xy 190.104522 -109.599984)
			(xy 190.085261 -109.578649) (xy 190.052694 -109.531289) (xy 190.0276 -109.479579) (xy 190.010547 -109.42469)
			(xy 190.001921 -109.367864) (xy 190.001398 -109.339126) (xy 190.00188 -109.311874) (xy 190.009633 -109.257923)
			(xy 190.024986 -109.205625) (xy 190.047626 -109.156045) (xy 190.077092 -109.110191) (xy 190.112784 -109.068998)
			(xy 190.153975 -109.033304) (xy 190.199827 -109.003836) (xy 190.249406 -108.981193) (xy 190.301703 -108.965837)
			(xy 190.355654 -108.958081) (xy 190.382906 -108.957618) (xy 190.40922 -108.958076) (xy 190.46135 -108.965312)
			(xy 190.511993 -108.979632) (xy 190.560192 -109.000767) (xy 190.605035 -109.028315) (xy 190.645674 -109.061755)
			(xy 190.66383 -109.080808) (xy 190.671338 -109.088226) (xy 190.690628 -109.09674) (xy 190.701168 -109.097318)
			(xy 190.775844 -109.097318) (xy 190.786391 -109.096767) (xy 190.805686 -109.088247) (xy 190.813182 -109.080808)
			(xy 190.831355 -109.06177) (xy 190.871981 -109.028311) (xy 190.916817 -109.000749) (xy 190.965015 -108.979608)
			(xy 191.015659 -108.965287) (xy 191.067791 -108.958058) (xy 191.094106 -108.957618) (xy 191.12136 -108.95805)
			(xy 191.175314 -108.965808) (xy 191.227614 -108.981166) (xy 191.277195 -109.003811) (xy 191.32305 -109.033283)
			(xy 191.364243 -109.06898) (xy 191.399937 -109.110176) (xy 191.429404 -109.156033) (xy 191.452045 -109.205616)
			(xy 191.467399 -109.257918) (xy 191.475152 -109.311872) (xy 191.475614 -109.339126) (xy 191.475102 -109.367865)
			(xy 191.466476 -109.424693) (xy 191.449423 -109.479584) (xy 191.424329 -109.531295) (xy 191.391762 -109.578657)
			(xy 191.37249 -109.599984) (xy 191.365886 -109.606842) (xy 191.358774 -109.624876) (xy 191.358774 -109.713776)
			(xy 191.365886 -109.73181) (xy 191.37249 -109.738668) (xy 191.391786 -109.759973) (xy 191.424349 -109.807339)
			(xy 191.449438 -109.859055) (xy 191.466486 -109.913949) (xy 191.475106 -109.970779) (xy 191.475103 -110.028259)
			(xy 191.466477 -110.085088) (xy 191.449424 -110.13998) (xy 191.42433 -110.191693) (xy 191.391762 -110.239057)
			(xy 191.37249 -110.260384) (xy 191.365886 -110.267242) (xy 191.358774 -110.285276) (xy 191.358774 -110.374176)
			(xy 191.365886 -110.39221) (xy 191.37249 -110.399068) (xy 191.391786 -110.420373) (xy 191.424349 -110.467739)
			(xy 191.449438 -110.519455) (xy 191.466486 -110.574349) (xy 191.475106 -110.631179) (xy 191.475103 -110.688659)
			(xy 191.466477 -110.745488) (xy 191.449424 -110.80038) (xy 191.42433 -110.852093) (xy 191.391762 -110.899457)
			(xy 191.37249 -110.920784) (xy 191.365886 -110.927642) (xy 191.358774 -110.945676) (xy 191.358774 -111.034576)
			(xy 191.365886 -111.05261) (xy 191.37249 -111.059468) (xy 191.391786 -111.080773) (xy 191.424349 -111.128139)
			(xy 191.449438 -111.179855) (xy 191.466486 -111.234749) (xy 191.475106 -111.291579) (xy 191.475103 -111.349059)
			(xy 191.466477 -111.405888) (xy 191.449424 -111.46078) (xy 191.42433 -111.512493) (xy 191.391762 -111.559857)
			(xy 191.37249 -111.581184) (xy 191.365886 -111.588042) (xy 191.358774 -111.606076) (xy 191.358774 -111.694976)
			(xy 191.365886 -111.71301) (xy 191.37249 -111.719868) (xy 191.391778 -111.74118) (xy 191.424341 -111.788547)
			(xy 191.449429 -111.840262) (xy 191.466476 -111.895156) (xy 191.475095 -111.951986) (xy 191.475614 -111.980726)
			(xy 191.475146 -112.007978) (xy 191.467387 -112.061926) (xy 191.452028 -112.11422) (xy 191.429385 -112.163797)
			(xy 191.399916 -112.209647) (xy 191.364223 -112.250837) (xy 191.323031 -112.286528) (xy 191.27718 -112.315994)
			(xy 191.227602 -112.338635) (xy 191.175306 -112.353991) (xy 191.121358 -112.361748) (xy 191.094106 -112.362234)
			(xy 191.067793 -112.361752) (xy 191.015665 -112.354518) (xy 190.965023 -112.340201) (xy 190.916824 -112.319072)
			(xy 190.87198 -112.291529) (xy 190.83134 -112.258094) (xy 190.813182 -112.239044) (xy 190.805663 -112.231639)
			(xy 190.786381 -112.223115) (xy 190.775844 -112.222534) (xy 190.701168 -112.222534) (xy 190.69062 -112.223076)
			(xy 190.671323 -112.231601) (xy 190.66383 -112.239044) (xy 190.645661 -112.258086) (xy 190.605034 -112.291543)
			(xy 190.560196 -112.319103) (xy 190.511998 -112.340243) (xy 190.461353 -112.354564) (xy 190.409221 -112.361793)
			(xy 190.382906 -112.362234) (xy 190.355656 -112.361717) (xy 190.301711 -112.353962) (xy 190.249418 -112.338609)
			(xy 190.199843 -112.31597) (xy 190.153994 -112.286507) (xy 190.112804 -112.250819) (xy 190.077112 -112.209632)
			(xy 190.047645 -112.163785) (xy 190.025003 -112.114212) (xy 190.009645 -112.06192) (xy 190.001886 -112.007976)
			(xy 190.001398 -111.980726) (xy 185.933588 -111.980726) (xy 185.933588 -111.992156) (xy 185.933989 -112.00147)
			(xy 185.940609 -112.018878) (xy 185.953024 -112.032762) (xy 185.969588 -112.041278) (xy 185.9788 -112.042702)
			(xy 186.006461 -112.046222) (xy 186.060403 -112.060348) (xy 186.111714 -112.082175) (xy 186.159301 -112.111238)
			(xy 186.202151 -112.146919) (xy 186.239352 -112.188456) (xy 186.27011 -112.234966) (xy 186.29377 -112.285458)
			(xy 186.30983 -112.338856) (xy 186.317946 -112.394022) (xy 186.317945 -112.449783) (xy 186.309829 -112.50495)
			(xy 186.293769 -112.558347) (xy 186.270107 -112.608839) (xy 186.239348 -112.655348) (xy 186.202147 -112.696885)
			(xy 186.159297 -112.732565) (xy 186.111709 -112.761628) (xy 186.060398 -112.783454) (xy 186.006456 -112.797579)
			(xy 185.9788 -112.801146) (xy 185.969591 -112.802559) (xy 185.953049 -112.811105) (xy 185.940641 -112.824988)
			(xy 185.933999 -112.842382) (xy 185.933588 -112.851692) (xy 185.933588 -113.03) (xy 185.957718 -113.058194)
			(xy 185.97626 -113.061242) (xy 186.002793 -113.065934) (xy 186.054264 -113.081874) (xy 186.10298 -113.104898)
			(xy 186.147972 -113.134547) (xy 186.188344 -113.170232) (xy 186.223294 -113.211242) (xy 186.252127 -113.256762)
			(xy 186.274267 -113.305885) (xy 186.289276 -113.357636) (xy 186.296854 -113.410983) (xy 186.297316 -113.437924)
			(xy 186.296598 -113.471123) (xy 186.285105 -113.536519) (xy 186.274456 -113.567972) (xy 186.274456 -113.568226)
			(xy 186.270984 -113.579916) (xy 186.274176 -113.604058) (xy 186.280552 -113.614454) (xy 186.328304 -113.682526)
			(xy 186.33594 -113.692135) (xy 186.357706 -113.703403) (xy 186.36996 -113.704116) (xy 186.842146 -113.704116)
			(xy 186.876244 -113.704626) (xy 186.943979 -113.712548) (xy 187.010337 -113.72828) (xy 187.07442 -113.751609)
			(xy 187.135361 -113.782219) (xy 187.192337 -113.819696) (xy 187.244576 -113.863535) (xy 187.291374 -113.913141)
			(xy 187.332097 -113.967845) (xy 187.366194 -114.026906) (xy 187.393204 -114.089526) (xy 187.412762 -114.154858)
			(xy 187.424603 -114.222019) (xy 187.428569 -114.2901) (xy 187.424603 -114.358181) (xy 187.412762 -114.425342)
			(xy 187.393204 -114.490674) (xy 187.366194 -114.553294) (xy 187.332097 -114.612355) (xy 187.291374 -114.667059)
			(xy 187.244576 -114.716665) (xy 187.192337 -114.760504) (xy 187.135361 -114.797981) (xy 187.07442 -114.828591)
			(xy 187.010337 -114.85192) (xy 186.943979 -114.867652) (xy 186.876244 -114.875574) (xy 186.842146 -114.876072)
			(xy 185.842402 -114.876072) (xy 185.808821 -114.875637) (xy 185.742098 -114.867957) (xy 185.676691 -114.852698)
			(xy 185.613459 -114.830061) (xy 185.553229 -114.800341) (xy 185.496793 -114.763929) (xy 185.470546 -114.742976)
			(xy 185.462672 -114.736372) (xy 185.442352 -114.73053) (xy 185.35904 -114.740944) (xy 185.348737 -114.742715)
			(xy 185.330761 -114.753345) (xy 185.324242 -114.761518) (xy 185.310749 -114.779575) (xy 185.281377 -114.813775)
			(xy 185.265568 -114.829844) (xy 184.734454 -115.360958) (xy 190.218314 -115.360958) (xy 190.218811 -115.333589)
			(xy 190.226621 -115.279411) (xy 190.242102 -115.226908) (xy 190.264937 -115.177161) (xy 190.294656 -115.131193)
			(xy 190.312294 -115.11026) (xy 190.312548 -115.110006) (xy 190.318144 -115.102926) (xy 190.324384 -115.086004)
			(xy 190.32474 -115.076986) (xy 190.32474 -115.00993) (xy 190.324382 -115.000913) (xy 190.318136 -114.983995)
			(xy 190.312548 -114.97691) (xy 190.312294 -114.97691) (xy 190.312294 -114.976656) (xy 190.294667 -114.955714)
			(xy 190.264953 -114.909744) (xy 190.242115 -114.859999) (xy 190.226621 -114.807501) (xy 190.21879 -114.753326)
			(xy 190.218314 -114.725958) (xy 190.218739 -114.698705) (xy 190.226502 -114.644754) (xy 190.241863 -114.592456)
			(xy 190.264511 -114.542878) (xy 190.293984 -114.497026) (xy 190.329681 -114.455836) (xy 190.370878 -114.420145)
			(xy 190.416734 -114.39068) (xy 190.466316 -114.368041) (xy 190.518616 -114.352688) (xy 190.572569 -114.344934)
			(xy 190.599822 -114.34445) (xy 190.627193 -114.344891) (xy 190.681374 -114.352713) (xy 190.733878 -114.368207)
			(xy 190.783624 -114.391055) (xy 190.82959 -114.420786) (xy 190.85052 -114.43843) (xy 190.850774 -114.438684)
			(xy 190.857865 -114.444264) (xy 190.874778 -114.450515) (xy 190.883794 -114.450876) (xy 190.95085 -114.450876)
			(xy 190.959865 -114.4505) (xy 190.976782 -114.444266) (xy 190.98387 -114.438684) (xy 190.98387 -114.43843)
			(xy 190.984124 -114.43843) (xy 191.005078 -114.420818) (xy 191.051044 -114.391101) (xy 191.100786 -114.368259)
			(xy 191.153282 -114.352762) (xy 191.207454 -114.344927) (xy 191.234822 -114.34445) (xy 191.262072 -114.344957)
			(xy 191.316017 -114.352716) (xy 191.368308 -114.368071) (xy 191.417883 -114.390712) (xy 191.463731 -114.420177)
			(xy 191.50492 -114.455866) (xy 191.540611 -114.497053) (xy 191.570078 -114.542899) (xy 191.592722 -114.592473)
			(xy 191.60808 -114.644764) (xy 191.615841 -114.698708) (xy 191.61633 -114.725958) (xy 191.615856 -114.753328)
			(xy 191.608043 -114.807508) (xy 191.592557 -114.860011) (xy 191.569716 -114.909758) (xy 191.539992 -114.955725)
			(xy 191.52235 -114.976656) (xy 191.522096 -114.97691) (xy 191.516499 -114.983989) (xy 191.510259 -115.000912)
			(xy 191.509904 -115.00993) (xy 191.509904 -115.076986) (xy 191.510267 -115.086002) (xy 191.51651 -115.102919)
			(xy 191.522096 -115.110006) (xy 191.52235 -115.110006) (xy 191.52235 -115.11026) (xy 191.539976 -115.131203)
			(xy 191.569692 -115.177172) (xy 191.592531 -115.226917) (xy 191.608025 -115.279415) (xy 191.615855 -115.333589)
			(xy 191.61633 -115.360958) (xy 191.615806 -115.388209) (xy 191.608055 -115.442156) (xy 191.592705 -115.494452)
			(xy 191.570069 -115.54403) (xy 191.540608 -115.589883) (xy 191.50492 -115.631075) (xy 191.463734 -115.666769)
			(xy 191.417887 -115.696239) (xy 191.368312 -115.718883) (xy 191.316019 -115.734241) (xy 191.262073 -115.742001)
			(xy 191.234822 -115.742466) (xy 191.207452 -115.741995) (xy 191.153273 -115.73418) (xy 191.100769 -115.718692)
			(xy 191.051022 -115.695851) (xy 191.005056 -115.666127) (xy 190.984124 -115.648486) (xy 190.98387 -115.648232)
			(xy 190.976773 -115.642661) (xy 190.959864 -115.636407) (xy 190.95085 -115.63604) (xy 190.883794 -115.63604)
			(xy 190.874776 -115.636385) (xy 190.857858 -115.64264) (xy 190.850774 -115.648232) (xy 190.850774 -115.648486)
			(xy 190.85052 -115.648486) (xy 190.829589 -115.666127) (xy 190.783616 -115.695839) (xy 190.733869 -115.718675)
			(xy 190.681367 -115.734165) (xy 190.627191 -115.741993) (xy 190.599822 -115.742466) (xy 190.572568 -115.742024)
			(xy 190.518614 -115.734269) (xy 190.466313 -115.718914) (xy 190.41673 -115.696271) (xy 190.370875 -115.666801)
			(xy 190.329681 -115.631105) (xy 190.293987 -115.589909) (xy 190.26452 -115.544052) (xy 190.241879 -115.494468)
			(xy 190.226527 -115.442167) (xy 190.218774 -115.388212) (xy 190.218314 -115.360958) (xy 184.734454 -115.360958)
			(xy 184.395364 -115.700048) (xy 184.371768 -115.722946) (xy 184.32036 -115.763943) (xy 184.26469 -115.798932)
			(xy 184.205455 -115.827475) (xy 184.143399 -115.849212) (xy 184.079302 -115.863872) (xy 184.013966 -115.871271)
			(xy 183.98109 -115.871752) (xy 183.412638 -115.871752) (xy 183.377224 -115.871229) (xy 183.306911 -115.862695)
			(xy 183.23814 -115.845748) (xy 183.171913 -115.820635) (xy 183.109197 -115.787721) (xy 183.050905 -115.747487)
			(xy 182.997889 -115.70052) (xy 182.95092 -115.647504) (xy 182.910685 -115.589214) (xy 182.87777 -115.526498)
			(xy 182.852655 -115.460271) (xy 182.835707 -115.391501) (xy 182.827172 -115.321188) (xy 182.82666 -115.285774)
			(xy 182.827126 -115.253692) (xy 182.834199 -115.189918) (xy 182.848192 -115.127297) (xy 182.858156 -115.096798)
			(xy 182.8613 -115.085374) (xy 182.857996 -115.061942) (xy 182.851806 -115.05184) (xy 182.79872 -114.974624)
			(xy 182.778146 -114.963194) (xy 182.765954 -114.962686) (xy 182.739444 -114.961194) (xy 182.687206 -114.951684)
			(xy 182.63679 -114.935025) (xy 182.58917 -114.911538) (xy 182.545265 -114.881677) (xy 182.505924 -114.846018)
			(xy 182.471905 -114.805251) (xy 182.443865 -114.760161) (xy 182.422346 -114.71162) (xy 182.407764 -114.660564)
			(xy 182.4004 -114.60798) (xy 182.39994 -114.581432) (xy 180.175994 -114.581432) (xy 179.923018 -115.90909)
			(xy 180.121304 -115.90909) (xy 180.125375 -115.853468) (xy 180.137501 -115.799031) (xy 180.157424 -115.74694)
			(xy 180.18472 -115.698305) (xy 180.218806 -115.654162) (xy 180.258955 -115.615453) (xy 180.304313 -115.583002)
			(xy 180.353913 -115.557501) (xy 180.406697 -115.539494) (xy 180.46154 -115.529364) (xy 180.517274 -115.527327)
			(xy 180.572711 -115.533427) (xy 180.626668 -115.547533) (xy 180.677997 -115.569345) (xy 180.725603 -115.598399)
			(xy 180.768471 -115.634074) (xy 180.805688 -115.675611) (xy 180.836461 -115.722124) (xy 180.860133 -115.772621)
			(xy 180.876201 -115.826028) (xy 180.884321 -115.881204) (xy 180.88483 -115.90909) (xy 180.884321 -115.936976)
			(xy 180.876201 -115.992152) (xy 180.860133 -116.045559) (xy 180.836461 -116.096056) (xy 180.805688 -116.142569)
			(xy 180.768471 -116.184106) (xy 180.725603 -116.219781) (xy 180.677997 -116.248835) (xy 180.626668 -116.270647)
			(xy 180.572711 -116.284753) (xy 180.517274 -116.290853) (xy 180.46154 -116.288816) (xy 180.406697 -116.278686)
			(xy 180.353913 -116.260679) (xy 180.304313 -116.235178) (xy 180.258955 -116.202727) (xy 180.218806 -116.164018)
			(xy 180.18472 -116.119875) (xy 180.157424 -116.07124) (xy 180.137501 -116.019149) (xy 180.125375 -115.964712)
			(xy 180.121304 -115.90909) (xy 179.923018 -115.90909) (xy 179.820414 -116.44757) (xy 182.256936 -116.44757)
			(xy 182.261007 -116.391948) (xy 182.273133 -116.337511) (xy 182.293056 -116.28542) (xy 182.320352 -116.236785)
			(xy 182.354438 -116.192642) (xy 182.394587 -116.153933) (xy 182.439945 -116.121482) (xy 182.489545 -116.095981)
			(xy 182.542329 -116.077974) (xy 182.597172 -116.067844) (xy 182.652906 -116.065807) (xy 182.708343 -116.071907)
			(xy 182.7623 -116.086013) (xy 182.813629 -116.107825) (xy 182.861235 -116.136879) (xy 182.904103 -116.172554)
			(xy 182.94132 -116.214091) (xy 182.972093 -116.260604) (xy 182.995765 -116.311101) (xy 183.011833 -116.364508)
			(xy 183.019953 -116.419684) (xy 183.020462 -116.44757) (xy 183.019953 -116.475456) (xy 183.019683 -116.477288)
			(xy 187.404246 -116.477288) (xy 187.408317 -116.421666) (xy 187.420443 -116.367229) (xy 187.440366 -116.315138)
			(xy 187.467662 -116.266503) (xy 187.501748 -116.22236) (xy 187.541897 -116.183651) (xy 187.587255 -116.1512)
			(xy 187.636855 -116.125699) (xy 187.689639 -116.107692) (xy 187.744482 -116.097562) (xy 187.800216 -116.095525)
			(xy 187.855653 -116.101625) (xy 187.90961 -116.115731) (xy 187.960939 -116.137543) (xy 188.008545 -116.166597)
			(xy 188.051413 -116.202272) (xy 188.08863 -116.243809) (xy 188.119403 -116.290322) (xy 188.143075 -116.340819)
			(xy 188.159143 -116.394226) (xy 188.167263 -116.449402) (xy 188.167772 -116.477288) (xy 188.167263 -116.505174)
			(xy 188.159143 -116.56035) (xy 188.143075 -116.613757) (xy 188.119403 -116.664254) (xy 188.08863 -116.710767)
			(xy 188.051413 -116.752304) (xy 188.008545 -116.787979) (xy 187.960939 -116.817033) (xy 187.90961 -116.838845)
			(xy 187.855653 -116.852951) (xy 187.800216 -116.859051) (xy 187.744482 -116.857014) (xy 187.689639 -116.846884)
			(xy 187.636855 -116.828877) (xy 187.587255 -116.803376) (xy 187.541897 -116.770925) (xy 187.501748 -116.732216)
			(xy 187.467662 -116.688073) (xy 187.440366 -116.639438) (xy 187.420443 -116.587347) (xy 187.408317 -116.53291)
			(xy 187.404246 -116.477288) (xy 183.019683 -116.477288) (xy 183.011833 -116.530632) (xy 182.995765 -116.584039)
			(xy 182.972093 -116.634536) (xy 182.94132 -116.681049) (xy 182.904103 -116.722586) (xy 182.861235 -116.758261)
			(xy 182.813629 -116.787315) (xy 182.7623 -116.809127) (xy 182.708343 -116.823233) (xy 182.652906 -116.829333)
			(xy 182.597172 -116.827296) (xy 182.542329 -116.817166) (xy 182.489545 -116.799159) (xy 182.439945 -116.773658)
			(xy 182.394587 -116.741207) (xy 182.354438 -116.702498) (xy 182.320352 -116.658355) (xy 182.293056 -116.60972)
			(xy 182.273133 -116.557629) (xy 182.261007 -116.503192) (xy 182.256936 -116.44757) (xy 179.820414 -116.44757)
			(xy 179.644294 -117.371876) (xy 179.644294 -117.37213) (xy 179.64404 -117.373908) (xy 179.601848 -117.723666)
			(xy 185.789568 -117.723666) (xy 185.793639 -117.668044) (xy 185.805765 -117.613607) (xy 185.825688 -117.561516)
			(xy 185.852984 -117.512881) (xy 185.88707 -117.468738) (xy 185.927219 -117.430029) (xy 185.972577 -117.397578)
			(xy 186.022177 -117.372077) (xy 186.074961 -117.35407) (xy 186.129804 -117.34394) (xy 186.185538 -117.341903)
			(xy 186.240975 -117.348003) (xy 186.294932 -117.362109) (xy 186.346261 -117.383921) (xy 186.393867 -117.412975)
			(xy 186.436735 -117.44865) (xy 186.473952 -117.490187) (xy 186.504725 -117.5367) (xy 186.528397 -117.587197)
			(xy 186.544465 -117.640604) (xy 186.552585 -117.69578) (xy 186.553094 -117.723666) (xy 186.552585 -117.751552)
			(xy 186.55153 -117.758718) (xy 190.574676 -117.758718) (xy 190.574676 -116.895118) (xy 190.575166 -116.865134)
			(xy 190.582994 -116.805678) (xy 190.598515 -116.747753) (xy 190.621464 -116.692349) (xy 190.651448 -116.640415)
			(xy 190.687954 -116.592839) (xy 190.730359 -116.550434) (xy 190.777935 -116.513928) (xy 190.829869 -116.483944)
			(xy 190.885273 -116.460995) (xy 190.943198 -116.445474) (xy 191.002654 -116.437646) (xy 191.062622 -116.437646)
			(xy 191.122078 -116.445474) (xy 191.180003 -116.460995) (xy 191.235407 -116.483944) (xy 191.287341 -116.513928)
			(xy 191.334917 -116.550434) (xy 191.377322 -116.592839) (xy 191.413828 -116.640415) (xy 191.443812 -116.692349)
			(xy 191.466761 -116.747753) (xy 191.482282 -116.805678) (xy 191.49011 -116.865134) (xy 191.4906 -116.895118)
			(xy 191.4906 -117.758718) (xy 191.49011 -117.788702) (xy 191.482282 -117.848158) (xy 191.466761 -117.906083)
			(xy 191.443812 -117.961487) (xy 191.413828 -118.013421) (xy 191.377322 -118.060997) (xy 191.334917 -118.103402)
			(xy 191.287341 -118.139908) (xy 191.235407 -118.169892) (xy 191.180003 -118.192841) (xy 191.122078 -118.208362)
			(xy 191.062622 -118.21619) (xy 191.002654 -118.21619) (xy 190.943198 -118.208362) (xy 190.885273 -118.192841)
			(xy 190.829869 -118.169892) (xy 190.777935 -118.139908) (xy 190.730359 -118.103402) (xy 190.687954 -118.060997)
			(xy 190.651448 -118.013421) (xy 190.621464 -117.961487) (xy 190.598515 -117.906083) (xy 190.582994 -117.848158)
			(xy 190.575166 -117.788702) (xy 190.574676 -117.758718) (xy 186.55153 -117.758718) (xy 186.544465 -117.806728)
			(xy 186.528397 -117.860135) (xy 186.504725 -117.910632) (xy 186.473952 -117.957145) (xy 186.436735 -117.998682)
			(xy 186.393867 -118.034357) (xy 186.346261 -118.063411) (xy 186.294932 -118.085223) (xy 186.240975 -118.099329)
			(xy 186.185538 -118.105429) (xy 186.129804 -118.103392) (xy 186.074961 -118.093262) (xy 186.022177 -118.075255)
			(xy 185.972577 -118.049754) (xy 185.927219 -118.017303) (xy 185.88707 -117.978594) (xy 185.852984 -117.934451)
			(xy 185.825688 -117.885816) (xy 185.805765 -117.833725) (xy 185.793639 -117.779288) (xy 185.789568 -117.723666)
			(xy 179.601848 -117.723666) (xy 179.572158 -117.969792) (xy 179.57153 -117.976592) (xy 179.573469 -117.990106)
			(xy 179.575968 -117.996462) (xy 179.58181 -118.009416) (xy 179.584604 -118.011194) (xy 179.606579 -118.025901)
			(xy 179.646631 -118.060422) (xy 179.681529 -118.100147) (xy 179.710602 -118.144313) (xy 179.733292 -118.192073)
			(xy 179.749165 -118.242511) (xy 179.757915 -118.294659) (xy 179.759102 -118.321074) (xy 179.759102 -118.321582)
			(xy 179.759356 -118.330218) (xy 179.759356 -118.331996) (xy 179.758813 -118.361135) (xy 179.749972 -118.418737)
			(xy 179.732478 -118.474326) (xy 179.706739 -118.526611) (xy 179.673352 -118.574376) (xy 179.633093 -118.616512)
			(xy 179.586898 -118.652039) (xy 179.53584 -118.680133) (xy 179.508658 -118.690644) (xy 179.498127 -118.696306)
			(xy 179.48343 -118.715127) (xy 179.480464 -118.726712) (xy 179.379006 -119.567198) (xy 182.69966 -119.567198)
			(xy 182.69966 -118.703598) (xy 182.70015 -118.67363) (xy 182.707973 -118.614208) (xy 182.723486 -118.556315)
			(xy 182.746422 -118.500942) (xy 182.776389 -118.449036) (xy 182.812876 -118.401486) (xy 182.855256 -118.359106)
			(xy 182.902806 -118.322619) (xy 182.954712 -118.292652) (xy 183.010085 -118.269716) (xy 183.067978 -118.254203)
			(xy 183.1274 -118.24638) (xy 183.187336 -118.24638) (xy 183.246758 -118.254203) (xy 183.304651 -118.269716)
			(xy 183.360024 -118.292652) (xy 183.41193 -118.322619) (xy 183.45948 -118.359106) (xy 183.50186 -118.401486)
			(xy 183.538347 -118.449036) (xy 183.568314 -118.500942) (xy 183.59125 -118.556315) (xy 183.606763 -118.614208)
			(xy 183.614586 -118.67363) (xy 183.615076 -118.703598) (xy 183.615076 -118.711218) (xy 185.909202 -118.711218)
			(xy 185.913273 -118.655596) (xy 185.925399 -118.601159) (xy 185.945322 -118.549068) (xy 185.972618 -118.500433)
			(xy 186.006704 -118.45629) (xy 186.046853 -118.417581) (xy 186.092211 -118.38513) (xy 186.141811 -118.359629)
			(xy 186.194595 -118.341622) (xy 186.249438 -118.331492) (xy 186.305172 -118.329455) (xy 186.360609 -118.335555)
			(xy 186.414566 -118.349661) (xy 186.465895 -118.371473) (xy 186.513501 -118.400527) (xy 186.556369 -118.436202)
			(xy 186.593586 -118.477739) (xy 186.624359 -118.524252) (xy 186.648031 -118.574749) (xy 186.664099 -118.628156)
			(xy 186.672219 -118.683332) (xy 186.672728 -118.711218) (xy 186.672219 -118.739104) (xy 186.664099 -118.79428)
			(xy 186.648031 -118.847687) (xy 186.624359 -118.898184) (xy 186.593586 -118.944697) (xy 186.556369 -118.986234)
			(xy 186.513501 -119.021909) (xy 186.465895 -119.050963) (xy 186.414566 -119.072775) (xy 186.360609 -119.086881)
			(xy 186.305172 -119.092981) (xy 186.249438 -119.090944) (xy 186.194595 -119.080814) (xy 186.141811 -119.062807)
			(xy 186.092211 -119.037306) (xy 186.046853 -119.004855) (xy 186.006704 -118.966146) (xy 185.972618 -118.922003)
			(xy 185.945322 -118.873368) (xy 185.925399 -118.821277) (xy 185.913273 -118.76684) (xy 185.909202 -118.711218)
			(xy 183.615076 -118.711218) (xy 183.615076 -119.567198) (xy 183.614586 -119.597166) (xy 183.606763 -119.656588)
			(xy 183.59125 -119.714481) (xy 183.568314 -119.769854) (xy 183.538347 -119.82176) (xy 183.50186 -119.86931)
			(xy 183.45948 -119.91169) (xy 183.41193 -119.948177) (xy 183.360024 -119.978144) (xy 183.304651 -120.00108)
			(xy 183.246758 -120.016593) (xy 183.187336 -120.024416) (xy 183.1274 -120.024416) (xy 183.067978 -120.016593)
			(xy 183.010085 -120.00108) (xy 182.954712 -119.978144) (xy 182.902806 -119.948177) (xy 182.855256 -119.91169)
			(xy 182.812876 -119.86931) (xy 182.776389 -119.82176) (xy 182.746422 -119.769854) (xy 182.723486 -119.714481)
			(xy 182.707973 -119.656588) (xy 182.70015 -119.597166) (xy 182.69966 -119.567198) (xy 179.379006 -119.567198)
			(xy 179.325778 -120.008142) (xy 179.231798 -120.786652) (xy 179.201318 -121.041414) (xy 179.201064 -121.04497)
			(xy 179.184003 -121.367296) (xy 180.84546 -121.367296) (xy 180.84546 -120.503696) (xy 180.84595 -120.473728)
			(xy 180.853773 -120.414306) (xy 180.869286 -120.356413) (xy 180.892222 -120.30104) (xy 180.922189 -120.249134)
			(xy 180.958676 -120.201584) (xy 181.001056 -120.159204) (xy 181.048606 -120.122717) (xy 181.100512 -120.09275)
			(xy 181.155885 -120.069814) (xy 181.213778 -120.054301) (xy 181.2732 -120.046478) (xy 181.333136 -120.046478)
			(xy 181.392558 -120.054301) (xy 181.450451 -120.069814) (xy 181.505824 -120.09275) (xy 181.55773 -120.122717)
			(xy 181.60528 -120.159204) (xy 181.64766 -120.201584) (xy 181.684147 -120.249134) (xy 181.714114 -120.30104)
			(xy 181.73705 -120.356413) (xy 181.752563 -120.414306) (xy 181.760386 -120.473728) (xy 181.760876 -120.503696)
			(xy 181.760876 -121.367296) (xy 181.760386 -121.397264) (xy 181.752563 -121.456686) (xy 181.73705 -121.514579)
			(xy 181.714114 -121.569952) (xy 181.684147 -121.621858) (xy 181.64766 -121.669408) (xy 181.60528 -121.711788)
			(xy 181.55773 -121.748275) (xy 181.505824 -121.778242) (xy 181.450451 -121.801178) (xy 181.392558 -121.816691)
			(xy 181.333136 -121.824514) (xy 181.2732 -121.824514) (xy 181.213778 -121.816691) (xy 181.155885 -121.801178)
			(xy 181.100512 -121.778242) (xy 181.048606 -121.748275) (xy 181.001056 -121.711788) (xy 180.958676 -121.669408)
			(xy 180.922189 -121.621858) (xy 180.892222 -121.569952) (xy 180.869286 -121.514579) (xy 180.853773 -121.456686)
			(xy 180.84595 -121.397264) (xy 180.84546 -121.367296) (xy 179.184003 -121.367296) (xy 179.088735 -123.16714)
			(xy 182.69966 -123.16714) (xy 182.69966 -122.30354) (xy 182.70015 -122.273572) (xy 182.707973 -122.21415)
			(xy 182.723486 -122.156257) (xy 182.746422 -122.100884) (xy 182.776389 -122.048978) (xy 182.812876 -122.001428)
			(xy 182.855256 -121.959048) (xy 182.902806 -121.922561) (xy 182.954712 -121.892594) (xy 183.010085 -121.869658)
			(xy 183.067978 -121.854145) (xy 183.1274 -121.846322) (xy 183.187336 -121.846322) (xy 183.246758 -121.854145)
			(xy 183.304651 -121.869658) (xy 183.360024 -121.892594) (xy 183.41193 -121.922561) (xy 183.45948 -121.959048)
			(xy 183.50186 -122.001428) (xy 183.538347 -122.048978) (xy 183.568314 -122.100884) (xy 183.59125 -122.156257)
			(xy 183.606763 -122.21415) (xy 183.614586 -122.273572) (xy 183.615076 -122.30354) (xy 183.615076 -123.16714)
			(xy 183.614586 -123.197108) (xy 183.606763 -123.25653) (xy 183.59125 -123.314423) (xy 183.568314 -123.369796)
			(xy 183.538347 -123.421702) (xy 183.50186 -123.469252) (xy 183.45948 -123.511632) (xy 183.41193 -123.548119)
			(xy 183.360024 -123.578086) (xy 183.304651 -123.601022) (xy 183.246758 -123.616535) (xy 183.187336 -123.624358)
			(xy 183.1274 -123.624358) (xy 183.067978 -123.616535) (xy 183.010085 -123.601022) (xy 182.954712 -123.578086)
			(xy 182.902806 -123.548119) (xy 182.855256 -123.511632) (xy 182.812876 -123.469252) (xy 182.776389 -123.421702)
			(xy 182.746422 -123.369796) (xy 182.723486 -123.314423) (xy 182.707973 -123.25653) (xy 182.70015 -123.197108)
			(xy 182.69966 -123.16714) (xy 179.088735 -123.16714) (xy 178.993454 -124.967238) (xy 180.84546 -124.967238)
			(xy 180.84546 -124.103638) (xy 180.84595 -124.07367) (xy 180.853773 -124.014248) (xy 180.869286 -123.956355)
			(xy 180.892222 -123.900982) (xy 180.922189 -123.849076) (xy 180.958676 -123.801526) (xy 181.001056 -123.759146)
			(xy 181.048606 -123.722659) (xy 181.100512 -123.692692) (xy 181.155885 -123.669756) (xy 181.213778 -123.654243)
			(xy 181.2732 -123.64642) (xy 181.333136 -123.64642) (xy 181.392558 -123.654243) (xy 181.450451 -123.669756)
			(xy 181.505824 -123.692692) (xy 181.55773 -123.722659) (xy 181.60528 -123.759146) (xy 181.64766 -123.801526)
			(xy 181.684147 -123.849076) (xy 181.714114 -123.900982) (xy 181.73705 -123.956355) (xy 181.752563 -124.014248)
			(xy 181.760386 -124.07367) (xy 181.760876 -124.103638) (xy 181.760876 -124.967238) (xy 181.760386 -124.997206)
			(xy 181.752563 -125.056628) (xy 181.73705 -125.114521) (xy 181.714114 -125.169894) (xy 181.684147 -125.2218)
			(xy 181.64766 -125.26935) (xy 181.60528 -125.31173) (xy 181.55773 -125.348217) (xy 181.505824 -125.378184)
			(xy 181.450451 -125.40112) (xy 181.392558 -125.416633) (xy 181.333136 -125.424456) (xy 181.2732 -125.424456)
			(xy 181.213778 -125.416633) (xy 181.155885 -125.40112) (xy 181.100512 -125.378184) (xy 181.048606 -125.348217)
			(xy 181.001056 -125.31173) (xy 180.958676 -125.26935) (xy 180.922189 -125.2218) (xy 180.892222 -125.169894)
			(xy 180.869286 -125.114521) (xy 180.853773 -125.056628) (xy 180.84595 -124.997206) (xy 180.84546 -124.967238)
			(xy 178.993454 -124.967238) (xy 178.822251 -128.201674) (xy 183.60593 -128.201674) (xy 183.610001 -128.146052)
			(xy 183.622127 -128.091615) (xy 183.64205 -128.039524) (xy 183.669346 -127.990889) (xy 183.703432 -127.946746)
			(xy 183.743581 -127.908037) (xy 183.788939 -127.875586) (xy 183.838539 -127.850085) (xy 183.891323 -127.832078)
			(xy 183.946166 -127.821948) (xy 184.0019 -127.819911) (xy 184.057337 -127.826011) (xy 184.111294 -127.840117)
			(xy 184.162623 -127.861929) (xy 184.210229 -127.890983) (xy 184.253097 -127.926658) (xy 184.290314 -127.968195)
			(xy 184.321087 -128.014708) (xy 184.344759 -128.065205) (xy 184.360827 -128.118612) (xy 184.368947 -128.173788)
			(xy 184.369456 -128.201674) (xy 184.368947 -128.22956) (xy 184.360827 -128.284736) (xy 184.344759 -128.338143)
			(xy 184.321087 -128.38864) (xy 184.290314 -128.435153) (xy 184.253097 -128.47669) (xy 184.210229 -128.512365)
			(xy 184.162623 -128.541419) (xy 184.111294 -128.563231) (xy 184.057337 -128.577337) (xy 184.0019 -128.583437)
			(xy 183.946166 -128.5814) (xy 183.891323 -128.57127) (xy 183.838539 -128.553263) (xy 183.788939 -128.527762)
			(xy 183.743581 -128.495311) (xy 183.703432 -128.456602) (xy 183.669346 -128.412459) (xy 183.64205 -128.363824)
			(xy 183.622127 -128.311733) (xy 183.610001 -128.257296) (xy 183.60593 -128.201674) (xy 178.822251 -128.201674)
			(xy 178.685923 -130.777234) (xy 182.69966 -130.777234) (xy 182.69966 -129.913634) (xy 182.70015 -129.883666)
			(xy 182.707973 -129.824244) (xy 182.723486 -129.766351) (xy 182.746422 -129.710978) (xy 182.776389 -129.659072)
			(xy 182.812876 -129.611522) (xy 182.855256 -129.569142) (xy 182.902806 -129.532655) (xy 182.954712 -129.502688)
			(xy 183.010085 -129.479752) (xy 183.067978 -129.464239) (xy 183.1274 -129.456416) (xy 183.187336 -129.456416)
			(xy 183.246758 -129.464239) (xy 183.304651 -129.479752) (xy 183.360024 -129.502688) (xy 183.41193 -129.532655)
			(xy 183.45948 -129.569142) (xy 183.50186 -129.611522) (xy 183.538347 -129.659072) (xy 183.568314 -129.710978)
			(xy 183.59125 -129.766351) (xy 183.606763 -129.824244) (xy 183.614586 -129.883666) (xy 183.615076 -129.913634)
			(xy 183.615076 -130.777234) (xy 183.614586 -130.807202) (xy 183.606763 -130.866624) (xy 183.59125 -130.924517)
			(xy 183.568314 -130.97989) (xy 183.538347 -131.031796) (xy 183.50186 -131.079346) (xy 183.45948 -131.121726)
			(xy 183.41193 -131.158213) (xy 183.360024 -131.18818) (xy 183.304651 -131.211116) (xy 183.246758 -131.226629)
			(xy 183.187336 -131.234452) (xy 183.1274 -131.234452) (xy 183.067978 -131.226629) (xy 183.010085 -131.211116)
			(xy 182.954712 -131.18818) (xy 182.902806 -131.158213) (xy 182.855256 -131.121726) (xy 182.812876 -131.079346)
			(xy 182.776389 -131.031796) (xy 182.746422 -130.97989) (xy 182.723486 -130.924517) (xy 182.707973 -130.866624)
			(xy 182.70015 -130.807202) (xy 182.69966 -130.777234) (xy 178.685923 -130.777234) (xy 178.590642 -132.577332)
			(xy 180.84546 -132.577332) (xy 180.84546 -131.713732) (xy 180.84595 -131.683764) (xy 180.853773 -131.624342)
			(xy 180.869286 -131.566449) (xy 180.892222 -131.511076) (xy 180.922189 -131.45917) (xy 180.958676 -131.41162)
			(xy 181.001056 -131.36924) (xy 181.048606 -131.332753) (xy 181.100512 -131.302786) (xy 181.155885 -131.27985)
			(xy 181.213778 -131.264337) (xy 181.2732 -131.256514) (xy 181.333136 -131.256514) (xy 181.392558 -131.264337)
			(xy 181.450451 -131.27985) (xy 181.505824 -131.302786) (xy 181.55773 -131.332753) (xy 181.60528 -131.36924)
			(xy 181.64766 -131.41162) (xy 181.684147 -131.45917) (xy 181.714114 -131.511076) (xy 181.73705 -131.566449)
			(xy 181.752563 -131.624342) (xy 181.760386 -131.683764) (xy 181.760876 -131.713732) (xy 181.760876 -132.577332)
			(xy 181.760386 -132.6073) (xy 181.752563 -132.666722) (xy 181.73705 -132.724615) (xy 181.714114 -132.779988)
			(xy 181.684147 -132.831894) (xy 181.64766 -132.879444) (xy 181.60528 -132.921824) (xy 181.55773 -132.958311)
			(xy 181.505824 -132.988278) (xy 181.450451 -133.011214) (xy 181.392558 -133.026727) (xy 181.333136 -133.03455)
			(xy 181.2732 -133.03455) (xy 181.213778 -133.026727) (xy 181.155885 -133.011214) (xy 181.100512 -132.988278)
			(xy 181.048606 -132.958311) (xy 181.001056 -132.921824) (xy 180.958676 -132.879444) (xy 180.922189 -132.831894)
			(xy 180.892222 -132.779988) (xy 180.869286 -132.724615) (xy 180.853773 -132.666722) (xy 180.84595 -132.6073)
			(xy 180.84546 -132.577332) (xy 178.590642 -132.577332) (xy 178.495374 -134.377176) (xy 182.69966 -134.377176)
			(xy 182.69966 -133.513576) (xy 182.70015 -133.483608) (xy 182.707973 -133.424186) (xy 182.723486 -133.366293)
			(xy 182.746422 -133.31092) (xy 182.776389 -133.259014) (xy 182.812876 -133.211464) (xy 182.855256 -133.169084)
			(xy 182.902806 -133.132597) (xy 182.954712 -133.10263) (xy 183.010085 -133.079694) (xy 183.067978 -133.064181)
			(xy 183.1274 -133.056358) (xy 183.187336 -133.056358) (xy 183.246758 -133.064181) (xy 183.304651 -133.079694)
			(xy 183.360024 -133.10263) (xy 183.41193 -133.132597) (xy 183.45948 -133.169084) (xy 183.50186 -133.211464)
			(xy 183.538347 -133.259014) (xy 183.568314 -133.31092) (xy 183.59125 -133.366293) (xy 183.606763 -133.424186)
			(xy 183.614586 -133.483608) (xy 183.615076 -133.513576) (xy 183.615076 -134.377176) (xy 183.614586 -134.407144)
			(xy 183.606763 -134.466566) (xy 183.59125 -134.524459) (xy 183.568314 -134.579832) (xy 183.538347 -134.631738)
			(xy 183.50186 -134.679288) (xy 183.45948 -134.721668) (xy 183.41193 -134.758155) (xy 183.360024 -134.788122)
			(xy 183.304651 -134.811058) (xy 183.246758 -134.826571) (xy 183.187336 -134.834394) (xy 183.1274 -134.834394)
			(xy 183.067978 -134.826571) (xy 183.010085 -134.811058) (xy 182.954712 -134.788122) (xy 182.902806 -134.758155)
			(xy 182.855256 -134.721668) (xy 182.812876 -134.679288) (xy 182.776389 -134.631738) (xy 182.746422 -134.579832)
			(xy 182.723486 -134.524459) (xy 182.707973 -134.466566) (xy 182.70015 -134.407144) (xy 182.69966 -134.377176)
			(xy 178.495374 -134.377176) (xy 178.400093 -136.177274) (xy 180.84546 -136.177274) (xy 180.84546 -135.313674)
			(xy 180.84595 -135.283706) (xy 180.853773 -135.224284) (xy 180.869286 -135.166391) (xy 180.892222 -135.111018)
			(xy 180.922189 -135.059112) (xy 180.958676 -135.011562) (xy 181.001056 -134.969182) (xy 181.048606 -134.932695)
			(xy 181.100512 -134.902728) (xy 181.155885 -134.879792) (xy 181.213778 -134.864279) (xy 181.2732 -134.856456)
			(xy 181.333136 -134.856456) (xy 181.392558 -134.864279) (xy 181.450451 -134.879792) (xy 181.505824 -134.902728)
			(xy 181.55773 -134.932695) (xy 181.60528 -134.969182) (xy 181.64766 -135.011562) (xy 181.684147 -135.059112)
			(xy 181.714114 -135.111018) (xy 181.73705 -135.166391) (xy 181.752563 -135.224284) (xy 181.760386 -135.283706)
			(xy 181.760876 -135.313674) (xy 181.760876 -136.177274) (xy 181.760386 -136.207242) (xy 181.752563 -136.266664)
			(xy 181.73705 -136.324557) (xy 181.714114 -136.37993) (xy 181.684147 -136.431836) (xy 181.64766 -136.479386)
			(xy 181.60528 -136.521766) (xy 181.55773 -136.558253) (xy 181.505824 -136.58822) (xy 181.450451 -136.611156)
			(xy 181.392558 -136.626669) (xy 181.333136 -136.634492) (xy 181.2732 -136.634492) (xy 181.213778 -136.626669)
			(xy 181.155885 -136.611156) (xy 181.100512 -136.58822) (xy 181.048606 -136.558253) (xy 181.001056 -136.521766)
			(xy 180.958676 -136.479386) (xy 180.922189 -136.431836) (xy 180.892222 -136.37993) (xy 180.869286 -136.324557)
			(xy 180.853773 -136.266664) (xy 180.84595 -136.207242) (xy 180.84546 -136.177274) (xy 178.400093 -136.177274)
			(xy 178.334416 -137.418064) (xy 178.334888 -137.427426) (xy 178.341711 -137.444868) (xy 178.354347 -137.458691)
			(xy 178.371108 -137.467048) (xy 178.38039 -137.468356) (xy 178.382168 -137.46861) (xy 178.382422 -137.46861)
			(xy 178.385724 -137.468864) (xy 178.38928 -137.46861) (xy 178.42103 -137.46734) (xy 178.421792 -137.46734)
			(xy 178.449044 -137.467803) (xy 178.502993 -137.475559) (xy 178.555289 -137.490915) (xy 178.604867 -137.513558)
			(xy 178.650718 -137.543026) (xy 178.691908 -137.578721) (xy 178.727598 -137.619914) (xy 178.757062 -137.665768)
			(xy 178.779699 -137.715348) (xy 178.795049 -137.767646) (xy 178.8028 -137.821596) (xy 178.8033 -137.848848)
			(xy 178.802812 -137.876085) (xy 178.795056 -137.930005) (xy 178.77971 -137.982273) (xy 178.757084 -138.031827)
			(xy 178.72764 -138.077659) (xy 178.691976 -138.118836) (xy 178.650817 -138.154521) (xy 178.605001 -138.183989)
			(xy 178.555459 -138.20664) (xy 178.503199 -138.222014) (xy 178.449283 -138.229798) (xy 178.422046 -138.230356)
			(xy 178.421538 -138.230356) (xy 178.392328 -138.229086) (xy 178.387502 -138.228832) (xy 178.387248 -138.228832)
			(xy 178.373532 -138.227816) (xy 178.301396 -138.291316) (xy 178.295395 -138.297686) (xy 178.287716 -138.313398)
			(xy 178.28641 -138.32205) (xy 178.283362 -138.37793) (xy 178.283313 -138.388755) (xy 178.291205 -138.408889)
			(xy 178.298602 -138.416792) (xy 178.353212 -138.470132) (xy 178.357188 -138.47385) (xy 178.366414 -138.479622)
			(xy 178.3715 -138.481562) (xy 178.38166 -138.485118) (xy 178.392582 -138.484356) (xy 178.421792 -138.48334)
			(xy 178.449044 -138.483803) (xy 178.502993 -138.491559) (xy 178.555289 -138.506915) (xy 178.604867 -138.529558)
			(xy 178.650718 -138.559026) (xy 178.691908 -138.594721) (xy 178.727598 -138.635914) (xy 178.757062 -138.681768)
			(xy 178.779699 -138.731348) (xy 178.795049 -138.783646) (xy 178.8028 -138.837596) (xy 178.8033 -138.864848)
			(xy 180.329584 -138.864848) (xy 180.333655 -138.809226) (xy 180.345781 -138.754789) (xy 180.365704 -138.702698)
			(xy 180.393 -138.654063) (xy 180.427086 -138.60992) (xy 180.467235 -138.571211) (xy 180.512593 -138.53876)
			(xy 180.562193 -138.513259) (xy 180.614977 -138.495252) (xy 180.66982 -138.485122) (xy 180.725554 -138.483085)
			(xy 180.780991 -138.489185) (xy 180.834948 -138.503291) (xy 180.886277 -138.525103) (xy 180.933883 -138.554157)
			(xy 180.976751 -138.589832) (xy 181.013968 -138.631369) (xy 181.044741 -138.677882) (xy 181.068413 -138.728379)
			(xy 181.084481 -138.781786) (xy 181.092601 -138.836962) (xy 181.09311 -138.864848) (xy 181.092601 -138.892734)
			(xy 181.084481 -138.94791) (xy 181.068413 -139.001317) (xy 181.044741 -139.051814) (xy 181.013968 -139.098327)
			(xy 180.976751 -139.139864) (xy 180.933883 -139.175539) (xy 180.886277 -139.204593) (xy 180.834948 -139.226405)
			(xy 180.780991 -139.240511) (xy 180.725554 -139.246611) (xy 180.66982 -139.244574) (xy 180.614977 -139.234444)
			(xy 180.562193 -139.216437) (xy 180.512593 -139.190936) (xy 180.467235 -139.158485) (xy 180.427086 -139.119776)
			(xy 180.393 -139.075633) (xy 180.365704 -139.026998) (xy 180.345781 -138.974907) (xy 180.333655 -138.92047)
			(xy 180.329584 -138.864848) (xy 178.8033 -138.864848) (xy 178.802799 -138.892587) (xy 178.794761 -138.947479)
			(xy 178.778861 -139.000629) (xy 178.755434 -139.050917) (xy 178.724974 -139.097285) (xy 178.688122 -139.138754)
			(xy 178.645656 -139.174451) (xy 178.598468 -139.203625) (xy 178.547555 -139.22566) (xy 178.493988 -139.240093)
			(xy 178.466496 -139.243816) (xy 178.45278 -139.24534) (xy 178.421792 -139.24661) (xy 178.404357 -139.246416)
			(xy 178.369631 -139.243235) (xy 178.35245 -139.24026) (xy 178.341528 -139.238228) (xy 178.331368 -139.240768)
			(xy 178.326079 -139.242176) (xy 178.316217 -139.246919) (xy 178.31181 -139.250166) (xy 178.251866 -139.29741)
			(xy 178.244125 -139.304118) (xy 178.234307 -139.322073) (xy 178.232816 -139.332208) (xy 178.012897 -143.48714)
			(xy 182.69966 -143.48714) (xy 182.69966 -142.62354) (xy 182.70015 -142.593572) (xy 182.707973 -142.53415)
			(xy 182.723486 -142.476257) (xy 182.746422 -142.420884) (xy 182.776389 -142.368978) (xy 182.812876 -142.321428)
			(xy 182.855256 -142.279048) (xy 182.902806 -142.242561) (xy 182.954712 -142.212594) (xy 183.010085 -142.189658)
			(xy 183.067978 -142.174145) (xy 183.1274 -142.166322) (xy 183.187336 -142.166322) (xy 183.246758 -142.174145)
			(xy 183.304651 -142.189658) (xy 183.360024 -142.212594) (xy 183.41193 -142.242561) (xy 183.45948 -142.279048)
			(xy 183.50186 -142.321428) (xy 183.538347 -142.368978) (xy 183.568314 -142.420884) (xy 183.59125 -142.476257)
			(xy 183.606763 -142.53415) (xy 183.614586 -142.593572) (xy 183.615076 -142.62354) (xy 183.615076 -143.48714)
			(xy 183.614586 -143.517108) (xy 183.606763 -143.57653) (xy 183.59125 -143.634423) (xy 183.568314 -143.689796)
			(xy 183.538347 -143.741702) (xy 183.50186 -143.789252) (xy 183.45948 -143.831632) (xy 183.41193 -143.868119)
			(xy 183.360024 -143.898086) (xy 183.304651 -143.921022) (xy 183.246758 -143.936535) (xy 183.187336 -143.944358)
			(xy 183.1274 -143.944358) (xy 183.067978 -143.936535) (xy 183.010085 -143.921022) (xy 182.954712 -143.898086)
			(xy 182.902806 -143.868119) (xy 182.855256 -143.831632) (xy 182.812876 -143.789252) (xy 182.776389 -143.741702)
			(xy 182.746422 -143.689796) (xy 182.723486 -143.634423) (xy 182.707973 -143.57653) (xy 182.70015 -143.517108)
			(xy 182.69966 -143.48714) (xy 178.012897 -143.48714) (xy 177.917619 -145.287238) (xy 180.84546 -145.287238)
			(xy 180.84546 -144.423638) (xy 180.84595 -144.39367) (xy 180.853773 -144.334248) (xy 180.869286 -144.276355)
			(xy 180.892222 -144.220982) (xy 180.922189 -144.169076) (xy 180.958676 -144.121526) (xy 181.001056 -144.079146)
			(xy 181.048606 -144.042659) (xy 181.100512 -144.012692) (xy 181.155885 -143.989756) (xy 181.213778 -143.974243)
			(xy 181.2732 -143.96642) (xy 181.333136 -143.96642) (xy 181.392558 -143.974243) (xy 181.450451 -143.989756)
			(xy 181.505824 -144.012692) (xy 181.55773 -144.042659) (xy 181.60528 -144.079146) (xy 181.64766 -144.121526)
			(xy 181.684147 -144.169076) (xy 181.714114 -144.220982) (xy 181.73705 -144.276355) (xy 181.752563 -144.334248)
			(xy 181.760386 -144.39367) (xy 181.760876 -144.423638) (xy 181.760876 -145.287238) (xy 181.760386 -145.317206)
			(xy 181.752563 -145.376628) (xy 181.73705 -145.434521) (xy 181.714114 -145.489894) (xy 181.684147 -145.5418)
			(xy 181.64766 -145.58935) (xy 181.60528 -145.63173) (xy 181.55773 -145.668217) (xy 181.505824 -145.698184)
			(xy 181.450451 -145.72112) (xy 181.392558 -145.736633) (xy 181.333136 -145.744456) (xy 181.2732 -145.744456)
			(xy 181.213778 -145.736633) (xy 181.155885 -145.72112) (xy 181.100512 -145.698184) (xy 181.048606 -145.668217)
			(xy 181.001056 -145.63173) (xy 180.958676 -145.58935) (xy 180.922189 -145.5418) (xy 180.892222 -145.489894)
			(xy 180.869286 -145.434521) (xy 180.853773 -145.376628) (xy 180.84595 -145.317206) (xy 180.84546 -145.287238)
			(xy 177.917619 -145.287238) (xy 177.822341 -147.087336) (xy 182.69966 -147.087336) (xy 182.69966 -146.223736)
			(xy 182.70015 -146.193768) (xy 182.707973 -146.134346) (xy 182.723486 -146.076453) (xy 182.746422 -146.02108)
			(xy 182.776389 -145.969174) (xy 182.812876 -145.921624) (xy 182.855256 -145.879244) (xy 182.902806 -145.842757)
			(xy 182.954712 -145.81279) (xy 183.010085 -145.789854) (xy 183.067978 -145.774341) (xy 183.1274 -145.766518)
			(xy 183.187336 -145.766518) (xy 183.246758 -145.774341) (xy 183.304651 -145.789854) (xy 183.360024 -145.81279)
			(xy 183.41193 -145.842757) (xy 183.45948 -145.879244) (xy 183.50186 -145.921624) (xy 183.538347 -145.969174)
			(xy 183.568314 -146.02108) (xy 183.59125 -146.076453) (xy 183.606763 -146.134346) (xy 183.614586 -146.193768)
			(xy 183.615076 -146.223736) (xy 183.615076 -147.087336) (xy 183.614586 -147.117304) (xy 183.606763 -147.176726)
			(xy 183.59125 -147.234619) (xy 183.568314 -147.289992) (xy 183.538347 -147.341898) (xy 183.50186 -147.389448)
			(xy 183.45948 -147.431828) (xy 183.41193 -147.468315) (xy 183.360024 -147.498282) (xy 183.304651 -147.521218)
			(xy 183.246758 -147.536731) (xy 183.187336 -147.544554) (xy 183.1274 -147.544554) (xy 183.067978 -147.536731)
			(xy 183.010085 -147.521218) (xy 182.954712 -147.498282) (xy 182.902806 -147.468315) (xy 182.855256 -147.431828)
			(xy 182.812876 -147.389448) (xy 182.776389 -147.341898) (xy 182.746422 -147.289992) (xy 182.723486 -147.234619)
			(xy 182.707973 -147.176726) (xy 182.70015 -147.117304) (xy 182.69966 -147.087336) (xy 177.822341 -147.087336)
			(xy 177.727063 -148.887434) (xy 180.84546 -148.887434) (xy 180.84546 -148.023834) (xy 180.84595 -147.993866)
			(xy 180.853773 -147.934444) (xy 180.869286 -147.876551) (xy 180.892222 -147.821178) (xy 180.922189 -147.769272)
			(xy 180.958676 -147.721722) (xy 181.001056 -147.679342) (xy 181.048606 -147.642855) (xy 181.100512 -147.612888)
			(xy 181.155885 -147.589952) (xy 181.213778 -147.574439) (xy 181.2732 -147.566616) (xy 181.333136 -147.566616)
			(xy 181.392558 -147.574439) (xy 181.450451 -147.589952) (xy 181.505824 -147.612888) (xy 181.55773 -147.642855)
			(xy 181.60528 -147.679342) (xy 181.64766 -147.721722) (xy 181.684147 -147.769272) (xy 181.714114 -147.821178)
			(xy 181.73705 -147.876551) (xy 181.752563 -147.934444) (xy 181.760386 -147.993866) (xy 181.760876 -148.023834)
			(xy 181.760876 -148.887434) (xy 181.760386 -148.917402) (xy 181.752563 -148.976824) (xy 181.73705 -149.034717)
			(xy 181.714114 -149.09009) (xy 181.684147 -149.141996) (xy 181.64766 -149.189546) (xy 181.60528 -149.231926)
			(xy 181.55773 -149.268413) (xy 181.505824 -149.29838) (xy 181.450451 -149.321316) (xy 181.392558 -149.336829)
			(xy 181.333136 -149.344652) (xy 181.2732 -149.344652) (xy 181.213778 -149.336829) (xy 181.155885 -149.321316)
			(xy 181.100512 -149.29838) (xy 181.048606 -149.268413) (xy 181.001056 -149.231926) (xy 180.958676 -149.189546)
			(xy 180.922189 -149.141996) (xy 180.892222 -149.09009) (xy 180.869286 -149.034717) (xy 180.853773 -148.976824)
			(xy 180.84595 -148.917402) (xy 180.84546 -148.887434) (xy 177.727063 -148.887434) (xy 177.631798 -150.687278)
			(xy 182.69966 -150.687278) (xy 182.69966 -149.823678) (xy 182.70015 -149.79371) (xy 182.707973 -149.734288)
			(xy 182.723486 -149.676395) (xy 182.746422 -149.621022) (xy 182.776389 -149.569116) (xy 182.812876 -149.521566)
			(xy 182.855256 -149.479186) (xy 182.902806 -149.442699) (xy 182.954712 -149.412732) (xy 183.010085 -149.389796)
			(xy 183.067978 -149.374283) (xy 183.1274 -149.36646) (xy 183.187336 -149.36646) (xy 183.246758 -149.374283)
			(xy 183.304651 -149.389796) (xy 183.360024 -149.412732) (xy 183.41193 -149.442699) (xy 183.45948 -149.479186)
			(xy 183.50186 -149.521566) (xy 183.538347 -149.569116) (xy 183.568314 -149.621022) (xy 183.59125 -149.676395)
			(xy 183.606763 -149.734288) (xy 183.614586 -149.79371) (xy 183.615076 -149.823678) (xy 183.615076 -150.687278)
			(xy 183.614586 -150.717246) (xy 183.606763 -150.776668) (xy 183.59125 -150.834561) (xy 183.568314 -150.889934)
			(xy 183.538347 -150.94184) (xy 183.50186 -150.98939) (xy 183.45948 -151.03177) (xy 183.41193 -151.068257)
			(xy 183.360024 -151.098224) (xy 183.304651 -151.12116) (xy 183.246758 -151.136673) (xy 183.187336 -151.144496)
			(xy 183.1274 -151.144496) (xy 183.067978 -151.136673) (xy 183.010085 -151.12116) (xy 182.954712 -151.098224)
			(xy 182.902806 -151.068257) (xy 182.855256 -151.03177) (xy 182.812876 -150.98939) (xy 182.776389 -150.94184)
			(xy 182.746422 -150.889934) (xy 182.723486 -150.834561) (xy 182.707973 -150.776668) (xy 182.70015 -150.717246)
			(xy 182.69966 -150.687278) (xy 177.631798 -150.687278) (xy 177.53652 -152.487376) (xy 180.84546 -152.487376)
			(xy 180.84546 -151.623776) (xy 180.84595 -151.593808) (xy 180.853773 -151.534386) (xy 180.869286 -151.476493)
			(xy 180.892222 -151.42112) (xy 180.922189 -151.369214) (xy 180.958676 -151.321664) (xy 181.001056 -151.279284)
			(xy 181.048606 -151.242797) (xy 181.100512 -151.21283) (xy 181.155885 -151.189894) (xy 181.213778 -151.174381)
			(xy 181.2732 -151.166558) (xy 181.333136 -151.166558) (xy 181.392558 -151.174381) (xy 181.450451 -151.189894)
			(xy 181.505824 -151.21283) (xy 181.55773 -151.242797) (xy 181.60528 -151.279284) (xy 181.64766 -151.321664)
			(xy 181.684147 -151.369214) (xy 181.714114 -151.42112) (xy 181.73705 -151.476493) (xy 181.752563 -151.534386)
			(xy 181.760386 -151.593808) (xy 181.760876 -151.623776) (xy 181.760876 -152.487376) (xy 181.760386 -152.517344)
			(xy 181.752563 -152.576766) (xy 181.73705 -152.634659) (xy 181.714114 -152.690032) (xy 181.684147 -152.741938)
			(xy 181.64766 -152.789488) (xy 181.60528 -152.831868) (xy 181.55773 -152.868355) (xy 181.505824 -152.898322)
			(xy 181.450451 -152.921258) (xy 181.392558 -152.936771) (xy 181.333136 -152.944594) (xy 181.2732 -152.944594)
			(xy 181.213778 -152.936771) (xy 181.155885 -152.921258) (xy 181.100512 -152.898322) (xy 181.048606 -152.868355)
			(xy 181.001056 -152.831868) (xy 180.958676 -152.789488) (xy 180.922189 -152.741938) (xy 180.892222 -152.690032)
			(xy 180.869286 -152.634659) (xy 180.853773 -152.576766) (xy 180.84595 -152.517344) (xy 180.84546 -152.487376)
			(xy 177.53652 -152.487376) (xy 177.441255 -154.28722) (xy 182.69966 -154.28722) (xy 182.69966 -153.42362)
			(xy 182.70015 -153.393652) (xy 182.707973 -153.33423) (xy 182.723486 -153.276337) (xy 182.746422 -153.220964)
			(xy 182.776389 -153.169058) (xy 182.812876 -153.121508) (xy 182.855256 -153.079128) (xy 182.902806 -153.042641)
			(xy 182.954712 -153.012674) (xy 183.010085 -152.989738) (xy 183.067978 -152.974225) (xy 183.1274 -152.966402)
			(xy 183.187336 -152.966402) (xy 183.246758 -152.974225) (xy 183.304651 -152.989738) (xy 183.360024 -153.012674)
			(xy 183.41193 -153.042641) (xy 183.45948 -153.079128) (xy 183.50186 -153.121508) (xy 183.538347 -153.169058)
			(xy 183.568314 -153.220964) (xy 183.59125 -153.276337) (xy 183.606763 -153.33423) (xy 183.614586 -153.393652)
			(xy 183.615076 -153.42362) (xy 183.615076 -154.28722) (xy 183.614586 -154.317188) (xy 183.606763 -154.37661)
			(xy 183.59125 -154.434503) (xy 183.568314 -154.489876) (xy 183.538347 -154.541782) (xy 183.50186 -154.589332)
			(xy 183.45948 -154.631712) (xy 183.41193 -154.668199) (xy 183.360024 -154.698166) (xy 183.304651 -154.721102)
			(xy 183.246758 -154.736615) (xy 183.187336 -154.744438) (xy 183.1274 -154.744438) (xy 183.067978 -154.736615)
			(xy 183.010085 -154.721102) (xy 182.954712 -154.698166) (xy 182.902806 -154.668199) (xy 182.855256 -154.631712)
			(xy 182.812876 -154.589332) (xy 182.776389 -154.541782) (xy 182.746422 -154.489876) (xy 182.723486 -154.434503)
			(xy 182.707973 -154.37661) (xy 182.70015 -154.317188) (xy 182.69966 -154.28722) (xy 177.441255 -154.28722)
			(xy 177.345977 -156.087318) (xy 180.84546 -156.087318) (xy 180.84546 -155.223718) (xy 180.84595 -155.19375)
			(xy 180.853773 -155.134328) (xy 180.869286 -155.076435) (xy 180.892222 -155.021062) (xy 180.922189 -154.969156)
			(xy 180.958676 -154.921606) (xy 181.001056 -154.879226) (xy 181.048606 -154.842739) (xy 181.100512 -154.812772)
			(xy 181.155885 -154.789836) (xy 181.213778 -154.774323) (xy 181.2732 -154.7665) (xy 181.333136 -154.7665)
			(xy 181.392558 -154.774323) (xy 181.450451 -154.789836) (xy 181.505824 -154.812772) (xy 181.55773 -154.842739)
			(xy 181.60528 -154.879226) (xy 181.64766 -154.921606) (xy 181.684147 -154.969156) (xy 181.714114 -155.021062)
			(xy 181.73705 -155.076435) (xy 181.752563 -155.134328) (xy 181.760386 -155.19375) (xy 181.760876 -155.223718)
			(xy 181.760876 -156.087318) (xy 181.760386 -156.117286) (xy 181.752563 -156.176708) (xy 181.73705 -156.234601)
			(xy 181.714114 -156.289974) (xy 181.684147 -156.34188) (xy 181.64766 -156.38943) (xy 181.60528 -156.43181)
			(xy 181.55773 -156.468297) (xy 181.505824 -156.498264) (xy 181.450451 -156.5212) (xy 181.392558 -156.536713)
			(xy 181.333136 -156.544536) (xy 181.2732 -156.544536) (xy 181.213778 -156.536713) (xy 181.155885 -156.5212)
			(xy 181.100512 -156.498264) (xy 181.048606 -156.468297) (xy 181.001056 -156.43181) (xy 180.958676 -156.38943)
			(xy 180.922189 -156.34188) (xy 180.892222 -156.289974) (xy 180.869286 -156.234601) (xy 180.853773 -156.176708)
			(xy 180.84595 -156.117286) (xy 180.84546 -156.087318) (xy 177.345977 -156.087318) (xy 177.295279 -157.045152)
			(xy 178.526438 -157.045152) (xy 178.530509 -156.98953) (xy 178.542635 -156.935093) (xy 178.562558 -156.883002)
			(xy 178.589854 -156.834367) (xy 178.62394 -156.790224) (xy 178.664089 -156.751515) (xy 178.709447 -156.719064)
			(xy 178.759047 -156.693563) (xy 178.811831 -156.675556) (xy 178.866674 -156.665426) (xy 178.922408 -156.663389)
			(xy 178.977845 -156.669489) (xy 179.031802 -156.683595) (xy 179.083131 -156.705407) (xy 179.130737 -156.734461)
			(xy 179.173605 -156.770136) (xy 179.210822 -156.811673) (xy 179.241595 -156.858186) (xy 179.265267 -156.908683)
			(xy 179.281335 -156.96209) (xy 179.289455 -157.017266) (xy 179.289964 -157.045152) (xy 179.289455 -157.073038)
			(xy 179.281335 -157.128214) (xy 179.265267 -157.181621) (xy 179.241595 -157.232118) (xy 179.210822 -157.278631)
			(xy 179.173605 -157.320168) (xy 179.130737 -157.355843) (xy 179.083131 -157.384897) (xy 179.031802 -157.406709)
			(xy 178.977845 -157.420815) (xy 178.922408 -157.426915) (xy 178.866674 -157.424878) (xy 178.811831 -157.414748)
			(xy 178.759047 -157.396741) (xy 178.709447 -157.37124) (xy 178.664089 -157.338789) (xy 178.62394 -157.30008)
			(xy 178.589854 -157.255937) (xy 178.562558 -157.207302) (xy 178.542635 -157.155211) (xy 178.530509 -157.100774)
			(xy 178.526438 -157.045152) (xy 177.295279 -157.045152) (xy 177.129083 -160.1851) (xy 185.988973 -160.1851)
			(xy 185.992929 -160.093241) (xy 186.004766 -160.002062) (xy 186.024398 -159.912238) (xy 186.051679 -159.824435)
			(xy 186.086407 -159.739302) (xy 186.128325 -159.657469) (xy 186.177123 -159.579542) (xy 186.232438 -159.506099)
			(xy 186.293863 -159.437683) (xy 186.360942 -159.374801) (xy 186.433177 -159.317918) (xy 186.510036 -159.267455)
			(xy 186.590948 -159.223786) (xy 186.675314 -159.187234) (xy 186.76251 -159.15807) (xy 186.851891 -159.13651)
			(xy 186.942794 -159.122714) (xy 187.034547 -159.116782) (xy 187.126469 -159.118761) (xy 187.217882 -159.128634)
			(xy 187.308107 -159.146329) (xy 187.396478 -159.171714) (xy 187.482338 -159.204602) (xy 187.565054 -159.24475)
			(xy 187.644012 -159.291859) (xy 187.718629 -159.345582) (xy 187.78835 -159.40552) (xy 187.852661 -159.47123)
			(xy 187.911086 -159.542226) (xy 187.963191 -159.61798) (xy 188.00859 -159.697934) (xy 188.046949 -159.781494)
			(xy 188.077982 -159.868043) (xy 188.10146 -159.956939) (xy 188.11721 -160.047524) (xy 188.125114 -160.139128)
			(xy 188.125608 -160.1851) (xy 188.125114 -160.231072) (xy 188.11721 -160.322676) (xy 188.10146 -160.413261)
			(xy 188.077982 -160.502157) (xy 188.046949 -160.588706) (xy 188.00859 -160.672266) (xy 187.963191 -160.75222)
			(xy 187.911086 -160.827974) (xy 187.852661 -160.89897) (xy 187.78835 -160.96468) (xy 187.718629 -161.024618)
			(xy 187.644012 -161.078341) (xy 187.565054 -161.12545) (xy 187.482338 -161.165598) (xy 187.396478 -161.198486)
			(xy 187.308107 -161.223871) (xy 187.217882 -161.241566) (xy 187.126469 -161.251439) (xy 187.034547 -161.253418)
			(xy 186.942794 -161.247486) (xy 186.851891 -161.23369) (xy 186.76251 -161.21213) (xy 186.675314 -161.182966)
			(xy 186.590948 -161.146414) (xy 186.510036 -161.102745) (xy 186.433177 -161.052282) (xy 186.360942 -160.995399)
			(xy 186.293863 -160.932517) (xy 186.232438 -160.864101) (xy 186.177123 -160.790658) (xy 186.128325 -160.712731)
			(xy 186.086407 -160.630898) (xy 186.051679 -160.545765) (xy 186.024398 -160.457962) (xy 186.004766 -160.368138)
			(xy 185.992929 -160.276959) (xy 185.988973 -160.1851) (xy 177.129083 -160.1851) (xy 177.019204 -162.261042)
			(xy 176.964086 -163.30041) (xy 176.817494 -166.070534) (xy 180.295294 -166.070534) (xy 180.299365 -166.014912)
			(xy 180.311491 -165.960475) (xy 180.331414 -165.908384) (xy 180.35871 -165.859749) (xy 180.392796 -165.815606)
			(xy 180.432945 -165.776897) (xy 180.478303 -165.744446) (xy 180.527903 -165.718945) (xy 180.580687 -165.700938)
			(xy 180.63553 -165.690808) (xy 180.691264 -165.688771) (xy 180.746701 -165.694871) (xy 180.800658 -165.708977)
			(xy 180.851987 -165.730789) (xy 180.899593 -165.759843) (xy 180.942461 -165.795518) (xy 180.979678 -165.837055)
			(xy 181.010451 -165.883568) (xy 181.034123 -165.934065) (xy 181.050191 -165.987472) (xy 181.058311 -166.042648)
			(xy 181.05882 -166.070534) (xy 181.058311 -166.09842) (xy 181.050191 -166.153596) (xy 181.034123 -166.207003)
			(xy 181.010451 -166.2575) (xy 180.979678 -166.304013) (xy 180.942461 -166.34555) (xy 180.899593 -166.381225)
			(xy 180.851987 -166.410279) (xy 180.800658 -166.432091) (xy 180.746701 -166.446197) (xy 180.691264 -166.452297)
			(xy 180.63553 -166.45026) (xy 180.580687 -166.44013) (xy 180.527903 -166.422123) (xy 180.478303 -166.396622)
			(xy 180.432945 -166.364171) (xy 180.392796 -166.325462) (xy 180.35871 -166.281319) (xy 180.331414 -166.232684)
			(xy 180.311491 -166.180593) (xy 180.299365 -166.126156) (xy 180.295294 -166.070534) (xy 176.817494 -166.070534)
			(xy 176.78389 -166.705534) (xy 177.211734 -166.705534) (xy 177.215805 -166.649912) (xy 177.227931 -166.595475)
			(xy 177.247854 -166.543384) (xy 177.27515 -166.494749) (xy 177.309236 -166.450606) (xy 177.349385 -166.411897)
			(xy 177.394743 -166.379446) (xy 177.444343 -166.353945) (xy 177.497127 -166.335938) (xy 177.55197 -166.325808)
			(xy 177.607704 -166.323771) (xy 177.663141 -166.329871) (xy 177.717098 -166.343977) (xy 177.768427 -166.365789)
			(xy 177.816033 -166.394843) (xy 177.858901 -166.430518) (xy 177.896118 -166.472055) (xy 177.926891 -166.518568)
			(xy 177.950563 -166.569065) (xy 177.950966 -166.570406) (xy 178.787042 -166.570406) (xy 178.791113 -166.514784)
			(xy 178.803239 -166.460347) (xy 178.823162 -166.408256) (xy 178.850458 -166.359621) (xy 178.884544 -166.315478)
			(xy 178.924693 -166.276769) (xy 178.970051 -166.244318) (xy 179.019651 -166.218817) (xy 179.072435 -166.20081)
			(xy 179.127278 -166.19068) (xy 179.183012 -166.188643) (xy 179.238449 -166.194743) (xy 179.292406 -166.208849)
			(xy 179.343735 -166.230661) (xy 179.391341 -166.259715) (xy 179.434209 -166.29539) (xy 179.471426 -166.336927)
			(xy 179.502199 -166.38344) (xy 179.525871 -166.433937) (xy 179.541939 -166.487344) (xy 179.550059 -166.54252)
			(xy 179.550568 -166.570406) (xy 179.550059 -166.598292) (xy 179.541939 -166.653468) (xy 179.525871 -166.706875)
			(xy 179.502199 -166.757372) (xy 179.471426 -166.803885) (xy 179.434209 -166.845422) (xy 179.391341 -166.881097)
			(xy 179.343735 -166.910151) (xy 179.292406 -166.931963) (xy 179.238449 -166.946069) (xy 179.183012 -166.952169)
			(xy 179.127278 -166.950132) (xy 179.072435 -166.940002) (xy 179.019651 -166.921995) (xy 178.970051 -166.896494)
			(xy 178.924693 -166.864043) (xy 178.884544 -166.825334) (xy 178.850458 -166.781191) (xy 178.823162 -166.732556)
			(xy 178.803239 -166.680465) (xy 178.791113 -166.626028) (xy 178.787042 -166.570406) (xy 177.950966 -166.570406)
			(xy 177.966631 -166.622472) (xy 177.974751 -166.677648) (xy 177.97526 -166.705534) (xy 177.974751 -166.73342)
			(xy 177.966631 -166.788596) (xy 177.950563 -166.842003) (xy 177.926891 -166.8925) (xy 177.896118 -166.939013)
			(xy 177.858901 -166.98055) (xy 177.816033 -167.016225) (xy 177.768427 -167.045279) (xy 177.717098 -167.067091)
			(xy 177.663141 -167.081197) (xy 177.607704 -167.087297) (xy 177.55197 -167.08526) (xy 177.497127 -167.07513)
			(xy 177.444343 -167.057123) (xy 177.394743 -167.031622) (xy 177.349385 -166.999171) (xy 177.309236 -166.960462)
			(xy 177.27515 -166.916319) (xy 177.247854 -166.867684) (xy 177.227931 -166.815593) (xy 177.215805 -166.761156)
			(xy 177.211734 -166.705534) (xy 176.78389 -166.705534) (xy 176.486282 -172.329348) (xy 177.947826 -172.329348)
			(xy 177.951897 -172.273726) (xy 177.964023 -172.219289) (xy 177.983946 -172.167198) (xy 178.011242 -172.118563)
			(xy 178.045328 -172.07442) (xy 178.085477 -172.035711) (xy 178.130835 -172.00326) (xy 178.180435 -171.977759)
			(xy 178.233219 -171.959752) (xy 178.288062 -171.949622) (xy 178.343796 -171.947585) (xy 178.399233 -171.953685)
			(xy 178.45319 -171.967791) (xy 178.504519 -171.989603) (xy 178.552125 -172.018657) (xy 178.594993 -172.054332)
			(xy 178.63221 -172.095869) (xy 178.662983 -172.142382) (xy 178.686655 -172.192879) (xy 178.702723 -172.246286)
			(xy 178.710843 -172.301462) (xy 178.711352 -172.329348) (xy 178.711088 -172.343826) (xy 178.885086 -172.343826)
			(xy 178.889157 -172.288204) (xy 178.901283 -172.233767) (xy 178.921206 -172.181676) (xy 178.948502 -172.133041)
			(xy 178.982588 -172.088898) (xy 179.022737 -172.050189) (xy 179.068095 -172.017738) (xy 179.117695 -171.992237)
			(xy 179.170479 -171.97423) (xy 179.225322 -171.9641) (xy 179.281056 -171.962063) (xy 179.336493 -171.968163)
			(xy 179.39045 -171.982269) (xy 179.441779 -172.004081) (xy 179.489385 -172.033135) (xy 179.532253 -172.06881)
			(xy 179.56947 -172.110347) (xy 179.600243 -172.15686) (xy 179.623915 -172.207357) (xy 179.639983 -172.260764)
			(xy 179.648103 -172.31594) (xy 179.648612 -172.343826) (xy 179.648103 -172.371712) (xy 179.639983 -172.426888)
			(xy 179.623915 -172.480295) (xy 179.600243 -172.530792) (xy 179.56947 -172.577305) (xy 179.532253 -172.618842)
			(xy 179.489385 -172.654517) (xy 179.441779 -172.683571) (xy 179.39045 -172.705383) (xy 179.336493 -172.719489)
			(xy 179.281056 -172.725589) (xy 179.225322 -172.723552) (xy 179.170479 -172.713422) (xy 179.117695 -172.695415)
			(xy 179.068095 -172.669914) (xy 179.022737 -172.637463) (xy 178.982588 -172.598754) (xy 178.948502 -172.554611)
			(xy 178.921206 -172.505976) (xy 178.901283 -172.453885) (xy 178.889157 -172.399448) (xy 178.885086 -172.343826)
			(xy 178.711088 -172.343826) (xy 178.710843 -172.357234) (xy 178.702723 -172.41241) (xy 178.686655 -172.465817)
			(xy 178.662983 -172.516314) (xy 178.63221 -172.562827) (xy 178.594993 -172.604364) (xy 178.552125 -172.640039)
			(xy 178.504519 -172.669093) (xy 178.45319 -172.690905) (xy 178.399233 -172.705011) (xy 178.343796 -172.711111)
			(xy 178.288062 -172.709074) (xy 178.233219 -172.698944) (xy 178.180435 -172.680937) (xy 178.130835 -172.655436)
			(xy 178.085477 -172.622985) (xy 178.045328 -172.584276) (xy 178.011242 -172.540133) (xy 177.983946 -172.491498)
			(xy 177.964023 -172.439407) (xy 177.951897 -172.38497) (xy 177.947826 -172.329348) (xy 176.486282 -172.329348)
			(xy 176.281218 -176.204372) (xy 183.126124 -176.204372) (xy 183.130195 -176.14875) (xy 183.142321 -176.094313)
			(xy 183.162244 -176.042222) (xy 183.18954 -175.993587) (xy 183.223626 -175.949444) (xy 183.263775 -175.910735)
			(xy 183.309133 -175.878284) (xy 183.358733 -175.852783) (xy 183.411517 -175.834776) (xy 183.46636 -175.824646)
			(xy 183.522094 -175.822609) (xy 183.577531 -175.828709) (xy 183.631488 -175.842815) (xy 183.682817 -175.864627)
			(xy 183.730423 -175.893681) (xy 183.773291 -175.929356) (xy 183.810508 -175.970893) (xy 183.841281 -176.017406)
			(xy 183.864953 -176.067903) (xy 183.881021 -176.12131) (xy 183.889141 -176.176486) (xy 183.88965 -176.204372)
			(xy 183.889141 -176.232258) (xy 183.881021 -176.287434) (xy 183.864953 -176.340841) (xy 183.841281 -176.391338)
			(xy 183.810508 -176.437851) (xy 183.773291 -176.479388) (xy 183.730423 -176.515063) (xy 183.682817 -176.544117)
			(xy 183.631488 -176.565929) (xy 183.577531 -176.580035) (xy 183.522094 -176.586135) (xy 183.46636 -176.584098)
			(xy 183.411517 -176.573968) (xy 183.358733 -176.555961) (xy 183.309133 -176.53046) (xy 183.263775 -176.498009)
			(xy 183.223626 -176.4593) (xy 183.18954 -176.415157) (xy 183.162244 -176.366522) (xy 183.142321 -176.314431)
			(xy 183.130195 -176.259994) (xy 183.126124 -176.204372) (xy 176.281218 -176.204372) (xy 176.23584 -177.061876)
			(xy 178.352702 -177.061876) (xy 178.356773 -177.006254) (xy 178.368899 -176.951817) (xy 178.388822 -176.899726)
			(xy 178.416118 -176.851091) (xy 178.450204 -176.806948) (xy 178.490353 -176.768239) (xy 178.535711 -176.735788)
			(xy 178.585311 -176.710287) (xy 178.638095 -176.69228) (xy 178.692938 -176.68215) (xy 178.748672 -176.680113)
			(xy 178.804109 -176.686213) (xy 178.858066 -176.700319) (xy 178.909395 -176.722131) (xy 178.957001 -176.751185)
			(xy 178.999869 -176.78686) (xy 179.037086 -176.828397) (xy 179.067859 -176.87491) (xy 179.091531 -176.925407)
			(xy 179.107599 -176.978814) (xy 179.115719 -177.03399) (xy 179.116228 -177.061876) (xy 179.115719 -177.089762)
			(xy 179.107599 -177.144938) (xy 179.091531 -177.198345) (xy 179.067859 -177.248842) (xy 179.037086 -177.295355)
			(xy 178.999869 -177.336892) (xy 178.957001 -177.372567) (xy 178.909395 -177.401621) (xy 178.858066 -177.423433)
			(xy 178.804109 -177.437539) (xy 178.748672 -177.443639) (xy 178.692938 -177.441602) (xy 178.638095 -177.431472)
			(xy 178.585311 -177.413465) (xy 178.535711 -177.387964) (xy 178.490353 -177.355513) (xy 178.450204 -177.316804)
			(xy 178.416118 -177.272661) (xy 178.388822 -177.224026) (xy 178.368899 -177.171935) (xy 178.356773 -177.117498)
			(xy 178.352702 -177.061876) (xy 176.23584 -177.061876) (xy 176.201134 -177.717704) (xy 180.770782 -177.717704)
			(xy 180.774853 -177.662082) (xy 180.786979 -177.607645) (xy 180.806902 -177.555554) (xy 180.834198 -177.506919)
			(xy 180.868284 -177.462776) (xy 180.908433 -177.424067) (xy 180.953791 -177.391616) (xy 181.003391 -177.366115)
			(xy 181.056175 -177.348108) (xy 181.111018 -177.337978) (xy 181.166752 -177.335941) (xy 181.222189 -177.342041)
			(xy 181.276146 -177.356147) (xy 181.327475 -177.377959) (xy 181.375081 -177.407013) (xy 181.417949 -177.442688)
			(xy 181.455166 -177.484225) (xy 181.485939 -177.530738) (xy 181.509611 -177.581235) (xy 181.525679 -177.634642)
			(xy 181.533799 -177.689818) (xy 181.534308 -177.717704) (xy 181.533799 -177.74559) (xy 181.525679 -177.800766)
			(xy 181.509611 -177.854173) (xy 181.485939 -177.90467) (xy 181.455166 -177.951183) (xy 181.417949 -177.99272)
			(xy 181.375081 -178.028395) (xy 181.327475 -178.057449) (xy 181.276146 -178.079261) (xy 181.222189 -178.093367)
			(xy 181.166752 -178.099467) (xy 181.111018 -178.09743) (xy 181.056175 -178.0873) (xy 181.003391 -178.069293)
			(xy 180.953791 -178.043792) (xy 180.908433 -178.011341) (xy 180.868284 -177.972632) (xy 180.834198 -177.928489)
			(xy 180.806902 -177.879854) (xy 180.786979 -177.827763) (xy 180.774853 -177.773326) (xy 180.770782 -177.717704)
			(xy 176.201134 -177.717704) (xy 176.167047 -178.361848) (xy 178.332382 -178.361848) (xy 178.336453 -178.306226)
			(xy 178.348579 -178.251789) (xy 178.368502 -178.199698) (xy 178.395798 -178.151063) (xy 178.429884 -178.10692)
			(xy 178.470033 -178.068211) (xy 178.515391 -178.03576) (xy 178.564991 -178.010259) (xy 178.617775 -177.992252)
			(xy 178.672618 -177.982122) (xy 178.728352 -177.980085) (xy 178.783789 -177.986185) (xy 178.837746 -178.000291)
			(xy 178.889075 -178.022103) (xy 178.936681 -178.051157) (xy 178.979549 -178.086832) (xy 179.016766 -178.128369)
			(xy 179.047539 -178.174882) (xy 179.071211 -178.225379) (xy 179.087279 -178.278786) (xy 179.095399 -178.333962)
			(xy 179.095908 -178.361848) (xy 179.095399 -178.389734) (xy 179.09012 -178.425602) (xy 181.640224 -178.425602)
			(xy 181.644295 -178.36998) (xy 181.656421 -178.315543) (xy 181.676344 -178.263452) (xy 181.70364 -178.214817)
			(xy 181.737726 -178.170674) (xy 181.777875 -178.131965) (xy 181.823233 -178.099514) (xy 181.872833 -178.074013)
			(xy 181.925617 -178.056006) (xy 181.98046 -178.045876) (xy 182.036194 -178.043839) (xy 182.091631 -178.049939)
			(xy 182.145588 -178.064045) (xy 182.196917 -178.085857) (xy 182.244523 -178.114911) (xy 182.287391 -178.150586)
			(xy 182.324608 -178.192123) (xy 182.355381 -178.238636) (xy 182.379053 -178.289133) (xy 182.395121 -178.34254)
			(xy 182.403241 -178.397716) (xy 182.40375 -178.425602) (xy 182.403241 -178.453488) (xy 182.395121 -178.508664)
			(xy 182.379053 -178.562071) (xy 182.355381 -178.612568) (xy 182.324608 -178.659081) (xy 182.287391 -178.700618)
			(xy 182.244523 -178.736293) (xy 182.196917 -178.765347) (xy 182.145588 -178.787159) (xy 182.091631 -178.801265)
			(xy 182.036194 -178.807365) (xy 181.98046 -178.805328) (xy 181.925617 -178.795198) (xy 181.872833 -178.777191)
			(xy 181.823233 -178.75169) (xy 181.777875 -178.719239) (xy 181.737726 -178.68053) (xy 181.70364 -178.636387)
			(xy 181.676344 -178.587752) (xy 181.656421 -178.535661) (xy 181.644295 -178.481224) (xy 181.640224 -178.425602)
			(xy 179.09012 -178.425602) (xy 179.087279 -178.44491) (xy 179.071211 -178.498317) (xy 179.047539 -178.548814)
			(xy 179.016766 -178.595327) (xy 178.979549 -178.636864) (xy 178.936681 -178.672539) (xy 178.889075 -178.701593)
			(xy 178.837746 -178.723405) (xy 178.783789 -178.737511) (xy 178.728352 -178.743611) (xy 178.672618 -178.741574)
			(xy 178.617775 -178.731444) (xy 178.564991 -178.713437) (xy 178.515391 -178.687936) (xy 178.470033 -178.655485)
			(xy 178.429884 -178.616776) (xy 178.395798 -178.572633) (xy 178.368502 -178.523998) (xy 178.348579 -178.471907)
			(xy 178.336453 -178.41747) (xy 178.332382 -178.361848) (xy 176.167047 -178.361848) (xy 176.095135 -179.720748)
			(xy 180.007766 -179.720748) (xy 180.011837 -179.665126) (xy 180.023963 -179.610689) (xy 180.043886 -179.558598)
			(xy 180.071182 -179.509963) (xy 180.105268 -179.46582) (xy 180.145417 -179.427111) (xy 180.190775 -179.39466)
			(xy 180.240375 -179.369159) (xy 180.293159 -179.351152) (xy 180.348002 -179.341022) (xy 180.403736 -179.338985)
			(xy 180.459173 -179.345085) (xy 180.51313 -179.359191) (xy 180.564459 -179.381003) (xy 180.612065 -179.410057)
			(xy 180.644782 -179.437284) (xy 181.43169 -179.437284) (xy 181.435761 -179.381662) (xy 181.447887 -179.327225)
			(xy 181.46781 -179.275134) (xy 181.495106 -179.226499) (xy 181.529192 -179.182356) (xy 181.569341 -179.143647)
			(xy 181.614699 -179.111196) (xy 181.664299 -179.085695) (xy 181.717083 -179.067688) (xy 181.771926 -179.057558)
			(xy 181.82766 -179.055521) (xy 181.883097 -179.061621) (xy 181.937054 -179.075727) (xy 181.988383 -179.097539)
			(xy 182.035989 -179.126593) (xy 182.078857 -179.162268) (xy 182.116074 -179.203805) (xy 182.146847 -179.250318)
			(xy 182.16448 -179.287932) (xy 183.426606 -179.287932) (xy 183.430677 -179.23231) (xy 183.442803 -179.177873)
			(xy 183.462726 -179.125782) (xy 183.490022 -179.077147) (xy 183.524108 -179.033004) (xy 183.564257 -178.994295)
			(xy 183.609615 -178.961844) (xy 183.659215 -178.936343) (xy 183.711999 -178.918336) (xy 183.766842 -178.908206)
			(xy 183.822576 -178.906169) (xy 183.878013 -178.912269) (xy 183.93197 -178.926375) (xy 183.983299 -178.948187)
			(xy 184.030905 -178.977241) (xy 184.073773 -179.012916) (xy 184.11099 -179.054453) (xy 184.141763 -179.100966)
			(xy 184.165435 -179.151463) (xy 184.181503 -179.20487) (xy 184.189623 -179.260046) (xy 184.190132 -179.287932)
			(xy 184.189623 -179.315818) (xy 184.181503 -179.370994) (xy 184.165435 -179.424401) (xy 184.141763 -179.474898)
			(xy 184.11099 -179.521411) (xy 184.073773 -179.562948) (xy 184.030905 -179.598623) (xy 183.983299 -179.627677)
			(xy 183.93197 -179.649489) (xy 183.878013 -179.663595) (xy 183.822576 -179.669695) (xy 183.766842 -179.667658)
			(xy 183.711999 -179.657528) (xy 183.659215 -179.639521) (xy 183.609615 -179.61402) (xy 183.564257 -179.581569)
			(xy 183.524108 -179.54286) (xy 183.490022 -179.498717) (xy 183.462726 -179.450082) (xy 183.442803 -179.397991)
			(xy 183.430677 -179.343554) (xy 183.426606 -179.287932) (xy 182.16448 -179.287932) (xy 182.170519 -179.300815)
			(xy 182.186587 -179.354222) (xy 182.194707 -179.409398) (xy 182.195216 -179.437284) (xy 182.194707 -179.46517)
			(xy 182.186587 -179.520346) (xy 182.170519 -179.573753) (xy 182.146847 -179.62425) (xy 182.116074 -179.670763)
			(xy 182.078857 -179.7123) (xy 182.035989 -179.747975) (xy 181.988383 -179.777029) (xy 181.937054 -179.798841)
			(xy 181.883097 -179.812947) (xy 181.82766 -179.819047) (xy 181.771926 -179.81701) (xy 181.717083 -179.80688)
			(xy 181.664299 -179.788873) (xy 181.614699 -179.763372) (xy 181.569341 -179.730921) (xy 181.529192 -179.692212)
			(xy 181.495106 -179.648069) (xy 181.46781 -179.599434) (xy 181.447887 -179.547343) (xy 181.435761 -179.492906)
			(xy 181.43169 -179.437284) (xy 180.644782 -179.437284) (xy 180.654933 -179.445732) (xy 180.69215 -179.487269)
			(xy 180.722923 -179.533782) (xy 180.746595 -179.584279) (xy 180.762663 -179.637686) (xy 180.770783 -179.692862)
			(xy 180.771292 -179.720748) (xy 180.770783 -179.748634) (xy 180.762663 -179.80381) (xy 180.746595 -179.857217)
			(xy 180.722923 -179.907714) (xy 180.69215 -179.954227) (xy 180.654933 -179.995764) (xy 180.612065 -180.031439)
			(xy 180.564459 -180.060493) (xy 180.51313 -180.082305) (xy 180.459173 -180.096411) (xy 180.403736 -180.102511)
			(xy 180.348002 -180.100474) (xy 180.293159 -180.090344) (xy 180.240375 -180.072337) (xy 180.190775 -180.046836)
			(xy 180.145417 -180.014385) (xy 180.105268 -179.975676) (xy 180.071182 -179.931533) (xy 180.043886 -179.882898)
			(xy 180.023963 -179.830807) (xy 180.011837 -179.77637) (xy 180.007766 -179.720748) (xy 176.095135 -179.720748)
			(xy 176.040079 -180.761132) (xy 182.748172 -180.761132) (xy 182.752243 -180.70551) (xy 182.764369 -180.651073)
			(xy 182.784292 -180.598982) (xy 182.811588 -180.550347) (xy 182.845674 -180.506204) (xy 182.885823 -180.467495)
			(xy 182.931181 -180.435044) (xy 182.980781 -180.409543) (xy 183.033565 -180.391536) (xy 183.088408 -180.381406)
			(xy 183.144142 -180.379369) (xy 183.199579 -180.385469) (xy 183.253536 -180.399575) (xy 183.304865 -180.421387)
			(xy 183.352471 -180.450441) (xy 183.395339 -180.486116) (xy 183.432556 -180.527653) (xy 183.463329 -180.574166)
			(xy 183.487001 -180.624663) (xy 183.503069 -180.67807) (xy 183.511189 -180.733246) (xy 183.511698 -180.761132)
			(xy 183.511189 -180.789018) (xy 183.503069 -180.844194) (xy 183.487001 -180.897601) (xy 183.463329 -180.948098)
			(xy 183.432556 -180.994611) (xy 183.395339 -181.036148) (xy 183.352471 -181.071823) (xy 183.304865 -181.100877)
			(xy 183.253536 -181.122689) (xy 183.199579 -181.136795) (xy 183.144142 -181.142895) (xy 183.088408 -181.140858)
			(xy 183.033565 -181.130728) (xy 182.980781 -181.112721) (xy 182.931181 -181.08722) (xy 182.885823 -181.054769)
			(xy 182.845674 -181.01606) (xy 182.811588 -180.971917) (xy 182.784292 -180.923282) (xy 182.764369 -180.871191)
			(xy 182.752243 -180.816754) (xy 182.748172 -180.761132) (xy 176.040079 -180.761132) (xy 175.817475 -184.967626)
			(xy 183.30494 -184.967626) (xy 183.309011 -184.912004) (xy 183.321137 -184.857567) (xy 183.34106 -184.805476)
			(xy 183.368356 -184.756841) (xy 183.402442 -184.712698) (xy 183.442591 -184.673989) (xy 183.487949 -184.641538)
			(xy 183.537549 -184.616037) (xy 183.590333 -184.59803) (xy 183.645176 -184.5879) (xy 183.70091 -184.585863)
			(xy 183.756347 -184.591963) (xy 183.810304 -184.606069) (xy 183.861633 -184.627881) (xy 183.909239 -184.656935)
			(xy 183.952107 -184.69261) (xy 183.989324 -184.734147) (xy 184.020097 -184.78066) (xy 184.043769 -184.831157)
			(xy 184.059837 -184.884564) (xy 184.067957 -184.93974) (xy 184.068466 -184.967626) (xy 184.067957 -184.995512)
			(xy 184.059837 -185.050688) (xy 184.043769 -185.104095) (xy 184.020097 -185.154592) (xy 183.989324 -185.201105)
			(xy 183.952107 -185.242642) (xy 183.909239 -185.278317) (xy 183.861633 -185.307371) (xy 183.810304 -185.329183)
			(xy 183.756347 -185.343289) (xy 183.70091 -185.349389) (xy 183.645176 -185.347352) (xy 183.590333 -185.337222)
			(xy 183.537549 -185.319215) (xy 183.487949 -185.293714) (xy 183.442591 -185.261263) (xy 183.402442 -185.222554)
			(xy 183.368356 -185.178411) (xy 183.34106 -185.129776) (xy 183.321137 -185.077685) (xy 183.309011 -185.023248)
			(xy 183.30494 -184.967626) (xy 175.817475 -184.967626) (xy 175.807878 -185.148982) (xy 175.807862 -185.158418)
			(xy 175.813826 -185.176302) (xy 175.825846 -185.190825) (xy 175.842299 -185.200029) (xy 175.851566 -185.201814)
			(xy 175.859186 -185.202322) (xy 175.861726 -185.202322) (xy 175.887888 -185.201306) (xy 175.888396 -185.201306)
			(xy 175.895508 -185.201306) (xy 175.922472 -185.202205) (xy 175.975754 -185.21066) (xy 176.027313 -185.226539)
			(xy 176.07612 -185.249524) (xy 176.121202 -185.279157) (xy 176.161659 -185.314846) (xy 176.196684 -185.35588)
			(xy 176.225577 -185.401439) (xy 176.247763 -185.450615) (xy 176.262799 -185.502426) (xy 176.270384 -185.555839)
			(xy 176.27092 -185.582814) (xy 176.270433 -185.610065) (xy 176.262675 -185.664012) (xy 176.247319 -185.716306)
			(xy 176.224677 -185.765882) (xy 176.195211 -185.811731) (xy 176.159519 -185.852921) (xy 176.11833 -185.888612)
			(xy 176.07248 -185.918078) (xy 176.022904 -185.94072) (xy 175.97061 -185.956076) (xy 175.916663 -185.963833)
			(xy 175.889412 -185.964322) (xy 175.860964 -185.963306) (xy 175.86071 -185.963306) (xy 175.856646 -185.963052)
			(xy 175.847502 -185.966354) (xy 175.84293 -185.96812) (xy 175.841623 -185.968894) (xy 183.9374 -185.968894)
			(xy 183.941471 -185.913272) (xy 183.953597 -185.858835) (xy 183.97352 -185.806744) (xy 184.000816 -185.758109)
			(xy 184.034902 -185.713966) (xy 184.075051 -185.675257) (xy 184.120409 -185.642806) (xy 184.170009 -185.617305)
			(xy 184.222793 -185.599298) (xy 184.277636 -185.589168) (xy 184.33337 -185.587131) (xy 184.388807 -185.593231)
			(xy 184.442764 -185.607337) (xy 184.494093 -185.629149) (xy 184.541699 -185.658203) (xy 184.584567 -185.693878)
			(xy 184.621784 -185.735415) (xy 184.652557 -185.781928) (xy 184.676229 -185.832425) (xy 184.692297 -185.885832)
			(xy 184.700417 -185.941008) (xy 184.700926 -185.968894) (xy 184.700417 -185.99678) (xy 184.692297 -186.051956)
			(xy 184.676229 -186.105363) (xy 184.652557 -186.15586) (xy 184.621784 -186.202373) (xy 184.584567 -186.24391)
			(xy 184.541699 -186.279585) (xy 184.494093 -186.308639) (xy 184.442764 -186.330451) (xy 184.388807 -186.344557)
			(xy 184.33337 -186.350657) (xy 184.277636 -186.34862) (xy 184.222793 -186.33849) (xy 184.170009 -186.320483)
			(xy 184.120409 -186.294982) (xy 184.075051 -186.262531) (xy 184.034902 -186.223822) (xy 184.000816 -186.179679)
			(xy 183.97352 -186.131044) (xy 183.953597 -186.078953) (xy 183.941471 -186.024516) (xy 183.9374 -185.968894)
			(xy 175.841623 -185.968894) (xy 175.834498 -185.973115) (xy 175.830738 -185.97626) (xy 175.776382 -186.02452)
			(xy 175.769209 -186.031523) (xy 175.760559 -186.049592) (xy 175.759618 -186.059572) (xy 175.672708 -187.701174)
			(xy 182.793384 -187.701174) (xy 182.797455 -187.645552) (xy 182.809581 -187.591115) (xy 182.829504 -187.539024)
			(xy 182.8568 -187.490389) (xy 182.890886 -187.446246) (xy 182.931035 -187.407537) (xy 182.976393 -187.375086)
			(xy 183.025993 -187.349585) (xy 183.078777 -187.331578) (xy 183.13362 -187.321448) (xy 183.189354 -187.319411)
			(xy 183.244791 -187.325511) (xy 183.298748 -187.339617) (xy 183.350077 -187.361429) (xy 183.397683 -187.390483)
			(xy 183.440551 -187.426158) (xy 183.477768 -187.467695) (xy 183.508541 -187.514208) (xy 183.532213 -187.564705)
			(xy 183.548281 -187.618112) (xy 183.556401 -187.673288) (xy 183.55691 -187.701174) (xy 183.556401 -187.72906)
			(xy 183.548281 -187.784236) (xy 183.532213 -187.837643) (xy 183.508541 -187.88814) (xy 183.477768 -187.934653)
			(xy 183.440551 -187.97619) (xy 183.397683 -188.011865) (xy 183.350077 -188.040919) (xy 183.298748 -188.062731)
			(xy 183.244791 -188.076837) (xy 183.189354 -188.082937) (xy 183.13362 -188.0809) (xy 183.078777 -188.07077)
			(xy 183.025993 -188.052763) (xy 182.976393 -188.027262) (xy 182.931035 -187.994811) (xy 182.890886 -187.956102)
			(xy 182.8568 -187.911959) (xy 182.829504 -187.863324) (xy 182.809581 -187.811233) (xy 182.797455 -187.756796)
			(xy 182.793384 -187.701174) (xy 175.672708 -187.701174) (xy 175.43079 -192.270634) (xy 178.101496 -192.270634)
			(xy 178.105567 -192.215012) (xy 178.117693 -192.160575) (xy 178.137616 -192.108484) (xy 178.164912 -192.059849)
			(xy 178.198998 -192.015706) (xy 178.239147 -191.976997) (xy 178.284505 -191.944546) (xy 178.334105 -191.919045)
			(xy 178.386889 -191.901038) (xy 178.441732 -191.890908) (xy 178.497466 -191.888871) (xy 178.552903 -191.894971)
			(xy 178.60686 -191.909077) (xy 178.658189 -191.930889) (xy 178.705795 -191.959943) (xy 178.748663 -191.995618)
			(xy 178.78588 -192.037155) (xy 178.816653 -192.083668) (xy 178.840325 -192.134165) (xy 178.856393 -192.187572)
			(xy 178.864513 -192.242748) (xy 178.865022 -192.270634) (xy 178.864513 -192.29852) (xy 178.856393 -192.353696)
			(xy 178.840325 -192.407103) (xy 178.816653 -192.4576) (xy 178.78588 -192.504113) (xy 178.748663 -192.54565)
			(xy 178.705795 -192.581325) (xy 178.658189 -192.610379) (xy 178.60686 -192.632191) (xy 178.552903 -192.646297)
			(xy 178.497466 -192.652397) (xy 178.441732 -192.65036) (xy 178.386889 -192.64023) (xy 178.334105 -192.622223)
			(xy 178.284505 -192.596722) (xy 178.239147 -192.564271) (xy 178.198998 -192.525562) (xy 178.164912 -192.481419)
			(xy 178.137616 -192.432784) (xy 178.117693 -192.380693) (xy 178.105567 -192.326256) (xy 178.101496 -192.270634)
			(xy 175.43079 -192.270634) (xy 175.417988 -192.512442) (xy 175.417988 -192.518792) (xy 175.419527 -192.530932)
			(xy 175.432259 -192.551783) (xy 175.442372 -192.55867) (xy 175.518826 -192.605152) (xy 175.524882 -192.608582)
			(xy 175.538285 -192.612309) (xy 175.545242 -192.612518) (xy 175.558958 -192.612518) (xy 175.570896 -192.605406)
			(xy 175.571404 -192.605406) (xy 175.593555 -192.592766) (xy 175.640496 -192.572832) (xy 175.689675 -192.559328)
			(xy 175.740215 -192.552496) (xy 175.765714 -192.552066) (xy 175.792966 -192.552553) (xy 175.846916 -192.560311)
			(xy 175.899213 -192.575669) (xy 175.948792 -192.598312) (xy 175.994644 -192.627781) (xy 176.035835 -192.663475)
			(xy 176.071527 -192.704668) (xy 176.100994 -192.75052) (xy 176.123636 -192.8001) (xy 176.138992 -192.852397)
			(xy 176.146748 -192.906348) (xy 176.146748 -192.960852) (xy 176.138992 -193.014803) (xy 176.123636 -193.0671)
			(xy 176.100994 -193.11668) (xy 176.071527 -193.162532) (xy 176.035835 -193.203725) (xy 175.994644 -193.239419)
			(xy 175.948792 -193.268888) (xy 175.899213 -193.291531) (xy 175.846916 -193.306889) (xy 175.792966 -193.314647)
			(xy 175.765714 -193.315082) (xy 175.73517 -193.314457) (xy 175.674868 -193.304676) (xy 175.616895 -193.28541)
			(xy 175.562734 -193.257151) (xy 175.537876 -193.23939) (xy 175.537368 -193.23939) (xy 175.537368 -193.239136)
			(xy 175.531781 -193.235355) (xy 175.519168 -193.230585) (xy 175.512476 -193.229738) (xy 175.505618 -193.228976)
			(xy 175.492156 -193.231262) (xy 175.424846 -193.262758) (xy 175.424338 -193.262758) (xy 175.40478 -193.272156)
			(xy 175.396629 -193.276419) (xy 175.383813 -193.289594) (xy 175.376446 -193.306433) (xy 175.37557 -193.31559)
			(xy 175.350215 -193.794634) (xy 178.101496 -193.794634) (xy 178.105567 -193.739012) (xy 178.117693 -193.684575)
			(xy 178.137616 -193.632484) (xy 178.164912 -193.583849) (xy 178.198998 -193.539706) (xy 178.239147 -193.500997)
			(xy 178.284505 -193.468546) (xy 178.334105 -193.443045) (xy 178.386889 -193.425038) (xy 178.441732 -193.414908)
			(xy 178.497466 -193.412871) (xy 178.552903 -193.418971) (xy 178.60686 -193.433077) (xy 178.658189 -193.454889)
			(xy 178.705795 -193.483943) (xy 178.748663 -193.519618) (xy 178.78588 -193.561155) (xy 178.816653 -193.607668)
			(xy 178.840325 -193.658165) (xy 178.856393 -193.711572) (xy 178.864513 -193.766748) (xy 178.865022 -193.794634)
			(xy 178.864513 -193.82252) (xy 178.856393 -193.877696) (xy 178.840325 -193.931103) (xy 178.816653 -193.9816)
			(xy 178.78588 -194.028113) (xy 178.748663 -194.06965) (xy 178.705795 -194.105325) (xy 178.658189 -194.134379)
			(xy 178.60686 -194.156191) (xy 178.552903 -194.170297) (xy 178.497466 -194.176397) (xy 178.441732 -194.17436)
			(xy 178.386889 -194.16423) (xy 178.334105 -194.146223) (xy 178.284505 -194.120722) (xy 178.239147 -194.088271)
			(xy 178.198998 -194.049562) (xy 178.164912 -194.005419) (xy 178.137616 -193.956784) (xy 178.117693 -193.904693)
			(xy 178.105567 -193.850256) (xy 178.101496 -193.794634) (xy 175.350215 -193.794634) (xy 175.328126 -194.211956)
			(xy 175.476406 -194.211956) (xy 175.480477 -194.156334) (xy 175.492603 -194.101897) (xy 175.512526 -194.049806)
			(xy 175.539822 -194.001171) (xy 175.573908 -193.957028) (xy 175.614057 -193.918319) (xy 175.659415 -193.885868)
			(xy 175.709015 -193.860367) (xy 175.761799 -193.84236) (xy 175.816642 -193.83223) (xy 175.872376 -193.830193)
			(xy 175.927813 -193.836293) (xy 175.98177 -193.850399) (xy 176.033099 -193.872211) (xy 176.080705 -193.901265)
			(xy 176.123573 -193.93694) (xy 176.16079 -193.978477) (xy 176.191563 -194.02499) (xy 176.215235 -194.075487)
			(xy 176.231303 -194.128894) (xy 176.239423 -194.18407) (xy 176.239932 -194.211956) (xy 176.239423 -194.239842)
			(xy 176.231303 -194.295018) (xy 176.215235 -194.348425) (xy 176.191563 -194.398922) (xy 176.16079 -194.445435)
			(xy 176.123573 -194.486972) (xy 176.080705 -194.522647) (xy 176.033099 -194.551701) (xy 175.98177 -194.573513)
			(xy 175.927813 -194.587619) (xy 175.872376 -194.593719) (xy 175.816642 -194.591682) (xy 175.761799 -194.581552)
			(xy 175.709015 -194.563545) (xy 175.659415 -194.538044) (xy 175.614057 -194.505593) (xy 175.573908 -194.466884)
			(xy 175.539822 -194.422741) (xy 175.512526 -194.374106) (xy 175.492603 -194.322015) (xy 175.480477 -194.267578)
			(xy 175.476406 -194.211956) (xy 175.328126 -194.211956) (xy 175.209349 -196.456046) (xy 175.442116 -196.456046)
			(xy 175.446187 -196.400424) (xy 175.458313 -196.345987) (xy 175.478236 -196.293896) (xy 175.505532 -196.245261)
			(xy 175.539618 -196.201118) (xy 175.579767 -196.162409) (xy 175.625125 -196.129958) (xy 175.674725 -196.104457)
			(xy 175.727509 -196.08645) (xy 175.782352 -196.07632) (xy 175.838086 -196.074283) (xy 175.893523 -196.080383)
			(xy 175.94748 -196.094489) (xy 175.998809 -196.116301) (xy 176.046415 -196.145355) (xy 176.089283 -196.18103)
			(xy 176.1265 -196.222567) (xy 176.157273 -196.26908) (xy 176.180945 -196.319577) (xy 176.197013 -196.372984)
			(xy 176.205133 -196.42816) (xy 176.205642 -196.456046) (xy 176.205133 -196.483932) (xy 176.197013 -196.539108)
			(xy 176.180945 -196.592515) (xy 176.157273 -196.643012) (xy 176.1265 -196.689525) (xy 176.089283 -196.731062)
			(xy 176.046415 -196.766737) (xy 175.998809 -196.795791) (xy 175.94748 -196.817603) (xy 175.893523 -196.831709)
			(xy 175.838086 -196.837809) (xy 175.782352 -196.835772) (xy 175.727509 -196.825642) (xy 175.674725 -196.807635)
			(xy 175.625125 -196.782134) (xy 175.579767 -196.749683) (xy 175.539618 -196.710974) (xy 175.505532 -196.666831)
			(xy 175.478236 -196.618196) (xy 175.458313 -196.566105) (xy 175.446187 -196.511668) (xy 175.442116 -196.456046)
			(xy 175.209349 -196.456046) (xy 175.18636 -196.890386) (xy 178.09794 -196.890386) (xy 178.102011 -196.834764)
			(xy 178.114137 -196.780327) (xy 178.13406 -196.728236) (xy 178.161356 -196.679601) (xy 178.195442 -196.635458)
			(xy 178.235591 -196.596749) (xy 178.280949 -196.564298) (xy 178.330549 -196.538797) (xy 178.383333 -196.52079)
			(xy 178.438176 -196.51066) (xy 178.49391 -196.508623) (xy 178.549347 -196.514723) (xy 178.603304 -196.528829)
			(xy 178.654633 -196.550641) (xy 178.702239 -196.579695) (xy 178.745107 -196.61537) (xy 178.782324 -196.656907)
			(xy 178.813097 -196.70342) (xy 178.836769 -196.753917) (xy 178.852837 -196.807324) (xy 178.860957 -196.8625)
			(xy 178.861466 -196.890386) (xy 178.860957 -196.918272) (xy 178.852837 -196.973448) (xy 178.836769 -197.026855)
			(xy 178.813097 -197.077352) (xy 178.782324 -197.123865) (xy 178.745107 -197.165402) (xy 178.702239 -197.201077)
			(xy 178.654633 -197.230131) (xy 178.603304 -197.251943) (xy 178.549347 -197.266049) (xy 178.49391 -197.272149)
			(xy 178.438176 -197.270112) (xy 178.383333 -197.259982) (xy 178.330549 -197.241975) (xy 178.280949 -197.216474)
			(xy 178.235591 -197.184023) (xy 178.195442 -197.145314) (xy 178.161356 -197.101171) (xy 178.13406 -197.052536)
			(xy 178.114137 -197.000445) (xy 178.102011 -196.946008) (xy 178.09794 -196.890386) (xy 175.18636 -196.890386)
			(xy 175.135071 -197.859396) (xy 175.425352 -197.859396) (xy 175.429423 -197.803774) (xy 175.441549 -197.749337)
			(xy 175.461472 -197.697246) (xy 175.488768 -197.648611) (xy 175.522854 -197.604468) (xy 175.563003 -197.565759)
			(xy 175.608361 -197.533308) (xy 175.657961 -197.507807) (xy 175.710745 -197.4898) (xy 175.765588 -197.47967)
			(xy 175.821322 -197.477633) (xy 175.876759 -197.483733) (xy 175.930716 -197.497839) (xy 175.982045 -197.519651)
			(xy 176.029651 -197.548705) (xy 176.072519 -197.58438) (xy 176.109736 -197.625917) (xy 176.140509 -197.67243)
			(xy 176.164181 -197.722927) (xy 176.180249 -197.776334) (xy 176.188369 -197.83151) (xy 176.188878 -197.859396)
			(xy 176.188369 -197.887282) (xy 176.180249 -197.942458) (xy 176.164181 -197.995865) (xy 176.140509 -198.046362)
			(xy 176.109736 -198.092875) (xy 176.072519 -198.134412) (xy 176.029651 -198.170087) (xy 175.982045 -198.199141)
			(xy 175.930716 -198.220953) (xy 175.876759 -198.235059) (xy 175.821322 -198.241159) (xy 175.765588 -198.239122)
			(xy 175.710745 -198.228992) (xy 175.657961 -198.210985) (xy 175.608361 -198.185484) (xy 175.563003 -198.153033)
			(xy 175.522854 -198.114324) (xy 175.488768 -198.070181) (xy 175.461472 -198.021546) (xy 175.441549 -197.969455)
			(xy 175.429423 -197.915018) (xy 175.425352 -197.859396) (xy 175.135071 -197.859396) (xy 175.112418 -198.287386)
			(xy 178.09794 -198.287386) (xy 178.102011 -198.231764) (xy 178.114137 -198.177327) (xy 178.13406 -198.125236)
			(xy 178.161356 -198.076601) (xy 178.195442 -198.032458) (xy 178.235591 -197.993749) (xy 178.280949 -197.961298)
			(xy 178.330549 -197.935797) (xy 178.383333 -197.91779) (xy 178.438176 -197.90766) (xy 178.49391 -197.905623)
			(xy 178.549347 -197.911723) (xy 178.603304 -197.925829) (xy 178.654633 -197.947641) (xy 178.702239 -197.976695)
			(xy 178.745107 -198.01237) (xy 178.782324 -198.053907) (xy 178.813097 -198.10042) (xy 178.836769 -198.150917)
			(xy 178.852837 -198.204324) (xy 178.860957 -198.2595) (xy 178.861466 -198.287386) (xy 178.860957 -198.315272)
			(xy 178.852837 -198.370448) (xy 178.836769 -198.423855) (xy 178.813097 -198.474352) (xy 178.782324 -198.520865)
			(xy 178.745107 -198.562402) (xy 178.702239 -198.598077) (xy 178.654633 -198.627131) (xy 178.603304 -198.648943)
			(xy 178.549347 -198.663049) (xy 178.49391 -198.669149) (xy 178.438176 -198.667112) (xy 178.383333 -198.656982)
			(xy 178.330549 -198.638975) (xy 178.280949 -198.613474) (xy 178.235591 -198.581023) (xy 178.195442 -198.542314)
			(xy 178.161356 -198.498171) (xy 178.13406 -198.449536) (xy 178.114137 -198.397445) (xy 178.102011 -198.343008)
			(xy 178.09794 -198.287386) (xy 175.112418 -198.287386) (xy 175.038853 -199.677274) (xy 180.027832 -199.677274)
			(xy 180.031903 -199.621652) (xy 180.044029 -199.567215) (xy 180.063952 -199.515124) (xy 180.091248 -199.466489)
			(xy 180.125334 -199.422346) (xy 180.165483 -199.383637) (xy 180.210841 -199.351186) (xy 180.260441 -199.325685)
			(xy 180.313225 -199.307678) (xy 180.368068 -199.297548) (xy 180.423802 -199.295511) (xy 180.479239 -199.301611)
			(xy 180.533196 -199.315717) (xy 180.584525 -199.337529) (xy 180.632131 -199.366583) (xy 180.674999 -199.402258)
			(xy 180.712216 -199.443795) (xy 180.742989 -199.490308) (xy 180.766661 -199.540805) (xy 180.782729 -199.594212)
			(xy 180.790849 -199.649388) (xy 180.791358 -199.677274) (xy 180.790849 -199.70516) (xy 180.782729 -199.760336)
			(xy 180.766661 -199.813743) (xy 180.742989 -199.86424) (xy 180.712216 -199.910753) (xy 180.674999 -199.95229)
			(xy 180.632131 -199.987965) (xy 180.584525 -200.017019) (xy 180.533196 -200.038831) (xy 180.479239 -200.052937)
			(xy 180.423802 -200.059037) (xy 180.368068 -200.057) (xy 180.313225 -200.04687) (xy 180.260441 -200.028863)
			(xy 180.210841 -200.003362) (xy 180.165483 -199.970911) (xy 180.125334 -199.932202) (xy 180.091248 -199.888059)
			(xy 180.063952 -199.839424) (xy 180.044029 -199.787333) (xy 180.031903 -199.732896) (xy 180.027832 -199.677274)
			(xy 175.038853 -199.677274) (xy 174.942312 -201.501248) (xy 180.77688 -201.501248) (xy 180.777355 -201.473878)
			(xy 180.785167 -201.419698) (xy 180.800653 -201.367195) (xy 180.823494 -201.317447) (xy 180.853218 -201.271481)
			(xy 180.87086 -201.25055) (xy 180.871114 -201.250296) (xy 180.87671 -201.243216) (xy 180.882951 -201.226294)
			(xy 180.883306 -201.217276) (xy 180.883306 -201.15022) (xy 180.882938 -201.141204) (xy 180.876698 -201.124287)
			(xy 180.871114 -201.1172) (xy 180.87086 -201.1172) (xy 180.87086 -201.116946) (xy 180.853222 -201.096013)
			(xy 180.823512 -201.05004) (xy 180.800676 -201.000292) (xy 180.785184 -200.947792) (xy 180.777355 -200.893617)
			(xy 180.77688 -200.866248) (xy 180.777366 -200.838997) (xy 180.785122 -200.785049) (xy 180.800477 -200.732754)
			(xy 180.823119 -200.683177) (xy 180.852585 -200.637327) (xy 180.888276 -200.596136) (xy 180.929467 -200.560445)
			(xy 180.975317 -200.530979) (xy 181.024894 -200.508337) (xy 181.077189 -200.492982) (xy 181.131137 -200.485226)
			(xy 181.185639 -200.485226) (xy 181.239587 -200.492982) (xy 181.291882 -200.508337) (xy 181.341459 -200.530979)
			(xy 181.387309 -200.560445) (xy 181.4285 -200.596136) (xy 181.464191 -200.637327) (xy 181.493657 -200.683177)
			(xy 181.516299 -200.732754) (xy 181.531654 -200.785049) (xy 181.53941 -200.838997) (xy 181.539896 -200.866248)
			(xy 181.5394 -200.893617) (xy 181.53159 -200.947795) (xy 181.516108 -201.000298) (xy 181.493273 -201.050045)
			(xy 181.463554 -201.096013) (xy 181.445916 -201.116946) (xy 181.445662 -201.1172) (xy 181.440065 -201.124279)
			(xy 181.433826 -201.141202) (xy 181.43347 -201.15022) (xy 181.43347 -201.217276) (xy 181.433845 -201.226291)
			(xy 181.440081 -201.243208) (xy 181.445662 -201.250296) (xy 181.445916 -201.250296) (xy 181.445916 -201.25055)
			(xy 181.463548 -201.271488) (xy 181.49326 -201.317459) (xy 181.516097 -201.367205) (xy 181.53159 -201.419705)
			(xy 181.539421 -201.473879) (xy 181.539896 -201.501248) (xy 181.53941 -201.528499) (xy 181.531654 -201.582447)
			(xy 181.516299 -201.634742) (xy 181.493657 -201.684319) (xy 181.464191 -201.730169) (xy 181.4285 -201.77136)
			(xy 181.387309 -201.807051) (xy 181.341459 -201.836517) (xy 181.291882 -201.859159) (xy 181.239587 -201.874514)
			(xy 181.185639 -201.88227) (xy 181.131137 -201.88227) (xy 181.077189 -201.874514) (xy 181.024894 -201.859159)
			(xy 180.975317 -201.836517) (xy 180.929467 -201.807051) (xy 180.888276 -201.77136) (xy 180.852585 -201.730169)
			(xy 180.823119 -201.684319) (xy 180.800477 -201.634742) (xy 180.785122 -201.582447) (xy 180.777366 -201.528499)
			(xy 180.77688 -201.501248) (xy 174.942312 -201.501248) (xy 174.658724 -206.859124) (xy 174.992028 -206.859124)
			(xy 174.996099 -206.803502) (xy 175.008225 -206.749065) (xy 175.028148 -206.696974) (xy 175.055444 -206.648339)
			(xy 175.08953 -206.604196) (xy 175.129679 -206.565487) (xy 175.175037 -206.533036) (xy 175.224637 -206.507535)
			(xy 175.277421 -206.489528) (xy 175.332264 -206.479398) (xy 175.387998 -206.477361) (xy 175.443435 -206.483461)
			(xy 175.497392 -206.497567) (xy 175.548721 -206.519379) (xy 175.596327 -206.548433) (xy 175.639195 -206.584108)
			(xy 175.676412 -206.625645) (xy 175.707185 -206.672158) (xy 175.730857 -206.722655) (xy 175.746925 -206.776062)
			(xy 175.755045 -206.831238) (xy 175.755554 -206.859124) (xy 175.755045 -206.88701) (xy 175.746925 -206.942186)
			(xy 175.730857 -206.995593) (xy 175.707185 -207.04609) (xy 175.676412 -207.092603) (xy 175.639195 -207.13414)
			(xy 175.596327 -207.169815) (xy 175.548721 -207.198869) (xy 175.497392 -207.220681) (xy 175.443435 -207.234787)
			(xy 175.387998 -207.240887) (xy 175.332264 -207.23885) (xy 175.277421 -207.22872) (xy 175.224637 -207.210713)
			(xy 175.175037 -207.185212) (xy 175.129679 -207.152761) (xy 175.08953 -207.114052) (xy 175.055444 -207.069909)
			(xy 175.028148 -207.021274) (xy 175.008225 -206.969183) (xy 174.996099 -206.914746) (xy 174.992028 -206.859124)
			(xy 174.658724 -206.859124) (xy 172.256958 -252.236224) (xy 172.256872 -252.246562) (xy 172.263942 -252.26597)
			(xy 172.270674 -252.273816) (xy 172.27804 -252.281436) (xy 172.28693 -252.285246) (xy 172.291769 -252.287252)
			(xy 172.302013 -252.289435) (xy 172.30725 -252.289564) (xy 172.697394 -252.289564) (xy 172.709194 -252.288894)
			(xy 172.730281 -252.278283) (xy 172.744458 -252.259408) (xy 172.747178 -252.247908) (xy 178.81473 -219.242386)
			(xy 180.724556 -208.853786) (xy 180.72516 -208.850135) (xy 180.725416 -208.842738) (xy 180.725064 -208.839054)
			(xy 180.724302 -208.83245) (xy 180.721762 -208.825846) (xy 180.713397 -208.80356) (xy 180.701637 -208.757433)
			(xy 180.695711 -208.710201) (xy 180.695346 -208.6864) (xy 180.695849 -208.658254) (xy 180.704117 -208.602572)
			(xy 180.720475 -208.54871) (xy 180.744568 -208.497834) (xy 180.775872 -208.451049) (xy 180.794406 -208.42986)
			(xy 180.7972 -208.427066) (xy 180.800745 -208.422107) (xy 180.80562 -208.410938) (xy 180.806852 -208.404968)
			(xy 181.24551 -206.019146) (xy 181.327044 -205.575408) (xy 182.510684 -199.136508) (xy 182.51131 -199.127336)
			(xy 182.506759 -199.10954) (xy 182.496213 -199.0945) (xy 182.48884 -199.08901) (xy 182.47995 -199.082914)
			(xy 182.476252 -199.080832) (xy 182.468337 -199.077775) (xy 182.464202 -199.076818) (xy 182.462424 -199.076564)
			(xy 182.456652 -199.075638) (xy 182.444976 -199.076144) (xy 182.43931 -199.07758) (xy 182.426356 -199.081136)
			(xy 182.420768 -199.084438) (xy 182.398806 -199.096811) (xy 182.352317 -199.116295) (xy 182.303662 -199.129472)
			(xy 182.253694 -199.136111) (xy 182.22849 -199.136508) (xy 182.222648 -199.136508) (xy 182.195658 -199.135647)
			(xy 182.142316 -199.127254) (xy 182.09069 -199.111422) (xy 182.041812 -199.088468) (xy 181.996661 -199.05885)
			(xy 181.956137 -199.023161) (xy 181.921052 -198.982113) (xy 181.892107 -198.936528) (xy 181.869879 -198.887316)
			(xy 181.854814 -198.835461) (xy 181.847213 -198.782) (xy 181.846728 -198.755) (xy 181.847191 -198.727748)
			(xy 181.854949 -198.673799) (xy 181.870305 -198.621503) (xy 181.892948 -198.571925) (xy 181.922416 -198.526075)
			(xy 181.958111 -198.484885) (xy 181.999304 -198.449195) (xy 182.045157 -198.419731) (xy 182.094737 -198.397092)
			(xy 182.147034 -198.381741) (xy 182.200984 -198.373989) (xy 182.228236 -198.373492) (xy 182.256837 -198.373998)
			(xy 182.313399 -198.382528) (xy 182.368054 -198.399407) (xy 182.419576 -198.424257) (xy 182.46681 -198.456521)
			(xy 182.508699 -198.495474) (xy 182.52694 -198.51751) (xy 182.52948 -198.520558) (xy 182.53329 -198.524368)
			(xy 182.539665 -198.530244) (xy 182.555306 -198.537697) (xy 182.572536 -198.539509) (xy 182.581042 -198.53783)
			(xy 182.61076 -198.530718) (xy 182.611014 -198.530718) (xy 182.622698 -198.527924) (xy 189.458854 -161.340038)
			(xy 189.459362 -161.33699) (xy 190.007748 -156.736796) (xy 190.005462 -156.722826) (xy 190.00343 -156.718762)
			(xy 190.003176 -156.718) (xy 190.002414 -156.716476) (xy 189.993524 -156.695902) (xy 189.981332 -156.659834)
			(xy 189.981332 -156.659326) (xy 189.977248 -156.644698) (xy 189.971146 -156.614944) (xy 189.96914 -156.59989)
			(xy 189.968632 -156.595318) (xy 189.967653 -156.585251) (xy 189.966635 -156.565047) (xy 189.9666 -156.554932)
			(xy 189.9666 -156.554424) (xy 189.967037 -156.52874) (xy 189.973963 -156.477841) (xy 189.987653 -156.428331)
			(xy 190.007859 -156.381104) (xy 190.034216 -156.337014) (xy 190.049912 -156.31668) (xy 190.052198 -156.313886)
			(xy 190.055275 -156.309198) (xy 190.059506 -156.298816) (xy 190.06058 -156.293312) (xy 190.144654 -155.586684)
			(xy 190.185548 -155.244546) (xy 190.19774 -155.141676) (xy 190.198049 -155.13259) (xy 190.193029 -155.115129)
			(xy 190.182271 -155.100488) (xy 190.17488 -155.095194) (xy 190.170562 -155.092908) (xy 190.147821 -155.080445)
			(xy 190.105627 -155.0503) (xy 190.067902 -155.01472) (xy 190.035341 -154.974361) (xy 190.008542 -154.929966)
			(xy 189.988 -154.882352) (xy 189.974092 -154.832396) (xy 189.967074 -154.781016) (xy 189.9666 -154.755088)
			(xy 189.966679 -154.74235) (xy 189.968333 -154.716929) (xy 189.969902 -154.704288) (xy 189.974116 -154.67662)
			(xy 189.989589 -154.622834) (xy 190.012743 -154.571882) (xy 190.043085 -154.524854) (xy 190.079963 -154.482756)
			(xy 190.100966 -154.464258) (xy 190.122139 -154.446924) (xy 190.168497 -154.41785) (xy 190.218522 -154.395676)
			(xy 190.24473 -154.387804) (xy 190.255144 -154.384502) (xy 190.282322 -154.353768) (xy 190.287267 -154.347823)
			(xy 190.293603 -154.333727) (xy 190.294768 -154.326082) (xy 190.911226 -149.156166) (xy 190.91148 -149.152102)
			(xy 191.086994 -144.881092) (xy 191.111378 -144.287494) (xy 191.217042 -141.71676) (xy 191.219437 -141.670421)
			(xy 191.231773 -141.578449) (xy 191.24168 -141.533118) (xy 191.270382 -141.408912) (xy 191.366394 -140.993876)
			(xy 191.366394 -140.993368) (xy 191.573912 -136.095232) (xy 191.653668 -134.215886) (xy 191.653668 -131.097782)
			(xy 191.65443 -131.056888) (xy 192.18402 -118.147084) (xy 192.185034 -118.125431) (xy 192.188719 -118.082236)
			(xy 192.191386 -118.060724) (xy 192.763648 -113.613692) (xy 192.764386 -113.606116) (xy 192.761796 -113.591122)
			(xy 192.758568 -113.584228) (xy 192.75171 -113.570766) (xy 192.746376 -113.567972) (xy 192.720413 -113.553642)
			(xy 192.672867 -113.518205) (xy 192.631361 -113.475852) (xy 192.596892 -113.427599) (xy 192.570286 -113.374603)
			(xy 192.552181 -113.318134) (xy 192.543011 -113.259548) (xy 192.542414 -113.229898) (xy 192.542492 -113.21716)
			(xy 192.544146 -113.191739) (xy 192.545716 -113.179098) (xy 192.549926 -113.15154) (xy 192.565302 -113.097956)
			(xy 192.588316 -113.047181) (xy 192.618477 -113.000299) (xy 192.655143 -112.958306) (xy 192.676018 -112.93983)
			(xy 192.698315 -112.921386) (xy 192.747402 -112.890751) (xy 192.800556 -112.867886) (xy 192.828418 -112.860074)
			(xy 192.835784 -112.858296) (xy 192.848738 -112.850422) (xy 192.853564 -112.844834) (xy 192.85844 -112.838992)
			(xy 192.864773 -112.825164) (xy 192.86601 -112.817656) (xy 193.898266 -104.796336) (xy 193.905023 -104.74836)
			(xy 193.926653 -104.653912) (xy 193.957334 -104.562005) (xy 193.996778 -104.473504) (xy 194.020186 -104.431084)
			(xy 201.70648 -90.89517) (xy 201.709528 -90.889461) (xy 201.712988 -90.876995) (xy 201.713338 -90.870532)
			(xy 201.713338 -90.857832) (xy 201.706988 -90.846148) (xy 201.692716 -90.81825) (xy 201.672472 -90.758949)
			(xy 201.662187 -90.697138) (xy 201.661522 -90.665808) (xy 201.661522 -90.657934) (xy 201.662603 -90.629223)
			(xy 201.672322 -90.572598) (xy 201.690417 -90.518068) (xy 201.716478 -90.466866) (xy 201.749919 -90.420147)
			(xy 201.789983 -90.378967) (xy 201.835765 -90.344256) (xy 201.886232 -90.316797) (xy 201.940244 -90.297211)
			(xy 201.996581 -90.285941) (xy 202.02525 -90.284046) (xy 202.033886 -90.283792) (xy 202.03922 -90.283538)
			(xy 202.050142 -90.276934) (xy 202.055644 -90.273378) (xy 202.06477 -90.263988) (xy 202.068176 -90.258392)
			(xy 202.527662 -89.448894) (xy 202.531663 -89.440151) (xy 202.533488 -89.421024) (xy 202.52815 -89.402568)
			(xy 202.516397 -89.387369) (xy 202.508358 -89.382092) (xy 202.495404 -89.374726) (xy 202.481434 -89.37498)
			(xy 202.47356 -89.37498) (xy 202.446321 -89.374477) (xy 202.392401 -89.366693) (xy 202.340136 -89.351317)
			(xy 202.290591 -89.328662) (xy 202.244773 -89.299188) (xy 202.203614 -89.263497) (xy 202.167951 -89.222312)
			(xy 202.13851 -89.176473) (xy 202.115889 -89.126912) (xy 202.10055 -89.074637) (xy 202.092803 -89.020712)
			(xy 202.092306 -88.993472) (xy 202.092794 -88.966222) (xy 202.100554 -88.912279) (xy 202.115912 -88.859988)
			(xy 202.138555 -88.810415) (xy 202.168022 -88.764569) (xy 202.203714 -88.723384) (xy 202.244903 -88.687697)
			(xy 202.290752 -88.658234) (xy 202.340327 -88.635597) (xy 202.39262 -88.620245) (xy 202.446564 -88.612491)
			(xy 202.473814 -88.611964) (xy 202.474068 -88.611964) (xy 202.501943 -88.612446) (xy 202.557098 -88.620563)
			(xy 202.610482 -88.636628) (xy 202.660957 -88.660298) (xy 202.707445 -88.691069) (xy 202.748954 -88.728284)
			(xy 202.767184 -88.749378) (xy 202.771261 -88.753985) (xy 202.781148 -88.761296) (xy 202.786742 -88.763856)
			(xy 202.792584 -88.766142) (xy 202.804268 -88.76792) (xy 202.89393 -88.759792) (xy 202.9055 -88.758216)
			(xy 202.925471 -88.746164) (xy 202.932284 -88.736678) (xy 205.126082 -84.873084) (xy 205.222348 -84.703666)
			(xy 205.222856 -84.70265) (xy 205.22551 -84.697365) (xy 205.228584 -84.685947) (xy 205.228952 -84.680044)
			(xy 205.228952 -84.675472) (xy 205.229416 -84.648433) (xy 205.237031 -84.594895) (xy 205.25212 -84.542965)
			(xy 205.274381 -84.493682) (xy 205.303369 -84.44803) (xy 205.338505 -84.406922) (xy 205.358492 -84.388706)
			(xy 205.359 -84.388198) (xy 205.363572 -84.384388) (xy 205.368622 -84.379144) (xy 205.375837 -84.366508)
			(xy 205.377796 -84.359496) (xy 205.378812 -84.35213) (xy 205.379066 -84.349844) (xy 205.378558 -84.307934)
			(xy 205.37805 -84.269834) (xy 205.377788 -84.265064) (xy 205.37574 -84.255735) (xy 205.373986 -84.251292)
			(xy 205.370176 -84.241894) (xy 205.36027 -84.231988) (xy 205.358492 -84.230464) (xy 205.337262 -84.21225)
			(xy 205.299849 -84.170668) (xy 205.26891 -84.124067) (xy 205.245111 -84.073447) (xy 205.228961 -84.019893)
			(xy 205.220807 -83.964554) (xy 205.220316 -83.936586) (xy 205.220803 -83.909317) (xy 205.228567 -83.855333)
			(xy 205.243933 -83.803004) (xy 205.26659 -83.753395) (xy 205.296075 -83.707514) (xy 205.33179 -83.666296)
			(xy 205.373007 -83.63058) (xy 205.418888 -83.601093) (xy 205.468497 -83.578436) (xy 205.520826 -83.563068)
			(xy 205.574809 -83.555304) (xy 205.602078 -83.554824) (xy 205.602586 -83.554824) (xy 205.634108 -83.555487)
			(xy 205.696289 -83.565881) (xy 205.755917 -83.586354) (xy 205.783942 -83.600798) (xy 205.789022 -83.603592)
			(xy 205.814168 -83.610196) (xy 205.823024 -83.609721) (xy 205.839623 -83.603517) (xy 205.853128 -83.592045)
			(xy 205.857856 -83.584542) (xy 206.35595 -82.707734) (xy 207.164686 -81.283556) (xy 207.168098 -81.275974)
			(xy 207.170312 -81.259508) (xy 207.169004 -81.251298) (xy 207.169004 -81.251044) (xy 207.164432 -81.223104)
			(xy 207.16367 -81.21523) (xy 207.161892 -81.1784) (xy 207.162447 -81.149202) (xy 207.171342 -81.091486)
			(xy 207.188924 -81.035799) (xy 207.214783 -80.98344) (xy 207.248315 -80.935631) (xy 207.288739 -80.893487)
			(xy 207.335109 -80.857991) (xy 207.386346 -80.829973) (xy 207.413606 -80.819498) (xy 207.41386 -80.819498)
			(xy 207.421925 -80.816273) (xy 207.435432 -80.805371) (xy 207.440276 -80.798162) (xy 207.828642 -80.113632)
			(xy 207.83042 -80.10906) (xy 207.834083 -80.097063) (xy 207.830494 -80.072269) (xy 207.823562 -80.061816)
			(xy 207.795876 -80.024478) (xy 207.76819 -79.98714) (xy 207.762023 -79.979602) (xy 207.745418 -79.969454)
			(xy 207.726231 -79.966207) (xy 207.716628 -79.967836) (xy 207.716374 -79.967836) (xy 207.696002 -79.972096)
			(xy 207.654634 -79.976679) (xy 207.633824 -79.97698) (xy 207.606572 -79.976518) (xy 207.552622 -79.968765)
			(xy 207.500326 -79.953412) (xy 207.450746 -79.930772) (xy 207.404893 -79.901307) (xy 207.363701 -79.865616)
			(xy 207.328007 -79.824426) (xy 207.298539 -79.778575) (xy 207.275896 -79.728997) (xy 207.26054 -79.676701)
			(xy 207.252783 -79.622752) (xy 207.252783 -79.568248) (xy 207.26054 -79.514299) (xy 207.275896 -79.462003)
			(xy 207.298539 -79.412425) (xy 207.328007 -79.366574) (xy 207.363701 -79.325384) (xy 207.404893 -79.289693)
			(xy 207.450746 -79.260228) (xy 207.500326 -79.237588) (xy 207.552622 -79.222235) (xy 207.606572 -79.214482)
			(xy 207.633824 -79.213964) (xy 207.660353 -79.214422) (xy 207.712897 -79.221777) (xy 207.763917 -79.236341)
			(xy 207.812426 -79.257834) (xy 207.857489 -79.285841) (xy 207.898236 -79.319821) (xy 207.933883 -79.35912)
			(xy 207.963741 -79.402978) (xy 207.987234 -79.450551) (xy 207.996028 -79.475584) (xy 207.996028 -79.475838)
			(xy 207.998622 -79.482731) (xy 208.007141 -79.494737) (xy 208.012792 -79.49946) (xy 208.01838 -79.504032)
			(xy 208.031588 -79.509366) (xy 208.038954 -79.510128) (xy 208.131664 -79.519272) (xy 208.141417 -79.519747)
			(xy 208.160121 -79.514202) (xy 208.175421 -79.502098) (xy 208.180686 -79.493872) (xy 208.195418 -79.468218)
			(xy 208.217801 -79.429766) (xy 208.268436 -79.356599) (xy 208.325389 -79.288234) (xy 208.356454 -79.256382)
			(xy 208.632298 -78.979776) (xy 208.637755 -78.972834) (xy 208.644009 -78.956334) (xy 208.64449 -78.947518)
			(xy 208.645506 -78.876652) (xy 208.64541 -78.871774) (xy 208.643621 -78.862185) (xy 208.64195 -78.857602)
			(xy 208.638394 -78.848458) (xy 208.631536 -78.841092) (xy 208.612127 -78.819745) (xy 208.579313 -78.772291)
			(xy 208.554029 -78.720433) (xy 208.536852 -78.665356) (xy 208.528173 -78.608319) (xy 208.52765 -78.579472)
			(xy 208.528138 -78.552221) (xy 208.535897 -78.498274) (xy 208.551254 -78.44598) (xy 208.573896 -78.396404)
			(xy 208.603363 -78.350554) (xy 208.639054 -78.309364) (xy 208.680243 -78.273671) (xy 208.726092 -78.244203)
			(xy 208.775667 -78.221559) (xy 208.82796 -78.2062) (xy 208.881907 -78.198439) (xy 208.909158 -78.197964)
			(xy 208.937898 -78.198482) (xy 208.994728 -78.2071) (xy 209.049621 -78.224148) (xy 209.101335 -78.249239)
			(xy 209.148699 -78.281806) (xy 209.170016 -78.301088) (xy 209.171032 -78.302104) (xy 209.177636 -78.3082)
			(xy 209.186526 -78.311502) (xy 209.191056 -78.313106) (xy 209.200517 -78.314776) (xy 209.205322 -78.314804)
			(xy 209.276696 -78.313788) (xy 209.286103 -78.31322) (xy 209.303572 -78.306197) (xy 209.310732 -78.300072)
			(xy 209.44967 -78.16088) (xy 210.547458 -77.060298) (xy 210.547712 -77.060044) (xy 210.560158 -77.047344)
			(xy 210.561682 -77.046074) (xy 210.57362 -77.034136) (xy 210.594331 -77.013669) (xy 210.637792 -76.974907)
			(xy 210.660488 -76.956666) (xy 214.840566 -73.655428) (xy 214.841074 -73.65492) (xy 215.076532 -73.461626)
			(xy 215.076786 -73.461372) (xy 215.081866 -73.457308) (xy 217.950288 -69.279262) (xy 217.956566 -69.268898)
			(xy 217.959614 -69.244894) (xy 217.95613 -69.233288) (xy 217.932254 -69.166486) (xy 217.930024 -69.160895)
			(xy 217.923351 -69.150881) (xy 217.919046 -69.146674) (xy 217.918792 -69.14642) (xy 217.894662 -69.124068)
			(xy 217.887042 -69.121528) (xy 217.883486 -69.120512) (xy 217.8685 -69.115432) (xy 217.844116 -69.10578)
			(xy 217.828851 -69.098849) (xy 217.79947 -69.0827) (xy 217.785442 -69.073522) (xy 217.754962 -69.050662)
			(xy 217.746804 -69.043873) (xy 217.731173 -69.029515) (xy 217.72372 -69.02196) (xy 217.716862 -69.014848)
			(xy 217.689684 -69.002656) (xy 217.682064 -69.000116) (xy 217.66911 -68.998338) (xy 217.61577 -68.998338)
			(xy 217.615516 -68.998338) (xy 217.610969 -68.998463) (xy 217.602026 -69.000127) (xy 217.597736 -69.00164)
			(xy 217.57767 -69.01053) (xy 217.573223 -69.012625) (xy 217.565166 -69.018253) (xy 217.561668 -69.021706)
			(xy 217.543574 -69.039758) (xy 217.503427 -69.071391) (xy 217.459427 -69.0974) (xy 217.412357 -69.11732)
			(xy 217.363054 -69.130797) (xy 217.312396 -69.137593) (xy 217.28684 -69.138038) (xy 217.26133 -69.137609)
			(xy 217.210766 -69.130807) (xy 217.161558 -69.117332) (xy 217.114583 -69.097424) (xy 217.070677 -69.071437)
			(xy 217.050366 -69.055996) (xy 217.047318 -69.053456) (xy 217.045794 -69.05244) (xy 217.03919 -69.049138)
			(xy 217.033967 -69.046797) (xy 217.022813 -69.04424) (xy 217.017092 -69.044058) (xy 216.985088 -69.044058)
			(xy 216.985088 -69.032882) (xy 216.934288 -69.032882) (xy 216.925681 -69.033208) (xy 216.909438 -69.038905)
			(xy 216.902538 -69.044058) (xy 216.901014 -69.045328) (xy 216.880137 -69.062719) (xy 216.834386 -69.092032)
			(xy 216.784937 -69.114554) (xy 216.732793 -69.129829) (xy 216.679008 -69.137548) (xy 216.65184 -69.138038)
			(xy 216.624584 -69.137578) (xy 216.570628 -69.129826) (xy 216.518323 -69.114473) (xy 216.468736 -69.091834)
			(xy 216.422876 -69.062367) (xy 216.381676 -69.026674) (xy 216.345975 -68.98548) (xy 216.3165 -68.939626)
			(xy 216.293851 -68.890043) (xy 216.278489 -68.837741) (xy 216.270727 -68.783785) (xy 216.270332 -68.75653)
			(xy 216.270755 -68.731018) (xy 216.277546 -68.680448) (xy 216.29101 -68.631233) (xy 216.310909 -68.584249)
			(xy 216.336887 -68.540334) (xy 216.352374 -68.520056) (xy 216.354914 -68.517008) (xy 216.35593 -68.515484)
			(xy 216.359232 -68.50888) (xy 216.361569 -68.503656) (xy 216.36412 -68.492502) (xy 216.364312 -68.486782)
			(xy 216.364312 -68.454778) (xy 216.375488 -68.454778) (xy 216.375488 -68.403978) (xy 216.37516 -68.395372)
			(xy 216.369457 -68.379133) (xy 216.364312 -68.372228) (xy 216.363042 -68.370704) (xy 216.345652 -68.349826)
			(xy 216.316343 -68.304074) (xy 216.293824 -68.254626) (xy 216.278552 -68.202481) (xy 216.270835 -68.148697)
			(xy 216.270332 -68.12153) (xy 216.270793 -68.094277) (xy 216.278547 -68.040325) (xy 216.293901 -67.988026)
			(xy 216.316542 -67.938444) (xy 216.34601 -67.89259) (xy 216.381704 -67.851397) (xy 216.422898 -67.815704)
			(xy 216.468753 -67.786237) (xy 216.518335 -67.763597) (xy 216.570635 -67.748245) (xy 216.624587 -67.740493)
			(xy 216.65184 -67.740022) (xy 216.67735 -67.740449) (xy 216.727916 -67.747248) (xy 216.777127 -67.76072)
			(xy 216.824105 -67.780625) (xy 216.868014 -67.806608) (xy 216.888314 -67.822064) (xy 216.891362 -67.824604)
			(xy 216.892886 -67.82562) (xy 216.89949 -67.828922) (xy 216.904713 -67.831262) (xy 216.915867 -67.833821)
			(xy 216.921588 -67.834002) (xy 216.953592 -67.834002) (xy 216.953592 -67.845178) (xy 217.004392 -67.845178)
			(xy 217.012994 -67.844838) (xy 217.029218 -67.839118) (xy 217.036142 -67.834002) (xy 217.037666 -67.832732)
			(xy 217.058544 -67.815341) (xy 217.104295 -67.786029) (xy 217.153743 -67.763506) (xy 217.205888 -67.74823)
			(xy 217.259672 -67.74051) (xy 217.28684 -67.740022) (xy 217.312395 -67.740449) (xy 217.363051 -67.747256)
			(xy 217.412349 -67.760744) (xy 217.459415 -67.780672) (xy 217.503409 -67.806687) (xy 217.543551 -67.838325)
			(xy 217.561668 -67.856354) (xy 217.565163 -67.859811) (xy 217.573221 -67.865439) (xy 217.57767 -67.86753)
			(xy 217.597736 -67.87642) (xy 217.602023 -67.877945) (xy 217.610968 -67.879602) (xy 217.615516 -67.879722)
			(xy 217.66911 -67.879722) (xy 217.669364 -67.879722) (xy 217.673912 -67.879598) (xy 217.682855 -67.877937)
			(xy 217.687144 -67.87642) (xy 217.70721 -67.86753) (xy 217.711657 -67.865435) (xy 217.719713 -67.859806)
			(xy 217.723212 -67.856354) (xy 217.741307 -67.838303) (xy 217.781454 -67.80667) (xy 217.825454 -67.780663)
			(xy 217.872524 -67.760742) (xy 217.921826 -67.747263) (xy 217.972484 -67.740466) (xy 217.99804 -67.740022)
			(xy 218.025289 -67.740511) (xy 218.07923 -67.748272) (xy 218.131518 -67.763631) (xy 218.181089 -67.786275)
			(xy 218.226932 -67.815743) (xy 218.268115 -67.851435) (xy 218.303799 -67.892624) (xy 218.333259 -67.938473)
			(xy 218.355893 -67.988047) (xy 218.371243 -68.040338) (xy 218.378994 -68.094281) (xy 218.379548 -68.12153)
			(xy 218.379121 -68.147041) (xy 218.372323 -68.197607) (xy 218.358851 -68.246817) (xy 218.338946 -68.293795)
			(xy 218.312962 -68.337704) (xy 218.297506 -68.358004) (xy 218.294966 -68.361052) (xy 218.29395 -68.362576)
			(xy 218.290648 -68.36918) (xy 218.288304 -68.374402) (xy 218.28574 -68.385556) (xy 218.285568 -68.391278)
			(xy 218.285568 -68.423282) (xy 218.274392 -68.423282) (xy 218.274392 -68.474082) (xy 218.274729 -68.482685)
			(xy 218.280445 -68.498913) (xy 218.285568 -68.505832) (xy 218.286838 -68.507356) (xy 218.29141 -68.51269)
			(xy 218.291664 -68.512944) (xy 218.292934 -68.514468) (xy 218.303602 -68.527676) (xy 218.303602 -68.528184)
			(xy 218.30411 -68.528438) (xy 218.307771 -68.532977) (xy 218.316751 -68.540413) (xy 218.32189 -68.54317)
			(xy 218.327224 -68.54571) (xy 218.338908 -68.54825) (xy 218.368372 -68.547742) (xy 218.427554 -68.546218)
			(xy 218.43958 -68.545308) (xy 218.460784 -68.533892) (xy 218.468194 -68.524374) (xy 218.668854 -68.231766)
			(xy 218.806014 -68.032122) (xy 218.808954 -68.027591) (xy 218.813062 -68.017602) (xy 218.814142 -68.01231)
			(xy 218.81592 -68.001642) (xy 218.792298 -67.914012) (xy 218.789758 -67.907662) (xy 218.765374 -67.883278)
			(xy 218.762072 -67.8815) (xy 218.738163 -67.869478) (xy 218.693672 -67.839736) (xy 218.653774 -67.804069)
			(xy 218.619252 -67.763176) (xy 218.590783 -67.71786) (xy 218.568927 -67.669011) (xy 218.554111 -67.617586)
			(xy 218.546627 -67.564596) (xy 218.546172 -67.537838) (xy 218.54795 -67.500246) (xy 218.548712 -67.493134)
			(xy 218.552456 -67.465644) (xy 218.566866 -67.41207) (xy 218.588887 -67.361149) (xy 218.618052 -67.313955)
			(xy 218.653747 -67.271484) (xy 218.695218 -67.234634) (xy 218.741591 -67.20418) (xy 218.791886 -67.180765)
			(xy 218.845044 -67.164885) (xy 218.89994 -67.156873) (xy 218.92768 -67.15633) (xy 218.953965 -67.156779)
			(xy 219.006033 -67.164025) (xy 219.056608 -67.178369) (xy 219.104727 -67.199538) (xy 219.127324 -67.212972)
			(xy 219.127832 -67.212972) (xy 219.128086 -67.213226) (xy 219.133302 -67.216172) (xy 219.144728 -67.219764)
			(xy 219.150692 -67.220338) (xy 219.162884 -67.221354) (xy 219.251022 -67.182492) (xy 219.261663 -67.177144)
			(xy 219.276894 -67.158872) (xy 219.280232 -67.14744) (xy 220.597984 -60.311792) (xy 221.283022 -56.758332)
			(xy 221.2844 -56.748781) (xy 221.280754 -56.729847) (xy 221.27591 -56.721502) (xy 221.272862 -56.716676)
			(xy 221.268798 -56.710326) (xy 221.261178 -56.701436) (xy 221.26067 -56.700928) (xy 221.25559 -56.696356)
			(xy 221.232253 -56.684447) (xy 221.188792 -56.655185) (xy 221.149747 -56.620249) (xy 221.11585 -56.580298)
			(xy 221.101412 -56.558434) (xy 221.087281 -56.535353) (xy 221.064963 -56.486051) (xy 221.049834 -56.434091)
			(xy 221.042196 -56.380515) (xy 221.041722 -56.353456) (xy 221.042193 -56.326362) (xy 221.049854 -56.272717)
			(xy 221.065028 -56.220697) (xy 221.087411 -56.171348) (xy 221.116553 -56.125662) (xy 221.151866 -56.08456)
			(xy 221.19264 -56.048869) (xy 221.238054 -56.019307) (xy 221.262448 -56.007508) (xy 221.262702 -56.007508)
			(xy 221.271095 -56.003148) (xy 221.284137 -55.989466) (xy 221.291341 -55.971991) (xy 221.291912 -55.96255)
			(xy 221.284038 -55.48503) (xy 221.283671 -55.478108) (xy 221.279686 -55.464838) (xy 221.276164 -55.458868)
			(xy 221.2594 -55.432452) (xy 221.249748 -55.423562) (xy 221.243906 -55.420514) (xy 221.218105 -55.406163)
			(xy 221.170874 -55.370741) (xy 221.12966 -55.328469) (xy 221.095446 -55.280357) (xy 221.069046 -55.227551)
			(xy 221.051091 -55.17131) (xy 221.042009 -55.112975) (xy 221.041468 -55.083456) (xy 221.042738 -55.052976)
			(xy 221.044262 -55.038498) (xy 221.04781 -55.012451) (xy 221.061139 -54.9616) (xy 221.081319 -54.91306)
			(xy 221.107969 -54.867747) (xy 221.140585 -54.826521) (xy 221.178549 -54.790159) (xy 221.221144 -54.759352)
			(xy 221.24416 -54.746652) (xy 221.247208 -54.744874) (xy 221.254441 -54.73995) (xy 221.2653 -54.726246)
			(xy 221.270891 -54.70968) (xy 221.271084 -54.700932) (xy 221.26702 -54.446424) (xy 221.266696 -54.439581)
			(xy 221.26283 -54.426446) (xy 221.2594 -54.420516) (xy 221.252542 -54.40934) (xy 221.245176 -54.405276)
			(xy 221.219236 -54.390954) (xy 221.171734 -54.35554) (xy 221.130268 -54.313217) (xy 221.095833 -54.265)
			(xy 221.069255 -54.212044) (xy 221.051172 -54.15562) (xy 221.042016 -54.097081) (xy 221.041468 -54.067456)
			(xy 221.041468 -54.067202) (xy 221.042738 -54.036214) (xy 221.044262 -54.022498) (xy 221.04826 -53.993484)
			(xy 221.064 -53.937073) (xy 221.088174 -53.883729) (xy 221.120213 -53.834705) (xy 221.159366 -53.79115)
			(xy 221.204714 -53.754089) (xy 221.229682 -53.73878) (xy 221.235541 -53.73509) (xy 221.2452 -53.725178)
			(xy 221.248732 -53.719222) (xy 221.251526 -53.714142) (xy 221.254574 -53.701188) (xy 221.25432 -53.683154)
			(xy 221.250002 -53.4162) (xy 221.249261 -53.410634) (xy 221.245666 -53.399999) (xy 221.24289 -53.395118)
			(xy 221.225872 -53.3781) (xy 221.223332 -53.376576) (xy 221.199148 -53.361103) (xy 221.155295 -53.324049)
			(xy 221.117493 -53.28084) (xy 221.086595 -53.232453) (xy 221.0633 -53.17998) (xy 221.048134 -53.124608)
			(xy 221.044262 -53.09616) (xy 221.043246 -53.08727) (xy 221.043246 -53.086762) (xy 221.042738 -53.082698)
			(xy 221.041468 -53.05171) (xy 221.041468 -53.051456) (xy 221.041939 -53.024339) (xy 221.049603 -52.970649)
			(xy 221.064785 -52.918584) (xy 221.087179 -52.869189) (xy 221.116336 -52.82346) (xy 221.151668 -52.782315)
			(xy 221.192466 -52.746581) (xy 221.21495 -52.731416) (xy 221.217998 -52.729384) (xy 221.227117 -52.721646)
			(xy 221.237604 -52.700185) (xy 221.238064 -52.688236) (xy 221.237048 -52.616862) (xy 221.236794 -52.60848)
			(xy 221.236286 -52.58181) (xy 221.234508 -52.463954) (xy 221.234183 -52.457634) (xy 221.230833 -52.445434)
			(xy 221.227904 -52.439824) (xy 221.2086 -52.42052) (xy 221.206314 -52.418996) (xy 221.181197 -52.40428)
			(xy 221.134712 -52.369238) (xy 221.093247 -52.32838) (xy 221.057524 -52.282417) (xy 221.028164 -52.23215)
			(xy 221.005679 -52.178455) (xy 220.990461 -52.122266) (xy 220.982774 -52.064562) (xy 220.982286 -52.035456)
			(xy 220.982722 -52.007063) (xy 220.989995 -51.950744) (xy 221.00443 -51.895823) (xy 221.025787 -51.843206)
			(xy 221.053714 -51.793762) (xy 221.08775 -51.748306) (xy 221.127333 -51.707589) (xy 221.171809 -51.672283)
			(xy 221.1959 -51.65725) (xy 221.196154 -51.656996) (xy 221.201658 -51.653443) (xy 221.210793 -51.644057)
			(xy 221.214188 -51.638454) (xy 221.21749 -51.632612) (xy 221.220792 -51.619658) (xy 221.21622 -51.363118)
			(xy 221.21489 -51.352329) (xy 221.204495 -51.333259) (xy 221.196154 -51.326288) (xy 221.1959 -51.326034)
			(xy 221.17242 -51.307882) (xy 221.130835 -51.265541) (xy 221.096295 -51.217281) (xy 221.069629 -51.164262)
			(xy 221.05148 -51.107759) (xy 221.042282 -51.049129) (xy 221.041722 -51.019456) (xy 221.042146 -50.992909)
			(xy 221.049434 -50.940317) (xy 221.063934 -50.889242) (xy 221.074234 -50.86477) (xy 221.087244 -50.836956)
			(xy 221.120791 -50.785528) (xy 221.162115 -50.740114) (xy 221.18574 -50.720498) (xy 221.188534 -50.718212)
			(xy 221.19608 -50.710479) (xy 221.204609 -50.690655) (xy 221.205044 -50.679858) (xy 221.202504 -50.519838)
			(xy 221.202504 -50.518314) (xy 221.198694 -50.288698) (xy 221.1973 -50.278372) (xy 221.187466 -50.260023)
			(xy 221.179644 -50.253138) (xy 221.17939 -50.252884) (xy 221.157084 -50.23469) (xy 221.117679 -50.192732)
			(xy 221.085025 -50.14533) (xy 221.059863 -50.09356) (xy 221.042764 -50.038598) (xy 221.034115 -49.98169)
			(xy 221.033594 -49.95291) (xy 221.034092 -49.925172) (xy 221.04213 -49.87028) (xy 221.058038 -49.817133)
			(xy 221.081479 -49.766852) (xy 221.111959 -49.720499) (xy 221.148835 -49.679052) (xy 221.169738 -49.66081)
			(xy 221.174056 -49.657254) (xy 221.180914 -49.64811) (xy 221.183454 -49.64303) (xy 221.185588 -49.637831)
			(xy 221.187758 -49.626807) (xy 221.187772 -49.621186) (xy 221.186756 -49.558448) (xy 221.181422 -49.258474)
			(xy 221.180213 -49.248846) (xy 221.171593 -49.231479) (xy 221.164658 -49.224692) (xy 221.164404 -49.224438)
			(xy 221.144258 -49.206231) (xy 221.108808 -49.165097) (xy 221.079546 -49.119355) (xy 221.057063 -49.069927)
			(xy 221.041811 -49.017811) (xy 221.0341 -48.96406) (xy 221.033594 -48.93691) (xy 221.034041 -48.910796)
			(xy 221.041199 -48.859062) (xy 221.055342 -48.808785) (xy 221.076206 -48.760906) (xy 221.103402 -48.716318)
			(xy 221.136421 -48.675852) (xy 221.15526 -48.657764) (xy 221.155768 -48.657256) (xy 221.162458 -48.650309)
			(xy 221.170543 -48.632816) (xy 221.171516 -48.62322) (xy 221.159324 -47.891954) (xy 221.157038 -47.750476)
			(xy 221.15653 -47.709836) (xy 221.156337 -47.705545) (xy 221.154674 -47.697117) (xy 221.153228 -47.693072)
			(xy 221.150688 -47.686214) (xy 221.145354 -47.679356) (xy 221.129689 -47.659009) (xy 221.10338 -47.614909)
			(xy 221.08322 -47.56768) (xy 221.069575 -47.518175) (xy 221.062689 -47.467288) (xy 221.062296 -47.441612)
			(xy 221.062895 -47.411077) (xy 221.072614 -47.350785) (xy 221.091807 -47.292809) (xy 221.119984 -47.238627)
			(xy 221.137734 -47.213774) (xy 221.142814 -47.206916) (xy 221.145354 -47.199296) (xy 221.146538 -47.195276)
			(xy 221.147694 -47.186976) (xy 221.14764 -47.182786) (xy 221.130876 -46.161198) (xy 221.130517 -46.153367)
			(xy 221.125604 -46.138489) (xy 221.121224 -46.131988) (xy 221.119446 -46.129956) (xy 221.103272 -46.10946)
			(xy 221.076092 -46.064881) (xy 221.055251 -46.017009) (xy 221.041141 -45.96674) (xy 221.034026 -45.915016)
			(xy 221.033594 -45.88891) (xy 221.033995 -45.864036) (xy 221.040462 -45.814711) (xy 221.053287 -45.766644)
			(xy 221.072253 -45.720654) (xy 221.097036 -45.677519) (xy 221.111826 -45.657516) (xy 221.11716 -45.650404)
			(xy 221.1197 -45.64253) (xy 221.120835 -45.638565) (xy 221.121985 -45.630398) (xy 221.121986 -45.626274)
			(xy 221.11843 -45.394118) (xy 221.113858 -45.1231) (xy 221.11368 -45.11915) (xy 221.11228 -45.111368)
			(xy 221.111064 -45.107606) (xy 221.108778 -45.101002) (xy 221.104206 -45.094398) (xy 221.087504 -45.07001)
			(xy 221.061031 -45.017163) (xy 221.043027 -44.960865) (xy 221.033923 -44.902464) (xy 221.03334 -44.87291)
			(xy 221.03334 -44.869862) (xy 221.033848 -44.8564) (xy 221.035372 -44.834556) (xy 221.036134 -44.828206)
			(xy 221.038166 -44.813728) (xy 221.040012 -44.802688) (xy 221.044842 -44.78083) (xy 221.047818 -44.77004)
			(xy 221.056415 -44.741348) (xy 221.081289 -44.686865) (xy 221.097348 -44.661582) (xy 221.101666 -44.655232)
			(xy 221.103952 -44.647612) (xy 221.104949 -44.643948) (xy 221.105973 -44.636423) (xy 221.105984 -44.632626)
			(xy 221.098364 -44.181776) (xy 221.09684 -44.079668) (xy 221.09631 -44.073516) (xy 221.092713 -44.061706)
			(xy 221.089728 -44.0563) (xy 221.089474 -44.056046) (xy 221.076179 -44.033466) (xy 221.055211 -43.985445)
			(xy 221.040991 -43.935011) (xy 221.033786 -43.883109) (xy 221.03334 -43.85691) (xy 221.033594 -43.842178)
			(xy 221.035355 -43.811807) (xy 221.04732 -43.752163) (xy 221.06861 -43.695178) (xy 221.083124 -43.668442)
			(xy 221.086426 -43.6626) (xy 221.08795 -43.657012) (xy 221.088913 -43.653471) (xy 221.08993 -43.646203)
			(xy 221.089982 -43.642534) (xy 221.086172 -43.422316) (xy 221.079568 -43.02887) (xy 221.076774 -43.017694)
			(xy 221.074234 -43.012614) (xy 221.062012 -42.987182) (xy 221.044349 -42.933594) (xy 221.03475 -42.877993)
			(xy 221.033594 -42.8498) (xy 221.03334 -42.837608) (xy 218.27236 -37.702744) (xy 218.27236 -37.70249)
			(xy 218.2622 -37.683694) (xy 217.755978 -36.755324) (xy 217.693748 -36.641024) (xy 217.679524 -36.614862)
			(xy 217.67292 -36.605464) (xy 217.661744 -36.592764) (xy 217.657172 -36.589462) (xy 217.62909 -36.568773)
			(xy 217.575572 -36.524029) (xy 217.550238 -36.500054) (xy 217.513384 -36.463694) (xy 217.446606 -36.384574)
			(xy 217.388393 -36.298955) (xy 217.363294 -36.253674) (xy 217.343736 -36.217098) (xy 217.34018 -36.21278)
			(xy 217.339926 -36.212526) (xy 217.307045 -36.173042) (xy 217.248761 -36.088414) (xy 217.223594 -36.043616)
			(xy 217.067892 -35.757866) (xy 217.012012 -35.655504) (xy 216.98881 -35.61169) (xy 216.950299 -35.520327)
			(xy 216.921137 -35.425564) (xy 216.90162 -35.328355) (xy 216.896188 -35.279076) (xy 216.895934 -35.277044)
			(xy 216.894432 -35.268348) (xy 216.886251 -35.252723) (xy 216.879932 -35.246564) (xy 216.878662 -35.245548)
			(xy 216.874344 -35.24123) (xy 216.871288 -35.238673) (xy 216.864526 -35.234459) (xy 216.860882 -35.232848)
			(xy 216.852754 -35.229546) (xy 216.84488 -35.22726) (xy 216.771982 -35.22726) (xy 216.767104 -35.227353)
			(xy 216.757512 -35.229136) (xy 216.752932 -35.230816) (xy 216.744296 -35.234372) (xy 216.73693 -35.241484)
			(xy 216.706058 -35.270421) (xy 216.640194 -35.323552) (xy 216.570064 -35.370909) (xy 216.496172 -35.412152)
			(xy 216.41905 -35.446983) (xy 216.339254 -35.475152) (xy 216.257357 -35.496457) (xy 216.17395 -35.510743)
			(xy 216.089631 -35.517909) (xy 216.04732 -35.518344) (xy 216.000793 -35.51779) (xy 215.908146 -35.509089)
			(xy 215.816713 -35.491797) (xy 215.727287 -35.466065) (xy 215.640646 -35.432116) (xy 215.557544 -35.390246)
			(xy 215.478702 -35.340819) (xy 215.404806 -35.284263) (xy 215.336498 -35.221072) (xy 215.274372 -35.151794)
			(xy 215.218968 -35.077031) (xy 215.194388 -35.037522) (xy 215.191848 -35.033712) (xy 215.181434 -35.021774)
			(xy 215.17991 -35.020504) (xy 215.157288 -35.002317) (xy 215.117289 -34.960258) (xy 215.084121 -34.912627)
			(xy 215.05855 -34.860521) (xy 215.041164 -34.805144) (xy 215.032366 -34.747773) (xy 215.031828 -34.718752)
			(xy 215.031828 -34.718498) (xy 215.032292 -34.689997) (xy 215.04071 -34.633623) (xy 215.048592 -34.60623)
			(xy 215.050116 -34.599118) (xy 215.051894 -34.588196) (xy 215.051894 -34.58464) (xy 215.05164 -34.581846)
			(xy 215.051132 -34.567622) (xy 215.051132 -34.566606) (xy 215.050116 -34.520886) (xy 215.050551 -34.478299)
			(xy 215.057792 -34.393435) (xy 215.072244 -34.309497) (xy 215.093804 -34.227098) (xy 215.122314 -34.146839)
			(xy 215.139524 -34.107882) (xy 215.142705 -34.098749) (xy 215.1427 -34.079425) (xy 215.139524 -34.07029)
			(xy 215.122316 -34.031333) (xy 215.093824 -33.951069) (xy 215.072274 -33.86867) (xy 215.057823 -33.784734)
			(xy 215.050576 -33.699872) (xy 215.050116 -33.657286) (xy 215.051894 -33.595818) (xy 215.052656 -33.583626)
			(xy 215.050624 -33.578038) (xy 215.044274 -33.565846) (xy 215.039194 -33.558734) (xy 215.03767 -33.55721)
			(xy 214.996014 -33.513014) (xy 214.98857 -33.505777) (xy 214.969553 -33.4975) (xy 214.959184 -33.497012)
			(xy 214.794338 -33.497012) (xy 214.746775 -33.49643) (xy 214.652091 -33.487264) (xy 214.558724 -33.469053)
			(xy 214.467537 -33.441963) (xy 214.423244 -33.424622) (xy 214.419942 -33.423352) (xy 214.413592 -33.420812)
			(xy 214.12962 -33.420812) (xy 214.128096 -33.420812) (xy 214.119562 -33.421389) (xy 214.10359 -33.42748)
			(xy 214.096854 -33.43275) (xy 214.065948 -33.461874) (xy 213.999963 -33.515341) (xy 213.92967 -33.563003)
			(xy 213.855579 -33.604516) (xy 213.778227 -33.639579) (xy 213.698173 -33.667937) (xy 213.615998 -33.689385)
			(xy 213.532297 -33.703769) (xy 213.447676 -33.710983) (xy 213.405212 -33.711388) (xy 213.392004 -33.711388)
			(xy 213.34614 -33.710258) (xy 213.254897 -33.700623) (xy 213.164926 -33.682647) (xy 213.076986 -33.656482)
			(xy 212.991821 -33.622351) (xy 212.910151 -33.580541) (xy 212.832666 -33.531406) (xy 212.760023 -33.475362)
			(xy 212.692834 -33.412881) (xy 212.631669 -33.344494) (xy 212.577044 -33.270777) (xy 212.552788 -33.231836)
			(xy 212.550248 -33.227772) (xy 212.537802 -33.214056) (xy 212.5345 -33.211516) (xy 212.512297 -33.193284)
			(xy 212.473091 -33.151292) (xy 212.440608 -33.103907) (xy 212.41558 -33.052195) (xy 212.39857 -32.997322)
			(xy 212.389961 -32.940521) (xy 212.389466 -32.911796) (xy 212.39099 -32.879284) (xy 212.39226 -32.867092)
			(xy 212.394467 -32.849945) (xy 212.401594 -32.816111) (xy 212.406484 -32.799528) (xy 212.408008 -32.792416)
			(xy 212.409786 -32.781494) (xy 212.409786 -32.777938) (xy 212.409532 -32.775144) (xy 212.409024 -32.76092)
			(xy 212.409024 -32.759904) (xy 212.408008 -32.714184) (xy 212.408443 -32.671598) (xy 212.415685 -32.586733)
			(xy 212.430139 -32.502796) (xy 212.4517 -32.420398) (xy 212.480212 -32.34014) (xy 212.497416 -32.30118)
			(xy 212.500596 -32.292047) (xy 212.500591 -32.272724) (xy 212.497416 -32.263588) (xy 212.480208 -32.224631)
			(xy 212.451716 -32.144367) (xy 212.430167 -32.061968) (xy 212.415716 -31.978032) (xy 212.408469 -31.89317)
			(xy 212.408008 -31.850584) (xy 212.409024 -31.804864) (xy 212.409024 -31.803848) (xy 212.409532 -31.789624)
			(xy 212.409786 -31.78683) (xy 212.409786 -31.783274) (xy 212.408008 -31.772352) (xy 212.406484 -31.76524)
			(xy 212.397848 -31.731712) (xy 212.39226 -31.697676) (xy 212.39099 -31.685484) (xy 212.389466 -31.652972)
			(xy 212.390012 -31.62392) (xy 212.398822 -31.566486) (xy 212.416234 -31.511052) (xy 212.441847 -31.458896)
			(xy 212.475067 -31.411225) (xy 212.515129 -31.369138) (xy 212.537802 -31.350966) (xy 212.541467 -31.348008)
			(xy 212.547733 -31.340978) (xy 212.550248 -31.336996) (xy 212.551264 -31.335218) (xy 212.552788 -31.332932)
			(xy 212.577364 -31.293481) (xy 212.632787 -31.21886) (xy 212.694916 -31.149722) (xy 212.76321 -31.086667)
			(xy 212.837078 -31.030243) (xy 212.915876 -30.98094) (xy 212.998922 -30.939185) (xy 213.085494 -30.905342)
			(xy 213.174841 -30.879704) (xy 213.266186 -30.862495) (xy 213.358736 -30.853862) (xy 213.405212 -30.85338)
			(xy 213.405466 -30.85338) (xy 213.447916 -30.85382) (xy 213.532509 -30.861037) (xy 213.616182 -30.875421)
			(xy 213.698328 -30.896869) (xy 213.778354 -30.925224) (xy 213.855678 -30.960282) (xy 213.92974 -31.001788)
			(xy 214.000005 -31.049442) (xy 214.065963 -31.102898) (xy 214.096854 -31.132018) (xy 214.103597 -31.137279)
			(xy 214.119563 -31.143383) (xy 214.128096 -31.143956) (xy 214.97671 -31.143956) (xy 214.98306 -31.143448)
			(xy 214.991553 -31.142069) (xy 215.006963 -31.134439) (xy 215.018971 -31.122129) (xy 215.022938 -31.114492)
			(xy 215.03259 -31.091124) (xy 215.033352 -31.083504) (xy 215.033606 -31.081218) (xy 215.033606 -31.080456)
			(xy 215.035889 -31.060694) (xy 215.044034 -31.021753) (xy 215.049862 -31.002732) (xy 215.051115 -30.998273)
			(xy 215.052134 -30.989069) (xy 215.051894 -30.984444) (xy 215.051894 -30.983936) (xy 215.051008 -30.96814)
			(xy 215.050118 -30.936511) (xy 215.050116 -30.92069) (xy 215.050551 -30.878103) (xy 215.057791 -30.793239)
			(xy 215.072244 -30.709301) (xy 215.093803 -30.626902) (xy 215.122312 -30.546642) (xy 215.139524 -30.507686)
			(xy 215.142705 -30.498553) (xy 215.142702 -30.479229) (xy 215.139524 -30.470094) (xy 215.122316 -30.431137)
			(xy 215.093823 -30.350874) (xy 215.072273 -30.268474) (xy 215.057822 -30.184538) (xy 215.050574 -30.099676)
			(xy 215.050116 -30.05709) (xy 215.05037 -30.030166) (xy 215.05037 -30.029912) (xy 215.050191 -30.020569)
			(xy 215.043941 -30.002977) (xy 215.038178 -29.995622) (xy 214.991696 -29.948124) (xy 214.985295 -29.942783)
			(xy 214.969999 -29.936182) (xy 214.961724 -29.93517) (xy 214.957406 -29.934916) (xy 214.880444 -29.934916)
			(xy 214.833698 -29.934348) (xy 214.740627 -29.925472) (xy 214.648812 -29.907841) (xy 214.559073 -29.881613)
			(xy 214.472214 -29.847024) (xy 214.430356 -29.826204) (xy 214.424929 -29.823621) (xy 214.41325 -29.820797)
			(xy 214.407242 -29.820616) (xy 214.139272 -29.820616) (xy 214.134381 -29.820751) (xy 214.124787 -29.822665)
			(xy 214.120222 -29.824426) (xy 214.094822 -29.834586) (xy 214.094568 -29.83484) (xy 214.093298 -29.83611)
			(xy 214.087964 -29.84119) (xy 214.053402 -29.872925) (xy 213.979281 -29.930473) (xy 213.900083 -29.980804)
			(xy 213.816508 -30.023475) (xy 213.729294 -30.058106) (xy 213.639213 -30.084393) (xy 213.547062 -30.102103)
			(xy 213.453654 -30.11108) (xy 213.406736 -30.1117) (xy 213.405212 -30.1117) (xy 213.358683 -30.11115)
			(xy 213.266033 -30.102456) (xy 213.174594 -30.085171) (xy 213.085163 -30.059444) (xy 212.998517 -30.0255)
			(xy 212.91541 -29.983633) (xy 212.836563 -29.934207) (xy 212.762662 -29.877653) (xy 212.694349 -29.814462)
			(xy 212.632219 -29.745182) (xy 212.576812 -29.670418) (xy 212.55228 -29.630878) (xy 212.54974 -29.627068)
			(xy 212.539326 -29.61513) (xy 212.537802 -29.61386) (xy 212.515183 -29.595672) (xy 212.47519 -29.553611)
			(xy 212.442028 -29.505979) (xy 212.416463 -29.453873) (xy 212.399084 -29.398497) (xy 212.390293 -29.341128)
			(xy 212.38972 -29.312108) (xy 212.38972 -29.311854) (xy 212.390187 -29.283354) (xy 212.398612 -29.226981)
			(xy 212.406484 -29.199586) (xy 212.408008 -29.192474) (xy 212.409786 -29.181552) (xy 212.409786 -29.177996)
			(xy 212.409532 -29.175202) (xy 212.409024 -29.160978) (xy 212.409024 -29.159962) (xy 212.408008 -29.114242)
			(xy 212.408441 -29.071655) (xy 212.415677 -28.986789) (xy 212.430127 -28.90285) (xy 212.451684 -28.82045)
			(xy 212.480192 -28.740189) (xy 212.497416 -28.701238) (xy 212.500608 -28.692105) (xy 212.500622 -28.672773)
			(xy 212.497416 -28.663646) (xy 212.480206 -28.62469) (xy 212.45171 -28.544426) (xy 212.430155 -28.462027)
			(xy 212.415699 -28.378091) (xy 212.408448 -28.293228) (xy 212.408008 -28.250642) (xy 212.409024 -28.204922)
			(xy 212.409024 -28.203906) (xy 212.409532 -28.189682) (xy 212.409786 -28.186888) (xy 212.409786 -28.183332)
			(xy 212.408008 -28.17241) (xy 212.406484 -28.165298) (xy 212.397848 -28.13177) (xy 212.39226 -28.097734)
			(xy 212.39099 -28.085542) (xy 212.389466 -28.05303) (xy 212.389982 -28.024323) (xy 212.398578 -27.967557)
			(xy 212.41558 -27.912719) (xy 212.440604 -27.861047) (xy 212.473087 -27.813706) (xy 212.512295 -27.771765)
			(xy 212.5345 -27.753564) (xy 212.540342 -27.747976) (xy 212.550248 -27.737054) (xy 212.552788 -27.732736)
			(xy 212.577375 -27.693296) (xy 212.632816 -27.618697) (xy 212.694957 -27.549578) (xy 212.763258 -27.48654)
			(xy 212.837126 -27.430128) (xy 212.915922 -27.380833) (xy 212.998962 -27.339081) (xy 213.085526 -27.305235)
			(xy 213.174863 -27.279588) (xy 213.266198 -27.262363) (xy 213.358739 -27.253709) (xy 213.405212 -27.253184)
			(xy 213.452225 -27.253741) (xy 213.545831 -27.262618) (xy 213.638186 -27.280265) (xy 213.728471 -27.306524)
			(xy 213.815884 -27.341162) (xy 213.89965 -27.383873) (xy 213.979025 -27.434276) (xy 214.053304 -27.491925)
			(xy 214.087964 -27.523694) (xy 214.093298 -27.528774) (xy 214.094568 -27.530044) (xy 214.094822 -27.530298)
			(xy 214.120222 -27.540458) (xy 214.124789 -27.542211) (xy 214.134382 -27.544126) (xy 214.139272 -27.544268)
			(xy 215.51392 -27.544268) (xy 215.552946 -27.544648) (xy 215.630759 -27.550754) (xy 215.669368 -27.55646)
			(xy 215.673432 -27.556968) (xy 215.971882 -27.556968) (xy 216.016275 -27.557491) (xy 216.104699 -27.565498)
			(xy 216.192051 -27.581394) (xy 216.277627 -27.605052) (xy 216.319354 -27.620214) (xy 216.34958 -27.632152)
			(xy 217.866214 -28.260802) (xy 217.875564 -28.264175) (xy 217.895423 -28.264295) (xy 217.904822 -28.261056)
			(xy 217.911256 -28.258222) (xy 217.922337 -28.249579) (xy 217.926666 -28.244038) (xy 217.926666 -28.243784)
			(xy 217.944775 -28.220026) (xy 217.987138 -28.177912) (xy 218.035545 -28.142913) (xy 218.088814 -28.115883)
			(xy 218.145644 -28.097483) (xy 218.204647 -28.088163) (xy 218.234514 -28.087574) (xy 218.271852 -28.089352)
			(xy 218.279218 -28.090114) (xy 218.306396 -28.0938) (xy 218.359382 -28.107962) (xy 218.409793 -28.129565)
			(xy 218.425455 -28.139136) (xy 234.597954 -28.139136) (xy 234.602025 -28.083514) (xy 234.614151 -28.029077)
			(xy 234.634074 -27.976986) (xy 234.66137 -27.928351) (xy 234.695456 -27.884208) (xy 234.735605 -27.845499)
			(xy 234.780963 -27.813048) (xy 234.830563 -27.787547) (xy 234.883347 -27.76954) (xy 234.93819 -27.75941)
			(xy 234.993924 -27.757373) (xy 235.049361 -27.763473) (xy 235.103318 -27.777579) (xy 235.154647 -27.799391)
			(xy 235.202253 -27.828445) (xy 235.245121 -27.86412) (xy 235.282338 -27.905657) (xy 235.313111 -27.95217)
			(xy 235.336783 -28.002667) (xy 235.352851 -28.056074) (xy 235.360971 -28.11125) (xy 235.36148 -28.139136)
			(xy 235.867954 -28.139136) (xy 235.872025 -28.083514) (xy 235.884151 -28.029077) (xy 235.904074 -27.976986)
			(xy 235.93137 -27.928351) (xy 235.965456 -27.884208) (xy 236.005605 -27.845499) (xy 236.050963 -27.813048)
			(xy 236.100563 -27.787547) (xy 236.153347 -27.76954) (xy 236.20819 -27.75941) (xy 236.263924 -27.757373)
			(xy 236.319361 -27.763473) (xy 236.373318 -27.777579) (xy 236.424647 -27.799391) (xy 236.472253 -27.828445)
			(xy 236.515121 -27.86412) (xy 236.552338 -27.905657) (xy 236.583111 -27.95217) (xy 236.606783 -28.002667)
			(xy 236.622851 -28.056074) (xy 236.630971 -28.11125) (xy 236.63148 -28.139136) (xy 236.630971 -28.167022)
			(xy 236.622851 -28.222198) (xy 236.606783 -28.275605) (xy 236.583111 -28.326102) (xy 236.552338 -28.372615)
			(xy 236.515121 -28.414152) (xy 236.472253 -28.449827) (xy 236.424647 -28.478881) (xy 236.373318 -28.500693)
			(xy 236.319361 -28.514799) (xy 236.263924 -28.520899) (xy 236.20819 -28.518862) (xy 236.153347 -28.508732)
			(xy 236.100563 -28.490725) (xy 236.050963 -28.465224) (xy 236.005605 -28.432773) (xy 235.965456 -28.394064)
			(xy 235.93137 -28.349921) (xy 235.904074 -28.301286) (xy 235.884151 -28.249195) (xy 235.872025 -28.194758)
			(xy 235.867954 -28.139136) (xy 235.36148 -28.139136) (xy 235.360971 -28.167022) (xy 235.352851 -28.222198)
			(xy 235.336783 -28.275605) (xy 235.313111 -28.326102) (xy 235.282338 -28.372615) (xy 235.245121 -28.414152)
			(xy 235.202253 -28.449827) (xy 235.154647 -28.478881) (xy 235.103318 -28.500693) (xy 235.049361 -28.514799)
			(xy 234.993924 -28.520899) (xy 234.93819 -28.518862) (xy 234.883347 -28.508732) (xy 234.830563 -28.490725)
			(xy 234.780963 -28.465224) (xy 234.735605 -28.432773) (xy 234.695456 -28.394064) (xy 234.66137 -28.349921)
			(xy 234.634074 -28.301286) (xy 234.614151 -28.249195) (xy 234.602025 -28.194758) (xy 234.597954 -28.139136)
			(xy 218.425455 -28.139136) (xy 218.456592 -28.158164) (xy 218.498814 -28.19317) (xy 218.535587 -28.233861)
			(xy 218.566155 -28.279398) (xy 218.589887 -28.328844) (xy 218.606294 -28.381178) (xy 218.615038 -28.435322)
			(xy 218.616022 -28.462732) (xy 218.616022 -28.469082) (xy 218.616022 -28.46959) (xy 218.616022 -28.473908)
			(xy 218.615298 -28.499604) (xy 218.60779 -28.55046) (xy 218.593518 -28.599846) (xy 218.572742 -28.646867)
			(xy 218.559634 -28.66898) (xy 218.558364 -28.670758) (xy 218.557602 -28.672282) (xy 218.55684 -28.673552)
			(xy 218.556332 -28.674314) (xy 218.551397 -28.682284) (xy 218.547239 -28.700549) (xy 218.548204 -28.709874)
			(xy 218.549474 -28.71851) (xy 218.55811 -28.734512) (xy 218.565222 -28.740862) (xy 218.578822 -28.752754)
			(xy 218.605245 -28.777398) (xy 218.618054 -28.790138) (xy 218.949214 -29.12237) (xy 240.806732 -29.12237)
			(xy 240.806732 -28.25877) (xy 240.807222 -28.228786) (xy 240.81505 -28.16933) (xy 240.830571 -28.111405)
			(xy 240.85352 -28.056001) (xy 240.883504 -28.004067) (xy 240.92001 -27.956491) (xy 240.962415 -27.914086)
			(xy 241.009991 -27.87758) (xy 241.061925 -27.847596) (xy 241.117329 -27.824647) (xy 241.175254 -27.809126)
			(xy 241.23471 -27.801298) (xy 241.294678 -27.801298) (xy 241.354134 -27.809126) (xy 241.412059 -27.824647)
			(xy 241.467463 -27.847596) (xy 241.519397 -27.87758) (xy 241.566973 -27.914086) (xy 241.609378 -27.956491)
			(xy 241.645884 -28.004067) (xy 241.675868 -28.056001) (xy 241.698817 -28.111405) (xy 241.714338 -28.16933)
			(xy 241.722166 -28.228786) (xy 241.722656 -28.25877) (xy 241.722656 -29.12237) (xy 241.722166 -29.152354)
			(xy 241.714338 -29.21181) (xy 241.698817 -29.269735) (xy 241.675868 -29.325139) (xy 241.645884 -29.377073)
			(xy 241.609378 -29.424649) (xy 241.566973 -29.467054) (xy 241.519397 -29.50356) (xy 241.467463 -29.533544)
			(xy 241.412059 -29.556493) (xy 241.354134 -29.572014) (xy 241.294678 -29.579842) (xy 241.23471 -29.579842)
			(xy 241.175254 -29.572014) (xy 241.117329 -29.556493) (xy 241.061925 -29.533544) (xy 241.009991 -29.50356)
			(xy 240.962415 -29.467054) (xy 240.92001 -29.424649) (xy 240.883504 -29.377073) (xy 240.85352 -29.325139)
			(xy 240.830571 -29.269735) (xy 240.81505 -29.21181) (xy 240.807222 -29.152354) (xy 240.806732 -29.12237)
			(xy 218.949214 -29.12237) (xy 219.010484 -29.183838) (xy 219.251276 -29.425138) (xy 219.258768 -29.431379)
			(xy 219.277022 -29.438189) (xy 219.296498 -29.437702) (xy 219.305632 -29.434282) (xy 219.305886 -29.434282)
			(xy 219.329835 -29.424359) (xy 219.379746 -29.410354) (xy 219.431097 -29.403253) (xy 219.457016 -29.402786)
			(xy 219.45981 -29.402786) (xy 219.487433 -29.403442) (xy 219.542059 -29.411739) (xy 219.594919 -29.427825)
			(xy 219.644907 -29.451364) (xy 219.690979 -29.481864) (xy 219.732172 -29.518688) (xy 219.767626 -29.561066)
			(xy 219.7966 -29.608113) (xy 219.818487 -29.658846) (xy 219.832832 -29.712204) (xy 219.836492 -29.73959)
			(xy 219.837508 -29.749242) (xy 219.839032 -29.784294) (xy 219.838614 -29.810476) (xy 219.831485 -29.862353)
			(xy 219.817332 -29.912768) (xy 219.807282 -29.936948) (xy 219.807282 -29.937202) (xy 219.804463 -29.944274)
			(xy 219.802651 -29.959383) (xy 219.803726 -29.96692) (xy 219.804996 -29.973778) (xy 219.812108 -29.986986)
			(xy 220.201017 -30.376876) (xy 233.088942 -30.376876) (xy 233.089499 -30.34796) (xy 233.098218 -30.29079)
			(xy 233.115467 -30.235592) (xy 233.140851 -30.183629) (xy 233.173789 -30.136095) (xy 233.213525 -30.094077)
			(xy 233.236008 -30.075886) (xy 233.244813 -30.068276) (xy 233.254997 -30.047378) (xy 233.255566 -30.035754)
			(xy 233.255566 -29.955998) (xy 233.255026 -29.944366) (xy 233.244839 -29.923456) (xy 233.236008 -29.915866)
			(xy 233.21351 -29.897692) (xy 233.173775 -29.855669) (xy 233.140838 -29.808131) (xy 233.115452 -29.756166)
			(xy 233.098199 -29.700965) (xy 233.089474 -29.643793) (xy 233.088942 -29.614876) (xy 233.089428 -29.587625)
			(xy 233.097184 -29.533677) (xy 233.112539 -29.481382) (xy 233.135181 -29.431805) (xy 233.164647 -29.385955)
			(xy 233.200338 -29.344764) (xy 233.241529 -29.309073) (xy 233.287379 -29.279607) (xy 233.336956 -29.256965)
			(xy 233.389251 -29.24161) (xy 233.443199 -29.233854) (xy 233.497701 -29.233854) (xy 233.551649 -29.24161)
			(xy 233.603944 -29.256965) (xy 233.653521 -29.279607) (xy 233.699371 -29.309073) (xy 233.740562 -29.344764)
			(xy 233.776253 -29.385955) (xy 233.805719 -29.431805) (xy 233.828361 -29.481382) (xy 233.843716 -29.533677)
			(xy 233.851472 -29.587625) (xy 233.851958 -29.614876) (xy 233.851438 -29.643793) (xy 233.842712 -29.700965)
			(xy 233.825455 -29.756164) (xy 233.800064 -29.808126) (xy 233.76712 -29.85566) (xy 233.727378 -29.897676)
			(xy 233.704892 -29.915866) (xy 233.696109 -29.923497) (xy 233.685912 -29.944379) (xy 233.685334 -29.955998)
			(xy 233.685334 -30.035754) (xy 233.685845 -30.04739) (xy 233.696053 -30.0683) (xy 233.704892 -30.075886)
			(xy 233.727367 -30.094087) (xy 233.767103 -30.136104) (xy 233.800043 -30.183637) (xy 233.825433 -30.235597)
			(xy 233.842691 -30.290792) (xy 233.851422 -30.347961) (xy 233.851958 -30.376876) (xy 236.129068 -30.376876)
			(xy 236.129615 -30.34796) (xy 236.138335 -30.290789) (xy 236.155585 -30.23559) (xy 236.180971 -30.183627)
			(xy 236.213911 -30.136093) (xy 236.25365 -30.094076) (xy 236.276134 -30.075886) (xy 236.284943 -30.068281)
			(xy 236.295124 -30.047378) (xy 236.295692 -30.035754) (xy 236.295692 -29.955998) (xy 236.295143 -29.944367)
			(xy 236.284961 -29.923457) (xy 236.276134 -29.915866) (xy 236.253641 -29.897686) (xy 236.213905 -29.855665)
			(xy 236.180966 -29.808128) (xy 236.155579 -29.756164) (xy 236.138325 -29.700964) (xy 236.1296 -29.643793)
			(xy 236.129068 -29.614876) (xy 236.129554 -29.587625) (xy 236.13731 -29.533677) (xy 236.152665 -29.481382)
			(xy 236.175307 -29.431805) (xy 236.204773 -29.385955) (xy 236.240464 -29.344764) (xy 236.281655 -29.309073)
			(xy 236.327505 -29.279607) (xy 236.377082 -29.256965) (xy 236.429377 -29.24161) (xy 236.483325 -29.233854)
			(xy 236.537827 -29.233854) (xy 236.591775 -29.24161) (xy 236.64407 -29.256965) (xy 236.693647 -29.279607)
			(xy 236.739497 -29.309073) (xy 236.780688 -29.344764) (xy 236.816379 -29.385955) (xy 236.845845 -29.431805)
			(xy 236.868487 -29.481382) (xy 236.883842 -29.533677) (xy 236.891598 -29.587625) (xy 236.892084 -29.614876)
			(xy 236.891554 -29.643793) (xy 236.882829 -29.700964) (xy 236.865573 -29.756162) (xy 236.840184 -29.808124)
			(xy 236.807242 -29.855658) (xy 236.767503 -29.897676) (xy 236.745018 -29.915866) (xy 236.736222 -29.923484)
			(xy 236.726036 -29.944377) (xy 236.72546 -29.955998) (xy 236.72546 -30.035754) (xy 236.725961 -30.047391)
			(xy 236.736175 -30.068302) (xy 236.745018 -30.075886) (xy 236.767499 -30.09408) (xy 236.807233 -30.1361)
			(xy 236.840172 -30.183634) (xy 236.865561 -30.235595) (xy 236.882818 -30.290792) (xy 236.891548 -30.34796)
			(xy 236.892084 -30.376876) (xy 236.891598 -30.404127) (xy 236.883842 -30.458075) (xy 236.868487 -30.51037)
			(xy 236.845845 -30.559947) (xy 236.816379 -30.605797) (xy 236.780688 -30.646988) (xy 236.739497 -30.682679)
			(xy 236.693647 -30.712145) (xy 236.64407 -30.734787) (xy 236.591775 -30.750142) (xy 236.537827 -30.757898)
			(xy 236.483325 -30.757898) (xy 236.429377 -30.750142) (xy 236.377082 -30.734787) (xy 236.327505 -30.712145)
			(xy 236.281655 -30.682679) (xy 236.240464 -30.646988) (xy 236.204773 -30.605797) (xy 236.175307 -30.559947)
			(xy 236.152665 -30.51037) (xy 236.13731 -30.458075) (xy 236.129554 -30.404127) (xy 236.129068 -30.376876)
			(xy 233.851958 -30.376876) (xy 233.851472 -30.404127) (xy 233.843716 -30.458075) (xy 233.828361 -30.51037)
			(xy 233.805719 -30.559947) (xy 233.776253 -30.605797) (xy 233.740562 -30.646988) (xy 233.699371 -30.682679)
			(xy 233.653521 -30.712145) (xy 233.603944 -30.734787) (xy 233.551649 -30.750142) (xy 233.497701 -30.757898)
			(xy 233.443199 -30.757898) (xy 233.389251 -30.750142) (xy 233.336956 -30.734787) (xy 233.287379 -30.712145)
			(xy 233.241529 -30.682679) (xy 233.200338 -30.646988) (xy 233.164647 -30.605797) (xy 233.135181 -30.559947)
			(xy 233.112539 -30.51037) (xy 233.097184 -30.458075) (xy 233.089428 -30.404127) (xy 233.088942 -30.376876)
			(xy 220.201017 -30.376876) (xy 220.617288 -30.794198) (xy 220.74519 -30.922468) (xy 238.952532 -30.922468)
			(xy 238.952532 -30.058868) (xy 238.953022 -30.028884) (xy 238.96085 -29.969428) (xy 238.976371 -29.911503)
			(xy 238.99932 -29.856099) (xy 239.029304 -29.804165) (xy 239.06581 -29.756589) (xy 239.108215 -29.714184)
			(xy 239.155791 -29.677678) (xy 239.207725 -29.647694) (xy 239.263129 -29.624745) (xy 239.321054 -29.609224)
			(xy 239.38051 -29.601396) (xy 239.440478 -29.601396) (xy 239.499934 -29.609224) (xy 239.557859 -29.624745)
			(xy 239.613263 -29.647694) (xy 239.665197 -29.677678) (xy 239.712773 -29.714184) (xy 239.755178 -29.756589)
			(xy 239.791684 -29.804165) (xy 239.821668 -29.856099) (xy 239.844617 -29.911503) (xy 239.860138 -29.969428)
			(xy 239.867966 -30.028884) (xy 239.868456 -30.058868) (xy 239.868456 -30.922468) (xy 239.867966 -30.952452)
			(xy 239.860138 -31.011908) (xy 239.844617 -31.069833) (xy 239.821668 -31.125237) (xy 239.791684 -31.177171)
			(xy 239.755178 -31.224747) (xy 239.712773 -31.267152) (xy 239.665197 -31.303658) (xy 239.613263 -31.333642)
			(xy 239.557859 -31.356591) (xy 239.499934 -31.372112) (xy 239.440478 -31.37994) (xy 239.38051 -31.37994)
			(xy 239.321054 -31.372112) (xy 239.263129 -31.356591) (xy 239.207725 -31.333642) (xy 239.155791 -31.303658)
			(xy 239.108215 -31.267152) (xy 239.06581 -31.224747) (xy 239.029304 -31.177171) (xy 238.99932 -31.125237)
			(xy 238.976371 -31.069833) (xy 238.96085 -31.011908) (xy 238.953022 -30.952452) (xy 238.952532 -30.922468)
			(xy 220.74519 -30.922468) (xy 220.794072 -30.97149) (xy 220.826995 -31.005316) (xy 220.887008 -31.078183)
			(xy 220.939873 -31.156391) (xy 220.962982 -31.19755) (xy 221.165392 -31.567882) (xy 233.198668 -31.567882)
			(xy 233.202739 -31.51226) (xy 233.214865 -31.457823) (xy 233.234788 -31.405732) (xy 233.262084 -31.357097)
			(xy 233.29617 -31.312954) (xy 233.336319 -31.274245) (xy 233.381677 -31.241794) (xy 233.431277 -31.216293)
			(xy 233.484061 -31.198286) (xy 233.538904 -31.188156) (xy 233.594638 -31.186119) (xy 233.650075 -31.192219)
			(xy 233.704032 -31.206325) (xy 233.755361 -31.228137) (xy 233.802967 -31.257191) (xy 233.845835 -31.292866)
			(xy 233.883052 -31.334403) (xy 233.913825 -31.380916) (xy 233.937497 -31.431413) (xy 233.953565 -31.48482)
			(xy 233.961685 -31.539996) (xy 233.962194 -31.567882) (xy 233.961685 -31.595768) (xy 233.953565 -31.650944)
			(xy 233.937497 -31.704351) (xy 233.930505 -31.719266) (xy 234.485432 -31.719266) (xy 234.489503 -31.663644)
			(xy 234.501629 -31.609207) (xy 234.521552 -31.557116) (xy 234.548848 -31.508481) (xy 234.582934 -31.464338)
			(xy 234.623083 -31.425629) (xy 234.668441 -31.393178) (xy 234.718041 -31.367677) (xy 234.770825 -31.34967)
			(xy 234.825668 -31.33954) (xy 234.881402 -31.337503) (xy 234.936839 -31.343603) (xy 234.990796 -31.357709)
			(xy 235.042125 -31.379521) (xy 235.089731 -31.408575) (xy 235.132599 -31.44425) (xy 235.169816 -31.485787)
			(xy 235.200589 -31.5323) (xy 235.224261 -31.582797) (xy 235.240329 -31.636204) (xy 235.244479 -31.664402)
			(xy 235.76102 -31.664402) (xy 235.765091 -31.60878) (xy 235.777217 -31.554343) (xy 235.79714 -31.502252)
			(xy 235.824436 -31.453617) (xy 235.858522 -31.409474) (xy 235.898671 -31.370765) (xy 235.944029 -31.338314)
			(xy 235.993629 -31.312813) (xy 236.046413 -31.294806) (xy 236.101256 -31.284676) (xy 236.15699 -31.282639)
			(xy 236.212427 -31.288739) (xy 236.266384 -31.302845) (xy 236.317713 -31.324657) (xy 236.365319 -31.353711)
			(xy 236.408187 -31.389386) (xy 236.445404 -31.430923) (xy 236.476177 -31.477436) (xy 236.499849 -31.527933)
			(xy 236.515917 -31.58134) (xy 236.524037 -31.636516) (xy 236.524546 -31.664402) (xy 236.524037 -31.692288)
			(xy 236.515917 -31.747464) (xy 236.506977 -31.777178) (xy 237.026194 -31.777178) (xy 237.030265 -31.721556)
			(xy 237.042391 -31.667119) (xy 237.062314 -31.615028) (xy 237.08961 -31.566393) (xy 237.123696 -31.52225)
			(xy 237.163845 -31.483541) (xy 237.209203 -31.45109) (xy 237.258803 -31.425589) (xy 237.311587 -31.407582)
			(xy 237.36643 -31.397452) (xy 237.422164 -31.395415) (xy 237.477601 -31.401515) (xy 237.531558 -31.415621)
			(xy 237.582887 -31.437433) (xy 237.630493 -31.466487) (xy 237.673361 -31.502162) (xy 237.710578 -31.543699)
			(xy 237.741351 -31.590212) (xy 237.765023 -31.640709) (xy 237.781091 -31.694116) (xy 237.789211 -31.749292)
			(xy 237.78972 -31.777178) (xy 237.789211 -31.805064) (xy 237.781091 -31.86024) (xy 237.765023 -31.913647)
			(xy 237.741351 -31.964144) (xy 237.710578 -32.010657) (xy 237.673361 -32.052194) (xy 237.630493 -32.087869)
			(xy 237.582887 -32.116923) (xy 237.531558 -32.138735) (xy 237.477601 -32.152841) (xy 237.422164 -32.158941)
			(xy 237.36643 -32.156904) (xy 237.311587 -32.146774) (xy 237.258803 -32.128767) (xy 237.209203 -32.103266)
			(xy 237.163845 -32.070815) (xy 237.123696 -32.032106) (xy 237.08961 -31.987963) (xy 237.062314 -31.939328)
			(xy 237.042391 -31.887237) (xy 237.030265 -31.8328) (xy 237.026194 -31.777178) (xy 236.506977 -31.777178)
			(xy 236.499849 -31.800871) (xy 236.476177 -31.851368) (xy 236.445404 -31.897881) (xy 236.408187 -31.939418)
			(xy 236.365319 -31.975093) (xy 236.317713 -32.004147) (xy 236.266384 -32.025959) (xy 236.212427 -32.040065)
			(xy 236.15699 -32.046165) (xy 236.101256 -32.044128) (xy 236.046413 -32.033998) (xy 235.993629 -32.015991)
			(xy 235.944029 -31.99049) (xy 235.898671 -31.958039) (xy 235.858522 -31.91933) (xy 235.824436 -31.875187)
			(xy 235.79714 -31.826552) (xy 235.777217 -31.774461) (xy 235.765091 -31.720024) (xy 235.76102 -31.664402)
			(xy 235.244479 -31.664402) (xy 235.248449 -31.69138) (xy 235.248958 -31.719266) (xy 235.248449 -31.747152)
			(xy 235.240329 -31.802328) (xy 235.224261 -31.855735) (xy 235.200589 -31.906232) (xy 235.169816 -31.952745)
			(xy 235.132599 -31.994282) (xy 235.089731 -32.029957) (xy 235.042125 -32.059011) (xy 234.990796 -32.080823)
			(xy 234.936839 -32.094929) (xy 234.881402 -32.101029) (xy 234.825668 -32.098992) (xy 234.770825 -32.088862)
			(xy 234.718041 -32.070855) (xy 234.668441 -32.045354) (xy 234.623083 -32.012903) (xy 234.582934 -31.974194)
			(xy 234.548848 -31.930051) (xy 234.521552 -31.881416) (xy 234.501629 -31.829325) (xy 234.489503 -31.774888)
			(xy 234.485432 -31.719266) (xy 233.930505 -31.719266) (xy 233.913825 -31.754848) (xy 233.883052 -31.801361)
			(xy 233.845835 -31.842898) (xy 233.802967 -31.878573) (xy 233.755361 -31.907627) (xy 233.704032 -31.929439)
			(xy 233.650075 -31.943545) (xy 233.594638 -31.949645) (xy 233.538904 -31.947608) (xy 233.484061 -31.937478)
			(xy 233.431277 -31.919471) (xy 233.381677 -31.89397) (xy 233.336319 -31.861519) (xy 233.29617 -31.82281)
			(xy 233.262084 -31.778667) (xy 233.234788 -31.730032) (xy 233.214865 -31.677941) (xy 233.202739 -31.623504)
			(xy 233.198668 -31.567882) (xy 221.165392 -31.567882) (xy 221.796363 -32.722312) (xy 240.806732 -32.722312)
			(xy 240.806732 -31.858712) (xy 240.807222 -31.828728) (xy 240.81505 -31.769272) (xy 240.830571 -31.711347)
			(xy 240.85352 -31.655943) (xy 240.883504 -31.604009) (xy 240.92001 -31.556433) (xy 240.962415 -31.514028)
			(xy 241.009991 -31.477522) (xy 241.061925 -31.447538) (xy 241.117329 -31.424589) (xy 241.175254 -31.409068)
			(xy 241.23471 -31.40124) (xy 241.294678 -31.40124) (xy 241.354134 -31.409068) (xy 241.412059 -31.424589)
			(xy 241.467463 -31.447538) (xy 241.519397 -31.477522) (xy 241.566973 -31.514028) (xy 241.609378 -31.556433)
			(xy 241.645884 -31.604009) (xy 241.675868 -31.655943) (xy 241.698817 -31.711347) (xy 241.714338 -31.769272)
			(xy 241.722166 -31.828728) (xy 241.722656 -31.858712) (xy 241.722656 -32.722312) (xy 241.722166 -32.752296)
			(xy 241.714338 -32.811752) (xy 241.698817 -32.869677) (xy 241.675868 -32.925081) (xy 241.645884 -32.977015)
			(xy 241.609378 -33.024591) (xy 241.566973 -33.066996) (xy 241.519397 -33.103502) (xy 241.467463 -33.133486)
			(xy 241.412059 -33.156435) (xy 241.354134 -33.171956) (xy 241.294678 -33.179784) (xy 241.23471 -33.179784)
			(xy 241.175254 -33.171956) (xy 241.117329 -33.156435) (xy 241.061925 -33.133486) (xy 241.009991 -33.103502)
			(xy 240.962415 -33.066996) (xy 240.92001 -33.024591) (xy 240.883504 -32.977015) (xy 240.85352 -32.925081)
			(xy 240.830571 -32.869677) (xy 240.81505 -32.811752) (xy 240.807222 -32.752296) (xy 240.806732 -32.722312)
			(xy 221.796363 -32.722312) (xy 222.780234 -34.52241) (xy 238.952532 -34.52241) (xy 238.952532 -33.65881)
			(xy 238.953022 -33.628826) (xy 238.96085 -33.56937) (xy 238.976371 -33.511445) (xy 238.99932 -33.456041)
			(xy 239.029304 -33.404107) (xy 239.06581 -33.356531) (xy 239.108215 -33.314126) (xy 239.155791 -33.27762)
			(xy 239.207725 -33.247636) (xy 239.263129 -33.224687) (xy 239.321054 -33.209166) (xy 239.38051 -33.201338)
			(xy 239.440478 -33.201338) (xy 239.499934 -33.209166) (xy 239.557859 -33.224687) (xy 239.613263 -33.247636)
			(xy 239.665197 -33.27762) (xy 239.712773 -33.314126) (xy 239.755178 -33.356531) (xy 239.791684 -33.404107)
			(xy 239.821668 -33.456041) (xy 239.844617 -33.511445) (xy 239.860138 -33.56937) (xy 239.867966 -33.628826)
			(xy 239.868456 -33.65881) (xy 239.868456 -34.52241) (xy 239.867966 -34.552394) (xy 239.860138 -34.61185)
			(xy 239.844617 -34.669775) (xy 239.821668 -34.725179) (xy 239.791684 -34.777113) (xy 239.755178 -34.824689)
			(xy 239.712773 -34.867094) (xy 239.665197 -34.9036) (xy 239.613263 -34.933584) (xy 239.557859 -34.956533)
			(xy 239.499934 -34.972054) (xy 239.440478 -34.979882) (xy 239.38051 -34.979882) (xy 239.321054 -34.972054)
			(xy 239.263129 -34.956533) (xy 239.207725 -34.933584) (xy 239.155791 -34.9036) (xy 239.108215 -34.867094)
			(xy 239.06581 -34.824689) (xy 239.029304 -34.777113) (xy 238.99932 -34.725179) (xy 238.976371 -34.669775)
			(xy 238.96085 -34.61185) (xy 238.953022 -34.552394) (xy 238.952532 -34.52241) (xy 222.780234 -34.52241)
			(xy 223.186027 -35.264852) (xy 236.102396 -35.264852) (xy 236.106467 -35.20923) (xy 236.118593 -35.154793)
			(xy 236.138516 -35.102702) (xy 236.165812 -35.054067) (xy 236.199898 -35.009924) (xy 236.240047 -34.971215)
			(xy 236.285405 -34.938764) (xy 236.335005 -34.913263) (xy 236.387789 -34.895256) (xy 236.442632 -34.885126)
			(xy 236.498366 -34.883089) (xy 236.553803 -34.889189) (xy 236.60776 -34.903295) (xy 236.659089 -34.925107)
			(xy 236.706695 -34.954161) (xy 236.749563 -34.989836) (xy 236.78678 -35.031373) (xy 236.817553 -35.077886)
			(xy 236.841225 -35.128383) (xy 236.857293 -35.18179) (xy 236.865413 -35.236966) (xy 236.865922 -35.264852)
			(xy 236.865413 -35.292738) (xy 236.857293 -35.347914) (xy 236.841225 -35.401321) (xy 236.817553 -35.451818)
			(xy 236.78678 -35.498331) (xy 236.749563 -35.539868) (xy 236.706695 -35.575543) (xy 236.659089 -35.604597)
			(xy 236.60776 -35.626409) (xy 236.553803 -35.640515) (xy 236.498366 -35.646615) (xy 236.442632 -35.644578)
			(xy 236.387789 -35.634448) (xy 236.335005 -35.616441) (xy 236.285405 -35.59094) (xy 236.240047 -35.558489)
			(xy 236.199898 -35.51978) (xy 236.165812 -35.475637) (xy 236.138516 -35.427002) (xy 236.118593 -35.374911)
			(xy 236.106467 -35.320474) (xy 236.102396 -35.264852) (xy 223.186027 -35.264852) (xy 223.520462 -35.876738)
			(xy 224.917252 -35.876738) (xy 224.921323 -35.821116) (xy 224.933449 -35.766679) (xy 224.953372 -35.714588)
			(xy 224.980668 -35.665953) (xy 225.014754 -35.62181) (xy 225.054903 -35.583101) (xy 225.100261 -35.55065)
			(xy 225.149861 -35.525149) (xy 225.202645 -35.507142) (xy 225.257488 -35.497012) (xy 225.313222 -35.494975)
			(xy 225.368659 -35.501075) (xy 225.422616 -35.515181) (xy 225.473945 -35.536993) (xy 225.521551 -35.566047)
			(xy 225.564419 -35.601722) (xy 225.601636 -35.643259) (xy 225.632409 -35.689772) (xy 225.656081 -35.740269)
			(xy 225.672149 -35.793676) (xy 225.680269 -35.848852) (xy 225.680778 -35.876738) (xy 228.988872 -35.876738)
			(xy 228.992943 -35.821116) (xy 229.005069 -35.766679) (xy 229.024992 -35.714588) (xy 229.052288 -35.665953)
			(xy 229.086374 -35.62181) (xy 229.126523 -35.583101) (xy 229.171881 -35.55065) (xy 229.221481 -35.525149)
			(xy 229.274265 -35.507142) (xy 229.329108 -35.497012) (xy 229.384842 -35.494975) (xy 229.440279 -35.501075)
			(xy 229.494236 -35.515181) (xy 229.545565 -35.536993) (xy 229.593171 -35.566047) (xy 229.636039 -35.601722)
			(xy 229.673256 -35.643259) (xy 229.704029 -35.689772) (xy 229.727701 -35.740269) (xy 229.743769 -35.793676)
			(xy 229.751889 -35.848852) (xy 229.752398 -35.876738) (xy 229.751889 -35.904624) (xy 229.743769 -35.9598)
			(xy 229.727701 -36.013207) (xy 229.704029 -36.063704) (xy 229.673256 -36.110217) (xy 229.636039 -36.151754)
			(xy 229.593171 -36.187429) (xy 229.545565 -36.216483) (xy 229.494236 -36.238295) (xy 229.440279 -36.252401)
			(xy 229.384842 -36.258501) (xy 229.329108 -36.256464) (xy 229.274265 -36.246334) (xy 229.221481 -36.228327)
			(xy 229.171881 -36.202826) (xy 229.126523 -36.170375) (xy 229.086374 -36.131666) (xy 229.052288 -36.087523)
			(xy 229.024992 -36.038888) (xy 229.005069 -35.986797) (xy 228.992943 -35.93236) (xy 228.988872 -35.876738)
			(xy 225.680778 -35.876738) (xy 225.680269 -35.904624) (xy 225.672149 -35.9598) (xy 225.656081 -36.013207)
			(xy 225.632409 -36.063704) (xy 225.601636 -36.110217) (xy 225.564419 -36.151754) (xy 225.521551 -36.187429)
			(xy 225.473945 -36.216483) (xy 225.422616 -36.238295) (xy 225.368659 -36.252401) (xy 225.313222 -36.258501)
			(xy 225.257488 -36.256464) (xy 225.202645 -36.246334) (xy 225.149861 -36.228327) (xy 225.100261 -36.202826)
			(xy 225.054903 -36.170375) (xy 225.014754 -36.131666) (xy 224.980668 -36.087523) (xy 224.953372 -36.038888)
			(xy 224.933449 -35.986797) (xy 224.921323 -35.93236) (xy 224.917252 -35.876738) (xy 223.520462 -35.876738)
			(xy 223.866559 -36.50996) (xy 226.81387 -36.50996) (xy 226.817941 -36.454338) (xy 226.830067 -36.399901)
			(xy 226.84999 -36.34781) (xy 226.877286 -36.299175) (xy 226.911372 -36.255032) (xy 226.951521 -36.216323)
			(xy 226.996879 -36.183872) (xy 227.046479 -36.158371) (xy 227.099263 -36.140364) (xy 227.154106 -36.130234)
			(xy 227.20984 -36.128197) (xy 227.265277 -36.134297) (xy 227.319234 -36.148403) (xy 227.370563 -36.170215)
			(xy 227.418169 -36.199269) (xy 227.461037 -36.234944) (xy 227.498254 -36.276481) (xy 227.529027 -36.322994)
			(xy 227.552699 -36.373491) (xy 227.568767 -36.426898) (xy 227.572692 -36.453572) (xy 230.12857 -36.453572)
			(xy 230.132641 -36.39795) (xy 230.144767 -36.343513) (xy 230.16469 -36.291422) (xy 230.191986 -36.242787)
			(xy 230.226072 -36.198644) (xy 230.266221 -36.159935) (xy 230.311579 -36.127484) (xy 230.361179 -36.101983)
			(xy 230.413963 -36.083976) (xy 230.468806 -36.073846) (xy 230.52454 -36.071809) (xy 230.579977 -36.077909)
			(xy 230.633934 -36.092015) (xy 230.685263 -36.113827) (xy 230.732869 -36.142881) (xy 230.775737 -36.178556)
			(xy 230.812954 -36.220093) (xy 230.843727 -36.266606) (xy 230.853263 -36.286948) (xy 237.400336 -36.286948)
			(xy 237.404407 -36.231326) (xy 237.416533 -36.176889) (xy 237.436456 -36.124798) (xy 237.463752 -36.076163)
			(xy 237.497838 -36.03202) (xy 237.537987 -35.993311) (xy 237.583345 -35.96086) (xy 237.632945 -35.935359)
			(xy 237.685729 -35.917352) (xy 237.740572 -35.907222) (xy 237.796306 -35.905185) (xy 237.851743 -35.911285)
			(xy 237.9057 -35.925391) (xy 237.957029 -35.947203) (xy 238.004635 -35.976257) (xy 238.047503 -36.011932)
			(xy 238.08472 -36.053469) (xy 238.115493 -36.099982) (xy 238.139165 -36.150479) (xy 238.155233 -36.203886)
			(xy 238.163353 -36.259062) (xy 238.163862 -36.286948) (xy 238.163353 -36.314834) (xy 238.155233 -36.37001)
			(xy 238.139165 -36.423417) (xy 238.115493 -36.473914) (xy 238.087948 -36.515548) (xy 239.21415 -36.515548)
			(xy 239.218221 -36.459926) (xy 239.230347 -36.405489) (xy 239.25027 -36.353398) (xy 239.277566 -36.304763)
			(xy 239.311652 -36.26062) (xy 239.351801 -36.221911) (xy 239.397159 -36.18946) (xy 239.446759 -36.163959)
			(xy 239.499543 -36.145952) (xy 239.554386 -36.135822) (xy 239.61012 -36.133785) (xy 239.665557 -36.139885)
			(xy 239.719514 -36.153991) (xy 239.770843 -36.175803) (xy 239.818449 -36.204857) (xy 239.861317 -36.240532)
			(xy 239.898534 -36.282069) (xy 239.929307 -36.328582) (xy 239.952979 -36.379079) (xy 239.969047 -36.432486)
			(xy 239.977167 -36.487662) (xy 239.977676 -36.515548) (xy 239.977167 -36.543434) (xy 239.969047 -36.59861)
			(xy 239.96859 -36.60013) (xy 244.198655 -36.60013) (xy 244.202659 -36.512245) (xy 244.214639 -36.425088)
			(xy 244.234494 -36.339381) (xy 244.262061 -36.255836) (xy 244.297111 -36.175143) (xy 244.339353 -36.097971)
			(xy 244.388438 -36.024961) (xy 244.443959 -35.956717) (xy 244.505456 -35.893804) (xy 244.572418 -35.836744)
			(xy 244.644292 -35.78601) (xy 244.720482 -35.742022) (xy 244.800356 -35.705144) (xy 244.883253 -35.675683)
			(xy 244.968485 -35.653881) (xy 245.055347 -35.639921) (xy 245.143118 -35.633917) (xy 245.231072 -35.63592)
			(xy 245.318479 -35.645912) (xy 245.404615 -35.663812) (xy 245.488767 -35.68947) (xy 245.570237 -35.722674)
			(xy 245.64835 -35.763148) (xy 245.722458 -35.810559) (xy 245.791949 -35.864512) (xy 245.80504 -35.876738)
			(xy 250.9172 -35.876738) (xy 250.921271 -35.821116) (xy 250.933397 -35.766679) (xy 250.95332 -35.714588)
			(xy 250.980616 -35.665953) (xy 251.014702 -35.62181) (xy 251.054851 -35.583101) (xy 251.100209 -35.55065)
			(xy 251.149809 -35.525149) (xy 251.202593 -35.507142) (xy 251.257436 -35.497012) (xy 251.31317 -35.494975)
			(xy 251.368607 -35.501075) (xy 251.422564 -35.515181) (xy 251.473893 -35.536993) (xy 251.521499 -35.566047)
			(xy 251.564367 -35.601722) (xy 251.601584 -35.643259) (xy 251.632357 -35.689772) (xy 251.656029 -35.740269)
			(xy 251.672097 -35.793676) (xy 251.680217 -35.848852) (xy 251.680726 -35.876738) (xy 251.680217 -35.904624)
			(xy 251.672097 -35.9598) (xy 251.656029 -36.013207) (xy 251.632357 -36.063704) (xy 251.601584 -36.110217)
			(xy 251.564367 -36.151754) (xy 251.521499 -36.187429) (xy 251.473893 -36.216483) (xy 251.422564 -36.238295)
			(xy 251.368607 -36.252401) (xy 251.31317 -36.258501) (xy 251.257436 -36.256464) (xy 251.202593 -36.246334)
			(xy 251.149809 -36.228327) (xy 251.100209 -36.202826) (xy 251.054851 -36.170375) (xy 251.014702 -36.131666)
			(xy 250.980616 -36.087523) (xy 250.95332 -36.038888) (xy 250.933397 -35.986797) (xy 250.921271 -35.93236)
			(xy 250.9172 -35.876738) (xy 245.80504 -35.876738) (xy 245.856245 -35.92456) (xy 245.914814 -35.990207)
			(xy 245.967171 -36.060907) (xy 246.012883 -36.136076) (xy 246.051569 -36.21509) (xy 246.08291 -36.297295)
			(xy 246.106645 -36.382009) (xy 246.122579 -36.46853) (xy 246.126362 -36.50996) (xy 252.813818 -36.50996)
			(xy 252.817889 -36.454338) (xy 252.830015 -36.399901) (xy 252.849938 -36.34781) (xy 252.877234 -36.299175)
			(xy 252.91132 -36.255032) (xy 252.951469 -36.216323) (xy 252.996827 -36.183872) (xy 253.046427 -36.158371)
			(xy 253.099211 -36.140364) (xy 253.154054 -36.130234) (xy 253.209788 -36.128197) (xy 253.265225 -36.134297)
			(xy 253.319182 -36.148403) (xy 253.370511 -36.170215) (xy 253.418117 -36.199269) (xy 253.460985 -36.234944)
			(xy 253.498202 -36.276481) (xy 253.528975 -36.322994) (xy 253.552647 -36.373491) (xy 253.568715 -36.426898)
			(xy 253.576835 -36.482074) (xy 253.577344 -36.50996) (xy 253.576835 -36.537846) (xy 253.568715 -36.593022)
			(xy 253.552647 -36.646429) (xy 253.528975 -36.696926) (xy 253.498202 -36.743439) (xy 253.460985 -36.784976)
			(xy 253.418117 -36.820651) (xy 253.370511 -36.849705) (xy 253.319182 -36.871517) (xy 253.265225 -36.885623)
			(xy 253.209788 -36.891723) (xy 253.154054 -36.889686) (xy 253.099211 -36.879556) (xy 253.046427 -36.861549)
			(xy 252.996827 -36.836048) (xy 252.951469 -36.803597) (xy 252.91132 -36.764888) (xy 252.877234 -36.720745)
			(xy 252.849938 -36.67211) (xy 252.830015 -36.620019) (xy 252.817889 -36.565582) (xy 252.813818 -36.50996)
			(xy 246.126362 -36.50996) (xy 246.130579 -36.556142) (xy 246.13108 -36.60013) (xy 246.130579 -36.644118)
			(xy 246.122579 -36.73173) (xy 246.106645 -36.818251) (xy 246.08291 -36.902965) (xy 246.051569 -36.98517)
			(xy 246.012883 -37.064184) (xy 245.967171 -37.139353) (xy 245.914814 -37.210053) (xy 245.856245 -37.2757)
			(xy 245.791949 -37.335748) (xy 245.722458 -37.389701) (xy 245.64835 -37.437112) (xy 245.574919 -37.47516)
			(xy 249.959112 -37.47516) (xy 249.963183 -37.419538) (xy 249.975309 -37.365101) (xy 249.995232 -37.31301)
			(xy 250.022528 -37.264375) (xy 250.056614 -37.220232) (xy 250.096763 -37.181523) (xy 250.142121 -37.149072)
			(xy 250.191721 -37.123571) (xy 250.244505 -37.105564) (xy 250.299348 -37.095434) (xy 250.355082 -37.093397)
			(xy 250.410519 -37.099497) (xy 250.464476 -37.113603) (xy 250.515805 -37.135415) (xy 250.563411 -37.164469)
			(xy 250.606279 -37.200144) (xy 250.643496 -37.241681) (xy 250.674269 -37.288194) (xy 250.697941 -37.338691)
			(xy 250.714009 -37.392098) (xy 250.722129 -37.447274) (xy 250.722638 -37.47516) (xy 250.722129 -37.503046)
			(xy 250.714009 -37.558222) (xy 250.697941 -37.611629) (xy 250.674269 -37.662126) (xy 250.674116 -37.662358)
			(xy 252.148338 -37.662358) (xy 252.152409 -37.606736) (xy 252.164535 -37.552299) (xy 252.184458 -37.500208)
			(xy 252.211754 -37.451573) (xy 252.24584 -37.40743) (xy 252.285989 -37.368721) (xy 252.331347 -37.33627)
			(xy 252.380947 -37.310769) (xy 252.433731 -37.292762) (xy 252.488574 -37.282632) (xy 252.544308 -37.280595)
			(xy 252.599745 -37.286695) (xy 252.653702 -37.300801) (xy 252.705031 -37.322613) (xy 252.752637 -37.351667)
			(xy 252.795505 -37.387342) (xy 252.832722 -37.428879) (xy 252.863495 -37.475392) (xy 252.887167 -37.525889)
			(xy 252.903235 -37.579296) (xy 252.911355 -37.634472) (xy 252.911864 -37.662358) (xy 252.911355 -37.690244)
			(xy 252.903235 -37.74542) (xy 252.887167 -37.798827) (xy 252.863495 -37.849324) (xy 252.832722 -37.895837)
			(xy 252.795505 -37.937374) (xy 252.752637 -37.973049) (xy 252.705031 -38.002103) (xy 252.653702 -38.023915)
			(xy 252.599745 -38.038021) (xy 252.544308 -38.044121) (xy 252.488574 -38.042084) (xy 252.433731 -38.031954)
			(xy 252.380947 -38.013947) (xy 252.331347 -37.988446) (xy 252.285989 -37.955995) (xy 252.24584 -37.917286)
			(xy 252.211754 -37.873143) (xy 252.184458 -37.824508) (xy 252.164535 -37.772417) (xy 252.152409 -37.71798)
			(xy 252.148338 -37.662358) (xy 250.674116 -37.662358) (xy 250.643496 -37.708639) (xy 250.606279 -37.750176)
			(xy 250.563411 -37.785851) (xy 250.515805 -37.814905) (xy 250.464476 -37.836717) (xy 250.410519 -37.850823)
			(xy 250.355082 -37.856923) (xy 250.299348 -37.854886) (xy 250.244505 -37.844756) (xy 250.191721 -37.826749)
			(xy 250.142121 -37.801248) (xy 250.096763 -37.768797) (xy 250.056614 -37.730088) (xy 250.022528 -37.685945)
			(xy 249.995232 -37.63731) (xy 249.975309 -37.585219) (xy 249.963183 -37.530782) (xy 249.959112 -37.47516)
			(xy 245.574919 -37.47516) (xy 245.570237 -37.477586) (xy 245.488767 -37.51079) (xy 245.404615 -37.536448)
			(xy 245.318479 -37.554348) (xy 245.231072 -37.56434) (xy 245.143118 -37.566343) (xy 245.055347 -37.560339)
			(xy 244.968485 -37.546379) (xy 244.883253 -37.524577) (xy 244.800356 -37.495116) (xy 244.720482 -37.458238)
			(xy 244.644292 -37.41425) (xy 244.572418 -37.363516) (xy 244.505456 -37.306456) (xy 244.443959 -37.243543)
			(xy 244.388438 -37.175299) (xy 244.339353 -37.102289) (xy 244.297111 -37.025117) (xy 244.262061 -36.944424)
			(xy 244.234494 -36.860879) (xy 244.214639 -36.775172) (xy 244.202659 -36.688015) (xy 244.198655 -36.60013)
			(xy 239.96859 -36.60013) (xy 239.952979 -36.652017) (xy 239.929307 -36.702514) (xy 239.898534 -36.749027)
			(xy 239.861317 -36.790564) (xy 239.818449 -36.826239) (xy 239.770843 -36.855293) (xy 239.719514 -36.877105)
			(xy 239.665557 -36.891211) (xy 239.61012 -36.897311) (xy 239.554386 -36.895274) (xy 239.499543 -36.885144)
			(xy 239.446759 -36.867137) (xy 239.397159 -36.841636) (xy 239.351801 -36.809185) (xy 239.311652 -36.770476)
			(xy 239.277566 -36.726333) (xy 239.25027 -36.677698) (xy 239.230347 -36.625607) (xy 239.218221 -36.57117)
			(xy 239.21415 -36.515548) (xy 238.087948 -36.515548) (xy 238.08472 -36.520427) (xy 238.047503 -36.561964)
			(xy 238.004635 -36.597639) (xy 237.957029 -36.626693) (xy 237.9057 -36.648505) (xy 237.851743 -36.662611)
			(xy 237.796306 -36.668711) (xy 237.740572 -36.666674) (xy 237.685729 -36.656544) (xy 237.632945 -36.638537)
			(xy 237.583345 -36.613036) (xy 237.537987 -36.580585) (xy 237.497838 -36.541876) (xy 237.463752 -36.497733)
			(xy 237.436456 -36.449098) (xy 237.416533 -36.397007) (xy 237.404407 -36.34257) (xy 237.400336 -36.286948)
			(xy 230.853263 -36.286948) (xy 230.867399 -36.317103) (xy 230.883467 -36.37051) (xy 230.891587 -36.425686)
			(xy 230.892096 -36.453572) (xy 230.891587 -36.481458) (xy 230.883467 -36.536634) (xy 230.867399 -36.590041)
			(xy 230.843727 -36.640538) (xy 230.812954 -36.687051) (xy 230.775737 -36.728588) (xy 230.732869 -36.764263)
			(xy 230.685263 -36.793317) (xy 230.633934 -36.815129) (xy 230.579977 -36.829235) (xy 230.52454 -36.835335)
			(xy 230.468806 -36.833298) (xy 230.413963 -36.823168) (xy 230.361179 -36.805161) (xy 230.311579 -36.77966)
			(xy 230.266221 -36.747209) (xy 230.226072 -36.7085) (xy 230.191986 -36.664357) (xy 230.16469 -36.615722)
			(xy 230.144767 -36.563631) (xy 230.132641 -36.509194) (xy 230.12857 -36.453572) (xy 227.572692 -36.453572)
			(xy 227.576887 -36.482074) (xy 227.577396 -36.50996) (xy 227.576887 -36.537846) (xy 227.568767 -36.593022)
			(xy 227.552699 -36.646429) (xy 227.529027 -36.696926) (xy 227.498254 -36.743439) (xy 227.461037 -36.784976)
			(xy 227.418169 -36.820651) (xy 227.370563 -36.849705) (xy 227.319234 -36.871517) (xy 227.265277 -36.885623)
			(xy 227.20984 -36.891723) (xy 227.154106 -36.889686) (xy 227.099263 -36.879556) (xy 227.046479 -36.861549)
			(xy 226.996879 -36.836048) (xy 226.951521 -36.803597) (xy 226.911372 -36.764888) (xy 226.877286 -36.720745)
			(xy 226.84999 -36.67211) (xy 226.830067 -36.620019) (xy 226.817941 -36.565582) (xy 226.81387 -36.50996)
			(xy 223.866559 -36.50996) (xy 224.179892 -37.083238) (xy 224.184329 -37.090663) (xy 224.197186 -37.102216)
			(xy 224.205038 -37.105844) (xy 224.213166 -37.109146) (xy 224.22993 -37.110162) (xy 224.238312 -37.107876)
			(xy 224.263515 -37.10126) (xy 224.31513 -37.09412) (xy 224.341182 -37.093652) (xy 224.368435 -37.094137)
			(xy 224.422387 -37.101891) (xy 224.474686 -37.117244) (xy 224.524268 -37.139883) (xy 224.570124 -37.169349)
			(xy 224.611319 -37.20504) (xy 224.647017 -37.24623) (xy 224.676489 -37.292081) (xy 224.699136 -37.341659)
			(xy 224.714497 -37.393956) (xy 224.722259 -37.447907) (xy 224.72269 -37.47516) (xy 224.722944 -37.47516)
			(xy 224.722504 -37.501204) (xy 224.715423 -37.552809) (xy 224.701388 -37.60297) (xy 224.680659 -37.650756)
			(xy 224.673613 -37.662358) (xy 226.14839 -37.662358) (xy 226.152461 -37.606736) (xy 226.164587 -37.552299)
			(xy 226.18451 -37.500208) (xy 226.211806 -37.451573) (xy 226.245892 -37.40743) (xy 226.286041 -37.368721)
			(xy 226.331399 -37.33627) (xy 226.380999 -37.310769) (xy 226.433783 -37.292762) (xy 226.488626 -37.282632)
			(xy 226.54436 -37.280595) (xy 226.599797 -37.286695) (xy 226.653754 -37.300801) (xy 226.705083 -37.322613)
			(xy 226.752689 -37.351667) (xy 226.795557 -37.387342) (xy 226.832774 -37.428879) (xy 226.863547 -37.475392)
			(xy 226.887219 -37.525889) (xy 226.903287 -37.579296) (xy 226.911407 -37.634472) (xy 226.911916 -37.662358)
			(xy 226.911407 -37.690244) (xy 226.903287 -37.74542) (xy 226.894653 -37.774118) (xy 237.66475 -37.774118)
			(xy 237.668821 -37.718496) (xy 237.680947 -37.664059) (xy 237.70087 -37.611968) (xy 237.728166 -37.563333)
			(xy 237.762252 -37.51919) (xy 237.802401 -37.480481) (xy 237.847759 -37.44803) (xy 237.897359 -37.422529)
			(xy 237.950143 -37.404522) (xy 238.004986 -37.394392) (xy 238.06072 -37.392355) (xy 238.116157 -37.398455)
			(xy 238.170114 -37.412561) (xy 238.221443 -37.434373) (xy 238.269049 -37.463427) (xy 238.311917 -37.499102)
			(xy 238.349134 -37.540639) (xy 238.379907 -37.587152) (xy 238.403579 -37.637649) (xy 238.419647 -37.691056)
			(xy 238.427767 -37.746232) (xy 238.428276 -37.774118) (xy 238.427767 -37.802004) (xy 238.419647 -37.85718)
			(xy 238.403579 -37.910587) (xy 238.379907 -37.961084) (xy 238.349134 -38.007597) (xy 238.311917 -38.049134)
			(xy 238.269049 -38.084809) (xy 238.221443 -38.113863) (xy 238.170114 -38.135675) (xy 238.116157 -38.149781)
			(xy 238.06072 -38.155881) (xy 238.004986 -38.153844) (xy 237.950143 -38.143714) (xy 237.897359 -38.125707)
			(xy 237.847759 -38.100206) (xy 237.802401 -38.067755) (xy 237.762252 -38.029046) (xy 237.728166 -37.984903)
			(xy 237.70087 -37.936268) (xy 237.680947 -37.884177) (xy 237.668821 -37.82974) (xy 237.66475 -37.774118)
			(xy 226.894653 -37.774118) (xy 226.887219 -37.798827) (xy 226.863547 -37.849324) (xy 226.832774 -37.895837)
			(xy 226.795557 -37.937374) (xy 226.752689 -37.973049) (xy 226.705083 -38.002103) (xy 226.653754 -38.023915)
			(xy 226.599797 -38.038021) (xy 226.54436 -38.044121) (xy 226.488626 -38.042084) (xy 226.433783 -38.031954)
			(xy 226.380999 -38.013947) (xy 226.331399 -37.988446) (xy 226.286041 -37.955995) (xy 226.245892 -37.917286)
			(xy 226.211806 -37.873143) (xy 226.18451 -37.824508) (xy 226.164587 -37.772417) (xy 226.152461 -37.71798)
			(xy 226.14839 -37.662358) (xy 224.673613 -37.662358) (xy 224.653622 -37.695277) (xy 224.620779 -37.735707)
			(xy 224.60204 -37.753798) (xy 224.594674 -37.760656) (xy 224.57791 -37.798248) (xy 224.578104 -37.804541)
			(xy 224.581198 -37.816742) (xy 224.584006 -37.822378) (xy 224.58934 -37.832284) (xy 224.594166 -37.84092)
			(xy 225.079839 -38.729948) (xy 229.90102 -38.729948) (xy 229.90102 -38.675452) (xy 229.908775 -38.621512)
			(xy 229.924128 -38.569224) (xy 229.946766 -38.519653) (xy 229.976228 -38.473808) (xy 230.011914 -38.432623)
			(xy 230.053098 -38.396935) (xy 230.098942 -38.367472) (xy 230.148512 -38.344832) (xy 230.2008 -38.329478)
			(xy 230.25474 -38.321721) (xy 230.281988 -38.321234) (xy 230.310293 -38.321717) (xy 230.366282 -38.330068)
			(xy 230.420422 -38.346604) (xy 230.471523 -38.37096) (xy 230.518463 -38.402602) (xy 230.56021 -38.440834)
			(xy 230.595847 -38.484818) (xy 230.610664 -38.50894) (xy 230.618212 -38.521009) (xy 230.638841 -38.540613)
			(xy 230.664084 -38.553754) (xy 230.691975 -38.55941) (xy 230.720342 -38.557139) (xy 230.746979 -38.547119)
			(xy 230.769809 -38.53013) (xy 230.778812 -38.5191) (xy 230.796997 -38.496222) (xy 230.83916 -38.455758)
			(xy 230.886996 -38.422191) (xy 230.939388 -38.396304) (xy 230.995113 -38.378703) (xy 231.052869 -38.369797)
			(xy 231.082088 -38.36924) (xy 231.109345 -38.369606) (xy 231.163304 -38.377363) (xy 231.21561 -38.39272)
			(xy 231.265198 -38.415364) (xy 231.311058 -38.444836) (xy 231.352258 -38.480534) (xy 231.387957 -38.521732)
			(xy 231.41743 -38.567592) (xy 231.440076 -38.617179) (xy 231.455435 -38.669484) (xy 231.463193 -38.723443)
			(xy 231.463193 -38.777957) (xy 231.455435 -38.831916) (xy 231.440076 -38.884221) (xy 231.41743 -38.933808)
			(xy 231.387957 -38.979668) (xy 231.352258 -39.020866) (xy 231.311058 -39.056564) (xy 231.265198 -39.086036)
			(xy 231.21561 -39.10868) (xy 231.163304 -39.124037) (xy 231.109345 -39.131794) (xy 231.082088 -39.132256)
			(xy 231.053785 -39.131718) (xy 230.997798 -39.123377) (xy 230.943659 -39.106852) (xy 230.892558 -39.082505)
			(xy 230.845617 -39.050872) (xy 230.803869 -39.012646) (xy 230.76823 -38.968669) (xy 230.753412 -38.94455)
			(xy 230.745765 -38.93255) (xy 230.725156 -38.912952) (xy 230.699935 -38.89981) (xy 230.672064 -38.894147)
			(xy 230.643714 -38.896404) (xy 230.617091 -38.906405) (xy 230.594266 -38.923372) (xy 230.585264 -38.93439)
			(xy 230.567091 -38.957277) (xy 230.524925 -38.997741) (xy 230.477087 -39.031307) (xy 230.424693 -39.057193)
			(xy 230.368966 -39.074792) (xy 230.311208 -39.083695) (xy 230.281988 -39.08425) (xy 230.25474 -39.083679)
			(xy 230.2008 -39.075922) (xy 230.148512 -39.060568) (xy 230.098942 -39.037928) (xy 230.053098 -39.008465)
			(xy 230.011914 -38.972777) (xy 229.976228 -38.931592) (xy 229.946766 -38.885747) (xy 229.924128 -38.836176)
			(xy 229.908775 -38.783888) (xy 229.90102 -38.729948) (xy 225.079839 -38.729948) (xy 225.088704 -38.746176)
			(xy 225.094337 -38.753618) (xy 225.109703 -38.764186) (xy 225.118676 -38.76675) (xy 225.121216 -38.767258)
			(xy 225.149695 -38.773483) (xy 225.204474 -38.793416) (xy 225.255583 -38.821448) (xy 225.301835 -38.856928)
			(xy 225.342151 -38.899031) (xy 225.375595 -38.946775) (xy 225.401387 -38.999051) (xy 225.418928 -39.054642)
			(xy 225.42781 -39.112254) (xy 225.428302 -39.1414) (xy 225.427936 -39.165201) (xy 225.422011 -39.212433)
			(xy 225.410252 -39.258561) (xy 225.401886 -39.280846) (xy 225.401632 -39.281354) (xy 225.398369 -39.2912)
			(xy 225.399172 -39.311907) (xy 225.403156 -39.321486) (xy 225.406966 -39.328344) (xy 225.423327 -39.35881)
			(xy 225.452309 -39.421604) (xy 225.464878 -39.45382) (xy 225.473699 -39.477592) (xy 225.489203 -39.525875)
			(xy 225.495866 -39.55034) (xy 225.663721 -40.18153) (xy 228.109524 -40.18153) (xy 228.113595 -40.125908)
			(xy 228.125721 -40.071471) (xy 228.145644 -40.01938) (xy 228.17294 -39.970745) (xy 228.207026 -39.926602)
			(xy 228.247175 -39.887893) (xy 228.292533 -39.855442) (xy 228.342133 -39.829941) (xy 228.394917 -39.811934)
			(xy 228.44976 -39.801804) (xy 228.505494 -39.799767) (xy 228.560931 -39.805867) (xy 228.614888 -39.819973)
			(xy 228.666217 -39.841785) (xy 228.713823 -39.870839) (xy 228.756691 -39.906514) (xy 228.793908 -39.948051)
			(xy 228.809739 -39.97198) (xy 232.0958 -39.97198) (xy 232.099871 -39.916358) (xy 232.111997 -39.861921)
			(xy 232.13192 -39.80983) (xy 232.159216 -39.761195) (xy 232.193302 -39.717052) (xy 232.233451 -39.678343)
			(xy 232.278809 -39.645892) (xy 232.328409 -39.620391) (xy 232.381193 -39.602384) (xy 232.436036 -39.592254)
			(xy 232.49177 -39.590217) (xy 232.547207 -39.596317) (xy 232.601164 -39.610423) (xy 232.652493 -39.632235)
			(xy 232.700099 -39.661289) (xy 232.742967 -39.696964) (xy 232.780184 -39.738501) (xy 232.810957 -39.785014)
			(xy 232.834629 -39.835511) (xy 232.850697 -39.888918) (xy 232.858817 -39.944094) (xy 232.859326 -39.97198)
			(xy 232.858817 -39.999866) (xy 232.850697 -40.055042) (xy 232.834629 -40.108449) (xy 232.810957 -40.158946)
			(xy 232.780184 -40.205459) (xy 232.742967 -40.246996) (xy 232.700099 -40.282671) (xy 232.652493 -40.311725)
			(xy 232.601164 -40.333537) (xy 232.547207 -40.347643) (xy 232.49177 -40.353743) (xy 232.436036 -40.351706)
			(xy 232.381193 -40.341576) (xy 232.328409 -40.323569) (xy 232.278809 -40.298068) (xy 232.233451 -40.265617)
			(xy 232.193302 -40.226908) (xy 232.159216 -40.182765) (xy 232.13192 -40.13413) (xy 232.111997 -40.082039)
			(xy 232.099871 -40.027602) (xy 232.0958 -39.97198) (xy 228.809739 -39.97198) (xy 228.824681 -39.994564)
			(xy 228.848353 -40.045061) (xy 228.864421 -40.098468) (xy 228.872541 -40.153644) (xy 228.87305 -40.18153)
			(xy 228.872541 -40.209416) (xy 228.864421 -40.264592) (xy 228.848353 -40.317999) (xy 228.824681 -40.368496)
			(xy 228.793908 -40.415009) (xy 228.756691 -40.456546) (xy 228.713823 -40.492221) (xy 228.666217 -40.521275)
			(xy 228.614888 -40.543087) (xy 228.560931 -40.557193) (xy 228.505494 -40.563293) (xy 228.44976 -40.561256)
			(xy 228.394917 -40.551126) (xy 228.342133 -40.533119) (xy 228.292533 -40.507618) (xy 228.247175 -40.475167)
			(xy 228.207026 -40.436458) (xy 228.17294 -40.392315) (xy 228.145644 -40.34368) (xy 228.125721 -40.291589)
			(xy 228.113595 -40.237152) (xy 228.109524 -40.18153) (xy 225.663721 -40.18153) (xy 225.711004 -40.35933)
			(xy 225.81108 -40.736012) (xy 225.815144 -40.745664) (xy 225.938343 -40.971724) (xy 232.794046 -40.971724)
			(xy 232.798117 -40.916102) (xy 232.810243 -40.861665) (xy 232.830166 -40.809574) (xy 232.857462 -40.760939)
			(xy 232.891548 -40.716796) (xy 232.931697 -40.678087) (xy 232.977055 -40.645636) (xy 233.026655 -40.620135)
			(xy 233.079439 -40.602128) (xy 233.134282 -40.591998) (xy 233.190016 -40.589961) (xy 233.245453 -40.596061)
			(xy 233.29941 -40.610167) (xy 233.350739 -40.631979) (xy 233.398345 -40.661033) (xy 233.441213 -40.696708)
			(xy 233.47843 -40.738245) (xy 233.509203 -40.784758) (xy 233.532875 -40.835255) (xy 233.548943 -40.888662)
			(xy 233.557063 -40.943838) (xy 233.557572 -40.971724) (xy 233.557063 -40.99961) (xy 233.548943 -41.054786)
			(xy 233.532875 -41.108193) (xy 233.509203 -41.15869) (xy 233.47843 -41.205203) (xy 233.441213 -41.24674)
			(xy 233.414764 -41.268751) (xy 248.04395 -41.268751) (xy 248.04395 -41.214249) (xy 248.051706 -41.160301)
			(xy 248.06706 -41.108006) (xy 248.089699 -41.058428) (xy 248.119163 -41.012577) (xy 248.154852 -40.971385)
			(xy 248.19604 -40.935691) (xy 248.241888 -40.906221) (xy 248.291463 -40.883576) (xy 248.343756 -40.868215)
			(xy 248.397703 -40.860453) (xy 248.424954 -40.859964) (xy 248.453694 -40.860465) (xy 248.510522 -40.869094)
			(xy 248.565412 -40.88615) (xy 248.617124 -40.911247) (xy 248.664485 -40.943816) (xy 248.685812 -40.963088)
			(xy 248.69267 -40.969692) (xy 248.710704 -40.976804) (xy 248.799604 -40.976804) (xy 248.817638 -40.969692)
			(xy 248.824496 -40.963088) (xy 248.845808 -40.9438) (xy 248.893173 -40.911234) (xy 248.944889 -40.886144)
			(xy 248.999783 -40.869098) (xy 249.056614 -40.860481) (xy 249.085354 -40.859964) (xy 249.112607 -40.86048)
			(xy 249.166559 -40.868231) (xy 249.218858 -40.883582) (xy 249.268441 -40.90622) (xy 249.314296 -40.935685)
			(xy 249.355491 -40.971376) (xy 249.391187 -41.012567) (xy 249.420658 -41.058419) (xy 249.443302 -41.107998)
			(xy 249.458659 -41.160296) (xy 249.466417 -41.214247) (xy 249.466417 -41.268753) (xy 249.458659 -41.322704)
			(xy 249.443302 -41.375002) (xy 249.420658 -41.424581) (xy 249.391187 -41.470433) (xy 249.355491 -41.511624)
			(xy 249.314296 -41.547315) (xy 249.268441 -41.57678) (xy 249.218858 -41.599418) (xy 249.166559 -41.614769)
			(xy 249.112607 -41.62252) (xy 249.085354 -41.62298) (xy 249.056615 -41.622463) (xy 248.999788 -41.613835)
			(xy 248.944898 -41.596783) (xy 248.893187 -41.57169) (xy 248.845824 -41.539126) (xy 248.824496 -41.519856)
			(xy 248.817638 -41.513252) (xy 248.799604 -41.50614) (xy 248.710704 -41.50614) (xy 248.69267 -41.513252)
			(xy 248.685812 -41.519856) (xy 248.664503 -41.539148) (xy 248.617136 -41.571711) (xy 248.56542 -41.5968)
			(xy 248.510525 -41.613845) (xy 248.453694 -41.622462) (xy 248.424954 -41.62298) (xy 248.397703 -41.622547)
			(xy 248.343756 -41.614785) (xy 248.291463 -41.599424) (xy 248.241888 -41.576779) (xy 248.19604 -41.547309)
			(xy 248.154852 -41.511615) (xy 248.119163 -41.470423) (xy 248.089699 -41.424572) (xy 248.06706 -41.374994)
			(xy 248.051706 -41.322699) (xy 248.04395 -41.268751) (xy 233.414764 -41.268751) (xy 233.398345 -41.282415)
			(xy 233.350739 -41.311469) (xy 233.29941 -41.333281) (xy 233.245453 -41.347387) (xy 233.190016 -41.353487)
			(xy 233.134282 -41.35145) (xy 233.079439 -41.34132) (xy 233.026655 -41.323313) (xy 232.977055 -41.297812)
			(xy 232.931697 -41.265361) (xy 232.891548 -41.226652) (xy 232.857462 -41.182509) (xy 232.830166 -41.133874)
			(xy 232.810243 -41.081783) (xy 232.798117 -41.027346) (xy 232.794046 -40.971724) (xy 225.938343 -40.971724)
			(xy 226.055174 -41.1861) (xy 226.077386 -41.228003) (xy 226.114606 -41.31524) (xy 226.143293 -41.405643)
			(xy 226.163186 -41.498379) (xy 226.174099 -41.592595) (xy 226.17557 -41.639998) (xy 226.18573 -42.142918)
			(xy 226.186238 -42.146728) (xy 226.192842 -42.171874) (xy 226.197668 -42.189908) (xy 226.207541 -42.228571)
			(xy 226.221813 -42.307088) (xy 226.229756 -42.386496) (xy 226.230942 -42.426382) (xy 226.235708 -42.66565)
			(xy 232.397044 -42.66565) (xy 232.401115 -42.610028) (xy 232.413241 -42.555591) (xy 232.433164 -42.5035)
			(xy 232.46046 -42.454865) (xy 232.494546 -42.410722) (xy 232.534695 -42.372013) (xy 232.580053 -42.339562)
			(xy 232.629653 -42.314061) (xy 232.682437 -42.296054) (xy 232.73728 -42.285924) (xy 232.793014 -42.283887)
			(xy 232.848451 -42.289987) (xy 232.902408 -42.304093) (xy 232.953737 -42.325905) (xy 233.001343 -42.354959)
			(xy 233.044211 -42.390634) (xy 233.081428 -42.432171) (xy 233.112201 -42.478684) (xy 233.135873 -42.529181)
			(xy 233.151941 -42.582588) (xy 233.160061 -42.637764) (xy 233.16057 -42.66565) (xy 233.160061 -42.693536)
			(xy 233.151941 -42.748712) (xy 233.135873 -42.802119) (xy 233.112201 -42.852616) (xy 233.081428 -42.899129)
			(xy 233.044211 -42.940666) (xy 233.001343 -42.976341) (xy 232.953737 -43.005395) (xy 232.902408 -43.027207)
			(xy 232.848451 -43.041313) (xy 232.793014 -43.047413) (xy 232.73728 -43.045376) (xy 232.682437 -43.035246)
			(xy 232.629653 -43.017239) (xy 232.580053 -42.991738) (xy 232.534695 -42.959287) (xy 232.494546 -42.920578)
			(xy 232.46046 -42.876435) (xy 232.433164 -42.8278) (xy 232.413241 -42.775709) (xy 232.401115 -42.721272)
			(xy 232.397044 -42.66565) (xy 226.235708 -42.66565) (xy 226.248448 -43.305222) (xy 250.507246 -43.305222)
			(xy 250.507714 -43.277852) (xy 250.515529 -43.223672) (xy 250.531018 -43.171169) (xy 250.553859 -43.121422)
			(xy 250.583584 -43.075455) (xy 250.601226 -43.054524) (xy 250.60148 -43.05427) (xy 250.607053 -43.047174)
			(xy 250.613306 -43.030264) (xy 250.613672 -43.02125) (xy 250.613672 -42.954194) (xy 250.613324 -42.945176)
			(xy 250.607071 -42.928259) (xy 250.60148 -42.921174) (xy 250.601226 -42.921174) (xy 250.601226 -42.92092)
			(xy 250.583587 -42.899988) (xy 250.553874 -42.854015) (xy 250.531038 -42.804268) (xy 250.515547 -42.751767)
			(xy 250.507719 -42.697591) (xy 250.507246 -42.670222) (xy 250.507798 -42.641484) (xy 250.516416 -42.584659)
			(xy 250.53346 -42.529769) (xy 250.558545 -42.478057) (xy 250.591103 -42.430692) (xy 250.61037 -42.409364)
			(xy 250.616974 -42.402506) (xy 250.624086 -42.384472) (xy 250.624086 -42.295572) (xy 250.616974 -42.277538)
			(xy 250.61037 -42.27068) (xy 250.591123 -42.249333) (xy 250.558562 -42.201973) (xy 250.533473 -42.150264)
			(xy 250.516424 -42.095377) (xy 250.5078 -42.038553) (xy 250.507798 -41.981079) (xy 250.516417 -41.924255)
			(xy 250.533461 -41.869366) (xy 250.558546 -41.817655) (xy 250.591103 -41.770292) (xy 250.61037 -41.748964)
			(xy 250.616974 -41.742106) (xy 250.624086 -41.724072) (xy 250.624086 -41.635172) (xy 250.616974 -41.617138)
			(xy 250.61037 -41.61028) (xy 250.591115 -41.588939) (xy 250.558545 -41.541582) (xy 250.533449 -41.489873)
			(xy 250.516395 -41.434986) (xy 250.507769 -41.37816) (xy 250.507246 -41.349422) (xy 250.507732 -41.322171)
			(xy 250.515488 -41.268223) (xy 250.530843 -41.215928) (xy 250.553485 -41.166351) (xy 250.582951 -41.120501)
			(xy 250.618642 -41.07931) (xy 250.659833 -41.043619) (xy 250.705683 -41.014153) (xy 250.75526 -40.991511)
			(xy 250.807555 -40.976156) (xy 250.861503 -40.9684) (xy 250.916005 -40.9684) (xy 250.969953 -40.976156)
			(xy 251.022248 -40.991511) (xy 251.071825 -41.014153) (xy 251.117675 -41.043619) (xy 251.158866 -41.07931)
			(xy 251.194557 -41.120501) (xy 251.224023 -41.166351) (xy 251.246665 -41.215928) (xy 251.26202 -41.268223)
			(xy 251.269776 -41.322171) (xy 251.270262 -41.349422) (xy 251.269735 -41.378161) (xy 251.261111 -41.434987)
			(xy 251.24406 -41.489877) (xy 251.21897 -41.541589) (xy 251.186407 -41.588952) (xy 251.167138 -41.61028)
			(xy 251.160534 -41.617138) (xy 251.153422 -41.635172) (xy 251.153422 -41.724072) (xy 251.160534 -41.742106)
			(xy 251.167138 -41.748964) (xy 251.186432 -41.770271) (xy 251.219 -41.817636) (xy 251.244093 -41.869351)
			(xy 251.261143 -41.924245) (xy 251.269765 -41.981075) (xy 251.269762 -42.038557) (xy 251.261136 -42.095387)
			(xy 251.244081 -42.150279) (xy 251.218984 -42.201992) (xy 251.186412 -42.249354) (xy 251.167138 -42.27068)
			(xy 251.160534 -42.277538) (xy 251.153422 -42.295572) (xy 251.153422 -42.384472) (xy 251.160534 -42.402506)
			(xy 251.167138 -42.409364) (xy 251.186415 -42.430686) (xy 251.218981 -42.478049) (xy 251.244073 -42.529762)
			(xy 251.261122 -42.584654) (xy 251.269743 -42.641483) (xy 251.270262 -42.670222) (xy 251.269818 -42.697593)
			(xy 251.261996 -42.751774) (xy 251.246503 -42.804277) (xy 251.225946 -42.849038) (xy 253.091948 -42.849038)
			(xy 253.096019 -42.793416) (xy 253.108145 -42.738979) (xy 253.128068 -42.686888) (xy 253.155364 -42.638253)
			(xy 253.18945 -42.59411) (xy 253.229599 -42.555401) (xy 253.274957 -42.52295) (xy 253.324557 -42.497449)
			(xy 253.377341 -42.479442) (xy 253.432184 -42.469312) (xy 253.487918 -42.467275) (xy 253.543355 -42.473375)
			(xy 253.597312 -42.487481) (xy 253.648641 -42.509293) (xy 253.696247 -42.538347) (xy 253.739115 -42.574022)
			(xy 253.776332 -42.615559) (xy 253.807105 -42.662072) (xy 253.830777 -42.712569) (xy 253.846845 -42.765976)
			(xy 253.854965 -42.821152) (xy 253.855474 -42.849038) (xy 253.854965 -42.876924) (xy 253.846845 -42.9321)
			(xy 253.830777 -42.985507) (xy 253.807105 -43.036004) (xy 253.776332 -43.082517) (xy 253.739115 -43.124054)
			(xy 253.696247 -43.159729) (xy 253.648641 -43.188783) (xy 253.597312 -43.210595) (xy 253.543355 -43.224701)
			(xy 253.487918 -43.230801) (xy 253.432184 -43.228764) (xy 253.377341 -43.218634) (xy 253.324557 -43.200627)
			(xy 253.274957 -43.175126) (xy 253.229599 -43.142675) (xy 253.18945 -43.103966) (xy 253.155364 -43.059823)
			(xy 253.128068 -43.011188) (xy 253.108145 -42.959097) (xy 253.096019 -42.90466) (xy 253.091948 -42.849038)
			(xy 251.225946 -42.849038) (xy 251.223656 -42.854024) (xy 251.193926 -42.899989) (xy 251.176282 -42.92092)
			(xy 251.176028 -42.921174) (xy 251.170438 -42.928258) (xy 251.164195 -42.945177) (xy 251.163836 -42.954194)
			(xy 251.163836 -43.02125) (xy 251.164209 -43.030265) (xy 251.170445 -43.047183) (xy 251.176028 -43.05427)
			(xy 251.176282 -43.05427) (xy 251.176282 -43.054524) (xy 251.193896 -43.075476) (xy 251.223612 -43.121443)
			(xy 251.246453 -43.171186) (xy 251.26195 -43.223682) (xy 251.269785 -43.277854) (xy 251.270262 -43.305222)
			(xy 251.269776 -43.332473) (xy 251.26202 -43.386421) (xy 251.246665 -43.438716) (xy 251.224023 -43.488293)
			(xy 251.194557 -43.534143) (xy 251.158866 -43.575334) (xy 251.117675 -43.611025) (xy 251.071825 -43.640491)
			(xy 251.022248 -43.663133) (xy 250.969953 -43.678488) (xy 250.916005 -43.686244) (xy 250.861503 -43.686244)
			(xy 250.807555 -43.678488) (xy 250.75526 -43.663133) (xy 250.705683 -43.640491) (xy 250.659833 -43.611025)
			(xy 250.618642 -43.575334) (xy 250.582951 -43.534143) (xy 250.553485 -43.488293) (xy 250.530843 -43.438716)
			(xy 250.515488 -43.386421) (xy 250.507732 -43.332473) (xy 250.507246 -43.305222) (xy 226.248448 -43.305222)
			(xy 226.257034 -43.73626) (xy 252.413006 -43.73626) (xy 252.417077 -43.680638) (xy 252.429203 -43.626201)
			(xy 252.449126 -43.57411) (xy 252.476422 -43.525475) (xy 252.510508 -43.481332) (xy 252.550657 -43.442623)
			(xy 252.596015 -43.410172) (xy 252.645615 -43.384671) (xy 252.698399 -43.366664) (xy 252.753242 -43.356534)
			(xy 252.808976 -43.354497) (xy 252.864413 -43.360597) (xy 252.91837 -43.374703) (xy 252.969699 -43.396515)
			(xy 253.017305 -43.425569) (xy 253.060173 -43.461244) (xy 253.09739 -43.502781) (xy 253.128163 -43.549294)
			(xy 253.151835 -43.599791) (xy 253.167903 -43.653198) (xy 253.176023 -43.708374) (xy 253.176532 -43.73626)
			(xy 253.176023 -43.764146) (xy 253.167903 -43.819322) (xy 253.156594 -43.85691) (xy 256.919728 -43.85691)
			(xy 256.923799 -43.801288) (xy 256.935925 -43.746851) (xy 256.955848 -43.69476) (xy 256.983144 -43.646125)
			(xy 257.01723 -43.601982) (xy 257.057379 -43.563273) (xy 257.102737 -43.530822) (xy 257.152337 -43.505321)
			(xy 257.205121 -43.487314) (xy 257.259964 -43.477184) (xy 257.315698 -43.475147) (xy 257.371135 -43.481247)
			(xy 257.425092 -43.495353) (xy 257.476421 -43.517165) (xy 257.524027 -43.546219) (xy 257.566895 -43.581894)
			(xy 257.604112 -43.623431) (xy 257.634885 -43.669944) (xy 257.658557 -43.720441) (xy 257.674625 -43.773848)
			(xy 257.682745 -43.829024) (xy 257.683254 -43.85691) (xy 257.682745 -43.884796) (xy 257.674625 -43.939972)
			(xy 257.658557 -43.993379) (xy 257.634885 -44.043876) (xy 257.604112 -44.090389) (xy 257.566895 -44.131926)
			(xy 257.524027 -44.167601) (xy 257.476421 -44.196655) (xy 257.425092 -44.218467) (xy 257.371135 -44.232573)
			(xy 257.315698 -44.238673) (xy 257.259964 -44.236636) (xy 257.205121 -44.226506) (xy 257.152337 -44.208499)
			(xy 257.102737 -44.182998) (xy 257.057379 -44.150547) (xy 257.01723 -44.111838) (xy 256.983144 -44.067695)
			(xy 256.955848 -44.01906) (xy 256.935925 -43.966969) (xy 256.923799 -43.912532) (xy 256.919728 -43.85691)
			(xy 253.156594 -43.85691) (xy 253.151835 -43.872729) (xy 253.128163 -43.923226) (xy 253.09739 -43.969739)
			(xy 253.060173 -44.011276) (xy 253.017305 -44.046951) (xy 252.969699 -44.076005) (xy 252.91837 -44.097817)
			(xy 252.864413 -44.111923) (xy 252.808976 -44.118023) (xy 252.753242 -44.115986) (xy 252.698399 -44.105856)
			(xy 252.645615 -44.087849) (xy 252.596015 -44.062348) (xy 252.550657 -44.029897) (xy 252.510508 -43.991188)
			(xy 252.476422 -43.947045) (xy 252.449126 -43.89841) (xy 252.429203 -43.846319) (xy 252.417077 -43.791882)
			(xy 252.413006 -43.73626) (xy 226.257034 -43.73626) (xy 226.284487 -45.114464) (xy 252.265432 -45.114464)
			(xy 252.269503 -45.058842) (xy 252.281629 -45.004405) (xy 252.301552 -44.952314) (xy 252.328848 -44.903679)
			(xy 252.362934 -44.859536) (xy 252.403083 -44.820827) (xy 252.448441 -44.788376) (xy 252.498041 -44.762875)
			(xy 252.550825 -44.744868) (xy 252.605668 -44.734738) (xy 252.661402 -44.732701) (xy 252.716839 -44.738801)
			(xy 252.770796 -44.752907) (xy 252.822125 -44.774719) (xy 252.869731 -44.803773) (xy 252.912599 -44.839448)
			(xy 252.942581 -44.87291) (xy 259.133084 -44.87291) (xy 259.137155 -44.817288) (xy 259.149281 -44.762851)
			(xy 259.169204 -44.71076) (xy 259.1965 -44.662125) (xy 259.230586 -44.617982) (xy 259.270735 -44.579273)
			(xy 259.316093 -44.546822) (xy 259.365693 -44.521321) (xy 259.418477 -44.503314) (xy 259.47332 -44.493184)
			(xy 259.529054 -44.491147) (xy 259.584491 -44.497247) (xy 259.638448 -44.511353) (xy 259.689777 -44.533165)
			(xy 259.737383 -44.562219) (xy 259.780251 -44.597894) (xy 259.817468 -44.639431) (xy 259.848241 -44.685944)
			(xy 259.871913 -44.736441) (xy 259.887981 -44.789848) (xy 259.896101 -44.845024) (xy 259.89661 -44.87291)
			(xy 259.896101 -44.900796) (xy 259.887981 -44.955972) (xy 259.871913 -45.009379) (xy 259.848241 -45.059876)
			(xy 259.817468 -45.106389) (xy 259.780251 -45.147926) (xy 259.737383 -45.183601) (xy 259.689777 -45.212655)
			(xy 259.638448 -45.234467) (xy 259.584491 -45.248573) (xy 259.529054 -45.254673) (xy 259.47332 -45.252636)
			(xy 259.418477 -45.242506) (xy 259.365693 -45.224499) (xy 259.316093 -45.198998) (xy 259.270735 -45.166547)
			(xy 259.230586 -45.127838) (xy 259.1965 -45.083695) (xy 259.169204 -45.03506) (xy 259.149281 -44.982969)
			(xy 259.137155 -44.928532) (xy 259.133084 -44.87291) (xy 252.942581 -44.87291) (xy 252.949816 -44.880985)
			(xy 252.980589 -44.927498) (xy 253.004261 -44.977995) (xy 253.020329 -45.031402) (xy 253.028449 -45.086578)
			(xy 253.028958 -45.114464) (xy 253.028449 -45.14235) (xy 253.020329 -45.197526) (xy 253.004261 -45.250933)
			(xy 252.980589 -45.30143) (xy 252.949816 -45.347943) (xy 252.944174 -45.35424) (xy 256.903726 -45.35424)
			(xy 256.907797 -45.298618) (xy 256.919923 -45.244181) (xy 256.939846 -45.19209) (xy 256.967142 -45.143455)
			(xy 257.001228 -45.099312) (xy 257.041377 -45.060603) (xy 257.086735 -45.028152) (xy 257.136335 -45.002651)
			(xy 257.189119 -44.984644) (xy 257.243962 -44.974514) (xy 257.299696 -44.972477) (xy 257.355133 -44.978577)
			(xy 257.40909 -44.992683) (xy 257.460419 -45.014495) (xy 257.508025 -45.043549) (xy 257.550893 -45.079224)
			(xy 257.58811 -45.120761) (xy 257.618883 -45.167274) (xy 257.642555 -45.217771) (xy 257.658623 -45.271178)
			(xy 257.666743 -45.326354) (xy 257.667252 -45.35424) (xy 257.666743 -45.382126) (xy 257.658623 -45.437302)
			(xy 257.642555 -45.490709) (xy 257.618883 -45.541206) (xy 257.58811 -45.587719) (xy 257.550893 -45.629256)
			(xy 257.508025 -45.664931) (xy 257.460419 -45.693985) (xy 257.40909 -45.715797) (xy 257.355133 -45.729903)
			(xy 257.299696 -45.736003) (xy 257.243962 -45.733966) (xy 257.189119 -45.723836) (xy 257.136335 -45.705829)
			(xy 257.086735 -45.680328) (xy 257.041377 -45.647877) (xy 257.001228 -45.609168) (xy 256.967142 -45.565025)
			(xy 256.939846 -45.51639) (xy 256.919923 -45.464299) (xy 256.907797 -45.409862) (xy 256.903726 -45.35424)
			(xy 252.944174 -45.35424) (xy 252.912599 -45.38948) (xy 252.869731 -45.425155) (xy 252.822125 -45.454209)
			(xy 252.770796 -45.476021) (xy 252.716839 -45.490127) (xy 252.661402 -45.496227) (xy 252.605668 -45.49419)
			(xy 252.550825 -45.48406) (xy 252.498041 -45.466053) (xy 252.448441 -45.440552) (xy 252.403083 -45.408101)
			(xy 252.362934 -45.369392) (xy 252.328848 -45.325249) (xy 252.301552 -45.276614) (xy 252.281629 -45.224523)
			(xy 252.269503 -45.170086) (xy 252.265432 -45.114464) (xy 226.284487 -45.114464) (xy 226.298846 -45.835351)
			(xy 238.482093 -45.835351) (xy 238.482093 -45.780849) (xy 238.48985 -45.726901) (xy 238.505206 -45.674607)
			(xy 238.527848 -45.62503) (xy 238.557315 -45.57918) (xy 238.593008 -45.537991) (xy 238.634199 -45.502301)
			(xy 238.680051 -45.472836) (xy 238.729629 -45.450197) (xy 238.781925 -45.434845) (xy 238.835873 -45.427092)
			(xy 238.863124 -45.42663) (xy 238.890495 -45.427075) (xy 238.944675 -45.434897) (xy 238.997179 -45.45039)
			(xy 239.046926 -45.473237) (xy 239.092891 -45.502966) (xy 239.113822 -45.52061) (xy 239.114076 -45.520864)
			(xy 239.12116 -45.526454) (xy 239.138079 -45.532697) (xy 239.147096 -45.533056) (xy 239.214152 -45.533056)
			(xy 239.223168 -45.532686) (xy 239.240085 -45.526448) (xy 239.247172 -45.520864) (xy 239.247172 -45.52061)
			(xy 239.247426 -45.52061) (xy 239.268359 -45.502969) (xy 239.314327 -45.473245) (xy 239.364073 -45.450399)
			(xy 239.416575 -45.434903) (xy 239.470753 -45.427074) (xy 239.525495 -45.427074) (xy 239.579673 -45.434903)
			(xy 239.632175 -45.450399) (xy 239.681921 -45.473245) (xy 239.727889 -45.502969) (xy 239.748822 -45.52061)
			(xy 239.749076 -45.520864) (xy 239.75616 -45.526454) (xy 239.773079 -45.532697) (xy 239.782096 -45.533056)
			(xy 239.849152 -45.533056) (xy 239.858168 -45.532686) (xy 239.875085 -45.526448) (xy 239.882172 -45.520864)
			(xy 239.882172 -45.52061) (xy 239.882426 -45.52061) (xy 239.903359 -45.502969) (xy 239.949327 -45.473245)
			(xy 239.999073 -45.450399) (xy 240.051575 -45.434903) (xy 240.105753 -45.427074) (xy 240.160495 -45.427074)
			(xy 240.214673 -45.434903) (xy 240.267175 -45.450399) (xy 240.316921 -45.473245) (xy 240.362889 -45.502969)
			(xy 240.383822 -45.52061) (xy 240.384076 -45.520864) (xy 240.39116 -45.526454) (xy 240.408079 -45.532697)
			(xy 240.417096 -45.533056) (xy 240.484152 -45.533056) (xy 240.493168 -45.532686) (xy 240.510085 -45.526448)
			(xy 240.517172 -45.520864) (xy 240.517172 -45.52061) (xy 240.517426 -45.52061) (xy 240.538376 -45.502994)
			(xy 240.584344 -45.473278) (xy 240.634087 -45.450438) (xy 240.686584 -45.434941) (xy 240.740756 -45.427107)
			(xy 240.768124 -45.42663) (xy 240.795377 -45.427042) (xy 240.849327 -45.434802) (xy 240.901624 -45.45016)
			(xy 240.951204 -45.472805) (xy 240.997056 -45.502275) (xy 241.038247 -45.53797) (xy 241.073939 -45.579164)
			(xy 241.103406 -45.625018) (xy 241.126048 -45.674598) (xy 241.141404 -45.726896) (xy 241.14916 -45.780847)
			(xy 241.14916 -45.835353) (xy 241.141404 -45.889304) (xy 241.126048 -45.941602) (xy 241.103406 -45.991182)
			(xy 241.073939 -46.037036) (xy 241.038247 -46.07823) (xy 241.033661 -46.082204) (xy 250.252484 -46.082204)
			(xy 250.252981 -46.054953) (xy 250.260737 -46.001006) (xy 250.276091 -45.948712) (xy 250.298732 -45.899136)
			(xy 250.328197 -45.853286) (xy 250.363887 -45.812095) (xy 250.405076 -45.776404) (xy 250.450925 -45.746937)
			(xy 250.500501 -45.724296) (xy 250.552795 -45.70894) (xy 250.606741 -45.701182) (xy 250.633992 -45.700696)
			(xy 250.660894 -45.701164) (xy 250.714164 -45.708735) (xy 250.765842 -45.723713) (xy 250.814904 -45.745802)
			(xy 250.860376 -45.774564) (xy 250.901358 -45.809428) (xy 250.937036 -45.849703) (xy 250.952254 -45.871892)
			(xy 250.959366 -45.882814) (xy 250.982226 -45.894752) (xy 251.094494 -45.89272) (xy 251.116846 -45.879766)
			(xy 251.123704 -45.86859) (xy 251.138636 -45.844996) (xy 251.174314 -45.802044) (xy 251.21587 -45.764751)
			(xy 251.262418 -45.733912) (xy 251.312964 -45.710188) (xy 251.366428 -45.694083) (xy 251.421668 -45.685943)
			(xy 251.449586 -45.685456) (xy 251.476579 -45.685925) (xy 251.530027 -45.693529) (xy 251.58187 -45.708588)
			(xy 251.631075 -45.7308) (xy 251.676659 -45.759723) (xy 251.69749 -45.776896) (xy 251.705618 -45.784008)
			(xy 251.726192 -45.790104) (xy 251.811536 -45.779182) (xy 251.822087 -45.777435) (xy 251.840367 -45.766361)
			(xy 251.846842 -45.757846) (xy 251.862176 -45.736601) (xy 251.897766 -45.698148) (xy 251.938287 -45.664931)
			(xy 251.982973 -45.637574) (xy 252.030984 -45.616593) (xy 252.081416 -45.602383) (xy 252.133318 -45.595211)
			(xy 252.159516 -45.594778) (xy 252.186765 -45.595293) (xy 252.240709 -45.603051) (xy 252.293 -45.618407)
			(xy 252.342574 -45.641049) (xy 252.38842 -45.670514) (xy 252.429607 -45.706204) (xy 252.465295 -45.747393)
			(xy 252.494759 -45.79324) (xy 252.517398 -45.842815) (xy 252.532752 -45.895106) (xy 252.540508 -45.949051)
			(xy 252.540508 -46.003549) (xy 252.532752 -46.057494) (xy 252.517398 -46.109785) (xy 252.494759 -46.15936)
			(xy 252.465295 -46.205207) (xy 252.429607 -46.246396) (xy 252.38842 -46.282086) (xy 252.342574 -46.311551)
			(xy 252.293 -46.334193) (xy 252.240709 -46.349549) (xy 252.186765 -46.357307) (xy 252.159516 -46.357794)
			(xy 252.132524 -46.357312) (xy 252.079077 -46.349709) (xy 252.027234 -46.334653) (xy 251.978029 -46.312444)
			(xy 251.932444 -46.283525) (xy 251.911612 -46.266354) (xy 251.903484 -46.259242) (xy 251.88291 -46.253146)
			(xy 251.797566 -46.264068) (xy 251.78702 -46.265833) (xy 251.768739 -46.276896) (xy 251.76226 -46.285404)
			(xy 251.744649 -46.309706) (xy 251.703052 -46.352965) (xy 251.679456 -46.37151) (xy 251.671582 -46.377352)
			(xy 251.661168 -46.394878) (xy 251.64796 -46.485302) (xy 251.652786 -46.504606) (xy 251.658628 -46.51248)
			(xy 251.658628 -46.512734) (xy 251.676125 -46.537482) (xy 251.703931 -46.591333) (xy 251.722869 -46.648904)
			(xy 251.730072 -46.693836) (xy 256.876296 -46.693836) (xy 256.876782 -46.666585) (xy 256.884538 -46.612637)
			(xy 256.899893 -46.560342) (xy 256.922535 -46.510765) (xy 256.952001 -46.464915) (xy 256.987692 -46.423724)
			(xy 257.028883 -46.388033) (xy 257.074733 -46.358567) (xy 257.12431 -46.335925) (xy 257.176605 -46.32057)
			(xy 257.230553 -46.312814) (xy 257.285055 -46.312814) (xy 257.339003 -46.32057) (xy 257.391298 -46.335925)
			(xy 257.440875 -46.358567) (xy 257.486725 -46.388033) (xy 257.527916 -46.423724) (xy 257.563607 -46.464915)
			(xy 257.593073 -46.510765) (xy 257.615715 -46.560342) (xy 257.63107 -46.612637) (xy 257.638826 -46.666585)
			(xy 257.639312 -46.693836) (xy 257.638838 -46.720263) (xy 257.631528 -46.772611) (xy 257.617056 -46.823446)
			(xy 257.595696 -46.871793) (xy 257.582162 -46.894496) (xy 257.581908 -46.89475) (xy 257.576571 -46.904768)
			(xy 257.574316 -46.927318) (xy 257.57759 -46.938184) (xy 257.603752 -47.01286) (xy 257.608136 -47.023375)
			(xy 257.624225 -47.039464) (xy 257.63474 -47.043848) (xy 257.634994 -47.043848) (xy 257.659513 -47.052891)
			(xy 257.705964 -47.076839) (xy 257.748715 -47.106899) (xy 257.786965 -47.142511) (xy 257.82 -47.183007)
			(xy 257.847202 -47.227631) (xy 257.868063 -47.275548) (xy 257.882192 -47.325863) (xy 257.889325 -47.377635)
			(xy 257.889756 -47.403766) (xy 257.88927 -47.431017) (xy 257.887747 -47.441612) (xy 259.161786 -47.441612)
			(xy 259.165857 -47.38599) (xy 259.177983 -47.331553) (xy 259.197906 -47.279462) (xy 259.225202 -47.230827)
			(xy 259.259288 -47.186684) (xy 259.299437 -47.147975) (xy 259.344795 -47.115524) (xy 259.394395 -47.090023)
			(xy 259.447179 -47.072016) (xy 259.502022 -47.061886) (xy 259.557756 -47.059849) (xy 259.613193 -47.065949)
			(xy 259.66715 -47.080055) (xy 259.718479 -47.101867) (xy 259.766085 -47.130921) (xy 259.808953 -47.166596)
			(xy 259.84617 -47.208133) (xy 259.876943 -47.254646) (xy 259.900615 -47.305143) (xy 259.916683 -47.35855)
			(xy 259.924803 -47.413726) (xy 259.925312 -47.441612) (xy 259.924803 -47.469498) (xy 259.916683 -47.524674)
			(xy 259.900615 -47.578081) (xy 259.876943 -47.628578) (xy 259.84617 -47.675091) (xy 259.808953 -47.716628)
			(xy 259.766085 -47.752303) (xy 259.718479 -47.781357) (xy 259.66715 -47.803169) (xy 259.613193 -47.817275)
			(xy 259.557756 -47.823375) (xy 259.502022 -47.821338) (xy 259.447179 -47.811208) (xy 259.394395 -47.793201)
			(xy 259.344795 -47.7677) (xy 259.299437 -47.735249) (xy 259.259288 -47.69654) (xy 259.225202 -47.652397)
			(xy 259.197906 -47.603762) (xy 259.177983 -47.551671) (xy 259.165857 -47.497234) (xy 259.161786 -47.441612)
			(xy 257.887747 -47.441612) (xy 257.881514 -47.484965) (xy 257.866159 -47.53726) (xy 257.843517 -47.586837)
			(xy 257.814051 -47.632687) (xy 257.77836 -47.673878) (xy 257.737169 -47.709569) (xy 257.691319 -47.739035)
			(xy 257.641742 -47.761677) (xy 257.589447 -47.777032) (xy 257.535499 -47.784788) (xy 257.480997 -47.784788)
			(xy 257.427049 -47.777032) (xy 257.374754 -47.761677) (xy 257.325177 -47.739035) (xy 257.279327 -47.709569)
			(xy 257.238136 -47.673878) (xy 257.202445 -47.632687) (xy 257.172979 -47.586837) (xy 257.150337 -47.53726)
			(xy 257.134982 -47.484965) (xy 257.127226 -47.431017) (xy 257.12674 -47.403766) (xy 257.127208 -47.377338)
			(xy 257.134518 -47.324991) (xy 257.148993 -47.274155) (xy 257.170354 -47.225809) (xy 257.18389 -47.203106)
			(xy 257.184144 -47.202852) (xy 257.189479 -47.192833) (xy 257.191738 -47.170284) (xy 257.188462 -47.159418)
			(xy 257.1623 -47.084742) (xy 257.157937 -47.074216) (xy 257.141834 -47.058131) (xy 257.131312 -47.053754)
			(xy 257.131058 -47.053754) (xy 257.106551 -47.04468) (xy 257.060098 -47.020739) (xy 257.017346 -46.990683)
			(xy 256.979094 -46.955077) (xy 256.946057 -46.914584) (xy 256.918854 -46.869964) (xy 256.897991 -46.822049)
			(xy 256.883861 -46.771736) (xy 256.876727 -46.719966) (xy 256.876296 -46.693836) (xy 251.730072 -46.693836)
			(xy 251.732462 -46.708745) (xy 251.73305 -46.739048) (xy 251.732567 -46.766299) (xy 251.724805 -46.820244)
			(xy 251.709446 -46.872536) (xy 251.686802 -46.922111) (xy 251.657335 -46.967959) (xy 251.621643 -47.009148)
			(xy 251.580454 -47.044838) (xy 251.534606 -47.074305) (xy 251.485031 -47.096948) (xy 251.432738 -47.112306)
			(xy 251.378793 -47.120067) (xy 251.351542 -47.120556) (xy 251.325508 -47.120134) (xy 251.273924 -47.11304)
			(xy 251.223782 -47.099005) (xy 251.176011 -47.078288) (xy 251.131498 -47.051275) (xy 251.111004 -47.035212)
			(xy 251.103253 -47.029461) (xy 251.084838 -47.023726) (xy 251.07519 -47.024036) (xy 250.995434 -47.030386)
			(xy 250.977654 -47.039022) (xy 250.971304 -47.046388) (xy 250.953144 -47.066054) (xy 250.912232 -47.100574)
			(xy 250.866898 -47.129041) (xy 250.818033 -47.150895) (xy 250.766593 -47.165708) (xy 250.713589 -47.17319)
			(xy 250.686824 -47.173642) (xy 250.659575 -47.1731) (xy 250.605631 -47.165347) (xy 250.553339 -47.149997)
			(xy 250.503765 -47.127361) (xy 250.457916 -47.0979) (xy 250.416726 -47.062215) (xy 250.381034 -47.021031)
			(xy 250.351567 -46.975186) (xy 250.328923 -46.925615) (xy 250.313565 -46.873326) (xy 250.305805 -46.819383)
			(xy 250.305316 -46.792134) (xy 250.305836 -46.76336) (xy 250.314488 -46.706465) (xy 250.331585 -46.651515)
			(xy 250.356739 -46.599754) (xy 250.389381 -46.552359) (xy 250.408694 -46.531022) (xy 250.41606 -46.523148)
			(xy 250.423172 -46.503336) (xy 250.415806 -46.40707) (xy 250.4059 -46.388274) (xy 250.397518 -46.38167)
			(xy 250.375333 -46.363446) (xy 250.336123 -46.32151) (xy 250.303638 -46.274174) (xy 250.278609 -46.222506)
			(xy 250.261603 -46.167672) (xy 250.253002 -46.110909) (xy 250.252484 -46.082204) (xy 241.033661 -46.082204)
			(xy 240.997056 -46.113925) (xy 240.951204 -46.143395) (xy 240.901624 -46.16604) (xy 240.849327 -46.181398)
			(xy 240.795377 -46.189158) (xy 240.768124 -46.189646) (xy 240.740754 -46.189179) (xy 240.686574 -46.181363)
			(xy 240.63407 -46.165875) (xy 240.584324 -46.143033) (xy 240.538357 -46.113308) (xy 240.517426 -46.095666)
			(xy 240.517172 -46.095412) (xy 240.510068 -46.089851) (xy 240.493165 -46.083588) (xy 240.484152 -46.08322)
			(xy 240.417096 -46.08322) (xy 240.408078 -46.083571) (xy 240.391161 -46.089822) (xy 240.384076 -46.095412)
			(xy 240.383822 -46.095666) (xy 240.362889 -46.113307) (xy 240.316921 -46.143031) (xy 240.267175 -46.165877)
			(xy 240.214673 -46.181373) (xy 240.160495 -46.189202) (xy 240.105753 -46.189202) (xy 240.051575 -46.181373)
			(xy 239.999073 -46.165877) (xy 239.949327 -46.143031) (xy 239.903359 -46.113307) (xy 239.882426 -46.095666)
			(xy 239.882172 -46.095412) (xy 239.875068 -46.089851) (xy 239.858165 -46.083588) (xy 239.849152 -46.08322)
			(xy 239.782096 -46.08322) (xy 239.773078 -46.083571) (xy 239.756161 -46.089822) (xy 239.749076 -46.095412)
			(xy 239.749076 -46.095666) (xy 239.748822 -46.095666) (xy 239.727889 -46.113307) (xy 239.681921 -46.143031)
			(xy 239.632175 -46.165877) (xy 239.579673 -46.181373) (xy 239.525495 -46.189202) (xy 239.470753 -46.189202)
			(xy 239.416575 -46.181373) (xy 239.364073 -46.165877) (xy 239.314327 -46.143031) (xy 239.268359 -46.113307)
			(xy 239.247426 -46.095666) (xy 239.247172 -46.095412) (xy 239.240068 -46.089851) (xy 239.223165 -46.083588)
			(xy 239.214152 -46.08322) (xy 239.147096 -46.08322) (xy 239.138078 -46.083571) (xy 239.121161 -46.089822)
			(xy 239.114076 -46.095412) (xy 239.114076 -46.095666) (xy 239.113822 -46.095666) (xy 239.092888 -46.113303)
			(xy 239.046916 -46.143016) (xy 238.997169 -46.165853) (xy 238.944669 -46.181345) (xy 238.890493 -46.189172)
			(xy 238.863124 -46.189646) (xy 238.835873 -46.189108) (xy 238.781925 -46.181355) (xy 238.729629 -46.166003)
			(xy 238.680051 -46.143364) (xy 238.634199 -46.113899) (xy 238.593008 -46.078209) (xy 238.557315 -46.03702)
			(xy 238.527848 -45.99117) (xy 238.505206 -45.941593) (xy 238.48985 -45.889299) (xy 238.482093 -45.835351)
			(xy 226.298846 -45.835351) (xy 226.331555 -47.477426) (xy 239.502188 -47.477426) (xy 239.502672 -47.450056)
			(xy 239.510486 -47.395878) (xy 239.525971 -47.343375) (xy 239.548809 -47.293628) (xy 239.578529 -47.247661)
			(xy 239.596168 -47.226728) (xy 239.596422 -47.226474) (xy 239.601986 -47.219372) (xy 239.608246 -47.202467)
			(xy 239.608614 -47.193454) (xy 239.608614 -47.126398) (xy 239.608255 -47.117381) (xy 239.602008 -47.100465)
			(xy 239.596422 -47.093378) (xy 239.596168 -47.093378) (xy 239.596168 -47.093124) (xy 239.578522 -47.072198)
			(xy 239.548812 -47.026223) (xy 239.525978 -46.976474) (xy 239.510489 -46.923972) (xy 239.502662 -46.869795)
			(xy 239.502188 -46.842426) (xy 239.502679 -46.815174) (xy 239.510433 -46.761224) (xy 239.525785 -46.708927)
			(xy 239.548425 -46.659347) (xy 239.577889 -46.613494) (xy 239.61358 -46.572301) (xy 239.65477 -46.536607)
			(xy 239.700621 -46.507139) (xy 239.750199 -46.484496) (xy 239.802495 -46.469139) (xy 239.856444 -46.461382)
			(xy 239.883696 -46.460918) (xy 239.912613 -46.461433) (xy 239.969785 -46.470161) (xy 240.024984 -46.48742)
			(xy 240.076946 -46.512812) (xy 240.12448 -46.545756) (xy 240.166496 -46.585498) (xy 240.184686 -46.607984)
			(xy 240.192294 -46.616789) (xy 240.213195 -46.626971) (xy 240.224818 -46.627542) (xy 240.304574 -46.627542)
			(xy 240.316205 -46.626994) (xy 240.337116 -46.616813) (xy 240.344706 -46.607984) (xy 240.36289 -46.585494)
			(xy 240.404911 -46.54576) (xy 240.452448 -46.512822) (xy 240.504411 -46.487435) (xy 240.559609 -46.47018)
			(xy 240.61678 -46.461452) (xy 240.645696 -46.460918) (xy 240.67295 -46.461359) (xy 240.726903 -46.469116)
			(xy 240.779203 -46.484473) (xy 240.828785 -46.507117) (xy 240.874639 -46.536587) (xy 240.915832 -46.572283)
			(xy 240.951526 -46.613479) (xy 240.980994 -46.659335) (xy 241.003635 -46.708918) (xy 241.018988 -46.761219)
			(xy 241.026742 -46.815172) (xy 241.027204 -46.842426) (xy 241.026753 -46.86874) (xy 241.019514 -46.92087)
			(xy 241.005192 -46.971513) (xy 240.984057 -47.019712) (xy 240.956508 -47.064555) (xy 240.923067 -47.105194)
			(xy 240.904014 -47.12335) (xy 240.89659 -47.130853) (xy 240.888078 -47.150147) (xy 240.887504 -47.160688)
			(xy 240.887504 -47.235364) (xy 240.888038 -47.245913) (xy 240.89657 -47.265209) (xy 240.904014 -47.272702)
			(xy 240.923066 -47.290861) (xy 240.956523 -47.33149) (xy 240.984082 -47.37633) (xy 241.005221 -47.42453)
			(xy 241.019539 -47.475177) (xy 241.026765 -47.52731) (xy 241.027204 -47.553626) (xy 241.026746 -47.580878)
			(xy 241.018986 -47.634827) (xy 241.003628 -47.687123) (xy 240.980983 -47.7367) (xy 240.951514 -47.782551)
			(xy 240.915819 -47.823741) (xy 240.874627 -47.859432) (xy 240.828774 -47.888898) (xy 240.779194 -47.911538)
			(xy 240.726898 -47.926893) (xy 240.672948 -47.934649) (xy 240.645696 -47.935134) (xy 240.618029 -47.934655)
			(xy 240.563277 -47.926654) (xy 240.510254 -47.910834) (xy 240.460068 -47.887526) (xy 240.413773 -47.857219)
			(xy 240.372336 -47.820547) (xy 240.336627 -47.778278) (xy 240.321592 -47.755048) (xy 240.314961 -47.745367)
			(xy 240.295096 -47.732925) (xy 240.283492 -47.731172) (xy 240.203482 -47.723298) (xy 240.191844 -47.722678)
			(xy 240.170009 -47.730752) (xy 240.161572 -47.738792) (xy 240.161318 -47.739046) (xy 240.143201 -47.757591)
			(xy 240.102878 -47.790175) (xy 240.058511 -47.816994) (xy 240.01092 -47.837553) (xy 239.960982 -47.851474)
			(xy 239.909617 -47.858499) (xy 239.883696 -47.858934) (xy 239.856446 -47.858426) (xy 239.8025 -47.85067)
			(xy 239.750208 -47.835315) (xy 239.700632 -47.812676) (xy 239.654783 -47.783211) (xy 239.613593 -47.747522)
			(xy 239.577902 -47.706335) (xy 239.548435 -47.660487) (xy 239.525792 -47.610913) (xy 239.510435 -47.558621)
			(xy 239.502676 -47.504676) (xy 239.502188 -47.477426) (xy 226.331555 -47.477426) (xy 226.348079 -48.30699)
			(xy 256.753866 -48.30699) (xy 256.757937 -48.251368) (xy 256.770063 -48.196931) (xy 256.789986 -48.14484)
			(xy 256.817282 -48.096205) (xy 256.851368 -48.052062) (xy 256.891517 -48.013353) (xy 256.936875 -47.980902)
			(xy 256.986475 -47.955401) (xy 257.039259 -47.937394) (xy 257.094102 -47.927264) (xy 257.149836 -47.925227)
			(xy 257.205273 -47.931327) (xy 257.25923 -47.945433) (xy 257.310559 -47.967245) (xy 257.358165 -47.996299)
			(xy 257.401033 -48.031974) (xy 257.43825 -48.073511) (xy 257.469023 -48.120024) (xy 257.492695 -48.170521)
			(xy 257.508763 -48.223928) (xy 257.516883 -48.279104) (xy 257.517392 -48.30699) (xy 257.516883 -48.334876)
			(xy 257.508763 -48.390052) (xy 257.492695 -48.443459) (xy 257.469023 -48.493956) (xy 257.43825 -48.540469)
			(xy 257.401033 -48.582006) (xy 257.358165 -48.617681) (xy 257.310559 -48.646735) (xy 257.25923 -48.668547)
			(xy 257.205273 -48.682653) (xy 257.149836 -48.688753) (xy 257.094102 -48.686716) (xy 257.039259 -48.676586)
			(xy 256.986475 -48.658579) (xy 256.936875 -48.633078) (xy 256.891517 -48.600627) (xy 256.851368 -48.561918)
			(xy 256.817282 -48.517775) (xy 256.789986 -48.46914) (xy 256.770063 -48.417049) (xy 256.757937 -48.362612)
			(xy 256.753866 -48.30699) (xy 226.348079 -48.30699) (xy 226.35769 -48.789458) (xy 238.952913 -48.789458)
			(xy 238.952913 -48.734942) (xy 238.960672 -48.680982) (xy 238.976032 -48.628675) (xy 238.99868 -48.579087)
			(xy 239.028155 -48.533227) (xy 239.063857 -48.492028) (xy 239.105059 -48.456331) (xy 239.150922 -48.42686)
			(xy 239.200513 -48.404218) (xy 239.252821 -48.388863) (xy 239.306782 -48.38111) (xy 239.33404 -48.38065)
			(xy 239.36141 -48.381139) (xy 239.415588 -48.388949) (xy 239.468091 -48.404432) (xy 239.517839 -48.427269)
			(xy 239.563806 -48.45699) (xy 239.584738 -48.47463) (xy 239.584992 -48.474884) (xy 239.592078 -48.480472)
			(xy 239.608995 -48.486718) (xy 239.618012 -48.487076) (xy 239.685068 -48.487076) (xy 239.694084 -48.486709)
			(xy 239.711001 -48.480469) (xy 239.718088 -48.474884) (xy 239.718088 -48.47463) (xy 239.718342 -48.47463)
			(xy 239.739289 -48.457009) (xy 239.785257 -48.427294) (xy 239.835001 -48.404454) (xy 239.887498 -48.388958)
			(xy 239.941672 -48.381126) (xy 239.96904 -48.38065) (xy 239.996286 -48.381223) (xy 240.050224 -48.388983)
			(xy 240.102508 -48.40434) (xy 240.152075 -48.426981) (xy 240.197915 -48.456445) (xy 240.239096 -48.492133)
			(xy 240.274779 -48.533317) (xy 240.304238 -48.579161) (xy 240.326874 -48.62873) (xy 240.342225 -48.681015)
			(xy 240.34998 -48.734954) (xy 240.34998 -48.753014) (xy 253.3683 -48.753014) (xy 253.372371 -48.697392)
			(xy 253.384497 -48.642955) (xy 253.40442 -48.590864) (xy 253.431716 -48.542229) (xy 253.465802 -48.498086)
			(xy 253.505951 -48.459377) (xy 253.551309 -48.426926) (xy 253.600909 -48.401425) (xy 253.653693 -48.383418)
			(xy 253.708536 -48.373288) (xy 253.76427 -48.371251) (xy 253.819707 -48.377351) (xy 253.873664 -48.391457)
			(xy 253.924993 -48.413269) (xy 253.972599 -48.442323) (xy 254.015467 -48.477998) (xy 254.052684 -48.519535)
			(xy 254.083457 -48.566048) (xy 254.107129 -48.616545) (xy 254.123197 -48.669952) (xy 254.131317 -48.725128)
			(xy 254.131826 -48.753014) (xy 254.131317 -48.7809) (xy 254.123197 -48.836076) (xy 254.120753 -48.8442)
			(xy 254.387348 -48.8442) (xy 254.391419 -48.788578) (xy 254.403545 -48.734141) (xy 254.423468 -48.68205)
			(xy 254.450764 -48.633415) (xy 254.48485 -48.589272) (xy 254.524999 -48.550563) (xy 254.570357 -48.518112)
			(xy 254.619957 -48.492611) (xy 254.672741 -48.474604) (xy 254.727584 -48.464474) (xy 254.783318 -48.462437)
			(xy 254.838755 -48.468537) (xy 254.892712 -48.482643) (xy 254.944041 -48.504455) (xy 254.991647 -48.533509)
			(xy 255.034515 -48.569184) (xy 255.071732 -48.610721) (xy 255.102505 -48.657234) (xy 255.126177 -48.707731)
			(xy 255.142245 -48.761138) (xy 255.150365 -48.816314) (xy 255.150874 -48.8442) (xy 255.150365 -48.872086)
			(xy 255.147367 -48.89246) (xy 255.414016 -48.89246) (xy 255.418087 -48.836838) (xy 255.430213 -48.782401)
			(xy 255.450136 -48.73031) (xy 255.477432 -48.681675) (xy 255.511518 -48.637532) (xy 255.551667 -48.598823)
			(xy 255.597025 -48.566372) (xy 255.646625 -48.540871) (xy 255.699409 -48.522864) (xy 255.754252 -48.512734)
			(xy 255.809986 -48.510697) (xy 255.865423 -48.516797) (xy 255.91938 -48.530903) (xy 255.970709 -48.552715)
			(xy 256.018315 -48.581769) (xy 256.061183 -48.617444) (xy 256.0984 -48.658981) (xy 256.129173 -48.705494)
			(xy 256.152845 -48.755991) (xy 256.168913 -48.809398) (xy 256.177033 -48.864574) (xy 256.177542 -48.89246)
			(xy 256.177033 -48.920346) (xy 256.174595 -48.93691) (xy 259.133084 -48.93691) (xy 259.137155 -48.881288)
			(xy 259.149281 -48.826851) (xy 259.169204 -48.77476) (xy 259.1965 -48.726125) (xy 259.230586 -48.681982)
			(xy 259.270735 -48.643273) (xy 259.316093 -48.610822) (xy 259.365693 -48.585321) (xy 259.418477 -48.567314)
			(xy 259.47332 -48.557184) (xy 259.529054 -48.555147) (xy 259.584491 -48.561247) (xy 259.638448 -48.575353)
			(xy 259.689777 -48.597165) (xy 259.737383 -48.626219) (xy 259.780251 -48.661894) (xy 259.817468 -48.703431)
			(xy 259.848241 -48.749944) (xy 259.871913 -48.800441) (xy 259.887981 -48.853848) (xy 259.896101 -48.909024)
			(xy 259.89661 -48.93691) (xy 259.896101 -48.964796) (xy 259.887981 -49.019972) (xy 259.871913 -49.073379)
			(xy 259.848241 -49.123876) (xy 259.817468 -49.170389) (xy 259.780251 -49.211926) (xy 259.737383 -49.247601)
			(xy 259.689777 -49.276655) (xy 259.638448 -49.298467) (xy 259.584491 -49.312573) (xy 259.529054 -49.318673)
			(xy 259.47332 -49.316636) (xy 259.418477 -49.306506) (xy 259.365693 -49.288499) (xy 259.316093 -49.262998)
			(xy 259.270735 -49.230547) (xy 259.230586 -49.191838) (xy 259.1965 -49.147695) (xy 259.169204 -49.09906)
			(xy 259.149281 -49.046969) (xy 259.137155 -48.992532) (xy 259.133084 -48.93691) (xy 256.174595 -48.93691)
			(xy 256.168913 -48.975522) (xy 256.152845 -49.028929) (xy 256.129173 -49.079426) (xy 256.0984 -49.125939)
			(xy 256.061183 -49.167476) (xy 256.018315 -49.203151) (xy 255.970709 -49.232205) (xy 255.91938 -49.254017)
			(xy 255.865423 -49.268123) (xy 255.809986 -49.274223) (xy 255.754252 -49.272186) (xy 255.699409 -49.262056)
			(xy 255.646625 -49.244049) (xy 255.597025 -49.218548) (xy 255.551667 -49.186097) (xy 255.511518 -49.147388)
			(xy 255.477432 -49.103245) (xy 255.450136 -49.05461) (xy 255.430213 -49.002519) (xy 255.418087 -48.948082)
			(xy 255.414016 -48.89246) (xy 255.147367 -48.89246) (xy 255.142245 -48.927262) (xy 255.126177 -48.980669)
			(xy 255.102505 -49.031166) (xy 255.071732 -49.077679) (xy 255.034515 -49.119216) (xy 254.991647 -49.154891)
			(xy 254.944041 -49.183945) (xy 254.892712 -49.205757) (xy 254.838755 -49.219863) (xy 254.783318 -49.225963)
			(xy 254.727584 -49.223926) (xy 254.672741 -49.213796) (xy 254.619957 -49.195789) (xy 254.570357 -49.170288)
			(xy 254.524999 -49.137837) (xy 254.48485 -49.099128) (xy 254.450764 -49.054985) (xy 254.423468 -49.00635)
			(xy 254.403545 -48.954259) (xy 254.391419 -48.899822) (xy 254.387348 -48.8442) (xy 254.120753 -48.8442)
			(xy 254.107129 -48.889483) (xy 254.083457 -48.93998) (xy 254.052684 -48.986493) (xy 254.015467 -49.02803)
			(xy 253.972599 -49.063705) (xy 253.924993 -49.092759) (xy 253.873664 -49.114571) (xy 253.819707 -49.128677)
			(xy 253.76427 -49.134777) (xy 253.708536 -49.13274) (xy 253.653693 -49.12261) (xy 253.600909 -49.104603)
			(xy 253.551309 -49.079102) (xy 253.505951 -49.046651) (xy 253.465802 -49.007942) (xy 253.431716 -48.963799)
			(xy 253.40442 -48.915164) (xy 253.384497 -48.863073) (xy 253.372371 -48.808636) (xy 253.3683 -48.753014)
			(xy 240.34998 -48.753014) (xy 240.34998 -48.789446) (xy 240.342225 -48.843385) (xy 240.326874 -48.89567)
			(xy 240.304238 -48.945239) (xy 240.274779 -48.991083) (xy 240.239096 -49.032267) (xy 240.197915 -49.067955)
			(xy 240.152075 -49.097419) (xy 240.102508 -49.12006) (xy 240.050224 -49.135417) (xy 239.996286 -49.143177)
			(xy 239.96904 -49.143666) (xy 239.94167 -49.143185) (xy 239.887491 -49.135372) (xy 239.834988 -49.119887)
			(xy 239.785241 -49.097048) (xy 239.739274 -49.067326) (xy 239.718342 -49.049686) (xy 239.718088 -49.049432)
			(xy 239.711015 -49.043826) (xy 239.694088 -49.037593) (xy 239.685068 -49.03724) (xy 239.618012 -49.03724)
			(xy 239.608995 -49.037594) (xy 239.592077 -49.043843) (xy 239.584992 -49.049432) (xy 239.584992 -49.049686)
			(xy 239.584738 -49.049686) (xy 239.563801 -49.067319) (xy 239.51783 -49.097032) (xy 239.468083 -49.119869)
			(xy 239.415584 -49.135362) (xy 239.361409 -49.143191) (xy 239.33404 -49.143666) (xy 239.306782 -49.14329)
			(xy 239.252821 -49.135537) (xy 239.200513 -49.120182) (xy 239.150922 -49.09754) (xy 239.105059 -49.068069)
			(xy 239.063857 -49.032372) (xy 239.028155 -48.991173) (xy 238.99868 -48.945313) (xy 238.976032 -48.895725)
			(xy 238.960672 -48.843418) (xy 238.952913 -48.789458) (xy 226.35769 -48.789458) (xy 226.376424 -49.72995)
			(xy 238.502698 -49.72995) (xy 238.502698 -49.67545) (xy 238.510454 -49.621506) (xy 238.525808 -49.569214)
			(xy 238.548448 -49.519639) (xy 238.577913 -49.473792) (xy 238.613602 -49.432604) (xy 238.65479 -49.396914)
			(xy 238.700638 -49.367449) (xy 238.750212 -49.344809) (xy 238.802504 -49.329455) (xy 238.856448 -49.321698)
			(xy 238.883698 -49.321212) (xy 238.911068 -49.321676) (xy 238.965248 -49.329494) (xy 239.017751 -49.344983)
			(xy 239.067498 -49.367826) (xy 239.113464 -49.397551) (xy 239.134396 -49.415192) (xy 239.13465 -49.415446)
			(xy 239.141743 -49.421023) (xy 239.158655 -49.427274) (xy 239.16767 -49.427638) (xy 239.234726 -49.427638)
			(xy 239.243743 -49.427285) (xy 239.26066 -49.421034) (xy 239.267746 -49.415446) (xy 239.267746 -49.415192)
			(xy 239.268 -49.415192) (xy 239.28892 -49.397538) (xy 239.334896 -49.367829) (xy 239.384647 -49.344996)
			(xy 239.43715 -49.329508) (xy 239.491328 -49.321684) (xy 239.518698 -49.321212) (xy 239.545952 -49.321635)
			(xy 239.599906 -49.329392) (xy 239.652207 -49.344749) (xy 239.70179 -49.367392) (xy 239.747646 -49.396862)
			(xy 239.788841 -49.432557) (xy 239.824537 -49.473752) (xy 239.854007 -49.519608) (xy 239.876651 -49.569191)
			(xy 239.892008 -49.621492) (xy 239.899765 -49.675446) (xy 239.899765 -49.729954) (xy 239.892008 -49.783908)
			(xy 239.876651 -49.836209) (xy 239.854007 -49.885792) (xy 239.824537 -49.931648) (xy 239.806113 -49.95291)
			(xy 259.133084 -49.95291) (xy 259.137155 -49.897288) (xy 259.149281 -49.842851) (xy 259.169204 -49.79076)
			(xy 259.1965 -49.742125) (xy 259.230586 -49.697982) (xy 259.270735 -49.659273) (xy 259.316093 -49.626822)
			(xy 259.365693 -49.601321) (xy 259.418477 -49.583314) (xy 259.47332 -49.573184) (xy 259.529054 -49.571147)
			(xy 259.584491 -49.577247) (xy 259.638448 -49.591353) (xy 259.689777 -49.613165) (xy 259.737383 -49.642219)
			(xy 259.780251 -49.677894) (xy 259.817468 -49.719431) (xy 259.848241 -49.765944) (xy 259.871913 -49.816441)
			(xy 259.887981 -49.869848) (xy 259.896101 -49.925024) (xy 259.89661 -49.95291) (xy 259.896101 -49.980796)
			(xy 259.887981 -50.035972) (xy 259.871913 -50.089379) (xy 259.848241 -50.139876) (xy 259.817468 -50.186389)
			(xy 259.780251 -50.227926) (xy 259.737383 -50.263601) (xy 259.689777 -50.292655) (xy 259.638448 -50.314467)
			(xy 259.584491 -50.328573) (xy 259.529054 -50.334673) (xy 259.47332 -50.332636) (xy 259.418477 -50.322506)
			(xy 259.365693 -50.304499) (xy 259.316093 -50.278998) (xy 259.270735 -50.246547) (xy 259.230586 -50.207838)
			(xy 259.1965 -50.163695) (xy 259.169204 -50.11506) (xy 259.149281 -50.062969) (xy 259.137155 -50.008532)
			(xy 259.133084 -49.95291) (xy 239.806113 -49.95291) (xy 239.788841 -49.972843) (xy 239.747646 -50.008538)
			(xy 239.70179 -50.038008) (xy 239.652207 -50.060651) (xy 239.599906 -50.076008) (xy 239.545952 -50.083765)
			(xy 239.518698 -50.084228) (xy 239.491327 -50.083781) (xy 239.437146 -50.075961) (xy 239.384642 -50.060469)
			(xy 239.334896 -50.037622) (xy 239.28893 -50.007892) (xy 239.268 -49.990248) (xy 239.267746 -49.989994)
			(xy 239.260651 -49.98442) (xy 239.243741 -49.978166) (xy 239.234726 -49.977802) (xy 239.16767 -49.977802)
			(xy 239.158652 -49.978144) (xy 239.141735 -49.984402) (xy 239.13465 -49.989994) (xy 239.13465 -49.990248)
			(xy 239.134396 -49.990248) (xy 239.11347 -50.007894) (xy 239.067496 -50.037607) (xy 239.017747 -50.060442)
			(xy 238.965245 -50.075931) (xy 238.911068 -50.083756) (xy 238.883698 -50.084228) (xy 238.856448 -50.083702)
			(xy 238.802504 -50.075945) (xy 238.750212 -50.060591) (xy 238.700638 -50.037951) (xy 238.65479 -50.008486)
			(xy 238.613602 -49.972796) (xy 238.577913 -49.931608) (xy 238.548448 -49.885761) (xy 238.525808 -49.836186)
			(xy 238.510454 -49.783894) (xy 238.502698 -49.72995) (xy 226.376424 -49.72995) (xy 226.396166 -50.721051)
			(xy 256.232883 -50.721051) (xy 256.232883 -50.666549) (xy 256.24064 -50.6126) (xy 256.255996 -50.560305)
			(xy 256.278638 -50.510728) (xy 256.308105 -50.464877) (xy 256.343797 -50.423687) (xy 256.384989 -50.387996)
			(xy 256.43084 -50.358531) (xy 256.480418 -50.335891) (xy 256.532714 -50.320537) (xy 256.586662 -50.312782)
			(xy 256.613914 -50.31232) (xy 256.640253 -50.312759) (xy 256.692432 -50.319983) (xy 256.74312 -50.33432)
			(xy 256.791353 -50.355496) (xy 256.836212 -50.383109) (xy 256.876844 -50.416633) (xy 256.912476 -50.45543)
			(xy 256.942429 -50.498762) (xy 256.966133 -50.545804) (xy 256.983138 -50.595661) (xy 256.988564 -50.621438)
			(xy 256.991588 -50.634981) (xy 257.003979 -50.6598) (xy 257.022604 -50.680357) (xy 257.046084 -50.695129)
			(xy 257.072678 -50.703021) (xy 257.100415 -50.703448) (xy 257.127239 -50.696378) (xy 257.13944 -50.689764)
			(xy 257.161399 -50.677474) (xy 257.207836 -50.658087) (xy 257.256419 -50.644971) (xy 257.306303 -50.638353)
			(xy 257.331464 -50.637948) (xy 257.358715 -50.638497) (xy 257.412664 -50.646249) (xy 257.46496 -50.6616)
			(xy 257.514539 -50.684238) (xy 257.560391 -50.713701) (xy 257.601584 -50.749391) (xy 257.637277 -50.79058)
			(xy 257.666745 -50.836429) (xy 257.689388 -50.886006) (xy 257.704744 -50.938301) (xy 257.712501 -50.992249)
			(xy 257.712501 -51.046751) (xy 257.704744 -51.100699) (xy 257.689388 -51.152994) (xy 257.666745 -51.202571)
			(xy 257.637277 -51.24842) (xy 257.601584 -51.289609) (xy 257.560391 -51.325299) (xy 257.514539 -51.354762)
			(xy 257.46496 -51.3774) (xy 257.412664 -51.392751) (xy 257.358715 -51.400503) (xy 257.331464 -51.400964)
			(xy 257.305128 -51.400478) (xy 257.252954 -51.393252) (xy 257.20227 -51.378917) (xy 257.154042 -51.357743)
			(xy 257.109185 -51.330135) (xy 257.068554 -51.296617) (xy 257.032922 -51.257827) (xy 257.002966 -51.214503)
			(xy 256.979257 -51.167469) (xy 256.962245 -51.11762) (xy 256.956814 -51.091846) (xy 256.953689 -51.078332)
			(xy 256.941309 -51.053527) (xy 256.922699 -51.032979) (xy 256.899239 -51.018209) (xy 256.872666 -51.010311)
			(xy 256.844947 -51.00987) (xy 256.818135 -51.016918) (xy 256.805938 -51.02352) (xy 256.783983 -51.035817)
			(xy 256.737544 -51.055203) (xy 256.688961 -51.068317) (xy 256.639075 -51.074933) (xy 256.613914 -51.075336)
			(xy 256.586662 -51.074818) (xy 256.532714 -51.067063) (xy 256.480418 -51.051709) (xy 256.43084 -51.029069)
			(xy 256.384989 -50.999604) (xy 256.343797 -50.963913) (xy 256.308105 -50.922723) (xy 256.278638 -50.876872)
			(xy 256.255996 -50.827295) (xy 256.24064 -50.775) (xy 256.232883 -50.721051) (xy 226.396166 -50.721051)
			(xy 226.406153 -51.222449) (xy 236.270302 -51.222449) (xy 236.270302 -51.167951) (xy 236.278058 -51.114007)
			(xy 236.293412 -51.061717) (xy 236.316051 -51.012143) (xy 236.345514 -50.966296) (xy 236.381203 -50.925109)
			(xy 236.42239 -50.889419) (xy 236.468236 -50.859955) (xy 236.517809 -50.837315) (xy 236.570099 -50.82196)
			(xy 236.624043 -50.814203) (xy 236.651292 -50.813716) (xy 236.679384 -50.814201) (xy 236.734962 -50.822428)
			(xy 236.788732 -50.838719) (xy 236.83953 -50.862723) (xy 236.886257 -50.89392) (xy 236.927902 -50.931634)
			(xy 236.963562 -50.97505) (xy 236.978444 -50.998882) (xy 236.983778 -51.007772) (xy 237.000796 -51.019964)
			(xy 237.094014 -51.040284) (xy 237.114588 -51.035966) (xy 237.123224 -51.030124) (xy 237.147282 -51.014114)
			(xy 237.199215 -50.988773) (xy 237.254375 -50.97155) (xy 237.311501 -50.962838) (xy 237.340394 -50.962306)
			(xy 237.367647 -50.962761) (xy 237.421599 -50.970517) (xy 237.473898 -50.985873) (xy 237.523479 -51.008516)
			(xy 237.569333 -51.037985) (xy 237.610526 -51.07368) (xy 237.64622 -51.114873) (xy 237.675688 -51.160728)
			(xy 237.698329 -51.210309) (xy 237.713684 -51.262609) (xy 237.72144 -51.316561) (xy 237.721902 -51.343814)
			(xy 237.721444 -51.371185) (xy 237.713624 -51.425364) (xy 237.698133 -51.477867) (xy 237.67529 -51.527614)
			(xy 237.645564 -51.57358) (xy 237.627922 -51.594512) (xy 237.627668 -51.594766) (xy 237.622086 -51.601856)
			(xy 237.615838 -51.61877) (xy 237.615476 -51.627786) (xy 237.615476 -51.694842) (xy 237.615866 -51.703855)
			(xy 237.622091 -51.720772) (xy 237.627668 -51.727862) (xy 237.627922 -51.727862) (xy 237.627922 -51.728116)
			(xy 237.645574 -51.749039) (xy 237.675295 -51.795009) (xy 237.698136 -51.844758) (xy 237.713629 -51.897261)
			(xy 237.721456 -51.95144) (xy 237.721454 -52.006181) (xy 237.717224 -52.035456) (xy 259.141212 -52.035456)
			(xy 259.145283 -51.979834) (xy 259.157409 -51.925397) (xy 259.177332 -51.873306) (xy 259.204628 -51.824671)
			(xy 259.238714 -51.780528) (xy 259.278863 -51.741819) (xy 259.324221 -51.709368) (xy 259.373821 -51.683867)
			(xy 259.426605 -51.66586) (xy 259.481448 -51.65573) (xy 259.537182 -51.653693) (xy 259.592619 -51.659793)
			(xy 259.646576 -51.673899) (xy 259.697905 -51.695711) (xy 259.745511 -51.724765) (xy 259.788379 -51.76044)
			(xy 259.825596 -51.801977) (xy 259.856369 -51.84849) (xy 259.880041 -51.898987) (xy 259.896109 -51.952394)
			(xy 259.904229 -52.00757) (xy 259.904738 -52.035456) (xy 259.904229 -52.063342) (xy 259.896109 -52.118518)
			(xy 259.880041 -52.171925) (xy 259.856369 -52.222422) (xy 259.825596 -52.268935) (xy 259.788379 -52.310472)
			(xy 259.745511 -52.346147) (xy 259.697905 -52.375201) (xy 259.646576 -52.397013) (xy 259.592619 -52.411119)
			(xy 259.537182 -52.417219) (xy 259.481448 -52.415182) (xy 259.426605 -52.405052) (xy 259.373821 -52.387045)
			(xy 259.324221 -52.361544) (xy 259.278863 -52.329093) (xy 259.238714 -52.290384) (xy 259.204628 -52.246241)
			(xy 259.177332 -52.197606) (xy 259.157409 -52.145515) (xy 259.145283 -52.091078) (xy 259.141212 -52.035456)
			(xy 237.717224 -52.035456) (xy 237.713625 -52.06036) (xy 237.698129 -52.112862) (xy 237.675285 -52.162609)
			(xy 237.645562 -52.208578) (xy 237.627922 -52.229512) (xy 237.627668 -52.229766) (xy 237.622086 -52.236856)
			(xy 237.615838 -52.25377) (xy 237.615476 -52.262786) (xy 237.615476 -52.329842) (xy 237.615866 -52.338855)
			(xy 237.622091 -52.355772) (xy 237.627668 -52.362862) (xy 237.627922 -52.362862) (xy 237.627922 -52.363116)
			(xy 237.645539 -52.384066) (xy 237.675253 -52.430034) (xy 237.698093 -52.479777) (xy 237.713589 -52.532274)
			(xy 237.721424 -52.586446) (xy 237.721902 -52.613814) (xy 237.721416 -52.641065) (xy 237.71366 -52.695013)
			(xy 237.698305 -52.747308) (xy 237.675663 -52.796885) (xy 237.646197 -52.842735) (xy 237.610506 -52.883926)
			(xy 237.569315 -52.919617) (xy 237.523465 -52.949083) (xy 237.473888 -52.971725) (xy 237.421593 -52.98708)
			(xy 237.367645 -52.994836) (xy 237.313143 -52.994836) (xy 237.259195 -52.98708) (xy 237.2069 -52.971725)
			(xy 237.157323 -52.949083) (xy 237.111473 -52.919617) (xy 237.070282 -52.883926) (xy 237.034591 -52.842735)
			(xy 237.005125 -52.796885) (xy 236.982483 -52.747308) (xy 236.967128 -52.695013) (xy 236.959372 -52.641065)
			(xy 236.958886 -52.613814) (xy 236.959364 -52.586444) (xy 236.967179 -52.532266) (xy 236.982666 -52.479763)
			(xy 237.005505 -52.430016) (xy 237.035226 -52.384048) (xy 237.052866 -52.363116) (xy 237.05312 -52.362862)
			(xy 237.058689 -52.355763) (xy 237.064946 -52.338856) (xy 237.065312 -52.329842) (xy 237.065312 -52.262786)
			(xy 237.064959 -52.253769) (xy 237.058708 -52.236852) (xy 237.05312 -52.229766) (xy 237.052866 -52.229766)
			(xy 237.052866 -52.229512) (xy 237.035237 -52.208569) (xy 237.005509 -52.162604) (xy 236.98266 -52.11286)
			(xy 236.967161 -52.060359) (xy 236.959331 -52.006181) (xy 236.959329 -51.95144) (xy 236.967157 -51.897262)
			(xy 236.982653 -51.84476) (xy 237.005499 -51.795015) (xy 237.035225 -51.749048) (xy 237.052866 -51.728116)
			(xy 237.05312 -51.727862) (xy 237.058689 -51.720763) (xy 237.064946 -51.703856) (xy 237.065312 -51.694842)
			(xy 237.065312 -51.627786) (xy 237.064959 -51.618769) (xy 237.058708 -51.601852) (xy 237.05312 -51.594766)
			(xy 237.052866 -51.594258) (xy 237.041923 -51.581523) (xy 237.022081 -51.554432) (xy 237.013242 -51.540156)
			(xy 237.007908 -51.531266) (xy 236.99089 -51.519074) (xy 236.897672 -51.498754) (xy 236.877098 -51.503072)
			(xy 236.868462 -51.508914) (xy 236.844411 -51.524934) (xy 236.792475 -51.550272) (xy 236.737313 -51.567492)
			(xy 236.680186 -51.576201) (xy 236.651292 -51.576732) (xy 236.624043 -51.576197) (xy 236.570099 -51.56844)
			(xy 236.517809 -51.553085) (xy 236.468236 -51.530445) (xy 236.42239 -51.500981) (xy 236.381203 -51.465291)
			(xy 236.345514 -51.424104) (xy 236.316051 -51.378257) (xy 236.293412 -51.328683) (xy 236.278058 -51.276393)
			(xy 236.270302 -51.222449) (xy 226.406153 -51.222449) (xy 226.414754 -51.654249) (xy 234.593902 -51.654249)
			(xy 234.593902 -51.599751) (xy 234.601658 -51.545807) (xy 234.617012 -51.493517) (xy 234.639651 -51.443943)
			(xy 234.669114 -51.398096) (xy 234.704803 -51.356909) (xy 234.74599 -51.321219) (xy 234.791836 -51.291755)
			(xy 234.841409 -51.269115) (xy 234.893699 -51.25376) (xy 234.947643 -51.246003) (xy 234.974892 -51.245516)
			(xy 235.001206 -51.245984) (xy 235.053335 -51.253218) (xy 235.103978 -51.267536) (xy 235.152177 -51.288669)
			(xy 235.19702 -51.316215) (xy 235.23766 -51.349654) (xy 235.255816 -51.368706) (xy 235.263329 -51.376117)
			(xy 235.282616 -51.384636) (xy 235.293154 -51.385216) (xy 235.36783 -51.385216) (xy 235.378376 -51.384658)
			(xy 235.397672 -51.376143) (xy 235.405168 -51.368706) (xy 235.423299 -51.349626) (xy 235.463934 -51.31617)
			(xy 235.508779 -51.288615) (xy 235.556985 -51.26748) (xy 235.607637 -51.253169) (xy 235.659774 -51.245951)
			(xy 235.686092 -51.245516) (xy 235.713347 -51.24593) (xy 235.767302 -51.253687) (xy 235.819604 -51.269043)
			(xy 235.869189 -51.291687) (xy 235.915046 -51.321156) (xy 235.956242 -51.356852) (xy 235.991939 -51.398048)
			(xy 236.021409 -51.443904) (xy 236.044054 -51.493488) (xy 236.059411 -51.54579) (xy 236.067169 -51.599745)
			(xy 236.067169 -51.654255) (xy 236.059411 -51.70821) (xy 236.044054 -51.760512) (xy 236.021409 -51.810096)
			(xy 235.991939 -51.855952) (xy 235.956242 -51.897148) (xy 235.915046 -51.932844) (xy 235.869189 -51.962313)
			(xy 235.819604 -51.984957) (xy 235.767302 -52.000313) (xy 235.713347 -52.00807) (xy 235.686092 -52.008532)
			(xy 235.659778 -52.00806) (xy 235.60765 -52.000824) (xy 235.557008 -51.986506) (xy 235.508809 -51.965374)
			(xy 235.463966 -51.937829) (xy 235.423325 -51.904393) (xy 235.405168 -51.885342) (xy 235.397654 -51.877931)
			(xy 235.378369 -51.869411) (xy 235.36783 -51.868832) (xy 235.293154 -51.868832) (xy 235.282605 -51.869367)
			(xy 235.263309 -51.877897) (xy 235.255816 -51.885342) (xy 235.237654 -51.904391) (xy 235.197025 -51.937847)
			(xy 235.152185 -51.965406) (xy 235.103986 -51.986545) (xy 235.05334 -52.000864) (xy 235.001208 -52.008092)
			(xy 234.974892 -52.008532) (xy 234.947643 -52.007997) (xy 234.893699 -52.00024) (xy 234.841409 -51.984885)
			(xy 234.791836 -51.962245) (xy 234.74599 -51.932781) (xy 234.704803 -51.897091) (xy 234.669114 -51.855904)
			(xy 234.639651 -51.810057) (xy 234.617012 -51.760483) (xy 234.601658 -51.708193) (xy 234.593902 -51.654249)
			(xy 226.414754 -51.654249) (xy 226.455876 -53.718714) (xy 236.97514 -53.718714) (xy 236.979211 -53.663092)
			(xy 236.991337 -53.608655) (xy 237.01126 -53.556564) (xy 237.038556 -53.507929) (xy 237.072642 -53.463786)
			(xy 237.112791 -53.425077) (xy 237.158149 -53.392626) (xy 237.207749 -53.367125) (xy 237.260533 -53.349118)
			(xy 237.315376 -53.338988) (xy 237.37111 -53.336951) (xy 237.426547 -53.343051) (xy 237.480504 -53.357157)
			(xy 237.531833 -53.378969) (xy 237.579439 -53.408023) (xy 237.622307 -53.443698) (xy 237.659524 -53.485235)
			(xy 237.690297 -53.531748) (xy 237.713969 -53.582245) (xy 237.730037 -53.635652) (xy 237.738157 -53.690828)
			(xy 237.738666 -53.718714) (xy 237.738157 -53.7466) (xy 237.730037 -53.801776) (xy 237.713969 -53.855183)
			(xy 237.690297 -53.90568) (xy 237.659524 -53.952193) (xy 237.622307 -53.99373) (xy 237.579439 -54.029405)
			(xy 237.531833 -54.058459) (xy 237.480504 -54.080271) (xy 237.426547 -54.094377) (xy 237.37111 -54.100477)
			(xy 237.315376 -54.09844) (xy 237.260533 -54.08831) (xy 237.207749 -54.070303) (xy 237.158149 -54.044802)
			(xy 237.112791 -54.012351) (xy 237.072642 -53.973642) (xy 237.038556 -53.929499) (xy 237.01126 -53.880864)
			(xy 236.991337 -53.828773) (xy 236.979211 -53.774336) (xy 236.97514 -53.718714) (xy 226.455876 -53.718714)
			(xy 226.467644 -54.309518) (xy 237.727234 -54.309518) (xy 237.731305 -54.253896) (xy 237.743431 -54.199459)
			(xy 237.763354 -54.147368) (xy 237.79065 -54.098733) (xy 237.824736 -54.05459) (xy 237.864885 -54.015881)
			(xy 237.910243 -53.98343) (xy 237.959843 -53.957929) (xy 238.012627 -53.939922) (xy 238.06747 -53.929792)
			(xy 238.123204 -53.927755) (xy 238.178641 -53.933855) (xy 238.232598 -53.947961) (xy 238.283927 -53.969773)
			(xy 238.331533 -53.998827) (xy 238.374401 -54.034502) (xy 238.411618 -54.076039) (xy 238.442391 -54.122552)
			(xy 238.466063 -54.173049) (xy 238.47449 -54.20106) (xy 239.961418 -54.20106) (xy 239.965489 -54.145438)
			(xy 239.977615 -54.091001) (xy 239.997538 -54.03891) (xy 240.024834 -53.990275) (xy 240.05892 -53.946132)
			(xy 240.099069 -53.907423) (xy 240.144427 -53.874972) (xy 240.194027 -53.849471) (xy 240.246811 -53.831464)
			(xy 240.301654 -53.821334) (xy 240.357388 -53.819297) (xy 240.412825 -53.825397) (xy 240.466782 -53.839503)
			(xy 240.518111 -53.861315) (xy 240.565717 -53.890369) (xy 240.608585 -53.926044) (xy 240.645802 -53.967581)
			(xy 240.676575 -54.014094) (xy 240.700247 -54.064591) (xy 240.716315 -54.117998) (xy 240.724435 -54.173174)
			(xy 240.724944 -54.20106) (xy 240.724435 -54.228946) (xy 240.716315 -54.284122) (xy 240.700247 -54.337529)
			(xy 240.676575 -54.388026) (xy 240.645802 -54.434539) (xy 240.608585 -54.476076) (xy 240.565717 -54.511751)
			(xy 240.518111 -54.540805) (xy 240.466782 -54.562617) (xy 240.412825 -54.576723) (xy 240.357388 -54.582823)
			(xy 240.301654 -54.580786) (xy 240.246811 -54.570656) (xy 240.194027 -54.552649) (xy 240.144427 -54.527148)
			(xy 240.099069 -54.494697) (xy 240.05892 -54.455988) (xy 240.024834 -54.411845) (xy 239.997538 -54.36321)
			(xy 239.977615 -54.311119) (xy 239.965489 -54.256682) (xy 239.961418 -54.20106) (xy 238.47449 -54.20106)
			(xy 238.482131 -54.226456) (xy 238.490251 -54.281632) (xy 238.49076 -54.309518) (xy 238.490251 -54.337404)
			(xy 238.482131 -54.39258) (xy 238.466063 -54.445987) (xy 238.442391 -54.496484) (xy 238.411618 -54.542997)
			(xy 238.374401 -54.584534) (xy 238.331533 -54.620209) (xy 238.283927 -54.649263) (xy 238.232598 -54.671075)
			(xy 238.178641 -54.685181) (xy 238.123204 -54.691281) (xy 238.06747 -54.689244) (xy 238.012627 -54.679114)
			(xy 237.959843 -54.661107) (xy 237.910243 -54.635606) (xy 237.864885 -54.603155) (xy 237.824736 -54.564446)
			(xy 237.79065 -54.520303) (xy 237.763354 -54.471668) (xy 237.743431 -54.419577) (xy 237.731305 -54.36514)
			(xy 237.727234 -54.309518) (xy 226.467644 -54.309518) (xy 226.477308 -54.794658) (xy 238.931448 -54.794658)
			(xy 238.935519 -54.739036) (xy 238.947645 -54.684599) (xy 238.967568 -54.632508) (xy 238.994864 -54.583873)
			(xy 239.02895 -54.53973) (xy 239.069099 -54.501021) (xy 239.114457 -54.46857) (xy 239.164057 -54.443069)
			(xy 239.216841 -54.425062) (xy 239.271684 -54.414932) (xy 239.327418 -54.412895) (xy 239.382855 -54.418995)
			(xy 239.436812 -54.433101) (xy 239.488141 -54.454913) (xy 239.535747 -54.483967) (xy 239.578615 -54.519642)
			(xy 239.615832 -54.561179) (xy 239.646605 -54.607692) (xy 239.670277 -54.658189) (xy 239.686345 -54.711596)
			(xy 239.694465 -54.766772) (xy 239.694974 -54.794658) (xy 239.69496 -54.79542) (xy 240.96294 -54.79542)
			(xy 240.967011 -54.739798) (xy 240.979137 -54.685361) (xy 240.99906 -54.63327) (xy 241.026356 -54.584635)
			(xy 241.060442 -54.540492) (xy 241.100591 -54.501783) (xy 241.145949 -54.469332) (xy 241.195549 -54.443831)
			(xy 241.248333 -54.425824) (xy 241.303176 -54.415694) (xy 241.35891 -54.413657) (xy 241.414347 -54.419757)
			(xy 241.468304 -54.433863) (xy 241.519633 -54.455675) (xy 241.567239 -54.484729) (xy 241.610107 -54.520404)
			(xy 241.647324 -54.561941) (xy 241.678097 -54.608454) (xy 241.701769 -54.658951) (xy 241.717837 -54.712358)
			(xy 241.720641 -54.731412) (xy 245.720616 -54.731412) (xy 245.721085 -54.704042) (xy 245.728902 -54.649863)
			(xy 245.74439 -54.597359) (xy 245.767231 -54.547613) (xy 245.796955 -54.501646) (xy 245.814596 -54.480714)
			(xy 245.81485 -54.48046) (xy 245.820424 -54.473365) (xy 245.826677 -54.456454) (xy 245.827042 -54.44744)
			(xy 245.827042 -54.380384) (xy 245.826705 -54.371365) (xy 245.820445 -54.354447) (xy 245.81485 -54.347364)
			(xy 245.814596 -54.347364) (xy 245.814596 -54.34711) (xy 245.796968 -54.326167) (xy 245.767245 -54.2802)
			(xy 245.744401 -54.230456) (xy 245.728905 -54.177955) (xy 245.721076 -54.123779) (xy 245.721075 -54.069039)
			(xy 245.728902 -54.014862) (xy 245.744395 -53.962361) (xy 245.767237 -53.912616) (xy 245.796957 -53.866647)
			(xy 245.814596 -53.845714) (xy 245.81485 -53.84546) (xy 245.820424 -53.838365) (xy 245.826677 -53.821454)
			(xy 245.827042 -53.81244) (xy 245.827042 -53.745384) (xy 245.826705 -53.736365) (xy 245.820445 -53.719447)
			(xy 245.81485 -53.712364) (xy 245.814596 -53.712364) (xy 245.814596 -53.71211) (xy 245.796968 -53.691167)
			(xy 245.767245 -53.6452) (xy 245.744401 -53.595456) (xy 245.728905 -53.542955) (xy 245.721076 -53.488779)
			(xy 245.721075 -53.434039) (xy 245.728902 -53.379862) (xy 245.744395 -53.327361) (xy 245.767237 -53.277616)
			(xy 245.796957 -53.231647) (xy 245.814596 -53.210714) (xy 245.81485 -53.21046) (xy 245.820424 -53.203365)
			(xy 245.826677 -53.186454) (xy 245.827042 -53.17744) (xy 245.827042 -53.110384) (xy 245.826705 -53.101365)
			(xy 245.820445 -53.084447) (xy 245.81485 -53.077364) (xy 245.814596 -53.077364) (xy 245.814596 -53.07711)
			(xy 245.796948 -53.056186) (xy 245.767237 -53.010211) (xy 245.744403 -52.960461) (xy 245.728914 -52.907959)
			(xy 245.721089 -52.853782) (xy 245.720616 -52.826412) (xy 245.721102 -52.799161) (xy 245.728858 -52.745213)
			(xy 245.744213 -52.692918) (xy 245.766855 -52.643341) (xy 245.796321 -52.597491) (xy 245.832012 -52.5563)
			(xy 245.873203 -52.520609) (xy 245.919053 -52.491143) (xy 245.96863 -52.468501) (xy 246.020925 -52.453146)
			(xy 246.074873 -52.44539) (xy 246.129375 -52.44539) (xy 246.183323 -52.453146) (xy 246.235618 -52.468501)
			(xy 246.285195 -52.491143) (xy 246.331045 -52.520609) (xy 246.372236 -52.5563) (xy 246.407927 -52.597491)
			(xy 246.437393 -52.643341) (xy 246.460035 -52.692918) (xy 246.47539 -52.745213) (xy 246.483146 -52.799161)
			(xy 246.483632 -52.826412) (xy 246.48319 -52.853783) (xy 246.475369 -52.907964) (xy 246.459875 -52.960468)
			(xy 246.437027 -53.010215) (xy 246.407297 -53.05618) (xy 246.389652 -53.07711) (xy 246.389398 -53.077364)
			(xy 246.38382 -53.084457) (xy 246.377568 -53.101369) (xy 246.377206 -53.110384) (xy 246.377206 -53.17744)
			(xy 246.377543 -53.186459) (xy 246.383804 -53.203376) (xy 246.389398 -53.21046) (xy 246.389652 -53.21046)
			(xy 246.389652 -53.210714) (xy 246.407305 -53.231637) (xy 246.437031 -53.277606) (xy 246.459877 -53.327354)
			(xy 246.475373 -53.379857) (xy 246.483201 -53.434038) (xy 246.4832 -53.48878) (xy 246.47537 -53.54296)
			(xy 246.459871 -53.595463) (xy 246.437023 -53.64521) (xy 246.407294 -53.691178) (xy 246.389652 -53.71211)
			(xy 246.389398 -53.712364) (xy 246.38382 -53.719457) (xy 246.377568 -53.736369) (xy 246.377206 -53.745384)
			(xy 246.377206 -53.81244) (xy 246.377543 -53.821459) (xy 246.383804 -53.838376) (xy 246.389398 -53.84546)
			(xy 246.389652 -53.84546) (xy 246.389652 -53.845714) (xy 246.407305 -53.866637) (xy 246.437031 -53.912606)
			(xy 246.459877 -53.962354) (xy 246.475373 -54.014857) (xy 246.483201 -54.069038) (xy 246.4832 -54.12378)
			(xy 246.47537 -54.17796) (xy 246.459871 -54.230463) (xy 246.437023 -54.28021) (xy 246.407294 -54.326178)
			(xy 246.389652 -54.34711) (xy 246.389398 -54.347364) (xy 246.38382 -54.354457) (xy 246.377568 -54.371369)
			(xy 246.377206 -54.380384) (xy 246.377206 -54.44744) (xy 246.377543 -54.456459) (xy 246.383804 -54.473376)
			(xy 246.389398 -54.48046) (xy 246.389652 -54.48046) (xy 246.389652 -54.480714) (xy 246.407257 -54.501674)
			(xy 246.436975 -54.547638) (xy 246.459819 -54.597379) (xy 246.475318 -54.649873) (xy 246.483154 -54.704045)
			(xy 246.483632 -54.731412) (xy 246.483146 -54.758663) (xy 246.478482 -54.791102) (xy 248.37644 -54.791102)
			(xy 248.376897 -54.763731) (xy 248.384716 -54.709552) (xy 248.400206 -54.657048) (xy 248.42305 -54.607301)
			(xy 248.452777 -54.561335) (xy 248.47042 -54.540404) (xy 248.470674 -54.54015) (xy 248.476254 -54.53306)
			(xy 248.482503 -54.516145) (xy 248.482866 -54.50713) (xy 248.482866 -54.440074) (xy 248.482529 -54.431055)
			(xy 248.476268 -54.414138) (xy 248.470674 -54.407054) (xy 248.47042 -54.407054) (xy 248.47042 -54.4068)
			(xy 248.452782 -54.385866) (xy 248.423057 -54.339898) (xy 248.400212 -54.290152) (xy 248.384716 -54.23765)
			(xy 248.376887 -54.183472) (xy 248.376887 -54.128731) (xy 248.384715 -54.074553) (xy 248.400211 -54.022051)
			(xy 248.423056 -53.972305) (xy 248.45278 -53.926337) (xy 248.47042 -53.905404) (xy 248.470674 -53.90515)
			(xy 248.476254 -53.89806) (xy 248.482503 -53.881145) (xy 248.482866 -53.87213) (xy 248.482866 -53.805074)
			(xy 248.482529 -53.796055) (xy 248.476268 -53.779138) (xy 248.470674 -53.772054) (xy 248.47042 -53.772054)
			(xy 248.47042 -53.7718) (xy 248.452782 -53.750866) (xy 248.423057 -53.704898) (xy 248.400212 -53.655152)
			(xy 248.384716 -53.60265) (xy 248.376887 -53.548472) (xy 248.376887 -53.493731) (xy 248.384715 -53.439553)
			(xy 248.400211 -53.387051) (xy 248.423056 -53.337305) (xy 248.45278 -53.291337) (xy 248.47042 -53.270404)
			(xy 248.470674 -53.27015) (xy 248.476254 -53.26306) (xy 248.482503 -53.246145) (xy 248.482866 -53.23713)
			(xy 248.482866 -53.170074) (xy 248.482529 -53.161055) (xy 248.476268 -53.144138) (xy 248.470674 -53.137054)
			(xy 248.47042 -53.137054) (xy 248.47042 -53.1368) (xy 248.452771 -53.115876) (xy 248.42306 -53.069901)
			(xy 248.400225 -53.020152) (xy 248.384737 -52.967649) (xy 248.376912 -52.913472) (xy 248.37644 -52.886102)
			(xy 248.376926 -52.858851) (xy 248.384682 -52.804903) (xy 248.400037 -52.752608) (xy 248.422679 -52.703031)
			(xy 248.452145 -52.657181) (xy 248.487836 -52.61599) (xy 248.529027 -52.580299) (xy 248.574877 -52.550833)
			(xy 248.624454 -52.528191) (xy 248.676749 -52.512836) (xy 248.730697 -52.50508) (xy 248.785199 -52.50508)
			(xy 248.839147 -52.512836) (xy 248.891442 -52.528191) (xy 248.930551 -52.546052) (xy 253.879573 -52.546052)
			(xy 253.879573 -52.491548) (xy 253.88733 -52.4376) (xy 253.902686 -52.385304) (xy 253.925327 -52.335726)
			(xy 253.954794 -52.289875) (xy 253.990487 -52.248684) (xy 254.031678 -52.212992) (xy 254.077529 -52.183525)
			(xy 254.127108 -52.160884) (xy 254.179403 -52.145529) (xy 254.233352 -52.137773) (xy 254.260604 -52.13731)
			(xy 254.287974 -52.137771) (xy 254.342154 -52.14559) (xy 254.394657 -52.16108) (xy 254.444404 -52.183923)
			(xy 254.49037 -52.213648) (xy 254.511302 -52.23129) (xy 254.511556 -52.231544) (xy 254.518647 -52.237124)
			(xy 254.535561 -52.243373) (xy 254.544576 -52.243736) (xy 254.611632 -52.243736) (xy 254.620649 -52.243387)
			(xy 254.637566 -52.237133) (xy 254.644652 -52.231544) (xy 254.644652 -52.23129) (xy 254.644906 -52.23129)
			(xy 254.665839 -52.213649) (xy 254.711807 -52.183925) (xy 254.761553 -52.161079) (xy 254.814055 -52.145583)
			(xy 254.868233 -52.137754) (xy 254.922975 -52.137754) (xy 254.977153 -52.145583) (xy 255.029655 -52.161079)
			(xy 255.079401 -52.183925) (xy 255.125369 -52.213649) (xy 255.146302 -52.23129) (xy 255.146556 -52.231544)
			(xy 255.153647 -52.237124) (xy 255.170561 -52.243373) (xy 255.179576 -52.243736) (xy 255.246632 -52.243736)
			(xy 255.255649 -52.243387) (xy 255.272566 -52.237133) (xy 255.279652 -52.231544) (xy 255.279652 -52.23129)
			(xy 255.279906 -52.23129) (xy 255.300824 -52.213633) (xy 255.346801 -52.183924) (xy 255.396552 -52.161092)
			(xy 255.449056 -52.145605) (xy 255.503234 -52.137782) (xy 255.530604 -52.13731) (xy 255.557856 -52.13776)
			(xy 255.611806 -52.145517) (xy 255.664103 -52.160874) (xy 255.713682 -52.183516) (xy 255.759534 -52.212984)
			(xy 255.800726 -52.248677) (xy 255.836419 -52.289869) (xy 255.865886 -52.335722) (xy 255.888528 -52.385301)
			(xy 255.903883 -52.437598) (xy 255.91164 -52.491548) (xy 255.91164 -52.546052) (xy 255.905695 -52.587398)
			(xy 256.955288 -52.587398) (xy 256.959359 -52.531776) (xy 256.971485 -52.477339) (xy 256.991408 -52.425248)
			(xy 257.018704 -52.376613) (xy 257.05279 -52.33247) (xy 257.092939 -52.293761) (xy 257.138297 -52.26131)
			(xy 257.187897 -52.235809) (xy 257.240681 -52.217802) (xy 257.295524 -52.207672) (xy 257.351258 -52.205635)
			(xy 257.406695 -52.211735) (xy 257.460652 -52.225841) (xy 257.511981 -52.247653) (xy 257.559587 -52.276707)
			(xy 257.602455 -52.312382) (xy 257.639672 -52.353919) (xy 257.670445 -52.400432) (xy 257.694117 -52.450929)
			(xy 257.710185 -52.504336) (xy 257.717781 -52.555952) (xy 264.783779 -52.555952) (xy 264.783779 -52.501448)
			(xy 264.791536 -52.447498) (xy 264.806893 -52.395202) (xy 264.829536 -52.345623) (xy 264.859004 -52.299772)
			(xy 264.894698 -52.258581) (xy 264.935891 -52.22289) (xy 264.981744 -52.193424) (xy 265.031324 -52.170784)
			(xy 265.083622 -52.155431) (xy 265.137572 -52.147678) (xy 265.164824 -52.147216) (xy 265.192195 -52.147664)
			(xy 265.246375 -52.155486) (xy 265.298878 -52.170979) (xy 265.348625 -52.193825) (xy 265.394591 -52.223553)
			(xy 265.415522 -52.241196) (xy 265.415776 -52.24145) (xy 265.422861 -52.247039) (xy 265.439779 -52.253283)
			(xy 265.448796 -52.253642) (xy 265.515852 -52.253642) (xy 265.524868 -52.253275) (xy 265.541786 -52.247036)
			(xy 265.548872 -52.24145) (xy 265.548872 -52.241196) (xy 265.549126 -52.241196) (xy 265.570075 -52.223578)
			(xy 265.616043 -52.193863) (xy 265.665786 -52.171023) (xy 265.718283 -52.155527) (xy 265.772456 -52.147693)
			(xy 265.799824 -52.147216) (xy 265.827076 -52.147655) (xy 265.881024 -52.155415) (xy 265.93332 -52.170773)
			(xy 265.982897 -52.193417) (xy 266.028747 -52.222886) (xy 266.069937 -52.25858) (xy 266.105628 -52.299772)
			(xy 266.135094 -52.345624) (xy 266.157735 -52.395203) (xy 266.17309 -52.447499) (xy 266.180846 -52.501448)
			(xy 266.180846 -52.555952) (xy 266.17309 -52.609901) (xy 266.157735 -52.662197) (xy 266.135094 -52.711776)
			(xy 266.105628 -52.757628) (xy 266.069937 -52.79882) (xy 266.028747 -52.834514) (xy 265.982897 -52.863983)
			(xy 265.93332 -52.886627) (xy 265.881024 -52.901985) (xy 265.827076 -52.909745) (xy 265.799824 -52.910232)
			(xy 265.772453 -52.909768) (xy 265.718274 -52.901953) (xy 265.66577 -52.886464) (xy 265.616023 -52.863621)
			(xy 265.570057 -52.833895) (xy 265.549126 -52.816252) (xy 265.548872 -52.815998) (xy 265.541769 -52.810435)
			(xy 265.524865 -52.804174) (xy 265.515852 -52.803806) (xy 265.448796 -52.803806) (xy 265.439779 -52.80416)
			(xy 265.422862 -52.810409) (xy 265.415776 -52.815998) (xy 265.415776 -52.816252) (xy 265.415522 -52.816252)
			(xy 265.394586 -52.833887) (xy 265.348615 -52.863601) (xy 265.298869 -52.886438) (xy 265.246369 -52.90193)
			(xy 265.192193 -52.909758) (xy 265.164824 -52.910232) (xy 265.137572 -52.909722) (xy 265.083622 -52.901969)
			(xy 265.031324 -52.886616) (xy 264.981744 -52.863976) (xy 264.935891 -52.83451) (xy 264.894698 -52.798819)
			(xy 264.859004 -52.757628) (xy 264.829536 -52.711777) (xy 264.806893 -52.662198) (xy 264.791536 -52.609902)
			(xy 264.783779 -52.555952) (xy 257.717781 -52.555952) (xy 257.718305 -52.559512) (xy 257.718814 -52.587398)
			(xy 257.718305 -52.615284) (xy 257.710185 -52.67046) (xy 257.694117 -52.723867) (xy 257.670445 -52.774364)
			(xy 257.639672 -52.820877) (xy 257.602455 -52.862414) (xy 257.559587 -52.898089) (xy 257.511981 -52.927143)
			(xy 257.460652 -52.948955) (xy 257.406695 -52.963061) (xy 257.351258 -52.969161) (xy 257.295524 -52.967124)
			(xy 257.240681 -52.956994) (xy 257.187897 -52.938987) (xy 257.138297 -52.913486) (xy 257.092939 -52.881035)
			(xy 257.05279 -52.842326) (xy 257.018704 -52.798183) (xy 256.991408 -52.749548) (xy 256.971485 -52.697457)
			(xy 256.959359 -52.64302) (xy 256.955288 -52.587398) (xy 255.905695 -52.587398) (xy 255.903883 -52.600002)
			(xy 255.888528 -52.652299) (xy 255.865886 -52.701878) (xy 255.836419 -52.747731) (xy 255.800726 -52.788923)
			(xy 255.759534 -52.824616) (xy 255.713682 -52.854084) (xy 255.664103 -52.876726) (xy 255.611806 -52.892083)
			(xy 255.557856 -52.89984) (xy 255.530604 -52.900326) (xy 255.503233 -52.899876) (xy 255.449053 -52.892057)
			(xy 255.396549 -52.876565) (xy 255.346802 -52.853719) (xy 255.300836 -52.82399) (xy 255.279906 -52.806346)
			(xy 255.279652 -52.806092) (xy 255.272555 -52.80052) (xy 255.255646 -52.794265) (xy 255.246632 -52.7939)
			(xy 255.179576 -52.7939) (xy 255.170558 -52.794246) (xy 255.153641 -52.800501) (xy 255.146556 -52.806092)
			(xy 255.146302 -52.806346) (xy 255.125369 -52.823987) (xy 255.079401 -52.853711) (xy 255.029655 -52.876557)
			(xy 254.977153 -52.892053) (xy 254.922975 -52.899882) (xy 254.868233 -52.899882) (xy 254.814055 -52.892053)
			(xy 254.761553 -52.876557) (xy 254.711807 -52.853711) (xy 254.665839 -52.823987) (xy 254.644906 -52.806346)
			(xy 254.644652 -52.806092) (xy 254.637555 -52.80052) (xy 254.620646 -52.794265) (xy 254.611632 -52.7939)
			(xy 254.544576 -52.7939) (xy 254.535558 -52.794246) (xy 254.518641 -52.800501) (xy 254.511556 -52.806092)
			(xy 254.511556 -52.806346) (xy 254.511302 -52.806346) (xy 254.490373 -52.823989) (xy 254.4444 -52.853702)
			(xy 254.394652 -52.876538) (xy 254.34215 -52.892028) (xy 254.287974 -52.899854) (xy 254.260604 -52.900326)
			(xy 254.233352 -52.899827) (xy 254.179403 -52.892071) (xy 254.127108 -52.876716) (xy 254.077529 -52.854075)
			(xy 254.031678 -52.824608) (xy 253.990487 -52.788916) (xy 253.954794 -52.747725) (xy 253.925327 -52.701874)
			(xy 253.902686 -52.652296) (xy 253.88733 -52.6) (xy 253.879573 -52.546052) (xy 248.930551 -52.546052)
			(xy 248.941019 -52.550833) (xy 248.986869 -52.580299) (xy 249.02806 -52.61599) (xy 249.063751 -52.657181)
			(xy 249.093217 -52.703031) (xy 249.115859 -52.752608) (xy 249.131214 -52.804903) (xy 249.13897 -52.858851)
			(xy 249.139456 -52.886102) (xy 249.139002 -52.913473) (xy 249.131183 -52.967653) (xy 249.115692 -53.020156)
			(xy 249.092847 -53.069903) (xy 249.063119 -53.115869) (xy 249.045476 -53.1368) (xy 249.045222 -53.137054)
			(xy 249.039639 -53.144143) (xy 249.033392 -53.161058) (xy 249.03303 -53.170074) (xy 249.03303 -53.23713)
			(xy 249.033366 -53.246149) (xy 249.039627 -53.263066) (xy 249.045222 -53.27015) (xy 249.045476 -53.27015)
			(xy 249.045476 -53.270404) (xy 249.063119 -53.291335) (xy 249.092843 -53.337303) (xy 249.115688 -53.38705)
			(xy 249.131184 -53.439552) (xy 249.139012 -53.493731) (xy 249.139012 -53.548472) (xy 249.131183 -53.602651)
			(xy 249.115687 -53.655153) (xy 249.092842 -53.704899) (xy 249.063117 -53.750867) (xy 249.046546 -53.77053)
			(xy 249.410728 -53.77053) (xy 249.411257 -53.741613) (xy 249.419983 -53.684442) (xy 249.437238 -53.629243)
			(xy 249.462627 -53.577281) (xy 249.495569 -53.529747) (xy 249.535309 -53.48773) (xy 249.557794 -53.46954)
			(xy 249.566572 -53.461905) (xy 249.576772 -53.441025) (xy 249.577352 -53.429408) (xy 249.577352 -53.349652)
			(xy 249.576843 -53.338016) (xy 249.566635 -53.317106) (xy 249.557794 -53.30952) (xy 249.535319 -53.291319)
			(xy 249.495583 -53.249301) (xy 249.462644 -53.201768) (xy 249.437254 -53.149809) (xy 249.419996 -53.094613)
			(xy 249.411264 -53.037445) (xy 249.410728 -53.00853) (xy 249.411183 -52.981276) (xy 249.418937 -52.927323)
			(xy 249.434291 -52.875023) (xy 249.456933 -52.825441) (xy 249.486401 -52.779586) (xy 249.522096 -52.738392)
			(xy 249.56329 -52.702697) (xy 249.609146 -52.67323) (xy 249.658729 -52.650589) (xy 249.711029 -52.635236)
			(xy 249.764982 -52.627483) (xy 249.792236 -52.627022) (xy 249.818551 -52.627458) (xy 249.870681 -52.634699)
			(xy 249.921325 -52.649023) (xy 249.969524 -52.670162) (xy 250.014367 -52.697713) (xy 250.055005 -52.731158)
			(xy 250.07316 -52.750212) (xy 250.080693 -52.7576) (xy 250.099964 -52.766132) (xy 250.110498 -52.766722)
			(xy 250.185174 -52.766722) (xy 250.195723 -52.766186) (xy 250.215018 -52.757655) (xy 250.222512 -52.750212)
			(xy 250.240671 -52.73116) (xy 250.2813 -52.697702) (xy 250.326139 -52.670142) (xy 250.374339 -52.649003)
			(xy 250.424986 -52.634685) (xy 250.47712 -52.62746) (xy 250.503436 -52.627022) (xy 250.53069 -52.627444)
			(xy 250.584641 -52.635207) (xy 250.636939 -52.650568) (xy 250.686518 -52.673215) (xy 250.73237 -52.702688)
			(xy 250.77356 -52.738386) (xy 250.809251 -52.779583) (xy 250.838716 -52.82544) (xy 250.861355 -52.875023)
			(xy 250.876707 -52.927324) (xy 250.88446 -52.981276) (xy 250.884944 -53.00853) (xy 250.884481 -53.036197)
			(xy 250.88225 -53.051456) (xy 259.141212 -53.051456) (xy 259.145283 -52.995834) (xy 259.157409 -52.941397)
			(xy 259.177332 -52.889306) (xy 259.204628 -52.840671) (xy 259.238714 -52.796528) (xy 259.278863 -52.757819)
			(xy 259.324221 -52.725368) (xy 259.373821 -52.699867) (xy 259.426605 -52.68186) (xy 259.481448 -52.67173)
			(xy 259.537182 -52.669693) (xy 259.592619 -52.675793) (xy 259.646576 -52.689899) (xy 259.697905 -52.711711)
			(xy 259.745511 -52.740765) (xy 259.788379 -52.77644) (xy 259.825596 -52.817977) (xy 259.856369 -52.86449)
			(xy 259.880041 -52.914987) (xy 259.896109 -52.968394) (xy 259.904229 -53.02357) (xy 259.904738 -53.051456)
			(xy 259.904229 -53.079342) (xy 259.896109 -53.134518) (xy 259.880041 -53.187925) (xy 259.856369 -53.238422)
			(xy 259.825596 -53.284935) (xy 259.788379 -53.326472) (xy 259.745511 -53.362147) (xy 259.697905 -53.391201)
			(xy 259.646576 -53.413013) (xy 259.592619 -53.427119) (xy 259.537182 -53.433219) (xy 259.481448 -53.431182)
			(xy 259.426605 -53.421052) (xy 259.373821 -53.403045) (xy 259.324221 -53.377544) (xy 259.278863 -53.345093)
			(xy 259.238714 -53.306384) (xy 259.204628 -53.262241) (xy 259.177332 -53.213606) (xy 259.157409 -53.161515)
			(xy 259.145283 -53.107078) (xy 259.141212 -53.051456) (xy 250.88225 -53.051456) (xy 250.876476 -53.09095)
			(xy 250.860653 -53.143974) (xy 250.837342 -53.194159) (xy 250.807033 -53.240454) (xy 250.770359 -53.28189)
			(xy 250.728089 -53.317599) (xy 250.704858 -53.332634) (xy 250.695169 -53.339256) (xy 250.68273 -53.359128)
			(xy 250.680982 -53.370734) (xy 250.673108 -53.450744) (xy 250.672469 -53.462382) (xy 250.680556 -53.484219)
			(xy 250.688602 -53.492654) (xy 250.688856 -53.492908) (xy 250.707415 -53.511011) (xy 250.739997 -53.551337)
			(xy 250.766814 -53.595707) (xy 250.787371 -53.643301) (xy 250.801289 -53.693242) (xy 250.80831 -53.744608)
			(xy 250.808744 -53.77053) (xy 250.80825 -53.79778) (xy 250.800491 -53.851726) (xy 250.785133 -53.904018)
			(xy 250.762491 -53.953593) (xy 250.733025 -53.999442) (xy 250.697335 -54.040631) (xy 250.656147 -54.076322)
			(xy 250.610299 -54.105789) (xy 250.560724 -54.128431) (xy 250.508432 -54.143789) (xy 250.454486 -54.15155)
			(xy 250.427236 -54.152038) (xy 250.399866 -54.151566) (xy 250.345686 -54.143752) (xy 250.293183 -54.128265)
			(xy 250.243436 -54.105424) (xy 250.197469 -54.0757) (xy 250.176538 -54.058058) (xy 250.176284 -54.057804)
			(xy 250.169206 -54.052205) (xy 250.152283 -54.045966) (xy 250.143264 -54.045612) (xy 250.076208 -54.045612)
			(xy 250.067191 -54.04597) (xy 250.050274 -54.052217) (xy 250.043188 -54.057804) (xy 250.043188 -54.058058)
			(xy 250.042934 -54.058058) (xy 250.021995 -54.075688) (xy 249.976024 -54.105403) (xy 249.926279 -54.128241)
			(xy 249.87378 -54.143734) (xy 249.819605 -54.151564) (xy 249.792236 -54.152038) (xy 249.764985 -54.151511)
			(xy 249.711038 -54.14376) (xy 249.658743 -54.12841) (xy 249.609165 -54.105774) (xy 249.563314 -54.076312)
			(xy 249.522121 -54.040625) (xy 249.486427 -53.999439) (xy 249.456958 -53.953593) (xy 249.434313 -53.904018)
			(xy 249.418954 -53.851726) (xy 249.411193 -53.797781) (xy 249.410728 -53.77053) (xy 249.046546 -53.77053)
			(xy 249.045476 -53.7718) (xy 249.045222 -53.772054) (xy 249.039639 -53.779143) (xy 249.033392 -53.796058)
			(xy 249.03303 -53.805074) (xy 249.03303 -53.87213) (xy 249.033366 -53.881149) (xy 249.039627 -53.898066)
			(xy 249.045222 -53.90515) (xy 249.045476 -53.90515) (xy 249.045476 -53.905404) (xy 249.063119 -53.926335)
			(xy 249.092843 -53.972303) (xy 249.115688 -54.02205) (xy 249.131184 -54.074552) (xy 249.139012 -54.128731)
			(xy 249.139012 -54.183472) (xy 249.131183 -54.237651) (xy 249.115687 -54.290153) (xy 249.101895 -54.320186)
			(xy 251.33046 -54.320186) (xy 251.330903 -54.292815) (xy 251.338724 -54.238634) (xy 251.354218 -54.18613)
			(xy 251.377065 -54.136384) (xy 251.406796 -54.090418) (xy 251.42444 -54.069488) (xy 251.424694 -54.069234)
			(xy 251.430272 -54.062141) (xy 251.436524 -54.045229) (xy 251.436886 -54.036214) (xy 251.436886 -53.969158)
			(xy 251.436504 -53.960144) (xy 251.430274 -53.943226) (xy 251.424694 -53.936138) (xy 251.42444 -53.936138)
			(xy 251.42444 -53.935884) (xy 251.406833 -53.914926) (xy 251.377115 -53.868961) (xy 251.354272 -53.81922)
			(xy 251.338774 -53.766725) (xy 251.330938 -53.712553) (xy 251.33046 -53.685186) (xy 251.330946 -53.657935)
			(xy 251.338702 -53.603987) (xy 251.354057 -53.551692) (xy 251.376699 -53.502115) (xy 251.406165 -53.456265)
			(xy 251.441856 -53.415074) (xy 251.483047 -53.379383) (xy 251.528897 -53.349917) (xy 251.578474 -53.327275)
			(xy 251.630769 -53.31192) (xy 251.684717 -53.304164) (xy 251.739219 -53.304164) (xy 251.793167 -53.31192)
			(xy 251.845462 -53.327275) (xy 251.895039 -53.349917) (xy 251.940889 -53.379383) (xy 251.98208 -53.415074)
			(xy 252.017771 -53.456265) (xy 252.043661 -53.496551) (xy 264.333464 -53.496551) (xy 264.333464 -53.442049)
			(xy 264.34122 -53.3881) (xy 264.356575 -53.335805) (xy 264.379216 -53.286227) (xy 264.408681 -53.240376)
			(xy 264.444372 -53.199185) (xy 264.485562 -53.163492) (xy 264.531412 -53.134024) (xy 264.580988 -53.111381)
			(xy 264.633283 -53.096024) (xy 264.687231 -53.088265) (xy 264.714482 -53.087778) (xy 264.741853 -53.088236)
			(xy 264.796033 -53.096053) (xy 264.848537 -53.111543) (xy 264.898284 -53.134387) (xy 264.944249 -53.164115)
			(xy 264.96518 -53.181758) (xy 264.965434 -53.182012) (xy 264.972534 -53.187578) (xy 264.989441 -53.193837)
			(xy 264.998454 -53.194204) (xy 265.06551 -53.194204) (xy 265.074527 -53.193851) (xy 265.091444 -53.1876)
			(xy 265.09853 -53.182012) (xy 265.09853 -53.181758) (xy 265.098784 -53.181758) (xy 265.119706 -53.164106)
			(xy 265.165682 -53.134397) (xy 265.215432 -53.111565) (xy 265.267935 -53.096076) (xy 265.322112 -53.08825)
			(xy 265.349482 -53.087778) (xy 265.376735 -53.088268) (xy 265.430686 -53.096023) (xy 265.482984 -53.111377)
			(xy 265.532564 -53.134017) (xy 265.578418 -53.163484) (xy 265.619611 -53.199176) (xy 265.655306 -53.240368)
			(xy 265.684774 -53.28622) (xy 265.707417 -53.335799) (xy 265.722773 -53.388097) (xy 265.730531 -53.442047)
			(xy 265.730531 -53.496553) (xy 265.722773 -53.550503) (xy 265.707417 -53.602801) (xy 265.684774 -53.65238)
			(xy 265.655306 -53.698232) (xy 265.619611 -53.739424) (xy 265.578418 -53.775116) (xy 265.532564 -53.804583)
			(xy 265.482984 -53.827223) (xy 265.430686 -53.842577) (xy 265.376735 -53.850332) (xy 265.349482 -53.850794)
			(xy 265.322111 -53.85034) (xy 265.267932 -53.842519) (xy 265.215428 -53.827028) (xy 265.165682 -53.804183)
			(xy 265.119715 -53.774456) (xy 265.098784 -53.756814) (xy 265.09853 -53.75656) (xy 265.091443 -53.750975)
			(xy 265.074526 -53.744728) (xy 265.06551 -53.744368) (xy 264.998454 -53.744368) (xy 264.989441 -53.744758)
			(xy 264.972524 -53.750983) (xy 264.965434 -53.75656) (xy 264.965434 -53.756814) (xy 264.96518 -53.756814)
			(xy 264.94423 -53.774431) (xy 264.898262 -53.804146) (xy 264.848519 -53.826986) (xy 264.796022 -53.842482)
			(xy 264.74185 -53.850316) (xy 264.714482 -53.850794) (xy 264.687231 -53.850335) (xy 264.633283 -53.842576)
			(xy 264.580988 -53.827219) (xy 264.531412 -53.804576) (xy 264.485562 -53.775108) (xy 264.444372 -53.739415)
			(xy 264.408681 -53.698224) (xy 264.379216 -53.652373) (xy 264.356575 -53.602795) (xy 264.34122 -53.5505)
			(xy 264.333464 -53.496551) (xy 252.043661 -53.496551) (xy 252.047237 -53.502115) (xy 252.069879 -53.551692)
			(xy 252.085234 -53.603987) (xy 252.09299 -53.657935) (xy 252.093476 -53.685186) (xy 252.093008 -53.712556)
			(xy 252.085191 -53.766735) (xy 252.069703 -53.819239) (xy 252.046862 -53.868986) (xy 252.017137 -53.914952)
			(xy 251.999496 -53.935884) (xy 251.999242 -53.936138) (xy 251.993668 -53.943233) (xy 251.987415 -53.960144)
			(xy 251.98705 -53.969158) (xy 251.98705 -54.036214) (xy 251.98739 -54.045233) (xy 251.993648 -54.06215)
			(xy 251.999242 -54.069234) (xy 251.999496 -54.069234) (xy 251.999496 -54.069488) (xy 252.017142 -54.090414)
			(xy 252.046853 -54.136389) (xy 252.069688 -54.186138) (xy 252.085177 -54.23864) (xy 252.093003 -54.292816)
			(xy 252.093476 -54.320186) (xy 252.09299 -54.347437) (xy 252.085234 -54.401385) (xy 252.069879 -54.45368)
			(xy 252.047237 -54.503257) (xy 252.017771 -54.549107) (xy 251.98208 -54.590298) (xy 251.940889 -54.625989)
			(xy 251.895039 -54.655455) (xy 251.845462 -54.678097) (xy 251.793167 -54.693452) (xy 251.739219 -54.701208)
			(xy 251.684717 -54.701208) (xy 251.630769 -54.693452) (xy 251.578474 -54.678097) (xy 251.528897 -54.655455)
			(xy 251.483047 -54.625989) (xy 251.441856 -54.590298) (xy 251.406165 -54.549107) (xy 251.376699 -54.503257)
			(xy 251.354057 -54.45368) (xy 251.338702 -54.401385) (xy 251.330946 -54.347437) (xy 251.33046 -54.320186)
			(xy 249.101895 -54.320186) (xy 249.092842 -54.339899) (xy 249.063117 -54.385867) (xy 249.045476 -54.4068)
			(xy 249.045222 -54.407054) (xy 249.039639 -54.414143) (xy 249.033392 -54.431058) (xy 249.03303 -54.440074)
			(xy 249.03303 -54.50713) (xy 249.033366 -54.516149) (xy 249.039627 -54.533066) (xy 249.045222 -54.54015)
			(xy 249.045476 -54.54015) (xy 249.045476 -54.540404) (xy 249.063127 -54.561327) (xy 249.092838 -54.607302)
			(xy 249.115672 -54.657052) (xy 249.13116 -54.709554) (xy 249.138984 -54.763732) (xy 249.139101 -54.770528)
			(xy 252.271022 -54.770528) (xy 252.271499 -54.743158) (xy 252.279313 -54.688979) (xy 252.2948 -54.636476)
			(xy 252.317639 -54.586729) (xy 252.347362 -54.540762) (xy 252.365002 -54.51983) (xy 252.365256 -54.519576)
			(xy 252.370865 -54.512505) (xy 252.377097 -54.495576) (xy 252.377448 -54.486556) (xy 252.377448 -54.4195)
			(xy 252.377102 -54.410482) (xy 252.370848 -54.393564) (xy 252.365256 -54.38648) (xy 252.365002 -54.38648)
			(xy 252.365002 -54.386226) (xy 252.347362 -54.365295) (xy 252.31765 -54.319322) (xy 252.294814 -54.269574)
			(xy 252.279324 -54.217073) (xy 252.271496 -54.162897) (xy 252.271022 -54.135528) (xy 252.271508 -54.108277)
			(xy 252.279264 -54.054329) (xy 252.294619 -54.002034) (xy 252.317261 -53.952457) (xy 252.346727 -53.906607)
			(xy 252.382418 -53.865416) (xy 252.423609 -53.829725) (xy 252.469459 -53.800259) (xy 252.519036 -53.777617)
			(xy 252.571331 -53.762262) (xy 252.625279 -53.754506) (xy 252.679781 -53.754506) (xy 252.733729 -53.762262)
			(xy 252.786024 -53.777617) (xy 252.835601 -53.800259) (xy 252.881451 -53.829725) (xy 252.922642 -53.865416)
			(xy 252.958333 -53.906607) (xy 252.987799 -53.952457) (xy 252.992874 -53.96357) (xy 256.972052 -53.96357)
			(xy 256.976123 -53.907948) (xy 256.988249 -53.853511) (xy 257.008172 -53.80142) (xy 257.035468 -53.752785)
			(xy 257.069554 -53.708642) (xy 257.109703 -53.669933) (xy 257.155061 -53.637482) (xy 257.204661 -53.611981)
			(xy 257.257445 -53.593974) (xy 257.312288 -53.583844) (xy 257.368022 -53.581807) (xy 257.423459 -53.587907)
			(xy 257.477416 -53.602013) (xy 257.528745 -53.623825) (xy 257.576351 -53.652879) (xy 257.619219 -53.688554)
			(xy 257.656436 -53.730091) (xy 257.687209 -53.776604) (xy 257.710881 -53.827101) (xy 257.726949 -53.880508)
			(xy 257.735069 -53.935684) (xy 257.735578 -53.96357) (xy 257.735069 -53.991456) (xy 257.726949 -54.046632)
			(xy 257.710881 -54.100039) (xy 257.687209 -54.150536) (xy 257.656436 -54.197049) (xy 257.619219 -54.238586)
			(xy 257.576351 -54.274261) (xy 257.528745 -54.303315) (xy 257.477416 -54.325127) (xy 257.423459 -54.339233)
			(xy 257.368022 -54.345333) (xy 257.312288 -54.343296) (xy 257.257445 -54.333166) (xy 257.204661 -54.315159)
			(xy 257.155061 -54.289658) (xy 257.109703 -54.257207) (xy 257.069554 -54.218498) (xy 257.035468 -54.174355)
			(xy 257.008172 -54.12572) (xy 256.988249 -54.073629) (xy 256.976123 -54.019192) (xy 256.972052 -53.96357)
			(xy 252.992874 -53.96357) (xy 253.010441 -54.002034) (xy 253.025796 -54.054329) (xy 253.033552 -54.108277)
			(xy 253.034038 -54.135528) (xy 253.033603 -54.1629) (xy 253.02578 -54.217081) (xy 253.010285 -54.269585)
			(xy 252.987436 -54.319331) (xy 252.957703 -54.365296) (xy 252.940058 -54.386226) (xy 252.939804 -54.38648)
			(xy 252.93422 -54.393568) (xy 252.927972 -54.410484) (xy 252.927612 -54.4195) (xy 252.927612 -54.486556)
			(xy 252.927988 -54.495571) (xy 252.934222 -54.512488) (xy 252.939804 -54.519576) (xy 252.940058 -54.519576)
			(xy 252.940058 -54.51983) (xy 252.957671 -54.540783) (xy 252.987388 -54.586749) (xy 253.01023 -54.636492)
			(xy 253.025727 -54.688988) (xy 253.033561 -54.74316) (xy 253.034038 -54.770528) (xy 253.033552 -54.797779)
			(xy 253.025796 -54.851727) (xy 253.010441 -54.904022) (xy 252.987799 -54.953599) (xy 252.965015 -54.989051)
			(xy 262.101068 -54.989051) (xy 262.101068 -54.934549) (xy 262.108824 -54.880602) (xy 262.124178 -54.828308)
			(xy 262.146818 -54.778731) (xy 262.176283 -54.732881) (xy 262.211973 -54.69169) (xy 262.253161 -54.655997)
			(xy 262.29901 -54.62653) (xy 262.348585 -54.603887) (xy 262.400879 -54.588529) (xy 262.454825 -54.580769)
			(xy 262.482076 -54.580282) (xy 262.510167 -54.580796) (xy 262.565743 -54.58902) (xy 262.619512 -54.605307)
			(xy 262.670309 -54.629307) (xy 262.717036 -54.660499) (xy 262.758682 -54.698208) (xy 262.794345 -54.741619)
			(xy 262.809228 -54.765448) (xy 262.814562 -54.774338) (xy 262.83158 -54.78653) (xy 262.924798 -54.80685)
			(xy 262.945372 -54.802532) (xy 262.954008 -54.79669) (xy 262.978068 -54.780683) (xy 263.030001 -54.755342)
			(xy 263.08516 -54.738119) (xy 263.142285 -54.729406) (xy 263.171178 -54.728872) (xy 263.198429 -54.729376)
			(xy 263.252378 -54.737129) (xy 263.304674 -54.752481) (xy 263.354252 -54.77512) (xy 263.400105 -54.804584)
			(xy 263.441297 -54.840273) (xy 263.476991 -54.881462) (xy 263.50646 -54.927311) (xy 263.529104 -54.976887)
			(xy 263.544462 -55.029181) (xy 263.552221 -55.083129) (xy 263.552686 -55.11038) (xy 263.552212 -55.13775)
			(xy 263.544396 -55.191929) (xy 263.528909 -55.244432) (xy 263.506069 -55.294179) (xy 263.476346 -55.340146)
			(xy 263.458706 -55.361078) (xy 263.458452 -55.361332) (xy 263.452882 -55.36843) (xy 263.446627 -55.385338)
			(xy 263.44626 -55.394352) (xy 263.44626 -55.461408) (xy 263.4466 -55.470427) (xy 263.452858 -55.487344)
			(xy 263.458452 -55.494428) (xy 263.458706 -55.494428) (xy 263.458706 -55.494682) (xy 263.476326 -55.515631)
			(xy 263.506049 -55.561597) (xy 263.528893 -55.611341) (xy 263.54439 -55.66384) (xy 263.552219 -55.718016)
			(xy 263.552222 -55.772754) (xy 263.544396 -55.826931) (xy 263.528904 -55.879431) (xy 263.506063 -55.929177)
			(xy 263.476344 -55.975145) (xy 263.458706 -55.996078) (xy 263.458452 -55.996332) (xy 263.452882 -56.00343)
			(xy 263.446627 -56.020338) (xy 263.44626 -56.029352) (xy 263.44626 -56.096408) (xy 263.4466 -56.105427)
			(xy 263.452858 -56.122344) (xy 263.458452 -56.129428) (xy 263.458706 -56.129428) (xy 263.458706 -56.129682)
			(xy 263.476351 -56.150609) (xy 263.506062 -56.196583) (xy 263.528896 -56.246332) (xy 263.544386 -56.298834)
			(xy 263.552213 -56.353011) (xy 263.552686 -56.38038) (xy 263.5522 -56.407631) (xy 263.544444 -56.461579)
			(xy 263.529089 -56.513874) (xy 263.506447 -56.563451) (xy 263.476981 -56.609301) (xy 263.44129 -56.650492)
			(xy 263.400099 -56.686183) (xy 263.354249 -56.715649) (xy 263.304672 -56.738291) (xy 263.252377 -56.753646)
			(xy 263.198429 -56.761402) (xy 263.143927 -56.761402) (xy 263.089979 -56.753646) (xy 263.037684 -56.738291)
			(xy 262.988107 -56.715649) (xy 262.942257 -56.686183) (xy 262.901066 -56.650492) (xy 262.865375 -56.609301)
			(xy 262.835909 -56.563451) (xy 262.813267 -56.513874) (xy 262.797912 -56.461579) (xy 262.790156 -56.407631)
			(xy 262.78967 -56.38038) (xy 262.790107 -56.353009) (xy 262.797929 -56.298828) (xy 262.813424 -56.246323)
			(xy 262.836273 -56.196577) (xy 262.866005 -56.150612) (xy 262.88365 -56.129682) (xy 262.883904 -56.129428)
			(xy 262.889485 -56.122338) (xy 262.895735 -56.105424) (xy 262.896096 -56.096408) (xy 262.896096 -56.029352)
			(xy 262.895715 -56.020338) (xy 262.889484 -56.00342) (xy 262.883904 -55.996332) (xy 262.88365 -55.996332)
			(xy 262.88365 -55.996078) (xy 262.865989 -55.975162) (xy 262.836263 -55.929192) (xy 262.813417 -55.879443)
			(xy 262.797922 -55.826938) (xy 262.790094 -55.772757) (xy 262.790097 -55.718013) (xy 262.797928 -55.663833)
			(xy 262.813428 -55.611329) (xy 262.836278 -55.561582) (xy 262.866007 -55.515614) (xy 262.88365 -55.494682)
			(xy 262.883904 -55.494428) (xy 262.889485 -55.487338) (xy 262.895735 -55.470424) (xy 262.896096 -55.461408)
			(xy 262.896096 -55.394352) (xy 262.895715 -55.385338) (xy 262.889484 -55.36842) (xy 262.883904 -55.361332)
			(xy 262.88365 -55.360824) (xy 262.872704 -55.348092) (xy 262.852864 -55.320999) (xy 262.844026 -55.306722)
			(xy 262.838692 -55.297832) (xy 262.821674 -55.28564) (xy 262.728456 -55.26532) (xy 262.707882 -55.269638)
			(xy 262.699246 -55.27548) (xy 262.67517 -55.29146) (xy 262.623243 -55.316808) (xy 262.568089 -55.334039)
			(xy 262.510967 -55.34276) (xy 262.482076 -55.343298) (xy 262.454825 -55.342831) (xy 262.400879 -55.335071)
			(xy 262.348585 -55.319713) (xy 262.29901 -55.29707) (xy 262.253161 -55.267603) (xy 262.211973 -55.23191)
			(xy 262.176283 -55.190719) (xy 262.146818 -55.144869) (xy 262.124178 -55.095292) (xy 262.108824 -55.042998)
			(xy 262.101068 -54.989051) (xy 252.965015 -54.989051) (xy 252.958333 -54.999449) (xy 252.922642 -55.04064)
			(xy 252.881451 -55.076331) (xy 252.835601 -55.105797) (xy 252.786024 -55.128439) (xy 252.733729 -55.143794)
			(xy 252.679781 -55.15155) (xy 252.625279 -55.15155) (xy 252.571331 -55.143794) (xy 252.519036 -55.128439)
			(xy 252.469459 -55.105797) (xy 252.423609 -55.076331) (xy 252.382418 -55.04064) (xy 252.346727 -54.999449)
			(xy 252.317261 -54.953599) (xy 252.294619 -54.904022) (xy 252.279264 -54.851727) (xy 252.271508 -54.797779)
			(xy 252.271022 -54.770528) (xy 249.139101 -54.770528) (xy 249.139456 -54.791102) (xy 249.13897 -54.818353)
			(xy 249.131214 -54.872301) (xy 249.115859 -54.924596) (xy 249.093217 -54.974173) (xy 249.063751 -55.020023)
			(xy 249.02806 -55.061214) (xy 248.986869 -55.096905) (xy 248.941019 -55.126371) (xy 248.891442 -55.149013)
			(xy 248.839147 -55.164368) (xy 248.785199 -55.172124) (xy 248.730697 -55.172124) (xy 248.676749 -55.164368)
			(xy 248.624454 -55.149013) (xy 248.574877 -55.126371) (xy 248.529027 -55.096905) (xy 248.487836 -55.061214)
			(xy 248.452145 -55.020023) (xy 248.422679 -54.974173) (xy 248.400037 -54.924596) (xy 248.384682 -54.872301)
			(xy 248.376926 -54.818353) (xy 248.37644 -54.791102) (xy 246.478482 -54.791102) (xy 246.47539 -54.812611)
			(xy 246.460035 -54.864906) (xy 246.437393 -54.914483) (xy 246.407927 -54.960333) (xy 246.372236 -55.001524)
			(xy 246.331045 -55.037215) (xy 246.285195 -55.066681) (xy 246.235618 -55.089323) (xy 246.183323 -55.104678)
			(xy 246.129375 -55.112434) (xy 246.074873 -55.112434) (xy 246.020925 -55.104678) (xy 245.96863 -55.089323)
			(xy 245.919053 -55.066681) (xy 245.873203 -55.037215) (xy 245.832012 -55.001524) (xy 245.796321 -54.960333)
			(xy 245.766855 -54.914483) (xy 245.744213 -54.864906) (xy 245.728858 -54.812611) (xy 245.721102 -54.758663)
			(xy 245.720616 -54.731412) (xy 241.720641 -54.731412) (xy 241.725957 -54.767534) (xy 241.726466 -54.79542)
			(xy 241.725957 -54.823306) (xy 241.717837 -54.878482) (xy 241.701769 -54.931889) (xy 241.678097 -54.982386)
			(xy 241.647324 -55.028899) (xy 241.610107 -55.070436) (xy 241.567239 -55.106111) (xy 241.519633 -55.135165)
			(xy 241.468304 -55.156977) (xy 241.414347 -55.171083) (xy 241.35891 -55.177183) (xy 241.303176 -55.175146)
			(xy 241.248333 -55.165016) (xy 241.195549 -55.147009) (xy 241.145949 -55.121508) (xy 241.100591 -55.089057)
			(xy 241.060442 -55.050348) (xy 241.026356 -55.006205) (xy 240.99906 -54.95757) (xy 240.979137 -54.905479)
			(xy 240.967011 -54.851042) (xy 240.96294 -54.79542) (xy 239.69496 -54.79542) (xy 239.694465 -54.822544)
			(xy 239.686345 -54.87772) (xy 239.670277 -54.931127) (xy 239.646605 -54.981624) (xy 239.615832 -55.028137)
			(xy 239.578615 -55.069674) (xy 239.535747 -55.105349) (xy 239.488141 -55.134403) (xy 239.436812 -55.156215)
			(xy 239.382855 -55.170321) (xy 239.327418 -55.176421) (xy 239.271684 -55.174384) (xy 239.216841 -55.164254)
			(xy 239.164057 -55.146247) (xy 239.114457 -55.120746) (xy 239.069099 -55.088295) (xy 239.02895 -55.049586)
			(xy 238.994864 -55.005443) (xy 238.967568 -54.956808) (xy 238.947645 -54.904717) (xy 238.935519 -54.85028)
			(xy 238.931448 -54.794658) (xy 226.477308 -54.794658) (xy 226.489527 -55.408068) (xy 237.462312 -55.408068)
			(xy 237.466383 -55.352446) (xy 237.478509 -55.298009) (xy 237.498432 -55.245918) (xy 237.525728 -55.197283)
			(xy 237.559814 -55.15314) (xy 237.599963 -55.114431) (xy 237.645321 -55.08198) (xy 237.694921 -55.056479)
			(xy 237.747705 -55.038472) (xy 237.802548 -55.028342) (xy 237.858282 -55.026305) (xy 237.913719 -55.032405)
			(xy 237.967676 -55.046511) (xy 238.019005 -55.068323) (xy 238.066611 -55.097377) (xy 238.109479 -55.133052)
			(xy 238.146696 -55.174589) (xy 238.177469 -55.221102) (xy 238.201141 -55.271599) (xy 238.217209 -55.325006)
			(xy 238.225329 -55.380182) (xy 238.225838 -55.408068) (xy 238.225329 -55.435954) (xy 238.217209 -55.49113)
			(xy 238.201141 -55.544537) (xy 238.177469 -55.595034) (xy 238.146696 -55.641547) (xy 238.109479 -55.683084)
			(xy 238.066611 -55.718759) (xy 238.060865 -55.722266) (xy 258.034026 -55.722266) (xy 258.038097 -55.666644)
			(xy 258.050223 -55.612207) (xy 258.070146 -55.560116) (xy 258.097442 -55.511481) (xy 258.131528 -55.467338)
			(xy 258.171677 -55.428629) (xy 258.217035 -55.396178) (xy 258.266635 -55.370677) (xy 258.319419 -55.35267)
			(xy 258.374262 -55.34254) (xy 258.429996 -55.340503) (xy 258.485433 -55.346603) (xy 258.53939 -55.360709)
			(xy 258.590719 -55.382521) (xy 258.638325 -55.411575) (xy 258.649471 -55.420851) (xy 260.424668 -55.420851)
			(xy 260.424668 -55.366349) (xy 260.432424 -55.312402) (xy 260.447778 -55.260108) (xy 260.470418 -55.210531)
			(xy 260.499883 -55.164681) (xy 260.535573 -55.12349) (xy 260.576761 -55.087797) (xy 260.62261 -55.05833)
			(xy 260.672185 -55.035687) (xy 260.724479 -55.020329) (xy 260.778425 -55.012569) (xy 260.805676 -55.012082)
			(xy 260.831989 -55.012571) (xy 260.884116 -55.019802) (xy 260.934759 -55.034118) (xy 260.982958 -55.055246)
			(xy 261.027802 -55.082788) (xy 261.068442 -55.116222) (xy 261.0866 -55.135272) (xy 261.094123 -55.142672)
			(xy 261.113402 -55.151198) (xy 261.123938 -55.151782) (xy 261.198614 -55.151782) (xy 261.209167 -55.151279)
			(xy 261.228462 -55.142726) (xy 261.235952 -55.135272) (xy 261.254084 -55.116193) (xy 261.294719 -55.082739)
			(xy 261.339565 -55.055184) (xy 261.38777 -55.03405) (xy 261.438421 -55.019737) (xy 261.490559 -55.012518)
			(xy 261.516876 -55.012082) (xy 261.544129 -55.012564) (xy 261.598081 -55.020318) (xy 261.650381 -55.035671)
			(xy 261.699963 -55.058312) (xy 261.745817 -55.087778) (xy 261.787012 -55.123471) (xy 261.822707 -55.164663)
			(xy 261.852177 -55.210516) (xy 261.87482 -55.260097) (xy 261.890177 -55.312395) (xy 261.897935 -55.366347)
			(xy 261.897935 -55.420853) (xy 261.890177 -55.474805) (xy 261.87482 -55.527103) (xy 261.852177 -55.576684)
			(xy 261.822707 -55.622537) (xy 261.787012 -55.663729) (xy 261.745817 -55.699422) (xy 261.699963 -55.728888)
			(xy 261.650381 -55.751529) (xy 261.598081 -55.766882) (xy 261.544129 -55.774636) (xy 261.516876 -55.775098)
			(xy 261.490561 -55.774647) (xy 261.438432 -55.767409) (xy 261.387789 -55.753087) (xy 261.33959 -55.731951)
			(xy 261.294747 -55.704402) (xy 261.254108 -55.670961) (xy 261.235952 -55.651908) (xy 261.228449 -55.644484)
			(xy 261.209155 -55.635972) (xy 261.198614 -55.635398) (xy 261.123938 -55.635398) (xy 261.113389 -55.635935)
			(xy 261.094094 -55.644465) (xy 261.0866 -55.651908) (xy 261.068439 -55.670958) (xy 261.02781 -55.704415)
			(xy 260.982971 -55.731975) (xy 260.934771 -55.753114) (xy 260.884125 -55.767433) (xy 260.831992 -55.774659)
			(xy 260.805676 -55.775098) (xy 260.778425 -55.774631) (xy 260.724479 -55.766871) (xy 260.672185 -55.751513)
			(xy 260.62261 -55.72887) (xy 260.576761 -55.699403) (xy 260.535573 -55.66371) (xy 260.499883 -55.622519)
			(xy 260.470418 -55.576669) (xy 260.447778 -55.527092) (xy 260.432424 -55.474798) (xy 260.424668 -55.420851)
			(xy 258.649471 -55.420851) (xy 258.681193 -55.44725) (xy 258.71841 -55.488787) (xy 258.749183 -55.5353)
			(xy 258.772855 -55.585797) (xy 258.788923 -55.639204) (xy 258.797043 -55.69438) (xy 258.797552 -55.722266)
			(xy 258.797043 -55.750152) (xy 258.788923 -55.805328) (xy 258.772855 -55.858735) (xy 258.749183 -55.909232)
			(xy 258.71841 -55.955745) (xy 258.681193 -55.997282) (xy 258.638325 -56.032957) (xy 258.590719 -56.062011)
			(xy 258.53939 -56.083823) (xy 258.485433 -56.097929) (xy 258.429996 -56.104029) (xy 258.374262 -56.101992)
			(xy 258.319419 -56.091862) (xy 258.266635 -56.073855) (xy 258.217035 -56.048354) (xy 258.171677 -56.015903)
			(xy 258.131528 -55.977194) (xy 258.097442 -55.933051) (xy 258.070146 -55.884416) (xy 258.050223 -55.832325)
			(xy 258.038097 -55.777888) (xy 258.034026 -55.722266) (xy 238.060865 -55.722266) (xy 238.019005 -55.747813)
			(xy 237.967676 -55.769625) (xy 237.913719 -55.783731) (xy 237.858282 -55.789831) (xy 237.802548 -55.787794)
			(xy 237.747705 -55.777664) (xy 237.694921 -55.759657) (xy 237.645321 -55.734156) (xy 237.599963 -55.701705)
			(xy 237.559814 -55.662996) (xy 237.525728 -55.618853) (xy 237.498432 -55.570218) (xy 237.478509 -55.518127)
			(xy 237.466383 -55.46369) (xy 237.462312 -55.408068) (xy 226.489527 -55.408068) (xy 226.518583 -56.86679)
			(xy 240.166142 -56.86679) (xy 240.170213 -56.811168) (xy 240.182339 -56.756731) (xy 240.202262 -56.70464)
			(xy 240.229558 -56.656005) (xy 240.263644 -56.611862) (xy 240.303793 -56.573153) (xy 240.349151 -56.540702)
			(xy 240.398751 -56.515201) (xy 240.451535 -56.497194) (xy 240.506378 -56.487064) (xy 240.562112 -56.485027)
			(xy 240.617549 -56.491127) (xy 240.671506 -56.505233) (xy 240.722835 -56.527045) (xy 240.770441 -56.556099)
			(xy 240.813309 -56.591774) (xy 240.850526 -56.633311) (xy 240.881299 -56.679824) (xy 240.904971 -56.730321)
			(xy 240.921039 -56.783728) (xy 240.929159 -56.838904) (xy 240.929668 -56.86679) (xy 240.929159 -56.894676)
			(xy 240.921039 -56.949852) (xy 240.905069 -57.002934) (xy 253.763526 -57.002934) (xy 253.764026 -56.974842)
			(xy 253.77225 -56.919265) (xy 253.788538 -56.865495) (xy 253.81254 -56.814696) (xy 253.843734 -56.767969)
			(xy 253.881447 -56.726325) (xy 253.924861 -56.690664) (xy 253.948692 -56.675782) (xy 253.957582 -56.670448)
			(xy 253.969774 -56.65343) (xy 253.990094 -56.560212) (xy 253.985776 -56.539638) (xy 253.979934 -56.531002)
			(xy 253.963937 -56.506936) (xy 253.938592 -56.455006) (xy 253.921366 -56.399848) (xy 253.91265 -56.342724)
			(xy 253.912116 -56.313832) (xy 253.912585 -56.286579) (xy 253.920338 -56.232627) (xy 253.935692 -56.180328)
			(xy 253.958332 -56.130746) (xy 253.987799 -56.084892) (xy 254.023492 -56.043698) (xy 254.064685 -56.008004)
			(xy 254.110539 -55.978536) (xy 254.16012 -55.955894) (xy 254.212419 -55.94054) (xy 254.266371 -55.932786)
			(xy 254.293624 -55.932324) (xy 254.320995 -55.93277) (xy 254.375175 -55.940592) (xy 254.427679 -55.956085)
			(xy 254.477425 -55.978932) (xy 254.523391 -56.008661) (xy 254.544322 -56.026304) (xy 254.544576 -56.026558)
			(xy 254.55166 -56.032148) (xy 254.568579 -56.038391) (xy 254.577596 -56.03875) (xy 254.644652 -56.03875)
			(xy 254.653668 -56.038381) (xy 254.670586 -56.032143) (xy 254.677672 -56.026558) (xy 254.677672 -56.026304)
			(xy 254.677926 -56.026304) (xy 254.698859 -56.008663) (xy 254.744827 -55.978939) (xy 254.794573 -55.956093)
			(xy 254.847075 -55.940597) (xy 254.901253 -55.932768) (xy 254.955995 -55.932768) (xy 255.010173 -55.940597)
			(xy 255.062675 -55.956093) (xy 255.112421 -55.978939) (xy 255.158389 -56.008663) (xy 255.179322 -56.026304)
			(xy 255.179576 -56.026558) (xy 255.18666 -56.032148) (xy 255.203579 -56.038391) (xy 255.212596 -56.03875)
			(xy 255.279652 -56.03875) (xy 255.288668 -56.038381) (xy 255.305586 -56.032143) (xy 255.312672 -56.026558)
			(xy 255.312672 -56.026304) (xy 255.312926 -56.026304) (xy 255.333876 -56.008687) (xy 255.379844 -55.978971)
			(xy 255.429587 -55.956131) (xy 255.482083 -55.940635) (xy 255.536256 -55.932801) (xy 255.563624 -55.932324)
			(xy 255.590876 -55.932747) (xy 255.644826 -55.940507) (xy 255.697122 -55.955866) (xy 255.746701 -55.97851)
			(xy 255.792552 -56.00798) (xy 255.833743 -56.043674) (xy 255.869435 -56.084867) (xy 255.898901 -56.13072)
			(xy 255.921542 -56.1803) (xy 255.936898 -56.232597) (xy 255.944654 -56.286548) (xy 255.944654 -56.297068)
			(xy 256.286506 -56.297068) (xy 256.290577 -56.241446) (xy 256.302703 -56.187009) (xy 256.322626 -56.134918)
			(xy 256.349922 -56.086283) (xy 256.384008 -56.04214) (xy 256.424157 -56.003431) (xy 256.469515 -55.97098)
			(xy 256.519115 -55.945479) (xy 256.571899 -55.927472) (xy 256.626742 -55.917342) (xy 256.682476 -55.915305)
			(xy 256.737913 -55.921405) (xy 256.79187 -55.935511) (xy 256.843199 -55.957323) (xy 256.890805 -55.986377)
			(xy 256.933673 -56.022052) (xy 256.97089 -56.063589) (xy 257.001663 -56.110102) (xy 257.025335 -56.160599)
			(xy 257.041403 -56.214006) (xy 257.049523 -56.269182) (xy 257.050032 -56.297068) (xy 257.049523 -56.324954)
			(xy 257.041403 -56.38013) (xy 257.025335 -56.433537) (xy 257.001663 -56.484034) (xy 256.97089 -56.530547)
			(xy 256.933673 -56.572084) (xy 256.890805 -56.607759) (xy 256.843199 -56.636813) (xy 256.79187 -56.658625)
			(xy 256.737913 -56.672731) (xy 256.682476 -56.678831) (xy 256.626742 -56.676794) (xy 256.571899 -56.666664)
			(xy 256.519115 -56.648657) (xy 256.469515 -56.623156) (xy 256.424157 -56.590705) (xy 256.384008 -56.551996)
			(xy 256.349922 -56.507853) (xy 256.322626 -56.459218) (xy 256.302703 -56.407127) (xy 256.290577 -56.35269)
			(xy 256.286506 -56.297068) (xy 255.944654 -56.297068) (xy 255.944654 -56.341052) (xy 255.936898 -56.395003)
			(xy 255.921542 -56.4473) (xy 255.898901 -56.49688) (xy 255.869435 -56.542733) (xy 255.833743 -56.583926)
			(xy 255.792552 -56.61962) (xy 255.746701 -56.64909) (xy 255.697122 -56.671734) (xy 255.644826 -56.687093)
			(xy 255.590876 -56.694853) (xy 255.563624 -56.69534) (xy 255.536254 -56.694874) (xy 255.482074 -56.687059)
			(xy 255.42957 -56.67157) (xy 255.379823 -56.648728) (xy 255.333857 -56.619002) (xy 255.312926 -56.60136)
			(xy 255.312672 -56.601106) (xy 255.305568 -56.595544) (xy 255.288665 -56.589282) (xy 255.279652 -56.588914)
			(xy 255.212596 -56.588914) (xy 255.203579 -56.589266) (xy 255.186661 -56.595517) (xy 255.179576 -56.601106)
			(xy 255.179576 -56.60136) (xy 255.179322 -56.60136) (xy 255.158389 -56.619001) (xy 255.112421 -56.648725)
			(xy 255.062675 -56.671571) (xy 255.010173 -56.687067) (xy 254.955995 -56.694896) (xy 254.901253 -56.694896)
			(xy 254.847075 -56.687067) (xy 254.794573 -56.671571) (xy 254.744827 -56.648725) (xy 254.698859 -56.619001)
			(xy 254.677926 -56.60136) (xy 254.677672 -56.601106) (xy 254.670568 -56.595544) (xy 254.653665 -56.589282)
			(xy 254.644652 -56.588914) (xy 254.577596 -56.588914) (xy 254.568579 -56.589266) (xy 254.551661 -56.595517)
			(xy 254.544576 -56.601106) (xy 254.544068 -56.60136) (xy 254.531333 -56.612303) (xy 254.504242 -56.632145)
			(xy 254.489966 -56.640984) (xy 254.481076 -56.646318) (xy 254.468884 -56.663336) (xy 254.448564 -56.756554)
			(xy 254.452882 -56.777128) (xy 254.458724 -56.785764) (xy 254.474714 -56.809834) (xy 254.500058 -56.861764)
			(xy 254.517286 -56.91692) (xy 254.526005 -56.974042) (xy 254.526542 -57.002934) (xy 254.526056 -57.030185)
			(xy 254.5183 -57.084133) (xy 254.502945 -57.136428) (xy 254.480303 -57.186005) (xy 254.450837 -57.231855)
			(xy 254.415146 -57.273046) (xy 254.373955 -57.308737) (xy 254.328105 -57.338203) (xy 254.278528 -57.360845)
			(xy 254.226233 -57.3762) (xy 254.172285 -57.383956) (xy 254.117783 -57.383956) (xy 254.063835 -57.3762)
			(xy 254.01154 -57.360845) (xy 253.961963 -57.338203) (xy 253.916113 -57.308737) (xy 253.874922 -57.273046)
			(xy 253.839231 -57.231855) (xy 253.809765 -57.186005) (xy 253.787123 -57.136428) (xy 253.771768 -57.084133)
			(xy 253.764012 -57.030185) (xy 253.763526 -57.002934) (xy 240.905069 -57.002934) (xy 240.904971 -57.003259)
			(xy 240.881299 -57.053756) (xy 240.850526 -57.100269) (xy 240.813309 -57.141806) (xy 240.770441 -57.177481)
			(xy 240.722835 -57.206535) (xy 240.671506 -57.228347) (xy 240.617549 -57.242453) (xy 240.562112 -57.248553)
			(xy 240.506378 -57.246516) (xy 240.451535 -57.236386) (xy 240.398751 -57.218379) (xy 240.349151 -57.192878)
			(xy 240.303793 -57.160427) (xy 240.263644 -57.121718) (xy 240.229558 -57.077575) (xy 240.202262 -57.02894)
			(xy 240.182339 -56.976849) (xy 240.170213 -56.922412) (xy 240.166142 -56.86679) (xy 226.518583 -56.86679)
			(xy 226.520248 -56.950356) (xy 226.520248 -56.971184) (xy 226.519673 -57.019434) (xy 226.510383 -57.115487)
			(xy 226.501706 -57.162954) (xy 226.20101 -58.698471) (xy 229.808523 -58.698471) (xy 229.808523 -58.601777)
			(xy 229.816508 -58.505414) (xy 229.832424 -58.410039) (xy 229.85616 -58.316305) (xy 229.887557 -58.22485)
			(xy 229.926398 -58.136301) (xy 229.972419 -58.051261) (xy 230.025305 -57.970313) (xy 230.084696 -57.894008)
			(xy 230.150184 -57.822868) (xy 230.221324 -57.75738) (xy 230.297629 -57.697989) (xy 230.378577 -57.645103)
			(xy 230.463617 -57.599082) (xy 230.552166 -57.560241) (xy 230.643621 -57.528844) (xy 230.737355 -57.505108)
			(xy 230.83273 -57.489192) (xy 230.929093 -57.481207) (xy 231.025787 -57.481207) (xy 231.07494 -57.48528)
			(xy 262.805924 -57.48528) (xy 262.809995 -57.429658) (xy 262.822121 -57.375221) (xy 262.842044 -57.32313)
			(xy 262.86934 -57.274495) (xy 262.903426 -57.230352) (xy 262.943575 -57.191643) (xy 262.988933 -57.159192)
			(xy 263.038533 -57.133691) (xy 263.091317 -57.115684) (xy 263.14616 -57.105554) (xy 263.201894 -57.103517)
			(xy 263.257331 -57.109617) (xy 263.311288 -57.123723) (xy 263.362617 -57.145535) (xy 263.410223 -57.174589)
			(xy 263.453091 -57.210264) (xy 263.490308 -57.251801) (xy 263.521081 -57.298314) (xy 263.544753 -57.348811)
			(xy 263.560821 -57.402218) (xy 263.568941 -57.457394) (xy 263.56945 -57.48528) (xy 263.568941 -57.513166)
			(xy 263.560821 -57.568342) (xy 263.544753 -57.621749) (xy 263.521081 -57.672246) (xy 263.490308 -57.718759)
			(xy 263.453091 -57.760296) (xy 263.410223 -57.795971) (xy 263.362617 -57.825025) (xy 263.311288 -57.846837)
			(xy 263.257331 -57.860943) (xy 263.201894 -57.867043) (xy 263.14616 -57.865006) (xy 263.091317 -57.854876)
			(xy 263.038533 -57.836869) (xy 262.988933 -57.811368) (xy 262.943575 -57.778917) (xy 262.903426 -57.740208)
			(xy 262.86934 -57.696065) (xy 262.842044 -57.64743) (xy 262.822121 -57.595339) (xy 262.809995 -57.540902)
			(xy 262.805924 -57.48528) (xy 231.07494 -57.48528) (xy 231.12215 -57.489192) (xy 231.217525 -57.505108)
			(xy 231.311259 -57.528844) (xy 231.402714 -57.560241) (xy 231.491263 -57.599082) (xy 231.576303 -57.645103)
			(xy 231.657251 -57.697989) (xy 231.733556 -57.75738) (xy 231.804696 -57.822868) (xy 231.870184 -57.894008)
			(xy 231.929575 -57.970313) (xy 231.982461 -58.051261) (xy 232.028482 -58.136301) (xy 232.067323 -58.22485)
			(xy 232.087929 -58.284872) (xy 240.598196 -58.284872) (xy 240.602267 -58.22925) (xy 240.614393 -58.174813)
			(xy 240.634316 -58.122722) (xy 240.661612 -58.074087) (xy 240.695698 -58.029944) (xy 240.735847 -57.991235)
			(xy 240.781205 -57.958784) (xy 240.830805 -57.933283) (xy 240.883589 -57.915276) (xy 240.938432 -57.905146)
			(xy 240.994166 -57.903109) (xy 241.049603 -57.909209) (xy 241.10356 -57.923315) (xy 241.154889 -57.945127)
			(xy 241.202495 -57.974181) (xy 241.245363 -58.009856) (xy 241.28258 -58.051393) (xy 241.313353 -58.097906)
			(xy 241.337025 -58.148403) (xy 241.353093 -58.20181) (xy 241.361213 -58.256986) (xy 241.361722 -58.284872)
			(xy 241.361213 -58.312758) (xy 241.353093 -58.367934) (xy 241.337025 -58.421341) (xy 241.313353 -58.471838)
			(xy 241.28258 -58.518351) (xy 241.245363 -58.559888) (xy 241.202495 -58.595563) (xy 241.154889 -58.624617)
			(xy 241.10356 -58.646429) (xy 241.049603 -58.660535) (xy 240.994166 -58.666635) (xy 240.938432 -58.664598)
			(xy 240.883589 -58.654468) (xy 240.830805 -58.636461) (xy 240.781205 -58.61096) (xy 240.735847 -58.578509)
			(xy 240.695698 -58.5398) (xy 240.661612 -58.495657) (xy 240.634316 -58.447022) (xy 240.614393 -58.394931)
			(xy 240.602267 -58.340494) (xy 240.598196 -58.284872) (xy 232.087929 -58.284872) (xy 232.09872 -58.316305)
			(xy 232.122456 -58.410039) (xy 232.138372 -58.505414) (xy 232.146357 -58.601777) (xy 232.146856 -58.650124)
			(xy 232.146555 -58.679334) (xy 254.195326 -58.679334) (xy 254.195741 -58.653018) (xy 254.202985 -58.600887)
			(xy 254.217314 -58.550243) (xy 254.238456 -58.502044) (xy 254.266012 -58.457202) (xy 254.29946 -58.416565)
			(xy 254.318516 -58.39841) (xy 254.325918 -58.390889) (xy 254.334442 -58.371608) (xy 254.335026 -58.361072)
			(xy 254.335026 -58.286396) (xy 254.334505 -58.275846) (xy 254.325963 -58.256551) (xy 254.318516 -58.249058)
			(xy 254.29945 -58.230913) (xy 254.265993 -58.190281) (xy 254.238435 -58.145439) (xy 254.217298 -58.097236)
			(xy 254.202984 -58.046587) (xy 254.195762 -57.994451) (xy 254.195326 -57.968134) (xy 254.195812 -57.940883)
			(xy 254.203568 -57.886935) (xy 254.218923 -57.83464) (xy 254.241565 -57.785063) (xy 254.271031 -57.739213)
			(xy 254.306722 -57.698022) (xy 254.347913 -57.662331) (xy 254.393763 -57.632865) (xy 254.44334 -57.610223)
			(xy 254.495635 -57.594868) (xy 254.549583 -57.587112) (xy 254.604085 -57.587112) (xy 254.658033 -57.594868)
			(xy 254.710328 -57.610223) (xy 254.759905 -57.632865) (xy 254.805755 -57.662331) (xy 254.846946 -57.698022)
			(xy 254.882637 -57.739213) (xy 254.912103 -57.785063) (xy 254.934745 -57.83464) (xy 254.9501 -57.886935)
			(xy 254.957856 -57.940883) (xy 254.958342 -57.968134) (xy 254.957916 -57.99445) (xy 254.950675 -58.046581)
			(xy 254.943407 -58.072274) (xy 258.193538 -58.072274) (xy 258.197609 -58.016652) (xy 258.209735 -57.962215)
			(xy 258.229658 -57.910124) (xy 258.256954 -57.861489) (xy 258.29104 -57.817346) (xy 258.331189 -57.778637)
			(xy 258.376547 -57.746186) (xy 258.426147 -57.720685) (xy 258.478931 -57.702678) (xy 258.533774 -57.692548)
			(xy 258.589508 -57.690511) (xy 258.644945 -57.696611) (xy 258.698902 -57.710717) (xy 258.750231 -57.732529)
			(xy 258.797837 -57.761583) (xy 258.840705 -57.797258) (xy 258.877922 -57.838795) (xy 258.908695 -57.885308)
			(xy 258.932367 -57.935805) (xy 258.948435 -57.989212) (xy 258.956555 -58.044388) (xy 258.957064 -58.072274)
			(xy 258.956994 -58.076084) (xy 263.558018 -58.076084) (xy 263.562089 -58.020462) (xy 263.574215 -57.966025)
			(xy 263.594138 -57.913934) (xy 263.621434 -57.865299) (xy 263.65552 -57.821156) (xy 263.695669 -57.782447)
			(xy 263.741027 -57.749996) (xy 263.790627 -57.724495) (xy 263.843411 -57.706488) (xy 263.898254 -57.696358)
			(xy 263.953988 -57.694321) (xy 264.009425 -57.700421) (xy 264.063382 -57.714527) (xy 264.114711 -57.736339)
			(xy 264.162317 -57.765393) (xy 264.205185 -57.801068) (xy 264.242402 -57.842605) (xy 264.258738 -57.867296)
			(xy 265.843002 -57.867296) (xy 265.847073 -57.811674) (xy 265.859199 -57.757237) (xy 265.879122 -57.705146)
			(xy 265.906418 -57.656511) (xy 265.940504 -57.612368) (xy 265.980653 -57.573659) (xy 266.026011 -57.541208)
			(xy 266.075611 -57.515707) (xy 266.128395 -57.4977) (xy 266.183238 -57.48757) (xy 266.238972 -57.485533)
			(xy 266.294409 -57.491633) (xy 266.348366 -57.505739) (xy 266.399695 -57.527551) (xy 266.447301 -57.556605)
			(xy 266.490169 -57.59228) (xy 266.527386 -57.633817) (xy 266.558159 -57.68033) (xy 266.581831 -57.730827)
			(xy 266.597899 -57.784234) (xy 266.606019 -57.83941) (xy 266.606528 -57.867296) (xy 266.606019 -57.895182)
			(xy 266.597899 -57.950358) (xy 266.581831 -58.003765) (xy 266.558159 -58.054262) (xy 266.527386 -58.100775)
			(xy 266.490169 -58.142312) (xy 266.447301 -58.177987) (xy 266.399695 -58.207041) (xy 266.348366 -58.228853)
			(xy 266.294409 -58.242959) (xy 266.238972 -58.249059) (xy 266.183238 -58.247022) (xy 266.128395 -58.236892)
			(xy 266.075611 -58.218885) (xy 266.026011 -58.193384) (xy 265.980653 -58.160933) (xy 265.940504 -58.122224)
			(xy 265.906418 -58.078081) (xy 265.879122 -58.029446) (xy 265.859199 -57.977355) (xy 265.847073 -57.922918)
			(xy 265.843002 -57.867296) (xy 264.258738 -57.867296) (xy 264.273175 -57.889118) (xy 264.296847 -57.939615)
			(xy 264.312915 -57.993022) (xy 264.321035 -58.048198) (xy 264.321544 -58.076084) (xy 264.321035 -58.10397)
			(xy 264.312915 -58.159146) (xy 264.296847 -58.212553) (xy 264.273175 -58.26305) (xy 264.242402 -58.309563)
			(xy 264.205185 -58.3511) (xy 264.162317 -58.386775) (xy 264.114711 -58.415829) (xy 264.063382 -58.437641)
			(xy 264.009425 -58.451747) (xy 263.953988 -58.457847) (xy 263.898254 -58.45581) (xy 263.843411 -58.44568)
			(xy 263.790627 -58.427673) (xy 263.741027 -58.402172) (xy 263.695669 -58.369721) (xy 263.65552 -58.331012)
			(xy 263.621434 -58.286869) (xy 263.594138 -58.238234) (xy 263.574215 -58.186143) (xy 263.562089 -58.131706)
			(xy 263.558018 -58.076084) (xy 258.956994 -58.076084) (xy 258.956555 -58.10016) (xy 258.948435 -58.155336)
			(xy 258.932367 -58.208743) (xy 258.908695 -58.25924) (xy 258.877922 -58.305753) (xy 258.840705 -58.34729)
			(xy 258.797837 -58.382965) (xy 258.750231 -58.412019) (xy 258.698902 -58.433831) (xy 258.644945 -58.447937)
			(xy 258.589508 -58.454037) (xy 258.533774 -58.452) (xy 258.478931 -58.44187) (xy 258.426147 -58.423863)
			(xy 258.376547 -58.398362) (xy 258.331189 -58.365911) (xy 258.29104 -58.327202) (xy 258.256954 -58.283059)
			(xy 258.229658 -58.234424) (xy 258.209735 -58.182333) (xy 258.197609 -58.127896) (xy 258.193538 -58.072274)
			(xy 254.943407 -58.072274) (xy 254.936349 -58.097225) (xy 254.915209 -58.145424) (xy 254.887655 -58.190266)
			(xy 254.854208 -58.230903) (xy 254.835152 -58.249058) (xy 254.827775 -58.2566) (xy 254.819235 -58.275864)
			(xy 254.818642 -58.286396) (xy 254.818642 -58.361072) (xy 254.819161 -58.371623) (xy 254.827702 -58.390919)
			(xy 254.835152 -58.39841) (xy 254.854215 -58.416558) (xy 254.88767 -58.45719) (xy 254.915226 -58.502032)
			(xy 254.936363 -58.550235) (xy 254.939469 -58.561224) (xy 264.762232 -58.561224) (xy 264.766303 -58.505602)
			(xy 264.778429 -58.451165) (xy 264.798352 -58.399074) (xy 264.825648 -58.350439) (xy 264.859734 -58.306296)
			(xy 264.899883 -58.267587) (xy 264.945241 -58.235136) (xy 264.994841 -58.209635) (xy 265.047625 -58.191628)
			(xy 265.102468 -58.181498) (xy 265.158202 -58.179461) (xy 265.213639 -58.185561) (xy 265.267596 -58.199667)
			(xy 265.318925 -58.221479) (xy 265.366531 -58.250533) (xy 265.409399 -58.286208) (xy 265.446616 -58.327745)
			(xy 265.477389 -58.374258) (xy 265.501061 -58.424755) (xy 265.517129 -58.478162) (xy 265.525249 -58.533338)
			(xy 265.525758 -58.561224) (xy 265.525249 -58.58911) (xy 265.517129 -58.644286) (xy 265.501061 -58.697693)
			(xy 265.477389 -58.74819) (xy 265.446616 -58.794703) (xy 265.409399 -58.83624) (xy 265.366531 -58.871915)
			(xy 265.318925 -58.900969) (xy 265.267596 -58.922781) (xy 265.213639 -58.936887) (xy 265.158202 -58.942987)
			(xy 265.102468 -58.94095) (xy 265.047625 -58.93082) (xy 264.994841 -58.912813) (xy 264.945241 -58.887312)
			(xy 264.899883 -58.854861) (xy 264.859734 -58.816152) (xy 264.825648 -58.772009) (xy 264.798352 -58.723374)
			(xy 264.778429 -58.671283) (xy 264.766303 -58.616846) (xy 264.762232 -58.561224) (xy 254.939469 -58.561224)
			(xy 254.950679 -58.600883) (xy 254.957904 -58.653018) (xy 254.958342 -58.679334) (xy 254.957856 -58.706585)
			(xy 254.9501 -58.760533) (xy 254.934745 -58.812828) (xy 254.912103 -58.862405) (xy 254.882637 -58.908255)
			(xy 254.846946 -58.949446) (xy 254.805755 -58.985137) (xy 254.759905 -59.014603) (xy 254.710328 -59.037245)
			(xy 254.658033 -59.0526) (xy 254.604085 -59.060356) (xy 254.549583 -59.060356) (xy 254.495635 -59.0526)
			(xy 254.44334 -59.037245) (xy 254.393763 -59.014603) (xy 254.347913 -58.985137) (xy 254.306722 -58.949446)
			(xy 254.271031 -58.908255) (xy 254.241565 -58.862405) (xy 254.218923 -58.812828) (xy 254.203568 -58.760533)
			(xy 254.195812 -58.706585) (xy 254.195326 -58.679334) (xy 232.146555 -58.679334) (xy 232.146357 -58.698471)
			(xy 232.138372 -58.794834) (xy 232.122456 -58.890209) (xy 232.09872 -58.983943) (xy 232.067323 -59.075398)
			(xy 232.028482 -59.163947) (xy 232.022699 -59.174634) (xy 263.293096 -59.174634) (xy 263.297167 -59.119012)
			(xy 263.309293 -59.064575) (xy 263.329216 -59.012484) (xy 263.356512 -58.963849) (xy 263.390598 -58.919706)
			(xy 263.430747 -58.880997) (xy 263.476105 -58.848546) (xy 263.525705 -58.823045) (xy 263.578489 -58.805038)
			(xy 263.633332 -58.794908) (xy 263.689066 -58.792871) (xy 263.744503 -58.798971) (xy 263.79846 -58.813077)
			(xy 263.849789 -58.834889) (xy 263.897395 -58.863943) (xy 263.940263 -58.899618) (xy 263.97748 -58.941155)
			(xy 264.008253 -58.987668) (xy 264.031925 -59.038165) (xy 264.047993 -59.091572) (xy 264.056113 -59.146748)
			(xy 264.056622 -59.174634) (xy 264.056113 -59.20252) (xy 264.047993 -59.257696) (xy 264.031925 -59.311103)
			(xy 264.008253 -59.3616) (xy 263.97748 -59.408113) (xy 263.940263 -59.44965) (xy 263.897395 -59.485325)
			(xy 263.849789 -59.514379) (xy 263.79846 -59.536191) (xy 263.744503 -59.550297) (xy 263.689066 -59.556397)
			(xy 263.633332 -59.55436) (xy 263.578489 -59.54423) (xy 263.525705 -59.526223) (xy 263.476105 -59.500722)
			(xy 263.430747 -59.468271) (xy 263.390598 -59.429562) (xy 263.356512 -59.385419) (xy 263.329216 -59.336784)
			(xy 263.309293 -59.284693) (xy 263.297167 -59.230256) (xy 263.293096 -59.174634) (xy 232.022699 -59.174634)
			(xy 231.982461 -59.248987) (xy 231.929575 -59.329935) (xy 231.870184 -59.40624) (xy 231.804696 -59.47738)
			(xy 231.733556 -59.542868) (xy 231.657251 -59.602259) (xy 231.576303 -59.655145) (xy 231.491263 -59.701166)
			(xy 231.402714 -59.740007) (xy 231.311259 -59.771404) (xy 231.217525 -59.79514) (xy 231.12215 -59.811056)
			(xy 231.025787 -59.819041) (xy 230.929093 -59.819041) (xy 230.83273 -59.811056) (xy 230.737355 -59.79514)
			(xy 230.643621 -59.771404) (xy 230.552166 -59.740007) (xy 230.463617 -59.701166) (xy 230.378577 -59.655145)
			(xy 230.297629 -59.602259) (xy 230.221324 -59.542868) (xy 230.150184 -59.47738) (xy 230.084696 -59.40624)
			(xy 230.025305 -59.329935) (xy 229.972419 -59.248987) (xy 229.926398 -59.163947) (xy 229.887557 -59.075398)
			(xy 229.85616 -58.983943) (xy 229.832424 -58.890209) (xy 229.816508 -58.794834) (xy 229.808523 -58.698471)
			(xy 226.20101 -58.698471) (xy 225.920294 -60.13196) (xy 226.436428 -60.13196) (xy 226.436428 -59.26836)
			(xy 226.436918 -59.238392) (xy 226.444741 -59.17897) (xy 226.460254 -59.121077) (xy 226.48319 -59.065704)
			(xy 226.513157 -59.013798) (xy 226.549644 -58.966248) (xy 226.592024 -58.923868) (xy 226.639574 -58.887381)
			(xy 226.69148 -58.857414) (xy 226.746853 -58.834478) (xy 226.804746 -58.818965) (xy 226.864168 -58.811142)
			(xy 226.924104 -58.811142) (xy 226.983526 -58.818965) (xy 227.041419 -58.834478) (xy 227.096792 -58.857414)
			(xy 227.148698 -58.887381) (xy 227.196248 -58.923868) (xy 227.238628 -58.966248) (xy 227.275115 -59.013798)
			(xy 227.305082 -59.065704) (xy 227.328018 -59.121077) (xy 227.343531 -59.17897) (xy 227.351354 -59.238392)
			(xy 227.351844 -59.26836) (xy 227.351844 -60.01925) (xy 254.335784 -60.01925) (xy 254.335784 -59.96475)
			(xy 254.34354 -59.910804) (xy 254.358894 -59.858511) (xy 254.381534 -59.808935) (xy 254.410999 -59.763086)
			(xy 254.446688 -59.721897) (xy 254.487877 -59.686206) (xy 254.533725 -59.65674) (xy 254.5833 -59.634098)
			(xy 254.635592 -59.618742) (xy 254.689538 -59.610985) (xy 254.716788 -59.610498) (xy 254.744158 -59.610972)
			(xy 254.798337 -59.618788) (xy 254.85084 -59.634275) (xy 254.900587 -59.657115) (xy 254.946554 -59.686838)
			(xy 254.967486 -59.704478) (xy 254.96774 -59.704732) (xy 254.974837 -59.710303) (xy 254.991746 -59.716558)
			(xy 255.00076 -59.716924) (xy 255.067816 -59.716924) (xy 255.076833 -59.716569) (xy 255.09375 -59.710319)
			(xy 255.100836 -59.704732) (xy 255.100836 -59.704478) (xy 255.10109 -59.704478) (xy 255.122023 -59.686837)
			(xy 255.167991 -59.657113) (xy 255.217737 -59.634267) (xy 255.270239 -59.618771) (xy 255.324417 -59.610942)
			(xy 255.379159 -59.610942) (xy 255.433337 -59.618771) (xy 255.485839 -59.634267) (xy 255.535585 -59.657113)
			(xy 255.581553 -59.686837) (xy 255.602486 -59.704478) (xy 255.60274 -59.704732) (xy 255.609837 -59.710303)
			(xy 255.626746 -59.716558) (xy 255.63576 -59.716924) (xy 255.702816 -59.716924) (xy 255.711833 -59.716569)
			(xy 255.72875 -59.710319) (xy 255.735836 -59.704732) (xy 255.735836 -59.704478) (xy 255.73609 -59.704478)
			(xy 255.757012 -59.686827) (xy 255.802988 -59.657117) (xy 255.852738 -59.634284) (xy 255.905241 -59.618796)
			(xy 255.959418 -59.610971) (xy 255.986788 -59.610498) (xy 256.014042 -59.610949) (xy 256.067995 -59.618704)
			(xy 256.120295 -59.634059) (xy 256.169877 -59.656702) (xy 256.215733 -59.68617) (xy 256.256928 -59.721864)
			(xy 256.292623 -59.763058) (xy 256.322093 -59.808912) (xy 256.344736 -59.858494) (xy 256.360093 -59.910793)
			(xy 256.367851 -59.964746) (xy 256.367851 -60.019254) (xy 256.360093 -60.073207) (xy 256.344736 -60.125506)
			(xy 256.322093 -60.175088) (xy 256.292623 -60.220942) (xy 256.256928 -60.262136) (xy 256.215733 -60.29783)
			(xy 256.169877 -60.327298) (xy 256.120295 -60.349941) (xy 256.067995 -60.365296) (xy 256.014042 -60.373051)
			(xy 255.986788 -60.373514) (xy 255.959418 -60.373052) (xy 255.905239 -60.365232) (xy 255.852736 -60.349742)
			(xy 255.802989 -60.3269) (xy 255.757022 -60.297175) (xy 255.73609 -60.279534) (xy 255.735836 -60.27928)
			(xy 255.728745 -60.2737) (xy 255.711832 -60.26745) (xy 255.702816 -60.267088) (xy 255.63576 -60.267088)
			(xy 255.626741 -60.267428) (xy 255.609825 -60.273688) (xy 255.60274 -60.27928) (xy 255.602486 -60.279534)
			(xy 255.581553 -60.297175) (xy 255.535585 -60.326899) (xy 255.485839 -60.349745) (xy 255.433337 -60.365241)
			(xy 255.379159 -60.37307) (xy 255.324417 -60.37307) (xy 255.270239 -60.365241) (xy 255.217737 -60.349745)
			(xy 255.167991 -60.326899) (xy 255.122023 -60.297175) (xy 255.10109 -60.279534) (xy 255.100836 -60.27928)
			(xy 255.093745 -60.2737) (xy 255.076832 -60.26745) (xy 255.067816 -60.267088) (xy 255.00076 -60.267088)
			(xy 254.991741 -60.267428) (xy 254.974825 -60.273688) (xy 254.96774 -60.27928) (xy 254.96774 -60.279534)
			(xy 254.967486 -60.279534) (xy 254.946537 -60.297152) (xy 254.900568 -60.326865) (xy 254.850825 -60.349705)
			(xy 254.798328 -60.365201) (xy 254.744156 -60.373036) (xy 254.716788 -60.373514) (xy 254.689538 -60.373015)
			(xy 254.635592 -60.365258) (xy 254.5833 -60.349902) (xy 254.533725 -60.32726) (xy 254.487877 -60.297794)
			(xy 254.446688 -60.262103) (xy 254.410999 -60.220914) (xy 254.381534 -60.175065) (xy 254.358894 -60.125489)
			(xy 254.34354 -60.073196) (xy 254.335784 -60.01925) (xy 227.351844 -60.01925) (xy 227.351844 -60.13196)
			(xy 227.351354 -60.161928) (xy 227.343531 -60.22135) (xy 227.328018 -60.279243) (xy 227.305082 -60.334616)
			(xy 227.275115 -60.386522) (xy 227.238628 -60.434072) (xy 227.196248 -60.476452) (xy 227.148698 -60.512939)
			(xy 227.096792 -60.542906) (xy 227.041419 -60.565842) (xy 226.983526 -60.581355) (xy 226.924104 -60.589178)
			(xy 226.864168 -60.589178) (xy 226.804746 -60.581355) (xy 226.746853 -60.565842) (xy 226.69148 -60.542906)
			(xy 226.639574 -60.512939) (xy 226.592024 -60.476452) (xy 226.549644 -60.434072) (xy 226.513157 -60.386522)
			(xy 226.48319 -60.334616) (xy 226.460254 -60.279243) (xy 226.444741 -60.22135) (xy 226.436918 -60.161928)
			(xy 226.436428 -60.13196) (xy 225.920294 -60.13196) (xy 225.711136 -61.20003) (xy 233.19054 -61.20003)
			(xy 233.194611 -61.144408) (xy 233.206737 -61.089971) (xy 233.22666 -61.03788) (xy 233.253956 -60.989245)
			(xy 233.288042 -60.945102) (xy 233.328191 -60.906393) (xy 233.373549 -60.873942) (xy 233.423149 -60.848441)
			(xy 233.475933 -60.830434) (xy 233.530776 -60.820304) (xy 233.58651 -60.818267) (xy 233.641947 -60.824367)
			(xy 233.695904 -60.838473) (xy 233.747233 -60.860285) (xy 233.794839 -60.889339) (xy 233.832134 -60.920376)
			(xy 239.456974 -60.920376) (xy 239.461045 -60.864754) (xy 239.473171 -60.810317) (xy 239.493094 -60.758226)
			(xy 239.52039 -60.709591) (xy 239.554476 -60.665448) (xy 239.594625 -60.626739) (xy 239.639983 -60.594288)
			(xy 239.689583 -60.568787) (xy 239.742367 -60.55078) (xy 239.79721 -60.54065) (xy 239.852944 -60.538613)
			(xy 239.908381 -60.544713) (xy 239.962338 -60.558819) (xy 240.013667 -60.580631) (xy 240.061273 -60.609685)
			(xy 240.089717 -60.633356) (xy 265.996926 -60.633356) (xy 266.000997 -60.577734) (xy 266.013123 -60.523297)
			(xy 266.033046 -60.471206) (xy 266.060342 -60.422571) (xy 266.094428 -60.378428) (xy 266.134577 -60.339719)
			(xy 266.179935 -60.307268) (xy 266.229535 -60.281767) (xy 266.282319 -60.26376) (xy 266.337162 -60.25363)
			(xy 266.392896 -60.251593) (xy 266.448333 -60.257693) (xy 266.50229 -60.271799) (xy 266.553619 -60.293611)
			(xy 266.601225 -60.322665) (xy 266.644093 -60.35834) (xy 266.68131 -60.399877) (xy 266.712083 -60.44639)
			(xy 266.735755 -60.496887) (xy 266.751823 -60.550294) (xy 266.759943 -60.60547) (xy 266.760452 -60.633356)
			(xy 266.759943 -60.661242) (xy 266.751823 -60.716418) (xy 266.735755 -60.769825) (xy 266.712083 -60.820322)
			(xy 266.68131 -60.866835) (xy 266.644093 -60.908372) (xy 266.601225 -60.944047) (xy 266.553619 -60.973101)
			(xy 266.50229 -60.994913) (xy 266.448333 -61.009019) (xy 266.392896 -61.015119) (xy 266.337162 -61.013082)
			(xy 266.282319 -61.002952) (xy 266.229535 -60.984945) (xy 266.179935 -60.959444) (xy 266.134577 -60.926993)
			(xy 266.094428 -60.888284) (xy 266.060342 -60.844141) (xy 266.033046 -60.795506) (xy 266.013123 -60.743415)
			(xy 266.000997 -60.688978) (xy 265.996926 -60.633356) (xy 240.089717 -60.633356) (xy 240.104141 -60.64536)
			(xy 240.141358 -60.686897) (xy 240.172131 -60.73341) (xy 240.195803 -60.783907) (xy 240.211871 -60.837314)
			(xy 240.219991 -60.89249) (xy 240.2205 -60.920376) (xy 240.219991 -60.948262) (xy 240.211871 -61.003438)
			(xy 240.195803 -61.056845) (xy 240.172131 -61.107342) (xy 240.141358 -61.153855) (xy 240.104141 -61.195392)
			(xy 240.061273 -61.231067) (xy 240.013667 -61.260121) (xy 239.962338 -61.281933) (xy 239.908381 -61.296039)
			(xy 239.852944 -61.302139) (xy 239.79721 -61.300102) (xy 239.742367 -61.289972) (xy 239.689583 -61.271965)
			(xy 239.639983 -61.246464) (xy 239.594625 -61.214013) (xy 239.554476 -61.175304) (xy 239.52039 -61.131161)
			(xy 239.493094 -61.082526) (xy 239.473171 -61.030435) (xy 239.461045 -60.975998) (xy 239.456974 -60.920376)
			(xy 233.832134 -60.920376) (xy 233.837707 -60.925014) (xy 233.874924 -60.966551) (xy 233.905697 -61.013064)
			(xy 233.929369 -61.063561) (xy 233.945437 -61.116968) (xy 233.953557 -61.172144) (xy 233.954066 -61.20003)
			(xy 233.953557 -61.227916) (xy 233.945437 -61.283092) (xy 233.929369 -61.336499) (xy 233.905697 -61.386996)
			(xy 233.874924 -61.433509) (xy 233.837707 -61.475046) (xy 233.794839 -61.510721) (xy 233.747233 -61.539775)
			(xy 233.695904 -61.561587) (xy 233.641947 -61.575693) (xy 233.58651 -61.581793) (xy 233.530776 -61.579756)
			(xy 233.475933 -61.569626) (xy 233.423149 -61.551619) (xy 233.373549 -61.526118) (xy 233.328191 -61.493667)
			(xy 233.288042 -61.454958) (xy 233.253956 -61.410815) (xy 233.22666 -61.36218) (xy 233.206737 -61.310089)
			(xy 233.194611 -61.255652) (xy 233.19054 -61.20003) (xy 225.711136 -61.20003) (xy 225.598823 -61.773562)
			(xy 226.029264 -61.773562) (xy 226.033335 -61.71794) (xy 226.045461 -61.663503) (xy 226.065384 -61.611412)
			(xy 226.09268 -61.562777) (xy 226.126766 -61.518634) (xy 226.166915 -61.479925) (xy 226.212273 -61.447474)
			(xy 226.261873 -61.421973) (xy 226.314657 -61.403966) (xy 226.3695 -61.393836) (xy 226.425234 -61.391799)
			(xy 226.480671 -61.397899) (xy 226.534628 -61.412005) (xy 226.585957 -61.433817) (xy 226.633563 -61.462871)
			(xy 226.676431 -61.498546) (xy 226.713648 -61.540083) (xy 226.744421 -61.586596) (xy 226.768093 -61.637093)
			(xy 226.784161 -61.6905) (xy 226.792281 -61.745676) (xy 226.79279 -61.773562) (xy 226.792308 -61.799978)
			(xy 227.210618 -61.799978) (xy 227.214689 -61.744356) (xy 227.226815 -61.689919) (xy 227.246738 -61.637828)
			(xy 227.274034 -61.589193) (xy 227.30812 -61.54505) (xy 227.348269 -61.506341) (xy 227.393627 -61.47389)
			(xy 227.443227 -61.448389) (xy 227.496011 -61.430382) (xy 227.550854 -61.420252) (xy 227.606588 -61.418215)
			(xy 227.662025 -61.424315) (xy 227.715982 -61.438421) (xy 227.767311 -61.460233) (xy 227.814917 -61.489287)
			(xy 227.857785 -61.524962) (xy 227.895002 -61.566499) (xy 227.925775 -61.613012) (xy 227.949447 -61.663509)
			(xy 227.965515 -61.716916) (xy 227.973635 -61.772092) (xy 227.974144 -61.799978) (xy 231.00614 -61.799978)
			(xy 231.010211 -61.744356) (xy 231.022337 -61.689919) (xy 231.04226 -61.637828) (xy 231.069556 -61.589193)
			(xy 231.103642 -61.54505) (xy 231.143791 -61.506341) (xy 231.189149 -61.47389) (xy 231.238749 -61.448389)
			(xy 231.291533 -61.430382) (xy 231.346376 -61.420252) (xy 231.40211 -61.418215) (xy 231.457547 -61.424315)
			(xy 231.511504 -61.438421) (xy 231.562833 -61.460233) (xy 231.610439 -61.489287) (xy 231.653307 -61.524962)
			(xy 231.690524 -61.566499) (xy 231.703331 -61.585856) (xy 240.609372 -61.585856) (xy 240.613443 -61.530234)
			(xy 240.625569 -61.475797) (xy 240.645492 -61.423706) (xy 240.672788 -61.375071) (xy 240.706874 -61.330928)
			(xy 240.747023 -61.292219) (xy 240.792381 -61.259768) (xy 240.841981 -61.234267) (xy 240.894765 -61.21626)
			(xy 240.949608 -61.20613) (xy 241.005342 -61.204093) (xy 241.060779 -61.210193) (xy 241.114736 -61.224299)
			(xy 241.166065 -61.246111) (xy 241.213671 -61.275165) (xy 241.256539 -61.31084) (xy 241.293756 -61.352377)
			(xy 241.324529 -61.39889) (xy 241.348201 -61.449387) (xy 241.359762 -61.487812) (xy 264.504422 -61.487812)
			(xy 264.508493 -61.43219) (xy 264.520619 -61.377753) (xy 264.540542 -61.325662) (xy 264.567838 -61.277027)
			(xy 264.601924 -61.232884) (xy 264.642073 -61.194175) (xy 264.687431 -61.161724) (xy 264.737031 -61.136223)
			(xy 264.789815 -61.118216) (xy 264.844658 -61.108086) (xy 264.900392 -61.106049) (xy 264.955829 -61.112149)
			(xy 265.009786 -61.126255) (xy 265.061115 -61.148067) (xy 265.108721 -61.177121) (xy 265.151589 -61.212796)
			(xy 265.188806 -61.254333) (xy 265.219579 -61.300846) (xy 265.243251 -61.351343) (xy 265.259319 -61.40475)
			(xy 265.267439 -61.459926) (xy 265.267948 -61.487812) (xy 265.267439 -61.515698) (xy 265.259319 -61.570874)
			(xy 265.243251 -61.624281) (xy 265.219579 -61.674778) (xy 265.188806 -61.721291) (xy 265.151589 -61.762828)
			(xy 265.108721 -61.798503) (xy 265.061115 -61.827557) (xy 265.009786 -61.849369) (xy 264.955829 -61.863475)
			(xy 264.900392 -61.869575) (xy 264.844658 -61.867538) (xy 264.789815 -61.857408) (xy 264.737031 -61.839401)
			(xy 264.687431 -61.8139) (xy 264.642073 -61.781449) (xy 264.601924 -61.74274) (xy 264.567838 -61.698597)
			(xy 264.540542 -61.649962) (xy 264.520619 -61.597871) (xy 264.508493 -61.543434) (xy 264.504422 -61.487812)
			(xy 241.359762 -61.487812) (xy 241.364269 -61.502794) (xy 241.372389 -61.55797) (xy 241.372898 -61.585856)
			(xy 241.372389 -61.613742) (xy 241.364269 -61.668918) (xy 241.348201 -61.722325) (xy 241.324529 -61.772822)
			(xy 241.293756 -61.819335) (xy 241.256539 -61.860872) (xy 241.213671 -61.896547) (xy 241.166065 -61.925601)
			(xy 241.114736 -61.947413) (xy 241.060779 -61.961519) (xy 241.005342 -61.967619) (xy 240.949608 -61.965582)
			(xy 240.894765 -61.955452) (xy 240.841981 -61.937445) (xy 240.792381 -61.911944) (xy 240.747023 -61.879493)
			(xy 240.706874 -61.840784) (xy 240.672788 -61.796641) (xy 240.645492 -61.748006) (xy 240.625569 -61.695915)
			(xy 240.613443 -61.641478) (xy 240.609372 -61.585856) (xy 231.703331 -61.585856) (xy 231.721297 -61.613012)
			(xy 231.744969 -61.663509) (xy 231.761037 -61.716916) (xy 231.769157 -61.772092) (xy 231.769666 -61.799978)
			(xy 231.769157 -61.827864) (xy 231.761037 -61.88304) (xy 231.744969 -61.936447) (xy 231.721297 -61.986944)
			(xy 231.690524 -62.033457) (xy 231.653307 -62.074994) (xy 231.610439 -62.110669) (xy 231.562833 -62.139723)
			(xy 231.511504 -62.161535) (xy 231.457547 -62.175641) (xy 231.40211 -62.181741) (xy 231.346376 -62.179704)
			(xy 231.291533 -62.169574) (xy 231.238749 -62.151567) (xy 231.189149 -62.126066) (xy 231.143791 -62.093615)
			(xy 231.103642 -62.054906) (xy 231.069556 -62.010763) (xy 231.04226 -61.962128) (xy 231.022337 -61.910037)
			(xy 231.010211 -61.8556) (xy 231.00614 -61.799978) (xy 227.974144 -61.799978) (xy 227.973635 -61.827864)
			(xy 227.965515 -61.88304) (xy 227.949447 -61.936447) (xy 227.925775 -61.986944) (xy 227.895002 -62.033457)
			(xy 227.857785 -62.074994) (xy 227.814917 -62.110669) (xy 227.767311 -62.139723) (xy 227.715982 -62.161535)
			(xy 227.662025 -62.175641) (xy 227.606588 -62.181741) (xy 227.550854 -62.179704) (xy 227.496011 -62.169574)
			(xy 227.443227 -62.151567) (xy 227.393627 -62.126066) (xy 227.348269 -62.093615) (xy 227.30812 -62.054906)
			(xy 227.274034 -62.010763) (xy 227.246738 -61.962128) (xy 227.226815 -61.910037) (xy 227.214689 -61.8556)
			(xy 227.210618 -61.799978) (xy 226.792308 -61.799978) (xy 226.792281 -61.801448) (xy 226.784161 -61.856624)
			(xy 226.768093 -61.910031) (xy 226.744421 -61.960528) (xy 226.713648 -62.007041) (xy 226.676431 -62.048578)
			(xy 226.633563 -62.084253) (xy 226.585957 -62.113307) (xy 226.534628 -62.135119) (xy 226.480671 -62.149225)
			(xy 226.425234 -62.155325) (xy 226.3695 -62.153288) (xy 226.314657 -62.143158) (xy 226.261873 -62.125151)
			(xy 226.212273 -62.09965) (xy 226.166915 -62.067199) (xy 226.126766 -62.02849) (xy 226.09268 -61.984347)
			(xy 226.065384 -61.935712) (xy 226.045461 -61.883621) (xy 226.033335 -61.829184) (xy 226.029264 -61.773562)
			(xy 225.598823 -61.773562) (xy 225.484222 -62.358778) (xy 236.702344 -62.358778) (xy 236.706415 -62.303156)
			(xy 236.718541 -62.248719) (xy 236.738464 -62.196628) (xy 236.76576 -62.147993) (xy 236.799846 -62.10385)
			(xy 236.839995 -62.065141) (xy 236.885353 -62.03269) (xy 236.934953 -62.007189) (xy 236.987737 -61.989182)
			(xy 237.04258 -61.979052) (xy 237.098314 -61.977015) (xy 237.153751 -61.983115) (xy 237.207708 -61.997221)
			(xy 237.259037 -62.019033) (xy 237.306643 -62.048087) (xy 237.349511 -62.083762) (xy 237.382907 -62.121034)
			(xy 262.442196 -62.121034) (xy 262.446267 -62.065412) (xy 262.458393 -62.010975) (xy 262.478316 -61.958884)
			(xy 262.505612 -61.910249) (xy 262.539698 -61.866106) (xy 262.579847 -61.827397) (xy 262.625205 -61.794946)
			(xy 262.674805 -61.769445) (xy 262.727589 -61.751438) (xy 262.782432 -61.741308) (xy 262.838166 -61.739271)
			(xy 262.893603 -61.745371) (xy 262.94756 -61.759477) (xy 262.998889 -61.781289) (xy 263.046495 -61.810343)
			(xy 263.089363 -61.846018) (xy 263.12658 -61.887555) (xy 263.157353 -61.934068) (xy 263.181025 -61.984565)
			(xy 263.197093 -62.037972) (xy 263.205213 -62.093148) (xy 263.205722 -62.121034) (xy 263.205213 -62.14892)
			(xy 263.197093 -62.204096) (xy 263.181025 -62.257503) (xy 263.157353 -62.308) (xy 263.12658 -62.354513)
			(xy 263.089363 -62.39605) (xy 263.046495 -62.431725) (xy 262.998889 -62.460779) (xy 262.94756 -62.482591)
			(xy 262.893603 -62.496697) (xy 262.838166 -62.502797) (xy 262.782432 -62.50076) (xy 262.727589 -62.49063)
			(xy 262.674805 -62.472623) (xy 262.625205 -62.447122) (xy 262.579847 -62.414671) (xy 262.539698 -62.375962)
			(xy 262.505612 -62.331819) (xy 262.478316 -62.283184) (xy 262.458393 -62.231093) (xy 262.446267 -62.176656)
			(xy 262.442196 -62.121034) (xy 237.382907 -62.121034) (xy 237.386728 -62.125299) (xy 237.417501 -62.171812)
			(xy 237.441173 -62.222309) (xy 237.457241 -62.275716) (xy 237.465361 -62.330892) (xy 237.46587 -62.358778)
			(xy 237.465361 -62.386664) (xy 237.457241 -62.44184) (xy 237.441173 -62.495247) (xy 237.417501 -62.545744)
			(xy 237.386728 -62.592257) (xy 237.349511 -62.633794) (xy 237.306643 -62.669469) (xy 237.259037 -62.698523)
			(xy 237.207708 -62.720335) (xy 237.153751 -62.734441) (xy 237.098314 -62.740541) (xy 237.04258 -62.738504)
			(xy 236.987737 -62.728374) (xy 236.934953 -62.710367) (xy 236.885353 -62.684866) (xy 236.839995 -62.652415)
			(xy 236.799846 -62.613706) (xy 236.76576 -62.569563) (xy 236.738464 -62.520928) (xy 236.718541 -62.468837)
			(xy 236.706415 -62.4144) (xy 236.702344 -62.358778) (xy 225.484222 -62.358778) (xy 225.37166 -62.93358)
			(xy 225.370766 -62.938954) (xy 225.371025 -62.949843) (xy 225.372168 -62.95517) (xy 225.374708 -62.965584)
			(xy 225.37674 -62.968378) (xy 225.37674 -62.968886) (xy 225.400172 -63.000128) (xy 231.00614 -63.000128)
			(xy 231.010211 -62.944506) (xy 231.022337 -62.890069) (xy 231.04226 -62.837978) (xy 231.069556 -62.789343)
			(xy 231.103642 -62.7452) (xy 231.143791 -62.706491) (xy 231.189149 -62.67404) (xy 231.238749 -62.648539)
			(xy 231.291533 -62.630532) (xy 231.346376 -62.620402) (xy 231.40211 -62.618365) (xy 231.457547 -62.624465)
			(xy 231.511504 -62.638571) (xy 231.562833 -62.660383) (xy 231.610439 -62.689437) (xy 231.653307 -62.725112)
			(xy 231.690524 -62.766649) (xy 231.721297 -62.813162) (xy 231.744969 -62.863659) (xy 231.761037 -62.917066)
			(xy 231.769157 -62.972242) (xy 231.769666 -63.000128) (xy 231.769157 -63.028014) (xy 231.761037 -63.08319)
			(xy 231.744969 -63.136597) (xy 231.721297 -63.187094) (xy 231.690524 -63.233607) (xy 231.653307 -63.275144)
			(xy 231.610439 -63.310819) (xy 231.562833 -63.339873) (xy 231.511504 -63.361685) (xy 231.457547 -63.375791)
			(xy 231.40211 -63.381891) (xy 231.346376 -63.379854) (xy 231.291533 -63.369724) (xy 231.238749 -63.351717)
			(xy 231.189149 -63.326216) (xy 231.143791 -63.293765) (xy 231.103642 -63.255056) (xy 231.069556 -63.210913)
			(xy 231.04226 -63.162278) (xy 231.022337 -63.110187) (xy 231.010211 -63.05575) (xy 231.00614 -63.000128)
			(xy 225.400172 -63.000128) (xy 225.414078 -63.01867) (xy 225.420707 -63.025842) (xy 225.437951 -63.034975)
			(xy 225.447606 -63.03645) (xy 225.448114 -63.03645) (xy 225.476041 -63.039698) (xy 225.530579 -63.05335)
			(xy 225.582524 -63.074858) (xy 225.630748 -63.103758) (xy 225.674209 -63.139423) (xy 225.711965 -63.18108)
			(xy 225.743198 -63.227827) (xy 225.767231 -63.278653) (xy 225.783545 -63.332455) (xy 225.791785 -63.388069)
			(xy 225.792284 -63.41618) (xy 225.791741 -63.445218) (xy 225.782939 -63.502622) (xy 225.768923 -63.547244)
			(xy 226.964238 -63.547244) (xy 226.968309 -63.491622) (xy 226.980435 -63.437185) (xy 227.000358 -63.385094)
			(xy 227.027654 -63.336459) (xy 227.06174 -63.292316) (xy 227.101889 -63.253607) (xy 227.147247 -63.221156)
			(xy 227.196847 -63.195655) (xy 227.249631 -63.177648) (xy 227.304474 -63.167518) (xy 227.360208 -63.165481)
			(xy 227.415645 -63.171581) (xy 227.469602 -63.185687) (xy 227.520931 -63.207499) (xy 227.568537 -63.236553)
			(xy 227.611405 -63.272228) (xy 227.648622 -63.313765) (xy 227.679395 -63.360278) (xy 227.703067 -63.410775)
			(xy 227.719135 -63.464182) (xy 227.727255 -63.519358) (xy 227.727764 -63.547244) (xy 227.727255 -63.57513)
			(xy 227.723584 -63.600076) (xy 233.19054 -63.600076) (xy 233.194611 -63.544454) (xy 233.206737 -63.490017)
			(xy 233.22666 -63.437926) (xy 233.253956 -63.389291) (xy 233.288042 -63.345148) (xy 233.328191 -63.306439)
			(xy 233.373549 -63.273988) (xy 233.423149 -63.248487) (xy 233.475933 -63.23048) (xy 233.530776 -63.22035)
			(xy 233.58651 -63.218313) (xy 233.641947 -63.224413) (xy 233.695904 -63.238519) (xy 233.747233 -63.260331)
			(xy 233.794839 -63.289385) (xy 233.837707 -63.32506) (xy 233.874924 -63.366597) (xy 233.905697 -63.41311)
			(xy 233.923449 -63.450978) (xy 237.60633 -63.450978) (xy 237.610401 -63.395356) (xy 237.622527 -63.340919)
			(xy 237.64245 -63.288828) (xy 237.669746 -63.240193) (xy 237.703832 -63.19605) (xy 237.743981 -63.157341)
			(xy 237.789339 -63.12489) (xy 237.838939 -63.099389) (xy 237.891723 -63.081382) (xy 237.946566 -63.071252)
			(xy 238.0023 -63.069215) (xy 238.057737 -63.075315) (xy 238.111694 -63.089421) (xy 238.163023 -63.111233)
			(xy 238.210629 -63.140287) (xy 238.253497 -63.175962) (xy 238.287178 -63.213552) (xy 254.320765 -63.213552)
			(xy 254.320765 -63.159048) (xy 254.328522 -63.105098) (xy 254.343878 -63.052801) (xy 254.36652 -63.003222)
			(xy 254.395987 -62.95737) (xy 254.43168 -62.916179) (xy 254.472872 -62.880486) (xy 254.518724 -62.851019)
			(xy 254.568303 -62.828377) (xy 254.6206 -62.813022) (xy 254.67455 -62.805265) (xy 254.701802 -62.804802)
			(xy 254.729172 -62.805266) (xy 254.783351 -62.813085) (xy 254.835855 -62.828574) (xy 254.885601 -62.851416)
			(xy 254.931568 -62.881141) (xy 254.9525 -62.898782) (xy 254.952754 -62.899036) (xy 254.959847 -62.904613)
			(xy 254.976759 -62.910865) (xy 254.985774 -62.911228) (xy 255.05283 -62.911228) (xy 255.061848 -62.910879)
			(xy 255.078764 -62.904625) (xy 255.08585 -62.899036) (xy 255.08585 -62.898782) (xy 255.086104 -62.898782)
			(xy 255.107037 -62.881141) (xy 255.153005 -62.851417) (xy 255.202751 -62.828571) (xy 255.255253 -62.813075)
			(xy 255.309431 -62.805246) (xy 255.364173 -62.805246) (xy 255.418351 -62.813075) (xy 255.470853 -62.828571)
			(xy 255.520599 -62.851417) (xy 255.566567 -62.881141) (xy 255.5875 -62.898782) (xy 255.587754 -62.899036)
			(xy 255.594847 -62.904613) (xy 255.611759 -62.910865) (xy 255.620774 -62.911228) (xy 255.68783 -62.911228)
			(xy 255.696848 -62.910879) (xy 255.713764 -62.904625) (xy 255.72085 -62.899036) (xy 255.72085 -62.898782)
			(xy 255.721104 -62.898782) (xy 255.742021 -62.881125) (xy 255.787999 -62.851416) (xy 255.83775 -62.828584)
			(xy 255.890254 -62.813097) (xy 255.944432 -62.805274) (xy 255.971802 -62.804802) (xy 255.999054 -62.805268)
			(xy 256.053003 -62.813025) (xy 256.105299 -62.828381) (xy 256.154877 -62.851022) (xy 256.200728 -62.88049)
			(xy 256.241919 -62.916182) (xy 256.277612 -62.957373) (xy 256.307079 -63.003225) (xy 256.32972 -63.052803)
			(xy 256.339537 -63.086234) (xy 259.58749 -63.086234) (xy 259.591561 -63.030612) (xy 259.603687 -62.976175)
			(xy 259.62361 -62.924084) (xy 259.650906 -62.875449) (xy 259.684992 -62.831306) (xy 259.725141 -62.792597)
			(xy 259.770499 -62.760146) (xy 259.820099 -62.734645) (xy 259.872883 -62.716638) (xy 259.927726 -62.706508)
			(xy 259.98346 -62.704471) (xy 260.038897 -62.710571) (xy 260.092854 -62.724677) (xy 260.113012 -62.733243)
			(xy 265.866051 -62.733243) (xy 265.866052 -62.678736) (xy 265.873811 -62.624784) (xy 265.889169 -62.572485)
			(xy 265.911814 -62.522905) (xy 265.941284 -62.477052) (xy 265.97698 -62.43586) (xy 266.018175 -62.400167)
			(xy 266.06403 -62.3707) (xy 266.113612 -62.348059) (xy 266.165912 -62.332705) (xy 266.219865 -62.32495)
			(xy 266.247118 -62.324488) (xy 266.270673 -62.324865) (xy 266.317417 -62.330724) (xy 266.340336 -62.336172)
			(xy 266.354094 -62.3392) (xy 266.382243 -62.338346) (xy 266.40909 -62.329842) (xy 266.432597 -62.314332)
			(xy 266.450978 -62.292996) (xy 266.462837 -62.267452) (xy 266.467274 -62.239642) (xy 266.463952 -62.211676)
			(xy 266.458954 -62.198504) (xy 266.449643 -62.175115) (xy 266.436518 -62.126514) (xy 266.429895 -62.076609)
			(xy 266.42949 -62.051438) (xy 266.429914 -62.024182) (xy 266.437667 -61.970223) (xy 266.45302 -61.917918)
			(xy 266.475661 -61.868329) (xy 266.505128 -61.822468) (xy 266.540823 -61.781267) (xy 266.582018 -61.745566)
			(xy 266.627874 -61.716091) (xy 266.677459 -61.693442) (xy 266.729762 -61.67808) (xy 266.783719 -61.670319)
			(xy 266.838232 -61.670315) (xy 266.89219 -61.67807) (xy 266.944495 -61.693425) (xy 266.994082 -61.716067)
			(xy 267.039943 -61.745536) (xy 267.081142 -61.781233) (xy 267.116842 -61.822429) (xy 267.146315 -61.868286)
			(xy 267.168963 -61.917871) (xy 267.184323 -61.970175) (xy 267.192082 -62.024132) (xy 267.192084 -62.078645)
			(xy 267.184327 -62.132603) (xy 267.168971 -62.184907) (xy 267.146326 -62.234494) (xy 267.116856 -62.280353)
			(xy 267.081158 -62.321551) (xy 267.039961 -62.35725) (xy 266.994102 -62.386722) (xy 266.944516 -62.409367)
			(xy 266.892212 -62.424725) (xy 266.838254 -62.432483) (xy 266.810998 -62.432946) (xy 266.787444 -62.432565)
			(xy 266.740699 -62.426709) (xy 266.71778 -62.421262) (xy 266.704026 -62.418204) (xy 266.675869 -62.419054)
			(xy 266.649015 -62.427558) (xy 266.625502 -62.443071) (xy 266.607118 -62.464415) (xy 266.59526 -62.489966)
			(xy 266.590828 -62.517785) (xy 266.594159 -62.545756) (xy 266.599162 -62.55893) (xy 266.608484 -62.582315)
			(xy 266.621605 -62.630918) (xy 266.628223 -62.680825) (xy 266.628626 -62.705996) (xy 266.628149 -62.733249)
			(xy 266.620392 -62.787202) (xy 266.605036 -62.839501) (xy 266.582393 -62.889082) (xy 266.552925 -62.934936)
			(xy 266.517231 -62.97613) (xy 266.476037 -63.011825) (xy 266.430183 -63.041293) (xy 266.380601 -63.063936)
			(xy 266.328302 -63.079292) (xy 266.27435 -63.087049) (xy 266.219843 -63.087048) (xy 266.165891 -63.079291)
			(xy 266.113592 -63.063934) (xy 266.064011 -63.04129) (xy 266.018158 -63.011821) (xy 265.976965 -62.976125)
			(xy 265.941271 -62.934931) (xy 265.911803 -62.889076) (xy 265.889161 -62.839495) (xy 265.873806 -62.787195)
			(xy 265.866051 -62.733243) (xy 260.113012 -62.733243) (xy 260.144183 -62.746489) (xy 260.191789 -62.775543)
			(xy 260.234657 -62.811218) (xy 260.271874 -62.852755) (xy 260.302647 -62.899268) (xy 260.326319 -62.949765)
			(xy 260.342387 -63.003172) (xy 260.350507 -63.058348) (xy 260.351016 -63.086234) (xy 260.350507 -63.11412)
			(xy 260.342387 -63.169296) (xy 260.326319 -63.222703) (xy 260.302647 -63.2732) (xy 260.302494 -63.273432)
			(xy 261.776716 -63.273432) (xy 261.780787 -63.21781) (xy 261.792913 -63.163373) (xy 261.812836 -63.111282)
			(xy 261.840132 -63.062647) (xy 261.874218 -63.018504) (xy 261.914367 -62.979795) (xy 261.959725 -62.947344)
			(xy 262.009325 -62.921843) (xy 262.062109 -62.903836) (xy 262.116952 -62.893706) (xy 262.172686 -62.891669)
			(xy 262.228123 -62.897769) (xy 262.28208 -62.911875) (xy 262.333409 -62.933687) (xy 262.381015 -62.962741)
			(xy 262.423883 -62.998416) (xy 262.4611 -63.039953) (xy 262.491873 -63.086466) (xy 262.515545 -63.136963)
			(xy 262.531613 -63.19037) (xy 262.539733 -63.245546) (xy 262.540242 -63.273432) (xy 262.539733 -63.301318)
			(xy 262.531613 -63.356494) (xy 262.515545 -63.409901) (xy 262.491873 -63.460398) (xy 262.4611 -63.506911)
			(xy 262.423883 -63.548448) (xy 262.381015 -63.584123) (xy 262.333409 -63.613177) (xy 262.28208 -63.634989)
			(xy 262.228123 -63.649095) (xy 262.172686 -63.655195) (xy 262.116952 -63.653158) (xy 262.062109 -63.643028)
			(xy 262.009325 -63.625021) (xy 261.959725 -63.59952) (xy 261.914367 -63.567069) (xy 261.874218 -63.52836)
			(xy 261.840132 -63.484217) (xy 261.812836 -63.435582) (xy 261.792913 -63.383491) (xy 261.780787 -63.329054)
			(xy 261.776716 -63.273432) (xy 260.302494 -63.273432) (xy 260.271874 -63.319713) (xy 260.234657 -63.36125)
			(xy 260.191789 -63.396925) (xy 260.144183 -63.425979) (xy 260.092854 -63.447791) (xy 260.038897 -63.461897)
			(xy 259.98346 -63.467997) (xy 259.927726 -63.46596) (xy 259.872883 -63.45583) (xy 259.820099 -63.437823)
			(xy 259.770499 -63.412322) (xy 259.725141 -63.379871) (xy 259.684992 -63.341162) (xy 259.650906 -63.297019)
			(xy 259.62361 -63.248384) (xy 259.603687 -63.196293) (xy 259.591561 -63.141856) (xy 259.58749 -63.086234)
			(xy 256.339537 -63.086234) (xy 256.345076 -63.105099) (xy 256.352832 -63.159048) (xy 256.352832 -63.213552)
			(xy 256.345076 -63.267501) (xy 256.32972 -63.319797) (xy 256.307079 -63.369375) (xy 256.277612 -63.415227)
			(xy 256.241919 -63.456418) (xy 256.200728 -63.49211) (xy 256.154877 -63.521578) (xy 256.105299 -63.544219)
			(xy 256.053003 -63.559575) (xy 255.999054 -63.567332) (xy 255.971802 -63.567818) (xy 255.944431 -63.567371)
			(xy 255.89025 -63.559551) (xy 255.837746 -63.544059) (xy 255.787999 -63.521213) (xy 255.742034 -63.491482)
			(xy 255.721104 -63.473838) (xy 255.72085 -63.473584) (xy 255.713755 -63.46801) (xy 255.696845 -63.461756)
			(xy 255.68783 -63.461392) (xy 255.620774 -63.461392) (xy 255.611756 -63.461739) (xy 255.594839 -63.467994)
			(xy 255.587754 -63.473584) (xy 255.5875 -63.473838) (xy 255.566567 -63.491479) (xy 255.520599 -63.521203)
			(xy 255.470853 -63.544049) (xy 255.418351 -63.559545) (xy 255.364173 -63.567374) (xy 255.309431 -63.567374)
			(xy 255.255253 -63.559545) (xy 255.202751 -63.544049) (xy 255.153005 -63.521203) (xy 255.107037 -63.491479)
			(xy 255.086104 -63.473838) (xy 255.08585 -63.473584) (xy 255.078755 -63.46801) (xy 255.061845 -63.461756)
			(xy 255.05283 -63.461392) (xy 254.985774 -63.461392) (xy 254.976756 -63.461739) (xy 254.959839 -63.467994)
			(xy 254.952754 -63.473584) (xy 254.952754 -63.473838) (xy 254.9525 -63.473838) (xy 254.931584 -63.491497)
			(xy 254.885606 -63.521205) (xy 254.835855 -63.544036) (xy 254.783351 -63.559523) (xy 254.729172 -63.567347)
			(xy 254.701802 -63.567818) (xy 254.67455 -63.567335) (xy 254.6206 -63.559578) (xy 254.568303 -63.544223)
			(xy 254.518724 -63.521581) (xy 254.472872 -63.492114) (xy 254.43168 -63.456421) (xy 254.395987 -63.41523)
			(xy 254.36652 -63.369378) (xy 254.343878 -63.319799) (xy 254.328522 -63.267502) (xy 254.320765 -63.213552)
			(xy 238.287178 -63.213552) (xy 238.290714 -63.217499) (xy 238.321487 -63.264012) (xy 238.345159 -63.314509)
			(xy 238.361227 -63.367916) (xy 238.369347 -63.423092) (xy 238.369856 -63.450978) (xy 238.369347 -63.478864)
			(xy 238.361227 -63.53404) (xy 238.345159 -63.587447) (xy 238.321487 -63.637944) (xy 238.31478 -63.648082)
			(xy 241.242594 -63.648082) (xy 241.246665 -63.59246) (xy 241.258791 -63.538023) (xy 241.278714 -63.485932)
			(xy 241.30601 -63.437297) (xy 241.340096 -63.393154) (xy 241.380245 -63.354445) (xy 241.425603 -63.321994)
			(xy 241.475203 -63.296493) (xy 241.527987 -63.278486) (xy 241.58283 -63.268356) (xy 241.638564 -63.266319)
			(xy 241.694001 -63.272419) (xy 241.747958 -63.286525) (xy 241.799287 -63.308337) (xy 241.846893 -63.337391)
			(xy 241.889761 -63.373066) (xy 241.926978 -63.414603) (xy 241.957751 -63.461116) (xy 241.981423 -63.511613)
			(xy 241.997491 -63.56502) (xy 242.005611 -63.620196) (xy 242.00612 -63.648082) (xy 242.005611 -63.675968)
			(xy 241.997491 -63.731144) (xy 241.981423 -63.784551) (xy 241.957751 -63.835048) (xy 241.926978 -63.881561)
			(xy 241.889761 -63.923098) (xy 241.846893 -63.958773) (xy 241.799287 -63.987827) (xy 241.747958 -64.009639)
			(xy 241.694001 -64.023745) (xy 241.638564 -64.029845) (xy 241.58283 -64.027808) (xy 241.527987 -64.017678)
			(xy 241.475203 -63.999671) (xy 241.425603 -63.97417) (xy 241.380245 -63.941719) (xy 241.340096 -63.90301)
			(xy 241.30601 -63.858867) (xy 241.278714 -63.810232) (xy 241.258791 -63.758141) (xy 241.246665 -63.703704)
			(xy 241.242594 -63.648082) (xy 238.31478 -63.648082) (xy 238.290714 -63.684457) (xy 238.253497 -63.725994)
			(xy 238.210629 -63.761669) (xy 238.163023 -63.790723) (xy 238.111694 -63.812535) (xy 238.057737 -63.826641)
			(xy 238.0023 -63.832741) (xy 237.946566 -63.830704) (xy 237.891723 -63.820574) (xy 237.838939 -63.802567)
			(xy 237.789339 -63.777066) (xy 237.743981 -63.744615) (xy 237.703832 -63.705906) (xy 237.669746 -63.661763)
			(xy 237.64245 -63.613128) (xy 237.622527 -63.561037) (xy 237.610401 -63.5066) (xy 237.60633 -63.450978)
			(xy 233.923449 -63.450978) (xy 233.929369 -63.463607) (xy 233.945437 -63.517014) (xy 233.953557 -63.57219)
			(xy 233.954066 -63.600076) (xy 233.953557 -63.627962) (xy 233.945437 -63.683138) (xy 233.929369 -63.736545)
			(xy 233.905697 -63.787042) (xy 233.874924 -63.833555) (xy 233.837707 -63.875092) (xy 233.794839 -63.910767)
			(xy 233.747233 -63.939821) (xy 233.695904 -63.961633) (xy 233.641947 -63.975739) (xy 233.58651 -63.981839)
			(xy 233.530776 -63.979802) (xy 233.475933 -63.969672) (xy 233.423149 -63.951665) (xy 233.373549 -63.926164)
			(xy 233.328191 -63.893713) (xy 233.288042 -63.855004) (xy 233.253956 -63.810861) (xy 233.22666 -63.762226)
			(xy 233.206737 -63.710135) (xy 233.194611 -63.655698) (xy 233.19054 -63.600076) (xy 227.723584 -63.600076)
			(xy 227.719135 -63.630306) (xy 227.703067 -63.683713) (xy 227.679395 -63.73421) (xy 227.648622 -63.780723)
			(xy 227.611405 -63.82226) (xy 227.568537 -63.857935) (xy 227.520931 -63.886989) (xy 227.469602 -63.908801)
			(xy 227.415645 -63.922907) (xy 227.360208 -63.929007) (xy 227.304474 -63.92697) (xy 227.249631 -63.91684)
			(xy 227.196847 -63.898833) (xy 227.147247 -63.873332) (xy 227.101889 -63.840881) (xy 227.06174 -63.802172)
			(xy 227.027654 -63.758029) (xy 227.000358 -63.709394) (xy 226.980435 -63.657303) (xy 226.968309 -63.602866)
			(xy 226.964238 -63.547244) (xy 225.768923 -63.547244) (xy 225.765536 -63.558028) (xy 225.739934 -63.610156)
			(xy 225.706724 -63.657799) (xy 225.666675 -63.699856) (xy 225.620713 -63.735356) (xy 225.5699 -63.763476)
			(xy 225.542856 -63.774066) (xy 225.533966 -63.777368) (xy 225.51263 -63.796418) (xy 225.509 -63.799822)
			(xy 225.502986 -63.80775) (xy 225.500692 -63.812166) (xy 225.47326 -63.867792) (xy 225.471162 -63.872361)
			(xy 225.468612 -63.882086) (xy 225.46818 -63.887096) (xy 225.467672 -63.897002) (xy 225.468688 -63.899796)
			(xy 225.479493 -63.931412) (xy 225.491118 -63.997202) (xy 225.491802 -64.030606) (xy 225.491802 -64.03467)
			(xy 225.490918 -64.064487) (xy 225.481036 -64.12331) (xy 225.462131 -64.179883) (xy 225.434663 -64.232831)
			(xy 225.3993 -64.280866) (xy 225.3569 -64.32282) (xy 225.333052 -64.34074) (xy 225.327972 -64.344296)
			(xy 225.320098 -64.353186) (xy 225.317558 -64.358012) (xy 225.315085 -64.363209) (xy 225.312256 -64.374362)
			(xy 225.31197 -64.38011) (xy 225.309176 -64.473328) (xy 225.31324 -64.481964) (xy 225.315018 -64.48552)
			(xy 225.317535 -64.490219) (xy 225.324193 -64.498543) (xy 225.328226 -64.50203) (xy 225.32848 -64.502284)
			(xy 225.350349 -64.520513) (xy 225.388962 -64.56235) (xy 225.420933 -64.609456) (xy 225.445555 -64.660788)
			(xy 225.46228 -64.715207) (xy 225.470739 -64.771506) (xy 225.471228 -64.799972) (xy 225.470753 -64.827098)
			(xy 225.463072 -64.880804) (xy 225.44786 -64.93288) (xy 225.425425 -64.982276) (xy 225.408506 -65.00876)
			(xy 240.02441 -65.00876) (xy 240.028481 -64.953138) (xy 240.040607 -64.898701) (xy 240.06053 -64.84661)
			(xy 240.087826 -64.797975) (xy 240.121912 -64.753832) (xy 240.162061 -64.715123) (xy 240.207419 -64.682672)
			(xy 240.257019 -64.657171) (xy 240.309803 -64.639164) (xy 240.364646 -64.629034) (xy 240.42038 -64.626997)
			(xy 240.475817 -64.633097) (xy 240.529774 -64.647203) (xy 240.581103 -64.669015) (xy 240.628709 -64.698069)
			(xy 240.671577 -64.733744) (xy 240.708794 -64.775281) (xy 240.739567 -64.821794) (xy 240.763239 -64.872291)
			(xy 240.779307 -64.925698) (xy 240.787427 -64.980874) (xy 240.787936 -65.00876) (xy 240.787427 -65.036646)
			(xy 240.779307 -65.091822) (xy 240.776557 -65.100962) (xy 252.332488 -65.100962) (xy 252.336559 -65.04534)
			(xy 252.348685 -64.990903) (xy 252.368608 -64.938812) (xy 252.395904 -64.890177) (xy 252.42999 -64.846034)
			(xy 252.470139 -64.807325) (xy 252.515497 -64.774874) (xy 252.565097 -64.749373) (xy 252.617881 -64.731366)
			(xy 252.672724 -64.721236) (xy 252.728458 -64.719199) (xy 252.783895 -64.725299) (xy 252.837852 -64.739405)
			(xy 252.889181 -64.761217) (xy 252.936787 -64.790271) (xy 252.979655 -64.825946) (xy 253.016872 -64.867483)
			(xy 253.047645 -64.913996) (xy 253.071317 -64.964493) (xy 253.087385 -65.0179) (xy 253.095505 -65.073076)
			(xy 253.096014 -65.100962) (xy 253.095592 -65.124076) (xy 264.307318 -65.124076) (xy 264.311389 -65.068454)
			(xy 264.323515 -65.014017) (xy 264.343438 -64.961926) (xy 264.370734 -64.913291) (xy 264.40482 -64.869148)
			(xy 264.444969 -64.830439) (xy 264.490327 -64.797988) (xy 264.539927 -64.772487) (xy 264.592711 -64.75448)
			(xy 264.647554 -64.74435) (xy 264.703288 -64.742313) (xy 264.758725 -64.748413) (xy 264.812682 -64.762519)
			(xy 264.864011 -64.784331) (xy 264.911617 -64.813385) (xy 264.954485 -64.84906) (xy 264.991702 -64.890597)
			(xy 265.022475 -64.93711) (xy 265.046147 -64.987607) (xy 265.062215 -65.041014) (xy 265.070335 -65.09619)
			(xy 265.070844 -65.124076) (xy 265.070335 -65.151962) (xy 265.062215 -65.207138) (xy 265.046147 -65.260545)
			(xy 265.022475 -65.311042) (xy 264.991702 -65.357555) (xy 264.954485 -65.399092) (xy 264.911617 -65.434767)
			(xy 264.864011 -65.463821) (xy 264.812682 -65.485633) (xy 264.758725 -65.499739) (xy 264.703288 -65.505839)
			(xy 264.647554 -65.503802) (xy 264.592711 -65.493672) (xy 264.539927 -65.475665) (xy 264.490327 -65.450164)
			(xy 264.444969 -65.417713) (xy 264.40482 -65.379004) (xy 264.370734 -65.334861) (xy 264.343438 -65.286226)
			(xy 264.323515 -65.234135) (xy 264.311389 -65.179698) (xy 264.307318 -65.124076) (xy 253.095592 -65.124076)
			(xy 253.095505 -65.128848) (xy 253.087385 -65.184024) (xy 253.071317 -65.237431) (xy 253.047645 -65.287928)
			(xy 253.016872 -65.334441) (xy 252.979655 -65.375978) (xy 252.936787 -65.411653) (xy 252.889181 -65.440707)
			(xy 252.837852 -65.462519) (xy 252.783895 -65.476625) (xy 252.728458 -65.482725) (xy 252.672724 -65.480688)
			(xy 252.617881 -65.470558) (xy 252.565097 -65.452551) (xy 252.515497 -65.42705) (xy 252.470139 -65.394599)
			(xy 252.42999 -65.35589) (xy 252.395904 -65.311747) (xy 252.368608 -65.263112) (xy 252.348685 -65.211021)
			(xy 252.336559 -65.156584) (xy 252.332488 -65.100962) (xy 240.776557 -65.100962) (xy 240.763239 -65.145229)
			(xy 240.739567 -65.195726) (xy 240.708794 -65.242239) (xy 240.671577 -65.283776) (xy 240.628709 -65.319451)
			(xy 240.581103 -65.348505) (xy 240.529774 -65.370317) (xy 240.475817 -65.384423) (xy 240.42038 -65.390523)
			(xy 240.364646 -65.388486) (xy 240.309803 -65.378356) (xy 240.257019 -65.360349) (xy 240.207419 -65.334848)
			(xy 240.162061 -65.302397) (xy 240.121912 -65.263688) (xy 240.087826 -65.219545) (xy 240.06053 -65.17091)
			(xy 240.040607 -65.118819) (xy 240.028481 -65.064382) (xy 240.02441 -65.00876) (xy 225.408506 -65.00876)
			(xy 225.396218 -65.027996) (xy 225.36083 -65.069118) (xy 225.319973 -65.104811) (xy 225.274472 -65.134358)
			(xy 225.225245 -65.15716) (xy 225.173283 -65.17276) (xy 225.119636 -65.180841) (xy 225.092514 -65.18148)
			(xy 225.089212 -65.18148) (xy 225.056192 -65.18021) (xy 225.053398 -65.179956) (xy 225.05035 -65.179956)
			(xy 225.047556 -65.18021) (xy 225.014536 -65.18148) (xy 225.005392 -65.18148) (xy 224.997518 -65.181226)
			(xy 224.989644 -65.183512) (xy 224.986015 -65.184712) (xy 224.979131 -65.18803) (xy 224.975928 -65.190116)
			(xy 224.971356 -65.193164) (xy 224.93986 -65.215008) (xy 224.932536 -65.220505) (xy 224.92201 -65.235474)
			(xy 224.919286 -65.244218) (xy 224.888807 -65.39992) (xy 227.456998 -65.39992) (xy 227.461069 -65.344298)
			(xy 227.473195 -65.289861) (xy 227.493118 -65.23777) (xy 227.520414 -65.189135) (xy 227.5545 -65.144992)
			(xy 227.594649 -65.106283) (xy 227.640007 -65.073832) (xy 227.689607 -65.048331) (xy 227.742391 -65.030324)
			(xy 227.797234 -65.020194) (xy 227.852968 -65.018157) (xy 227.908405 -65.024257) (xy 227.962362 -65.038363)
			(xy 228.013691 -65.060175) (xy 228.061297 -65.089229) (xy 228.104165 -65.124904) (xy 228.141382 -65.166441)
			(xy 228.172155 -65.212954) (xy 228.195827 -65.263451) (xy 228.211895 -65.316858) (xy 228.220015 -65.372034)
			(xy 228.220524 -65.39992) (xy 228.220015 -65.427806) (xy 228.211895 -65.482982) (xy 228.195827 -65.536389)
			(xy 228.172155 -65.586886) (xy 228.141382 -65.633399) (xy 228.104165 -65.674936) (xy 228.061297 -65.710611)
			(xy 228.013691 -65.739665) (xy 227.97638 -65.75552) (xy 246.546622 -65.75552) (xy 246.550693 -65.699898)
			(xy 246.562819 -65.645461) (xy 246.582742 -65.59337) (xy 246.610038 -65.544735) (xy 246.644124 -65.500592)
			(xy 246.684273 -65.461883) (xy 246.729631 -65.429432) (xy 246.779231 -65.403931) (xy 246.832015 -65.385924)
			(xy 246.886858 -65.375794) (xy 246.942592 -65.373757) (xy 246.998029 -65.379857) (xy 247.051986 -65.393963)
			(xy 247.103315 -65.415775) (xy 247.150921 -65.444829) (xy 247.193789 -65.480504) (xy 247.231006 -65.522041)
			(xy 247.261779 -65.568554) (xy 247.285451 -65.619051) (xy 247.301519 -65.672458) (xy 247.309639 -65.727634)
			(xy 247.310148 -65.75552) (xy 247.309639 -65.783406) (xy 247.301519 -65.838582) (xy 247.285451 -65.891989)
			(xy 247.261779 -65.942486) (xy 247.231006 -65.988999) (xy 247.193789 -66.030536) (xy 247.150921 -66.066211)
			(xy 247.103315 -66.095265) (xy 247.051986 -66.117077) (xy 246.998029 -66.131183) (xy 246.942592 -66.137283)
			(xy 246.886858 -66.135246) (xy 246.832015 -66.125116) (xy 246.779231 -66.107109) (xy 246.729631 -66.081608)
			(xy 246.684273 -66.049157) (xy 246.644124 -66.010448) (xy 246.610038 -65.966305) (xy 246.582742 -65.91767)
			(xy 246.562819 -65.865579) (xy 246.550693 -65.811142) (xy 246.546622 -65.75552) (xy 227.97638 -65.75552)
			(xy 227.962362 -65.761477) (xy 227.908405 -65.775583) (xy 227.852968 -65.781683) (xy 227.797234 -65.779646)
			(xy 227.742391 -65.769516) (xy 227.689607 -65.751509) (xy 227.640007 -65.726008) (xy 227.594649 -65.693557)
			(xy 227.5545 -65.654848) (xy 227.520414 -65.610705) (xy 227.493118 -65.56207) (xy 227.473195 -65.509979)
			(xy 227.461069 -65.455542) (xy 227.456998 -65.39992) (xy 224.888807 -65.39992) (xy 224.788222 -65.913762)
			(xy 224.720713 -66.25844) (xy 226.308918 -66.25844) (xy 226.312989 -66.202818) (xy 226.325115 -66.148381)
			(xy 226.345038 -66.09629) (xy 226.372334 -66.047655) (xy 226.40642 -66.003512) (xy 226.446569 -65.964803)
			(xy 226.491927 -65.932352) (xy 226.541527 -65.906851) (xy 226.594311 -65.888844) (xy 226.649154 -65.878714)
			(xy 226.704888 -65.876677) (xy 226.760325 -65.882777) (xy 226.814282 -65.896883) (xy 226.865611 -65.918695)
			(xy 226.913217 -65.947749) (xy 226.956085 -65.983424) (xy 226.993302 -66.024961) (xy 227.024075 -66.071474)
			(xy 227.047747 -66.121971) (xy 227.063815 -66.175378) (xy 227.071935 -66.230554) (xy 227.072444 -66.25844)
			(xy 227.071935 -66.286326) (xy 227.063815 -66.341502) (xy 227.047747 -66.394909) (xy 227.024075 -66.445406)
			(xy 226.993302 -66.491919) (xy 226.956085 -66.533456) (xy 226.913217 -66.569131) (xy 226.865611 -66.598185)
			(xy 226.861175 -66.60007) (xy 231.00614 -66.60007) (xy 231.010211 -66.544448) (xy 231.022337 -66.490011)
			(xy 231.04226 -66.43792) (xy 231.069556 -66.389285) (xy 231.103642 -66.345142) (xy 231.143791 -66.306433)
			(xy 231.189149 -66.273982) (xy 231.238749 -66.248481) (xy 231.291533 -66.230474) (xy 231.346376 -66.220344)
			(xy 231.40211 -66.218307) (xy 231.457547 -66.224407) (xy 231.511504 -66.238513) (xy 231.562833 -66.260325)
			(xy 231.610439 -66.289379) (xy 231.653307 -66.325054) (xy 231.690524 -66.366591) (xy 231.721297 -66.413104)
			(xy 231.744969 -66.463601) (xy 231.761037 -66.517008) (xy 231.769157 -66.572184) (xy 231.769666 -66.60007)
			(xy 231.769157 -66.627956) (xy 231.761037 -66.683132) (xy 231.744969 -66.736539) (xy 231.721297 -66.787036)
			(xy 231.690524 -66.833549) (xy 231.653307 -66.875086) (xy 231.610439 -66.910761) (xy 231.562833 -66.939815)
			(xy 231.511504 -66.961627) (xy 231.457547 -66.975733) (xy 231.40211 -66.981833) (xy 231.346376 -66.979796)
			(xy 231.291533 -66.969666) (xy 231.238749 -66.951659) (xy 231.189149 -66.926158) (xy 231.143791 -66.893707)
			(xy 231.103642 -66.854998) (xy 231.069556 -66.810855) (xy 231.04226 -66.76222) (xy 231.022337 -66.710129)
			(xy 231.010211 -66.655692) (xy 231.00614 -66.60007) (xy 226.861175 -66.60007) (xy 226.814282 -66.619997)
			(xy 226.760325 -66.634103) (xy 226.704888 -66.640203) (xy 226.649154 -66.638166) (xy 226.594311 -66.628036)
			(xy 226.541527 -66.610029) (xy 226.491927 -66.584528) (xy 226.446569 -66.552077) (xy 226.40642 -66.513368)
			(xy 226.372334 -66.469225) (xy 226.345038 -66.42059) (xy 226.325115 -66.368499) (xy 226.312989 -66.314062)
			(xy 226.308918 -66.25844) (xy 224.720713 -66.25844) (xy 224.663254 -66.55181) (xy 224.662746 -66.566034)
			(xy 224.663254 -66.573146) (xy 224.666048 -66.580004) (xy 224.673668 -66.600832) (xy 224.677837 -66.613693)
			(xy 224.684576 -66.639879) (xy 224.68713 -66.653156) (xy 224.69094 -66.677794) (xy 224.691448 -66.681858)
			(xy 224.692431 -66.691989) (xy 224.693445 -66.71232) (xy 224.69348 -66.722498) (xy 224.692943 -66.751833)
			(xy 224.683965 -66.809811) (xy 224.666221 -66.865733) (xy 224.640129 -66.918281) (xy 224.606303 -66.966218)
			(xy 224.586292 -66.987674) (xy 224.585784 -66.988182) (xy 224.581121 -66.993529) (xy 224.574666 -67.006158)
			(xy 224.573084 -67.013074) (xy 224.503112 -67.369944) (xy 226.983542 -67.369944) (xy 226.987613 -67.314322)
			(xy 226.999739 -67.259885) (xy 227.019662 -67.207794) (xy 227.046958 -67.159159) (xy 227.081044 -67.115016)
			(xy 227.121193 -67.076307) (xy 227.166551 -67.043856) (xy 227.216151 -67.018355) (xy 227.268935 -67.000348)
			(xy 227.323778 -66.990218) (xy 227.379512 -66.988181) (xy 227.434949 -66.994281) (xy 227.488906 -67.008387)
			(xy 227.540235 -67.030199) (xy 227.587841 -67.059253) (xy 227.630709 -67.094928) (xy 227.667926 -67.136465)
			(xy 227.698699 -67.182978) (xy 227.706687 -67.200018) (xy 233.19054 -67.200018) (xy 233.194611 -67.144396)
			(xy 233.206737 -67.089959) (xy 233.22666 -67.037868) (xy 233.253956 -66.989233) (xy 233.288042 -66.94509)
			(xy 233.328191 -66.906381) (xy 233.373549 -66.87393) (xy 233.423149 -66.848429) (xy 233.475933 -66.830422)
			(xy 233.530776 -66.820292) (xy 233.58651 -66.818255) (xy 233.641947 -66.824355) (xy 233.695904 -66.838461)
			(xy 233.747233 -66.860273) (xy 233.794839 -66.889327) (xy 233.837707 -66.925002) (xy 233.874924 -66.966539)
			(xy 233.905697 -67.013052) (xy 233.929369 -67.063549) (xy 233.940503 -67.100555) (xy 246.218627 -67.100555)
			(xy 246.218627 -67.046045) (xy 246.226385 -66.992089) (xy 246.241742 -66.939786) (xy 246.264387 -66.890202)
			(xy 246.293858 -66.844345) (xy 246.329556 -66.803149) (xy 246.370753 -66.767452) (xy 246.416611 -66.737983)
			(xy 246.466196 -66.715339) (xy 246.518499 -66.699983) (xy 246.572455 -66.692226) (xy 246.59971 -66.691764)
			(xy 246.627081 -66.692209) (xy 246.681262 -66.700029) (xy 246.733766 -66.715522) (xy 246.783512 -66.738369)
			(xy 246.829478 -66.7681) (xy 246.850408 -66.785744) (xy 246.850662 -66.785998) (xy 246.857755 -66.791575)
			(xy 246.874667 -66.797827) (xy 246.883682 -66.79819) (xy 246.950738 -66.79819) (xy 246.959757 -66.797853)
			(xy 246.976674 -66.791592) (xy 246.983758 -66.785998) (xy 246.983758 -66.785744) (xy 246.984012 -66.785744)
			(xy 247.004972 -66.76814) (xy 247.050937 -66.738421) (xy 247.100677 -66.715578) (xy 247.153172 -66.700079)
			(xy 247.207343 -66.692242) (xy 247.23471 -66.691764) (xy 247.261959 -66.692307) (xy 247.315901 -66.700064)
			(xy 247.368191 -66.715419) (xy 247.417763 -66.738059) (xy 247.463609 -66.767523) (xy 247.504795 -66.803212)
			(xy 247.540483 -66.844399) (xy 247.569946 -66.890245) (xy 247.592585 -66.939818) (xy 247.607938 -66.992108)
			(xy 247.615694 -67.046051) (xy 247.615694 -67.100549) (xy 247.607938 -67.154492) (xy 247.592585 -67.206782)
			(xy 247.569946 -67.256355) (xy 247.540483 -67.302201) (xy 247.504795 -67.343388) (xy 247.463609 -67.379077)
			(xy 247.417763 -67.408541) (xy 247.368191 -67.431181) (xy 247.315901 -67.446536) (xy 247.261959 -67.454293)
			(xy 247.23471 -67.45478) (xy 247.20734 -67.454313) (xy 247.153161 -67.446496) (xy 247.100657 -67.431008)
			(xy 247.05091 -67.408166) (xy 247.004944 -67.378441) (xy 246.984012 -67.3608) (xy 246.983758 -67.360546)
			(xy 246.976664 -67.354971) (xy 246.959753 -67.348719) (xy 246.950738 -67.348354) (xy 246.883682 -67.348354)
			(xy 246.874663 -67.348691) (xy 246.857746 -67.354951) (xy 246.850662 -67.360546) (xy 246.850662 -67.3608)
			(xy 246.850408 -67.3608) (xy 246.829484 -67.378449) (xy 246.783509 -67.408159) (xy 246.733759 -67.430993)
			(xy 246.681257 -67.446482) (xy 246.62708 -67.454307) (xy 246.59971 -67.45478) (xy 246.572455 -67.454374)
			(xy 246.518499 -67.446617) (xy 246.466196 -67.431261) (xy 246.416611 -67.408617) (xy 246.370753 -67.379148)
			(xy 246.329556 -67.343451) (xy 246.293858 -67.302255) (xy 246.264387 -67.256398) (xy 246.241742 -67.206814)
			(xy 246.226385 -67.154511) (xy 246.218627 -67.100555) (xy 233.940503 -67.100555) (xy 233.945437 -67.116956)
			(xy 233.953557 -67.172132) (xy 233.954066 -67.200018) (xy 233.953557 -67.227904) (xy 233.945437 -67.28308)
			(xy 233.929369 -67.336487) (xy 233.905697 -67.386984) (xy 233.874924 -67.433497) (xy 233.837707 -67.475034)
			(xy 233.822062 -67.488054) (xy 250.979176 -67.488054) (xy 250.983247 -67.432432) (xy 250.995373 -67.377995)
			(xy 251.015296 -67.325904) (xy 251.042592 -67.277269) (xy 251.076678 -67.233126) (xy 251.116827 -67.194417)
			(xy 251.162185 -67.161966) (xy 251.211785 -67.136465) (xy 251.264569 -67.118458) (xy 251.319412 -67.108328)
			(xy 251.375146 -67.106291) (xy 251.430583 -67.112391) (xy 251.48454 -67.126497) (xy 251.535869 -67.148309)
			(xy 251.583475 -67.177363) (xy 251.626343 -67.213038) (xy 251.66356 -67.254575) (xy 251.694333 -67.301088)
			(xy 251.718005 -67.351585) (xy 251.734073 -67.404992) (xy 251.742193 -67.460168) (xy 251.742702 -67.488054)
			(xy 251.742193 -67.51594) (xy 251.739008 -67.537584) (xy 252.271274 -67.537584) (xy 252.275345 -67.481962)
			(xy 252.287471 -67.427525) (xy 252.307394 -67.375434) (xy 252.33469 -67.326799) (xy 252.368776 -67.282656)
			(xy 252.408925 -67.243947) (xy 252.454283 -67.211496) (xy 252.503883 -67.185995) (xy 252.556667 -67.167988)
			(xy 252.61151 -67.157858) (xy 252.667244 -67.155821) (xy 252.722681 -67.161921) (xy 252.776638 -67.176027)
			(xy 252.827967 -67.197839) (xy 252.875573 -67.226893) (xy 252.918441 -67.262568) (xy 252.955658 -67.304105)
			(xy 252.986431 -67.350618) (xy 253.010103 -67.401115) (xy 253.026171 -67.454522) (xy 253.034291 -67.509698)
			(xy 253.0348 -67.537584) (xy 253.034291 -67.56547) (xy 253.030246 -67.592956) (xy 253.545338 -67.592956)
			(xy 253.549409 -67.537334) (xy 253.561535 -67.482897) (xy 253.581458 -67.430806) (xy 253.608754 -67.382171)
			(xy 253.64284 -67.338028) (xy 253.682989 -67.299319) (xy 253.728347 -67.266868) (xy 253.777947 -67.241367)
			(xy 253.830731 -67.22336) (xy 253.885574 -67.21323) (xy 253.941308 -67.211193) (xy 253.996745 -67.217293)
			(xy 254.050702 -67.231399) (xy 254.102031 -67.253211) (xy 254.149637 -67.282265) (xy 254.192505 -67.31794)
			(xy 254.229722 -67.359477) (xy 254.260495 -67.40599) (xy 254.284167 -67.456487) (xy 254.300235 -67.509894)
			(xy 254.308352 -67.565048) (xy 256.646716 -67.565048) (xy 256.646716 -67.510552) (xy 256.654471 -67.456612)
			(xy 256.669824 -67.404324) (xy 256.692461 -67.354753) (xy 256.721923 -67.308908) (xy 256.757609 -67.267723)
			(xy 256.798792 -67.232035) (xy 256.844636 -67.202571) (xy 256.894205 -67.179931) (xy 256.946492 -67.164576)
			(xy 257.000432 -67.156818) (xy 257.02768 -67.15633) (xy 257.05505 -67.1568) (xy 257.109229 -67.164616)
			(xy 257.161733 -67.180104) (xy 257.21148 -67.202945) (xy 257.257446 -67.232669) (xy 257.278378 -67.25031)
			(xy 257.278632 -67.250564) (xy 257.285728 -67.256136) (xy 257.302638 -67.26239) (xy 257.311652 -67.262756)
			(xy 257.378708 -67.262756) (xy 257.387726 -67.262412) (xy 257.404644 -67.256156) (xy 257.411728 -67.250564)
			(xy 257.411728 -67.25031) (xy 257.411982 -67.25031) (xy 257.432911 -67.232667) (xy 257.478885 -67.202956)
			(xy 257.528633 -67.18012) (xy 257.581134 -67.16463) (xy 257.635311 -67.156803) (xy 257.66268 -67.15633)
			(xy 257.689937 -67.156716) (xy 257.743895 -67.164471) (xy 257.796201 -67.179827) (xy 257.845788 -67.20247)
			(xy 257.891648 -67.231941) (xy 257.932848 -67.267638) (xy 257.968547 -67.308836) (xy 257.99802 -67.354694)
			(xy 258.020666 -67.404281) (xy 258.036025 -67.456585) (xy 258.043783 -67.510543) (xy 258.043783 -67.565057)
			(xy 258.036025 -67.619015) (xy 258.020666 -67.671319) (xy 257.99802 -67.720906) (xy 257.968547 -67.766764)
			(xy 257.932848 -67.807962) (xy 257.891648 -67.843659) (xy 257.845788 -67.87313) (xy 257.796201 -67.895773)
			(xy 257.743895 -67.911129) (xy 257.689937 -67.918884) (xy 257.66268 -67.919346) (xy 257.635309 -67.918905)
			(xy 257.581128 -67.911083) (xy 257.528624 -67.895589) (xy 257.478878 -67.872741) (xy 257.432912 -67.84301)
			(xy 257.411982 -67.825366) (xy 257.411728 -67.825112) (xy 257.404637 -67.819532) (xy 257.387724 -67.813281)
			(xy 257.378708 -67.81292) (xy 257.311652 -67.81292) (xy 257.302637 -67.813298) (xy 257.28572 -67.81953)
			(xy 257.278632 -67.825112) (xy 257.278632 -67.825366) (xy 257.278378 -67.825366) (xy 257.257423 -67.842977)
			(xy 257.211457 -67.872694) (xy 257.161715 -67.895536) (xy 257.10922 -67.911034) (xy 257.055048 -67.918869)
			(xy 257.02768 -67.919346) (xy 257.000432 -67.918782) (xy 256.946492 -67.911024) (xy 256.894205 -67.895669)
			(xy 256.844636 -67.873029) (xy 256.798792 -67.843565) (xy 256.757609 -67.807877) (xy 256.721923 -67.766692)
			(xy 256.692461 -67.720847) (xy 256.669824 -67.671276) (xy 256.654471 -67.618988) (xy 256.646716 -67.565048)
			(xy 254.308352 -67.565048) (xy 254.308355 -67.56507) (xy 254.308864 -67.592956) (xy 254.308355 -67.620842)
			(xy 254.300235 -67.676018) (xy 254.284167 -67.729425) (xy 254.260495 -67.779922) (xy 254.229722 -67.826435)
			(xy 254.192505 -67.867972) (xy 254.149637 -67.903647) (xy 254.102031 -67.932701) (xy 254.050702 -67.954513)
			(xy 253.996745 -67.968619) (xy 253.941308 -67.974719) (xy 253.885574 -67.972682) (xy 253.830731 -67.962552)
			(xy 253.777947 -67.944545) (xy 253.728347 -67.919044) (xy 253.682989 -67.886593) (xy 253.64284 -67.847884)
			(xy 253.608754 -67.803741) (xy 253.581458 -67.755106) (xy 253.561535 -67.703015) (xy 253.549409 -67.648578)
			(xy 253.545338 -67.592956) (xy 253.030246 -67.592956) (xy 253.026171 -67.620646) (xy 253.010103 -67.674053)
			(xy 252.986431 -67.72455) (xy 252.955658 -67.771063) (xy 252.918441 -67.8126) (xy 252.875573 -67.848275)
			(xy 252.827967 -67.877329) (xy 252.776638 -67.899141) (xy 252.722681 -67.913247) (xy 252.667244 -67.919347)
			(xy 252.61151 -67.91731) (xy 252.556667 -67.90718) (xy 252.503883 -67.889173) (xy 252.454283 -67.863672)
			(xy 252.408925 -67.831221) (xy 252.368776 -67.792512) (xy 252.33469 -67.748369) (xy 252.307394 -67.699734)
			(xy 252.287471 -67.647643) (xy 252.275345 -67.593206) (xy 252.271274 -67.537584) (xy 251.739008 -67.537584)
			(xy 251.734073 -67.571116) (xy 251.718005 -67.624523) (xy 251.694333 -67.67502) (xy 251.66356 -67.721533)
			(xy 251.626343 -67.76307) (xy 251.583475 -67.798745) (xy 251.535869 -67.827799) (xy 251.48454 -67.849611)
			(xy 251.430583 -67.863717) (xy 251.375146 -67.869817) (xy 251.319412 -67.86778) (xy 251.264569 -67.85765)
			(xy 251.211785 -67.839643) (xy 251.162185 -67.814142) (xy 251.116827 -67.781691) (xy 251.076678 -67.742982)
			(xy 251.042592 -67.698839) (xy 251.015296 -67.650204) (xy 250.995373 -67.598113) (xy 250.983247 -67.543676)
			(xy 250.979176 -67.488054) (xy 233.822062 -67.488054) (xy 233.794839 -67.510709) (xy 233.747233 -67.539763)
			(xy 233.695904 -67.561575) (xy 233.641947 -67.575681) (xy 233.58651 -67.581781) (xy 233.530776 -67.579744)
			(xy 233.475933 -67.569614) (xy 233.423149 -67.551607) (xy 233.373549 -67.526106) (xy 233.328191 -67.493655)
			(xy 233.288042 -67.454946) (xy 233.253956 -67.410803) (xy 233.22666 -67.362168) (xy 233.206737 -67.310077)
			(xy 233.194611 -67.25564) (xy 233.19054 -67.200018) (xy 227.706687 -67.200018) (xy 227.722371 -67.233475)
			(xy 227.738439 -67.286882) (xy 227.746559 -67.342058) (xy 227.747068 -67.369944) (xy 227.746559 -67.39783)
			(xy 227.738439 -67.453006) (xy 227.722371 -67.506413) (xy 227.698699 -67.55691) (xy 227.667926 -67.603423)
			(xy 227.630709 -67.64496) (xy 227.587841 -67.680635) (xy 227.540235 -67.709689) (xy 227.488906 -67.731501)
			(xy 227.434949 -67.745607) (xy 227.379512 -67.751707) (xy 227.323778 -67.74967) (xy 227.268935 -67.73954)
			(xy 227.216151 -67.721533) (xy 227.166551 -67.696032) (xy 227.121193 -67.663581) (xy 227.081044 -67.624872)
			(xy 227.046958 -67.580729) (xy 227.019662 -67.532094) (xy 226.999739 -67.480003) (xy 226.987613 -67.425566)
			(xy 226.983542 -67.369944) (xy 224.503112 -67.369944) (xy 224.433638 -67.724274) (xy 224.317484 -68.317872)
			(xy 224.787966 -68.317872) (xy 224.792037 -68.26225) (xy 224.804163 -68.207813) (xy 224.824086 -68.155722)
			(xy 224.851382 -68.107087) (xy 224.885468 -68.062944) (xy 224.925617 -68.024235) (xy 224.970975 -67.991784)
			(xy 225.020575 -67.966283) (xy 225.073359 -67.948276) (xy 225.128202 -67.938146) (xy 225.183936 -67.936109)
			(xy 225.239373 -67.942209) (xy 225.29333 -67.956315) (xy 225.344659 -67.978127) (xy 225.392265 -68.007181)
			(xy 225.435133 -68.042856) (xy 225.47235 -68.084393) (xy 225.503123 -68.130906) (xy 225.526795 -68.181403)
			(xy 225.542863 -68.23481) (xy 225.550983 -68.289986) (xy 225.551492 -68.317872) (xy 225.550983 -68.345758)
			(xy 225.542863 -68.400934) (xy 225.526795 -68.454341) (xy 225.503123 -68.504838) (xy 225.47235 -68.551351)
			(xy 225.435133 -68.592888) (xy 225.392265 -68.628563) (xy 225.344659 -68.657617) (xy 225.29333 -68.679429)
			(xy 225.239373 -68.693535) (xy 225.183936 -68.699635) (xy 225.128202 -68.697598) (xy 225.073359 -68.687468)
			(xy 225.020575 -68.669461) (xy 224.970975 -68.64396) (xy 224.925617 -68.611509) (xy 224.885468 -68.5728)
			(xy 224.851382 -68.528657) (xy 224.824086 -68.480022) (xy 224.804163 -68.427931) (xy 224.792037 -68.373494)
			(xy 224.787966 -68.317872) (xy 224.317484 -68.317872) (xy 224.263458 -68.59397) (xy 224.192084 -68.957698)
			(xy 224.184511 -68.994512) (xy 224.164548 -69.066978) (xy 224.15618 -69.091048) (xy 227.444554 -69.091048)
			(xy 227.445004 -69.064761) (xy 227.452209 -69.012684) (xy 227.466505 -68.962092) (xy 227.487618 -68.913945)
			(xy 227.515148 -68.869156) (xy 227.548573 -68.828577) (xy 227.587259 -68.792976) (xy 227.63047 -68.763031)
			(xy 227.677387 -68.739309) (xy 227.70211 -68.730368) (xy 227.702364 -68.730368) (xy 227.712221 -68.726236)
			(xy 227.727715 -68.711555) (xy 227.732336 -68.70192) (xy 227.765864 -68.621402) (xy 227.765102 -68.599812)
			(xy 227.76053 -68.59016) (xy 227.748579 -68.564207) (xy 227.731715 -68.509616) (xy 227.723191 -68.45312)
			(xy 227.722684 -68.424552) (xy 227.722684 -68.424298) (xy 227.72317 -68.397047) (xy 227.730926 -68.343099)
			(xy 227.746281 -68.290804) (xy 227.768923 -68.241227) (xy 227.798389 -68.195377) (xy 227.83408 -68.154186)
			(xy 227.875271 -68.118495) (xy 227.921121 -68.089029) (xy 227.970698 -68.066387) (xy 228.022993 -68.051032)
			(xy 228.076941 -68.043276) (xy 228.131443 -68.043276) (xy 228.185391 -68.051032) (xy 228.237686 -68.066387)
			(xy 228.287263 -68.089029) (xy 228.333113 -68.118495) (xy 228.374304 -68.154186) (xy 228.409995 -68.195377)
			(xy 228.439461 -68.241227) (xy 228.462103 -68.290804) (xy 228.477458 -68.343099) (xy 228.485214 -68.397047)
			(xy 228.4857 -68.424298) (xy 228.485254 -68.450584) (xy 228.478044 -68.50266) (xy 228.463745 -68.553251)
			(xy 228.44263 -68.601396) (xy 228.415099 -68.646183) (xy 228.381674 -68.686762) (xy 228.34299 -68.722363)
			(xy 228.299781 -68.75231) (xy 228.252866 -68.776035) (xy 228.228144 -68.784978) (xy 228.22789 -68.784978)
			(xy 228.218015 -68.789074) (xy 228.202529 -68.80378) (xy 228.197918 -68.813426) (xy 228.16439 -68.893944)
			(xy 228.165152 -68.915534) (xy 228.169724 -68.925186) (xy 228.181687 -68.951134) (xy 228.198548 -69.005727)
			(xy 228.207066 -69.062225) (xy 228.20757 -69.090794) (xy 228.20757 -69.091048) (xy 228.207084 -69.118299)
			(xy 228.199328 -69.172247) (xy 228.183973 -69.224542) (xy 228.161331 -69.274119) (xy 228.131865 -69.319969)
			(xy 228.096174 -69.36116) (xy 228.054983 -69.396851) (xy 228.009133 -69.426317) (xy 227.959556 -69.448959)
			(xy 227.907261 -69.464314) (xy 227.853313 -69.47207) (xy 227.798811 -69.47207) (xy 227.744863 -69.464314)
			(xy 227.692568 -69.448959) (xy 227.642991 -69.426317) (xy 227.597141 -69.396851) (xy 227.55595 -69.36116)
			(xy 227.520259 -69.319969) (xy 227.490793 -69.274119) (xy 227.468151 -69.224542) (xy 227.452796 -69.172247)
			(xy 227.44504 -69.118299) (xy 227.444554 -69.091048) (xy 224.15618 -69.091048) (xy 224.152206 -69.102478)
			(xy 223.902749 -69.798271) (xy 229.808523 -69.798271) (xy 229.808523 -69.701577) (xy 229.816508 -69.605214)
			(xy 229.832424 -69.509839) (xy 229.85616 -69.416105) (xy 229.887557 -69.32465) (xy 229.926398 -69.236101)
			(xy 229.972419 -69.151061) (xy 230.025305 -69.070113) (xy 230.084696 -68.993808) (xy 230.150184 -68.922668)
			(xy 230.221324 -68.85718) (xy 230.297629 -68.797789) (xy 230.378577 -68.744903) (xy 230.463617 -68.698882)
			(xy 230.552166 -68.660041) (xy 230.643621 -68.628644) (xy 230.737355 -68.604908) (xy 230.83273 -68.588992)
			(xy 230.929093 -68.581007) (xy 231.025787 -68.581007) (xy 231.12215 -68.588992) (xy 231.217525 -68.604908)
			(xy 231.311259 -68.628644) (xy 231.402714 -68.660041) (xy 231.491263 -68.698882) (xy 231.576303 -68.744903)
			(xy 231.657251 -68.797789) (xy 231.733556 -68.85718) (xy 231.804696 -68.922668) (xy 231.870184 -68.993808)
			(xy 231.875094 -69.000116) (xy 233.19105 -69.000116) (xy 233.191549 -68.972636) (xy 233.19944 -68.918244)
			(xy 233.215059 -68.865549) (xy 233.238083 -68.815644) (xy 233.268035 -68.769561) (xy 233.304294 -68.728258)
			(xy 233.346108 -68.69259) (xy 233.369104 -68.677536) (xy 233.381055 -68.669324) (xy 233.400234 -68.647601)
			(xy 233.412546 -68.621369) (xy 233.417 -68.592735) (xy 233.413239 -68.564002) (xy 233.401565 -68.537479)
			(xy 233.382916 -68.515299) (xy 233.371136 -68.506848) (xy 233.349088 -68.491587) (xy 233.309032 -68.455942)
			(xy 233.274366 -68.415036) (xy 233.245774 -68.369677) (xy 233.223819 -68.320759) (xy 233.208935 -68.269247)
			(xy 233.201415 -68.216158) (xy 233.200956 -68.189348) (xy 233.201442 -68.162097) (xy 233.209198 -68.108149)
			(xy 233.224553 -68.055854) (xy 233.247195 -68.006277) (xy 233.276661 -67.960427) (xy 233.312352 -67.919236)
			(xy 233.353543 -67.883545) (xy 233.399393 -67.854079) (xy 233.44897 -67.831437) (xy 233.501265 -67.816082)
			(xy 233.555213 -67.808326) (xy 233.609715 -67.808326) (xy 233.663663 -67.816082) (xy 233.715958 -67.831437)
			(xy 233.765535 -67.854079) (xy 233.811385 -67.883545) (xy 233.852576 -67.919236) (xy 233.888267 -67.960427)
			(xy 233.917733 -68.006277) (xy 233.940375 -68.055854) (xy 233.95573 -68.108149) (xy 233.963486 -68.162097)
			(xy 233.963972 -68.189348) (xy 233.963512 -68.21683) (xy 233.955613 -68.271223) (xy 233.939987 -68.323918)
			(xy 233.916956 -68.373823) (xy 233.886998 -68.419905) (xy 233.850734 -68.461207) (xy 233.808915 -68.496875)
			(xy 233.785918 -68.511928) (xy 233.773905 -68.520056) (xy 233.754719 -68.541796) (xy 233.742407 -68.568047)
			(xy 233.737959 -68.596699) (xy 233.741732 -68.625448) (xy 233.753425 -68.651981) (xy 233.772095 -68.674166)
			(xy 233.783886 -68.682616) (xy 233.805969 -68.697829) (xy 233.846022 -68.733483) (xy 233.880685 -68.774397)
			(xy 233.909274 -68.819765) (xy 233.931223 -68.86869) (xy 233.9461 -68.920209) (xy 233.953611 -68.973304)
			(xy 233.954066 -69.000116) (xy 233.95358 -69.027367) (xy 233.945824 -69.081315) (xy 233.930469 -69.13361)
			(xy 233.907827 -69.183187) (xy 233.878361 -69.229037) (xy 233.84267 -69.270228) (xy 233.801479 -69.305919)
			(xy 233.755629 -69.335385) (xy 233.706052 -69.358027) (xy 233.653757 -69.373382) (xy 233.599809 -69.381138)
			(xy 233.545307 -69.381138) (xy 233.491359 -69.373382) (xy 233.439064 -69.358027) (xy 233.389487 -69.335385)
			(xy 233.343637 -69.305919) (xy 233.302446 -69.270228) (xy 233.266755 -69.229037) (xy 233.237289 -69.183187)
			(xy 233.214647 -69.13361) (xy 233.199292 -69.081315) (xy 233.191536 -69.027367) (xy 233.19105 -69.000116)
			(xy 231.875094 -69.000116) (xy 231.929575 -69.070113) (xy 231.982461 -69.151061) (xy 232.028482 -69.236101)
			(xy 232.067323 -69.32465) (xy 232.09872 -69.416105) (xy 232.122456 -69.509839) (xy 232.138372 -69.605214)
			(xy 232.146357 -69.701577) (xy 232.146856 -69.749924) (xy 232.146357 -69.798271) (xy 232.138372 -69.894634)
			(xy 232.122456 -69.990009) (xy 232.09872 -70.083743) (xy 232.067323 -70.175198) (xy 232.028482 -70.263747)
			(xy 231.982461 -70.348787) (xy 231.929575 -70.429735) (xy 231.870184 -70.50604) (xy 231.804696 -70.57718)
			(xy 231.733556 -70.642668) (xy 231.657251 -70.702059) (xy 231.576303 -70.754945) (xy 231.491263 -70.800966)
			(xy 231.402714 -70.839807) (xy 231.311259 -70.871204) (xy 231.217525 -70.89494) (xy 231.12215 -70.910856)
			(xy 231.025787 -70.918841) (xy 230.929093 -70.918841) (xy 230.83273 -70.910856) (xy 230.737355 -70.89494)
			(xy 230.643621 -70.871204) (xy 230.552166 -70.839807) (xy 230.463617 -70.800966) (xy 230.378577 -70.754945)
			(xy 230.297629 -70.702059) (xy 230.221324 -70.642668) (xy 230.150184 -70.57718) (xy 230.084696 -70.50604)
			(xy 230.025305 -70.429735) (xy 229.972419 -70.348787) (xy 229.926398 -70.263747) (xy 229.887557 -70.175198)
			(xy 229.85616 -70.083743) (xy 229.832424 -69.990009) (xy 229.816508 -69.894634) (xy 229.808523 -69.798271)
			(xy 223.902749 -69.798271) (xy 223.760538 -70.194932) (xy 223.431862 -71.111364) (xy 223.27832 -71.539608)
			(xy 238.982504 -71.539608) (xy 238.982948 -71.506727) (xy 238.990314 -71.441379) (xy 239.004955 -71.377268)
			(xy 239.026687 -71.3152) (xy 239.055235 -71.255958) (xy 239.09024 -71.200287) (xy 239.131261 -71.148888)
			(xy 239.154208 -71.125334) (xy 239.612424 -70.667118) (xy 239.619125 -70.659778) (xy 239.626835 -70.64148)
			(xy 239.62741 -70.631558) (xy 239.628172 -70.550278) (xy 239.620552 -70.531482) (xy 239.613694 -70.524624)
			(xy 239.591588 -70.501198) (xy 239.552152 -70.450267) (xy 239.518538 -70.395318) (xy 239.491153 -70.337015)
			(xy 239.470327 -70.276061) (xy 239.456311 -70.21319) (xy 239.449274 -70.149161) (xy 239.448848 -70.116954)
			(xy 239.449328 -70.084083) (xy 239.456669 -70.018753) (xy 239.471278 -69.954656) (xy 239.492969 -69.892596)
			(xy 239.521471 -69.833354) (xy 239.556425 -69.777676) (xy 239.597391 -69.726259) (xy 239.620298 -69.70268)
			(xy 240.214404 -69.108574) (xy 240.237968 -69.085674) (xy 240.289343 -69.044706) (xy 240.344982 -69.009749)
			(xy 240.404186 -68.98124) (xy 240.466209 -68.95954) (xy 240.530272 -68.944921) (xy 240.595569 -68.937566)
			(xy 240.628424 -68.937124) (xy 248.792746 -68.937124) (xy 248.801665 -68.936797) (xy 248.8184 -68.930617)
			(xy 248.831992 -68.919061) (xy 248.836688 -68.91147) (xy 248.887234 -68.822316) (xy 248.88698 -68.795138)
			(xy 248.879868 -68.7832) (xy 248.866919 -68.760846) (xy 248.846494 -68.713395) (xy 248.832666 -68.66362)
			(xy 248.825688 -68.612434) (xy 248.825258 -68.586604) (xy 248.825712 -68.559233) (xy 248.833531 -68.505053)
			(xy 248.849022 -68.452549) (xy 248.871867 -68.402803) (xy 248.901595 -68.356837) (xy 248.919238 -68.335906)
			(xy 248.919492 -68.335652) (xy 248.925062 -68.328554) (xy 248.931319 -68.311646) (xy 248.931684 -68.302632)
			(xy 248.931684 -68.235576) (xy 248.931342 -68.226558) (xy 248.925084 -68.209641) (xy 248.919492 -68.202556)
			(xy 248.919238 -68.202556) (xy 248.919238 -68.202302) (xy 248.901592 -68.181375) (xy 248.87188 -68.135401)
			(xy 248.849045 -68.085653) (xy 248.833555 -68.033151) (xy 248.82573 -67.978974) (xy 248.825258 -67.951604)
			(xy 248.825781 -67.924354) (xy 248.833536 -67.87041) (xy 248.848889 -67.818118) (xy 248.871528 -67.768543)
			(xy 248.90099 -67.722694) (xy 248.936678 -67.681505) (xy 248.977864 -67.645813) (xy 249.023709 -67.616346)
			(xy 249.073282 -67.593703) (xy 249.125573 -67.578345) (xy 249.179516 -67.570584) (xy 249.206766 -67.570096)
			(xy 249.233081 -67.570521) (xy 249.285212 -67.577764) (xy 249.335855 -67.592092) (xy 249.384054 -67.613233)
			(xy 249.428896 -67.640786) (xy 249.469534 -67.674231) (xy 249.48769 -67.693286) (xy 249.495215 -67.700683)
			(xy 249.514492 -67.709211) (xy 249.525028 -67.709796) (xy 249.599704 -67.709796) (xy 249.610256 -67.709284)
			(xy 249.629551 -67.700737) (xy 249.637042 -67.693286) (xy 249.655181 -67.674214) (xy 249.695815 -67.640759)
			(xy 249.740659 -67.613203) (xy 249.788863 -67.592067) (xy 249.839513 -67.577753) (xy 249.891649 -67.570532)
			(xy 249.917966 -67.570096) (xy 249.945335 -67.570583) (xy 249.999514 -67.578396) (xy 250.052016 -67.59388)
			(xy 250.101764 -67.616717) (xy 250.147732 -67.646437) (xy 250.168664 -67.664076) (xy 250.168918 -67.66433)
			(xy 250.175993 -67.669934) (xy 250.192919 -67.676169) (xy 250.201938 -67.676522) (xy 250.268994 -67.676522)
			(xy 250.27801 -67.676157) (xy 250.294927 -67.669914) (xy 250.302014 -67.66433) (xy 250.302014 -67.664076)
			(xy 250.302268 -67.664076) (xy 250.323198 -67.646435) (xy 250.369172 -67.616724) (xy 250.41892 -67.593889)
			(xy 250.471421 -67.578398) (xy 250.525597 -67.57057) (xy 250.552966 -67.570096) (xy 250.580218 -67.570587)
			(xy 250.634168 -67.578339) (xy 250.686466 -67.593691) (xy 250.736046 -67.61633) (xy 250.7819 -67.645795)
			(xy 250.823093 -67.681486) (xy 250.858787 -67.722676) (xy 250.888255 -67.768527) (xy 250.910898 -67.818106)
			(xy 250.926254 -67.870402) (xy 250.934011 -67.924352) (xy 250.934474 -67.951604) (xy 250.934017 -67.978975)
			(xy 250.926198 -68.033154) (xy 250.910707 -68.085658) (xy 250.887863 -68.135405) (xy 250.858136 -68.181371)
			(xy 250.840494 -68.202302) (xy 250.84024 -68.202556) (xy 250.834659 -68.209646) (xy 250.82841 -68.22656)
			(xy 250.828048 -68.235576) (xy 250.828048 -68.302632) (xy 250.828379 -68.311652) (xy 250.834643 -68.328569)
			(xy 250.84024 -68.335652) (xy 250.840494 -68.335652) (xy 250.840494 -68.335906) (xy 250.858148 -68.356826)
			(xy 250.887858 -68.402802) (xy 250.910691 -68.452552) (xy 250.926179 -68.505056) (xy 250.934002 -68.559234)
			(xy 250.934474 -68.586604) (xy 250.934063 -68.612435) (xy 250.927076 -68.663621) (xy 250.913243 -68.713396)
			(xy 250.892818 -68.760848) (xy 250.879864 -68.7832) (xy 250.872752 -68.795138) (xy 250.872498 -68.822316)
			(xy 250.923044 -68.91147) (xy 250.927793 -68.91901) (xy 250.941386 -68.930511) (xy 250.958086 -68.936686)
			(xy 250.966986 -68.937124) (xy 254.275082 -68.937124) (xy 254.286196 -68.936586) (xy 254.306356 -68.927229)
			(xy 254.313944 -68.91909) (xy 254.363982 -68.859908) (xy 254.370737 -68.851192) (xy 254.376654 -68.829972)
			(xy 254.375412 -68.819014) (xy 254.375412 -68.81876) (xy 254.373024 -68.803378) (xy 254.370484 -68.77235)
			(xy 254.370332 -68.756784) (xy 254.370332 -68.75653) (xy 254.370808 -68.72916) (xy 254.378622 -68.674981)
			(xy 254.394108 -68.622478) (xy 254.416948 -68.572731) (xy 254.446671 -68.526764) (xy 254.464312 -68.505832)
			(xy 254.464566 -68.505578) (xy 254.470176 -68.498508) (xy 254.476407 -68.481578) (xy 254.476758 -68.472558)
			(xy 254.476758 -68.405502) (xy 254.476409 -68.396484) (xy 254.470157 -68.379567) (xy 254.464566 -68.372482)
			(xy 254.464312 -68.372482) (xy 254.464312 -68.372228) (xy 254.446674 -68.351295) (xy 254.416962 -68.305322)
			(xy 254.394126 -68.255575) (xy 254.378634 -68.203075) (xy 254.370806 -68.148899) (xy 254.370332 -68.12153)
			(xy 254.370783 -68.094276) (xy 254.378537 -68.040323) (xy 254.393892 -67.988022) (xy 254.416533 -67.938439)
			(xy 254.446002 -67.892584) (xy 254.481697 -67.85139) (xy 254.522892 -67.815696) (xy 254.568748 -67.786229)
			(xy 254.618331 -67.763588) (xy 254.670632 -67.748235) (xy 254.724586 -67.740483) (xy 254.75184 -67.740022)
			(xy 254.779209 -67.740518) (xy 254.833387 -67.748328) (xy 254.88589 -67.76381) (xy 254.935638 -67.786645)
			(xy 254.981606 -67.816363) (xy 255.002538 -67.834002) (xy 255.002792 -67.834256) (xy 255.009872 -67.839852)
			(xy 255.026794 -67.846092) (xy 255.035812 -67.846448) (xy 255.102868 -67.846448) (xy 255.111885 -67.846087)
			(xy 255.128802 -67.839843) (xy 255.135888 -67.834256) (xy 255.135888 -67.834002) (xy 255.136142 -67.834002)
			(xy 255.157085 -67.816377) (xy 255.203055 -67.786663) (xy 255.2528 -67.763824) (xy 255.305298 -67.74833)
			(xy 255.359472 -67.740498) (xy 255.38684 -67.740022) (xy 255.413155 -67.740456) (xy 255.465285 -67.747696)
			(xy 255.515929 -67.762022) (xy 255.564128 -67.78316) (xy 255.608971 -67.810713) (xy 255.649609 -67.844158)
			(xy 255.667764 -67.863212) (xy 255.675295 -67.870602) (xy 255.694568 -67.879133) (xy 255.705102 -67.879722)
			(xy 255.779778 -67.879722) (xy 255.790327 -67.879188) (xy 255.809622 -67.870655) (xy 255.817116 -67.863212)
			(xy 255.835273 -67.844158) (xy 255.875902 -67.8107) (xy 255.920742 -67.783141) (xy 255.968943 -67.762002)
			(xy 256.01959 -67.747685) (xy 256.071724 -67.74046) (xy 256.09804 -67.740022) (xy 256.125294 -67.740441)
			(xy 256.179245 -67.748203) (xy 256.231543 -67.763565) (xy 256.281122 -67.786213) (xy 256.326974 -67.815686)
			(xy 256.368165 -67.851385) (xy 256.403856 -67.892582) (xy 256.43332 -67.938439) (xy 256.455959 -67.988023)
			(xy 256.471311 -68.040323) (xy 256.479064 -68.094276) (xy 256.479548 -68.12153) (xy 256.479112 -68.148901)
			(xy 256.471289 -68.203082) (xy 256.455794 -68.255586) (xy 256.432945 -68.305333) (xy 256.403213 -68.351298)
			(xy 256.385568 -68.372228) (xy 256.385314 -68.372482) (xy 256.37973 -68.379571) (xy 256.373481 -68.396486)
			(xy 256.373122 -68.405502) (xy 256.373122 -68.472558) (xy 256.373494 -68.481573) (xy 256.379731 -68.498491)
			(xy 256.385314 -68.505578) (xy 256.385568 -68.505578) (xy 256.385568 -68.505832) (xy 256.403184 -68.526783)
			(xy 256.4329 -68.57275) (xy 256.455741 -68.622493) (xy 256.471238 -68.674989) (xy 256.479071 -68.729162)
			(xy 256.479548 -68.75653) (xy 256.479548 -68.756784) (xy 256.479379 -68.772349) (xy 256.476838 -68.803376)
			(xy 256.474468 -68.81876) (xy 256.474468 -68.819014) (xy 256.473276 -68.829967) (xy 256.479197 -68.851163)
			(xy 256.485898 -68.859908) (xy 256.535936 -68.91909) (xy 256.543529 -68.927219) (xy 256.563688 -68.936568)
			(xy 256.574798 -68.937124) (xy 256.670048 -68.937124) (xy 256.702902 -68.937563) (xy 256.768196 -68.944932)
			(xy 256.832256 -68.959559) (xy 256.894277 -68.981262) (xy 256.95348 -69.009768) (xy 257.009122 -69.044718)
			(xy 257.060504 -69.085675) (xy 257.084068 -69.108574) (xy 259.068824 -71.09333) (xy 265.140438 -71.09333)
			(xy 265.144509 -71.037708) (xy 265.156635 -70.983271) (xy 265.176558 -70.93118) (xy 265.203854 -70.882545)
			(xy 265.23794 -70.838402) (xy 265.278089 -70.799693) (xy 265.323447 -70.767242) (xy 265.373047 -70.741741)
			(xy 265.425831 -70.723734) (xy 265.480674 -70.713604) (xy 265.536408 -70.711567) (xy 265.591845 -70.717667)
			(xy 265.645802 -70.731773) (xy 265.697131 -70.753585) (xy 265.744737 -70.782639) (xy 265.787605 -70.818314)
			(xy 265.824822 -70.859851) (xy 265.855595 -70.906364) (xy 265.879267 -70.956861) (xy 265.895335 -71.010268)
			(xy 265.903455 -71.065444) (xy 265.903964 -71.09333) (xy 265.903455 -71.121216) (xy 265.895335 -71.176392)
			(xy 265.879267 -71.229799) (xy 265.855595 -71.280296) (xy 265.824822 -71.326809) (xy 265.787605 -71.368346)
			(xy 265.744737 -71.404021) (xy 265.697131 -71.433075) (xy 265.645802 -71.454887) (xy 265.591845 -71.468993)
			(xy 265.536408 -71.475093) (xy 265.480674 -71.473056) (xy 265.425831 -71.462926) (xy 265.373047 -71.444919)
			(xy 265.323447 -71.419418) (xy 265.278089 -71.386967) (xy 265.23794 -71.348258) (xy 265.203854 -71.304115)
			(xy 265.176558 -71.25548) (xy 265.156635 -71.203389) (xy 265.144509 -71.148952) (xy 265.140438 -71.09333)
			(xy 259.068824 -71.09333) (xy 260.892544 -72.91705) (xy 260.899717 -72.923656) (xy 260.917614 -72.93136)
			(xy 260.927342 -72.932036) (xy 260.962167 -72.933367) (xy 261.03114 -72.943362) (xy 261.09844 -72.961469)
			(xy 261.163118 -72.987433) (xy 261.224258 -73.020886) (xy 261.280997 -73.061356) (xy 261.332535 -73.108272)
			(xy 261.378143 -73.160971) (xy 261.417176 -73.218708) (xy 261.449085 -73.280669) (xy 261.473417 -73.345977)
			(xy 261.48983 -73.413711) (xy 261.498091 -73.482913) (xy 261.498588 -73.51776) (xy 261.498073 -73.553159)
			(xy 261.489543 -73.623442) (xy 261.472604 -73.692184) (xy 261.447501 -73.758383) (xy 261.414601 -73.821073)
			(xy 261.374384 -73.879339) (xy 261.327436 -73.932333) (xy 261.274443 -73.979281) (xy 261.216176 -74.019499)
			(xy 261.153486 -74.052399) (xy 261.087288 -74.077502) (xy 261.018546 -74.094443) (xy 260.948263 -74.102973)
			(xy 260.912864 -74.103484) (xy 260.664198 -74.103484) (xy 260.632782 -74.103057) (xy 260.570313 -74.096325)
			(xy 260.508924 -74.082939) (xy 260.449323 -74.063053) (xy 260.392196 -74.036896) (xy 260.364986 -74.021188)
			(xy 260.356425 -74.016565) (xy 260.337215 -74.013571) (xy 260.327648 -74.015346) (xy 260.249924 -74.032872)
			(xy 260.233922 -74.043794) (xy 260.228588 -74.051922) (xy 260.208138 -74.081507) (xy 260.161155 -74.135961)
			(xy 260.10786 -74.184255) (xy 260.049056 -74.225664) (xy 259.985625 -74.259564) (xy 259.918523 -74.285446)
			(xy 259.848757 -74.30292) (xy 259.777377 -74.311725) (xy 259.741416 -74.312272) (xy 259.706021 -74.311675)
			(xy 259.635746 -74.303144) (xy 259.567012 -74.286206) (xy 259.500821 -74.261105) (xy 259.438137 -74.22821)
			(xy 259.379876 -74.187999) (xy 259.326886 -74.141059) (xy 259.27994 -74.088075) (xy 259.239723 -74.029818)
			(xy 259.206821 -73.967138) (xy 259.181714 -73.900949) (xy 259.164767 -73.832217) (xy 259.156229 -73.761943)
			(xy 259.155692 -73.726548) (xy 259.155692 -73.605644) (xy 259.155246 -73.595577) (xy 259.14754 -73.576979)
			(xy 259.140706 -73.569576) (xy 256.22504 -70.65391) (xy 256.217619 -70.647096) (xy 256.199036 -70.639361)
			(xy 256.188972 -70.638924) (xy 241.318542 -70.638924) (xy 241.308474 -70.639365) (xy 241.289876 -70.647074)
			(xy 241.282474 -70.65391) (xy 240.380696 -71.555864) (xy 251.394466 -71.555864) (xy 251.398537 -71.500242)
			(xy 251.410663 -71.445805) (xy 251.430586 -71.393714) (xy 251.457882 -71.345079) (xy 251.491968 -71.300936)
			(xy 251.532117 -71.262227) (xy 251.577475 -71.229776) (xy 251.627075 -71.204275) (xy 251.679859 -71.186268)
			(xy 251.734702 -71.176138) (xy 251.790436 -71.174101) (xy 251.845873 -71.180201) (xy 251.89983 -71.194307)
			(xy 251.951159 -71.216119) (xy 251.998765 -71.245173) (xy 252.041633 -71.280848) (xy 252.07885 -71.322385)
			(xy 252.109623 -71.368898) (xy 252.133295 -71.419395) (xy 252.149363 -71.472802) (xy 252.157483 -71.527978)
			(xy 252.157992 -71.555864) (xy 252.157483 -71.58375) (xy 252.151644 -71.623428) (xy 252.90348 -71.623428)
			(xy 252.907551 -71.567806) (xy 252.919677 -71.513369) (xy 252.9396 -71.461278) (xy 252.966896 -71.412643)
			(xy 253.000982 -71.3685) (xy 253.041131 -71.329791) (xy 253.086489 -71.29734) (xy 253.136089 -71.271839)
			(xy 253.188873 -71.253832) (xy 253.243716 -71.243702) (xy 253.29945 -71.241665) (xy 253.354887 -71.247765)
			(xy 253.408844 -71.261871) (xy 253.460173 -71.283683) (xy 253.507779 -71.312737) (xy 253.550647 -71.348412)
			(xy 253.587864 -71.389949) (xy 253.618637 -71.436462) (xy 253.642309 -71.486959) (xy 253.658377 -71.540366)
			(xy 253.666497 -71.595542) (xy 253.667006 -71.623428) (xy 253.666497 -71.651314) (xy 253.658377 -71.70649)
			(xy 253.642309 -71.759897) (xy 253.618637 -71.810394) (xy 253.587864 -71.856907) (xy 253.550647 -71.898444)
			(xy 253.507779 -71.934119) (xy 253.460173 -71.963173) (xy 253.408844 -71.984985) (xy 253.354887 -71.999091)
			(xy 253.29945 -72.005191) (xy 253.243716 -72.003154) (xy 253.188873 -71.993024) (xy 253.136089 -71.975017)
			(xy 253.086489 -71.949516) (xy 253.041131 -71.917065) (xy 253.000982 -71.878356) (xy 252.966896 -71.834213)
			(xy 252.9396 -71.785578) (xy 252.919677 -71.733487) (xy 252.907551 -71.67905) (xy 252.90348 -71.623428)
			(xy 252.151644 -71.623428) (xy 252.149363 -71.638926) (xy 252.133295 -71.692333) (xy 252.109623 -71.74283)
			(xy 252.07885 -71.789343) (xy 252.041633 -71.83088) (xy 251.998765 -71.866555) (xy 251.951159 -71.895609)
			(xy 251.89983 -71.917421) (xy 251.845873 -71.931527) (xy 251.790436 -71.937627) (xy 251.734702 -71.93559)
			(xy 251.679859 -71.92546) (xy 251.627075 -71.907453) (xy 251.577475 -71.881952) (xy 251.532117 -71.849501)
			(xy 251.491968 -71.810792) (xy 251.457882 -71.766649) (xy 251.430586 -71.718014) (xy 251.410663 -71.665923)
			(xy 251.398537 -71.611486) (xy 251.394466 -71.555864) (xy 240.380696 -71.555864) (xy 239.982756 -71.953882)
			(xy 239.95921 -71.9768) (xy 239.907829 -72.017762) (xy 239.852186 -72.052714) (xy 239.792979 -72.081217)
			(xy 239.730954 -72.102912) (xy 239.666889 -72.117526) (xy 239.601591 -72.124875) (xy 239.568736 -72.125332)
			(xy 239.568482 -72.125332) (xy 239.533077 -72.124861) (xy 239.462783 -72.116326) (xy 239.394029 -72.099381)
			(xy 239.327819 -72.074276) (xy 239.265117 -72.041374) (xy 239.206836 -72.001156) (xy 239.153827 -71.954208)
			(xy 239.106861 -71.901214) (xy 239.066625 -71.842946) (xy 239.033702 -71.780254) (xy 239.008575 -71.714052)
			(xy 238.991609 -71.645304) (xy 238.983051 -71.575013) (xy 238.982504 -71.539608) (xy 223.27832 -71.539608)
			(xy 223.005843 -72.299576) (xy 224.676968 -72.299576) (xy 224.681039 -72.243954) (xy 224.693165 -72.189517)
			(xy 224.713088 -72.137426) (xy 224.740384 -72.088791) (xy 224.77447 -72.044648) (xy 224.814619 -72.005939)
			(xy 224.859977 -71.973488) (xy 224.909577 -71.947987) (xy 224.962361 -71.92998) (xy 225.017204 -71.91985)
			(xy 225.072938 -71.917813) (xy 225.128375 -71.923913) (xy 225.182332 -71.938019) (xy 225.233661 -71.959831)
			(xy 225.281267 -71.988885) (xy 225.324135 -72.02456) (xy 225.361352 -72.066097) (xy 225.392125 -72.11261)
			(xy 225.415797 -72.163107) (xy 225.431865 -72.216514) (xy 225.439985 -72.27169) (xy 225.440494 -72.299576)
			(xy 225.439985 -72.327462) (xy 225.431865 -72.382638) (xy 225.415797 -72.436045) (xy 225.392125 -72.486542)
			(xy 225.361352 -72.533055) (xy 225.324135 -72.574592) (xy 225.281267 -72.610267) (xy 225.233661 -72.639321)
			(xy 225.182332 -72.661133) (xy 225.128375 -72.675239) (xy 225.072938 -72.681339) (xy 225.017204 -72.679302)
			(xy 224.962361 -72.669172) (xy 224.909577 -72.651165) (xy 224.859977 -72.625664) (xy 224.814619 -72.593213)
			(xy 224.77447 -72.554504) (xy 224.740384 -72.510361) (xy 224.713088 -72.461726) (xy 224.693165 -72.409635)
			(xy 224.681039 -72.355198) (xy 224.676968 -72.299576) (xy 223.005843 -72.299576) (xy 222.563613 -73.533)
			(xy 224.641154 -73.533) (xy 224.645225 -73.477378) (xy 224.657351 -73.422941) (xy 224.677274 -73.37085)
			(xy 224.70457 -73.322215) (xy 224.738656 -73.278072) (xy 224.778805 -73.239363) (xy 224.824163 -73.206912)
			(xy 224.873763 -73.181411) (xy 224.926547 -73.163404) (xy 224.98139 -73.153274) (xy 225.037124 -73.151237)
			(xy 225.092561 -73.157337) (xy 225.146518 -73.171443) (xy 225.197847 -73.193255) (xy 225.245453 -73.222309)
			(xy 225.288321 -73.257984) (xy 225.325538 -73.299521) (xy 225.356311 -73.346034) (xy 225.379983 -73.396531)
			(xy 225.396051 -73.449938) (xy 225.404171 -73.505114) (xy 225.40468 -73.533) (xy 225.404171 -73.560886)
			(xy 225.396051 -73.616062) (xy 225.379983 -73.669469) (xy 225.356311 -73.719966) (xy 225.325538 -73.766479)
			(xy 225.288321 -73.808016) (xy 225.245453 -73.843691) (xy 225.197847 -73.872745) (xy 225.146518 -73.894557)
			(xy 225.092561 -73.908663) (xy 225.037124 -73.914763) (xy 224.98139 -73.912726) (xy 224.926547 -73.902596)
			(xy 224.873763 -73.884589) (xy 224.824163 -73.859088) (xy 224.778805 -73.826637) (xy 224.738656 -73.787928)
			(xy 224.70457 -73.743785) (xy 224.677274 -73.69515) (xy 224.657351 -73.643059) (xy 224.645225 -73.588622)
			(xy 224.641154 -73.533) (xy 222.563613 -73.533) (xy 222.376558 -74.054716) (xy 240.911378 -74.054716)
			(xy 240.915449 -73.999094) (xy 240.927575 -73.944657) (xy 240.947498 -73.892566) (xy 240.974794 -73.843931)
			(xy 241.00888 -73.799788) (xy 241.049029 -73.761079) (xy 241.094387 -73.728628) (xy 241.143987 -73.703127)
			(xy 241.196771 -73.68512) (xy 241.251614 -73.67499) (xy 241.307348 -73.672953) (xy 241.362785 -73.679053)
			(xy 241.416742 -73.693159) (xy 241.468071 -73.714971) (xy 241.515677 -73.744025) (xy 241.558545 -73.7797)
			(xy 241.595762 -73.821237) (xy 241.626535 -73.86775) (xy 241.650207 -73.918247) (xy 241.666275 -73.971654)
			(xy 241.674395 -74.02683) (xy 241.674904 -74.054716) (xy 241.674395 -74.082602) (xy 241.666275 -74.137778)
			(xy 241.650207 -74.191185) (xy 241.626535 -74.241682) (xy 241.595762 -74.288195) (xy 241.558545 -74.329732)
			(xy 241.515677 -74.365407) (xy 241.468071 -74.394461) (xy 241.416742 -74.416273) (xy 241.362785 -74.430379)
			(xy 241.307348 -74.436479) (xy 241.251614 -74.434442) (xy 241.196771 -74.424312) (xy 241.143987 -74.406305)
			(xy 241.094387 -74.380804) (xy 241.049029 -74.348353) (xy 241.00888 -74.309644) (xy 240.974794 -74.265501)
			(xy 240.947498 -74.216866) (xy 240.927575 -74.164775) (xy 240.915449 -74.110338) (xy 240.911378 -74.054716)
			(xy 222.376558 -74.054716) (xy 222.345504 -74.14133) (xy 222.342647 -74.150273) (xy 222.343041 -74.169031)
			(xy 222.3502 -74.186374) (xy 222.356426 -74.1934) (xy 222.359728 -74.196702) (xy 222.430594 -74.258932)
			(xy 222.436602 -74.263737) (xy 222.45068 -74.269921) (xy 222.45828 -74.271124) (xy 222.4659 -74.271886)
			(xy 222.480886 -74.269346) (xy 222.48749 -74.26579) (xy 222.514599 -74.25252) (xy 222.571959 -74.233748)
			(xy 222.631557 -74.224222) (xy 222.661734 -74.223626) (xy 222.669862 -74.223626) (xy 222.696743 -74.224641)
			(xy 222.749836 -74.233295) (xy 222.801186 -74.249322) (xy 222.849775 -74.272404) (xy 222.89464 -74.302084)
			(xy 222.93489 -74.337772) (xy 222.969726 -74.378761) (xy 222.998459 -74.424238) (xy 223.020518 -74.4733)
			(xy 223.035464 -74.524975) (xy 223.043003 -74.578237) (xy 223.043496 -74.605134) (xy 223.043007 -74.632383)
			(xy 223.035247 -74.686327) (xy 223.019889 -74.738617) (xy 222.997245 -74.788189) (xy 222.967778 -74.834034)
			(xy 222.932086 -74.875219) (xy 222.890897 -74.910906) (xy 222.845048 -74.940368) (xy 222.795473 -74.963005)
			(xy 222.743182 -74.978357) (xy 222.689237 -74.986111) (xy 222.661988 -74.986642) (xy 222.634235 -74.986142)
			(xy 222.579316 -74.978095) (xy 222.526142 -74.962173) (xy 222.475838 -74.938713) (xy 222.429465 -74.90821)
			(xy 222.388003 -74.871307) (xy 222.352328 -74.828785) (xy 222.323192 -74.781541) (xy 222.311722 -74.756264)
			(xy 222.311722 -74.75601) (xy 222.307404 -74.747262) (xy 222.293485 -74.733618) (xy 222.275487 -74.726135)
			(xy 222.265748 -74.72553) (xy 222.216218 -74.727054) (xy 222.168974 -74.728578) (xy 222.159072 -74.729332)
			(xy 222.140947 -74.737395) (xy 222.127254 -74.751749) (xy 222.123254 -74.760836) (xy 222.082868 -74.873104)
			(xy 221.934059 -75.288385) (xy 262.150829 -75.288385) (xy 262.150829 -75.228415) (xy 262.158657 -75.168959)
			(xy 262.174178 -75.111033) (xy 262.197128 -75.055628) (xy 262.227114 -75.003693) (xy 262.263621 -74.956116)
			(xy 262.306027 -74.913712) (xy 262.353605 -74.877206) (xy 262.405541 -74.847222) (xy 262.460946 -74.824274)
			(xy 262.518872 -74.808754) (xy 262.578329 -74.800928) (xy 262.608314 -74.80046) (xy 263.471914 -74.80046)
			(xy 263.501899 -74.800907) (xy 263.561356 -74.808736) (xy 263.619283 -74.824259) (xy 263.674687 -74.84721)
			(xy 263.726623 -74.877196) (xy 263.7742 -74.913705) (xy 263.816604 -74.956111) (xy 263.853111 -75.003689)
			(xy 263.883096 -75.055625) (xy 263.906045 -75.111031) (xy 263.921566 -75.168958) (xy 263.929394 -75.228415)
			(xy 263.929394 -75.288385) (xy 263.921566 -75.347842) (xy 263.906045 -75.405769) (xy 263.883096 -75.461175)
			(xy 263.853111 -75.513111) (xy 263.816604 -75.560689) (xy 263.7742 -75.603095) (xy 263.726623 -75.639604)
			(xy 263.674687 -75.66959) (xy 263.619283 -75.692541) (xy 263.561356 -75.708064) (xy 263.501899 -75.715893)
			(xy 263.471914 -75.716384) (xy 262.608314 -75.716384) (xy 262.578329 -75.715872) (xy 262.518872 -75.708046)
			(xy 262.460946 -75.692526) (xy 262.405541 -75.669578) (xy 262.353605 -75.639594) (xy 262.306027 -75.603088)
			(xy 262.263621 -75.560684) (xy 262.227114 -75.513107) (xy 262.197128 -75.461172) (xy 262.174178 -75.405767)
			(xy 262.158657 -75.347841) (xy 262.150829 -75.288385) (xy 221.934059 -75.288385) (xy 221.787974 -75.696064)
			(xy 221.784749 -75.70648) (xy 221.786447 -75.728199) (xy 221.791276 -75.737974) (xy 221.83217 -75.806808)
			(xy 221.835146 -75.811582) (xy 221.842835 -75.819791) (xy 221.84741 -75.823064) (xy 221.856046 -75.828906)
			(xy 221.86773 -75.830684) (xy 221.894337 -75.835334) (xy 221.945983 -75.851151) (xy 221.99488 -75.874096)
			(xy 222.040052 -75.90371) (xy 222.080594 -75.9394) (xy 222.115696 -75.980452) (xy 222.144655 -76.026046)
			(xy 222.166892 -76.07527) (xy 222.181963 -76.127138) (xy 222.189567 -76.180613) (xy 222.190056 -76.20762)
			(xy 222.189579 -76.235054) (xy 222.184506 -76.270104) (xy 253.795274 -76.270104) (xy 253.799345 -76.214482)
			(xy 253.811471 -76.160045) (xy 253.831394 -76.107954) (xy 253.85869 -76.059319) (xy 253.892776 -76.015176)
			(xy 253.932925 -75.976467) (xy 253.978283 -75.944016) (xy 254.027883 -75.918515) (xy 254.080667 -75.900508)
			(xy 254.13551 -75.890378) (xy 254.191244 -75.888341) (xy 254.246681 -75.894441) (xy 254.300638 -75.908547)
			(xy 254.351967 -75.930359) (xy 254.399573 -75.959413) (xy 254.442441 -75.995088) (xy 254.479658 -76.036625)
			(xy 254.510431 -76.083138) (xy 254.534103 -76.133635) (xy 254.550171 -76.187042) (xy 254.558291 -76.242218)
			(xy 254.5588 -76.270104) (xy 256.827272 -76.270104) (xy 256.831343 -76.214482) (xy 256.843469 -76.160045)
			(xy 256.863392 -76.107954) (xy 256.890688 -76.059319) (xy 256.924774 -76.015176) (xy 256.964923 -75.976467)
			(xy 257.010281 -75.944016) (xy 257.059881 -75.918515) (xy 257.112665 -75.900508) (xy 257.167508 -75.890378)
			(xy 257.223242 -75.888341) (xy 257.278679 -75.894441) (xy 257.332636 -75.908547) (xy 257.383965 -75.930359)
			(xy 257.431571 -75.959413) (xy 257.474439 -75.995088) (xy 257.511656 -76.036625) (xy 257.542429 -76.083138)
			(xy 257.566101 -76.133635) (xy 257.582169 -76.187042) (xy 257.590289 -76.242218) (xy 257.590798 -76.270104)
			(xy 257.843272 -76.270104) (xy 257.847343 -76.214482) (xy 257.859469 -76.160045) (xy 257.879392 -76.107954)
			(xy 257.906688 -76.059319) (xy 257.940774 -76.015176) (xy 257.980923 -75.976467) (xy 258.026281 -75.944016)
			(xy 258.075881 -75.918515) (xy 258.128665 -75.900508) (xy 258.183508 -75.890378) (xy 258.239242 -75.888341)
			(xy 258.294679 -75.894441) (xy 258.348636 -75.908547) (xy 258.399965 -75.930359) (xy 258.447571 -75.959413)
			(xy 258.490439 -75.995088) (xy 258.527656 -76.036625) (xy 258.558429 -76.083138) (xy 258.582101 -76.133635)
			(xy 258.598169 -76.187042) (xy 258.606289 -76.242218) (xy 258.606798 -76.270104) (xy 258.859272 -76.270104)
			(xy 258.863343 -76.214482) (xy 258.875469 -76.160045) (xy 258.895392 -76.107954) (xy 258.922688 -76.059319)
			(xy 258.956774 -76.015176) (xy 258.996923 -75.976467) (xy 259.042281 -75.944016) (xy 259.091881 -75.918515)
			(xy 259.144665 -75.900508) (xy 259.199508 -75.890378) (xy 259.255242 -75.888341) (xy 259.310679 -75.894441)
			(xy 259.364636 -75.908547) (xy 259.415965 -75.930359) (xy 259.463571 -75.959413) (xy 259.506439 -75.995088)
			(xy 259.543656 -76.036625) (xy 259.574429 -76.083138) (xy 259.598101 -76.133635) (xy 259.614169 -76.187042)
			(xy 259.622289 -76.242218) (xy 259.622798 -76.270104) (xy 260.158228 -76.270104) (xy 260.162299 -76.214482)
			(xy 260.174425 -76.160045) (xy 260.194348 -76.107954) (xy 260.221644 -76.059319) (xy 260.25573 -76.015176)
			(xy 260.295879 -75.976467) (xy 260.341237 -75.944016) (xy 260.390837 -75.918515) (xy 260.443621 -75.900508)
			(xy 260.498464 -75.890378) (xy 260.554198 -75.888341) (xy 260.609635 -75.894441) (xy 260.663592 -75.908547)
			(xy 260.714921 -75.930359) (xy 260.762527 -75.959413) (xy 260.805395 -75.995088) (xy 260.842612 -76.036625)
			(xy 260.873385 -76.083138) (xy 260.897057 -76.133635) (xy 260.913125 -76.187042) (xy 260.920303 -76.235814)
			(xy 261.146288 -76.235814) (xy 261.150359 -76.180192) (xy 261.162485 -76.125755) (xy 261.182408 -76.073664)
			(xy 261.209704 -76.025029) (xy 261.24379 -75.980886) (xy 261.283939 -75.942177) (xy 261.329297 -75.909726)
			(xy 261.378897 -75.884225) (xy 261.431681 -75.866218) (xy 261.486524 -75.856088) (xy 261.542258 -75.854051)
			(xy 261.597695 -75.860151) (xy 261.651652 -75.874257) (xy 261.702981 -75.896069) (xy 261.750587 -75.925123)
			(xy 261.793455 -75.960798) (xy 261.830672 -76.002335) (xy 261.861445 -76.048848) (xy 261.885117 -76.099345)
			(xy 261.901185 -76.152752) (xy 261.909305 -76.207928) (xy 261.909591 -76.223622) (xy 265.213082 -76.223622)
			(xy 265.217153 -76.168) (xy 265.229279 -76.113563) (xy 265.249202 -76.061472) (xy 265.276498 -76.012837)
			(xy 265.310584 -75.968694) (xy 265.350733 -75.929985) (xy 265.396091 -75.897534) (xy 265.445691 -75.872033)
			(xy 265.498475 -75.854026) (xy 265.553318 -75.843896) (xy 265.609052 -75.841859) (xy 265.664489 -75.847959)
			(xy 265.718446 -75.862065) (xy 265.769775 -75.883877) (xy 265.817381 -75.912931) (xy 265.860249 -75.948606)
			(xy 265.897466 -75.990143) (xy 265.928239 -76.036656) (xy 265.951911 -76.087153) (xy 265.967979 -76.14056)
			(xy 265.976099 -76.195736) (xy 265.976608 -76.223622) (xy 265.976099 -76.251508) (xy 265.967979 -76.306684)
			(xy 265.951911 -76.360091) (xy 265.928239 -76.410588) (xy 265.897466 -76.457101) (xy 265.860249 -76.498638)
			(xy 265.817381 -76.534313) (xy 265.769775 -76.563367) (xy 265.718446 -76.585179) (xy 265.664489 -76.599285)
			(xy 265.609052 -76.605385) (xy 265.553318 -76.603348) (xy 265.498475 -76.593218) (xy 265.445691 -76.575211)
			(xy 265.396091 -76.54971) (xy 265.350733 -76.517259) (xy 265.310584 -76.47855) (xy 265.276498 -76.434407)
			(xy 265.249202 -76.385772) (xy 265.229279 -76.333681) (xy 265.217153 -76.279244) (xy 265.213082 -76.223622)
			(xy 261.909591 -76.223622) (xy 261.909814 -76.235814) (xy 261.909305 -76.2637) (xy 261.901185 -76.318876)
			(xy 261.885117 -76.372283) (xy 261.861445 -76.42278) (xy 261.830672 -76.469293) (xy 261.793455 -76.51083)
			(xy 261.750587 -76.546505) (xy 261.702981 -76.575559) (xy 261.651652 -76.597371) (xy 261.597695 -76.611477)
			(xy 261.542258 -76.617577) (xy 261.486524 -76.61554) (xy 261.431681 -76.60541) (xy 261.378897 -76.587403)
			(xy 261.329297 -76.561902) (xy 261.283939 -76.529451) (xy 261.24379 -76.490742) (xy 261.209704 -76.446599)
			(xy 261.182408 -76.397964) (xy 261.162485 -76.345873) (xy 261.150359 -76.291436) (xy 261.146288 -76.235814)
			(xy 260.920303 -76.235814) (xy 260.921245 -76.242218) (xy 260.921754 -76.270104) (xy 260.921245 -76.29799)
			(xy 260.913125 -76.353166) (xy 260.897057 -76.406573) (xy 260.873385 -76.45707) (xy 260.842612 -76.503583)
			(xy 260.805395 -76.54512) (xy 260.762527 -76.580795) (xy 260.714921 -76.609849) (xy 260.663592 -76.631661)
			(xy 260.609635 -76.645767) (xy 260.554198 -76.651867) (xy 260.498464 -76.64983) (xy 260.443621 -76.6397)
			(xy 260.390837 -76.621693) (xy 260.341237 -76.596192) (xy 260.295879 -76.563741) (xy 260.25573 -76.525032)
			(xy 260.221644 -76.480889) (xy 260.194348 -76.432254) (xy 260.174425 -76.380163) (xy 260.162299 -76.325726)
			(xy 260.158228 -76.270104) (xy 259.622798 -76.270104) (xy 259.622289 -76.29799) (xy 259.614169 -76.353166)
			(xy 259.598101 -76.406573) (xy 259.574429 -76.45707) (xy 259.543656 -76.503583) (xy 259.506439 -76.54512)
			(xy 259.463571 -76.580795) (xy 259.415965 -76.609849) (xy 259.364636 -76.631661) (xy 259.310679 -76.645767)
			(xy 259.255242 -76.651867) (xy 259.199508 -76.64983) (xy 259.144665 -76.6397) (xy 259.091881 -76.621693)
			(xy 259.042281 -76.596192) (xy 258.996923 -76.563741) (xy 258.956774 -76.525032) (xy 258.922688 -76.480889)
			(xy 258.895392 -76.432254) (xy 258.875469 -76.380163) (xy 258.863343 -76.325726) (xy 258.859272 -76.270104)
			(xy 258.606798 -76.270104) (xy 258.606289 -76.29799) (xy 258.598169 -76.353166) (xy 258.582101 -76.406573)
			(xy 258.558429 -76.45707) (xy 258.527656 -76.503583) (xy 258.490439 -76.54512) (xy 258.447571 -76.580795)
			(xy 258.399965 -76.609849) (xy 258.348636 -76.631661) (xy 258.294679 -76.645767) (xy 258.239242 -76.651867)
			(xy 258.183508 -76.64983) (xy 258.128665 -76.6397) (xy 258.075881 -76.621693) (xy 258.026281 -76.596192)
			(xy 257.980923 -76.563741) (xy 257.940774 -76.525032) (xy 257.906688 -76.480889) (xy 257.879392 -76.432254)
			(xy 257.859469 -76.380163) (xy 257.847343 -76.325726) (xy 257.843272 -76.270104) (xy 257.590798 -76.270104)
			(xy 257.590289 -76.29799) (xy 257.582169 -76.353166) (xy 257.566101 -76.406573) (xy 257.542429 -76.45707)
			(xy 257.511656 -76.503583) (xy 257.474439 -76.54512) (xy 257.431571 -76.580795) (xy 257.383965 -76.609849)
			(xy 257.332636 -76.631661) (xy 257.278679 -76.645767) (xy 257.223242 -76.651867) (xy 257.167508 -76.64983)
			(xy 257.112665 -76.6397) (xy 257.059881 -76.621693) (xy 257.010281 -76.596192) (xy 256.964923 -76.563741)
			(xy 256.924774 -76.525032) (xy 256.890688 -76.480889) (xy 256.863392 -76.432254) (xy 256.843469 -76.380163)
			(xy 256.831343 -76.325726) (xy 256.827272 -76.270104) (xy 254.5588 -76.270104) (xy 254.558291 -76.29799)
			(xy 254.550171 -76.353166) (xy 254.534103 -76.406573) (xy 254.510431 -76.45707) (xy 254.479658 -76.503583)
			(xy 254.442441 -76.54512) (xy 254.399573 -76.580795) (xy 254.351967 -76.609849) (xy 254.300638 -76.631661)
			(xy 254.246681 -76.645767) (xy 254.191244 -76.651867) (xy 254.13551 -76.64983) (xy 254.080667 -76.6397)
			(xy 254.027883 -76.621693) (xy 253.978283 -76.596192) (xy 253.932925 -76.563741) (xy 253.892776 -76.525032)
			(xy 253.85869 -76.480889) (xy 253.831394 -76.432254) (xy 253.811471 -76.380163) (xy 253.799345 -76.325726)
			(xy 253.795274 -76.270104) (xy 222.184506 -76.270104) (xy 222.181719 -76.289358) (xy 222.166163 -76.341975)
			(xy 222.143233 -76.391823) (xy 222.113401 -76.437874) (xy 222.077281 -76.479177) (xy 222.035619 -76.514883)
			(xy 221.989273 -76.544254) (xy 221.939199 -76.566686) (xy 221.912942 -76.57465) (xy 221.905121 -76.577165)
			(xy 221.891524 -76.586366) (xy 221.886272 -76.592684) (xy 221.880684 -76.602082) (xy 221.848172 -76.671424)
			(xy 221.845929 -76.676538) (xy 221.843487 -76.687432) (xy 221.843346 -76.693014) (xy 221.843346 -76.703682)
			(xy 221.844616 -76.70673) (xy 221.856443 -76.732586) (xy 221.873166 -76.786928) (xy 221.881646 -76.843148)
			(xy 221.882208 -76.871576) (xy 221.881746 -76.89883) (xy 221.873992 -76.952783) (xy 221.858638 -77.005084)
			(xy 221.835997 -77.054667) (xy 221.80653 -77.100523) (xy 221.770836 -77.141719) (xy 221.729643 -77.177415)
			(xy 221.683788 -77.206886) (xy 221.634207 -77.22953) (xy 221.581907 -77.244887) (xy 221.527954 -77.252645)
			(xy 221.5007 -77.253084) (xy 221.500446 -77.253084) (xy 221.472426 -77.252593) (xy 221.416988 -77.244402)
			(xy 221.363346 -77.228188) (xy 221.312652 -77.2043) (xy 221.265999 -77.173253) (xy 221.22439 -77.135715)
			(xy 221.18872 -77.092494) (xy 221.159757 -77.044519) (xy 221.138124 -76.992823) (xy 221.124288 -76.938518)
			(xy 221.12097 -76.910692) (xy 221.12097 -76.910184) (xy 221.119895 -76.902917) (xy 221.114222 -76.889375)
			(xy 221.109794 -76.883514) (xy 221.105222 -76.877926) (xy 221.099126 -76.873862) (xy 221.086934 -76.867766)
			(xy 221.056962 -76.85786) (xy 221.049788 -76.855674) (xy 221.034807 -76.855163) (xy 221.027498 -76.856844)
			(xy 221.020208 -76.859114) (xy 221.007302 -76.867258) (xy 221.002098 -76.872846) (xy 220.942662 -76.9493)
			(xy 220.889322 -77.018134) (xy 220.884091 -77.025441) (xy 220.878628 -77.042549) (xy 220.87938 -77.060492)
			(xy 220.882464 -77.068934) (xy 220.922596 -77.153262) (xy 220.925882 -77.159532) (xy 220.935288 -77.170105)
			(xy 220.941138 -77.17409) (xy 220.953076 -77.18171) (xy 220.967554 -77.181964) (xy 220.994484 -77.182912)
			(xy 221.047688 -77.191452) (xy 221.099161 -77.207393) (xy 221.147879 -77.230419) (xy 221.192872 -77.260071)
			(xy 221.233245 -77.295759) (xy 221.268194 -77.336773) (xy 221.297024 -77.382297) (xy 221.319162 -77.431425)
			(xy 221.334166 -77.483179) (xy 221.341738 -77.536529) (xy 221.342204 -77.563472) (xy 222.62465 -77.563472)
			(xy 222.625214 -77.534544) (xy 222.633953 -77.477352) (xy 222.651228 -77.422136) (xy 222.676641 -77.37016)
			(xy 222.709611 -77.322618) (xy 222.749381 -77.280599) (xy 222.79504 -77.245066) (xy 222.84554 -77.216834)
			(xy 222.899723 -77.196551) (xy 222.927926 -77.190092) (xy 222.942126 -77.186685) (xy 222.967846 -77.172874)
			(xy 222.988617 -77.152358) (xy 223.002745 -77.126811) (xy 223.009079 -77.098312) (xy 223.007103 -77.069185)
			(xy 222.996978 -77.041803) (xy 222.988632 -77.029818) (xy 222.970842 -77.004942) (xy 222.942568 -76.950716)
			(xy 222.923305 -76.892674) (xy 222.913547 -76.832303) (xy 222.91294 -76.801726) (xy 222.913426 -76.774475)
			(xy 222.921182 -76.720527) (xy 222.936537 -76.668232) (xy 222.959179 -76.618655) (xy 222.988645 -76.572805)
			(xy 223.024336 -76.531614) (xy 223.065527 -76.495923) (xy 223.111377 -76.466457) (xy 223.160954 -76.443815)
			(xy 223.213249 -76.42846) (xy 223.267197 -76.420704) (xy 223.321699 -76.420704) (xy 223.375647 -76.42846)
			(xy 223.427942 -76.443815) (xy 223.477519 -76.466457) (xy 223.523369 -76.495923) (xy 223.56456 -76.531614)
			(xy 223.600251 -76.572805) (xy 223.629717 -76.618655) (xy 223.652359 -76.668232) (xy 223.667714 -76.720527)
			(xy 223.67547 -76.774475) (xy 223.675956 -76.801726) (xy 223.675476 -76.826085) (xy 229.640845 -76.826085)
			(xy 229.640845 -76.766115) (xy 229.648673 -76.706658) (xy 229.664196 -76.648731) (xy 229.687147 -76.593327)
			(xy 229.717134 -76.541392) (xy 229.753643 -76.493816) (xy 229.796051 -76.451413) (xy 229.84363 -76.414908)
			(xy 229.895568 -76.384926) (xy 229.950975 -76.361981) (xy 230.008903 -76.346464) (xy 230.068361 -76.338642)
			(xy 230.098346 -76.338176) (xy 230.961946 -76.338176) (xy 230.991931 -76.338593) (xy 231.051387 -76.346426)
			(xy 231.109312 -76.361952) (xy 231.164715 -76.384906) (xy 231.216648 -76.414894) (xy 231.264223 -76.451404)
			(xy 231.306626 -76.493811) (xy 231.343131 -76.54139) (xy 231.373114 -76.593326) (xy 231.396063 -76.648732)
			(xy 231.411583 -76.706658) (xy 231.41941 -76.766115) (xy 231.41941 -76.826085) (xy 231.415862 -76.853034)
			(xy 236.02264 -76.853034) (xy 236.026711 -76.797412) (xy 236.038837 -76.742975) (xy 236.05876 -76.690884)
			(xy 236.086056 -76.642249) (xy 236.120142 -76.598106) (xy 236.160291 -76.559397) (xy 236.205649 -76.526946)
			(xy 236.255249 -76.501445) (xy 236.308033 -76.483438) (xy 236.362876 -76.473308) (xy 236.41861 -76.471271)
			(xy 236.474047 -76.477371) (xy 236.528004 -76.491477) (xy 236.579333 -76.513289) (xy 236.626939 -76.542343)
			(xy 236.669807 -76.578018) (xy 236.707024 -76.619555) (xy 236.737797 -76.666068) (xy 236.761469 -76.716565)
			(xy 236.777537 -76.769972) (xy 236.785657 -76.825148) (xy 236.786166 -76.853034) (xy 236.785657 -76.88092)
			(xy 236.777537 -76.936096) (xy 236.761469 -76.989503) (xy 236.737797 -77.04) (xy 236.707024 -77.086513)
			(xy 236.669807 -77.12805) (xy 236.626939 -77.163725) (xy 236.579333 -77.192779) (xy 236.528004 -77.214591)
			(xy 236.474047 -77.228697) (xy 236.41861 -77.234797) (xy 236.362876 -77.23276) (xy 236.308033 -77.22263)
			(xy 236.255249 -77.204623) (xy 236.205649 -77.179122) (xy 236.160291 -77.146671) (xy 236.120142 -77.107962)
			(xy 236.086056 -77.063819) (xy 236.05876 -77.015184) (xy 236.038837 -76.963093) (xy 236.026711 -76.908656)
			(xy 236.02264 -76.853034) (xy 231.415862 -76.853034) (xy 231.411583 -76.885542) (xy 231.396063 -76.943468)
			(xy 231.373114 -76.998874) (xy 231.343131 -77.05081) (xy 231.306626 -77.098389) (xy 231.264223 -77.140796)
			(xy 231.216648 -77.177306) (xy 231.164715 -77.207294) (xy 231.109312 -77.230248) (xy 231.051387 -77.245774)
			(xy 230.991931 -77.253607) (xy 230.961946 -77.2541) (xy 230.098346 -77.2541) (xy 230.068361 -77.253558)
			(xy 230.008903 -77.245736) (xy 229.950975 -77.230219) (xy 229.895568 -77.207274) (xy 229.84363 -77.177292)
			(xy 229.796051 -77.140787) (xy 229.753643 -77.098384) (xy 229.717134 -77.050808) (xy 229.687147 -76.998873)
			(xy 229.664196 -76.943469) (xy 229.648673 -76.885542) (xy 229.640845 -76.826085) (xy 223.675476 -76.826085)
			(xy 223.675386 -76.830654) (xy 223.666647 -76.887845) (xy 223.649373 -76.943061) (xy 223.62396 -76.995036)
			(xy 223.590991 -77.042578) (xy 223.551222 -77.084598) (xy 223.505564 -77.120131) (xy 223.455065 -77.148363)
			(xy 223.400882 -77.168647) (xy 223.37268 -77.175106) (xy 223.358481 -77.178519) (xy 223.332761 -77.192328)
			(xy 223.31199 -77.212843) (xy 223.297862 -77.238389) (xy 223.291528 -77.266887) (xy 223.293503 -77.296014)
			(xy 223.303628 -77.323395) (xy 223.311974 -77.33538) (xy 223.329764 -77.360257) (xy 223.358038 -77.414483)
			(xy 223.377301 -77.472524) (xy 223.387059 -77.532895) (xy 223.387666 -77.563472) (xy 224.659188 -77.563472)
			(xy 224.663259 -77.50785) (xy 224.675385 -77.453413) (xy 224.695308 -77.401322) (xy 224.722604 -77.352687)
			(xy 224.75669 -77.308544) (xy 224.796839 -77.269835) (xy 224.842197 -77.237384) (xy 224.891797 -77.211883)
			(xy 224.944581 -77.193876) (xy 224.999424 -77.183746) (xy 225.055158 -77.181709) (xy 225.110595 -77.187809)
			(xy 225.164552 -77.201915) (xy 225.215881 -77.223727) (xy 225.263487 -77.252781) (xy 225.306355 -77.288456)
			(xy 225.343572 -77.329993) (xy 225.366461 -77.36459) (xy 234.24591 -77.36459) (xy 234.249981 -77.308968)
			(xy 234.262107 -77.254531) (xy 234.28203 -77.20244) (xy 234.309326 -77.153805) (xy 234.343412 -77.109662)
			(xy 234.383561 -77.070953) (xy 234.428919 -77.038502) (xy 234.478519 -77.013001) (xy 234.531303 -76.994994)
			(xy 234.586146 -76.984864) (xy 234.64188 -76.982827) (xy 234.697317 -76.988927) (xy 234.751274 -77.003033)
			(xy 234.802603 -77.024845) (xy 234.850209 -77.053899) (xy 234.893077 -77.089574) (xy 234.930294 -77.131111)
			(xy 234.961067 -77.177624) (xy 234.984739 -77.228121) (xy 235.000807 -77.281528) (xy 235.008927 -77.336704)
			(xy 235.009436 -77.36459) (xy 235.008927 -77.392476) (xy 235.000807 -77.447652) (xy 234.984739 -77.501059)
			(xy 234.961067 -77.551556) (xy 234.930294 -77.598069) (xy 234.893077 -77.639606) (xy 234.850209 -77.675281)
			(xy 234.802603 -77.704335) (xy 234.751274 -77.726147) (xy 234.697317 -77.740253) (xy 234.64188 -77.746353)
			(xy 234.586146 -77.744316) (xy 234.531303 -77.734186) (xy 234.478519 -77.716179) (xy 234.428919 -77.690678)
			(xy 234.383561 -77.658227) (xy 234.343412 -77.619518) (xy 234.309326 -77.575375) (xy 234.28203 -77.52674)
			(xy 234.262107 -77.474649) (xy 234.249981 -77.420212) (xy 234.24591 -77.36459) (xy 225.366461 -77.36459)
			(xy 225.374345 -77.376506) (xy 225.398017 -77.427003) (xy 225.414085 -77.48041) (xy 225.422205 -77.535586)
			(xy 225.422714 -77.563472) (xy 225.422205 -77.591358) (xy 225.414085 -77.646534) (xy 225.398017 -77.699941)
			(xy 225.374345 -77.750438) (xy 225.343572 -77.796951) (xy 225.306355 -77.838488) (xy 225.263487 -77.874163)
			(xy 225.215881 -77.903217) (xy 225.164552 -77.925029) (xy 225.110595 -77.939135) (xy 225.055158 -77.945235)
			(xy 224.999424 -77.943198) (xy 224.944581 -77.933068) (xy 224.891797 -77.915061) (xy 224.842197 -77.88956)
			(xy 224.796839 -77.857109) (xy 224.75669 -77.8184) (xy 224.722604 -77.774257) (xy 224.695308 -77.725622)
			(xy 224.675385 -77.673531) (xy 224.663259 -77.619094) (xy 224.659188 -77.563472) (xy 223.387666 -77.563472)
			(xy 223.38718 -77.590723) (xy 223.379424 -77.644671) (xy 223.364069 -77.696966) (xy 223.341427 -77.746543)
			(xy 223.311961 -77.792393) (xy 223.27627 -77.833584) (xy 223.235079 -77.869275) (xy 223.189229 -77.898741)
			(xy 223.139652 -77.921383) (xy 223.087357 -77.936738) (xy 223.033409 -77.944494) (xy 222.978907 -77.944494)
			(xy 222.924959 -77.936738) (xy 222.872664 -77.921383) (xy 222.823087 -77.898741) (xy 222.777237 -77.869275)
			(xy 222.736046 -77.833584) (xy 222.700355 -77.792393) (xy 222.670889 -77.746543) (xy 222.648247 -77.696966)
			(xy 222.632892 -77.644671) (xy 222.625136 -77.590723) (xy 222.62465 -77.563472) (xy 221.342204 -77.563472)
			(xy 221.341743 -77.590726) (xy 221.333989 -77.64468) (xy 221.318635 -77.696981) (xy 221.295994 -77.746564)
			(xy 221.266527 -77.792421) (xy 221.230833 -77.833616) (xy 221.18964 -77.869313) (xy 221.143785 -77.898783)
			(xy 221.094203 -77.921427) (xy 221.041903 -77.936784) (xy 220.98795 -77.944541) (xy 220.960696 -77.94498)
			(xy 220.934317 -77.944527) (xy 220.882064 -77.937243) (xy 220.831314 -77.922827) (xy 220.783034 -77.901556)
			(xy 220.738146 -77.873835) (xy 220.697506 -77.840193) (xy 220.66189 -77.801272) (xy 220.631976 -77.757814)
			(xy 220.608337 -77.710648) (xy 220.591422 -77.660675) (xy 220.586046 -77.634846) (xy 220.583506 -77.622654)
			(xy 220.561154 -77.594714) (xy 220.557014 -77.58974) (xy 220.546729 -77.58189) (xy 220.540834 -77.57922)
			(xy 220.47073 -77.550518) (xy 220.466611 -77.549133) (xy 220.458056 -77.547607) (xy 220.453712 -77.54747)
			(xy 220.423486 -77.557376) (xy 220.417136 -77.561948) (xy 220.39065 -77.580778) (xy 220.335614 -77.615348)
			(xy 220.307154 -77.631036) (xy 219.499942 -78.069186) (xy 219.492184 -78.073785) (xy 219.480272 -78.087311)
			(xy 219.473778 -78.104123) (xy 219.473272 -78.113128) (xy 219.47251 -78.203298) (xy 219.472931 -78.211941)
			(xy 219.478862 -78.228184) (xy 219.4899 -78.241496) (xy 219.497148 -78.246224) (xy 219.522164 -78.260814)
			(xy 219.567876 -78.296367) (xy 219.607695 -78.338415) (xy 219.640709 -78.385993) (xy 219.66616 -78.43801)
			(xy 219.683466 -78.493274) (xy 219.692229 -78.550517) (xy 219.692728 -78.579472) (xy 222.62414 -78.579472)
			(xy 222.628211 -78.52385) (xy 222.640337 -78.469413) (xy 222.66026 -78.417322) (xy 222.687556 -78.368687)
			(xy 222.721642 -78.324544) (xy 222.761791 -78.285835) (xy 222.807149 -78.253384) (xy 222.856749 -78.227883)
			(xy 222.909533 -78.209876) (xy 222.964376 -78.199746) (xy 223.02011 -78.197709) (xy 223.075547 -78.203809)
			(xy 223.129504 -78.217915) (xy 223.180833 -78.239727) (xy 223.228439 -78.268781) (xy 223.271307 -78.304456)
			(xy 223.308524 -78.345993) (xy 223.339297 -78.392506) (xy 223.362969 -78.443003) (xy 223.379037 -78.49641)
			(xy 223.387157 -78.551586) (xy 223.387666 -78.579472) (xy 224.659188 -78.579472) (xy 224.663259 -78.52385)
			(xy 224.675385 -78.469413) (xy 224.695308 -78.417322) (xy 224.722604 -78.368687) (xy 224.75669 -78.324544)
			(xy 224.796839 -78.285835) (xy 224.842197 -78.253384) (xy 224.891797 -78.227883) (xy 224.944581 -78.209876)
			(xy 224.999424 -78.199746) (xy 225.055158 -78.197709) (xy 225.110595 -78.203809) (xy 225.164552 -78.217915)
			(xy 225.215881 -78.239727) (xy 225.263487 -78.268781) (xy 225.306355 -78.304456) (xy 225.343572 -78.345993)
			(xy 225.374345 -78.392506) (xy 225.398017 -78.443003) (xy 225.414085 -78.49641) (xy 225.422205 -78.551586)
			(xy 225.422714 -78.579472) (xy 225.422205 -78.607358) (xy 225.414085 -78.662534) (xy 225.398017 -78.715941)
			(xy 225.374345 -78.766438) (xy 225.343572 -78.812951) (xy 225.306355 -78.854488) (xy 225.263487 -78.890163)
			(xy 225.215881 -78.919217) (xy 225.164552 -78.941029) (xy 225.110595 -78.955135) (xy 225.055158 -78.961235)
			(xy 224.999424 -78.959198) (xy 224.944581 -78.949068) (xy 224.891797 -78.931061) (xy 224.842197 -78.90556)
			(xy 224.796839 -78.873109) (xy 224.75669 -78.8344) (xy 224.722604 -78.790257) (xy 224.695308 -78.741622)
			(xy 224.675385 -78.689531) (xy 224.663259 -78.635094) (xy 224.659188 -78.579472) (xy 223.387666 -78.579472)
			(xy 223.387157 -78.607358) (xy 223.379037 -78.662534) (xy 223.362969 -78.715941) (xy 223.339297 -78.766438)
			(xy 223.308524 -78.812951) (xy 223.271307 -78.854488) (xy 223.228439 -78.890163) (xy 223.180833 -78.919217)
			(xy 223.129504 -78.941029) (xy 223.075547 -78.955135) (xy 223.02011 -78.961235) (xy 222.964376 -78.959198)
			(xy 222.909533 -78.949068) (xy 222.856749 -78.931061) (xy 222.807149 -78.90556) (xy 222.761791 -78.873109)
			(xy 222.721642 -78.8344) (xy 222.687556 -78.790257) (xy 222.66026 -78.741622) (xy 222.640337 -78.689531)
			(xy 222.628211 -78.635094) (xy 222.62414 -78.579472) (xy 219.692728 -78.579472) (xy 219.692267 -78.606727)
			(xy 219.684513 -78.660682) (xy 219.66916 -78.712984) (xy 219.646519 -78.762569) (xy 219.617052 -78.808427)
			(xy 219.581359 -78.849625) (xy 219.540166 -78.885324) (xy 219.494311 -78.914796) (xy 219.444729 -78.937443)
			(xy 219.392429 -78.952803) (xy 219.338475 -78.960564) (xy 219.31122 -78.96098) (xy 219.310966 -78.96098)
			(xy 219.283832 -78.9605) (xy 219.230113 -78.952804) (xy 219.178027 -78.937574) (xy 219.128625 -78.915116)
			(xy 219.082904 -78.885884) (xy 219.041787 -78.850467) (xy 219.006104 -78.809581) (xy 218.976575 -78.764051)
			(xy 218.953797 -78.714796) (xy 218.938229 -78.662809) (xy 218.930185 -78.609141) (xy 218.929458 -78.582012)
			(xy 218.929458 -78.579218) (xy 218.93022 -78.555088) (xy 218.93022 -78.554834) (xy 218.930474 -78.548005)
			(xy 218.927763 -78.534617) (xy 218.924886 -78.528418) (xy 218.922092 -78.52283) (xy 218.913202 -78.512924)
			(xy 218.832176 -78.461108) (xy 218.828112 -78.458822) (xy 218.816762 -78.453639) (xy 218.791841 -78.453888)
			(xy 218.780614 -78.45933) (xy 216.686289 -79.595472) (xy 220.578678 -79.595472) (xy 220.582749 -79.53985)
			(xy 220.594875 -79.485413) (xy 220.614798 -79.433322) (xy 220.642094 -79.384687) (xy 220.67618 -79.340544)
			(xy 220.716329 -79.301835) (xy 220.761687 -79.269384) (xy 220.811287 -79.243883) (xy 220.864071 -79.225876)
			(xy 220.918914 -79.215746) (xy 220.974648 -79.213709) (xy 221.030085 -79.219809) (xy 221.084042 -79.233915)
			(xy 221.135371 -79.255727) (xy 221.182977 -79.284781) (xy 221.225845 -79.320456) (xy 221.263062 -79.361993)
			(xy 221.293835 -79.408506) (xy 221.317507 -79.459003) (xy 221.333575 -79.51241) (xy 221.341695 -79.567586)
			(xy 221.342204 -79.595472) (xy 222.62414 -79.595472) (xy 222.628211 -79.53985) (xy 222.640337 -79.485413)
			(xy 222.66026 -79.433322) (xy 222.687556 -79.384687) (xy 222.721642 -79.340544) (xy 222.761791 -79.301835)
			(xy 222.807149 -79.269384) (xy 222.856749 -79.243883) (xy 222.909533 -79.225876) (xy 222.964376 -79.215746)
			(xy 223.02011 -79.213709) (xy 223.075547 -79.219809) (xy 223.129504 -79.233915) (xy 223.180833 -79.255727)
			(xy 223.228439 -79.284781) (xy 223.271307 -79.320456) (xy 223.308524 -79.361993) (xy 223.339297 -79.408506)
			(xy 223.362969 -79.459003) (xy 223.379037 -79.51241) (xy 223.387157 -79.567586) (xy 223.387666 -79.595472)
			(xy 224.659188 -79.595472) (xy 224.663259 -79.53985) (xy 224.675385 -79.485413) (xy 224.695308 -79.433322)
			(xy 224.722604 -79.384687) (xy 224.75669 -79.340544) (xy 224.796839 -79.301835) (xy 224.842197 -79.269384)
			(xy 224.891797 -79.243883) (xy 224.944581 -79.225876) (xy 224.999424 -79.215746) (xy 225.055158 -79.213709)
			(xy 225.110595 -79.219809) (xy 225.164552 -79.233915) (xy 225.174386 -79.238094) (xy 227.9777 -79.238094)
			(xy 227.9777 -78.374494) (xy 227.97819 -78.344526) (xy 227.986013 -78.285104) (xy 228.001526 -78.227211)
			(xy 228.024462 -78.171838) (xy 228.054429 -78.119932) (xy 228.090916 -78.072382) (xy 228.133296 -78.030002)
			(xy 228.180846 -77.993515) (xy 228.232752 -77.963548) (xy 228.288125 -77.940612) (xy 228.346018 -77.925099)
			(xy 228.40544 -77.917276) (xy 228.465376 -77.917276) (xy 228.524798 -77.925099) (xy 228.582691 -77.940612)
			(xy 228.638064 -77.963548) (xy 228.68997 -77.993515) (xy 228.73752 -78.030002) (xy 228.7799 -78.072382)
			(xy 228.792845 -78.089252) (xy 232.193844 -78.089252) (xy 232.197915 -78.03363) (xy 232.210041 -77.979193)
			(xy 232.229964 -77.927102) (xy 232.25726 -77.878467) (xy 232.291346 -77.834324) (xy 232.331495 -77.795615)
			(xy 232.376853 -77.763164) (xy 232.426453 -77.737663) (xy 232.479237 -77.719656) (xy 232.53408 -77.709526)
			(xy 232.589814 -77.707489) (xy 232.645251 -77.713589) (xy 232.699208 -77.727695) (xy 232.750537 -77.749507)
			(xy 232.798143 -77.778561) (xy 232.841011 -77.814236) (xy 232.878228 -77.855773) (xy 232.909001 -77.902286)
			(xy 232.932673 -77.952783) (xy 232.948741 -78.00619) (xy 232.956861 -78.061366) (xy 232.95737 -78.089252)
			(xy 232.956861 -78.117138) (xy 232.948741 -78.172314) (xy 232.932673 -78.225721) (xy 232.909001 -78.276218)
			(xy 232.878228 -78.322731) (xy 232.841011 -78.364268) (xy 232.798143 -78.399943) (xy 232.750537 -78.428997)
			(xy 232.699208 -78.450809) (xy 232.645251 -78.464915) (xy 232.589814 -78.471015) (xy 232.53408 -78.468978)
			(xy 232.479237 -78.458848) (xy 232.426453 -78.440841) (xy 232.376853 -78.41534) (xy 232.331495 -78.382889)
			(xy 232.291346 -78.34418) (xy 232.25726 -78.300037) (xy 232.229964 -78.251402) (xy 232.210041 -78.199311)
			(xy 232.197915 -78.144874) (xy 232.193844 -78.089252) (xy 228.792845 -78.089252) (xy 228.816387 -78.119932)
			(xy 228.846354 -78.171838) (xy 228.86929 -78.227211) (xy 228.884803 -78.285104) (xy 228.892626 -78.344526)
			(xy 228.893116 -78.374494) (xy 228.893116 -79.005684) (xy 231.53446 -79.005684) (xy 231.538531 -78.950062)
			(xy 231.550657 -78.895625) (xy 231.57058 -78.843534) (xy 231.597876 -78.794899) (xy 231.631962 -78.750756)
			(xy 231.672111 -78.712047) (xy 231.717469 -78.679596) (xy 231.767069 -78.654095) (xy 231.819853 -78.636088)
			(xy 231.874696 -78.625958) (xy 231.93043 -78.623921) (xy 231.985867 -78.630021) (xy 232.036378 -78.643226)
			(xy 254.273302 -78.643226) (xy 254.277373 -78.587604) (xy 254.289499 -78.533167) (xy 254.309422 -78.481076)
			(xy 254.336718 -78.432441) (xy 254.370804 -78.388298) (xy 254.410953 -78.349589) (xy 254.456311 -78.317138)
			(xy 254.505911 -78.291637) (xy 254.558695 -78.27363) (xy 254.613538 -78.2635) (xy 254.669272 -78.261463)
			(xy 254.724709 -78.267563) (xy 254.778666 -78.281669) (xy 254.829995 -78.303481) (xy 254.877601 -78.332535)
			(xy 254.920469 -78.36821) (xy 254.957686 -78.409747) (xy 254.988459 -78.45626) (xy 255.009783 -78.501748)
			(xy 256.284728 -78.501748) (xy 256.288799 -78.446126) (xy 256.300925 -78.391689) (xy 256.320848 -78.339598)
			(xy 256.348144 -78.290963) (xy 256.38223 -78.24682) (xy 256.422379 -78.208111) (xy 256.467737 -78.17566)
			(xy 256.517337 -78.150159) (xy 256.570121 -78.132152) (xy 256.624964 -78.122022) (xy 256.680698 -78.119985)
			(xy 256.736135 -78.126085) (xy 256.790092 -78.140191) (xy 256.841421 -78.162003) (xy 256.889027 -78.191057)
			(xy 256.931895 -78.226732) (xy 256.969112 -78.268269) (xy 256.999885 -78.314782) (xy 257.023557 -78.365279)
			(xy 257.039625 -78.418686) (xy 257.047745 -78.473862) (xy 257.048254 -78.501748) (xy 257.047745 -78.529634)
			(xy 257.039625 -78.58481) (xy 257.023557 -78.638217) (xy 256.999885 -78.688714) (xy 256.969112 -78.735227)
			(xy 256.931895 -78.776764) (xy 256.889027 -78.812439) (xy 256.84291 -78.840584) (xy 259.167884 -78.840584)
			(xy 259.16837 -78.813333) (xy 259.176126 -78.759385) (xy 259.191481 -78.70709) (xy 259.214123 -78.657513)
			(xy 259.243589 -78.611663) (xy 259.27928 -78.570472) (xy 259.320471 -78.534781) (xy 259.366321 -78.505315)
			(xy 259.415898 -78.482673) (xy 259.468193 -78.467318) (xy 259.522141 -78.459562) (xy 259.576643 -78.459562)
			(xy 259.630591 -78.467318) (xy 259.682886 -78.482673) (xy 259.732463 -78.505315) (xy 259.778313 -78.534781)
			(xy 259.819504 -78.570472) (xy 259.855195 -78.611663) (xy 259.884661 -78.657513) (xy 259.907303 -78.70709)
			(xy 259.922658 -78.759385) (xy 259.930414 -78.813333) (xy 259.9309 -78.840584) (xy 259.930263 -78.872204)
			(xy 259.919821 -78.934576) (xy 259.89922 -78.994367) (xy 259.884672 -79.022448) (xy 259.880642 -79.030795)
			(xy 259.878307 -79.049168) (xy 259.8801 -79.058262) (xy 259.89788 -79.133446) (xy 259.908548 -79.149194)
			(xy 259.916168 -79.154274) (xy 259.937487 -79.169642) (xy 259.976117 -79.205275) (xy 260.009493 -79.24587)
			(xy 260.036983 -79.290661) (xy 260.058069 -79.338799) (xy 260.072352 -79.389376) (xy 260.07956 -79.441433)
			(xy 260.079998 -79.46771) (xy 260.079512 -79.494961) (xy 260.071756 -79.548909) (xy 260.056401 -79.601204)
			(xy 260.037442 -79.642716) (xy 261.293862 -79.642716) (xy 261.297933 -79.587094) (xy 261.310059 -79.532657)
			(xy 261.329982 -79.480566) (xy 261.357278 -79.431931) (xy 261.391364 -79.387788) (xy 261.431513 -79.349079)
			(xy 261.476871 -79.316628) (xy 261.526471 -79.291127) (xy 261.579255 -79.27312) (xy 261.634098 -79.26299)
			(xy 261.689832 -79.260953) (xy 261.745269 -79.267053) (xy 261.799226 -79.281159) (xy 261.850555 -79.302971)
			(xy 261.898161 -79.332025) (xy 261.941029 -79.3677) (xy 261.978246 -79.409237) (xy 262.009019 -79.45575)
			(xy 262.032691 -79.506247) (xy 262.048759 -79.559654) (xy 262.056879 -79.61483) (xy 262.057388 -79.642716)
			(xy 262.056879 -79.670602) (xy 262.048759 -79.725778) (xy 262.032691 -79.779185) (xy 262.009019 -79.829682)
			(xy 261.978246 -79.876195) (xy 261.941029 -79.917732) (xy 261.898161 -79.953407) (xy 261.850555 -79.982461)
			(xy 261.799226 -80.004273) (xy 261.745269 -80.018379) (xy 261.689832 -80.024479) (xy 261.634098 -80.022442)
			(xy 261.579255 -80.012312) (xy 261.526471 -79.994305) (xy 261.476871 -79.968804) (xy 261.431513 -79.936353)
			(xy 261.391364 -79.897644) (xy 261.357278 -79.853501) (xy 261.329982 -79.804866) (xy 261.310059 -79.752775)
			(xy 261.297933 -79.698338) (xy 261.293862 -79.642716) (xy 260.037442 -79.642716) (xy 260.033759 -79.650781)
			(xy 260.004293 -79.696631) (xy 259.968602 -79.737822) (xy 259.927411 -79.773513) (xy 259.881561 -79.802979)
			(xy 259.831984 -79.825621) (xy 259.779689 -79.840976) (xy 259.725741 -79.848732) (xy 259.671239 -79.848732)
			(xy 259.617291 -79.840976) (xy 259.564996 -79.825621) (xy 259.515419 -79.802979) (xy 259.469569 -79.773513)
			(xy 259.428378 -79.737822) (xy 259.392687 -79.696631) (xy 259.363221 -79.650781) (xy 259.340579 -79.601204)
			(xy 259.325224 -79.548909) (xy 259.317468 -79.494961) (xy 259.316982 -79.46771) (xy 259.317618 -79.43609)
			(xy 259.328061 -79.373718) (xy 259.348662 -79.313927) (xy 259.36321 -79.285846) (xy 259.367243 -79.2775)
			(xy 259.369576 -79.259127) (xy 259.367782 -79.250032) (xy 259.350002 -79.174848) (xy 259.339334 -79.1591)
			(xy 259.331714 -79.15402) (xy 259.310388 -79.138661) (xy 259.271759 -79.103026) (xy 259.238385 -79.062429)
			(xy 259.210895 -79.017637) (xy 259.18981 -78.969497) (xy 259.175529 -78.91892) (xy 259.168321 -78.866861)
			(xy 259.167884 -78.840584) (xy 256.84291 -78.840584) (xy 256.841421 -78.841493) (xy 256.790092 -78.863305)
			(xy 256.736135 -78.877411) (xy 256.680698 -78.883511) (xy 256.624964 -78.881474) (xy 256.570121 -78.871344)
			(xy 256.517337 -78.853337) (xy 256.467737 -78.827836) (xy 256.422379 -78.795385) (xy 256.38223 -78.756676)
			(xy 256.348144 -78.712533) (xy 256.320848 -78.663898) (xy 256.300925 -78.611807) (xy 256.288799 -78.55737)
			(xy 256.284728 -78.501748) (xy 255.009783 -78.501748) (xy 255.012131 -78.506757) (xy 255.028199 -78.560164)
			(xy 255.036319 -78.61534) (xy 255.036828 -78.643226) (xy 255.036319 -78.671112) (xy 255.028199 -78.726288)
			(xy 255.012131 -78.779695) (xy 254.988459 -78.830192) (xy 254.957686 -78.876705) (xy 254.920469 -78.918242)
			(xy 254.877601 -78.953917) (xy 254.829995 -78.982971) (xy 254.778666 -79.004783) (xy 254.724709 -79.018889)
			(xy 254.669272 -79.024989) (xy 254.613538 -79.022952) (xy 254.558695 -79.012822) (xy 254.505911 -78.994815)
			(xy 254.456311 -78.969314) (xy 254.410953 -78.936863) (xy 254.370804 -78.898154) (xy 254.336718 -78.854011)
			(xy 254.309422 -78.805376) (xy 254.289499 -78.753285) (xy 254.277373 -78.698848) (xy 254.273302 -78.643226)
			(xy 232.036378 -78.643226) (xy 232.039824 -78.644127) (xy 232.091153 -78.665939) (xy 232.138759 -78.694993)
			(xy 232.181627 -78.730668) (xy 232.218844 -78.772205) (xy 232.249617 -78.818718) (xy 232.273289 -78.869215)
			(xy 232.289357 -78.922622) (xy 232.297477 -78.977798) (xy 232.297986 -79.005684) (xy 232.297477 -79.03357)
			(xy 232.289357 -79.088746) (xy 232.273289 -79.142153) (xy 232.249617 -79.19265) (xy 232.218844 -79.239163)
			(xy 232.181627 -79.2807) (xy 232.138759 -79.316375) (xy 232.091153 -79.345429) (xy 232.039824 -79.367241)
			(xy 231.985867 -79.381347) (xy 231.93043 -79.387447) (xy 231.874696 -79.38541) (xy 231.819853 -79.37528)
			(xy 231.767069 -79.357273) (xy 231.717469 -79.331772) (xy 231.672111 -79.299321) (xy 231.631962 -79.260612)
			(xy 231.597876 -79.216469) (xy 231.57058 -79.167834) (xy 231.550657 -79.115743) (xy 231.538531 -79.061306)
			(xy 231.53446 -79.005684) (xy 228.893116 -79.005684) (xy 228.893116 -79.238094) (xy 228.892626 -79.268062)
			(xy 228.884803 -79.327484) (xy 228.86929 -79.385377) (xy 228.846354 -79.44075) (xy 228.816387 -79.492656)
			(xy 228.7799 -79.540206) (xy 228.73752 -79.582586) (xy 228.68997 -79.619073) (xy 228.638064 -79.64904)
			(xy 228.582691 -79.671976) (xy 228.524798 -79.687489) (xy 228.465376 -79.695312) (xy 228.40544 -79.695312)
			(xy 228.346018 -79.687489) (xy 228.288125 -79.671976) (xy 228.232752 -79.64904) (xy 228.180846 -79.619073)
			(xy 228.133296 -79.582586) (xy 228.090916 -79.540206) (xy 228.054429 -79.492656) (xy 228.024462 -79.44075)
			(xy 228.001526 -79.385377) (xy 227.986013 -79.327484) (xy 227.97819 -79.268062) (xy 227.9777 -79.238094)
			(xy 225.174386 -79.238094) (xy 225.215881 -79.255727) (xy 225.263487 -79.284781) (xy 225.306355 -79.320456)
			(xy 225.343572 -79.361993) (xy 225.374345 -79.408506) (xy 225.398017 -79.459003) (xy 225.414085 -79.51241)
			(xy 225.422205 -79.567586) (xy 225.422714 -79.595472) (xy 225.422205 -79.623358) (xy 225.414085 -79.678534)
			(xy 225.398017 -79.731941) (xy 225.374345 -79.782438) (xy 225.343572 -79.828951) (xy 225.306355 -79.870488)
			(xy 225.263487 -79.906163) (xy 225.215881 -79.935217) (xy 225.164552 -79.957029) (xy 225.110595 -79.971135)
			(xy 225.055158 -79.977235) (xy 224.999424 -79.975198) (xy 224.944581 -79.965068) (xy 224.891797 -79.947061)
			(xy 224.842197 -79.92156) (xy 224.796839 -79.889109) (xy 224.75669 -79.8504) (xy 224.722604 -79.806257)
			(xy 224.695308 -79.757622) (xy 224.675385 -79.705531) (xy 224.663259 -79.651094) (xy 224.659188 -79.595472)
			(xy 223.387666 -79.595472) (xy 223.387157 -79.623358) (xy 223.379037 -79.678534) (xy 223.362969 -79.731941)
			(xy 223.339297 -79.782438) (xy 223.308524 -79.828951) (xy 223.271307 -79.870488) (xy 223.228439 -79.906163)
			(xy 223.180833 -79.935217) (xy 223.129504 -79.957029) (xy 223.075547 -79.971135) (xy 223.02011 -79.977235)
			(xy 222.964376 -79.975198) (xy 222.909533 -79.965068) (xy 222.856749 -79.947061) (xy 222.807149 -79.92156)
			(xy 222.761791 -79.889109) (xy 222.721642 -79.8504) (xy 222.687556 -79.806257) (xy 222.66026 -79.757622)
			(xy 222.640337 -79.705531) (xy 222.628211 -79.651094) (xy 222.62414 -79.595472) (xy 221.342204 -79.595472)
			(xy 221.341695 -79.623358) (xy 221.333575 -79.678534) (xy 221.317507 -79.731941) (xy 221.293835 -79.782438)
			(xy 221.263062 -79.828951) (xy 221.225845 -79.870488) (xy 221.182977 -79.906163) (xy 221.135371 -79.935217)
			(xy 221.084042 -79.957029) (xy 221.030085 -79.971135) (xy 220.974648 -79.977235) (xy 220.918914 -79.975198)
			(xy 220.864071 -79.965068) (xy 220.811287 -79.947061) (xy 220.761687 -79.92156) (xy 220.716329 -79.889109)
			(xy 220.67618 -79.8504) (xy 220.642094 -79.806257) (xy 220.614798 -79.757622) (xy 220.594875 -79.705531)
			(xy 220.582749 -79.651094) (xy 220.578678 -79.595472) (xy 216.686289 -79.595472) (xy 214.999779 -80.51038)
			(xy 218.929202 -80.51038) (xy 218.933273 -80.454758) (xy 218.945399 -80.400321) (xy 218.965322 -80.34823)
			(xy 218.992618 -80.299595) (xy 219.026704 -80.255452) (xy 219.066853 -80.216743) (xy 219.112211 -80.184292)
			(xy 219.161811 -80.158791) (xy 219.214595 -80.140784) (xy 219.269438 -80.130654) (xy 219.325172 -80.128617)
			(xy 219.380609 -80.134717) (xy 219.434566 -80.148823) (xy 219.485895 -80.170635) (xy 219.506945 -80.183482)
			(xy 237.540292 -80.183482) (xy 237.540292 -79.319882) (xy 237.540782 -79.289914) (xy 237.548605 -79.230492)
			(xy 237.564118 -79.172599) (xy 237.587054 -79.117226) (xy 237.617021 -79.06532) (xy 237.653508 -79.01777)
			(xy 237.695888 -78.97539) (xy 237.743438 -78.938903) (xy 237.795344 -78.908936) (xy 237.850717 -78.886)
			(xy 237.90861 -78.870487) (xy 237.968032 -78.862664) (xy 238.027968 -78.862664) (xy 238.08739 -78.870487)
			(xy 238.145283 -78.886) (xy 238.200656 -78.908936) (xy 238.252562 -78.938903) (xy 238.300112 -78.97539)
			(xy 238.342492 -79.01777) (xy 238.378979 -79.06532) (xy 238.408946 -79.117226) (xy 238.431882 -79.172599)
			(xy 238.447395 -79.230492) (xy 238.455218 -79.289914) (xy 238.455708 -79.319882) (xy 238.455708 -79.779368)
			(xy 250.4473 -79.779368) (xy 250.451371 -79.723746) (xy 250.463497 -79.669309) (xy 250.48342 -79.617218)
			(xy 250.510716 -79.568583) (xy 250.544802 -79.52444) (xy 250.584951 -79.485731) (xy 250.630309 -79.45328)
			(xy 250.679909 -79.427779) (xy 250.732693 -79.409772) (xy 250.787536 -79.399642) (xy 250.84327 -79.397605)
			(xy 250.898707 -79.403705) (xy 250.952664 -79.417811) (xy 251.003993 -79.439623) (xy 251.051599 -79.468677)
			(xy 251.094467 -79.504352) (xy 251.131684 -79.545889) (xy 251.162457 -79.592402) (xy 251.186129 -79.642899)
			(xy 251.202197 -79.696306) (xy 251.210317 -79.751482) (xy 251.210826 -79.779368) (xy 251.210317 -79.807254)
			(xy 251.202197 -79.86243) (xy 251.186129 -79.915837) (xy 251.162457 -79.966334) (xy 251.131684 -80.012847)
			(xy 251.094467 -80.054384) (xy 251.051599 -80.090059) (xy 251.003993 -80.119113) (xy 250.952664 -80.140925)
			(xy 250.898707 -80.155031) (xy 250.84327 -80.161131) (xy 250.787536 -80.159094) (xy 250.732693 -80.148964)
			(xy 250.679909 -80.130957) (xy 250.630309 -80.105456) (xy 250.584951 -80.073005) (xy 250.544802 -80.034296)
			(xy 250.510716 -79.990153) (xy 250.48342 -79.941518) (xy 250.463497 -79.889427) (xy 250.451371 -79.83499)
			(xy 250.4473 -79.779368) (xy 238.455708 -79.779368) (xy 238.455708 -80.183482) (xy 238.455218 -80.21345)
			(xy 238.447395 -80.272872) (xy 238.431882 -80.330765) (xy 238.408946 -80.386138) (xy 238.378979 -80.438044)
			(xy 238.342492 -80.485594) (xy 238.300112 -80.527974) (xy 238.252562 -80.564461) (xy 238.200656 -80.594428)
			(xy 238.145283 -80.617364) (xy 238.08739 -80.632877) (xy 238.027968 -80.6407) (xy 237.968032 -80.6407)
			(xy 237.90861 -80.632877) (xy 237.850717 -80.617364) (xy 237.795344 -80.594428) (xy 237.743438 -80.564461)
			(xy 237.695888 -80.527974) (xy 237.653508 -80.485594) (xy 237.617021 -80.438044) (xy 237.587054 -80.386138)
			(xy 237.564118 -80.330765) (xy 237.548605 -80.272872) (xy 237.540782 -80.21345) (xy 237.540292 -80.183482)
			(xy 219.506945 -80.183482) (xy 219.533501 -80.199689) (xy 219.576369 -80.235364) (xy 219.613586 -80.276901)
			(xy 219.644359 -80.323414) (xy 219.668031 -80.373911) (xy 219.684099 -80.427318) (xy 219.692219 -80.482494)
			(xy 219.692728 -80.51038) (xy 219.692219 -80.538266) (xy 219.684099 -80.593442) (xy 219.678675 -80.611472)
			(xy 222.62414 -80.611472) (xy 222.628211 -80.55585) (xy 222.640337 -80.501413) (xy 222.66026 -80.449322)
			(xy 222.687556 -80.400687) (xy 222.721642 -80.356544) (xy 222.761791 -80.317835) (xy 222.807149 -80.285384)
			(xy 222.856749 -80.259883) (xy 222.909533 -80.241876) (xy 222.964376 -80.231746) (xy 223.02011 -80.229709)
			(xy 223.075547 -80.235809) (xy 223.129504 -80.249915) (xy 223.180833 -80.271727) (xy 223.228439 -80.300781)
			(xy 223.271307 -80.336456) (xy 223.308524 -80.377993) (xy 223.339297 -80.424506) (xy 223.362969 -80.475003)
			(xy 223.379037 -80.52841) (xy 223.387157 -80.583586) (xy 223.387666 -80.611472) (xy 224.659188 -80.611472)
			(xy 224.663259 -80.55585) (xy 224.675385 -80.501413) (xy 224.695308 -80.449322) (xy 224.722604 -80.400687)
			(xy 224.75669 -80.356544) (xy 224.796839 -80.317835) (xy 224.842197 -80.285384) (xy 224.891797 -80.259883)
			(xy 224.944581 -80.241876) (xy 224.999424 -80.231746) (xy 225.055158 -80.229709) (xy 225.110595 -80.235809)
			(xy 225.164552 -80.249915) (xy 225.215881 -80.271727) (xy 225.263487 -80.300781) (xy 225.306355 -80.336456)
			(xy 225.343572 -80.377993) (xy 225.374345 -80.424506) (xy 225.398017 -80.475003) (xy 225.414085 -80.52841)
			(xy 225.422205 -80.583586) (xy 225.422714 -80.611472) (xy 225.422205 -80.639358) (xy 225.414085 -80.694534)
			(xy 225.398017 -80.747941) (xy 225.393049 -80.758538) (xy 241.160044 -80.758538) (xy 241.164115 -80.702916)
			(xy 241.176241 -80.648479) (xy 241.196164 -80.596388) (xy 241.22346 -80.547753) (xy 241.257546 -80.50361)
			(xy 241.297695 -80.464901) (xy 241.343053 -80.43245) (xy 241.392653 -80.406949) (xy 241.445437 -80.388942)
			(xy 241.50028 -80.378812) (xy 241.556014 -80.376775) (xy 241.611451 -80.382875) (xy 241.665408 -80.396981)
			(xy 241.716737 -80.418793) (xy 241.764343 -80.447847) (xy 241.807211 -80.483522) (xy 241.844428 -80.525059)
			(xy 241.875201 -80.571572) (xy 241.898873 -80.622069) (xy 241.914941 -80.675476) (xy 241.923061 -80.730652)
			(xy 241.92357 -80.758538) (xy 241.923061 -80.786424) (xy 241.918642 -80.81645) (xy 251.98019 -80.81645)
			(xy 251.984261 -80.760828) (xy 251.996387 -80.706391) (xy 252.01631 -80.6543) (xy 252.043606 -80.605665)
			(xy 252.077692 -80.561522) (xy 252.117841 -80.522813) (xy 252.163199 -80.490362) (xy 252.212799 -80.464861)
			(xy 252.265583 -80.446854) (xy 252.320426 -80.436724) (xy 252.37616 -80.434687) (xy 252.431597 -80.440787)
			(xy 252.485554 -80.454893) (xy 252.536883 -80.476705) (xy 252.584489 -80.505759) (xy 252.627357 -80.541434)
			(xy 252.664574 -80.582971) (xy 252.695347 -80.629484) (xy 252.719019 -80.679981) (xy 252.735087 -80.733388)
			(xy 252.740994 -80.773524) (xy 253.898652 -80.773524) (xy 253.902723 -80.717902) (xy 253.914849 -80.663465)
			(xy 253.934772 -80.611374) (xy 253.962068 -80.562739) (xy 253.996154 -80.518596) (xy 254.036303 -80.479887)
			(xy 254.081661 -80.447436) (xy 254.131261 -80.421935) (xy 254.184045 -80.403928) (xy 254.238888 -80.393798)
			(xy 254.294622 -80.391761) (xy 254.350059 -80.397861) (xy 254.404016 -80.411967) (xy 254.455345 -80.433779)
			(xy 254.502951 -80.462833) (xy 254.545819 -80.498508) (xy 254.583036 -80.540045) (xy 254.613809 -80.586558)
			(xy 254.637481 -80.637055) (xy 254.653549 -80.690462) (xy 254.661669 -80.745638) (xy 254.662178 -80.773524)
			(xy 254.661669 -80.80141) (xy 254.653549 -80.856586) (xy 254.637481 -80.909993) (xy 254.613809 -80.96049)
			(xy 254.583036 -81.007003) (xy 254.545819 -81.04854) (xy 254.502951 -81.084215) (xy 254.455345 -81.113269)
			(xy 254.404016 -81.135081) (xy 254.350059 -81.149187) (xy 254.294622 -81.155287) (xy 254.238888 -81.15325)
			(xy 254.184045 -81.14312) (xy 254.131261 -81.125113) (xy 254.081661 -81.099612) (xy 254.036303 -81.067161)
			(xy 253.996154 -81.028452) (xy 253.962068 -80.984309) (xy 253.934772 -80.935674) (xy 253.914849 -80.883583)
			(xy 253.902723 -80.829146) (xy 253.898652 -80.773524) (xy 252.740994 -80.773524) (xy 252.743207 -80.788564)
			(xy 252.743716 -80.81645) (xy 252.743207 -80.844336) (xy 252.735087 -80.899512) (xy 252.719019 -80.952919)
			(xy 252.695347 -81.003416) (xy 252.664574 -81.049929) (xy 252.627357 -81.091466) (xy 252.584489 -81.127141)
			(xy 252.536883 -81.156195) (xy 252.485554 -81.178007) (xy 252.431597 -81.192113) (xy 252.37616 -81.198213)
			(xy 252.320426 -81.196176) (xy 252.265583 -81.186046) (xy 252.212799 -81.168039) (xy 252.163199 -81.142538)
			(xy 252.117841 -81.110087) (xy 252.077692 -81.071378) (xy 252.043606 -81.027235) (xy 252.01631 -80.9786)
			(xy 251.996387 -80.926509) (xy 251.984261 -80.872072) (xy 251.98019 -80.81645) (xy 241.918642 -80.81645)
			(xy 241.914941 -80.8416) (xy 241.898873 -80.895007) (xy 241.875201 -80.945504) (xy 241.844428 -80.992017)
			(xy 241.807211 -81.033554) (xy 241.764343 -81.069229) (xy 241.716737 -81.098283) (xy 241.665408 -81.120095)
			(xy 241.611451 -81.134201) (xy 241.556014 -81.140301) (xy 241.50028 -81.138264) (xy 241.445437 -81.128134)
			(xy 241.392653 -81.110127) (xy 241.343053 -81.084626) (xy 241.297695 -81.052175) (xy 241.257546 -81.013466)
			(xy 241.22346 -80.969323) (xy 241.196164 -80.920688) (xy 241.176241 -80.868597) (xy 241.164115 -80.81416)
			(xy 241.160044 -80.758538) (xy 225.393049 -80.758538) (xy 225.374345 -80.798438) (xy 225.343572 -80.844951)
			(xy 225.306355 -80.886488) (xy 225.263487 -80.922163) (xy 225.215881 -80.951217) (xy 225.164552 -80.973029)
			(xy 225.110595 -80.987135) (xy 225.055158 -80.993235) (xy 224.999424 -80.991198) (xy 224.944581 -80.981068)
			(xy 224.891797 -80.963061) (xy 224.842197 -80.93756) (xy 224.796839 -80.905109) (xy 224.75669 -80.8664)
			(xy 224.722604 -80.822257) (xy 224.695308 -80.773622) (xy 224.675385 -80.721531) (xy 224.663259 -80.667094)
			(xy 224.659188 -80.611472) (xy 223.387666 -80.611472) (xy 223.387157 -80.639358) (xy 223.379037 -80.694534)
			(xy 223.362969 -80.747941) (xy 223.339297 -80.798438) (xy 223.308524 -80.844951) (xy 223.271307 -80.886488)
			(xy 223.228439 -80.922163) (xy 223.180833 -80.951217) (xy 223.129504 -80.973029) (xy 223.075547 -80.987135)
			(xy 223.02011 -80.993235) (xy 222.964376 -80.991198) (xy 222.909533 -80.981068) (xy 222.856749 -80.963061)
			(xy 222.807149 -80.93756) (xy 222.761791 -80.905109) (xy 222.721642 -80.8664) (xy 222.687556 -80.822257)
			(xy 222.66026 -80.773622) (xy 222.640337 -80.721531) (xy 222.628211 -80.667094) (xy 222.62414 -80.611472)
			(xy 219.678675 -80.611472) (xy 219.668031 -80.646849) (xy 219.644359 -80.697346) (xy 219.613586 -80.743859)
			(xy 219.576369 -80.785396) (xy 219.533501 -80.821071) (xy 219.485895 -80.850125) (xy 219.434566 -80.871937)
			(xy 219.380609 -80.886043) (xy 219.325172 -80.892143) (xy 219.269438 -80.890106) (xy 219.214595 -80.879976)
			(xy 219.161811 -80.861969) (xy 219.112211 -80.836468) (xy 219.066853 -80.804017) (xy 219.026704 -80.765308)
			(xy 218.992618 -80.721165) (xy 218.965322 -80.67253) (xy 218.945399 -80.620439) (xy 218.933273 -80.566002)
			(xy 218.929202 -80.51038) (xy 214.999779 -80.51038) (xy 213.794594 -81.164176) (xy 213.791339 -81.166011)
			(xy 213.785344 -81.17047) (xy 213.782656 -81.173066) (xy 213.757002 -81.19872) (xy 240.342164 -81.19872)
			(xy 240.346235 -81.143098) (xy 240.358361 -81.088661) (xy 240.378284 -81.03657) (xy 240.40558 -80.987935)
			(xy 240.439666 -80.943792) (xy 240.479815 -80.905083) (xy 240.525173 -80.872632) (xy 240.574773 -80.847131)
			(xy 240.627557 -80.829124) (xy 240.6824 -80.818994) (xy 240.738134 -80.816957) (xy 240.793571 -80.823057)
			(xy 240.847528 -80.837163) (xy 240.898857 -80.858975) (xy 240.946463 -80.888029) (xy 240.989331 -80.923704)
			(xy 241.026548 -80.965241) (xy 241.057321 -81.011754) (xy 241.080993 -81.062251) (xy 241.097061 -81.115658)
			(xy 241.105181 -81.170834) (xy 241.10569 -81.19872) (xy 241.105181 -81.226606) (xy 241.097061 -81.281782)
			(xy 241.080993 -81.335189) (xy 241.057321 -81.385686) (xy 241.026548 -81.432199) (xy 240.989331 -81.473736)
			(xy 240.946463 -81.509411) (xy 240.898857 -81.538465) (xy 240.847528 -81.560277) (xy 240.837281 -81.562956)
			(xy 264.230864 -81.562956) (xy 264.234935 -81.507334) (xy 264.247061 -81.452897) (xy 264.266984 -81.400806)
			(xy 264.29428 -81.352171) (xy 264.328366 -81.308028) (xy 264.368515 -81.269319) (xy 264.413873 -81.236868)
			(xy 264.463473 -81.211367) (xy 264.516257 -81.19336) (xy 264.5711 -81.18323) (xy 264.626834 -81.181193)
			(xy 264.682271 -81.187293) (xy 264.736228 -81.201399) (xy 264.787557 -81.223211) (xy 264.835163 -81.252265)
			(xy 264.878031 -81.28794) (xy 264.915248 -81.329477) (xy 264.946021 -81.37599) (xy 264.969693 -81.426487)
			(xy 264.985761 -81.479894) (xy 264.993881 -81.53507) (xy 264.99439 -81.562956) (xy 264.993881 -81.590842)
			(xy 264.985761 -81.646018) (xy 264.969693 -81.699425) (xy 264.946021 -81.749922) (xy 264.915248 -81.796435)
			(xy 264.878031 -81.837972) (xy 264.835163 -81.873647) (xy 264.787557 -81.902701) (xy 264.736228 -81.924513)
			(xy 264.682271 -81.938619) (xy 264.626834 -81.944719) (xy 264.5711 -81.942682) (xy 264.516257 -81.932552)
			(xy 264.463473 -81.914545) (xy 264.413873 -81.889044) (xy 264.368515 -81.856593) (xy 264.328366 -81.817884)
			(xy 264.29428 -81.773741) (xy 264.266984 -81.725106) (xy 264.247061 -81.673015) (xy 264.234935 -81.618578)
			(xy 264.230864 -81.562956) (xy 240.837281 -81.562956) (xy 240.793571 -81.574383) (xy 240.738134 -81.580483)
			(xy 240.6824 -81.578446) (xy 240.627557 -81.568316) (xy 240.574773 -81.550309) (xy 240.525173 -81.524808)
			(xy 240.479815 -81.492357) (xy 240.439666 -81.453648) (xy 240.40558 -81.409505) (xy 240.378284 -81.36087)
			(xy 240.358361 -81.308779) (xy 240.346235 -81.254342) (xy 240.342164 -81.19872) (xy 213.757002 -81.19872)
			(xy 213.32825 -81.627472) (xy 220.578678 -81.627472) (xy 220.582749 -81.57185) (xy 220.594875 -81.517413)
			(xy 220.614798 -81.465322) (xy 220.642094 -81.416687) (xy 220.67618 -81.372544) (xy 220.716329 -81.333835)
			(xy 220.761687 -81.301384) (xy 220.811287 -81.275883) (xy 220.864071 -81.257876) (xy 220.918914 -81.247746)
			(xy 220.974648 -81.245709) (xy 221.030085 -81.251809) (xy 221.084042 -81.265915) (xy 221.135371 -81.287727)
			(xy 221.182977 -81.316781) (xy 221.225845 -81.352456) (xy 221.263062 -81.393993) (xy 221.293835 -81.440506)
			(xy 221.317507 -81.491003) (xy 221.333575 -81.54441) (xy 221.341695 -81.599586) (xy 221.342204 -81.627472)
			(xy 222.62414 -81.627472) (xy 222.628211 -81.57185) (xy 222.640337 -81.517413) (xy 222.66026 -81.465322)
			(xy 222.687556 -81.416687) (xy 222.721642 -81.372544) (xy 222.761791 -81.333835) (xy 222.807149 -81.301384)
			(xy 222.856749 -81.275883) (xy 222.909533 -81.257876) (xy 222.964376 -81.247746) (xy 223.02011 -81.245709)
			(xy 223.075547 -81.251809) (xy 223.129504 -81.265915) (xy 223.180833 -81.287727) (xy 223.228439 -81.316781)
			(xy 223.271307 -81.352456) (xy 223.308524 -81.393993) (xy 223.339297 -81.440506) (xy 223.362969 -81.491003)
			(xy 223.379037 -81.54441) (xy 223.387157 -81.599586) (xy 223.387666 -81.627472) (xy 224.650044 -81.627472)
			(xy 224.654115 -81.57185) (xy 224.666241 -81.517413) (xy 224.686164 -81.465322) (xy 224.71346 -81.416687)
			(xy 224.747546 -81.372544) (xy 224.787695 -81.333835) (xy 224.833053 -81.301384) (xy 224.882653 -81.275883)
			(xy 224.935437 -81.257876) (xy 224.99028 -81.247746) (xy 225.046014 -81.245709) (xy 225.101451 -81.251809)
			(xy 225.155408 -81.265915) (xy 225.206737 -81.287727) (xy 225.254343 -81.316781) (xy 225.297211 -81.352456)
			(xy 225.334428 -81.393993) (xy 225.365201 -81.440506) (xy 225.388873 -81.491003) (xy 225.404941 -81.54441)
			(xy 225.413061 -81.599586) (xy 225.41357 -81.627472) (xy 225.413061 -81.655358) (xy 225.404941 -81.710534)
			(xy 225.388873 -81.763941) (xy 225.365201 -81.814438) (xy 225.334428 -81.860951) (xy 225.297211 -81.902488)
			(xy 225.254343 -81.938163) (xy 225.206737 -81.967217) (xy 225.155408 -81.989029) (xy 225.101451 -82.003135)
			(xy 225.046014 -82.009235) (xy 224.99028 -82.007198) (xy 224.935437 -81.997068) (xy 224.882653 -81.979061)
			(xy 224.833053 -81.95356) (xy 224.787695 -81.921109) (xy 224.747546 -81.8824) (xy 224.71346 -81.838257)
			(xy 224.686164 -81.789622) (xy 224.666241 -81.737531) (xy 224.654115 -81.683094) (xy 224.650044 -81.627472)
			(xy 223.387666 -81.627472) (xy 223.387157 -81.655358) (xy 223.379037 -81.710534) (xy 223.362969 -81.763941)
			(xy 223.339297 -81.814438) (xy 223.308524 -81.860951) (xy 223.271307 -81.902488) (xy 223.228439 -81.938163)
			(xy 223.180833 -81.967217) (xy 223.129504 -81.989029) (xy 223.075547 -82.003135) (xy 223.02011 -82.009235)
			(xy 222.964376 -82.007198) (xy 222.909533 -81.997068) (xy 222.856749 -81.979061) (xy 222.807149 -81.95356)
			(xy 222.761791 -81.921109) (xy 222.721642 -81.8824) (xy 222.687556 -81.838257) (xy 222.66026 -81.789622)
			(xy 222.640337 -81.737531) (xy 222.628211 -81.683094) (xy 222.62414 -81.627472) (xy 221.342204 -81.627472)
			(xy 221.341695 -81.655358) (xy 221.333575 -81.710534) (xy 221.317507 -81.763941) (xy 221.293835 -81.814438)
			(xy 221.263062 -81.860951) (xy 221.225845 -81.902488) (xy 221.182977 -81.938163) (xy 221.135371 -81.967217)
			(xy 221.084042 -81.989029) (xy 221.030085 -82.003135) (xy 220.974648 -82.009235) (xy 220.918914 -82.007198)
			(xy 220.864071 -81.997068) (xy 220.811287 -81.979061) (xy 220.761687 -81.95356) (xy 220.716329 -81.921109)
			(xy 220.67618 -81.8824) (xy 220.642094 -81.838257) (xy 220.614798 -81.789622) (xy 220.594875 -81.737531)
			(xy 220.582749 -81.683094) (xy 220.578678 -81.627472) (xy 213.32825 -81.627472) (xy 213.033356 -81.922366)
			(xy 212.443047 -82.512916) (xy 213.546942 -82.512916) (xy 213.551013 -82.457294) (xy 213.563139 -82.402857)
			(xy 213.583062 -82.350766) (xy 213.610358 -82.302131) (xy 213.644444 -82.257988) (xy 213.684593 -82.219279)
			(xy 213.729951 -82.186828) (xy 213.779551 -82.161327) (xy 213.832335 -82.14332) (xy 213.887178 -82.13319)
			(xy 213.942912 -82.131153) (xy 213.998349 -82.137253) (xy 214.052306 -82.151359) (xy 214.103635 -82.173171)
			(xy 214.151241 -82.202225) (xy 214.194109 -82.2379) (xy 214.231326 -82.279437) (xy 214.262099 -82.32595)
			(xy 214.285771 -82.376447) (xy 214.300159 -82.42427) (xy 218.848938 -82.42427) (xy 218.853009 -82.368648)
			(xy 218.865135 -82.314211) (xy 218.885058 -82.26212) (xy 218.912354 -82.213485) (xy 218.94644 -82.169342)
			(xy 218.986589 -82.130633) (xy 219.031947 -82.098182) (xy 219.081547 -82.072681) (xy 219.134331 -82.054674)
			(xy 219.189174 -82.044544) (xy 219.244908 -82.042507) (xy 219.300345 -82.048607) (xy 219.354302 -82.062713)
			(xy 219.405631 -82.084525) (xy 219.453237 -82.113579) (xy 219.496105 -82.149254) (xy 219.533322 -82.190791)
			(xy 219.564095 -82.237304) (xy 219.587767 -82.287801) (xy 219.603835 -82.341208) (xy 219.611955 -82.396384)
			(xy 219.612464 -82.42427) (xy 219.611955 -82.452156) (xy 219.603835 -82.507332) (xy 219.587767 -82.560739)
			(xy 219.564095 -82.611236) (xy 219.542768 -82.643472) (xy 222.62414 -82.643472) (xy 222.628211 -82.58785)
			(xy 222.640337 -82.533413) (xy 222.66026 -82.481322) (xy 222.687556 -82.432687) (xy 222.721642 -82.388544)
			(xy 222.761791 -82.349835) (xy 222.807149 -82.317384) (xy 222.856749 -82.291883) (xy 222.909533 -82.273876)
			(xy 222.964376 -82.263746) (xy 223.02011 -82.261709) (xy 223.075547 -82.267809) (xy 223.129504 -82.281915)
			(xy 223.180833 -82.303727) (xy 223.228439 -82.332781) (xy 223.271307 -82.368456) (xy 223.308524 -82.409993)
			(xy 223.339297 -82.456506) (xy 223.362969 -82.507003) (xy 223.379037 -82.56041) (xy 223.387157 -82.615586)
			(xy 223.387666 -82.643472) (xy 224.650044 -82.643472) (xy 224.654115 -82.58785) (xy 224.666241 -82.533413)
			(xy 224.686164 -82.481322) (xy 224.71346 -82.432687) (xy 224.747546 -82.388544) (xy 224.787695 -82.349835)
			(xy 224.833053 -82.317384) (xy 224.882653 -82.291883) (xy 224.935437 -82.273876) (xy 224.99028 -82.263746)
			(xy 225.046014 -82.261709) (xy 225.101451 -82.267809) (xy 225.155408 -82.281915) (xy 225.206737 -82.303727)
			(xy 225.254343 -82.332781) (xy 225.297211 -82.368456) (xy 225.334428 -82.409993) (xy 225.365201 -82.456506)
			(xy 225.388873 -82.507003) (xy 225.404941 -82.56041) (xy 225.413061 -82.615586) (xy 225.41357 -82.643472)
			(xy 225.413061 -82.671358) (xy 225.404941 -82.726534) (xy 225.388873 -82.779941) (xy 225.365201 -82.830438)
			(xy 225.334428 -82.876951) (xy 225.297211 -82.918488) (xy 225.254343 -82.954163) (xy 225.206737 -82.983217)
			(xy 225.155408 -83.005029) (xy 225.101451 -83.019135) (xy 225.046014 -83.025235) (xy 224.99028 -83.023198)
			(xy 224.935437 -83.013068) (xy 224.882653 -82.995061) (xy 224.833053 -82.96956) (xy 224.787695 -82.937109)
			(xy 224.747546 -82.8984) (xy 224.71346 -82.854257) (xy 224.686164 -82.805622) (xy 224.666241 -82.753531)
			(xy 224.654115 -82.699094) (xy 224.650044 -82.643472) (xy 223.387666 -82.643472) (xy 223.387157 -82.671358)
			(xy 223.379037 -82.726534) (xy 223.362969 -82.779941) (xy 223.339297 -82.830438) (xy 223.308524 -82.876951)
			(xy 223.271307 -82.918488) (xy 223.228439 -82.954163) (xy 223.180833 -82.983217) (xy 223.129504 -83.005029)
			(xy 223.075547 -83.019135) (xy 223.02011 -83.025235) (xy 222.964376 -83.023198) (xy 222.909533 -83.013068)
			(xy 222.856749 -82.995061) (xy 222.807149 -82.96956) (xy 222.761791 -82.937109) (xy 222.721642 -82.8984)
			(xy 222.687556 -82.854257) (xy 222.66026 -82.805622) (xy 222.640337 -82.753531) (xy 222.628211 -82.699094)
			(xy 222.62414 -82.643472) (xy 219.542768 -82.643472) (xy 219.533322 -82.657749) (xy 219.496105 -82.699286)
			(xy 219.453237 -82.734961) (xy 219.405631 -82.764015) (xy 219.354302 -82.785827) (xy 219.300345 -82.799933)
			(xy 219.244908 -82.806033) (xy 219.189174 -82.803996) (xy 219.134331 -82.793866) (xy 219.081547 -82.775859)
			(xy 219.031947 -82.750358) (xy 218.986589 -82.717907) (xy 218.94644 -82.679198) (xy 218.912354 -82.635055)
			(xy 218.885058 -82.58642) (xy 218.865135 -82.534329) (xy 218.853009 -82.479892) (xy 218.848938 -82.42427)
			(xy 214.300159 -82.42427) (xy 214.301839 -82.429854) (xy 214.309959 -82.48503) (xy 214.310468 -82.512916)
			(xy 214.309959 -82.540802) (xy 214.301839 -82.595978) (xy 214.285771 -82.649385) (xy 214.262099 -82.699882)
			(xy 214.231326 -82.746395) (xy 214.194109 -82.787932) (xy 214.151241 -82.823607) (xy 214.103635 -82.852661)
			(xy 214.052306 -82.874473) (xy 213.998349 -82.888579) (xy 213.942912 -82.894679) (xy 213.887178 -82.892642)
			(xy 213.832335 -82.882512) (xy 213.779551 -82.864505) (xy 213.729951 -82.839004) (xy 213.684593 -82.806553)
			(xy 213.644444 -82.767844) (xy 213.610358 -82.723701) (xy 213.583062 -82.675066) (xy 213.563139 -82.622975)
			(xy 213.551013 -82.568538) (xy 213.546942 -82.512916) (xy 212.443047 -82.512916) (xy 212.41131 -82.544666)
			(xy 212.405722 -82.552032) (xy 212.402674 -82.55762) (xy 212.40242 -82.558128) (xy 211.697473 -83.85556)
			(xy 218.830142 -83.85556) (xy 218.834213 -83.799938) (xy 218.846339 -83.745501) (xy 218.866262 -83.69341)
			(xy 218.893558 -83.644775) (xy 218.927644 -83.600632) (xy 218.967793 -83.561923) (xy 219.013151 -83.529472)
			(xy 219.062751 -83.503971) (xy 219.115535 -83.485964) (xy 219.170378 -83.475834) (xy 219.226112 -83.473797)
			(xy 219.281549 -83.479897) (xy 219.335506 -83.494003) (xy 219.338765 -83.495388) (xy 220.578678 -83.495388)
			(xy 220.582749 -83.439766) (xy 220.594875 -83.385329) (xy 220.614798 -83.333238) (xy 220.642094 -83.284603)
			(xy 220.67618 -83.24046) (xy 220.716329 -83.201751) (xy 220.761687 -83.1693) (xy 220.811287 -83.143799)
			(xy 220.864071 -83.125792) (xy 220.918914 -83.115662) (xy 220.974648 -83.113625) (xy 221.030085 -83.119725)
			(xy 221.084042 -83.133831) (xy 221.135371 -83.155643) (xy 221.182977 -83.184697) (xy 221.225845 -83.220372)
			(xy 221.263062 -83.261909) (xy 221.293835 -83.308422) (xy 221.317507 -83.358919) (xy 221.333575 -83.412326)
			(xy 221.341695 -83.467502) (xy 221.342204 -83.495388) (xy 221.341695 -83.523274) (xy 221.333575 -83.57845)
			(xy 221.317507 -83.631857) (xy 221.304562 -83.659472) (xy 222.62414 -83.659472) (xy 222.628211 -83.60385)
			(xy 222.640337 -83.549413) (xy 222.66026 -83.497322) (xy 222.687556 -83.448687) (xy 222.721642 -83.404544)
			(xy 222.761791 -83.365835) (xy 222.807149 -83.333384) (xy 222.856749 -83.307883) (xy 222.909533 -83.289876)
			(xy 222.964376 -83.279746) (xy 223.02011 -83.277709) (xy 223.075547 -83.283809) (xy 223.129504 -83.297915)
			(xy 223.180833 -83.319727) (xy 223.228439 -83.348781) (xy 223.271307 -83.384456) (xy 223.308524 -83.425993)
			(xy 223.339297 -83.472506) (xy 223.362969 -83.523003) (xy 223.379037 -83.57641) (xy 223.387157 -83.631586)
			(xy 223.387666 -83.659472) (xy 224.650044 -83.659472) (xy 224.654115 -83.60385) (xy 224.666241 -83.549413)
			(xy 224.686164 -83.497322) (xy 224.71346 -83.448687) (xy 224.747546 -83.404544) (xy 224.787695 -83.365835)
			(xy 224.833053 -83.333384) (xy 224.882653 -83.307883) (xy 224.935437 -83.289876) (xy 224.99028 -83.279746)
			(xy 225.046014 -83.277709) (xy 225.101451 -83.283809) (xy 225.155408 -83.297915) (xy 225.206737 -83.319727)
			(xy 225.254343 -83.348781) (xy 225.276377 -83.367118) (xy 232.68432 -83.367118) (xy 232.68432 -82.503518)
			(xy 232.68481 -82.47355) (xy 232.692633 -82.414128) (xy 232.708146 -82.356235) (xy 232.731082 -82.300862)
			(xy 232.761049 -82.248956) (xy 232.797536 -82.201406) (xy 232.839916 -82.159026) (xy 232.887466 -82.122539)
			(xy 232.939372 -82.092572) (xy 232.994745 -82.069636) (xy 233.052638 -82.054123) (xy 233.11206 -82.0463)
			(xy 233.171996 -82.0463) (xy 233.231418 -82.054123) (xy 233.289311 -82.069636) (xy 233.344684 -82.092572)
			(xy 233.39659 -82.122539) (xy 233.44414 -82.159026) (xy 233.48652 -82.201406) (xy 233.523007 -82.248956)
			(xy 233.552974 -82.300862) (xy 233.568014 -82.337171) (xy 238.132537 -82.337171) (xy 238.132537 -82.277229)
			(xy 238.140362 -82.217799) (xy 238.155876 -82.159898) (xy 238.178816 -82.104519) (xy 238.208788 -82.052607)
			(xy 238.24528 -82.005052) (xy 238.287667 -81.962667) (xy 238.335224 -81.926177) (xy 238.387137 -81.896207)
			(xy 238.442517 -81.87327) (xy 238.500418 -81.857758) (xy 238.559849 -81.849936) (xy 238.58982 -81.849468)
			(xy 239.45342 -81.849468) (xy 239.483385 -81.850007) (xy 239.542803 -81.857832) (xy 239.600691 -81.873345)
			(xy 239.656058 -81.896282) (xy 239.707959 -81.926248) (xy 239.755504 -81.962733) (xy 239.79788 -82.005111)
			(xy 239.834363 -82.052658) (xy 239.836568 -82.056478) (xy 254.425956 -82.056478) (xy 254.430027 -82.000856)
			(xy 254.442153 -81.946419) (xy 254.462076 -81.894328) (xy 254.489372 -81.845693) (xy 254.523458 -81.80155)
			(xy 254.563607 -81.762841) (xy 254.608965 -81.73039) (xy 254.658565 -81.704889) (xy 254.711349 -81.686882)
			(xy 254.766192 -81.676752) (xy 254.821926 -81.674715) (xy 254.877363 -81.680815) (xy 254.93132 -81.694921)
			(xy 254.982649 -81.716733) (xy 255.030255 -81.745787) (xy 255.073123 -81.781462) (xy 255.11034 -81.822999)
			(xy 255.141113 -81.869512) (xy 255.164785 -81.920009) (xy 255.180853 -81.973416) (xy 255.188973 -82.028592)
			(xy 255.189482 -82.056478) (xy 255.188973 -82.084364) (xy 255.180853 -82.13954) (xy 255.164785 -82.192947)
			(xy 255.141113 -82.243444) (xy 255.11034 -82.289957) (xy 255.073123 -82.331494) (xy 255.030255 -82.367169)
			(xy 254.982649 -82.396223) (xy 254.93132 -82.418035) (xy 254.877363 -82.432141) (xy 254.821926 -82.438241)
			(xy 254.766192 -82.436204) (xy 254.711349 -82.426074) (xy 254.658565 -82.408067) (xy 254.608965 -82.382566)
			(xy 254.563607 -82.350115) (xy 254.523458 -82.311406) (xy 254.489372 -82.267263) (xy 254.462076 -82.218628)
			(xy 254.442153 -82.166537) (xy 254.430027 -82.1121) (xy 254.425956 -82.056478) (xy 239.836568 -82.056478)
			(xy 239.864327 -82.10456) (xy 239.887261 -82.159928) (xy 239.902772 -82.217817) (xy 239.910594 -82.277235)
			(xy 239.910594 -82.337165) (xy 239.902772 -82.396583) (xy 239.887261 -82.454472) (xy 239.864327 -82.50984)
			(xy 239.834363 -82.561742) (xy 239.79788 -82.609289) (xy 239.755504 -82.651667) (xy 239.707959 -82.688152)
			(xy 239.656058 -82.718118) (xy 239.600691 -82.741055) (xy 239.542803 -82.756568) (xy 239.483385 -82.764393)
			(xy 239.45342 -82.764884) (xy 238.58982 -82.764884) (xy 238.559849 -82.764464) (xy 238.500418 -82.756642)
			(xy 238.442517 -82.74113) (xy 238.387137 -82.718193) (xy 238.335224 -82.688223) (xy 238.287667 -82.651733)
			(xy 238.24528 -82.609348) (xy 238.208788 -82.561793) (xy 238.178816 -82.509881) (xy 238.155876 -82.454502)
			(xy 238.140362 -82.396601) (xy 238.132537 -82.337171) (xy 233.568014 -82.337171) (xy 233.57591 -82.356235)
			(xy 233.591423 -82.414128) (xy 233.599246 -82.47355) (xy 233.599736 -82.503518) (xy 233.599736 -83.367118)
			(xy 233.599246 -83.397086) (xy 233.591423 -83.456508) (xy 233.57591 -83.514401) (xy 233.552974 -83.569774)
			(xy 233.523007 -83.62168) (xy 233.48652 -83.66923) (xy 233.44414 -83.71161) (xy 233.39659 -83.748097)
			(xy 233.344684 -83.778064) (xy 233.289311 -83.801) (xy 233.231418 -83.816513) (xy 233.171996 -83.824336)
			(xy 233.11206 -83.824336) (xy 233.052638 -83.816513) (xy 232.994745 -83.801) (xy 232.939372 -83.778064)
			(xy 232.887466 -83.748097) (xy 232.839916 -83.71161) (xy 232.797536 -83.66923) (xy 232.761049 -83.62168)
			(xy 232.731082 -83.569774) (xy 232.708146 -83.514401) (xy 232.692633 -83.456508) (xy 232.68481 -83.397086)
			(xy 232.68432 -83.367118) (xy 225.276377 -83.367118) (xy 225.297211 -83.384456) (xy 225.334428 -83.425993)
			(xy 225.365201 -83.472506) (xy 225.388873 -83.523003) (xy 225.404941 -83.57641) (xy 225.413061 -83.631586)
			(xy 225.41357 -83.659472) (xy 225.413061 -83.687358) (xy 225.404941 -83.742534) (xy 225.388873 -83.795941)
			(xy 225.365201 -83.846438) (xy 225.334428 -83.892951) (xy 225.297211 -83.934488) (xy 225.254343 -83.970163)
			(xy 225.206737 -83.999217) (xy 225.155408 -84.021029) (xy 225.101451 -84.035135) (xy 225.046014 -84.041235)
			(xy 224.99028 -84.039198) (xy 224.935437 -84.029068) (xy 224.882653 -84.011061) (xy 224.833053 -83.98556)
			(xy 224.787695 -83.953109) (xy 224.747546 -83.9144) (xy 224.71346 -83.870257) (xy 224.686164 -83.821622)
			(xy 224.666241 -83.769531) (xy 224.654115 -83.715094) (xy 224.650044 -83.659472) (xy 223.387666 -83.659472)
			(xy 223.387157 -83.687358) (xy 223.379037 -83.742534) (xy 223.362969 -83.795941) (xy 223.339297 -83.846438)
			(xy 223.308524 -83.892951) (xy 223.271307 -83.934488) (xy 223.228439 -83.970163) (xy 223.180833 -83.999217)
			(xy 223.129504 -84.021029) (xy 223.075547 -84.035135) (xy 223.02011 -84.041235) (xy 222.964376 -84.039198)
			(xy 222.909533 -84.029068) (xy 222.856749 -84.011061) (xy 222.807149 -83.98556) (xy 222.761791 -83.953109)
			(xy 222.721642 -83.9144) (xy 222.687556 -83.870257) (xy 222.66026 -83.821622) (xy 222.640337 -83.769531)
			(xy 222.628211 -83.715094) (xy 222.62414 -83.659472) (xy 221.304562 -83.659472) (xy 221.293835 -83.682354)
			(xy 221.263062 -83.728867) (xy 221.225845 -83.770404) (xy 221.182977 -83.806079) (xy 221.135371 -83.835133)
			(xy 221.084042 -83.856945) (xy 221.030085 -83.871051) (xy 220.974648 -83.877151) (xy 220.918914 -83.875114)
			(xy 220.864071 -83.864984) (xy 220.811287 -83.846977) (xy 220.761687 -83.821476) (xy 220.716329 -83.789025)
			(xy 220.67618 -83.750316) (xy 220.642094 -83.706173) (xy 220.614798 -83.657538) (xy 220.594875 -83.605447)
			(xy 220.582749 -83.55101) (xy 220.578678 -83.495388) (xy 219.338765 -83.495388) (xy 219.386835 -83.515815)
			(xy 219.434441 -83.544869) (xy 219.477309 -83.580544) (xy 219.514526 -83.622081) (xy 219.545299 -83.668594)
			(xy 219.568971 -83.719091) (xy 219.585039 -83.772498) (xy 219.593159 -83.827674) (xy 219.593668 -83.85556)
			(xy 219.593159 -83.883446) (xy 219.585039 -83.938622) (xy 219.568971 -83.992029) (xy 219.545299 -84.042526)
			(xy 219.514526 -84.089039) (xy 219.477309 -84.130576) (xy 219.434441 -84.166251) (xy 219.386835 -84.195305)
			(xy 219.335506 -84.217117) (xy 219.281549 -84.231223) (xy 219.226112 -84.237323) (xy 219.170378 -84.235286)
			(xy 219.115535 -84.225156) (xy 219.062751 -84.207149) (xy 219.013151 -84.181648) (xy 218.967793 -84.149197)
			(xy 218.927644 -84.110488) (xy 218.893558 -84.066345) (xy 218.866262 -84.01771) (xy 218.846339 -83.965619)
			(xy 218.834213 -83.911182) (xy 218.830142 -83.85556) (xy 211.697473 -83.85556) (xy 211.203126 -84.765388)
			(xy 220.578678 -84.765388) (xy 220.582749 -84.709766) (xy 220.594875 -84.655329) (xy 220.614798 -84.603238)
			(xy 220.642094 -84.554603) (xy 220.67618 -84.51046) (xy 220.716329 -84.471751) (xy 220.761687 -84.4393)
			(xy 220.811287 -84.413799) (xy 220.864071 -84.395792) (xy 220.918914 -84.385662) (xy 220.974648 -84.383625)
			(xy 221.030085 -84.389725) (xy 221.084042 -84.403831) (xy 221.135371 -84.425643) (xy 221.182977 -84.454697)
			(xy 221.225845 -84.490372) (xy 221.263062 -84.531909) (xy 221.293835 -84.578422) (xy 221.317507 -84.628919)
			(xy 221.331513 -84.675472) (xy 222.62414 -84.675472) (xy 222.628211 -84.61985) (xy 222.640337 -84.565413)
			(xy 222.66026 -84.513322) (xy 222.687556 -84.464687) (xy 222.721642 -84.420544) (xy 222.761791 -84.381835)
			(xy 222.807149 -84.349384) (xy 222.856749 -84.323883) (xy 222.909533 -84.305876) (xy 222.964376 -84.295746)
			(xy 223.02011 -84.293709) (xy 223.075547 -84.299809) (xy 223.129504 -84.313915) (xy 223.180833 -84.335727)
			(xy 223.228439 -84.364781) (xy 223.271307 -84.400456) (xy 223.308524 -84.441993) (xy 223.339297 -84.488506)
			(xy 223.362969 -84.539003) (xy 223.379037 -84.59241) (xy 223.387157 -84.647586) (xy 223.387666 -84.675472)
			(xy 224.650044 -84.675472) (xy 224.654115 -84.61985) (xy 224.666241 -84.565413) (xy 224.686164 -84.513322)
			(xy 224.71346 -84.464687) (xy 224.747546 -84.420544) (xy 224.787695 -84.381835) (xy 224.833053 -84.349384)
			(xy 224.882653 -84.323883) (xy 224.935437 -84.305876) (xy 224.99028 -84.295746) (xy 225.046014 -84.293709)
			(xy 225.101451 -84.299809) (xy 225.155408 -84.313915) (xy 225.206737 -84.335727) (xy 225.254343 -84.364781)
			(xy 225.297211 -84.400456) (xy 225.334428 -84.441993) (xy 225.365201 -84.488506) (xy 225.388873 -84.539003)
			(xy 225.404941 -84.59241) (xy 225.413061 -84.647586) (xy 225.41357 -84.675472) (xy 225.413061 -84.703358)
			(xy 225.404941 -84.758534) (xy 225.388873 -84.811941) (xy 225.365201 -84.862438) (xy 225.334428 -84.908951)
			(xy 225.297211 -84.950488) (xy 225.282787 -84.962492) (xy 227.845364 -84.962492) (xy 227.849435 -84.90687)
			(xy 227.861561 -84.852433) (xy 227.881484 -84.800342) (xy 227.90878 -84.751707) (xy 227.942866 -84.707564)
			(xy 227.983015 -84.668855) (xy 228.028373 -84.636404) (xy 228.077973 -84.610903) (xy 228.130757 -84.592896)
			(xy 228.1856 -84.582766) (xy 228.241334 -84.580729) (xy 228.296771 -84.586829) (xy 228.350728 -84.600935)
			(xy 228.402057 -84.622747) (xy 228.449663 -84.651801) (xy 228.492531 -84.687476) (xy 228.529748 -84.729013)
			(xy 228.560521 -84.775526) (xy 228.584193 -84.826023) (xy 228.600261 -84.87943) (xy 228.608381 -84.934606)
			(xy 228.60889 -84.962492) (xy 228.608381 -84.990378) (xy 228.600261 -85.045554) (xy 228.584193 -85.098961)
			(xy 228.560521 -85.149458) (xy 228.529748 -85.195971) (xy 228.492531 -85.237508) (xy 228.449663 -85.273183)
			(xy 228.402057 -85.302237) (xy 228.350728 -85.324049) (xy 228.296771 -85.338155) (xy 228.241334 -85.344255)
			(xy 228.1856 -85.342218) (xy 228.130757 -85.332088) (xy 228.077973 -85.314081) (xy 228.028373 -85.28858)
			(xy 227.983015 -85.256129) (xy 227.942866 -85.21742) (xy 227.90878 -85.173277) (xy 227.881484 -85.124642)
			(xy 227.861561 -85.072551) (xy 227.849435 -85.018114) (xy 227.845364 -84.962492) (xy 225.282787 -84.962492)
			(xy 225.254343 -84.986163) (xy 225.206737 -85.015217) (xy 225.155408 -85.037029) (xy 225.101451 -85.051135)
			(xy 225.046014 -85.057235) (xy 224.99028 -85.055198) (xy 224.935437 -85.045068) (xy 224.882653 -85.027061)
			(xy 224.833053 -85.00156) (xy 224.787695 -84.969109) (xy 224.747546 -84.9304) (xy 224.71346 -84.886257)
			(xy 224.686164 -84.837622) (xy 224.666241 -84.785531) (xy 224.654115 -84.731094) (xy 224.650044 -84.675472)
			(xy 223.387666 -84.675472) (xy 223.387157 -84.703358) (xy 223.379037 -84.758534) (xy 223.362969 -84.811941)
			(xy 223.339297 -84.862438) (xy 223.308524 -84.908951) (xy 223.271307 -84.950488) (xy 223.228439 -84.986163)
			(xy 223.180833 -85.015217) (xy 223.129504 -85.037029) (xy 223.075547 -85.051135) (xy 223.02011 -85.057235)
			(xy 222.964376 -85.055198) (xy 222.909533 -85.045068) (xy 222.856749 -85.027061) (xy 222.807149 -85.00156)
			(xy 222.761791 -84.969109) (xy 222.721642 -84.9304) (xy 222.687556 -84.886257) (xy 222.66026 -84.837622)
			(xy 222.640337 -84.785531) (xy 222.628211 -84.731094) (xy 222.62414 -84.675472) (xy 221.331513 -84.675472)
			(xy 221.333575 -84.682326) (xy 221.341695 -84.737502) (xy 221.342204 -84.765388) (xy 221.341695 -84.793274)
			(xy 221.333575 -84.84845) (xy 221.317507 -84.901857) (xy 221.293835 -84.952354) (xy 221.263062 -84.998867)
			(xy 221.225845 -85.040404) (xy 221.182977 -85.076079) (xy 221.135371 -85.105133) (xy 221.084042 -85.126945)
			(xy 221.030085 -85.141051) (xy 220.974648 -85.147151) (xy 220.918914 -85.145114) (xy 220.864071 -85.134984)
			(xy 220.811287 -85.116977) (xy 220.761687 -85.091476) (xy 220.716329 -85.059025) (xy 220.67618 -85.020316)
			(xy 220.642094 -84.976173) (xy 220.614798 -84.927538) (xy 220.594875 -84.875447) (xy 220.582749 -84.82101)
			(xy 220.578678 -84.765388) (xy 211.203126 -84.765388) (xy 210.826483 -85.458587) (xy 232.264389 -85.458587)
			(xy 232.264389 -85.398613) (xy 232.272218 -85.339151) (xy 232.28774 -85.28122) (xy 232.310692 -85.225811)
			(xy 232.34068 -85.173871) (xy 232.377191 -85.126291) (xy 232.4196 -85.083883) (xy 232.467181 -85.047373)
			(xy 232.519122 -85.017387) (xy 232.574531 -84.994437) (xy 232.632463 -84.978915) (xy 232.691925 -84.971088)
			(xy 232.721912 -84.97062) (xy 233.585512 -84.97062) (xy 233.615495 -84.971147) (xy 233.674947 -84.978975)
			(xy 233.732868 -84.994497) (xy 233.788268 -85.017445) (xy 233.840199 -85.047429) (xy 233.887772 -85.083934)
			(xy 233.930174 -85.126337) (xy 233.963295 -85.169502) (xy 238.555276 -85.169502) (xy 238.555276 -84.305902)
			(xy 238.555766 -84.275918) (xy 238.563594 -84.216462) (xy 238.579115 -84.158537) (xy 238.602064 -84.103133)
			(xy 238.632048 -84.051199) (xy 238.668554 -84.003623) (xy 238.710959 -83.961218) (xy 238.758535 -83.924712)
			(xy 238.810469 -83.894728) (xy 238.865873 -83.871779) (xy 238.923798 -83.856258) (xy 238.983254 -83.84843)
			(xy 239.043222 -83.84843) (xy 239.102678 -83.856258) (xy 239.160603 -83.871779) (xy 239.216007 -83.894728)
			(xy 239.267941 -83.924712) (xy 239.315517 -83.961218) (xy 239.357922 -84.003623) (xy 239.394428 -84.051199)
			(xy 239.424412 -84.103133) (xy 239.447361 -84.158537) (xy 239.462882 -84.216462) (xy 239.47071 -84.275918)
			(xy 239.4712 -84.305902) (xy 239.4712 -84.320888) (xy 247.814082 -84.320888) (xy 247.818153 -84.265266)
			(xy 247.830279 -84.210829) (xy 247.850202 -84.158738) (xy 247.877498 -84.110103) (xy 247.911584 -84.06596)
			(xy 247.951733 -84.027251) (xy 247.997091 -83.9948) (xy 248.046691 -83.969299) (xy 248.099475 -83.951292)
			(xy 248.154318 -83.941162) (xy 248.210052 -83.939125) (xy 248.265489 -83.945225) (xy 248.319446 -83.959331)
			(xy 248.370775 -83.981143) (xy 248.418381 -84.010197) (xy 248.461249 -84.045872) (xy 248.498466 -84.087409)
			(xy 248.529239 -84.133922) (xy 248.552911 -84.184419) (xy 248.568979 -84.237826) (xy 248.577099 -84.293002)
			(xy 248.577608 -84.320888) (xy 248.577099 -84.348774) (xy 248.568979 -84.40395) (xy 248.553926 -84.453984)
			(xy 254.399286 -84.453984) (xy 254.403357 -84.398362) (xy 254.415483 -84.343925) (xy 254.435406 -84.291834)
			(xy 254.462702 -84.243199) (xy 254.496788 -84.199056) (xy 254.536937 -84.160347) (xy 254.582295 -84.127896)
			(xy 254.631895 -84.102395) (xy 254.684679 -84.084388) (xy 254.739522 -84.074258) (xy 254.795256 -84.072221)
			(xy 254.850693 -84.078321) (xy 254.90465 -84.092427) (xy 254.955979 -84.114239) (xy 255.003585 -84.143293)
			(xy 255.046453 -84.178968) (xy 255.08367 -84.220505) (xy 255.114443 -84.267018) (xy 255.138115 -84.317515)
			(xy 255.154183 -84.370922) (xy 255.162303 -84.426098) (xy 255.162812 -84.453984) (xy 255.162303 -84.48187)
			(xy 255.154183 -84.537046) (xy 255.138115 -84.590453) (xy 255.114443 -84.64095) (xy 255.08367 -84.687463)
			(xy 255.046453 -84.729) (xy 255.010664 -84.758784) (xy 264.526774 -84.758784) (xy 264.530845 -84.703162)
			(xy 264.542971 -84.648725) (xy 264.562894 -84.596634) (xy 264.59019 -84.547999) (xy 264.624276 -84.503856)
			(xy 264.664425 -84.465147) (xy 264.709783 -84.432696) (xy 264.759383 -84.407195) (xy 264.812167 -84.389188)
			(xy 264.86701 -84.379058) (xy 264.922744 -84.377021) (xy 264.978181 -84.383121) (xy 265.032138 -84.397227)
			(xy 265.083467 -84.419039) (xy 265.131073 -84.448093) (xy 265.173941 -84.483768) (xy 265.211158 -84.525305)
			(xy 265.241931 -84.571818) (xy 265.265603 -84.622315) (xy 265.281671 -84.675722) (xy 265.289791 -84.730898)
			(xy 265.2903 -84.758784) (xy 265.289791 -84.78667) (xy 265.281671 -84.841846) (xy 265.265603 -84.895253)
			(xy 265.241931 -84.94575) (xy 265.211158 -84.992263) (xy 265.173941 -85.0338) (xy 265.131073 -85.069475)
			(xy 265.083467 -85.098529) (xy 265.032138 -85.120341) (xy 264.978181 -85.134447) (xy 264.922744 -85.140547)
			(xy 264.86701 -85.13851) (xy 264.812167 -85.12838) (xy 264.759383 -85.110373) (xy 264.709783 -85.084872)
			(xy 264.664425 -85.052421) (xy 264.624276 -85.013712) (xy 264.59019 -84.969569) (xy 264.562894 -84.920934)
			(xy 264.542971 -84.868843) (xy 264.530845 -84.814406) (xy 264.526774 -84.758784) (xy 255.010664 -84.758784)
			(xy 255.003585 -84.764675) (xy 254.955979 -84.793729) (xy 254.90465 -84.815541) (xy 254.850693 -84.829647)
			(xy 254.795256 -84.835747) (xy 254.739522 -84.83371) (xy 254.684679 -84.82358) (xy 254.631895 -84.805573)
			(xy 254.582295 -84.780072) (xy 254.536937 -84.747621) (xy 254.496788 -84.708912) (xy 254.462702 -84.664769)
			(xy 254.435406 -84.616134) (xy 254.415483 -84.564043) (xy 254.403357 -84.509606) (xy 254.399286 -84.453984)
			(xy 248.553926 -84.453984) (xy 248.552911 -84.457357) (xy 248.529239 -84.507854) (xy 248.498466 -84.554367)
			(xy 248.461249 -84.595904) (xy 248.418381 -84.631579) (xy 248.370775 -84.660633) (xy 248.319446 -84.682445)
			(xy 248.265489 -84.696551) (xy 248.210052 -84.702651) (xy 248.154318 -84.700614) (xy 248.099475 -84.690484)
			(xy 248.046691 -84.672477) (xy 247.997091 -84.646976) (xy 247.951733 -84.614525) (xy 247.911584 -84.575816)
			(xy 247.877498 -84.531673) (xy 247.850202 -84.483038) (xy 247.830279 -84.430947) (xy 247.818153 -84.37651)
			(xy 247.814082 -84.320888) (xy 239.4712 -84.320888) (xy 239.4712 -85.169502) (xy 239.47071 -85.199486)
			(xy 239.462882 -85.258942) (xy 239.447361 -85.316867) (xy 239.424412 -85.372271) (xy 239.394428 -85.424205)
			(xy 239.357922 -85.471781) (xy 239.315517 -85.514186) (xy 239.267941 -85.550692) (xy 239.216007 -85.580676)
			(xy 239.160603 -85.603625) (xy 239.102678 -85.619146) (xy 239.043222 -85.626974) (xy 238.983254 -85.626974)
			(xy 238.923798 -85.619146) (xy 238.865873 -85.603625) (xy 238.810469 -85.580676) (xy 238.758535 -85.550692)
			(xy 238.710959 -85.514186) (xy 238.668554 -85.471781) (xy 238.632048 -85.424205) (xy 238.602064 -85.372271)
			(xy 238.579115 -85.316867) (xy 238.563594 -85.258942) (xy 238.555766 -85.199486) (xy 238.555276 -85.169502)
			(xy 233.963295 -85.169502) (xy 233.966678 -85.173911) (xy 233.99666 -85.225842) (xy 234.019607 -85.281243)
			(xy 234.035127 -85.339165) (xy 234.042954 -85.398617) (xy 234.042954 -85.458583) (xy 234.035127 -85.518035)
			(xy 234.019607 -85.575957) (xy 233.99666 -85.631358) (xy 233.966678 -85.683289) (xy 233.930174 -85.730863)
			(xy 233.887772 -85.773266) (xy 233.840199 -85.809771) (xy 233.788268 -85.839755) (xy 233.732868 -85.862703)
			(xy 233.674947 -85.878225) (xy 233.615495 -85.886053) (xy 233.585512 -85.886544) (xy 232.721912 -85.886544)
			(xy 232.691925 -85.886112) (xy 232.632463 -85.878285) (xy 232.574531 -85.862763) (xy 232.519122 -85.839813)
			(xy 232.467181 -85.809827) (xy 232.4196 -85.773317) (xy 232.377191 -85.730909) (xy 232.34068 -85.683329)
			(xy 232.310692 -85.631389) (xy 232.28774 -85.57598) (xy 232.272218 -85.518049) (xy 232.264389 -85.458587)
			(xy 210.826483 -85.458587) (xy 210.478581 -86.098888) (xy 247.814082 -86.098888) (xy 247.818153 -86.043266)
			(xy 247.830279 -85.988829) (xy 247.850202 -85.936738) (xy 247.877498 -85.888103) (xy 247.911584 -85.84396)
			(xy 247.951733 -85.805251) (xy 247.997091 -85.7728) (xy 248.046691 -85.747299) (xy 248.099475 -85.729292)
			(xy 248.154318 -85.719162) (xy 248.210052 -85.717125) (xy 248.265489 -85.723225) (xy 248.319446 -85.737331)
			(xy 248.370775 -85.759143) (xy 248.418381 -85.788197) (xy 248.461249 -85.823872) (xy 248.498466 -85.865409)
			(xy 248.529239 -85.911922) (xy 248.552911 -85.962419) (xy 248.568979 -86.015826) (xy 248.577099 -86.071002)
			(xy 248.577608 -86.098888) (xy 248.577099 -86.126774) (xy 248.568979 -86.18195) (xy 248.552911 -86.235357)
			(xy 248.529239 -86.285854) (xy 248.498466 -86.332367) (xy 248.461249 -86.373904) (xy 248.418381 -86.409579)
			(xy 248.370775 -86.438633) (xy 248.319446 -86.460445) (xy 248.265489 -86.474551) (xy 248.210052 -86.480651)
			(xy 248.154318 -86.478614) (xy 248.099475 -86.468484) (xy 248.046691 -86.450477) (xy 247.997091 -86.424976)
			(xy 247.951733 -86.392525) (xy 247.911584 -86.353816) (xy 247.877498 -86.309673) (xy 247.850202 -86.261038)
			(xy 247.830279 -86.208947) (xy 247.818153 -86.15451) (xy 247.814082 -86.098888) (xy 210.478581 -86.098888)
			(xy 209.921855 -87.123524) (xy 218.507562 -87.123524) (xy 218.511633 -87.067902) (xy 218.523759 -87.013465)
			(xy 218.543682 -86.961374) (xy 218.570978 -86.912739) (xy 218.605064 -86.868596) (xy 218.645213 -86.829887)
			(xy 218.690571 -86.797436) (xy 218.740171 -86.771935) (xy 218.792955 -86.753928) (xy 218.847798 -86.743798)
			(xy 218.903532 -86.741761) (xy 218.958969 -86.747861) (xy 219.012926 -86.761967) (xy 219.064255 -86.783779)
			(xy 219.111861 -86.812833) (xy 219.154729 -86.848508) (xy 219.191946 -86.890045) (xy 219.222719 -86.936558)
			(xy 219.246391 -86.987055) (xy 219.262459 -87.040462) (xy 219.266646 -87.068914) (xy 220.702884 -87.068914)
			(xy 220.706955 -87.013292) (xy 220.719081 -86.958855) (xy 220.739004 -86.906764) (xy 220.7663 -86.858129)
			(xy 220.800386 -86.813986) (xy 220.840535 -86.775277) (xy 220.885893 -86.742826) (xy 220.935493 -86.717325)
			(xy 220.988277 -86.699318) (xy 221.04312 -86.689188) (xy 221.098854 -86.687151) (xy 221.154291 -86.693251)
			(xy 221.208248 -86.707357) (xy 221.259577 -86.729169) (xy 221.307183 -86.758223) (xy 221.350051 -86.793898)
			(xy 221.387268 -86.835435) (xy 221.418041 -86.881948) (xy 221.441713 -86.932445) (xy 221.457781 -86.985852)
			(xy 221.465901 -87.041028) (xy 221.46641 -87.068914) (xy 221.465901 -87.0968) (xy 221.457781 -87.151976)
			(xy 221.441713 -87.205383) (xy 221.418041 -87.25588) (xy 221.387268 -87.302393) (xy 221.350051 -87.34393)
			(xy 221.307183 -87.379605) (xy 221.259577 -87.408659) (xy 221.208248 -87.430471) (xy 221.154291 -87.444577)
			(xy 221.098854 -87.450677) (xy 221.04312 -87.44864) (xy 220.988277 -87.43851) (xy 220.935493 -87.420503)
			(xy 220.885893 -87.395002) (xy 220.840535 -87.362551) (xy 220.800386 -87.323842) (xy 220.7663 -87.279699)
			(xy 220.739004 -87.231064) (xy 220.719081 -87.178973) (xy 220.706955 -87.124536) (xy 220.702884 -87.068914)
			(xy 219.266646 -87.068914) (xy 219.270579 -87.095638) (xy 219.271088 -87.123524) (xy 219.270579 -87.15141)
			(xy 219.262459 -87.206586) (xy 219.246391 -87.259993) (xy 219.222719 -87.31049) (xy 219.191946 -87.357003)
			(xy 219.154729 -87.39854) (xy 219.111861 -87.434215) (xy 219.064255 -87.463269) (xy 219.012926 -87.485081)
			(xy 218.958969 -87.499187) (xy 218.903532 -87.505287) (xy 218.847798 -87.50325) (xy 218.792955 -87.49312)
			(xy 218.740171 -87.475113) (xy 218.690571 -87.449612) (xy 218.645213 -87.417161) (xy 218.605064 -87.378452)
			(xy 218.570978 -87.334309) (xy 218.543682 -87.285674) (xy 218.523759 -87.233583) (xy 218.511633 -87.179146)
			(xy 218.507562 -87.123524) (xy 209.921855 -87.123524) (xy 209.89798 -87.167466) (xy 209.896418 -87.171175)
			(xy 209.894381 -87.178962) (xy 209.893916 -87.18296) (xy 209.893662 -87.187278) (xy 209.893699 -87.19174)
			(xy 209.89511 -87.20055) (xy 209.896456 -87.204804) (xy 209.897726 -87.208106) (xy 209.927797 -87.215436)
			(xy 209.985779 -87.237095) (xy 210.040325 -87.266347) (xy 210.090447 -87.302662) (xy 210.135236 -87.345381)
			(xy 210.17388 -87.39373) (xy 210.205678 -87.446833) (xy 210.230054 -87.503726) (xy 210.246566 -87.563377)
			(xy 210.254914 -87.624707) (xy 210.255358 -87.655654) (xy 210.307172 -87.655654) (xy 210.311243 -87.600032)
			(xy 210.323369 -87.545595) (xy 210.343292 -87.493504) (xy 210.370588 -87.444869) (xy 210.404674 -87.400726)
			(xy 210.444823 -87.362017) (xy 210.490181 -87.329566) (xy 210.539781 -87.304065) (xy 210.592565 -87.286058)
			(xy 210.647408 -87.275928) (xy 210.703142 -87.273891) (xy 210.758579 -87.279991) (xy 210.812536 -87.294097)
			(xy 210.863865 -87.315909) (xy 210.911471 -87.344963) (xy 210.954339 -87.380638) (xy 210.991556 -87.422175)
			(xy 211.022329 -87.468688) (xy 211.046001 -87.519185) (xy 211.062069 -87.572592) (xy 211.067415 -87.608918)
			(xy 221.615252 -87.608918) (xy 221.619323 -87.553296) (xy 221.631449 -87.498859) (xy 221.651372 -87.446768)
			(xy 221.678668 -87.398133) (xy 221.712754 -87.35399) (xy 221.752903 -87.315281) (xy 221.798261 -87.28283)
			(xy 221.847861 -87.257329) (xy 221.900645 -87.239322) (xy 221.955488 -87.229192) (xy 222.011222 -87.227155)
			(xy 222.066659 -87.233255) (xy 222.120616 -87.247361) (xy 222.171945 -87.269173) (xy 222.219551 -87.298227)
			(xy 222.262419 -87.333902) (xy 222.299636 -87.375439) (xy 222.330409 -87.421952) (xy 222.340776 -87.444066)
			(xy 232.194882 -87.444066) (xy 232.194882 -87.384134) (xy 232.202704 -87.324714) (xy 232.218215 -87.266824)
			(xy 232.241149 -87.211454) (xy 232.271114 -87.15955) (xy 232.307596 -87.112002) (xy 232.349973 -87.069621)
			(xy 232.397519 -87.033135) (xy 232.44942 -87.003166) (xy 232.504788 -86.980227) (xy 232.562677 -86.964712)
			(xy 232.622096 -86.956884) (xy 232.652062 -86.956392) (xy 233.515662 -86.956392) (xy 233.545633 -86.956859)
			(xy 233.605062 -86.964678) (xy 233.662961 -86.980188) (xy 233.718341 -87.003123) (xy 233.770254 -87.033091)
			(xy 233.81781 -87.069578) (xy 233.860197 -87.111961) (xy 233.896688 -87.159515) (xy 233.92666 -87.211425)
			(xy 233.9496 -87.266803) (xy 233.965115 -87.324701) (xy 233.972939 -87.384129) (xy 233.972939 -87.416385)
			(xy 234.381521 -87.416385) (xy 234.381521 -87.356415) (xy 234.389349 -87.296959) (xy 234.40487 -87.239032)
			(xy 234.42782 -87.183628) (xy 234.457804 -87.131692) (xy 234.494312 -87.084115) (xy 234.536717 -87.04171)
			(xy 234.584294 -87.005203) (xy 234.636229 -86.975219) (xy 234.691634 -86.952269) (xy 234.749561 -86.936748)
			(xy 234.809017 -86.928921) (xy 234.839002 -86.928452) (xy 235.702602 -86.928452) (xy 235.732587 -86.928914)
			(xy 235.792044 -86.936742) (xy 235.849971 -86.952264) (xy 235.905376 -86.975214) (xy 235.957312 -87.005199)
			(xy 236.004889 -87.041707) (xy 236.047295 -87.084112) (xy 236.083802 -87.13169) (xy 236.094632 -87.150448)
			(xy 247.428256 -87.150448) (xy 247.432327 -87.094826) (xy 247.444453 -87.040389) (xy 247.464376 -86.988298)
			(xy 247.491672 -86.939663) (xy 247.525758 -86.89552) (xy 247.565907 -86.856811) (xy 247.611265 -86.82436)
			(xy 247.660865 -86.798859) (xy 247.713649 -86.780852) (xy 247.768492 -86.770722) (xy 247.824226 -86.768685)
			(xy 247.879663 -86.774785) (xy 247.910742 -86.78291) (xy 249.4821 -86.78291) (xy 249.486171 -86.727288)
			(xy 249.498297 -86.672851) (xy 249.51822 -86.62076) (xy 249.545516 -86.572125) (xy 249.579602 -86.527982)
			(xy 249.619751 -86.489273) (xy 249.665109 -86.456822) (xy 249.714709 -86.431321) (xy 249.767493 -86.413314)
			(xy 249.822336 -86.403184) (xy 249.87807 -86.401147) (xy 249.933507 -86.407247) (xy 249.987464 -86.421353)
			(xy 250.038793 -86.443165) (xy 250.086399 -86.472219) (xy 250.09012 -86.475316) (xy 251.185172 -86.475316)
			(xy 251.18563 -86.447945) (xy 251.193447 -86.393765) (xy 251.208937 -86.341261) (xy 251.231781 -86.291514)
			(xy 251.261509 -86.245549) (xy 251.279152 -86.224618) (xy 251.279406 -86.224364) (xy 251.284973 -86.217264)
			(xy 251.291231 -86.200357) (xy 251.291598 -86.191344) (xy 251.291598 -86.124288) (xy 251.291247 -86.115271)
			(xy 251.284995 -86.098354) (xy 251.279406 -86.091268) (xy 251.279152 -86.091268) (xy 251.279152 -86.091014)
			(xy 251.261514 -86.070081) (xy 251.2318 -86.024109) (xy 251.208963 -85.974362) (xy 251.193472 -85.921861)
			(xy 251.185645 -85.867685) (xy 251.185172 -85.840316) (xy 251.185658 -85.813065) (xy 251.193414 -85.759117)
			(xy 251.208769 -85.706822) (xy 251.231411 -85.657245) (xy 251.260877 -85.611395) (xy 251.296568 -85.570204)
			(xy 251.337759 -85.534513) (xy 251.383609 -85.505047) (xy 251.433186 -85.482405) (xy 251.485481 -85.46705)
			(xy 251.539429 -85.459294) (xy 251.593931 -85.459294) (xy 251.647879 -85.46705) (xy 251.700174 -85.482405)
			(xy 251.749751 -85.505047) (xy 251.795601 -85.534513) (xy 251.836792 -85.570204) (xy 251.872483 -85.611395)
			(xy 251.901949 -85.657245) (xy 251.924591 -85.706822) (xy 251.939946 -85.759117) (xy 251.947702 -85.813065)
			(xy 251.948188 -85.840316) (xy 251.947734 -85.867687) (xy 251.939914 -85.921866) (xy 251.924422 -85.97437)
			(xy 251.901578 -86.024116) (xy 251.87185 -86.070083) (xy 251.854208 -86.091014) (xy 251.853954 -86.091268)
			(xy 251.848369 -86.098356) (xy 251.842123 -86.115272) (xy 251.841762 -86.124288) (xy 251.841762 -86.191344)
			(xy 251.842154 -86.200357) (xy 251.848378 -86.217274) (xy 251.853954 -86.224364) (xy 251.854208 -86.224364)
			(xy 251.854208 -86.224618) (xy 251.871823 -86.245569) (xy 251.901538 -86.291537) (xy 251.924379 -86.34128)
			(xy 251.939876 -86.393776) (xy 251.94771 -86.447948) (xy 251.948188 -86.475316) (xy 251.947702 -86.502567)
			(xy 251.939946 -86.556515) (xy 251.924591 -86.60881) (xy 251.901949 -86.658387) (xy 251.872483 -86.704237)
			(xy 251.836792 -86.745428) (xy 251.795601 -86.781119) (xy 251.749751 -86.810585) (xy 251.700174 -86.833227)
			(xy 251.647879 -86.848582) (xy 251.593931 -86.856338) (xy 251.539429 -86.856338) (xy 251.485481 -86.848582)
			(xy 251.433186 -86.833227) (xy 251.383609 -86.810585) (xy 251.337759 -86.781119) (xy 251.296568 -86.745428)
			(xy 251.260877 -86.704237) (xy 251.231411 -86.658387) (xy 251.208769 -86.60881) (xy 251.193414 -86.556515)
			(xy 251.185658 -86.502567) (xy 251.185172 -86.475316) (xy 250.09012 -86.475316) (xy 250.129267 -86.507894)
			(xy 250.166484 -86.549431) (xy 250.197257 -86.595944) (xy 250.220929 -86.646441) (xy 250.236997 -86.699848)
			(xy 250.245117 -86.755024) (xy 250.245626 -86.78291) (xy 250.245117 -86.810796) (xy 250.236997 -86.865972)
			(xy 250.220929 -86.919379) (xy 250.197257 -86.969876) (xy 250.166484 -87.016389) (xy 250.129267 -87.057926)
			(xy 250.086399 -87.093601) (xy 250.038793 -87.122655) (xy 249.987464 -87.144467) (xy 249.933507 -87.158573)
			(xy 249.87807 -87.164673) (xy 249.822336 -87.162636) (xy 249.767493 -87.152506) (xy 249.714709 -87.134499)
			(xy 249.665109 -87.108998) (xy 249.619751 -87.076547) (xy 249.579602 -87.037838) (xy 249.545516 -86.993695)
			(xy 249.51822 -86.94506) (xy 249.498297 -86.892969) (xy 249.486171 -86.838532) (xy 249.4821 -86.78291)
			(xy 247.910742 -86.78291) (xy 247.93362 -86.788891) (xy 247.984949 -86.810703) (xy 248.032555 -86.839757)
			(xy 248.075423 -86.875432) (xy 248.11264 -86.916969) (xy 248.143413 -86.963482) (xy 248.167085 -87.013979)
			(xy 248.183153 -87.067386) (xy 248.191273 -87.122562) (xy 248.191782 -87.150448) (xy 248.191273 -87.178334)
			(xy 248.183153 -87.23351) (xy 248.167085 -87.286917) (xy 248.143413 -87.337414) (xy 248.141075 -87.340948)
			(xy 250.984002 -87.340948) (xy 250.988073 -87.285326) (xy 251.000199 -87.230889) (xy 251.020122 -87.178798)
			(xy 251.047418 -87.130163) (xy 251.081504 -87.08602) (xy 251.121653 -87.047311) (xy 251.167011 -87.01486)
			(xy 251.216611 -86.989359) (xy 251.269395 -86.971352) (xy 251.324238 -86.961222) (xy 251.379972 -86.959185)
			(xy 251.435409 -86.965285) (xy 251.489366 -86.979391) (xy 251.540695 -87.001203) (xy 251.588301 -87.030257)
			(xy 251.631169 -87.065932) (xy 251.668386 -87.107469) (xy 251.699159 -87.153982) (xy 251.722831 -87.204479)
			(xy 251.738899 -87.257886) (xy 251.747019 -87.313062) (xy 251.747528 -87.340948) (xy 251.747019 -87.368834)
			(xy 251.738899 -87.42401) (xy 251.722831 -87.477417) (xy 251.699159 -87.527914) (xy 251.668386 -87.574427)
			(xy 251.631169 -87.615964) (xy 251.588301 -87.651639) (xy 251.540695 -87.680693) (xy 251.489366 -87.702505)
			(xy 251.435409 -87.716611) (xy 251.405373 -87.719916) (xy 252.861062 -87.719916) (xy 252.865133 -87.664294)
			(xy 252.877259 -87.609857) (xy 252.897182 -87.557766) (xy 252.924478 -87.509131) (xy 252.958564 -87.464988)
			(xy 252.998713 -87.426279) (xy 253.044071 -87.393828) (xy 253.093671 -87.368327) (xy 253.146455 -87.35032)
			(xy 253.201298 -87.34019) (xy 253.257032 -87.338153) (xy 253.312469 -87.344253) (xy 253.366426 -87.358359)
			(xy 253.417755 -87.380171) (xy 253.465361 -87.409225) (xy 253.508229 -87.4449) (xy 253.545446 -87.486437)
			(xy 253.554051 -87.499444) (xy 256.099562 -87.499444) (xy 256.103633 -87.443822) (xy 256.115759 -87.389385)
			(xy 256.135682 -87.337294) (xy 256.162978 -87.288659) (xy 256.197064 -87.244516) (xy 256.237213 -87.205807)
			(xy 256.282571 -87.173356) (xy 256.332171 -87.147855) (xy 256.384955 -87.129848) (xy 256.439798 -87.119718)
			(xy 256.495532 -87.117681) (xy 256.550969 -87.123781) (xy 256.604926 -87.137887) (xy 256.656255 -87.159699)
			(xy 256.703861 -87.188753) (xy 256.746729 -87.224428) (xy 256.783946 -87.265965) (xy 256.814719 -87.312478)
			(xy 256.838391 -87.362975) (xy 256.854459 -87.416382) (xy 256.862579 -87.471558) (xy 256.863088 -87.499444)
			(xy 256.862579 -87.52733) (xy 256.854459 -87.582506) (xy 256.838391 -87.635913) (xy 256.814719 -87.68641)
			(xy 256.783946 -87.732923) (xy 256.746729 -87.77446) (xy 256.703861 -87.810135) (xy 256.656255 -87.839189)
			(xy 256.604926 -87.861001) (xy 256.550969 -87.875107) (xy 256.495532 -87.881207) (xy 256.439798 -87.87917)
			(xy 256.384955 -87.86904) (xy 256.332171 -87.851033) (xy 256.282571 -87.825532) (xy 256.237213 -87.793081)
			(xy 256.197064 -87.754372) (xy 256.162978 -87.710229) (xy 256.135682 -87.661594) (xy 256.115759 -87.609503)
			(xy 256.103633 -87.555066) (xy 256.099562 -87.499444) (xy 253.554051 -87.499444) (xy 253.576219 -87.53295)
			(xy 253.599891 -87.583447) (xy 253.615959 -87.636854) (xy 253.624079 -87.69203) (xy 253.624588 -87.719916)
			(xy 253.624079 -87.747802) (xy 253.615959 -87.802978) (xy 253.599891 -87.856385) (xy 253.576219 -87.906882)
			(xy 253.545446 -87.953395) (xy 253.508229 -87.994932) (xy 253.465361 -88.030607) (xy 253.417755 -88.059661)
			(xy 253.366426 -88.081473) (xy 253.312469 -88.095579) (xy 253.257032 -88.101679) (xy 253.201298 -88.099642)
			(xy 253.146455 -88.089512) (xy 253.093671 -88.071505) (xy 253.044071 -88.046004) (xy 252.998713 -88.013553)
			(xy 252.958564 -87.974844) (xy 252.924478 -87.930701) (xy 252.897182 -87.882066) (xy 252.877259 -87.829975)
			(xy 252.865133 -87.775538) (xy 252.861062 -87.719916) (xy 251.405373 -87.719916) (xy 251.379972 -87.722711)
			(xy 251.324238 -87.720674) (xy 251.269395 -87.710544) (xy 251.216611 -87.692537) (xy 251.167011 -87.667036)
			(xy 251.121653 -87.634585) (xy 251.081504 -87.595876) (xy 251.047418 -87.551733) (xy 251.020122 -87.503098)
			(xy 251.000199 -87.451007) (xy 250.988073 -87.39657) (xy 250.984002 -87.340948) (xy 248.141075 -87.340948)
			(xy 248.11264 -87.383927) (xy 248.075423 -87.425464) (xy 248.032555 -87.461139) (xy 247.984949 -87.490193)
			(xy 247.93362 -87.512005) (xy 247.879663 -87.526111) (xy 247.824226 -87.532211) (xy 247.768492 -87.530174)
			(xy 247.713649 -87.520044) (xy 247.660865 -87.502037) (xy 247.611265 -87.476536) (xy 247.565907 -87.444085)
			(xy 247.525758 -87.405376) (xy 247.491672 -87.361233) (xy 247.464376 -87.312598) (xy 247.444453 -87.260507)
			(xy 247.432327 -87.20607) (xy 247.428256 -87.150448) (xy 236.094632 -87.150448) (xy 236.113787 -87.183626)
			(xy 236.136737 -87.239031) (xy 236.152258 -87.296958) (xy 236.160086 -87.356415) (xy 236.160086 -87.416385)
			(xy 236.152258 -87.475842) (xy 236.136737 -87.533769) (xy 236.113787 -87.589174) (xy 236.083802 -87.64111)
			(xy 236.047295 -87.688688) (xy 236.004889 -87.731093) (xy 235.957312 -87.767601) (xy 235.905376 -87.797586)
			(xy 235.849971 -87.820536) (xy 235.792044 -87.836058) (xy 235.732587 -87.843886) (xy 235.702602 -87.844376)
			(xy 234.839002 -87.844376) (xy 234.809017 -87.843879) (xy 234.749561 -87.836052) (xy 234.691634 -87.820531)
			(xy 234.636229 -87.797581) (xy 234.584294 -87.767597) (xy 234.536717 -87.73109) (xy 234.494312 -87.688685)
			(xy 234.457804 -87.641108) (xy 234.42782 -87.589172) (xy 234.40487 -87.533768) (xy 234.389349 -87.475841)
			(xy 234.381521 -87.416385) (xy 233.972939 -87.416385) (xy 233.972939 -87.444071) (xy 233.965115 -87.503499)
			(xy 233.9496 -87.561397) (xy 233.92666 -87.616775) (xy 233.896688 -87.668685) (xy 233.860197 -87.716239)
			(xy 233.81781 -87.758622) (xy 233.770254 -87.795109) (xy 233.718341 -87.825077) (xy 233.662961 -87.848012)
			(xy 233.605062 -87.863522) (xy 233.545633 -87.871341) (xy 233.515662 -87.871808) (xy 232.652062 -87.871808)
			(xy 232.622096 -87.871316) (xy 232.562677 -87.863488) (xy 232.504788 -87.847973) (xy 232.44942 -87.825034)
			(xy 232.397519 -87.795065) (xy 232.349973 -87.758579) (xy 232.307596 -87.716198) (xy 232.271114 -87.66865)
			(xy 232.241149 -87.616746) (xy 232.218215 -87.561376) (xy 232.202704 -87.503486) (xy 232.194882 -87.444066)
			(xy 222.340776 -87.444066) (xy 222.354081 -87.472449) (xy 222.370149 -87.525856) (xy 222.378269 -87.581032)
			(xy 222.378778 -87.608918) (xy 222.378269 -87.636804) (xy 222.370149 -87.69198) (xy 222.354081 -87.745387)
			(xy 222.330409 -87.795884) (xy 222.299636 -87.842397) (xy 222.262419 -87.883934) (xy 222.219551 -87.919609)
			(xy 222.171945 -87.948663) (xy 222.120616 -87.970475) (xy 222.066659 -87.984581) (xy 222.011222 -87.990681)
			(xy 221.955488 -87.988644) (xy 221.900645 -87.978514) (xy 221.847861 -87.960507) (xy 221.798261 -87.935006)
			(xy 221.752903 -87.902555) (xy 221.712754 -87.863846) (xy 221.678668 -87.819703) (xy 221.651372 -87.771068)
			(xy 221.631449 -87.718977) (xy 221.619323 -87.66454) (xy 221.615252 -87.608918) (xy 211.067415 -87.608918)
			(xy 211.070189 -87.627768) (xy 211.070698 -87.655654) (xy 211.070189 -87.68354) (xy 211.062069 -87.738716)
			(xy 211.046001 -87.792123) (xy 211.022329 -87.84262) (xy 210.991556 -87.889133) (xy 210.954339 -87.93067)
			(xy 210.911471 -87.966345) (xy 210.863865 -87.995399) (xy 210.838478 -88.006187) (xy 238.124409 -88.006187)
			(xy 238.124409 -87.946213) (xy 238.132238 -87.886751) (xy 238.147762 -87.82882) (xy 238.170714 -87.773411)
			(xy 238.200704 -87.721472) (xy 238.237216 -87.673892) (xy 238.279627 -87.631486) (xy 238.32721 -87.594978)
			(xy 238.379152 -87.564994) (xy 238.434563 -87.542047) (xy 238.492496 -87.526529) (xy 238.551959 -87.518706)
			(xy 238.581946 -87.51824) (xy 239.445546 -87.51824) (xy 239.475528 -87.518729) (xy 239.53498 -87.526561)
			(xy 239.5929 -87.542086) (xy 239.648299 -87.565038) (xy 239.700228 -87.595024) (xy 239.747799 -87.631531)
			(xy 239.790199 -87.673935) (xy 239.826701 -87.72151) (xy 239.856682 -87.773442) (xy 239.879628 -87.828843)
			(xy 239.895148 -87.886765) (xy 239.902974 -87.946217) (xy 239.902974 -88.006183) (xy 239.898595 -88.039448)
			(xy 247.428256 -88.039448) (xy 247.432327 -87.983826) (xy 247.444453 -87.929389) (xy 247.464376 -87.877298)
			(xy 247.491672 -87.828663) (xy 247.525758 -87.78452) (xy 247.565907 -87.745811) (xy 247.611265 -87.71336)
			(xy 247.660865 -87.687859) (xy 247.713649 -87.669852) (xy 247.768492 -87.659722) (xy 247.824226 -87.657685)
			(xy 247.879663 -87.663785) (xy 247.93362 -87.677891) (xy 247.984949 -87.699703) (xy 248.032555 -87.728757)
			(xy 248.075423 -87.764432) (xy 248.11264 -87.805969) (xy 248.143413 -87.852482) (xy 248.167085 -87.902979)
			(xy 248.183153 -87.956386) (xy 248.191273 -88.011562) (xy 248.191782 -88.039448) (xy 248.191597 -88.049608)
			(xy 249.542806 -88.049608) (xy 249.546877 -87.993986) (xy 249.559003 -87.939549) (xy 249.578926 -87.887458)
			(xy 249.606222 -87.838823) (xy 249.640308 -87.79468) (xy 249.680457 -87.755971) (xy 249.725815 -87.72352)
			(xy 249.775415 -87.698019) (xy 249.828199 -87.680012) (xy 249.883042 -87.669882) (xy 249.938776 -87.667845)
			(xy 249.994213 -87.673945) (xy 250.04817 -87.688051) (xy 250.099499 -87.709863) (xy 250.147105 -87.738917)
			(xy 250.189973 -87.774592) (xy 250.22719 -87.816129) (xy 250.257963 -87.862642) (xy 250.281635 -87.913139)
			(xy 250.297703 -87.966546) (xy 250.305823 -88.021722) (xy 250.306332 -88.049608) (xy 250.305823 -88.077494)
			(xy 250.297703 -88.13267) (xy 250.281635 -88.186077) (xy 250.257963 -88.236574) (xy 250.22719 -88.283087)
			(xy 250.189973 -88.324624) (xy 250.147105 -88.360299) (xy 250.099499 -88.389353) (xy 250.04817 -88.411165)
			(xy 249.994213 -88.425271) (xy 249.938776 -88.431371) (xy 249.883042 -88.429334) (xy 249.828199 -88.419204)
			(xy 249.775415 -88.401197) (xy 249.725815 -88.375696) (xy 249.680457 -88.343245) (xy 249.640308 -88.304536)
			(xy 249.606222 -88.260393) (xy 249.578926 -88.211758) (xy 249.559003 -88.159667) (xy 249.546877 -88.10523)
			(xy 249.542806 -88.049608) (xy 248.191597 -88.049608) (xy 248.191273 -88.067334) (xy 248.183153 -88.12251)
			(xy 248.167085 -88.175917) (xy 248.143413 -88.226414) (xy 248.11264 -88.272927) (xy 248.075423 -88.314464)
			(xy 248.032555 -88.350139) (xy 247.984949 -88.379193) (xy 247.93362 -88.401005) (xy 247.879663 -88.415111)
			(xy 247.824226 -88.421211) (xy 247.768492 -88.419174) (xy 247.713649 -88.409044) (xy 247.660865 -88.391037)
			(xy 247.611265 -88.365536) (xy 247.565907 -88.333085) (xy 247.525758 -88.294376) (xy 247.491672 -88.250233)
			(xy 247.464376 -88.201598) (xy 247.444453 -88.149507) (xy 247.432327 -88.09507) (xy 247.428256 -88.039448)
			(xy 239.898595 -88.039448) (xy 239.895148 -88.065635) (xy 239.879628 -88.123557) (xy 239.856682 -88.178958)
			(xy 239.826701 -88.23089) (xy 239.790199 -88.278465) (xy 239.747799 -88.320869) (xy 239.700228 -88.357376)
			(xy 239.648299 -88.387362) (xy 239.5929 -88.410314) (xy 239.53498 -88.425839) (xy 239.475528 -88.433671)
			(xy 239.445546 -88.434164) (xy 238.581946 -88.434164) (xy 238.551959 -88.433694) (xy 238.492496 -88.425871)
			(xy 238.434563 -88.410353) (xy 238.379152 -88.387406) (xy 238.32721 -88.357422) (xy 238.279627 -88.320914)
			(xy 238.237216 -88.278508) (xy 238.200704 -88.230928) (xy 238.170714 -88.178989) (xy 238.147762 -88.12358)
			(xy 238.132238 -88.065649) (xy 238.124409 -88.006187) (xy 210.838478 -88.006187) (xy 210.812536 -88.017211)
			(xy 210.758579 -88.031317) (xy 210.703142 -88.037417) (xy 210.647408 -88.03538) (xy 210.592565 -88.02525)
			(xy 210.539781 -88.007243) (xy 210.490181 -87.981742) (xy 210.444823 -87.949291) (xy 210.404674 -87.910582)
			(xy 210.370588 -87.866439) (xy 210.343292 -87.817804) (xy 210.323369 -87.765713) (xy 210.311243 -87.711276)
			(xy 210.307172 -87.655654) (xy 210.255358 -87.655654) (xy 210.254891 -87.685692) (xy 210.247055 -87.745256)
			(xy 210.231512 -87.803287) (xy 210.208527 -87.858792) (xy 210.178493 -87.910823) (xy 210.141925 -87.958488)
			(xy 210.099448 -88.000973) (xy 210.05179 -88.037549) (xy 209.999764 -88.067591) (xy 209.944263 -88.090586)
			(xy 209.886234 -88.10614) (xy 209.826672 -88.113986) (xy 209.796634 -88.114378) (xy 209.767049 -88.113913)
			(xy 209.708371 -88.106298) (xy 209.651158 -88.091205) (xy 209.59636 -88.068883) (xy 209.544886 -88.039702)
			(xy 209.49759 -88.004147) (xy 209.476086 -87.983822) (xy 209.47253 -87.984838) (xy 209.464462 -87.987186)
			(xy 209.450328 -87.996253) (xy 209.444844 -88.002618) (xy 209.440272 -88.009984) (xy 209.312256 -88.245442)
			(xy 209.30853 -88.252997) (xy 209.305679 -88.269588) (xy 209.306668 -88.277954) (xy 209.308192 -88.285574)
			(xy 209.309208 -88.288622) (xy 209.309208 -88.288876) (xy 209.309462 -88.28913) (xy 209.318386 -88.318163)
			(xy 209.327954 -88.378141) (xy 209.328512 -88.40851) (xy 209.328512 -88.414606) (xy 209.327603 -88.442297)
			(xy 209.318771 -88.496992) (xy 209.302121 -88.549835) (xy 209.278004 -88.599714) (xy 209.246927 -88.645581)
			(xy 209.209542 -88.686471) (xy 209.166637 -88.721523) (xy 209.119113 -88.750002) (xy 209.06797 -88.771309)
			(xy 209.041238 -88.778588) (xy 209.03057 -88.781382) (xy 209.02295 -88.787224) (xy 209.019202 -88.790151)
			(xy 209.012801 -88.797181) (xy 209.01025 -88.801194) (xy 208.802799 -89.182956) (xy 227.930708 -89.182956)
			(xy 227.934779 -89.127334) (xy 227.946905 -89.072897) (xy 227.966828 -89.020806) (xy 227.994124 -88.972171)
			(xy 228.02821 -88.928028) (xy 228.068359 -88.889319) (xy 228.113717 -88.856868) (xy 228.163317 -88.831367)
			(xy 228.216101 -88.81336) (xy 228.270944 -88.80323) (xy 228.326678 -88.801193) (xy 228.382115 -88.807293)
			(xy 228.436072 -88.821399) (xy 228.487401 -88.843211) (xy 228.535007 -88.872265) (xy 228.55582 -88.889586)
			(xy 234.138976 -88.889586) (xy 234.143047 -88.833964) (xy 234.155173 -88.779527) (xy 234.175096 -88.727436)
			(xy 234.202392 -88.678801) (xy 234.236478 -88.634658) (xy 234.276627 -88.595949) (xy 234.321985 -88.563498)
			(xy 234.371585 -88.537997) (xy 234.424369 -88.51999) (xy 234.479212 -88.50986) (xy 234.534946 -88.507823)
			(xy 234.590383 -88.513923) (xy 234.64434 -88.528029) (xy 234.695669 -88.549841) (xy 234.743275 -88.578895)
			(xy 234.786143 -88.61457) (xy 234.82336 -88.656107) (xy 234.854133 -88.70262) (xy 234.877805 -88.753117)
			(xy 234.883481 -88.771984) (xy 250.730256 -88.771984) (xy 250.734327 -88.716362) (xy 250.746453 -88.661925)
			(xy 250.766376 -88.609834) (xy 250.793672 -88.561199) (xy 250.827758 -88.517056) (xy 250.867907 -88.478347)
			(xy 250.913265 -88.445896) (xy 250.962865 -88.420395) (xy 251.015649 -88.402388) (xy 251.070492 -88.392258)
			(xy 251.126226 -88.390221) (xy 251.181663 -88.396321) (xy 251.23562 -88.410427) (xy 251.286949 -88.432239)
			(xy 251.334555 -88.461293) (xy 251.377423 -88.496968) (xy 251.41464 -88.538505) (xy 251.445413 -88.585018)
			(xy 251.469085 -88.635515) (xy 251.485153 -88.688922) (xy 251.493273 -88.744098) (xy 251.493782 -88.771984)
			(xy 251.493273 -88.79987) (xy 251.485153 -88.855046) (xy 251.469085 -88.908453) (xy 251.445413 -88.95895)
			(xy 251.41464 -89.005463) (xy 251.377423 -89.047) (xy 251.334555 -89.082675) (xy 251.286949 -89.111729)
			(xy 251.23562 -89.133541) (xy 251.181663 -89.147647) (xy 251.126226 -89.153747) (xy 251.070492 -89.15171)
			(xy 251.015649 -89.14158) (xy 250.962865 -89.123573) (xy 250.913265 -89.098072) (xy 250.867907 -89.065621)
			(xy 250.827758 -89.026912) (xy 250.793672 -88.982769) (xy 250.766376 -88.934134) (xy 250.746453 -88.882043)
			(xy 250.734327 -88.827606) (xy 250.730256 -88.771984) (xy 234.883481 -88.771984) (xy 234.893873 -88.806524)
			(xy 234.901993 -88.8617) (xy 234.902502 -88.889586) (xy 234.901993 -88.917472) (xy 234.893873 -88.972648)
			(xy 234.877805 -89.026055) (xy 234.854133 -89.076552) (xy 234.82336 -89.123065) (xy 234.786143 -89.164602)
			(xy 234.743275 -89.200277) (xy 234.695669 -89.229331) (xy 234.64434 -89.251143) (xy 234.590383 -89.265249)
			(xy 234.534946 -89.271349) (xy 234.479212 -89.269312) (xy 234.424369 -89.259182) (xy 234.371585 -89.241175)
			(xy 234.321985 -89.215674) (xy 234.276627 -89.183223) (xy 234.236478 -89.144514) (xy 234.202392 -89.100371)
			(xy 234.175096 -89.051736) (xy 234.155173 -88.999645) (xy 234.143047 -88.945208) (xy 234.138976 -88.889586)
			(xy 228.55582 -88.889586) (xy 228.577875 -88.90794) (xy 228.615092 -88.949477) (xy 228.645865 -88.99599)
			(xy 228.669537 -89.046487) (xy 228.685605 -89.099894) (xy 228.693725 -89.15507) (xy 228.694234 -89.182956)
			(xy 228.693725 -89.210842) (xy 228.685605 -89.266018) (xy 228.669537 -89.319425) (xy 228.645865 -89.369922)
			(xy 228.615092 -89.416435) (xy 228.577875 -89.457972) (xy 228.571691 -89.463118) (xy 248.974608 -89.463118)
			(xy 248.978679 -89.407496) (xy 248.990805 -89.353059) (xy 249.010728 -89.300968) (xy 249.038024 -89.252333)
			(xy 249.07211 -89.20819) (xy 249.112259 -89.169481) (xy 249.157617 -89.13703) (xy 249.207217 -89.111529)
			(xy 249.260001 -89.093522) (xy 249.314844 -89.083392) (xy 249.370578 -89.081355) (xy 249.426015 -89.087455)
			(xy 249.479972 -89.101561) (xy 249.531301 -89.123373) (xy 249.578907 -89.152427) (xy 249.621775 -89.188102)
			(xy 249.658992 -89.229639) (xy 249.689765 -89.276152) (xy 249.713437 -89.326649) (xy 249.729505 -89.380056)
			(xy 249.737625 -89.435232) (xy 249.73774 -89.441528) (xy 252.608078 -89.441528) (xy 252.612149 -89.385906)
			(xy 252.624275 -89.331469) (xy 252.644198 -89.279378) (xy 252.671494 -89.230743) (xy 252.70558 -89.1866)
			(xy 252.745729 -89.147891) (xy 252.791087 -89.11544) (xy 252.840687 -89.089939) (xy 252.893471 -89.071932)
			(xy 252.948314 -89.061802) (xy 253.004048 -89.059765) (xy 253.059485 -89.065865) (xy 253.113442 -89.079971)
			(xy 253.151369 -89.096088) (xy 258.801106 -89.096088) (xy 258.805177 -89.040466) (xy 258.817303 -88.986029)
			(xy 258.837226 -88.933938) (xy 258.864522 -88.885303) (xy 258.898608 -88.84116) (xy 258.938757 -88.802451)
			(xy 258.984115 -88.77) (xy 259.033715 -88.744499) (xy 259.086499 -88.726492) (xy 259.141342 -88.716362)
			(xy 259.197076 -88.714325) (xy 259.252513 -88.720425) (xy 259.30647 -88.734531) (xy 259.357799 -88.756343)
			(xy 259.405405 -88.785397) (xy 259.448273 -88.821072) (xy 259.48549 -88.862609) (xy 259.516263 -88.909122)
			(xy 259.539935 -88.959619) (xy 259.554629 -89.008458) (xy 261.557768 -89.008458) (xy 261.561839 -88.952836)
			(xy 261.573965 -88.898399) (xy 261.593888 -88.846308) (xy 261.621184 -88.797673) (xy 261.65527 -88.75353)
			(xy 261.695419 -88.714821) (xy 261.740777 -88.68237) (xy 261.790377 -88.656869) (xy 261.843161 -88.638862)
			(xy 261.898004 -88.628732) (xy 261.953738 -88.626695) (xy 262.009175 -88.632795) (xy 262.063132 -88.646901)
			(xy 262.114461 -88.668713) (xy 262.162067 -88.697767) (xy 262.204935 -88.733442) (xy 262.242152 -88.774979)
			(xy 262.272925 -88.821492) (xy 262.296597 -88.871989) (xy 262.312665 -88.925396) (xy 262.320785 -88.980572)
			(xy 262.321294 -89.008458) (xy 262.320785 -89.036344) (xy 262.312665 -89.09152) (xy 262.296597 -89.144927)
			(xy 262.272925 -89.195424) (xy 262.242152 -89.241937) (xy 262.204935 -89.283474) (xy 262.162067 -89.319149)
			(xy 262.114461 -89.348203) (xy 262.063132 -89.370015) (xy 262.009175 -89.384121) (xy 261.953738 -89.390221)
			(xy 261.898004 -89.388184) (xy 261.843161 -89.378054) (xy 261.790377 -89.360047) (xy 261.740777 -89.334546)
			(xy 261.695419 -89.302095) (xy 261.65527 -89.263386) (xy 261.621184 -89.219243) (xy 261.593888 -89.170608)
			(xy 261.573965 -89.118517) (xy 261.561839 -89.06408) (xy 261.557768 -89.008458) (xy 259.554629 -89.008458)
			(xy 259.556003 -89.013026) (xy 259.564123 -89.068202) (xy 259.564632 -89.096088) (xy 259.564123 -89.123974)
			(xy 259.556003 -89.17915) (xy 259.539935 -89.232557) (xy 259.516263 -89.283054) (xy 259.48549 -89.329567)
			(xy 259.448273 -89.371104) (xy 259.405405 -89.406779) (xy 259.357799 -89.435833) (xy 259.30647 -89.457645)
			(xy 259.252513 -89.471751) (xy 259.197076 -89.477851) (xy 259.141342 -89.475814) (xy 259.086499 -89.465684)
			(xy 259.033715 -89.447677) (xy 258.984115 -89.422176) (xy 258.938757 -89.389725) (xy 258.898608 -89.351016)
			(xy 258.864522 -89.306873) (xy 258.837226 -89.258238) (xy 258.817303 -89.206147) (xy 258.805177 -89.15171)
			(xy 258.801106 -89.096088) (xy 253.151369 -89.096088) (xy 253.164771 -89.101783) (xy 253.212377 -89.130837)
			(xy 253.255245 -89.166512) (xy 253.292462 -89.208049) (xy 253.323235 -89.254562) (xy 253.346907 -89.305059)
			(xy 253.362975 -89.358466) (xy 253.371095 -89.413642) (xy 253.371604 -89.441528) (xy 253.371095 -89.469414)
			(xy 253.362975 -89.52459) (xy 253.346907 -89.577997) (xy 253.323235 -89.628494) (xy 253.292462 -89.675007)
			(xy 253.255245 -89.716544) (xy 253.212377 -89.752219) (xy 253.164771 -89.781273) (xy 253.113442 -89.803085)
			(xy 253.059485 -89.817191) (xy 253.004048 -89.823291) (xy 252.948314 -89.821254) (xy 252.893471 -89.811124)
			(xy 252.840687 -89.793117) (xy 252.791087 -89.767616) (xy 252.745729 -89.735165) (xy 252.70558 -89.696456)
			(xy 252.671494 -89.652313) (xy 252.644198 -89.603678) (xy 252.624275 -89.551587) (xy 252.612149 -89.49715)
			(xy 252.608078 -89.441528) (xy 249.73774 -89.441528) (xy 249.738134 -89.463118) (xy 249.737625 -89.491004)
			(xy 249.729505 -89.54618) (xy 249.713437 -89.599587) (xy 249.689765 -89.650084) (xy 249.658992 -89.696597)
			(xy 249.621775 -89.738134) (xy 249.578907 -89.773809) (xy 249.531301 -89.802863) (xy 249.479972 -89.824675)
			(xy 249.426015 -89.838781) (xy 249.370578 -89.844881) (xy 249.314844 -89.842844) (xy 249.260001 -89.832714)
			(xy 249.207217 -89.814707) (xy 249.157617 -89.789206) (xy 249.112259 -89.756755) (xy 249.07211 -89.718046)
			(xy 249.038024 -89.673903) (xy 249.010728 -89.625268) (xy 248.990805 -89.573177) (xy 248.978679 -89.51874)
			(xy 248.974608 -89.463118) (xy 228.571691 -89.463118) (xy 228.535007 -89.493647) (xy 228.487401 -89.522701)
			(xy 228.436072 -89.544513) (xy 228.382115 -89.558619) (xy 228.326678 -89.564719) (xy 228.270944 -89.562682)
			(xy 228.216101 -89.552552) (xy 228.163317 -89.534545) (xy 228.113717 -89.509044) (xy 228.068359 -89.476593)
			(xy 228.02821 -89.437884) (xy 227.994124 -89.393741) (xy 227.966828 -89.345106) (xy 227.946905 -89.293015)
			(xy 227.934779 -89.238578) (xy 227.930708 -89.182956) (xy 208.802799 -89.182956) (xy 208.35353 -90.009726)
			(xy 227.35235 -90.009726) (xy 227.356421 -89.954104) (xy 227.368547 -89.899667) (xy 227.38847 -89.847576)
			(xy 227.415766 -89.798941) (xy 227.449852 -89.754798) (xy 227.490001 -89.716089) (xy 227.535359 -89.683638)
			(xy 227.584959 -89.658137) (xy 227.637743 -89.64013) (xy 227.692586 -89.63) (xy 227.74832 -89.627963)
			(xy 227.803757 -89.634063) (xy 227.857714 -89.648169) (xy 227.909043 -89.669981) (xy 227.956649 -89.699035)
			(xy 227.999517 -89.73471) (xy 228.036734 -89.776247) (xy 228.067507 -89.82276) (xy 228.091179 -89.873257)
			(xy 228.107247 -89.926664) (xy 228.115367 -89.98184) (xy 228.115876 -90.009726) (xy 228.115367 -90.037612)
			(xy 228.107247 -90.092788) (xy 228.091179 -90.146195) (xy 228.067507 -90.196692) (xy 228.036734 -90.243205)
			(xy 228.018328 -90.263747) (xy 229.611726 -90.263747) (xy 229.611726 -90.209253) (xy 229.619481 -90.155314)
			(xy 229.634833 -90.103027) (xy 229.65747 -90.053457) (xy 229.686931 -90.007614) (xy 229.722616 -89.966429)
			(xy 229.763799 -89.930742) (xy 229.809642 -89.901279) (xy 229.85921 -89.87864) (xy 229.911496 -89.863285)
			(xy 229.965435 -89.855527) (xy 229.992682 -89.85504) (xy 230.019221 -89.85549) (xy 230.071788 -89.862832)
			(xy 230.122829 -89.877391) (xy 230.171359 -89.898886) (xy 230.216441 -89.926901) (xy 230.257203 -89.960896)
			(xy 230.292859 -90.000214) (xy 230.322719 -90.044095) (xy 230.346208 -90.091692) (xy 230.362871 -90.142085)
			(xy 230.372386 -90.194303) (xy 230.373461 -90.212672) (xy 236.886494 -90.212672) (xy 236.890565 -90.15705)
			(xy 236.902691 -90.102613) (xy 236.922614 -90.050522) (xy 236.94991 -90.001887) (xy 236.983996 -89.957744)
			(xy 237.024145 -89.919035) (xy 237.069503 -89.886584) (xy 237.119103 -89.861083) (xy 237.171887 -89.843076)
			(xy 237.22673 -89.832946) (xy 237.282464 -89.830909) (xy 237.337901 -89.837009) (xy 237.391858 -89.851115)
			(xy 237.432774 -89.868502) (xy 251.846586 -89.868502) (xy 251.850657 -89.81288) (xy 251.862783 -89.758443)
			(xy 251.882706 -89.706352) (xy 251.910002 -89.657717) (xy 251.944088 -89.613574) (xy 251.984237 -89.574865)
			(xy 252.029595 -89.542414) (xy 252.079195 -89.516913) (xy 252.131979 -89.498906) (xy 252.186822 -89.488776)
			(xy 252.242556 -89.486739) (xy 252.297993 -89.492839) (xy 252.35195 -89.506945) (xy 252.403279 -89.528757)
			(xy 252.450885 -89.557811) (xy 252.493753 -89.593486) (xy 252.53097 -89.635023) (xy 252.561743 -89.681536)
			(xy 252.585415 -89.732033) (xy 252.601483 -89.78544) (xy 252.609603 -89.840616) (xy 252.610112 -89.868502)
			(xy 252.609603 -89.896388) (xy 252.608436 -89.904316) (xy 253.724662 -89.904316) (xy 253.728733 -89.848694)
			(xy 253.740859 -89.794257) (xy 253.760782 -89.742166) (xy 253.788078 -89.693531) (xy 253.822164 -89.649388)
			(xy 253.862313 -89.610679) (xy 253.907671 -89.578228) (xy 253.957271 -89.552727) (xy 254.010055 -89.53472)
			(xy 254.064898 -89.52459) (xy 254.120632 -89.522553) (xy 254.176069 -89.528653) (xy 254.230026 -89.542759)
			(xy 254.281355 -89.564571) (xy 254.328961 -89.593625) (xy 254.371829 -89.6293) (xy 254.409046 -89.670837)
			(xy 254.439819 -89.71735) (xy 254.463491 -89.767847) (xy 254.479559 -89.821254) (xy 254.487679 -89.87643)
			(xy 254.488188 -89.904316) (xy 254.487679 -89.932202) (xy 254.479559 -89.987378) (xy 254.463491 -90.040785)
			(xy 254.439819 -90.091282) (xy 254.409046 -90.137795) (xy 254.371829 -90.179332) (xy 254.328961 -90.215007)
			(xy 254.281355 -90.244061) (xy 254.230026 -90.265873) (xy 254.176069 -90.279979) (xy 254.120632 -90.286079)
			(xy 254.064898 -90.284042) (xy 254.010055 -90.273912) (xy 253.957271 -90.255905) (xy 253.907671 -90.230404)
			(xy 253.862313 -90.197953) (xy 253.822164 -90.159244) (xy 253.788078 -90.115101) (xy 253.760782 -90.066466)
			(xy 253.740859 -90.014375) (xy 253.728733 -89.959938) (xy 253.724662 -89.904316) (xy 252.608436 -89.904316)
			(xy 252.601483 -89.951564) (xy 252.585415 -90.004971) (xy 252.561743 -90.055468) (xy 252.53097 -90.101981)
			(xy 252.493753 -90.143518) (xy 252.450885 -90.179193) (xy 252.403279 -90.208247) (xy 252.35195 -90.230059)
			(xy 252.297993 -90.244165) (xy 252.242556 -90.250265) (xy 252.186822 -90.248228) (xy 252.131979 -90.238098)
			(xy 252.079195 -90.220091) (xy 252.029595 -90.19459) (xy 251.984237 -90.162139) (xy 251.944088 -90.12343)
			(xy 251.910002 -90.079287) (xy 251.882706 -90.030652) (xy 251.862783 -89.978561) (xy 251.850657 -89.924124)
			(xy 251.846586 -89.868502) (xy 237.432774 -89.868502) (xy 237.443187 -89.872927) (xy 237.490793 -89.901981)
			(xy 237.533661 -89.937656) (xy 237.570878 -89.979193) (xy 237.601651 -90.025706) (xy 237.625323 -90.076203)
			(xy 237.641391 -90.12961) (xy 237.649511 -90.184786) (xy 237.65002 -90.212672) (xy 237.649511 -90.240558)
			(xy 237.641391 -90.295734) (xy 237.625323 -90.349141) (xy 237.601651 -90.399638) (xy 237.570878 -90.446151)
			(xy 237.533661 -90.487688) (xy 237.490793 -90.523363) (xy 237.443187 -90.552417) (xy 237.391858 -90.574229)
			(xy 237.337901 -90.588335) (xy 237.282464 -90.594435) (xy 237.22673 -90.592398) (xy 237.171887 -90.582268)
			(xy 237.119103 -90.564261) (xy 237.069503 -90.53876) (xy 237.024145 -90.506309) (xy 236.983996 -90.4676)
			(xy 236.94991 -90.423457) (xy 236.922614 -90.374822) (xy 236.902691 -90.322731) (xy 236.890565 -90.268294)
			(xy 236.886494 -90.212672) (xy 230.373461 -90.212672) (xy 230.373936 -90.2208) (xy 230.374664 -90.230031)
			(xy 230.38189 -90.247067) (xy 230.394703 -90.260417) (xy 230.402892 -90.264742) (xy 230.483918 -90.303096)
			(xy 230.492374 -90.30672) (xy 230.510698 -90.308241) (xy 230.528377 -90.303188) (xy 230.535988 -90.298016)
			(xy 230.536242 -90.298016) (xy 230.561108 -90.28021) (xy 230.615337 -90.251937) (xy 230.673382 -90.232678)
			(xy 230.733756 -90.222926) (xy 230.764334 -90.222324) (xy 230.791588 -90.222746) (xy 230.845539 -90.230508)
			(xy 230.897837 -90.245869) (xy 230.947417 -90.268517) (xy 230.993268 -90.29799) (xy 231.034459 -90.333688)
			(xy 231.07015 -90.374885) (xy 231.099615 -90.420741) (xy 231.122254 -90.470325) (xy 231.137606 -90.522625)
			(xy 231.145358 -90.576578) (xy 231.145842 -90.603832) (xy 231.145409 -90.631204) (xy 231.137585 -90.685385)
			(xy 231.122089 -90.737889) (xy 231.09924 -90.787635) (xy 231.069507 -90.8336) (xy 231.051862 -90.85453)
			(xy 231.045818 -90.862034) (xy 231.039432 -90.880199) (xy 231.039416 -90.889836) (xy 231.042718 -90.969592)
			(xy 231.050592 -90.986864) (xy 231.05745 -90.993722) (xy 231.07528 -91.011731) (xy 231.106509 -91.051642)
			(xy 231.12844 -91.088972) (xy 236.971838 -91.088972) (xy 236.975909 -91.03335) (xy 236.988035 -90.978913)
			(xy 237.007958 -90.926822) (xy 237.035254 -90.878187) (xy 237.06934 -90.834044) (xy 237.109489 -90.795335)
			(xy 237.154847 -90.762884) (xy 237.204447 -90.737383) (xy 237.257231 -90.719376) (xy 237.312074 -90.709246)
			(xy 237.367808 -90.707209) (xy 237.423245 -90.713309) (xy 237.477202 -90.727415) (xy 237.528531 -90.749227)
			(xy 237.576137 -90.778281) (xy 237.619005 -90.813956) (xy 237.656222 -90.855493) (xy 237.686995 -90.902006)
			(xy 237.710667 -90.952503) (xy 237.726735 -91.00591) (xy 237.734855 -91.061086) (xy 237.735364 -91.088972)
			(xy 237.734855 -91.116858) (xy 237.726735 -91.172034) (xy 237.710667 -91.225441) (xy 237.686995 -91.275938)
			(xy 237.656222 -91.322451) (xy 237.619005 -91.363988) (xy 237.576137 -91.399663) (xy 237.528531 -91.428717)
			(xy 237.477202 -91.450529) (xy 237.423245 -91.464635) (xy 237.367808 -91.470735) (xy 237.312074 -91.468698)
			(xy 237.257231 -91.458568) (xy 237.204447 -91.440561) (xy 237.154847 -91.41506) (xy 237.109489 -91.382609)
			(xy 237.06934 -91.3439) (xy 237.035254 -91.299757) (xy 237.007958 -91.251122) (xy 236.988035 -91.199031)
			(xy 236.975909 -91.144594) (xy 236.971838 -91.088972) (xy 231.12844 -91.088972) (xy 231.132179 -91.095337)
			(xy 231.151837 -91.142047) (xy 231.165137 -91.190948) (xy 231.171845 -91.241179) (xy 231.172258 -91.266518)
			(xy 231.171772 -91.293769) (xy 231.164016 -91.347717) (xy 231.148661 -91.400012) (xy 231.126019 -91.449589)
			(xy 231.096553 -91.495439) (xy 231.060862 -91.53663) (xy 231.019671 -91.572321) (xy 230.973821 -91.601787)
			(xy 230.924244 -91.624429) (xy 230.871949 -91.639784) (xy 230.818001 -91.64754) (xy 230.763499 -91.64754)
			(xy 230.709551 -91.639784) (xy 230.657256 -91.624429) (xy 230.607679 -91.601787) (xy 230.561829 -91.572321)
			(xy 230.520638 -91.53663) (xy 230.484947 -91.495439) (xy 230.455481 -91.449589) (xy 230.432839 -91.400012)
			(xy 230.417484 -91.347717) (xy 230.409728 -91.293769) (xy 230.409242 -91.266518) (xy 230.409708 -91.239148)
			(xy 230.417525 -91.184968) (xy 230.433013 -91.132465) (xy 230.455855 -91.082718) (xy 230.48558 -91.036751)
			(xy 230.503222 -91.01582) (xy 230.509242 -91.008299) (xy 230.515643 -90.990147) (xy 230.515668 -90.980514)
			(xy 230.512366 -90.900758) (xy 230.504492 -90.883486) (xy 230.497634 -90.876628) (xy 230.47735 -90.85612)
			(xy 230.442623 -90.810066) (xy 230.415233 -90.759303) (xy 230.395808 -90.704992) (xy 230.38479 -90.648374)
			(xy 230.38308 -90.61958) (xy 230.382357 -90.610348) (xy 230.375127 -90.593314) (xy 230.362313 -90.579964)
			(xy 230.354124 -90.575638) (xy 230.273098 -90.537284) (xy 230.264636 -90.533676) (xy 230.246316 -90.532151)
			(xy 230.228639 -90.537197) (xy 230.221028 -90.542364) (xy 230.220774 -90.542364) (xy 230.19591 -90.560173)
			(xy 230.14168 -90.588443) (xy 230.083634 -90.607701) (xy 230.02326 -90.617453) (xy 229.992682 -90.618056)
			(xy 229.965435 -90.617473) (xy 229.911496 -90.609715) (xy 229.85921 -90.59436) (xy 229.809642 -90.571721)
			(xy 229.763799 -90.542258) (xy 229.722616 -90.506571) (xy 229.686931 -90.465386) (xy 229.65747 -90.419543)
			(xy 229.634833 -90.369973) (xy 229.619481 -90.317686) (xy 229.611726 -90.263747) (xy 228.018328 -90.263747)
			(xy 227.999517 -90.284742) (xy 227.956649 -90.320417) (xy 227.909043 -90.349471) (xy 227.857714 -90.371283)
			(xy 227.803757 -90.385389) (xy 227.74832 -90.391489) (xy 227.692586 -90.389452) (xy 227.637743 -90.379322)
			(xy 227.584959 -90.361315) (xy 227.535359 -90.335814) (xy 227.490001 -90.303363) (xy 227.449852 -90.264654)
			(xy 227.415766 -90.220511) (xy 227.38847 -90.171876) (xy 227.368547 -90.119785) (xy 227.356421 -90.065348)
			(xy 227.35235 -90.009726) (xy 208.35353 -90.009726) (xy 208.294732 -90.11793) (xy 208.290057 -90.125794)
			(xy 208.276284 -90.137815) (xy 208.259168 -90.144239) (xy 208.250028 -90.1446) (xy 208.145888 -90.1446)
			(xy 208.136902 -90.144946) (xy 208.12004 -90.151156) (xy 208.106383 -90.162836) (xy 208.101692 -90.170508)
			(xy 207.934643 -90.467688) (xy 214.358472 -90.467688) (xy 214.362543 -90.412066) (xy 214.374669 -90.357629)
			(xy 214.394592 -90.305538) (xy 214.421888 -90.256903) (xy 214.455974 -90.21276) (xy 214.496123 -90.174051)
			(xy 214.541481 -90.1416) (xy 214.591081 -90.116099) (xy 214.643865 -90.098092) (xy 214.698708 -90.087962)
			(xy 214.754442 -90.085925) (xy 214.809879 -90.092025) (xy 214.863836 -90.106131) (xy 214.915165 -90.127943)
			(xy 214.962771 -90.156997) (xy 215.005639 -90.192672) (xy 215.042856 -90.234209) (xy 215.073629 -90.280722)
			(xy 215.097301 -90.331219) (xy 215.113369 -90.384626) (xy 215.121489 -90.439802) (xy 215.121998 -90.467688)
			(xy 215.121489 -90.495574) (xy 215.113369 -90.55075) (xy 215.097301 -90.604157) (xy 215.096977 -90.604848)
			(xy 216.170508 -90.604848) (xy 216.174579 -90.549226) (xy 216.186705 -90.494789) (xy 216.206628 -90.442698)
			(xy 216.233924 -90.394063) (xy 216.26801 -90.34992) (xy 216.308159 -90.311211) (xy 216.353517 -90.27876)
			(xy 216.403117 -90.253259) (xy 216.455901 -90.235252) (xy 216.510744 -90.225122) (xy 216.566478 -90.223085)
			(xy 216.621915 -90.229185) (xy 216.675872 -90.243291) (xy 216.727201 -90.265103) (xy 216.774807 -90.294157)
			(xy 216.817675 -90.329832) (xy 216.854892 -90.371369) (xy 216.885665 -90.417882) (xy 216.909337 -90.468379)
			(xy 216.925405 -90.521786) (xy 216.926938 -90.532204) (xy 217.059508 -90.532204) (xy 217.063579 -90.476582)
			(xy 217.075705 -90.422145) (xy 217.095628 -90.370054) (xy 217.122924 -90.321419) (xy 217.15701 -90.277276)
			(xy 217.197159 -90.238567) (xy 217.242517 -90.206116) (xy 217.292117 -90.180615) (xy 217.344901 -90.162608)
			(xy 217.399744 -90.152478) (xy 217.455478 -90.150441) (xy 217.510915 -90.156541) (xy 217.564872 -90.170647)
			(xy 217.616201 -90.192459) (xy 217.663807 -90.221513) (xy 217.706675 -90.257188) (xy 217.743892 -90.298725)
			(xy 217.774665 -90.345238) (xy 217.798337 -90.395735) (xy 217.814405 -90.449142) (xy 217.822525 -90.504318)
			(xy 217.823034 -90.532204) (xy 217.822525 -90.56009) (xy 217.814405 -90.615266) (xy 217.798337 -90.668673)
			(xy 217.774665 -90.71917) (xy 217.755522 -90.748104) (xy 224.04019 -90.748104) (xy 224.044261 -90.692482)
			(xy 224.056387 -90.638045) (xy 224.07631 -90.585954) (xy 224.103606 -90.537319) (xy 224.137692 -90.493176)
			(xy 224.177841 -90.454467) (xy 224.223199 -90.422016) (xy 224.272799 -90.396515) (xy 224.325583 -90.378508)
			(xy 224.380426 -90.368378) (xy 224.43616 -90.366341) (xy 224.491597 -90.372441) (xy 224.545554 -90.386547)
			(xy 224.596883 -90.408359) (xy 224.644489 -90.437413) (xy 224.687357 -90.473088) (xy 224.724574 -90.514625)
			(xy 224.755347 -90.561138) (xy 224.779019 -90.611635) (xy 224.795087 -90.665042) (xy 224.803207 -90.720218)
			(xy 224.803716 -90.748104) (xy 224.803271 -90.772488) (xy 225.37623 -90.772488) (xy 225.380301 -90.716866)
			(xy 225.392427 -90.662429) (xy 225.41235 -90.610338) (xy 225.439646 -90.561703) (xy 225.473732 -90.51756)
			(xy 225.513881 -90.478851) (xy 225.559239 -90.4464) (xy 225.608839 -90.420899) (xy 225.661623 -90.402892)
			(xy 225.716466 -90.392762) (xy 225.7722 -90.390725) (xy 225.827637 -90.396825) (xy 225.881594 -90.410931)
			(xy 225.932923 -90.432743) (xy 225.980529 -90.461797) (xy 226.023397 -90.497472) (xy 226.060614 -90.539009)
			(xy 226.091387 -90.585522) (xy 226.115059 -90.636019) (xy 226.131127 -90.689426) (xy 226.139247 -90.744602)
			(xy 226.139756 -90.772488) (xy 226.139247 -90.800374) (xy 226.131127 -90.85555) (xy 226.115059 -90.908957)
			(xy 226.091387 -90.959454) (xy 226.060614 -91.005967) (xy 226.04291 -91.025726) (xy 227.35235 -91.025726)
			(xy 227.356421 -90.970104) (xy 227.368547 -90.915667) (xy 227.38847 -90.863576) (xy 227.415766 -90.814941)
			(xy 227.449852 -90.770798) (xy 227.490001 -90.732089) (xy 227.535359 -90.699638) (xy 227.584959 -90.674137)
			(xy 227.637743 -90.65613) (xy 227.692586 -90.646) (xy 227.74832 -90.643963) (xy 227.803757 -90.650063)
			(xy 227.857714 -90.664169) (xy 227.909043 -90.685981) (xy 227.956649 -90.715035) (xy 227.999517 -90.75071)
			(xy 228.036734 -90.792247) (xy 228.067507 -90.83876) (xy 228.091179 -90.889257) (xy 228.107247 -90.942664)
			(xy 228.115367 -90.99784) (xy 228.115876 -91.025726) (xy 228.115367 -91.053612) (xy 228.107247 -91.108788)
			(xy 228.091179 -91.162195) (xy 228.067507 -91.212692) (xy 228.036734 -91.259205) (xy 227.999517 -91.300742)
			(xy 227.956649 -91.336417) (xy 227.909043 -91.365471) (xy 227.857714 -91.387283) (xy 227.803757 -91.401389)
			(xy 227.74832 -91.407489) (xy 227.692586 -91.405452) (xy 227.637743 -91.395322) (xy 227.584959 -91.377315)
			(xy 227.535359 -91.351814) (xy 227.490001 -91.319363) (xy 227.449852 -91.280654) (xy 227.415766 -91.236511)
			(xy 227.38847 -91.187876) (xy 227.368547 -91.135785) (xy 227.356421 -91.081348) (xy 227.35235 -91.025726)
			(xy 226.04291 -91.025726) (xy 226.023397 -91.047504) (xy 225.980529 -91.083179) (xy 225.932923 -91.112233)
			(xy 225.881594 -91.134045) (xy 225.827637 -91.148151) (xy 225.7722 -91.154251) (xy 225.716466 -91.152214)
			(xy 225.661623 -91.142084) (xy 225.608839 -91.124077) (xy 225.559239 -91.098576) (xy 225.513881 -91.066125)
			(xy 225.473732 -91.027416) (xy 225.439646 -90.983273) (xy 225.41235 -90.934638) (xy 225.392427 -90.882547)
			(xy 225.380301 -90.82811) (xy 225.37623 -90.772488) (xy 224.803271 -90.772488) (xy 224.803207 -90.77599)
			(xy 224.795087 -90.831166) (xy 224.779019 -90.884573) (xy 224.755347 -90.93507) (xy 224.724574 -90.981583)
			(xy 224.687357 -91.02312) (xy 224.644489 -91.058795) (xy 224.596883 -91.087849) (xy 224.545554 -91.109661)
			(xy 224.491597 -91.123767) (xy 224.43616 -91.129867) (xy 224.380426 -91.12783) (xy 224.325583 -91.1177)
			(xy 224.272799 -91.099693) (xy 224.223199 -91.074192) (xy 224.177841 -91.041741) (xy 224.137692 -91.003032)
			(xy 224.103606 -90.958889) (xy 224.07631 -90.910254) (xy 224.056387 -90.858163) (xy 224.044261 -90.803726)
			(xy 224.04019 -90.748104) (xy 217.755522 -90.748104) (xy 217.743892 -90.765683) (xy 217.706675 -90.80722)
			(xy 217.663807 -90.842895) (xy 217.616201 -90.871949) (xy 217.564872 -90.893761) (xy 217.510915 -90.907867)
			(xy 217.455478 -90.913967) (xy 217.399744 -90.91193) (xy 217.344901 -90.9018) (xy 217.292117 -90.883793)
			(xy 217.242517 -90.858292) (xy 217.197159 -90.825841) (xy 217.15701 -90.787132) (xy 217.122924 -90.742989)
			(xy 217.095628 -90.694354) (xy 217.075705 -90.642263) (xy 217.063579 -90.587826) (xy 217.059508 -90.532204)
			(xy 216.926938 -90.532204) (xy 216.933525 -90.576962) (xy 216.934034 -90.604848) (xy 216.933525 -90.632734)
			(xy 216.925405 -90.68791) (xy 216.909337 -90.741317) (xy 216.885665 -90.791814) (xy 216.854892 -90.838327)
			(xy 216.817675 -90.879864) (xy 216.774807 -90.915539) (xy 216.727201 -90.944593) (xy 216.675872 -90.966405)
			(xy 216.621915 -90.980511) (xy 216.566478 -90.986611) (xy 216.510744 -90.984574) (xy 216.455901 -90.974444)
			(xy 216.403117 -90.956437) (xy 216.353517 -90.930936) (xy 216.308159 -90.898485) (xy 216.26801 -90.859776)
			(xy 216.233924 -90.815633) (xy 216.206628 -90.766998) (xy 216.186705 -90.714907) (xy 216.174579 -90.66047)
			(xy 216.170508 -90.604848) (xy 215.096977 -90.604848) (xy 215.073629 -90.654654) (xy 215.042856 -90.701167)
			(xy 215.005639 -90.742704) (xy 214.962771 -90.778379) (xy 214.915165 -90.807433) (xy 214.863836 -90.829245)
			(xy 214.809879 -90.843351) (xy 214.754442 -90.849451) (xy 214.698708 -90.847414) (xy 214.643865 -90.837284)
			(xy 214.591081 -90.819277) (xy 214.541481 -90.793776) (xy 214.496123 -90.761325) (xy 214.455974 -90.722616)
			(xy 214.421888 -90.678473) (xy 214.394592 -90.629838) (xy 214.374669 -90.577747) (xy 214.362543 -90.52331)
			(xy 214.358472 -90.467688) (xy 207.934643 -90.467688) (xy 207.266873 -91.655646) (xy 215.233248 -91.655646)
			(xy 215.237319 -91.600024) (xy 215.249445 -91.545587) (xy 215.269368 -91.493496) (xy 215.296664 -91.444861)
			(xy 215.33075 -91.400718) (xy 215.370899 -91.362009) (xy 215.416257 -91.329558) (xy 215.465857 -91.304057)
			(xy 215.518641 -91.28605) (xy 215.573484 -91.27592) (xy 215.629218 -91.273883) (xy 215.684655 -91.279983)
			(xy 215.738612 -91.294089) (xy 215.789941 -91.315901) (xy 215.837547 -91.344955) (xy 215.880415 -91.38063)
			(xy 215.917632 -91.422167) (xy 215.923045 -91.430348) (xy 221.146114 -91.430348) (xy 221.150185 -91.374726)
			(xy 221.162311 -91.320289) (xy 221.182234 -91.268198) (xy 221.20953 -91.219563) (xy 221.243616 -91.17542)
			(xy 221.283765 -91.136711) (xy 221.329123 -91.10426) (xy 221.378723 -91.078759) (xy 221.431507 -91.060752)
			(xy 221.48635 -91.050622) (xy 221.542084 -91.048585) (xy 221.597521 -91.054685) (xy 221.651478 -91.068791)
			(xy 221.702807 -91.090603) (xy 221.750413 -91.119657) (xy 221.793281 -91.155332) (xy 221.830498 -91.196869)
			(xy 221.861271 -91.243382) (xy 221.884943 -91.293879) (xy 221.901011 -91.347286) (xy 221.909131 -91.402462)
			(xy 221.90964 -91.430348) (xy 221.909131 -91.458234) (xy 221.901011 -91.51341) (xy 221.884943 -91.566817)
			(xy 221.861271 -91.617314) (xy 221.830498 -91.663827) (xy 221.793281 -91.705364) (xy 221.750413 -91.741039)
			(xy 221.702807 -91.770093) (xy 221.651478 -91.791905) (xy 221.597521 -91.806011) (xy 221.542084 -91.812111)
			(xy 221.48635 -91.810074) (xy 221.431507 -91.799944) (xy 221.378723 -91.781937) (xy 221.329123 -91.756436)
			(xy 221.283765 -91.723985) (xy 221.243616 -91.685276) (xy 221.20953 -91.641133) (xy 221.182234 -91.592498)
			(xy 221.162311 -91.540407) (xy 221.150185 -91.48597) (xy 221.146114 -91.430348) (xy 215.923045 -91.430348)
			(xy 215.948405 -91.46868) (xy 215.972077 -91.519177) (xy 215.988145 -91.572584) (xy 215.996265 -91.62776)
			(xy 215.996774 -91.655646) (xy 215.996265 -91.683532) (xy 215.988145 -91.738708) (xy 215.972077 -91.792115)
			(xy 215.948405 -91.842612) (xy 215.917632 -91.889125) (xy 215.880415 -91.930662) (xy 215.837547 -91.966337)
			(xy 215.801835 -91.988132) (xy 229.487982 -91.988132) (xy 229.492053 -91.93251) (xy 229.504179 -91.878073)
			(xy 229.524102 -91.825982) (xy 229.551398 -91.777347) (xy 229.585484 -91.733204) (xy 229.625633 -91.694495)
			(xy 229.670991 -91.662044) (xy 229.720591 -91.636543) (xy 229.773375 -91.618536) (xy 229.828218 -91.608406)
			(xy 229.883952 -91.606369) (xy 229.939389 -91.612469) (xy 229.993346 -91.626575) (xy 230.044675 -91.648387)
			(xy 230.047829 -91.650312) (xy 239.454434 -91.650312) (xy 239.458505 -91.59469) (xy 239.470631 -91.540253)
			(xy 239.490554 -91.488162) (xy 239.51785 -91.439527) (xy 239.551936 -91.395384) (xy 239.592085 -91.356675)
			(xy 239.637443 -91.324224) (xy 239.687043 -91.298723) (xy 239.739827 -91.280716) (xy 239.79467 -91.270586)
			(xy 239.850404 -91.268549) (xy 239.905841 -91.274649) (xy 239.959798 -91.288755) (xy 240.011127 -91.310567)
			(xy 240.058733 -91.339621) (xy 240.101601 -91.375296) (xy 240.138818 -91.416833) (xy 240.169591 -91.463346)
			(xy 240.193263 -91.513843) (xy 240.209331 -91.56725) (xy 240.217451 -91.622426) (xy 240.21796 -91.650312)
			(xy 240.217451 -91.678198) (xy 240.209331 -91.733374) (xy 240.193263 -91.786781) (xy 240.169591 -91.837278)
			(xy 240.138818 -91.883791) (xy 240.101601 -91.925328) (xy 240.058733 -91.961003) (xy 240.011127 -91.990057)
			(xy 239.959798 -92.011869) (xy 239.905841 -92.025975) (xy 239.850404 -92.032075) (xy 239.79467 -92.030038)
			(xy 239.739827 -92.019908) (xy 239.687043 -92.001901) (xy 239.637443 -91.9764) (xy 239.592085 -91.943949)
			(xy 239.551936 -91.90524) (xy 239.51785 -91.861097) (xy 239.490554 -91.812462) (xy 239.470631 -91.760371)
			(xy 239.458505 -91.705934) (xy 239.454434 -91.650312) (xy 230.047829 -91.650312) (xy 230.092281 -91.677441)
			(xy 230.135149 -91.713116) (xy 230.172366 -91.754653) (xy 230.203139 -91.801166) (xy 230.226811 -91.851663)
			(xy 230.242879 -91.90507) (xy 230.250999 -91.960246) (xy 230.251508 -91.988132) (xy 230.250999 -92.016018)
			(xy 230.242879 -92.071194) (xy 230.226811 -92.124601) (xy 230.203139 -92.175098) (xy 230.172366 -92.221611)
			(xy 230.135149 -92.263148) (xy 230.092281 -92.298823) (xy 230.044675 -92.327877) (xy 229.993346 -92.349689)
			(xy 229.939389 -92.363795) (xy 229.883952 -92.369895) (xy 229.828218 -92.367858) (xy 229.773375 -92.357728)
			(xy 229.720591 -92.339721) (xy 229.670991 -92.31422) (xy 229.625633 -92.281769) (xy 229.585484 -92.24306)
			(xy 229.551398 -92.198917) (xy 229.524102 -92.150282) (xy 229.504179 -92.098191) (xy 229.492053 -92.043754)
			(xy 229.487982 -91.988132) (xy 215.801835 -91.988132) (xy 215.789941 -91.995391) (xy 215.738612 -92.017203)
			(xy 215.684655 -92.031309) (xy 215.629218 -92.037409) (xy 215.573484 -92.035372) (xy 215.518641 -92.025242)
			(xy 215.465857 -92.007235) (xy 215.416257 -91.981734) (xy 215.370899 -91.949283) (xy 215.33075 -91.910574)
			(xy 215.296664 -91.866431) (xy 215.269368 -91.817796) (xy 215.249445 -91.765705) (xy 215.237319 -91.711268)
			(xy 215.233248 -91.655646) (xy 207.266873 -91.655646) (xy 206.699476 -92.665042) (xy 237.406432 -92.665042)
			(xy 237.410503 -92.60942) (xy 237.422629 -92.554983) (xy 237.442552 -92.502892) (xy 237.469848 -92.454257)
			(xy 237.503934 -92.410114) (xy 237.544083 -92.371405) (xy 237.589441 -92.338954) (xy 237.639041 -92.313453)
			(xy 237.691825 -92.295446) (xy 237.746668 -92.285316) (xy 237.802402 -92.283279) (xy 237.857839 -92.289379)
			(xy 237.911796 -92.303485) (xy 237.963125 -92.325297) (xy 238.010731 -92.354351) (xy 238.053599 -92.390026)
			(xy 238.090816 -92.431563) (xy 238.121589 -92.478076) (xy 238.145261 -92.528573) (xy 238.161329 -92.58198)
			(xy 238.169449 -92.637156) (xy 238.169958 -92.665042) (xy 238.169449 -92.692928) (xy 238.161329 -92.748104)
			(xy 238.145261 -92.801511) (xy 238.121589 -92.852008) (xy 238.090816 -92.898521) (xy 238.053599 -92.940058)
			(xy 238.010731 -92.975733) (xy 237.963125 -93.004787) (xy 237.911796 -93.026599) (xy 237.857839 -93.040705)
			(xy 237.802402 -93.046805) (xy 237.746668 -93.044768) (xy 237.691825 -93.034638) (xy 237.639041 -93.016631)
			(xy 237.589441 -92.99113) (xy 237.544083 -92.958679) (xy 237.503934 -92.91997) (xy 237.469848 -92.875827)
			(xy 237.442552 -92.827192) (xy 237.422629 -92.775101) (xy 237.410503 -92.720664) (xy 237.406432 -92.665042)
			(xy 206.699476 -92.665042) (xy 206.361379 -93.266514) (xy 229.782876 -93.266514) (xy 229.786947 -93.210892)
			(xy 229.799073 -93.156455) (xy 229.818996 -93.104364) (xy 229.846292 -93.055729) (xy 229.880378 -93.011586)
			(xy 229.920527 -92.972877) (xy 229.965885 -92.940426) (xy 230.015485 -92.914925) (xy 230.068269 -92.896918)
			(xy 230.123112 -92.886788) (xy 230.178846 -92.884751) (xy 230.234283 -92.890851) (xy 230.28824 -92.904957)
			(xy 230.339569 -92.926769) (xy 230.387175 -92.955823) (xy 230.430043 -92.991498) (xy 230.46726 -93.033035)
			(xy 230.498033 -93.079548) (xy 230.510427 -93.105986) (xy 248.549412 -93.105986) (xy 248.553483 -93.050364)
			(xy 248.565609 -92.995927) (xy 248.585532 -92.943836) (xy 248.612828 -92.895201) (xy 248.646914 -92.851058)
			(xy 248.687063 -92.812349) (xy 248.732421 -92.779898) (xy 248.782021 -92.754397) (xy 248.834805 -92.73639)
			(xy 248.889648 -92.72626) (xy 248.945382 -92.724223) (xy 249.000819 -92.730323) (xy 249.054776 -92.744429)
			(xy 249.106105 -92.766241) (xy 249.153711 -92.795295) (xy 249.196579 -92.83097) (xy 249.233796 -92.872507)
			(xy 249.264569 -92.91902) (xy 249.288241 -92.969517) (xy 249.304309 -93.022924) (xy 249.312429 -93.0781)
			(xy 249.312938 -93.105986) (xy 249.312429 -93.133872) (xy 249.304309 -93.189048) (xy 249.288241 -93.242455)
			(xy 249.264569 -93.292952) (xy 249.233796 -93.339465) (xy 249.196579 -93.381002) (xy 249.153711 -93.416677)
			(xy 249.106105 -93.445731) (xy 249.054776 -93.467543) (xy 249.000819 -93.481649) (xy 248.945382 -93.487749)
			(xy 248.889648 -93.485712) (xy 248.834805 -93.475582) (xy 248.782021 -93.457575) (xy 248.732421 -93.432074)
			(xy 248.687063 -93.399623) (xy 248.646914 -93.360914) (xy 248.612828 -93.316771) (xy 248.585532 -93.268136)
			(xy 248.565609 -93.216045) (xy 248.553483 -93.161608) (xy 248.549412 -93.105986) (xy 230.510427 -93.105986)
			(xy 230.521705 -93.130045) (xy 230.537773 -93.183452) (xy 230.545893 -93.238628) (xy 230.546402 -93.266514)
			(xy 230.545893 -93.2944) (xy 230.537773 -93.349576) (xy 230.521705 -93.402983) (xy 230.498033 -93.45348)
			(xy 230.46726 -93.499993) (xy 230.430043 -93.54153) (xy 230.387175 -93.577205) (xy 230.339569 -93.606259)
			(xy 230.28824 -93.628071) (xy 230.234283 -93.642177) (xy 230.178846 -93.648277) (xy 230.123112 -93.64624)
			(xy 230.068269 -93.63611) (xy 230.015485 -93.618103) (xy 229.965885 -93.592602) (xy 229.920527 -93.560151)
			(xy 229.880378 -93.521442) (xy 229.846292 -93.477299) (xy 229.818996 -93.428664) (xy 229.799073 -93.376573)
			(xy 229.786947 -93.322136) (xy 229.782876 -93.266514) (xy 206.361379 -93.266514) (xy 206.080251 -93.76664)
			(xy 236.86592 -93.76664) (xy 236.869991 -93.711018) (xy 236.882117 -93.656581) (xy 236.90204 -93.60449)
			(xy 236.929336 -93.555855) (xy 236.963422 -93.511712) (xy 237.003571 -93.473003) (xy 237.048929 -93.440552)
			(xy 237.098529 -93.415051) (xy 237.151313 -93.397044) (xy 237.206156 -93.386914) (xy 237.26189 -93.384877)
			(xy 237.317327 -93.390977) (xy 237.371284 -93.405083) (xy 237.422613 -93.426895) (xy 237.470219 -93.455949)
			(xy 237.513087 -93.491624) (xy 237.550304 -93.533161) (xy 237.581077 -93.579674) (xy 237.604749 -93.630171)
			(xy 237.620817 -93.683578) (xy 237.628937 -93.738754) (xy 237.629446 -93.76664) (xy 237.628937 -93.794526)
			(xy 237.620817 -93.849702) (xy 237.604749 -93.903109) (xy 237.581077 -93.953606) (xy 237.550304 -94.000119)
			(xy 237.513087 -94.041656) (xy 237.470219 -94.077331) (xy 237.43534 -94.098618) (xy 250.156724 -94.098618)
			(xy 250.160795 -94.042996) (xy 250.172921 -93.988559) (xy 250.192844 -93.936468) (xy 250.22014 -93.887833)
			(xy 250.254226 -93.84369) (xy 250.294375 -93.804981) (xy 250.339733 -93.77253) (xy 250.389333 -93.747029)
			(xy 250.442117 -93.729022) (xy 250.49696 -93.718892) (xy 250.552694 -93.716855) (xy 250.608131 -93.722955)
			(xy 250.662088 -93.737061) (xy 250.713417 -93.758873) (xy 250.761023 -93.787927) (xy 250.803891 -93.823602)
			(xy 250.841108 -93.865139) (xy 250.871881 -93.911652) (xy 250.895553 -93.962149) (xy 250.911621 -94.015556)
			(xy 250.919741 -94.070732) (xy 250.92025 -94.098618) (xy 250.919741 -94.126504) (xy 250.911621 -94.18168)
			(xy 250.895553 -94.235087) (xy 250.871881 -94.285584) (xy 250.841108 -94.332097) (xy 250.803891 -94.373634)
			(xy 250.761023 -94.409309) (xy 250.713417 -94.438363) (xy 250.662088 -94.460175) (xy 250.608131 -94.474281)
			(xy 250.552694 -94.480381) (xy 250.49696 -94.478344) (xy 250.442117 -94.468214) (xy 250.389333 -94.450207)
			(xy 250.339733 -94.424706) (xy 250.294375 -94.392255) (xy 250.254226 -94.353546) (xy 250.22014 -94.309403)
			(xy 250.192844 -94.260768) (xy 250.172921 -94.208677) (xy 250.160795 -94.15424) (xy 250.156724 -94.098618)
			(xy 237.43534 -94.098618) (xy 237.422613 -94.106385) (xy 237.371284 -94.128197) (xy 237.317327 -94.142303)
			(xy 237.26189 -94.148403) (xy 237.206156 -94.146366) (xy 237.151313 -94.136236) (xy 237.098529 -94.118229)
			(xy 237.048929 -94.092728) (xy 237.003571 -94.060277) (xy 236.963422 -94.021568) (xy 236.929336 -93.977425)
			(xy 236.90204 -93.92879) (xy 236.882117 -93.876699) (xy 236.869991 -93.822262) (xy 236.86592 -93.76664)
			(xy 206.080251 -93.76664) (xy 205.31782 -95.123) (xy 216.555826 -95.123) (xy 216.559897 -95.067378)
			(xy 216.572023 -95.012941) (xy 216.591946 -94.96085) (xy 216.619242 -94.912215) (xy 216.653328 -94.868072)
			(xy 216.693477 -94.829363) (xy 216.738835 -94.796912) (xy 216.788435 -94.771411) (xy 216.841219 -94.753404)
			(xy 216.896062 -94.743274) (xy 216.951796 -94.741237) (xy 217.007233 -94.747337) (xy 217.06119 -94.761443)
			(xy 217.112519 -94.783255) (xy 217.160125 -94.812309) (xy 217.202993 -94.847984) (xy 217.24021 -94.889521)
			(xy 217.270983 -94.936034) (xy 217.294655 -94.986531) (xy 217.310723 -95.039938) (xy 217.318843 -95.095114)
			(xy 217.319352 -95.123) (xy 217.698826 -95.123) (xy 217.702897 -95.067378) (xy 217.715023 -95.012941)
			(xy 217.734946 -94.96085) (xy 217.762242 -94.912215) (xy 217.796328 -94.868072) (xy 217.836477 -94.829363)
			(xy 217.881835 -94.796912) (xy 217.931435 -94.771411) (xy 217.984219 -94.753404) (xy 218.039062 -94.743274)
			(xy 218.094796 -94.741237) (xy 218.150233 -94.747337) (xy 218.20419 -94.761443) (xy 218.255519 -94.783255)
			(xy 218.303125 -94.812309) (xy 218.345993 -94.847984) (xy 218.38321 -94.889521) (xy 218.413983 -94.936034)
			(xy 218.437655 -94.986531) (xy 218.453723 -95.039938) (xy 218.461843 -95.095114) (xy 218.462352 -95.123)
			(xy 218.841826 -95.123) (xy 218.845897 -95.067378) (xy 218.858023 -95.012941) (xy 218.877946 -94.96085)
			(xy 218.905242 -94.912215) (xy 218.939328 -94.868072) (xy 218.979477 -94.829363) (xy 219.024835 -94.796912)
			(xy 219.074435 -94.771411) (xy 219.127219 -94.753404) (xy 219.182062 -94.743274) (xy 219.237796 -94.741237)
			(xy 219.293233 -94.747337) (xy 219.34719 -94.761443) (xy 219.398519 -94.783255) (xy 219.446125 -94.812309)
			(xy 219.488993 -94.847984) (xy 219.52621 -94.889521) (xy 219.554645 -94.9325) (xy 220.111826 -94.9325)
			(xy 220.115897 -94.876878) (xy 220.128023 -94.822441) (xy 220.147946 -94.77035) (xy 220.175242 -94.721715)
			(xy 220.209328 -94.677572) (xy 220.249477 -94.638863) (xy 220.294835 -94.606412) (xy 220.344435 -94.580911)
			(xy 220.397219 -94.562904) (xy 220.452062 -94.552774) (xy 220.507796 -94.550737) (xy 220.563233 -94.556837)
			(xy 220.61719 -94.570943) (xy 220.668519 -94.592755) (xy 220.714957 -94.621096) (xy 229.829358 -94.621096)
			(xy 229.833429 -94.565474) (xy 229.845555 -94.511037) (xy 229.865478 -94.458946) (xy 229.892774 -94.410311)
			(xy 229.92686 -94.366168) (xy 229.967009 -94.327459) (xy 230.012367 -94.295008) (xy 230.061967 -94.269507)
			(xy 230.114751 -94.2515) (xy 230.169594 -94.24137) (xy 230.225328 -94.239333) (xy 230.280765 -94.245433)
			(xy 230.334722 -94.259539) (xy 230.386051 -94.281351) (xy 230.433657 -94.310405) (xy 230.476525 -94.34608)
			(xy 230.513742 -94.387617) (xy 230.544515 -94.43413) (xy 230.568187 -94.484627) (xy 230.584255 -94.538034)
			(xy 230.592375 -94.59321) (xy 230.592884 -94.621096) (xy 230.592375 -94.648982) (xy 230.587956 -94.679008)
			(xy 231.593134 -94.679008) (xy 231.597205 -94.623386) (xy 231.609331 -94.568949) (xy 231.629254 -94.516858)
			(xy 231.65655 -94.468223) (xy 231.690636 -94.42408) (xy 231.730785 -94.385371) (xy 231.776143 -94.35292)
			(xy 231.825743 -94.327419) (xy 231.878527 -94.309412) (xy 231.93337 -94.299282) (xy 231.989104 -94.297245)
			(xy 232.044541 -94.303345) (xy 232.098498 -94.317451) (xy 232.149827 -94.339263) (xy 232.197433 -94.368317)
			(xy 232.240301 -94.403992) (xy 232.277518 -94.445529) (xy 232.308291 -94.492042) (xy 232.331963 -94.542539)
			(xy 232.348031 -94.595946) (xy 232.354573 -94.6404) (xy 235.823504 -94.6404) (xy 235.827575 -94.584778)
			(xy 235.839701 -94.530341) (xy 235.859624 -94.47825) (xy 235.88692 -94.429615) (xy 235.921006 -94.385472)
			(xy 235.961155 -94.346763) (xy 236.006513 -94.314312) (xy 236.056113 -94.288811) (xy 236.108897 -94.270804)
			(xy 236.16374 -94.260674) (xy 236.219474 -94.258637) (xy 236.274911 -94.264737) (xy 236.328868 -94.278843)
			(xy 236.380197 -94.300655) (xy 236.427803 -94.329709) (xy 236.470671 -94.365384) (xy 236.507888 -94.406921)
			(xy 236.538661 -94.453434) (xy 236.562333 -94.503931) (xy 236.578401 -94.557338) (xy 236.586521 -94.612514)
			(xy 236.58703 -94.6404) (xy 236.586521 -94.668286) (xy 236.578401 -94.723462) (xy 236.562333 -94.776869)
			(xy 236.538661 -94.827366) (xy 236.507888 -94.873879) (xy 236.470671 -94.915416) (xy 236.427803 -94.951091)
			(xy 236.380197 -94.980145) (xy 236.328868 -95.001957) (xy 236.274911 -95.016063) (xy 236.219474 -95.022163)
			(xy 236.16374 -95.020126) (xy 236.108897 -95.009996) (xy 236.056113 -94.991989) (xy 236.006513 -94.966488)
			(xy 235.961155 -94.934037) (xy 235.921006 -94.895328) (xy 235.88692 -94.851185) (xy 235.859624 -94.80255)
			(xy 235.839701 -94.750459) (xy 235.827575 -94.696022) (xy 235.823504 -94.6404) (xy 232.354573 -94.6404)
			(xy 232.356151 -94.651122) (xy 232.35666 -94.679008) (xy 232.356151 -94.706894) (xy 232.348031 -94.76207)
			(xy 232.331963 -94.815477) (xy 232.308291 -94.865974) (xy 232.277518 -94.912487) (xy 232.240301 -94.954024)
			(xy 232.197433 -94.989699) (xy 232.149827 -95.018753) (xy 232.098498 -95.040565) (xy 232.044541 -95.054671)
			(xy 231.989104 -95.060771) (xy 231.93337 -95.058734) (xy 231.878527 -95.048604) (xy 231.825743 -95.030597)
			(xy 231.776143 -95.005096) (xy 231.730785 -94.972645) (xy 231.690636 -94.933936) (xy 231.65655 -94.889793)
			(xy 231.629254 -94.841158) (xy 231.609331 -94.789067) (xy 231.597205 -94.73463) (xy 231.593134 -94.679008)
			(xy 230.587956 -94.679008) (xy 230.584255 -94.704158) (xy 230.568187 -94.757565) (xy 230.544515 -94.808062)
			(xy 230.513742 -94.854575) (xy 230.476525 -94.896112) (xy 230.433657 -94.931787) (xy 230.386051 -94.960841)
			(xy 230.334722 -94.982653) (xy 230.280765 -94.996759) (xy 230.225328 -95.002859) (xy 230.169594 -95.000822)
			(xy 230.114751 -94.990692) (xy 230.061967 -94.972685) (xy 230.012367 -94.947184) (xy 229.967009 -94.914733)
			(xy 229.92686 -94.876024) (xy 229.892774 -94.831881) (xy 229.865478 -94.783246) (xy 229.845555 -94.731155)
			(xy 229.833429 -94.676718) (xy 229.829358 -94.621096) (xy 220.714957 -94.621096) (xy 220.716125 -94.621809)
			(xy 220.758993 -94.657484) (xy 220.79621 -94.699021) (xy 220.826983 -94.745534) (xy 220.850655 -94.796031)
			(xy 220.866723 -94.849438) (xy 220.874843 -94.904614) (xy 220.875352 -94.9325) (xy 220.874843 -94.960386)
			(xy 220.866723 -95.015562) (xy 220.850655 -95.068969) (xy 220.840925 -95.089726) (xy 227.35235 -95.089726)
			(xy 227.356421 -95.034104) (xy 227.368547 -94.979667) (xy 227.38847 -94.927576) (xy 227.415766 -94.878941)
			(xy 227.449852 -94.834798) (xy 227.490001 -94.796089) (xy 227.535359 -94.763638) (xy 227.584959 -94.738137)
			(xy 227.637743 -94.72013) (xy 227.692586 -94.71) (xy 227.74832 -94.707963) (xy 227.803757 -94.714063)
			(xy 227.857714 -94.728169) (xy 227.909043 -94.749981) (xy 227.956649 -94.779035) (xy 227.999517 -94.81471)
			(xy 228.036734 -94.856247) (xy 228.067507 -94.90276) (xy 228.091179 -94.953257) (xy 228.107247 -95.006664)
			(xy 228.115367 -95.06184) (xy 228.115876 -95.089726) (xy 228.115367 -95.117612) (xy 228.107247 -95.172788)
			(xy 228.091179 -95.226195) (xy 228.067507 -95.276692) (xy 228.036734 -95.323205) (xy 227.999517 -95.364742)
			(xy 227.956649 -95.400417) (xy 227.909043 -95.429471) (xy 227.857714 -95.451283) (xy 227.803757 -95.465389)
			(xy 227.74832 -95.471489) (xy 227.692586 -95.469452) (xy 227.637743 -95.459322) (xy 227.584959 -95.441315)
			(xy 227.535359 -95.415814) (xy 227.490001 -95.383363) (xy 227.449852 -95.344654) (xy 227.415766 -95.300511)
			(xy 227.38847 -95.251876) (xy 227.368547 -95.199785) (xy 227.356421 -95.145348) (xy 227.35235 -95.089726)
			(xy 220.840925 -95.089726) (xy 220.826983 -95.119466) (xy 220.79621 -95.165979) (xy 220.758993 -95.207516)
			(xy 220.716125 -95.243191) (xy 220.668519 -95.272245) (xy 220.61719 -95.294057) (xy 220.563233 -95.308163)
			(xy 220.507796 -95.314263) (xy 220.452062 -95.312226) (xy 220.397219 -95.302096) (xy 220.344435 -95.284089)
			(xy 220.294835 -95.258588) (xy 220.249477 -95.226137) (xy 220.209328 -95.187428) (xy 220.175242 -95.143285)
			(xy 220.147946 -95.09465) (xy 220.128023 -95.042559) (xy 220.115897 -94.988122) (xy 220.111826 -94.9325)
			(xy 219.554645 -94.9325) (xy 219.556983 -94.936034) (xy 219.580655 -94.986531) (xy 219.596723 -95.039938)
			(xy 219.604843 -95.095114) (xy 219.605352 -95.123) (xy 219.604843 -95.150886) (xy 219.596723 -95.206062)
			(xy 219.580655 -95.259469) (xy 219.556983 -95.309966) (xy 219.52621 -95.356479) (xy 219.488993 -95.398016)
			(xy 219.446125 -95.433691) (xy 219.398519 -95.462745) (xy 219.34719 -95.484557) (xy 219.293233 -95.498663)
			(xy 219.237796 -95.504763) (xy 219.182062 -95.502726) (xy 219.127219 -95.492596) (xy 219.074435 -95.474589)
			(xy 219.024835 -95.449088) (xy 218.979477 -95.416637) (xy 218.939328 -95.377928) (xy 218.905242 -95.333785)
			(xy 218.877946 -95.28515) (xy 218.858023 -95.233059) (xy 218.845897 -95.178622) (xy 218.841826 -95.123)
			(xy 218.462352 -95.123) (xy 218.461843 -95.150886) (xy 218.453723 -95.206062) (xy 218.437655 -95.259469)
			(xy 218.413983 -95.309966) (xy 218.38321 -95.356479) (xy 218.345993 -95.398016) (xy 218.303125 -95.433691)
			(xy 218.255519 -95.462745) (xy 218.20419 -95.484557) (xy 218.150233 -95.498663) (xy 218.094796 -95.504763)
			(xy 218.039062 -95.502726) (xy 217.984219 -95.492596) (xy 217.931435 -95.474589) (xy 217.881835 -95.449088)
			(xy 217.836477 -95.416637) (xy 217.796328 -95.377928) (xy 217.762242 -95.333785) (xy 217.734946 -95.28515)
			(xy 217.715023 -95.233059) (xy 217.702897 -95.178622) (xy 217.698826 -95.123) (xy 217.319352 -95.123)
			(xy 217.318843 -95.150886) (xy 217.310723 -95.206062) (xy 217.294655 -95.259469) (xy 217.270983 -95.309966)
			(xy 217.24021 -95.356479) (xy 217.202993 -95.398016) (xy 217.160125 -95.433691) (xy 217.112519 -95.462745)
			(xy 217.06119 -95.484557) (xy 217.007233 -95.498663) (xy 216.951796 -95.504763) (xy 216.896062 -95.502726)
			(xy 216.841219 -95.492596) (xy 216.788435 -95.474589) (xy 216.738835 -95.449088) (xy 216.693477 -95.416637)
			(xy 216.653328 -95.377928) (xy 216.619242 -95.333785) (xy 216.591946 -95.28515) (xy 216.572023 -95.233059)
			(xy 216.559897 -95.178622) (xy 216.555826 -95.123) (xy 205.31782 -95.123) (xy 205.091661 -95.525336)
			(xy 230.922066 -95.525336) (xy 230.926137 -95.469714) (xy 230.938263 -95.415277) (xy 230.958186 -95.363186)
			(xy 230.985482 -95.314551) (xy 231.019568 -95.270408) (xy 231.059717 -95.231699) (xy 231.105075 -95.199248)
			(xy 231.154675 -95.173747) (xy 231.207459 -95.15574) (xy 231.262302 -95.14561) (xy 231.318036 -95.143573)
			(xy 231.373473 -95.149673) (xy 231.42743 -95.163779) (xy 231.478759 -95.185591) (xy 231.526365 -95.214645)
			(xy 231.569233 -95.25032) (xy 231.60645 -95.291857) (xy 231.637223 -95.33837) (xy 231.660895 -95.388867)
			(xy 231.676963 -95.442274) (xy 231.685083 -95.49745) (xy 231.685592 -95.525336) (xy 231.685083 -95.553222)
			(xy 231.676963 -95.608398) (xy 231.660895 -95.661805) (xy 231.637223 -95.712302) (xy 231.60645 -95.758815)
			(xy 231.569233 -95.800352) (xy 231.526365 -95.836027) (xy 231.478759 -95.865081) (xy 231.42743 -95.886893)
			(xy 231.373473 -95.900999) (xy 231.318036 -95.907099) (xy 231.262302 -95.905062) (xy 231.207459 -95.894932)
			(xy 231.154675 -95.876925) (xy 231.105075 -95.851424) (xy 231.059717 -95.818973) (xy 231.019568 -95.780264)
			(xy 230.985482 -95.736121) (xy 230.958186 -95.687486) (xy 230.938263 -95.635395) (xy 230.926137 -95.580958)
			(xy 230.922066 -95.525336) (xy 205.091661 -95.525336) (xy 204.854079 -95.947992) (xy 232.365802 -95.947992)
			(xy 232.369873 -95.89237) (xy 232.381999 -95.837933) (xy 232.401922 -95.785842) (xy 232.429218 -95.737207)
			(xy 232.463304 -95.693064) (xy 232.503453 -95.654355) (xy 232.548811 -95.621904) (xy 232.598411 -95.596403)
			(xy 232.651195 -95.578396) (xy 232.706038 -95.568266) (xy 232.761772 -95.566229) (xy 232.817209 -95.572329)
			(xy 232.871166 -95.586435) (xy 232.922495 -95.608247) (xy 232.970101 -95.637301) (xy 233.012969 -95.672976)
			(xy 233.050186 -95.714513) (xy 233.060136 -95.729552) (xy 233.639104 -95.729552) (xy 233.643175 -95.67393)
			(xy 233.655301 -95.619493) (xy 233.675224 -95.567402) (xy 233.70252 -95.518767) (xy 233.736606 -95.474624)
			(xy 233.776755 -95.435915) (xy 233.822113 -95.403464) (xy 233.871713 -95.377963) (xy 233.924497 -95.359956)
			(xy 233.97934 -95.349826) (xy 234.035074 -95.347789) (xy 234.090511 -95.353889) (xy 234.144468 -95.367995)
			(xy 234.195797 -95.389807) (xy 234.243403 -95.418861) (xy 234.286271 -95.454536) (xy 234.323488 -95.496073)
			(xy 234.354261 -95.542586) (xy 234.377933 -95.593083) (xy 234.394001 -95.64649) (xy 234.402121 -95.701666)
			(xy 234.402319 -95.712534) (xy 235.82452 -95.712534) (xy 235.828591 -95.656912) (xy 235.840717 -95.602475)
			(xy 235.86064 -95.550384) (xy 235.887936 -95.501749) (xy 235.922022 -95.457606) (xy 235.962171 -95.418897)
			(xy 236.007529 -95.386446) (xy 236.057129 -95.360945) (xy 236.109913 -95.342938) (xy 236.164756 -95.332808)
			(xy 236.22049 -95.330771) (xy 236.275927 -95.336871) (xy 236.329884 -95.350977) (xy 236.381213 -95.372789)
			(xy 236.428819 -95.401843) (xy 236.471687 -95.437518) (xy 236.508904 -95.479055) (xy 236.539677 -95.525568)
			(xy 236.563349 -95.576065) (xy 236.579417 -95.629472) (xy 236.587537 -95.684648) (xy 236.588046 -95.712534)
			(xy 236.587537 -95.74042) (xy 236.579417 -95.795596) (xy 236.563349 -95.849003) (xy 236.539677 -95.8995)
			(xy 236.508904 -95.946013) (xy 236.471687 -95.98755) (xy 236.428819 -96.023225) (xy 236.381213 -96.052279)
			(xy 236.329884 -96.074091) (xy 236.275927 -96.088197) (xy 236.22049 -96.094297) (xy 236.164756 -96.09226)
			(xy 236.109913 -96.08213) (xy 236.057129 -96.064123) (xy 236.007529 -96.038622) (xy 235.962171 -96.006171)
			(xy 235.922022 -95.967462) (xy 235.887936 -95.923319) (xy 235.86064 -95.874684) (xy 235.840717 -95.822593)
			(xy 235.828591 -95.768156) (xy 235.82452 -95.712534) (xy 234.402319 -95.712534) (xy 234.40263 -95.729552)
			(xy 234.402121 -95.757438) (xy 234.394001 -95.812614) (xy 234.377933 -95.866021) (xy 234.354261 -95.916518)
			(xy 234.323488 -95.963031) (xy 234.286271 -96.004568) (xy 234.243403 -96.040243) (xy 234.195797 -96.069297)
			(xy 234.144468 -96.091109) (xy 234.090511 -96.105215) (xy 234.035074 -96.111315) (xy 233.97934 -96.109278)
			(xy 233.924497 -96.099148) (xy 233.871713 -96.081141) (xy 233.822113 -96.05564) (xy 233.776755 -96.023189)
			(xy 233.736606 -95.98448) (xy 233.70252 -95.940337) (xy 233.675224 -95.891702) (xy 233.655301 -95.839611)
			(xy 233.643175 -95.785174) (xy 233.639104 -95.729552) (xy 233.060136 -95.729552) (xy 233.080959 -95.761026)
			(xy 233.104631 -95.811523) (xy 233.120699 -95.86493) (xy 233.128819 -95.920106) (xy 233.129328 -95.947992)
			(xy 233.128819 -95.975878) (xy 233.120699 -96.031054) (xy 233.104631 -96.084461) (xy 233.080959 -96.134958)
			(xy 233.050186 -96.181471) (xy 233.012969 -96.223008) (xy 232.970101 -96.258683) (xy 232.922495 -96.287737)
			(xy 232.871166 -96.309549) (xy 232.817209 -96.323655) (xy 232.761772 -96.329755) (xy 232.706038 -96.327718)
			(xy 232.651195 -96.317588) (xy 232.598411 -96.299581) (xy 232.548811 -96.27408) (xy 232.503453 -96.241629)
			(xy 232.463304 -96.20292) (xy 232.429218 -96.158777) (xy 232.401922 -96.110142) (xy 232.381999 -96.058051)
			(xy 232.369873 -96.003614) (xy 232.365802 -95.947992) (xy 204.854079 -95.947992) (xy 203.269548 -98.766863)
			(xy 206.090008 -98.766863) (xy 206.090008 -98.633301) (xy 206.098072 -98.499983) (xy 206.114172 -98.367395)
			(xy 206.138247 -98.236021) (xy 206.17021 -98.10634) (xy 206.209945 -97.978826) (xy 206.257307 -97.853943)
			(xy 206.312122 -97.732148) (xy 206.374192 -97.613885) (xy 206.443288 -97.499586) (xy 206.51916 -97.389666)
			(xy 206.60153 -97.284529) (xy 206.690098 -97.184556) (xy 206.78454 -97.090114) (xy 206.884513 -97.001546)
			(xy 206.98965 -96.919176) (xy 207.09957 -96.843304) (xy 207.213869 -96.774208) (xy 207.332132 -96.712138)
			(xy 207.453927 -96.657323) (xy 207.57881 -96.609961) (xy 207.706324 -96.570226) (xy 207.836005 -96.538263)
			(xy 207.967379 -96.514188) (xy 208.099967 -96.498088) (xy 208.233285 -96.490024) (xy 208.366847 -96.490024)
			(xy 208.500165 -96.498088) (xy 208.632753 -96.514188) (xy 208.764127 -96.538263) (xy 208.893808 -96.570226)
			(xy 209.021322 -96.609961) (xy 209.146205 -96.657323) (xy 209.268 -96.712138) (xy 209.386263 -96.774208)
			(xy 209.500562 -96.843304) (xy 209.610482 -96.919176) (xy 209.715619 -97.001546) (xy 209.815592 -97.090114)
			(xy 209.910034 -97.184556) (xy 209.996362 -97.282) (xy 218.206826 -97.282) (xy 218.210897 -97.226378)
			(xy 218.223023 -97.171941) (xy 218.242946 -97.11985) (xy 218.270242 -97.071215) (xy 218.304328 -97.027072)
			(xy 218.344477 -96.988363) (xy 218.389835 -96.955912) (xy 218.439435 -96.930411) (xy 218.492219 -96.912404)
			(xy 218.547062 -96.902274) (xy 218.602796 -96.900237) (xy 218.658233 -96.906337) (xy 218.71219 -96.920443)
			(xy 218.763519 -96.942255) (xy 218.811125 -96.971309) (xy 218.853993 -97.006984) (xy 218.89121 -97.048521)
			(xy 218.921983 -97.095034) (xy 218.945655 -97.145531) (xy 218.961723 -97.198938) (xy 218.969843 -97.254114)
			(xy 218.970352 -97.282) (xy 218.969843 -97.309886) (xy 218.961723 -97.365062) (xy 218.945655 -97.418469)
			(xy 218.921983 -97.468966) (xy 218.89121 -97.515479) (xy 218.872823 -97.536) (xy 219.095826 -97.536)
			(xy 219.099897 -97.480378) (xy 219.112023 -97.425941) (xy 219.131946 -97.37385) (xy 219.159242 -97.325215)
			(xy 219.193328 -97.281072) (xy 219.233477 -97.242363) (xy 219.278835 -97.209912) (xy 219.328435 -97.184411)
			(xy 219.381219 -97.166404) (xy 219.436062 -97.156274) (xy 219.491796 -97.154237) (xy 219.547233 -97.160337)
			(xy 219.60119 -97.174443) (xy 219.652519 -97.196255) (xy 219.700125 -97.225309) (xy 219.742993 -97.260984)
			(xy 219.78021 -97.302521) (xy 219.787639 -97.31375) (xy 222.308926 -97.31375) (xy 222.312997 -97.258128)
			(xy 222.325123 -97.203691) (xy 222.345046 -97.1516) (xy 222.372342 -97.102965) (xy 222.406428 -97.058822)
			(xy 222.446577 -97.020113) (xy 222.491935 -96.987662) (xy 222.541535 -96.962161) (xy 222.594319 -96.944154)
			(xy 222.649162 -96.934024) (xy 222.704896 -96.931987) (xy 222.760333 -96.938087) (xy 222.81429 -96.952193)
			(xy 222.865619 -96.974005) (xy 222.913225 -97.003059) (xy 222.956093 -97.038734) (xy 222.99331 -97.080271)
			(xy 223.024083 -97.126784) (xy 223.047755 -97.177281) (xy 223.063823 -97.230688) (xy 223.071943 -97.285864)
			(xy 223.072452 -97.31375) (xy 223.324926 -97.31375) (xy 223.328997 -97.258128) (xy 223.341123 -97.203691)
			(xy 223.361046 -97.1516) (xy 223.388342 -97.102965) (xy 223.422428 -97.058822) (xy 223.462577 -97.020113)
			(xy 223.507935 -96.987662) (xy 223.557535 -96.962161) (xy 223.610319 -96.944154) (xy 223.665162 -96.934024)
			(xy 223.720896 -96.931987) (xy 223.776333 -96.938087) (xy 223.83029 -96.952193) (xy 223.881619 -96.974005)
			(xy 223.929225 -97.003059) (xy 223.972093 -97.038734) (xy 224.00931 -97.080271) (xy 224.040083 -97.126784)
			(xy 224.063755 -97.177281) (xy 224.079823 -97.230688) (xy 224.087943 -97.285864) (xy 224.088452 -97.31375)
			(xy 227.642926 -97.31375) (xy 227.646997 -97.258128) (xy 227.659123 -97.203691) (xy 227.679046 -97.1516)
			(xy 227.706342 -97.102965) (xy 227.740428 -97.058822) (xy 227.780577 -97.020113) (xy 227.825935 -96.987662)
			(xy 227.875535 -96.962161) (xy 227.928319 -96.944154) (xy 227.983162 -96.934024) (xy 228.038896 -96.931987)
			(xy 228.094333 -96.938087) (xy 228.14829 -96.952193) (xy 228.199619 -96.974005) (xy 228.247225 -97.003059)
			(xy 228.290093 -97.038734) (xy 228.32731 -97.080271) (xy 228.358083 -97.126784) (xy 228.381755 -97.177281)
			(xy 228.397823 -97.230688) (xy 228.405943 -97.285864) (xy 228.406452 -97.31375) (xy 228.405943 -97.341636)
			(xy 228.397823 -97.396812) (xy 228.381755 -97.450219) (xy 228.358083 -97.500716) (xy 228.32731 -97.547229)
			(xy 228.290093 -97.588766) (xy 228.247225 -97.624441) (xy 228.199619 -97.653495) (xy 228.14829 -97.675307)
			(xy 228.094333 -97.689413) (xy 228.038896 -97.695513) (xy 227.983162 -97.693476) (xy 227.928319 -97.683346)
			(xy 227.875535 -97.665339) (xy 227.825935 -97.639838) (xy 227.780577 -97.607387) (xy 227.740428 -97.568678)
			(xy 227.706342 -97.524535) (xy 227.679046 -97.4759) (xy 227.659123 -97.423809) (xy 227.646997 -97.369372)
			(xy 227.642926 -97.31375) (xy 224.088452 -97.31375) (xy 224.087943 -97.341636) (xy 224.079823 -97.396812)
			(xy 224.063755 -97.450219) (xy 224.040083 -97.500716) (xy 224.00931 -97.547229) (xy 223.972093 -97.588766)
			(xy 223.929225 -97.624441) (xy 223.881619 -97.653495) (xy 223.83029 -97.675307) (xy 223.776333 -97.689413)
			(xy 223.720896 -97.695513) (xy 223.665162 -97.693476) (xy 223.610319 -97.683346) (xy 223.557535 -97.665339)
			(xy 223.507935 -97.639838) (xy 223.462577 -97.607387) (xy 223.422428 -97.568678) (xy 223.388342 -97.524535)
			(xy 223.361046 -97.4759) (xy 223.341123 -97.423809) (xy 223.328997 -97.369372) (xy 223.324926 -97.31375)
			(xy 223.072452 -97.31375) (xy 223.071943 -97.341636) (xy 223.063823 -97.396812) (xy 223.047755 -97.450219)
			(xy 223.024083 -97.500716) (xy 222.99331 -97.547229) (xy 222.956093 -97.588766) (xy 222.913225 -97.624441)
			(xy 222.865619 -97.653495) (xy 222.81429 -97.675307) (xy 222.760333 -97.689413) (xy 222.704896 -97.695513)
			(xy 222.649162 -97.693476) (xy 222.594319 -97.683346) (xy 222.541535 -97.665339) (xy 222.491935 -97.639838)
			(xy 222.446577 -97.607387) (xy 222.406428 -97.568678) (xy 222.372342 -97.524535) (xy 222.345046 -97.4759)
			(xy 222.325123 -97.423809) (xy 222.312997 -97.369372) (xy 222.308926 -97.31375) (xy 219.787639 -97.31375)
			(xy 219.810983 -97.349034) (xy 219.834655 -97.399531) (xy 219.850723 -97.452938) (xy 219.858843 -97.508114)
			(xy 219.859352 -97.536) (xy 219.858843 -97.563886) (xy 219.850723 -97.619062) (xy 219.834655 -97.672469)
			(xy 219.810983 -97.722966) (xy 219.78021 -97.769479) (xy 219.761823 -97.79) (xy 219.984826 -97.79)
			(xy 219.988897 -97.734378) (xy 220.001023 -97.679941) (xy 220.020946 -97.62785) (xy 220.048242 -97.579215)
			(xy 220.082328 -97.535072) (xy 220.122477 -97.496363) (xy 220.167835 -97.463912) (xy 220.217435 -97.438411)
			(xy 220.270219 -97.420404) (xy 220.325062 -97.410274) (xy 220.380796 -97.408237) (xy 220.436233 -97.414337)
			(xy 220.49019 -97.428443) (xy 220.541519 -97.450255) (xy 220.589125 -97.479309) (xy 220.631993 -97.514984)
			(xy 220.66921 -97.556521) (xy 220.699983 -97.603034) (xy 220.723655 -97.653531) (xy 220.739723 -97.706938)
			(xy 220.747843 -97.762114) (xy 220.748352 -97.79) (xy 220.747843 -97.817886) (xy 220.739723 -97.873062)
			(xy 220.723655 -97.926469) (xy 220.699983 -97.976966) (xy 220.66921 -98.023479) (xy 220.631993 -98.065016)
			(xy 220.589125 -98.100691) (xy 220.541519 -98.129745) (xy 220.49019 -98.151557) (xy 220.436233 -98.165663)
			(xy 220.380796 -98.171763) (xy 220.325062 -98.169726) (xy 220.270219 -98.159596) (xy 220.217435 -98.141589)
			(xy 220.167835 -98.116088) (xy 220.122477 -98.083637) (xy 220.082328 -98.044928) (xy 220.048242 -98.000785)
			(xy 220.020946 -97.95215) (xy 220.001023 -97.900059) (xy 219.988897 -97.845622) (xy 219.984826 -97.79)
			(xy 219.761823 -97.79) (xy 219.742993 -97.811016) (xy 219.700125 -97.846691) (xy 219.652519 -97.875745)
			(xy 219.60119 -97.897557) (xy 219.547233 -97.911663) (xy 219.491796 -97.917763) (xy 219.436062 -97.915726)
			(xy 219.381219 -97.905596) (xy 219.328435 -97.887589) (xy 219.278835 -97.862088) (xy 219.233477 -97.829637)
			(xy 219.193328 -97.790928) (xy 219.159242 -97.746785) (xy 219.131946 -97.69815) (xy 219.112023 -97.646059)
			(xy 219.099897 -97.591622) (xy 219.095826 -97.536) (xy 218.872823 -97.536) (xy 218.853993 -97.557016)
			(xy 218.811125 -97.592691) (xy 218.763519 -97.621745) (xy 218.71219 -97.643557) (xy 218.658233 -97.657663)
			(xy 218.602796 -97.663763) (xy 218.547062 -97.661726) (xy 218.492219 -97.651596) (xy 218.439435 -97.633589)
			(xy 218.389835 -97.608088) (xy 218.344477 -97.575637) (xy 218.304328 -97.536928) (xy 218.270242 -97.492785)
			(xy 218.242946 -97.44415) (xy 218.223023 -97.392059) (xy 218.210897 -97.337622) (xy 218.206826 -97.282)
			(xy 209.996362 -97.282) (xy 209.998602 -97.284529) (xy 210.080972 -97.389666) (xy 210.156844 -97.499586)
			(xy 210.22594 -97.613885) (xy 210.28801 -97.732148) (xy 210.342825 -97.853943) (xy 210.390187 -97.978826)
			(xy 210.429922 -98.10634) (xy 210.461885 -98.236021) (xy 210.48596 -98.367395) (xy 210.492461 -98.420936)
			(xy 225.995736 -98.420936) (xy 225.999807 -98.365314) (xy 226.011933 -98.310877) (xy 226.031856 -98.258786)
			(xy 226.059152 -98.210151) (xy 226.093238 -98.166008) (xy 226.133387 -98.127299) (xy 226.178745 -98.094848)
			(xy 226.228345 -98.069347) (xy 226.281129 -98.05134) (xy 226.335972 -98.04121) (xy 226.391706 -98.039173)
			(xy 226.447143 -98.045273) (xy 226.5011 -98.059379) (xy 226.552429 -98.081191) (xy 226.600035 -98.110245)
			(xy 226.642903 -98.14592) (xy 226.68012 -98.187457) (xy 226.710893 -98.23397) (xy 226.734565 -98.284467)
			(xy 226.738025 -98.295968) (xy 231.03027 -98.295968) (xy 231.034341 -98.240346) (xy 231.046467 -98.185909)
			(xy 231.06639 -98.133818) (xy 231.093686 -98.085183) (xy 231.127772 -98.04104) (xy 231.167921 -98.002331)
			(xy 231.213279 -97.96988) (xy 231.262879 -97.944379) (xy 231.315663 -97.926372) (xy 231.370506 -97.916242)
			(xy 231.42624 -97.914205) (xy 231.481677 -97.920305) (xy 231.535634 -97.934411) (xy 231.586963 -97.956223)
			(xy 231.634569 -97.985277) (xy 231.677437 -98.020952) (xy 231.714654 -98.062489) (xy 231.745427 -98.109002)
			(xy 231.769099 -98.159499) (xy 231.785167 -98.212906) (xy 231.793287 -98.268082) (xy 231.793796 -98.295968)
			(xy 232.04627 -98.295968) (xy 232.050341 -98.240346) (xy 232.062467 -98.185909) (xy 232.08239 -98.133818)
			(xy 232.109686 -98.085183) (xy 232.143772 -98.04104) (xy 232.183921 -98.002331) (xy 232.229279 -97.96988)
			(xy 232.278879 -97.944379) (xy 232.331663 -97.926372) (xy 232.386506 -97.916242) (xy 232.44224 -97.914205)
			(xy 232.497677 -97.920305) (xy 232.551634 -97.934411) (xy 232.602963 -97.956223) (xy 232.650569 -97.985277)
			(xy 232.693437 -98.020952) (xy 232.730654 -98.062489) (xy 232.761427 -98.109002) (xy 232.785099 -98.159499)
			(xy 232.801167 -98.212906) (xy 232.809287 -98.268082) (xy 232.809796 -98.295968) (xy 236.11027 -98.295968)
			(xy 236.114341 -98.240346) (xy 236.126467 -98.185909) (xy 236.14639 -98.133818) (xy 236.173686 -98.085183)
			(xy 236.207772 -98.04104) (xy 236.247921 -98.002331) (xy 236.293279 -97.96988) (xy 236.342879 -97.944379)
			(xy 236.395663 -97.926372) (xy 236.450506 -97.916242) (xy 236.50624 -97.914205) (xy 236.561677 -97.920305)
			(xy 236.615634 -97.934411) (xy 236.666963 -97.956223) (xy 236.714569 -97.985277) (xy 236.757437 -98.020952)
			(xy 236.794654 -98.062489) (xy 236.825427 -98.109002) (xy 236.849099 -98.159499) (xy 236.865167 -98.212906)
			(xy 236.873287 -98.268082) (xy 236.873796 -98.295968) (xy 236.873287 -98.323854) (xy 236.865167 -98.37903)
			(xy 236.849099 -98.432437) (xy 236.825427 -98.482934) (xy 236.794654 -98.529447) (xy 236.757437 -98.570984)
			(xy 236.714569 -98.606659) (xy 236.666963 -98.635713) (xy 236.615634 -98.657525) (xy 236.561677 -98.671631)
			(xy 236.50624 -98.677731) (xy 236.450506 -98.675694) (xy 236.395663 -98.665564) (xy 236.342879 -98.647557)
			(xy 236.293279 -98.622056) (xy 236.247921 -98.589605) (xy 236.207772 -98.550896) (xy 236.173686 -98.506753)
			(xy 236.14639 -98.458118) (xy 236.126467 -98.406027) (xy 236.114341 -98.35159) (xy 236.11027 -98.295968)
			(xy 232.809796 -98.295968) (xy 232.809287 -98.323854) (xy 232.801167 -98.37903) (xy 232.785099 -98.432437)
			(xy 232.761427 -98.482934) (xy 232.730654 -98.529447) (xy 232.693437 -98.570984) (xy 232.650569 -98.606659)
			(xy 232.602963 -98.635713) (xy 232.551634 -98.657525) (xy 232.497677 -98.671631) (xy 232.44224 -98.677731)
			(xy 232.386506 -98.675694) (xy 232.331663 -98.665564) (xy 232.278879 -98.647557) (xy 232.229279 -98.622056)
			(xy 232.183921 -98.589605) (xy 232.143772 -98.550896) (xy 232.109686 -98.506753) (xy 232.08239 -98.458118)
			(xy 232.062467 -98.406027) (xy 232.050341 -98.35159) (xy 232.04627 -98.295968) (xy 231.793796 -98.295968)
			(xy 231.793287 -98.323854) (xy 231.785167 -98.37903) (xy 231.769099 -98.432437) (xy 231.745427 -98.482934)
			(xy 231.714654 -98.529447) (xy 231.677437 -98.570984) (xy 231.634569 -98.606659) (xy 231.586963 -98.635713)
			(xy 231.535634 -98.657525) (xy 231.481677 -98.671631) (xy 231.42624 -98.677731) (xy 231.370506 -98.675694)
			(xy 231.315663 -98.665564) (xy 231.262879 -98.647557) (xy 231.213279 -98.622056) (xy 231.167921 -98.589605)
			(xy 231.127772 -98.550896) (xy 231.093686 -98.506753) (xy 231.06639 -98.458118) (xy 231.046467 -98.406027)
			(xy 231.034341 -98.35159) (xy 231.03027 -98.295968) (xy 226.738025 -98.295968) (xy 226.750633 -98.337874)
			(xy 226.758753 -98.39305) (xy 226.759262 -98.420936) (xy 226.758753 -98.448822) (xy 226.750633 -98.503998)
			(xy 226.734565 -98.557405) (xy 226.710893 -98.607902) (xy 226.68012 -98.654415) (xy 226.642903 -98.695952)
			(xy 226.600035 -98.731627) (xy 226.552429 -98.760681) (xy 226.537881 -98.766863) (xy 257.089906 -98.766863)
			(xy 257.089906 -98.633301) (xy 257.09797 -98.499983) (xy 257.11407 -98.367395) (xy 257.138145 -98.236021)
			(xy 257.170108 -98.10634) (xy 257.209843 -97.978826) (xy 257.257205 -97.853943) (xy 257.31202 -97.732148)
			(xy 257.37409 -97.613885) (xy 257.443186 -97.499586) (xy 257.519058 -97.389666) (xy 257.601428 -97.284529)
			(xy 257.689996 -97.184556) (xy 257.784438 -97.090114) (xy 257.884411 -97.001546) (xy 257.989548 -96.919176)
			(xy 258.099468 -96.843304) (xy 258.213767 -96.774208) (xy 258.33203 -96.712138) (xy 258.453825 -96.657323)
			(xy 258.578708 -96.609961) (xy 258.706222 -96.570226) (xy 258.835903 -96.538263) (xy 258.967277 -96.514188)
			(xy 259.099865 -96.498088) (xy 259.233183 -96.490024) (xy 259.366745 -96.490024) (xy 259.500063 -96.498088)
			(xy 259.632651 -96.514188) (xy 259.764025 -96.538263) (xy 259.893706 -96.570226) (xy 260.02122 -96.609961)
			(xy 260.146103 -96.657323) (xy 260.267898 -96.712138) (xy 260.386161 -96.774208) (xy 260.50046 -96.843304)
			(xy 260.61038 -96.919176) (xy 260.715517 -97.001546) (xy 260.81549 -97.090114) (xy 260.909932 -97.184556)
			(xy 260.9985 -97.284529) (xy 261.08087 -97.389666) (xy 261.156742 -97.499586) (xy 261.225838 -97.613885)
			(xy 261.287908 -97.732148) (xy 261.342723 -97.853943) (xy 261.390085 -97.978826) (xy 261.42982 -98.10634)
			(xy 261.461783 -98.236021) (xy 261.485858 -98.367395) (xy 261.501958 -98.499983) (xy 261.510022 -98.633301)
			(xy 261.510526 -98.700082) (xy 261.510022 -98.766863) (xy 261.501958 -98.900181) (xy 261.485858 -99.032769)
			(xy 261.461783 -99.164143) (xy 261.42982 -99.293824) (xy 261.390085 -99.421338) (xy 261.342723 -99.546221)
			(xy 261.287908 -99.668016) (xy 261.225838 -99.786279) (xy 261.156742 -99.900578) (xy 261.08087 -100.010498)
			(xy 260.9985 -100.115635) (xy 260.909932 -100.215608) (xy 260.81549 -100.31005) (xy 260.715517 -100.398618)
			(xy 260.61038 -100.480988) (xy 260.50046 -100.55686) (xy 260.386161 -100.625956) (xy 260.267898 -100.688026)
			(xy 260.146103 -100.742841) (xy 260.02122 -100.790203) (xy 259.893706 -100.829938) (xy 259.764025 -100.861901)
			(xy 259.632651 -100.885976) (xy 259.500063 -100.902076) (xy 259.366745 -100.91014) (xy 259.233183 -100.91014)
			(xy 259.099865 -100.902076) (xy 258.967277 -100.885976) (xy 258.835903 -100.861901) (xy 258.706222 -100.829938)
			(xy 258.578708 -100.790203) (xy 258.453825 -100.742841) (xy 258.33203 -100.688026) (xy 258.213767 -100.625956)
			(xy 258.099468 -100.55686) (xy 257.989548 -100.480988) (xy 257.884411 -100.398618) (xy 257.784438 -100.31005)
			(xy 257.689996 -100.215608) (xy 257.601428 -100.115635) (xy 257.519058 -100.010498) (xy 257.443186 -99.900578)
			(xy 257.37409 -99.786279) (xy 257.31202 -99.668016) (xy 257.257205 -99.546221) (xy 257.209843 -99.421338)
			(xy 257.170108 -99.293824) (xy 257.138145 -99.164143) (xy 257.11407 -99.032769) (xy 257.09797 -98.900181)
			(xy 257.089906 -98.766863) (xy 226.537881 -98.766863) (xy 226.5011 -98.782493) (xy 226.447143 -98.796599)
			(xy 226.391706 -98.802699) (xy 226.335972 -98.800662) (xy 226.281129 -98.790532) (xy 226.228345 -98.772525)
			(xy 226.178745 -98.747024) (xy 226.133387 -98.714573) (xy 226.093238 -98.675864) (xy 226.059152 -98.631721)
			(xy 226.031856 -98.583086) (xy 226.011933 -98.530995) (xy 225.999807 -98.476558) (xy 225.995736 -98.420936)
			(xy 210.492461 -98.420936) (xy 210.50206 -98.499983) (xy 210.510124 -98.633301) (xy 210.510628 -98.700082)
			(xy 210.510124 -98.766863) (xy 210.50206 -98.900181) (xy 210.48596 -99.032769) (xy 210.461885 -99.164143)
			(xy 210.429922 -99.293824) (xy 210.390187 -99.421338) (xy 210.342825 -99.546221) (xy 210.28801 -99.668016)
			(xy 210.22594 -99.786279) (xy 210.204499 -99.821746) (xy 216.555826 -99.821746) (xy 216.559897 -99.766124)
			(xy 216.572023 -99.711687) (xy 216.591946 -99.659596) (xy 216.619242 -99.610961) (xy 216.653328 -99.566818)
			(xy 216.693477 -99.528109) (xy 216.738835 -99.495658) (xy 216.788435 -99.470157) (xy 216.841219 -99.45215)
			(xy 216.896062 -99.44202) (xy 216.951796 -99.439983) (xy 217.007233 -99.446083) (xy 217.06119 -99.460189)
			(xy 217.112519 -99.482001) (xy 217.160125 -99.511055) (xy 217.202993 -99.54673) (xy 217.24021 -99.588267)
			(xy 217.270983 -99.63478) (xy 217.294655 -99.685277) (xy 217.310723 -99.738684) (xy 217.318843 -99.79386)
			(xy 217.319352 -99.821746) (xy 217.318843 -99.849632) (xy 217.310723 -99.904808) (xy 217.294655 -99.958215)
			(xy 217.270983 -100.008712) (xy 217.24021 -100.055225) (xy 217.221596 -100.076) (xy 218.371672 -100.076)
			(xy 218.375743 -100.020378) (xy 218.387869 -99.965941) (xy 218.407792 -99.91385) (xy 218.435088 -99.865215)
			(xy 218.469174 -99.821072) (xy 218.509323 -99.782363) (xy 218.554681 -99.749912) (xy 218.604281 -99.724411)
			(xy 218.657065 -99.706404) (xy 218.711908 -99.696274) (xy 218.767642 -99.694237) (xy 218.823079 -99.700337)
			(xy 218.877036 -99.714443) (xy 218.928365 -99.736255) (xy 218.975971 -99.765309) (xy 219.018839 -99.800984)
			(xy 219.037669 -99.822) (xy 219.984826 -99.822) (xy 219.988897 -99.766378) (xy 220.001023 -99.711941)
			(xy 220.020946 -99.65985) (xy 220.048242 -99.611215) (xy 220.082328 -99.567072) (xy 220.122477 -99.528363)
			(xy 220.167835 -99.495912) (xy 220.217435 -99.470411) (xy 220.270219 -99.452404) (xy 220.325062 -99.442274)
			(xy 220.380796 -99.440237) (xy 220.436233 -99.446337) (xy 220.49019 -99.460443) (xy 220.541519 -99.482255)
			(xy 220.579633 -99.505516) (xy 221.292926 -99.505516) (xy 221.296997 -99.449894) (xy 221.309123 -99.395457)
			(xy 221.329046 -99.343366) (xy 221.356342 -99.294731) (xy 221.390428 -99.250588) (xy 221.430577 -99.211879)
			(xy 221.475935 -99.179428) (xy 221.525535 -99.153927) (xy 221.578319 -99.13592) (xy 221.633162 -99.12579)
			(xy 221.688896 -99.123753) (xy 221.744333 -99.129853) (xy 221.79829 -99.143959) (xy 221.849619 -99.165771)
			(xy 221.897225 -99.194825) (xy 221.940093 -99.2305) (xy 221.97731 -99.272037) (xy 222.008083 -99.31855)
			(xy 222.031755 -99.369047) (xy 222.047823 -99.422454) (xy 222.055943 -99.47763) (xy 222.056345 -99.499674)
			(xy 222.606868 -99.499674) (xy 222.610939 -99.444052) (xy 222.623065 -99.389615) (xy 222.642988 -99.337524)
			(xy 222.670284 -99.288889) (xy 222.70437 -99.244746) (xy 222.744519 -99.206037) (xy 222.789877 -99.173586)
			(xy 222.839477 -99.148085) (xy 222.892261 -99.130078) (xy 222.947104 -99.119948) (xy 223.002838 -99.117911)
			(xy 223.058275 -99.124011) (xy 223.112232 -99.138117) (xy 223.163561 -99.159929) (xy 223.211167 -99.188983)
			(xy 223.254035 -99.224658) (xy 223.291252 -99.266195) (xy 223.322025 -99.312708) (xy 223.334419 -99.339146)
			(xy 223.880932 -99.339146) (xy 223.885003 -99.283524) (xy 223.897129 -99.229087) (xy 223.917052 -99.176996)
			(xy 223.944348 -99.128361) (xy 223.978434 -99.084218) (xy 224.018583 -99.045509) (xy 224.063941 -99.013058)
			(xy 224.113541 -98.987557) (xy 224.166325 -98.96955) (xy 224.221168 -98.95942) (xy 224.276902 -98.957383)
			(xy 224.332339 -98.963483) (xy 224.386296 -98.977589) (xy 224.437625 -98.999401) (xy 224.485231 -99.028455)
			(xy 224.528099 -99.06413) (xy 224.565316 -99.105667) (xy 224.596089 -99.15218) (xy 224.619761 -99.202677)
			(xy 224.635829 -99.256084) (xy 224.643949 -99.31126) (xy 224.644458 -99.339146) (xy 224.643949 -99.367032)
			(xy 224.635829 -99.422208) (xy 224.619761 -99.475615) (xy 224.596089 -99.526112) (xy 224.565316 -99.572625)
			(xy 224.560812 -99.577652) (xy 225.818444 -99.577652) (xy 225.822515 -99.52203) (xy 225.834641 -99.467593)
			(xy 225.854564 -99.415502) (xy 225.88186 -99.366867) (xy 225.915946 -99.322724) (xy 225.956095 -99.284015)
			(xy 226.001453 -99.251564) (xy 226.051053 -99.226063) (xy 226.103837 -99.208056) (xy 226.15868 -99.197926)
			(xy 226.214414 -99.195889) (xy 226.269851 -99.201989) (xy 226.323808 -99.216095) (xy 226.375137 -99.237907)
			(xy 226.422743 -99.266961) (xy 226.465611 -99.302636) (xy 226.502828 -99.344173) (xy 226.533601 -99.390686)
			(xy 226.557273 -99.441183) (xy 226.573341 -99.49459) (xy 226.581461 -99.549766) (xy 226.58197 -99.577652)
			(xy 226.581461 -99.605538) (xy 226.573341 -99.660714) (xy 226.557273 -99.714121) (xy 226.533601 -99.764618)
			(xy 226.52807 -99.772978) (xy 243.553486 -99.772978) (xy 243.557557 -99.717356) (xy 243.569683 -99.662919)
			(xy 243.589606 -99.610828) (xy 243.616902 -99.562193) (xy 243.650988 -99.51805) (xy 243.691137 -99.479341)
			(xy 243.736495 -99.44689) (xy 243.786095 -99.421389) (xy 243.838879 -99.403382) (xy 243.893722 -99.393252)
			(xy 243.949456 -99.391215) (xy 244.004893 -99.397315) (xy 244.05885 -99.411421) (xy 244.110179 -99.433233)
			(xy 244.157785 -99.462287) (xy 244.200653 -99.497962) (xy 244.23787 -99.539499) (xy 244.268643 -99.586012)
			(xy 244.292315 -99.636509) (xy 244.308383 -99.689916) (xy 244.316503 -99.745092) (xy 244.317012 -99.772978)
			(xy 244.316503 -99.800864) (xy 244.308383 -99.85604) (xy 244.292315 -99.909447) (xy 244.268643 -99.959944)
			(xy 244.23787 -100.006457) (xy 244.200653 -100.047994) (xy 244.157785 -100.083669) (xy 244.110179 -100.112723)
			(xy 244.05885 -100.134535) (xy 244.004893 -100.148641) (xy 243.949456 -100.154741) (xy 243.893722 -100.152704)
			(xy 243.838879 -100.142574) (xy 243.786095 -100.124567) (xy 243.736495 -100.099066) (xy 243.691137 -100.066615)
			(xy 243.650988 -100.027906) (xy 243.616902 -99.983763) (xy 243.589606 -99.935128) (xy 243.569683 -99.883037)
			(xy 243.557557 -99.8286) (xy 243.553486 -99.772978) (xy 226.52807 -99.772978) (xy 226.502828 -99.811131)
			(xy 226.465611 -99.852668) (xy 226.422743 -99.888343) (xy 226.375137 -99.917397) (xy 226.323808 -99.939209)
			(xy 226.269851 -99.953315) (xy 226.214414 -99.959415) (xy 226.15868 -99.957378) (xy 226.103837 -99.947248)
			(xy 226.051053 -99.929241) (xy 226.001453 -99.90374) (xy 225.956095 -99.871289) (xy 225.915946 -99.83258)
			(xy 225.88186 -99.788437) (xy 225.854564 -99.739802) (xy 225.834641 -99.687711) (xy 225.822515 -99.633274)
			(xy 225.818444 -99.577652) (xy 224.560812 -99.577652) (xy 224.528099 -99.614162) (xy 224.485231 -99.649837)
			(xy 224.437625 -99.678891) (xy 224.386296 -99.700703) (xy 224.332339 -99.714809) (xy 224.276902 -99.720909)
			(xy 224.221168 -99.718872) (xy 224.166325 -99.708742) (xy 224.113541 -99.690735) (xy 224.063941 -99.665234)
			(xy 224.018583 -99.632783) (xy 223.978434 -99.594074) (xy 223.944348 -99.549931) (xy 223.917052 -99.501296)
			(xy 223.897129 -99.449205) (xy 223.885003 -99.394768) (xy 223.880932 -99.339146) (xy 223.334419 -99.339146)
			(xy 223.345697 -99.363205) (xy 223.361765 -99.416612) (xy 223.369885 -99.471788) (xy 223.370394 -99.499674)
			(xy 223.369885 -99.52756) (xy 223.361765 -99.582736) (xy 223.345697 -99.636143) (xy 223.322025 -99.68664)
			(xy 223.291252 -99.733153) (xy 223.254035 -99.77469) (xy 223.211167 -99.810365) (xy 223.163561 -99.839419)
			(xy 223.112232 -99.861231) (xy 223.058275 -99.875337) (xy 223.002838 -99.881437) (xy 222.947104 -99.8794)
			(xy 222.892261 -99.86927) (xy 222.839477 -99.851263) (xy 222.789877 -99.825762) (xy 222.744519 -99.793311)
			(xy 222.70437 -99.754602) (xy 222.670284 -99.710459) (xy 222.642988 -99.661824) (xy 222.623065 -99.609733)
			(xy 222.610939 -99.555296) (xy 222.606868 -99.499674) (xy 222.056345 -99.499674) (xy 222.056452 -99.505516)
			(xy 222.055943 -99.533402) (xy 222.047823 -99.588578) (xy 222.031755 -99.641985) (xy 222.008083 -99.692482)
			(xy 221.97731 -99.738995) (xy 221.940093 -99.780532) (xy 221.897225 -99.816207) (xy 221.849619 -99.845261)
			(xy 221.79829 -99.867073) (xy 221.744333 -99.881179) (xy 221.688896 -99.887279) (xy 221.633162 -99.885242)
			(xy 221.578319 -99.875112) (xy 221.525535 -99.857105) (xy 221.475935 -99.831604) (xy 221.430577 -99.799153)
			(xy 221.390428 -99.760444) (xy 221.356342 -99.716301) (xy 221.329046 -99.667666) (xy 221.309123 -99.615575)
			(xy 221.296997 -99.561138) (xy 221.292926 -99.505516) (xy 220.579633 -99.505516) (xy 220.589125 -99.511309)
			(xy 220.631993 -99.546984) (xy 220.66921 -99.588521) (xy 220.699983 -99.635034) (xy 220.723655 -99.685531)
			(xy 220.739723 -99.738938) (xy 220.747843 -99.794114) (xy 220.748352 -99.822) (xy 220.747843 -99.849886)
			(xy 220.739723 -99.905062) (xy 220.723655 -99.958469) (xy 220.699983 -100.008966) (xy 220.66921 -100.055479)
			(xy 220.631993 -100.097016) (xy 220.589125 -100.132691) (xy 220.541519 -100.161745) (xy 220.49019 -100.183557)
			(xy 220.436233 -100.197663) (xy 220.380796 -100.203763) (xy 220.325062 -100.201726) (xy 220.270219 -100.191596)
			(xy 220.217435 -100.173589) (xy 220.167835 -100.148088) (xy 220.122477 -100.115637) (xy 220.082328 -100.076928)
			(xy 220.048242 -100.032785) (xy 220.020946 -99.98415) (xy 220.001023 -99.932059) (xy 219.988897 -99.877622)
			(xy 219.984826 -99.822) (xy 219.037669 -99.822) (xy 219.056056 -99.842521) (xy 219.086829 -99.889034)
			(xy 219.110501 -99.939531) (xy 219.126569 -99.992938) (xy 219.134689 -100.048114) (xy 219.135198 -100.076)
			(xy 219.134689 -100.103886) (xy 219.126569 -100.159062) (xy 219.110501 -100.212469) (xy 219.086829 -100.262966)
			(xy 219.056056 -100.309479) (xy 219.018839 -100.351016) (xy 218.975971 -100.386691) (xy 218.928365 -100.415745)
			(xy 218.877036 -100.437557) (xy 218.823079 -100.451663) (xy 218.767642 -100.457763) (xy 218.711908 -100.455726)
			(xy 218.657065 -100.445596) (xy 218.604281 -100.427589) (xy 218.554681 -100.402088) (xy 218.509323 -100.369637)
			(xy 218.469174 -100.330928) (xy 218.435088 -100.286785) (xy 218.407792 -100.23815) (xy 218.387869 -100.186059)
			(xy 218.375743 -100.131622) (xy 218.371672 -100.076) (xy 217.221596 -100.076) (xy 217.202993 -100.096762)
			(xy 217.160125 -100.132437) (xy 217.112519 -100.161491) (xy 217.06119 -100.183303) (xy 217.007233 -100.197409)
			(xy 216.951796 -100.203509) (xy 216.896062 -100.201472) (xy 216.841219 -100.191342) (xy 216.788435 -100.173335)
			(xy 216.738835 -100.147834) (xy 216.693477 -100.115383) (xy 216.653328 -100.076674) (xy 216.619242 -100.032531)
			(xy 216.591946 -99.983896) (xy 216.572023 -99.931805) (xy 216.559897 -99.877368) (xy 216.555826 -99.821746)
			(xy 210.204499 -99.821746) (xy 210.156844 -99.900578) (xy 210.080972 -100.010498) (xy 209.998602 -100.115635)
			(xy 209.910034 -100.215608) (xy 209.815592 -100.31005) (xy 209.715619 -100.398618) (xy 209.610482 -100.480988)
			(xy 209.500562 -100.55686) (xy 209.386263 -100.625956) (xy 209.268 -100.688026) (xy 209.146205 -100.742841)
			(xy 209.021322 -100.790203) (xy 208.893808 -100.829938) (xy 208.764127 -100.861901) (xy 208.632753 -100.885976)
			(xy 208.500165 -100.902076) (xy 208.366847 -100.91014) (xy 208.233285 -100.91014) (xy 208.099967 -100.902076)
			(xy 207.967379 -100.885976) (xy 207.836005 -100.861901) (xy 207.706324 -100.829938) (xy 207.57881 -100.790203)
			(xy 207.453927 -100.742841) (xy 207.332132 -100.688026) (xy 207.213869 -100.625956) (xy 207.09957 -100.55686)
			(xy 206.98965 -100.480988) (xy 206.884513 -100.398618) (xy 206.78454 -100.31005) (xy 206.690098 -100.215608)
			(xy 206.60153 -100.115635) (xy 206.51916 -100.010498) (xy 206.443288 -99.900578) (xy 206.374192 -99.786279)
			(xy 206.312122 -99.668016) (xy 206.257307 -99.546221) (xy 206.209945 -99.421338) (xy 206.17021 -99.293824)
			(xy 206.138247 -99.164143) (xy 206.114172 -99.032769) (xy 206.098072 -98.900181) (xy 206.090008 -98.766863)
			(xy 203.269548 -98.766863) (xy 201.891164 -101.219) (xy 220.238826 -101.219) (xy 220.242897 -101.163378)
			(xy 220.255023 -101.108941) (xy 220.274946 -101.05685) (xy 220.302242 -101.008215) (xy 220.336328 -100.964072)
			(xy 220.376477 -100.925363) (xy 220.421835 -100.892912) (xy 220.471435 -100.867411) (xy 220.524219 -100.849404)
			(xy 220.579062 -100.839274) (xy 220.634796 -100.837237) (xy 220.690233 -100.843337) (xy 220.74419 -100.857443)
			(xy 220.795519 -100.879255) (xy 220.843125 -100.908309) (xy 220.885993 -100.943984) (xy 220.92321 -100.985521)
			(xy 220.953983 -101.032034) (xy 220.977655 -101.082531) (xy 220.993723 -101.135938) (xy 221.001843 -101.191114)
			(xy 221.002352 -101.219) (xy 221.001843 -101.246886) (xy 220.993723 -101.302062) (xy 220.977655 -101.355469)
			(xy 220.953983 -101.405966) (xy 220.92321 -101.452479) (xy 220.885993 -101.494016) (xy 220.843125 -101.529691)
			(xy 220.795519 -101.558745) (xy 220.74419 -101.580557) (xy 220.690233 -101.594663) (xy 220.634796 -101.600763)
			(xy 220.579062 -101.598726) (xy 220.524219 -101.588596) (xy 220.471435 -101.570589) (xy 220.421835 -101.545088)
			(xy 220.376477 -101.512637) (xy 220.336328 -101.473928) (xy 220.302242 -101.429785) (xy 220.274946 -101.38115)
			(xy 220.255023 -101.329059) (xy 220.242897 -101.274622) (xy 220.238826 -101.219) (xy 201.891164 -101.219)
			(xy 200.940553 -102.910132) (xy 224.984056 -102.910132) (xy 224.984527 -102.882762) (xy 224.992342 -102.828582)
			(xy 225.007829 -102.776079) (xy 225.03067 -102.726332) (xy 225.060394 -102.680365) (xy 225.078036 -102.659434)
			(xy 225.07829 -102.65918) (xy 225.08389 -102.652103) (xy 225.090129 -102.635179) (xy 225.090482 -102.62616)
			(xy 225.090482 -102.559104) (xy 225.090127 -102.550087) (xy 225.083879 -102.53317) (xy 225.07829 -102.526084)
			(xy 225.078036 -102.526084) (xy 225.078036 -102.52583) (xy 225.060426 -102.504872) (xy 225.0307 -102.458909)
			(xy 225.007852 -102.409167) (xy 224.992353 -102.356669) (xy 224.984521 -102.302493) (xy 224.984517 -102.247755)
			(xy 224.992342 -102.193579) (xy 225.007835 -102.141078) (xy 225.030676 -102.091333) (xy 225.060397 -102.045367)
			(xy 225.078036 -102.024434) (xy 225.07829 -102.02418) (xy 225.08389 -102.017103) (xy 225.090129 -102.000179)
			(xy 225.090482 -101.99116) (xy 225.090482 -101.924104) (xy 225.090127 -101.915087) (xy 225.083879 -101.89817)
			(xy 225.07829 -101.891084) (xy 225.078036 -101.891084) (xy 225.078036 -101.89083) (xy 225.060403 -101.869893)
			(xy 225.030689 -101.823922) (xy 225.007851 -101.774176) (xy 224.992359 -101.721676) (xy 224.98453 -101.667501)
			(xy 224.984056 -101.640132) (xy 224.984542 -101.612881) (xy 224.992298 -101.558933) (xy 225.007653 -101.506638)
			(xy 225.030295 -101.457061) (xy 225.059761 -101.411211) (xy 225.095452 -101.37002) (xy 225.136643 -101.334329)
			(xy 225.182493 -101.304863) (xy 225.23207 -101.282221) (xy 225.284365 -101.266866) (xy 225.338313 -101.25911)
			(xy 225.392815 -101.25911) (xy 225.446763 -101.266866) (xy 225.499058 -101.282221) (xy 225.548635 -101.304863)
			(xy 225.594485 -101.334329) (xy 225.635676 -101.37002) (xy 225.671367 -101.411211) (xy 225.700833 -101.457061)
			(xy 225.723475 -101.506638) (xy 225.73883 -101.558933) (xy 225.746586 -101.612881) (xy 225.747072 -101.640132)
			(xy 225.746632 -101.667503) (xy 225.738809 -101.721684) (xy 225.723314 -101.774187) (xy 225.700466 -101.823934)
			(xy 225.670736 -101.869899) (xy 225.653092 -101.89083) (xy 225.652838 -101.891084) (xy 225.647245 -101.898166)
			(xy 225.641004 -101.915086) (xy 225.640646 -101.924104) (xy 225.640646 -101.99116) (xy 225.641012 -102.000176)
			(xy 225.647252 -102.017094) (xy 225.652838 -102.02418) (xy 225.653092 -102.02418) (xy 225.653092 -102.024434)
			(xy 225.670763 -102.045342) (xy 225.700485 -102.091314) (xy 225.723328 -102.141065) (xy 225.738821 -102.193571)
			(xy 225.746646 -102.247752) (xy 225.746642 -102.302496) (xy 225.73881 -102.356677) (xy 225.723311 -102.40918)
			(xy 225.700462 -102.458928) (xy 225.670734 -102.504897) (xy 225.653092 -102.52583) (xy 225.652838 -102.526084)
			(xy 225.647245 -102.533166) (xy 225.641004 -102.550086) (xy 225.640646 -102.559104) (xy 225.640646 -102.62616)
			(xy 225.641012 -102.635176) (xy 225.647252 -102.652094) (xy 225.648871 -102.654148) (xy 226.6389 -102.654148)
			(xy 226.6389 -102.599652) (xy 226.646655 -102.54571) (xy 226.662008 -102.493421) (xy 226.684645 -102.443849)
			(xy 226.714107 -102.398003) (xy 226.749792 -102.356816) (xy 226.790976 -102.321127) (xy 226.836819 -102.291661)
			(xy 226.886389 -102.26902) (xy 226.938677 -102.253663) (xy 226.992618 -102.245903) (xy 227.019866 -102.245414)
			(xy 227.046182 -102.245833) (xy 227.098312 -102.253077) (xy 227.148956 -102.267405) (xy 227.197155 -102.288547)
			(xy 227.241997 -102.316102) (xy 227.282635 -102.349549) (xy 227.30079 -102.368604) (xy 227.308313 -102.376004)
			(xy 227.327592 -102.384529) (xy 227.338128 -102.385114) (xy 227.412804 -102.385114) (xy 227.423355 -102.384596)
			(xy 227.44265 -102.376053) (xy 227.450142 -102.368604) (xy 227.468285 -102.349536) (xy 227.508917 -102.31608)
			(xy 227.55376 -102.288522) (xy 227.601963 -102.267386) (xy 227.652613 -102.253072) (xy 227.704749 -102.24585)
			(xy 227.731066 -102.245414) (xy 227.758322 -102.245831) (xy 227.81228 -102.253584) (xy 227.864585 -102.268938)
			(xy 227.914172 -102.29158) (xy 227.960032 -102.321049) (xy 228.001231 -102.356745) (xy 228.036931 -102.397941)
			(xy 228.066404 -102.443798) (xy 228.08612 -102.486968) (xy 228.66223 -102.486968) (xy 228.66267 -102.459597)
			(xy 228.670493 -102.405416) (xy 228.685988 -102.352913) (xy 228.708835 -102.303166) (xy 228.738566 -102.257201)
			(xy 228.75621 -102.23627) (xy 228.756464 -102.236016) (xy 228.762058 -102.228935) (xy 228.768298 -102.212014)
			(xy 228.768656 -102.202996) (xy 228.768656 -102.13594) (xy 228.768289 -102.126924) (xy 228.76205 -102.110006)
			(xy 228.756464 -102.10292) (xy 228.75621 -102.10292) (xy 228.75621 -102.102666) (xy 228.738539 -102.081758)
			(xy 228.708816 -102.035786) (xy 228.685974 -101.986035) (xy 228.670481 -101.93353) (xy 228.662656 -101.879348)
			(xy 228.662659 -101.824604) (xy 228.670491 -101.770423) (xy 228.685991 -101.71792) (xy 228.70884 -101.668172)
			(xy 228.738568 -101.622203) (xy 228.75621 -101.60127) (xy 228.756464 -101.601016) (xy 228.762058 -101.593935)
			(xy 228.768298 -101.577014) (xy 228.768656 -101.567996) (xy 228.768656 -101.50094) (xy 228.768289 -101.491924)
			(xy 228.76205 -101.475006) (xy 228.756464 -101.46792) (xy 228.75621 -101.46792) (xy 228.75621 -101.467666)
			(xy 228.73859 -101.446719) (xy 228.708875 -101.40075) (xy 228.686035 -101.351007) (xy 228.67054 -101.298509)
			(xy 228.662707 -101.244336) (xy 228.66223 -101.216968) (xy 228.662716 -101.189717) (xy 228.670472 -101.135769)
			(xy 228.685827 -101.083474) (xy 228.708469 -101.033897) (xy 228.737935 -100.988047) (xy 228.773626 -100.946856)
			(xy 228.814817 -100.911165) (xy 228.860667 -100.881699) (xy 228.910244 -100.859057) (xy 228.962539 -100.843702)
			(xy 229.016487 -100.835946) (xy 229.070989 -100.835946) (xy 229.124937 -100.843702) (xy 229.177232 -100.859057)
			(xy 229.226809 -100.881699) (xy 229.272659 -100.911165) (xy 229.31385 -100.946856) (xy 229.349541 -100.988047)
			(xy 229.379007 -101.033897) (xy 229.401649 -101.083474) (xy 229.417004 -101.135769) (xy 229.42476 -101.189717)
			(xy 229.425246 -101.216968) (xy 229.424774 -101.244338) (xy 229.41696 -101.298518) (xy 229.401473 -101.351021)
			(xy 229.378632 -101.400768) (xy 229.348907 -101.446735) (xy 229.331266 -101.467666) (xy 229.331012 -101.46792)
			(xy 229.325412 -101.474998) (xy 229.319173 -101.491921) (xy 229.31882 -101.50094) (xy 229.31882 -101.567996)
			(xy 229.319174 -101.577013) (xy 229.325423 -101.59393) (xy 229.331012 -101.601016) (xy 229.331266 -101.601016)
			(xy 229.331266 -101.60127) (xy 229.348876 -101.622228) (xy 229.378602 -101.668191) (xy 229.40145 -101.717933)
			(xy 229.416949 -101.770432) (xy 229.424781 -101.824607) (xy 229.424784 -101.879345) (xy 229.416959 -101.933521)
			(xy 229.401467 -101.986022) (xy 229.378625 -102.035766) (xy 229.348905 -102.081733) (xy 229.331266 -102.102666)
			(xy 229.331012 -102.10292) (xy 229.325412 -102.109998) (xy 229.319173 -102.126921) (xy 229.31882 -102.13594)
			(xy 229.31882 -102.202996) (xy 229.319174 -102.212013) (xy 229.325423 -102.22893) (xy 229.331012 -102.236016)
			(xy 229.331266 -102.236016) (xy 229.331266 -102.23627) (xy 229.348899 -102.257207) (xy 229.378613 -102.303178)
			(xy 229.401451 -102.352924) (xy 229.416943 -102.405424) (xy 229.424772 -102.459599) (xy 229.425246 -102.486968)
			(xy 229.424979 -102.501954) (xy 231.856534 -102.501954) (xy 231.857023 -102.474585) (xy 231.864834 -102.420406)
			(xy 231.880318 -102.367903) (xy 231.903154 -102.318156) (xy 231.932875 -102.272188) (xy 231.950514 -102.251256)
			(xy 231.950768 -102.251002) (xy 231.956368 -102.243925) (xy 231.962605 -102.227001) (xy 231.96296 -102.217982)
			(xy 231.96296 -102.150926) (xy 231.962599 -102.141909) (xy 231.956355 -102.124992) (xy 231.950768 -102.117906)
			(xy 231.950514 -102.117906) (xy 231.950514 -102.117652) (xy 231.932829 -102.096755) (xy 231.903107 -102.050781)
			(xy 231.880265 -102.001029) (xy 231.864773 -101.948521) (xy 231.856949 -101.894338) (xy 231.856954 -101.839593)
			(xy 231.864788 -101.785411) (xy 231.880289 -101.732906) (xy 231.90314 -101.683158) (xy 231.932871 -101.637189)
			(xy 231.950514 -101.616256) (xy 231.950768 -101.616002) (xy 231.956368 -101.608925) (xy 231.962605 -101.592001)
			(xy 231.96296 -101.582982) (xy 231.96296 -101.515926) (xy 231.962599 -101.506909) (xy 231.956355 -101.489992)
			(xy 231.950768 -101.482906) (xy 231.950514 -101.482906) (xy 231.950514 -101.482652) (xy 231.932888 -101.461709)
			(xy 231.903174 -101.41574) (xy 231.880335 -101.365995) (xy 231.864841 -101.313496) (xy 231.85701 -101.259322)
			(xy 231.856534 -101.231954) (xy 231.85702 -101.204703) (xy 231.864776 -101.150755) (xy 231.880131 -101.09846)
			(xy 231.902773 -101.048883) (xy 231.932239 -101.003033) (xy 231.96793 -100.961842) (xy 232.009121 -100.926151)
			(xy 232.054971 -100.896685) (xy 232.104548 -100.874043) (xy 232.156843 -100.858688) (xy 232.210791 -100.850932)
			(xy 232.265293 -100.850932) (xy 232.319241 -100.858688) (xy 232.371536 -100.874043) (xy 232.421113 -100.896685)
			(xy 232.466963 -100.926151) (xy 232.508154 -100.961842) (xy 232.543845 -101.003033) (xy 232.573311 -101.048883)
			(xy 232.595953 -101.09846) (xy 232.611308 -101.150755) (xy 232.619064 -101.204703) (xy 232.61955 -101.231954)
			(xy 232.619069 -101.259324) (xy 232.611257 -101.313503) (xy 232.595772 -101.366006) (xy 232.572933 -101.415753)
			(xy 232.543211 -101.46172) (xy 232.52557 -101.482652) (xy 232.525316 -101.482906) (xy 232.519723 -101.489988)
			(xy 232.513479 -101.506908) (xy 232.513124 -101.515926) (xy 232.513124 -101.582982) (xy 232.513485 -101.591999)
			(xy 232.519729 -101.608916) (xy 232.525316 -101.616002) (xy 232.52557 -101.616002) (xy 232.52557 -101.616256)
			(xy 232.543166 -101.637225) (xy 232.572893 -101.683187) (xy 232.595741 -101.732927) (xy 232.611241 -101.785423)
			(xy 232.619074 -101.839597) (xy 232.619079 -101.894334) (xy 232.611256 -101.948509) (xy 232.595765 -102.001008)
			(xy 232.572926 -102.050753) (xy 232.543208 -102.096719) (xy 232.52557 -102.117652) (xy 232.525316 -102.117906)
			(xy 232.519723 -102.124988) (xy 232.513479 -102.141908) (xy 232.513124 -102.150926) (xy 232.513124 -102.201726)
			(xy 245.578374 -102.201726) (xy 245.582445 -102.146104) (xy 245.594571 -102.091667) (xy 245.614494 -102.039576)
			(xy 245.64179 -101.990941) (xy 245.675876 -101.946798) (xy 245.716025 -101.908089) (xy 245.761383 -101.875638)
			(xy 245.810983 -101.850137) (xy 245.863767 -101.83213) (xy 245.91861 -101.822) (xy 245.974344 -101.819963)
			(xy 246.029781 -101.826063) (xy 246.083738 -101.840169) (xy 246.135067 -101.861981) (xy 246.182673 -101.891035)
			(xy 246.225541 -101.92671) (xy 246.262758 -101.968247) (xy 246.293531 -102.01476) (xy 246.317203 -102.065257)
			(xy 246.333271 -102.118664) (xy 246.341391 -102.17384) (xy 246.3419 -102.201726) (xy 246.341391 -102.229612)
			(xy 246.333271 -102.284788) (xy 246.317203 -102.338195) (xy 246.293531 -102.388692) (xy 246.262758 -102.435205)
			(xy 246.225541 -102.476742) (xy 246.182673 -102.512417) (xy 246.135067 -102.541471) (xy 246.083738 -102.563283)
			(xy 246.029781 -102.577389) (xy 245.974344 -102.583489) (xy 245.91861 -102.581452) (xy 245.863767 -102.571322)
			(xy 245.810983 -102.553315) (xy 245.761383 -102.527814) (xy 245.716025 -102.495363) (xy 245.675876 -102.456654)
			(xy 245.64179 -102.412511) (xy 245.614494 -102.363876) (xy 245.594571 -102.311785) (xy 245.582445 -102.257348)
			(xy 245.578374 -102.201726) (xy 232.513124 -102.201726) (xy 232.513124 -102.217982) (xy 232.513485 -102.226999)
			(xy 232.519729 -102.243916) (xy 232.525316 -102.251002) (xy 232.52557 -102.251002) (xy 232.52557 -102.251256)
			(xy 232.543197 -102.272198) (xy 232.572912 -102.318167) (xy 232.595751 -102.367912) (xy 232.611244 -102.420411)
			(xy 232.619075 -102.474585) (xy 232.61955 -102.501954) (xy 232.619064 -102.529205) (xy 232.611308 -102.583153)
			(xy 232.595953 -102.635448) (xy 232.573311 -102.685025) (xy 232.543845 -102.730875) (xy 232.508154 -102.772066)
			(xy 232.466963 -102.807757) (xy 232.421113 -102.837223) (xy 232.371536 -102.859865) (xy 232.319241 -102.87522)
			(xy 232.265293 -102.882976) (xy 232.210791 -102.882976) (xy 232.156843 -102.87522) (xy 232.104548 -102.859865)
			(xy 232.054971 -102.837223) (xy 232.009121 -102.807757) (xy 231.96793 -102.772066) (xy 231.932239 -102.730875)
			(xy 231.902773 -102.685025) (xy 231.880131 -102.635448) (xy 231.864776 -102.583153) (xy 231.85702 -102.529205)
			(xy 231.856534 -102.501954) (xy 229.424979 -102.501954) (xy 229.42476 -102.514219) (xy 229.417004 -102.568167)
			(xy 229.401649 -102.620462) (xy 229.379007 -102.670039) (xy 229.349541 -102.715889) (xy 229.31385 -102.75708)
			(xy 229.272659 -102.792771) (xy 229.226809 -102.822237) (xy 229.177232 -102.844879) (xy 229.124937 -102.860234)
			(xy 229.070989 -102.86799) (xy 229.016487 -102.86799) (xy 228.962539 -102.860234) (xy 228.910244 -102.844879)
			(xy 228.860667 -102.822237) (xy 228.814817 -102.792771) (xy 228.773626 -102.75708) (xy 228.737935 -102.715889)
			(xy 228.708469 -102.670039) (xy 228.685827 -102.620462) (xy 228.670472 -102.568167) (xy 228.662716 -102.514219)
			(xy 228.66223 -102.486968) (xy 228.08612 -102.486968) (xy 228.08905 -102.493383) (xy 228.104409 -102.545687)
			(xy 228.112167 -102.599644) (xy 228.112167 -102.654156) (xy 228.104409 -102.708113) (xy 228.08905 -102.760417)
			(xy 228.066404 -102.810002) (xy 228.036931 -102.855859) (xy 228.001231 -102.897055) (xy 227.960032 -102.932751)
			(xy 227.914172 -102.96222) (xy 227.864585 -102.984862) (xy 227.81228 -103.000216) (xy 227.758322 -103.007969)
			(xy 227.731066 -103.00843) (xy 227.704752 -103.007976) (xy 227.652623 -103.000737) (xy 227.60198 -102.986414)
			(xy 227.553782 -102.96528) (xy 227.508938 -102.937732) (xy 227.468299 -102.904292) (xy 227.450142 -102.88524)
			(xy 227.442601 -102.877861) (xy 227.423336 -102.869322) (xy 227.412804 -102.86873) (xy 227.338128 -102.86873)
			(xy 227.327577 -102.869252) (xy 227.308281 -102.877791) (xy 227.30079 -102.88524) (xy 227.28264 -102.904301)
			(xy 227.242008 -102.937756) (xy 227.197167 -102.965313) (xy 227.148965 -102.986451) (xy 227.098317 -103.000767)
			(xy 227.046182 -103.007991) (xy 227.019866 -103.00843) (xy 226.992618 -103.007897) (xy 226.938677 -103.000137)
			(xy 226.886389 -102.98478) (xy 226.836819 -102.962139) (xy 226.790976 -102.932673) (xy 226.749792 -102.896984)
			(xy 226.714107 -102.855797) (xy 226.684645 -102.809951) (xy 226.662008 -102.760379) (xy 226.646655 -102.70809)
			(xy 226.6389 -102.654148) (xy 225.648871 -102.654148) (xy 225.652838 -102.65918) (xy 225.653092 -102.659688)
			(xy 225.664036 -102.672422) (xy 225.683877 -102.699514) (xy 225.692716 -102.71379) (xy 225.69805 -102.72268)
			(xy 225.715068 -102.734872) (xy 225.808286 -102.755192) (xy 225.82886 -102.750874) (xy 225.837496 -102.745032)
			(xy 225.861562 -102.729035) (xy 225.913492 -102.703691) (xy 225.96865 -102.686464) (xy 226.025774 -102.677749)
			(xy 226.054666 -102.677214) (xy 226.081922 -102.677631) (xy 226.13588 -102.685384) (xy 226.188185 -102.700738)
			(xy 226.237772 -102.72338) (xy 226.283632 -102.752849) (xy 226.324831 -102.788545) (xy 226.360531 -102.829741)
			(xy 226.390004 -102.875598) (xy 226.41265 -102.925183) (xy 226.428009 -102.977487) (xy 226.435767 -103.031444)
			(xy 226.435767 -103.085956) (xy 226.428009 -103.139913) (xy 226.41265 -103.192217) (xy 226.390004 -103.241802)
			(xy 226.360531 -103.287659) (xy 226.324831 -103.328855) (xy 226.283632 -103.364551) (xy 226.237772 -103.39402)
			(xy 226.188185 -103.416662) (xy 226.13588 -103.432016) (xy 226.081922 -103.439769) (xy 226.054666 -103.44023)
			(xy 226.026574 -103.439756) (xy 225.970996 -103.431525) (xy 225.917227 -103.415229) (xy 225.866429 -103.391223)
			(xy 225.819703 -103.360025) (xy 225.778058 -103.322311) (xy 225.742396 -103.278895) (xy 225.727514 -103.255064)
			(xy 225.72218 -103.246174) (xy 225.705162 -103.233982) (xy 225.611944 -103.213662) (xy 225.59137 -103.21798)
			(xy 225.582734 -103.223822) (xy 225.558664 -103.239812) (xy 225.506735 -103.265157) (xy 225.451579 -103.282385)
			(xy 225.394456 -103.291103) (xy 225.365564 -103.29164) (xy 225.338313 -103.291156) (xy 225.284367 -103.283395)
			(xy 225.232074 -103.268037) (xy 225.182499 -103.245394) (xy 225.13665 -103.215927) (xy 225.095462 -103.180236)
			(xy 225.059771 -103.139046) (xy 225.030304 -103.093197) (xy 225.007661 -103.043622) (xy 224.992304 -102.991329)
			(xy 224.984544 -102.937383) (xy 224.984056 -102.910132) (xy 200.940553 -102.910132) (xy 200.931272 -102.926642)
			(xy 200.930002 -102.935532) (xy 200.925198 -102.961601) (xy 200.909335 -103.01218) (xy 200.886625 -103.060077)
			(xy 200.857506 -103.104372) (xy 200.822538 -103.14421) (xy 200.802748 -103.161846) (xy 200.79589 -103.167434)
			(xy 200.320295 -104.013508) (xy 201.266804 -104.013508) (xy 201.270875 -103.957886) (xy 201.283001 -103.903449)
			(xy 201.302924 -103.851358) (xy 201.33022 -103.802723) (xy 201.364306 -103.75858) (xy 201.404455 -103.719871)
			(xy 201.449813 -103.68742) (xy 201.499413 -103.661919) (xy 201.552197 -103.643912) (xy 201.60704 -103.633782)
			(xy 201.662774 -103.631745) (xy 201.718211 -103.637845) (xy 201.772168 -103.651951) (xy 201.823497 -103.673763)
			(xy 201.871103 -103.702817) (xy 201.913971 -103.738492) (xy 201.951188 -103.780029) (xy 201.973405 -103.81361)
			(xy 214.526874 -103.81361) (xy 214.530945 -103.757988) (xy 214.543071 -103.703551) (xy 214.562994 -103.65146)
			(xy 214.59029 -103.602825) (xy 214.624376 -103.558682) (xy 214.664525 -103.519973) (xy 214.709883 -103.487522)
			(xy 214.759483 -103.462021) (xy 214.812267 -103.444014) (xy 214.86711 -103.433884) (xy 214.922844 -103.431847)
			(xy 214.978281 -103.437947) (xy 215.032238 -103.452053) (xy 215.083567 -103.473865) (xy 215.131173 -103.502919)
			(xy 215.172436 -103.537258) (xy 220.43085 -103.537258) (xy 220.434921 -103.481636) (xy 220.447047 -103.427199)
			(xy 220.46697 -103.375108) (xy 220.494266 -103.326473) (xy 220.528352 -103.28233) (xy 220.568501 -103.243621)
			(xy 220.613859 -103.21117) (xy 220.663459 -103.185669) (xy 220.716243 -103.167662) (xy 220.771086 -103.157532)
			(xy 220.82682 -103.155495) (xy 220.882257 -103.161595) (xy 220.936214 -103.175701) (xy 220.987543 -103.197513)
			(xy 221.035149 -103.226567) (xy 221.078017 -103.262242) (xy 221.115234 -103.303779) (xy 221.146007 -103.350292)
			(xy 221.169679 -103.400789) (xy 221.185747 -103.454196) (xy 221.193867 -103.509372) (xy 221.194376 -103.537258)
			(xy 221.193867 -103.565144) (xy 221.192925 -103.571548) (xy 246.435116 -103.571548) (xy 246.439187 -103.515926)
			(xy 246.451313 -103.461489) (xy 246.471236 -103.409398) (xy 246.498532 -103.360763) (xy 246.532618 -103.31662)
			(xy 246.572767 -103.277911) (xy 246.618125 -103.24546) (xy 246.667725 -103.219959) (xy 246.720509 -103.201952)
			(xy 246.775352 -103.191822) (xy 246.831086 -103.189785) (xy 246.886523 -103.195885) (xy 246.94048 -103.209991)
			(xy 246.991809 -103.231803) (xy 247.039415 -103.260857) (xy 247.082283 -103.296532) (xy 247.1195 -103.338069)
			(xy 247.150273 -103.384582) (xy 247.173945 -103.435079) (xy 247.190013 -103.488486) (xy 247.198133 -103.543662)
			(xy 247.198642 -103.571548) (xy 247.198133 -103.599434) (xy 247.190013 -103.65461) (xy 247.173945 -103.708017)
			(xy 247.150273 -103.758514) (xy 247.1195 -103.805027) (xy 247.082283 -103.846564) (xy 247.039415 -103.882239)
			(xy 246.991809 -103.911293) (xy 246.94048 -103.933105) (xy 246.897199 -103.94442) (xy 251.43155 -103.94442)
			(xy 251.435621 -103.888798) (xy 251.447747 -103.834361) (xy 251.46767 -103.78227) (xy 251.494966 -103.733635)
			(xy 251.529052 -103.689492) (xy 251.569201 -103.650783) (xy 251.614559 -103.618332) (xy 251.664159 -103.592831)
			(xy 251.716943 -103.574824) (xy 251.771786 -103.564694) (xy 251.82752 -103.562657) (xy 251.882957 -103.568757)
			(xy 251.936914 -103.582863) (xy 251.988243 -103.604675) (xy 252.035849 -103.633729) (xy 252.078717 -103.669404)
			(xy 252.115934 -103.710941) (xy 252.146707 -103.757454) (xy 252.170379 -103.807951) (xy 252.186447 -103.861358)
			(xy 252.194567 -103.916534) (xy 252.195076 -103.94442) (xy 252.194567 -103.972306) (xy 252.186447 -104.027482)
			(xy 252.170379 -104.080889) (xy 252.146707 -104.131386) (xy 252.115934 -104.177899) (xy 252.078717 -104.219436)
			(xy 252.035849 -104.255111) (xy 251.988243 -104.284165) (xy 251.936914 -104.305977) (xy 251.882957 -104.320083)
			(xy 251.82752 -104.326183) (xy 251.771786 -104.324146) (xy 251.716943 -104.314016) (xy 251.664159 -104.296009)
			(xy 251.614559 -104.270508) (xy 251.569201 -104.238057) (xy 251.529052 -104.199348) (xy 251.494966 -104.155205)
			(xy 251.46767 -104.10657) (xy 251.447747 -104.054479) (xy 251.435621 -104.000042) (xy 251.43155 -103.94442)
			(xy 246.897199 -103.94442) (xy 246.886523 -103.947211) (xy 246.831086 -103.953311) (xy 246.775352 -103.951274)
			(xy 246.720509 -103.941144) (xy 246.667725 -103.923137) (xy 246.618125 -103.897636) (xy 246.572767 -103.865185)
			(xy 246.532618 -103.826476) (xy 246.498532 -103.782333) (xy 246.471236 -103.733698) (xy 246.451313 -103.681607)
			(xy 246.439187 -103.62717) (xy 246.435116 -103.571548) (xy 221.192925 -103.571548) (xy 221.185747 -103.62032)
			(xy 221.169679 -103.673727) (xy 221.146007 -103.724224) (xy 221.115234 -103.770737) (xy 221.078017 -103.812274)
			(xy 221.035149 -103.847949) (xy 220.987543 -103.877003) (xy 220.936214 -103.898815) (xy 220.882257 -103.912921)
			(xy 220.82682 -103.919021) (xy 220.771086 -103.916984) (xy 220.716243 -103.906854) (xy 220.663459 -103.888847)
			(xy 220.613859 -103.863346) (xy 220.568501 -103.830895) (xy 220.528352 -103.792186) (xy 220.494266 -103.748043)
			(xy 220.46697 -103.699408) (xy 220.447047 -103.647317) (xy 220.434921 -103.59288) (xy 220.43085 -103.537258)
			(xy 215.172436 -103.537258) (xy 215.174041 -103.538594) (xy 215.211258 -103.580131) (xy 215.242031 -103.626644)
			(xy 215.265703 -103.677141) (xy 215.281771 -103.730548) (xy 215.289891 -103.785724) (xy 215.2904 -103.81361)
			(xy 215.289891 -103.841496) (xy 215.281771 -103.896672) (xy 215.265703 -103.950079) (xy 215.242031 -104.000576)
			(xy 215.211258 -104.047089) (xy 215.174041 -104.088626) (xy 215.131173 -104.124301) (xy 215.083567 -104.153355)
			(xy 215.032238 -104.175167) (xy 214.978281 -104.189273) (xy 214.922844 -104.195373) (xy 214.86711 -104.193336)
			(xy 214.812267 -104.183206) (xy 214.759483 -104.165199) (xy 214.709883 -104.139698) (xy 214.664525 -104.107247)
			(xy 214.624376 -104.068538) (xy 214.59029 -104.024395) (xy 214.562994 -103.97576) (xy 214.543071 -103.923669)
			(xy 214.530945 -103.869232) (xy 214.526874 -103.81361) (xy 201.973405 -103.81361) (xy 201.981961 -103.826542)
			(xy 202.005633 -103.877039) (xy 202.021701 -103.930446) (xy 202.029821 -103.985622) (xy 202.03033 -104.013508)
			(xy 202.029821 -104.041394) (xy 202.021701 -104.09657) (xy 202.005633 -104.149977) (xy 201.981961 -104.200474)
			(xy 201.951188 -104.246987) (xy 201.913971 -104.288524) (xy 201.871103 -104.324199) (xy 201.823497 -104.353253)
			(xy 201.772168 -104.375065) (xy 201.718211 -104.389171) (xy 201.662774 -104.395271) (xy 201.60704 -104.393234)
			(xy 201.552197 -104.383104) (xy 201.499413 -104.365097) (xy 201.449813 -104.339596) (xy 201.404455 -104.307145)
			(xy 201.364306 -104.268436) (xy 201.33022 -104.224293) (xy 201.302924 -104.175658) (xy 201.283001 -104.123567)
			(xy 201.270875 -104.06913) (xy 201.266804 -104.013508) (xy 200.320295 -104.013508) (xy 200.051015 -104.492552)
			(xy 215.414096 -104.492552) (xy 215.418167 -104.43693) (xy 215.430293 -104.382493) (xy 215.450216 -104.330402)
			(xy 215.477512 -104.281767) (xy 215.511598 -104.237624) (xy 215.551747 -104.198915) (xy 215.597105 -104.166464)
			(xy 215.646705 -104.140963) (xy 215.699489 -104.122956) (xy 215.754332 -104.112826) (xy 215.810066 -104.110789)
			(xy 215.865503 -104.116889) (xy 215.91946 -104.130995) (xy 215.970789 -104.152807) (xy 216.018395 -104.181861)
			(xy 216.061263 -104.217536) (xy 216.09848 -104.259073) (xy 216.129253 -104.305586) (xy 216.152925 -104.356083)
			(xy 216.168993 -104.40949) (xy 216.177113 -104.464666) (xy 216.177622 -104.492552) (xy 216.177113 -104.520438)
			(xy 216.168993 -104.575614) (xy 216.152925 -104.629021) (xy 216.147719 -104.640126) (xy 216.7923 -104.640126)
			(xy 216.796371 -104.584504) (xy 216.808497 -104.530067) (xy 216.82842 -104.477976) (xy 216.855716 -104.429341)
			(xy 216.889802 -104.385198) (xy 216.929951 -104.346489) (xy 216.975309 -104.314038) (xy 217.024909 -104.288537)
			(xy 217.077693 -104.27053) (xy 217.132536 -104.2604) (xy 217.18827 -104.258363) (xy 217.243707 -104.264463)
			(xy 217.297664 -104.278569) (xy 217.348993 -104.300381) (xy 217.396599 -104.329435) (xy 217.439467 -104.36511)
			(xy 217.476684 -104.406647) (xy 217.507457 -104.45316) (xy 217.531129 -104.503657) (xy 217.547197 -104.557064)
			(xy 217.550344 -104.578448) (xy 222.806304 -104.578448) (xy 222.806304 -104.523952) (xy 222.814059 -104.470012)
			(xy 222.829411 -104.417724) (xy 222.852048 -104.368153) (xy 222.881508 -104.322308) (xy 222.917193 -104.281121)
			(xy 222.958376 -104.245432) (xy 223.004218 -104.215967) (xy 223.053787 -104.193325) (xy 223.106073 -104.177968)
			(xy 223.160013 -104.170207) (xy 223.18726 -104.169718) (xy 223.21463 -104.170203) (xy 223.268808 -104.178016)
			(xy 223.321311 -104.1935) (xy 223.371058 -104.216338) (xy 223.417026 -104.246058) (xy 223.437958 -104.263698)
			(xy 223.438212 -104.263952) (xy 223.445286 -104.269556) (xy 223.462213 -104.275791) (xy 223.471232 -104.276144)
			(xy 223.538288 -104.276144) (xy 223.547306 -104.275793) (xy 223.564223 -104.269543) (xy 223.571308 -104.263952)
			(xy 223.571308 -104.263698) (xy 223.571562 -104.263698) (xy 223.592497 -104.246063) (xy 223.638469 -104.216351)
			(xy 223.688216 -104.193514) (xy 223.740716 -104.178022) (xy 223.794891 -104.170193) (xy 223.82226 -104.169718)
			(xy 223.849517 -104.170126) (xy 223.903476 -104.177879) (xy 223.955782 -104.193233) (xy 224.00537 -104.215874)
			(xy 224.051232 -104.245343) (xy 224.092432 -104.28104) (xy 224.128133 -104.322236) (xy 224.157606 -104.368094)
			(xy 224.180253 -104.417681) (xy 224.195612 -104.469985) (xy 224.203371 -104.523943) (xy 224.203371 -104.578457)
			(xy 224.195612 -104.632415) (xy 224.180253 -104.684719) (xy 224.157606 -104.734306) (xy 224.128133 -104.780164)
			(xy 224.092432 -104.82136) (xy 224.051232 -104.857057) (xy 224.00537 -104.886526) (xy 223.955782 -104.909167)
			(xy 223.903476 -104.924521) (xy 223.849517 -104.932274) (xy 223.82226 -104.932734) (xy 223.79489 -104.932249)
			(xy 223.740711 -104.924438) (xy 223.688208 -104.908954) (xy 223.638461 -104.886116) (xy 223.592494 -104.856394)
			(xy 223.571562 -104.838754) (xy 223.571308 -104.8385) (xy 223.564223 -104.832911) (xy 223.547305 -104.826666)
			(xy 223.538288 -104.826308) (xy 223.471232 -104.826308) (xy 223.462216 -104.826678) (xy 223.445299 -104.832916)
			(xy 223.438212 -104.8385) (xy 223.438212 -104.838754) (xy 223.437958 -104.838754) (xy 223.417009 -104.856372)
			(xy 223.371042 -104.886089) (xy 223.321298 -104.908929) (xy 223.268801 -104.924425) (xy 223.214628 -104.932258)
			(xy 223.18726 -104.932734) (xy 223.160013 -104.932193) (xy 223.106073 -104.924432) (xy 223.053787 -104.909075)
			(xy 223.004218 -104.886433) (xy 222.958376 -104.856968) (xy 222.917193 -104.821279) (xy 222.881508 -104.780092)
			(xy 222.852048 -104.734247) (xy 222.829411 -104.684676) (xy 222.814059 -104.632388) (xy 222.806304 -104.578448)
			(xy 217.550344 -104.578448) (xy 217.555317 -104.61224) (xy 217.555826 -104.640126) (xy 217.555317 -104.668012)
			(xy 217.547197 -104.723188) (xy 217.531129 -104.776595) (xy 217.507457 -104.827092) (xy 217.476684 -104.873605)
			(xy 217.439467 -104.915142) (xy 217.396599 -104.950817) (xy 217.348993 -104.979871) (xy 217.297664 -105.001683)
			(xy 217.243707 -105.015789) (xy 217.18827 -105.021889) (xy 217.132536 -105.019852) (xy 217.077693 -105.009722)
			(xy 217.024909 -104.991715) (xy 216.975309 -104.966214) (xy 216.929951 -104.933763) (xy 216.889802 -104.895054)
			(xy 216.855716 -104.850911) (xy 216.82842 -104.802276) (xy 216.808497 -104.750185) (xy 216.796371 -104.695748)
			(xy 216.7923 -104.640126) (xy 216.147719 -104.640126) (xy 216.129253 -104.679518) (xy 216.09848 -104.726031)
			(xy 216.061263 -104.767568) (xy 216.018395 -104.803243) (xy 215.970789 -104.832297) (xy 215.91946 -104.854109)
			(xy 215.865503 -104.868215) (xy 215.810066 -104.874315) (xy 215.754332 -104.872278) (xy 215.699489 -104.862148)
			(xy 215.646705 -104.844141) (xy 215.597105 -104.81864) (xy 215.551747 -104.786189) (xy 215.511598 -104.74748)
			(xy 215.477512 -104.703337) (xy 215.450216 -104.654702) (xy 215.430293 -104.602611) (xy 215.418167 -104.548174)
			(xy 215.414096 -104.492552) (xy 200.051015 -104.492552) (xy 199.693783 -105.12806) (xy 217.654632 -105.12806)
			(xy 217.655118 -105.100809) (xy 217.662874 -105.046861) (xy 217.678229 -104.994566) (xy 217.700871 -104.944989)
			(xy 217.730337 -104.899139) (xy 217.766028 -104.857948) (xy 217.807219 -104.822257) (xy 217.853069 -104.792791)
			(xy 217.902646 -104.770149) (xy 217.954941 -104.754794) (xy 218.008889 -104.747038) (xy 218.063391 -104.747038)
			(xy 218.117339 -104.754794) (xy 218.169634 -104.770149) (xy 218.219211 -104.792791) (xy 218.265061 -104.822257)
			(xy 218.306252 -104.857948) (xy 218.341943 -104.899139) (xy 218.371409 -104.944989) (xy 218.394051 -104.994566)
			(xy 218.409406 -105.046861) (xy 218.417162 -105.100809) (xy 218.417648 -105.12806) (xy 218.417163 -105.155052)
			(xy 218.409562 -105.208499) (xy 218.394508 -105.260343) (xy 218.372299 -105.309548) (xy 218.34338 -105.355133)
			(xy 218.326208 -105.375964) (xy 218.319096 -105.384092) (xy 218.313 -105.404666) (xy 218.323922 -105.49001)
			(xy 218.32568 -105.500559) (xy 218.336746 -105.51884) (xy 218.337029 -105.519055) (xy 222.355843 -105.519055)
			(xy 222.355843 -105.464545) (xy 222.363601 -105.410591) (xy 222.378958 -105.35829) (xy 222.401603 -105.308707)
			(xy 222.431073 -105.262852) (xy 222.46677 -105.221657) (xy 222.507966 -105.185962) (xy 222.553823 -105.156494)
			(xy 222.603407 -105.133852) (xy 222.655709 -105.118497) (xy 222.709663 -105.110742) (xy 222.736918 -105.11028)
			(xy 222.76429 -105.110716) (xy 222.818471 -105.118538) (xy 222.870975 -105.134033) (xy 222.920721 -105.156882)
			(xy 222.966686 -105.186615) (xy 222.987616 -105.20426) (xy 222.98787 -105.204514) (xy 222.99496 -105.210096)
			(xy 223.011874 -105.216345) (xy 223.02089 -105.216706) (xy 223.087946 -105.216706) (xy 223.09696 -105.216322)
			(xy 223.113877 -105.210093) (xy 223.120966 -105.204514) (xy 223.120966 -105.20426) (xy 223.12122 -105.20426)
			(xy 223.142166 -105.186638) (xy 223.188136 -105.156925) (xy 223.23788 -105.134086) (xy 223.290377 -105.118591)
			(xy 223.34455 -105.110757) (xy 223.371918 -105.11028) (xy 223.399168 -105.110791) (xy 223.453112 -105.11855)
			(xy 223.505402 -105.133906) (xy 223.554976 -105.156547) (xy 223.600822 -105.186013) (xy 223.642009 -105.221704)
			(xy 223.677698 -105.262892) (xy 223.707161 -105.30874) (xy 223.7298 -105.358314) (xy 223.745154 -105.410606)
			(xy 223.75291 -105.46455) (xy 223.75291 -105.51905) (xy 223.745154 -105.572994) (xy 223.7298 -105.625286)
			(xy 223.707161 -105.67486) (xy 223.677698 -105.720708) (xy 223.642009 -105.761896) (xy 223.600822 -105.797587)
			(xy 223.554976 -105.827053) (xy 223.505402 -105.849694) (xy 223.453112 -105.86505) (xy 223.399168 -105.872809)
			(xy 223.371918 -105.873296) (xy 223.344548 -105.87282) (xy 223.290369 -105.865005) (xy 223.237866 -105.849518)
			(xy 223.188119 -105.826679) (xy 223.142152 -105.796956) (xy 223.12122 -105.779316) (xy 223.120966 -105.779062)
			(xy 223.113868 -105.773493) (xy 223.09696 -105.767237) (xy 223.087946 -105.76687) (xy 223.02089 -105.76687)
			(xy 223.011873 -105.767229) (xy 222.994957 -105.773476) (xy 222.98787 -105.779062) (xy 222.98787 -105.779316)
			(xy 222.987616 -105.779316) (xy 222.966691 -105.796964) (xy 222.920716 -105.826674) (xy 222.870967 -105.849508)
			(xy 222.818464 -105.864997) (xy 222.764288 -105.872823) (xy 222.736918 -105.873296) (xy 222.709663 -105.872858)
			(xy 222.655709 -105.865103) (xy 222.603407 -105.849748) (xy 222.553823 -105.827106) (xy 222.507966 -105.797638)
			(xy 222.46677 -105.761943) (xy 222.431073 -105.720748) (xy 222.401603 -105.674893) (xy 222.378958 -105.62531)
			(xy 222.363601 -105.573009) (xy 222.355843 -105.519055) (xy 218.337029 -105.519055) (xy 218.345258 -105.525316)
			(xy 218.369563 -105.542923) (xy 218.41282 -105.584522) (xy 218.431364 -105.60812) (xy 218.437206 -105.615994)
			(xy 218.454732 -105.626408) (xy 218.545156 -105.639616) (xy 218.56446 -105.63479) (xy 218.572334 -105.628948)
			(xy 218.572588 -105.628948) (xy 218.597318 -105.611424) (xy 218.651176 -105.583625) (xy 218.708752 -105.564695)
			(xy 218.768598 -105.555109) (xy 218.798902 -105.554526) (xy 218.826156 -105.554954) (xy 218.88011 -105.562712)
			(xy 218.932411 -105.57807) (xy 218.981993 -105.600715) (xy 219.027848 -105.630186) (xy 219.069042 -105.665884)
			(xy 219.104735 -105.707081) (xy 219.134202 -105.752938) (xy 219.156843 -105.802523) (xy 219.172196 -105.854825)
			(xy 219.179949 -105.90878) (xy 219.18041 -105.936034) (xy 219.179985 -105.962068) (xy 219.172893 -106.013652)
			(xy 219.158859 -106.063794) (xy 219.138143 -106.111565) (xy 219.111129 -106.156079) (xy 219.095066 -106.176572)
			(xy 219.089322 -106.184327) (xy 219.083584 -106.202739) (xy 219.08389 -106.212386) (xy 219.09024 -106.292142)
			(xy 219.098876 -106.309922) (xy 219.106242 -106.316272) (xy 219.125887 -106.334454) (xy 219.160411 -106.37536)
			(xy 219.188882 -106.420688) (xy 219.21074 -106.46955) (xy 219.225557 -106.520986) (xy 219.233042 -106.573988)
			(xy 219.233496 -106.600752) (xy 219.233 -106.628004) (xy 219.225249 -106.681955) (xy 219.209899 -106.734253)
			(xy 219.187261 -106.783833) (xy 219.157797 -106.829687) (xy 219.122106 -106.870881) (xy 219.080916 -106.906575)
			(xy 219.035065 -106.936044) (xy 218.985486 -106.958686) (xy 218.93319 -106.974042) (xy 218.87924 -106.981797)
			(xy 218.851988 -106.98226) (xy 218.823214 -106.981747) (xy 218.76632 -106.973091) (xy 218.71137 -106.955991)
			(xy 218.65961 -106.930835) (xy 218.612213 -106.898194) (xy 218.590876 -106.878882) (xy 218.583002 -106.871516)
			(xy 218.56319 -106.864404) (xy 218.466924 -106.87177) (xy 218.448128 -106.881676) (xy 218.441524 -106.890058)
			(xy 218.42332 -106.91226) (xy 218.381381 -106.95147) (xy 218.334041 -106.983954) (xy 218.282369 -107.00898)
			(xy 218.227531 -107.025982) (xy 218.170765 -107.034577) (xy 218.142058 -107.035092) (xy 218.114805 -107.034661)
			(xy 218.060854 -107.026899) (xy 218.008558 -107.011537) (xy 217.958979 -106.98889) (xy 217.913128 -106.959418)
			(xy 217.871938 -106.923721) (xy 217.836247 -106.882525) (xy 217.806782 -106.83667) (xy 217.784142 -106.787088)
			(xy 217.768789 -106.734789) (xy 217.761035 -106.680837) (xy 217.76055 -106.653584) (xy 217.761021 -106.626682)
			(xy 217.768594 -106.573413) (xy 217.783573 -106.521736) (xy 217.805662 -106.472675) (xy 217.834423 -106.427203)
			(xy 217.869285 -106.386221) (xy 217.909558 -106.350541) (xy 217.931746 -106.335322) (xy 217.942668 -106.32821)
			(xy 217.954606 -106.30535) (xy 217.952574 -106.193082) (xy 217.93962 -106.17073) (xy 217.928444 -106.163872)
			(xy 217.904851 -106.148937) (xy 217.861897 -106.113262) (xy 217.824601 -106.071707) (xy 217.793762 -106.02516)
			(xy 217.770037 -105.974614) (xy 217.753934 -105.921149) (xy 217.745796 -105.865908) (xy 217.74531 -105.83799)
			(xy 217.745776 -105.810997) (xy 217.753383 -105.75755) (xy 217.768442 -105.705707) (xy 217.790655 -105.656502)
			(xy 217.819577 -105.610917) (xy 217.83675 -105.590086) (xy 217.843862 -105.581958) (xy 217.849958 -105.561384)
			(xy 217.839036 -105.47604) (xy 217.837233 -105.465503) (xy 217.826198 -105.447218) (xy 217.8177 -105.440734)
			(xy 217.79648 -105.425367) (xy 217.758029 -105.38978) (xy 217.724811 -105.349265) (xy 217.697452 -105.304585)
			(xy 217.676467 -105.256579) (xy 217.66225 -105.206153) (xy 217.65507 -105.154256) (xy 217.654632 -105.12806)
			(xy 199.693783 -105.12806) (xy 199.55129 -105.381552) (xy 199.552306 -105.390188) (xy 199.572372 -105.413302)
			(xy 199.590015 -105.434233) (xy 199.619743 -105.480199) (xy 199.642588 -105.529945) (xy 199.658079 -105.582449)
			(xy 199.665898 -105.636629) (xy 199.666352 -105.664) (xy 199.665866 -105.691252) (xy 199.65811 -105.745202)
			(xy 199.642755 -105.7975) (xy 199.620115 -105.84708) (xy 199.590649 -105.892933) (xy 199.554958 -105.934127)
			(xy 199.513769 -105.969823) (xy 199.467918 -105.999294) (xy 199.418341 -106.02194) (xy 199.366046 -106.037301)
			(xy 199.312096 -106.045063) (xy 199.284844 -106.045508) (xy 199.28332 -106.045508) (xy 199.266531 -106.045336)
			(xy 199.233082 -106.04241) (xy 199.216518 -106.039666) (xy 199.212962 -106.039158) (xy 199.203056 -106.03738)
			(xy 199.202548 -106.03738) (xy 199.197217 -106.036992) (xy 199.186592 -106.03815) (xy 199.181466 -106.039666)
			(xy 199.010524 -106.343704) (xy 199.00872 -106.347315) (xy 199.006172 -106.354973) (xy 199.005444 -106.358944)
			(xy 198.874684 -107.41152) (xy 221.678754 -107.41152) (xy 221.679217 -107.385206) (xy 221.686451 -107.333076)
			(xy 221.700769 -107.282433) (xy 221.721902 -107.234233) (xy 221.74945 -107.18939) (xy 221.782891 -107.148752)
			(xy 221.801944 -107.130596) (xy 221.809341 -107.12307) (xy 221.81787 -107.103794) (xy 221.818454 -107.093258)
			(xy 221.818454 -107.018582) (xy 221.817907 -107.008034) (xy 221.809386 -106.988738) (xy 221.801944 -106.981244)
			(xy 221.782858 -106.96312) (xy 221.749405 -106.922482) (xy 221.721852 -106.877635) (xy 221.700719 -106.829428)
			(xy 221.686408 -106.778776) (xy 221.679189 -106.726638) (xy 221.678754 -106.70032) (xy 221.679297 -106.673071)
			(xy 221.68705 -106.619127) (xy 221.7024 -106.566836) (xy 221.725036 -106.517261) (xy 221.754497 -106.471413)
			(xy 221.790182 -106.430223) (xy 221.831366 -106.394532) (xy 221.877211 -106.365064) (xy 221.926782 -106.34242)
			(xy 221.979071 -106.327062) (xy 222.033013 -106.319301) (xy 222.060262 -106.318812) (xy 222.087926 -106.319348)
			(xy 222.142675 -106.327343) (xy 222.195696 -106.343155) (xy 222.24588 -106.366454) (xy 222.292176 -106.396751)
			(xy 222.333615 -106.433413) (xy 222.369328 -106.475672) (xy 222.384366 -106.498898) (xy 222.391031 -106.508552)
			(xy 222.410871 -106.52101) (xy 222.422466 -106.522774) (xy 222.502476 -106.530648) (xy 222.514114 -106.531258)
			(xy 222.53595 -106.523193) (xy 222.544386 -106.515154) (xy 222.54464 -106.5149) (xy 222.562719 -106.496317)
			(xy 222.603052 -106.463739) (xy 222.647426 -106.436926) (xy 222.695025 -106.416374) (xy 222.74497 -106.402461)
			(xy 222.796339 -106.395444) (xy 222.822262 -106.395012) (xy 222.849515 -106.395491) (xy 222.903466 -106.403243)
			(xy 222.955765 -106.418595) (xy 223.005346 -106.441235) (xy 223.051201 -106.470701) (xy 223.092394 -106.506393)
			(xy 223.128089 -106.547585) (xy 223.157557 -106.593438) (xy 223.180198 -106.643018) (xy 223.195553 -106.695316)
			(xy 223.203308 -106.749267) (xy 223.20377 -106.77652) (xy 223.203323 -106.803891) (xy 223.195502 -106.858071)
			(xy 223.180009 -106.910575) (xy 223.157162 -106.960321) (xy 223.127433 -107.006287) (xy 223.10979 -107.027218)
			(xy 223.109536 -107.027472) (xy 223.103947 -107.034557) (xy 223.097704 -107.051475) (xy 223.097344 -107.060492)
			(xy 223.097344 -107.127548) (xy 223.097716 -107.136564) (xy 223.103952 -107.153481) (xy 223.109536 -107.160568)
			(xy 223.10979 -107.160568) (xy 223.10979 -107.160822) (xy 223.127404 -107.181774) (xy 223.15712 -107.227741)
			(xy 223.179961 -107.277484) (xy 223.195458 -107.32998) (xy 223.203293 -107.384152) (xy 223.20377 -107.41152)
			(xy 223.203364 -107.438775) (xy 223.195603 -107.49273) (xy 223.180242 -107.545031) (xy 223.157595 -107.594614)
			(xy 223.128121 -107.640469) (xy 223.092421 -107.681663) (xy 223.051223 -107.717356) (xy 223.005363 -107.746823)
			(xy 222.955777 -107.769463) (xy 222.903473 -107.784815) (xy 222.849517 -107.792568) (xy 222.822262 -107.793028)
			(xy 222.793345 -107.792492) (xy 222.736174 -107.783771) (xy 222.680974 -107.766518) (xy 222.629012 -107.74113)
			(xy 222.581478 -107.708188) (xy 222.539462 -107.668447) (xy 222.521272 -107.645962) (xy 222.513674 -107.637146)
			(xy 222.492766 -107.626969) (xy 222.48114 -107.626404) (xy 222.401384 -107.626404) (xy 222.389753 -107.626947)
			(xy 222.368843 -107.637133) (xy 222.361252 -107.645962) (xy 222.343022 -107.668413) (xy 222.301012 -107.708152)
			(xy 222.253485 -107.741096) (xy 222.201531 -107.76649) (xy 222.14634 -107.783753) (xy 222.089176 -107.792489)
			(xy 222.060262 -107.793028) (xy 222.033011 -107.792558) (xy 221.979063 -107.784796) (xy 221.92677 -107.769437)
			(xy 221.877194 -107.746793) (xy 221.831344 -107.717325) (xy 221.790155 -107.681632) (xy 221.754464 -107.640441)
			(xy 221.724998 -107.594591) (xy 221.702356 -107.545013) (xy 221.687 -107.492719) (xy 221.679241 -107.438771)
			(xy 221.678754 -107.41152) (xy 198.874684 -107.41152) (xy 198.796083 -108.044234) (xy 198.958708 -108.044234)
			(xy 198.959194 -108.016983) (xy 198.96695 -107.963035) (xy 198.982305 -107.91074) (xy 199.004947 -107.861163)
			(xy 199.034413 -107.815313) (xy 199.070104 -107.774122) (xy 199.111295 -107.738431) (xy 199.157145 -107.708965)
			(xy 199.206722 -107.686323) (xy 199.259017 -107.670968) (xy 199.312965 -107.663212) (xy 199.367467 -107.663212)
			(xy 199.421415 -107.670968) (xy 199.47371 -107.686323) (xy 199.523287 -107.708965) (xy 199.569137 -107.738431)
			(xy 199.610328 -107.774122) (xy 199.646019 -107.815313) (xy 199.659475 -107.836251) (xy 233.797585 -107.836251)
			(xy 233.797585 -107.781749) (xy 233.805342 -107.727802) (xy 233.820697 -107.675508) (xy 233.843337 -107.625932)
			(xy 233.872803 -107.580082) (xy 233.908494 -107.538893) (xy 233.949684 -107.503202) (xy 233.995534 -107.473737)
			(xy 234.04511 -107.451096) (xy 234.097404 -107.435741) (xy 234.151351 -107.427985) (xy 234.178602 -107.427522)
			(xy 234.204916 -107.427981) (xy 234.257045 -107.435217) (xy 234.307689 -107.449537) (xy 234.355888 -107.470671)
			(xy 234.400731 -107.498219) (xy 234.44137 -107.531659) (xy 234.459526 -107.550712) (xy 234.467034 -107.558129)
			(xy 234.486325 -107.566644) (xy 234.496864 -107.567222) (xy 234.57154 -107.567222) (xy 234.582087 -107.566667)
			(xy 234.601382 -107.558149) (xy 234.608878 -107.550712) (xy 234.628698 -107.529924) (xy 234.67347 -107.493949)
			(xy 234.723128 -107.465089) (xy 234.77655 -107.443996) (xy 234.832529 -107.431147) (xy 234.889802 -107.426832)
			(xy 234.947075 -107.431147) (xy 235.003054 -107.443996) (xy 235.056476 -107.465089) (xy 235.106134 -107.493949)
			(xy 235.150906 -107.529924) (xy 235.170726 -107.550712) (xy 235.178234 -107.558129) (xy 235.197525 -107.566644)
			(xy 235.208064 -107.567222) (xy 235.28274 -107.567222) (xy 235.293287 -107.566667) (xy 235.312582 -107.558149)
			(xy 235.320078 -107.550712) (xy 235.338254 -107.531676) (xy 235.378879 -107.498217) (xy 235.423715 -107.470655)
			(xy 235.471912 -107.449513) (xy 235.522556 -107.435192) (xy 235.574687 -107.427963) (xy 235.601002 -107.427522)
			(xy 235.628255 -107.427948) (xy 235.682207 -107.435705) (xy 235.734506 -107.451062) (xy 235.784087 -107.473705)
			(xy 235.82994 -107.503174) (xy 235.871134 -107.538868) (xy 235.906828 -107.580061) (xy 235.936296 -107.625915)
			(xy 235.958939 -107.675496) (xy 235.974295 -107.727795) (xy 235.982052 -107.781747) (xy 235.982052 -107.836253)
			(xy 235.974295 -107.890205) (xy 235.958939 -107.942504) (xy 235.936296 -107.992085) (xy 235.906828 -108.037939)
			(xy 235.871134 -108.079132) (xy 235.82994 -108.114826) (xy 235.784087 -108.144295) (xy 235.734506 -108.166938)
			(xy 235.682207 -108.182295) (xy 235.628255 -108.190052) (xy 235.601002 -108.190538) (xy 235.574687 -108.190089)
			(xy 235.522557 -108.182853) (xy 235.471913 -108.168532) (xy 235.423714 -108.147396) (xy 235.378871 -108.119846)
			(xy 235.338233 -108.086402) (xy 235.320078 -108.067348) (xy 235.31256 -108.059942) (xy 235.293278 -108.051419)
			(xy 235.28274 -108.050838) (xy 235.208064 -108.050838) (xy 235.197515 -108.051377) (xy 235.178219 -108.059904)
			(xy 235.170726 -108.067348) (xy 235.150906 -108.088136) (xy 235.106134 -108.124111) (xy 235.056476 -108.152971)
			(xy 235.003054 -108.174064) (xy 234.947075 -108.186913) (xy 234.889802 -108.191228) (xy 234.832529 -108.186913)
			(xy 234.77655 -108.174064) (xy 234.723128 -108.152971) (xy 234.67347 -108.124111) (xy 234.628698 -108.088136)
			(xy 234.608878 -108.067348) (xy 234.60136 -108.059942) (xy 234.582078 -108.051419) (xy 234.57154 -108.050838)
			(xy 234.496864 -108.050838) (xy 234.486315 -108.051377) (xy 234.467019 -108.059904) (xy 234.459526 -108.067348)
			(xy 234.44136 -108.086393) (xy 234.400732 -108.119849) (xy 234.355893 -108.147409) (xy 234.307695 -108.168548)
			(xy 234.257049 -108.182868) (xy 234.204917 -108.190097) (xy 234.178602 -108.190538) (xy 234.151351 -108.190015)
			(xy 234.097404 -108.182259) (xy 234.04511 -108.166904) (xy 233.995534 -108.144263) (xy 233.949684 -108.114798)
			(xy 233.908494 -108.079107) (xy 233.872803 -108.037918) (xy 233.843337 -107.992068) (xy 233.820697 -107.942492)
			(xy 233.805342 -107.890198) (xy 233.797585 -107.836251) (xy 199.659475 -107.836251) (xy 199.675485 -107.861163)
			(xy 199.698127 -107.91074) (xy 199.713482 -107.963035) (xy 199.721238 -108.016983) (xy 199.721724 -108.044234)
			(xy 199.721188 -108.071805) (xy 199.713246 -108.126373) (xy 199.697531 -108.17923) (xy 199.674372 -108.229273)
			(xy 199.644251 -108.275463) (xy 199.607794 -108.316835) (xy 199.565762 -108.352529) (xy 199.542654 -108.367576)
			(xy 199.530079 -108.376034) (xy 199.510215 -108.398904) (xy 199.497933 -108.426595) (xy 199.494314 -108.45667)
			(xy 199.49726 -108.473054) (xy 221.556763 -108.473054) (xy 221.556763 -108.418546) (xy 221.564521 -108.364593)
			(xy 221.579879 -108.312294) (xy 221.602523 -108.262713) (xy 221.631994 -108.216859) (xy 221.66769 -108.175666)
			(xy 221.708886 -108.139973) (xy 221.754742 -108.110507) (xy 221.804326 -108.087867) (xy 221.856627 -108.072514)
			(xy 221.91058 -108.064761) (xy 221.937834 -108.0643) (xy 221.965205 -108.064746) (xy 222.019385 -108.072569)
			(xy 222.071888 -108.088063) (xy 222.121635 -108.110909) (xy 222.167601 -108.140637) (xy 222.188532 -108.15828)
			(xy 222.188786 -108.158534) (xy 222.19587 -108.164125) (xy 222.212789 -108.170368) (xy 222.221806 -108.170726)
			(xy 222.288862 -108.170726) (xy 222.297876 -108.170345) (xy 222.314793 -108.164114) (xy 222.321882 -108.158534)
			(xy 222.321882 -108.15828) (xy 222.322136 -108.15828) (xy 222.343069 -108.140639) (xy 222.389037 -108.110915)
			(xy 222.438783 -108.088069) (xy 222.491285 -108.072573) (xy 222.545463 -108.064744) (xy 222.600205 -108.064744)
			(xy 222.654383 -108.072573) (xy 222.706885 -108.088069) (xy 222.756631 -108.110915) (xy 222.802599 -108.140639)
			(xy 222.823532 -108.15828) (xy 222.823786 -108.158534) (xy 222.83087 -108.164125) (xy 222.847789 -108.170368)
			(xy 222.856806 -108.170726) (xy 222.923862 -108.170726) (xy 222.932876 -108.170345) (xy 222.949793 -108.164114)
			(xy 222.956882 -108.158534) (xy 222.956882 -108.15828) (xy 222.957136 -108.15828) (xy 222.978069 -108.140639)
			(xy 223.024037 -108.110915) (xy 223.073783 -108.088069) (xy 223.126285 -108.072573) (xy 223.180463 -108.064744)
			(xy 223.235205 -108.064744) (xy 223.289383 -108.072573) (xy 223.341885 -108.088069) (xy 223.391631 -108.110915)
			(xy 223.437599 -108.140639) (xy 223.458532 -108.15828) (xy 223.458786 -108.158534) (xy 223.46587 -108.164125)
			(xy 223.482789 -108.170368) (xy 223.491806 -108.170726) (xy 223.558862 -108.170726) (xy 223.567876 -108.170345)
			(xy 223.584793 -108.164114) (xy 223.591882 -108.158534) (xy 223.591882 -108.15828) (xy 223.592136 -108.15828)
			(xy 223.613079 -108.140654) (xy 223.659049 -108.110941) (xy 223.708794 -108.088103) (xy 223.761292 -108.072609)
			(xy 223.815466 -108.064776) (xy 223.842834 -108.0643) (xy 223.870084 -108.064772) (xy 223.924029 -108.072533)
			(xy 223.976321 -108.087891) (xy 224.025895 -108.110535) (xy 224.071742 -108.140002) (xy 224.112929 -108.175695)
			(xy 224.148618 -108.216885) (xy 224.178082 -108.262735) (xy 224.200721 -108.312311) (xy 224.216075 -108.364604)
			(xy 224.22383 -108.41855) (xy 224.22383 -108.47305) (xy 224.216075 -108.526996) (xy 224.200721 -108.579289)
			(xy 224.18663 -108.610146) (xy 245.158768 -108.610146) (xy 245.159298 -108.582895) (xy 245.167048 -108.528948)
			(xy 245.182397 -108.476653) (xy 245.205032 -108.427075) (xy 245.234493 -108.381222) (xy 245.27018 -108.34003)
			(xy 245.311366 -108.304335) (xy 245.357213 -108.274866) (xy 245.406787 -108.252222) (xy 245.45908 -108.236863)
			(xy 245.513025 -108.229103) (xy 245.540276 -108.228638) (xy 245.568957 -108.229202) (xy 245.625669 -108.237809)
			(xy 245.680456 -108.254802) (xy 245.732084 -108.2798) (xy 245.779392 -108.312239) (xy 245.821316 -108.351389)
			(xy 245.856911 -108.396371) (xy 245.885378 -108.446171) (xy 245.906074 -108.499669) (xy 245.918535 -108.55566)
			(xy 245.921022 -108.584238) (xy 245.922507 -108.59876) (xy 245.93262 -108.626129) (xy 245.950059 -108.649522)
			(xy 245.973399 -108.667031) (xy 246.000737 -108.677228) (xy 246.015256 -108.678726) (xy 246.043842 -108.681195)
			(xy 246.099854 -108.693625) (xy 246.153373 -108.7143) (xy 246.203194 -108.742756) (xy 246.248193 -108.778351)
			(xy 246.287354 -108.820282) (xy 246.319797 -108.867604) (xy 246.344788 -108.91925) (xy 246.361765 -108.974055)
			(xy 246.370345 -109.030785) (xy 246.370856 -109.059472) (xy 246.370296 -109.08672) (xy 246.362544 -109.140663)
			(xy 246.347195 -109.192953) (xy 246.324561 -109.242527) (xy 246.308516 -109.267498) (xy 246.461786 -109.267498)
			(xy 246.465857 -109.211876) (xy 246.477983 -109.157439) (xy 246.497906 -109.105348) (xy 246.525202 -109.056713)
			(xy 246.559288 -109.01257) (xy 246.599437 -108.973861) (xy 246.644795 -108.94141) (xy 246.694395 -108.915909)
			(xy 246.747179 -108.897902) (xy 246.802022 -108.887772) (xy 246.857756 -108.885735) (xy 246.913193 -108.891835)
			(xy 246.96715 -108.905941) (xy 247.018479 -108.927753) (xy 247.066085 -108.956807) (xy 247.108953 -108.992482)
			(xy 247.14617 -109.034019) (xy 247.176943 -109.080532) (xy 247.200615 -109.131029) (xy 247.216683 -109.184436)
			(xy 247.224803 -109.239612) (xy 247.225312 -109.267498) (xy 247.224803 -109.295384) (xy 247.216683 -109.35056)
			(xy 247.200615 -109.403967) (xy 247.176943 -109.454464) (xy 247.14617 -109.500977) (xy 247.108953 -109.542514)
			(xy 247.066085 -109.578189) (xy 247.018479 -109.607243) (xy 246.96715 -109.629055) (xy 246.913193 -109.643161)
			(xy 246.857756 -109.649261) (xy 246.802022 -109.647224) (xy 246.747179 -109.637094) (xy 246.694395 -109.619087)
			(xy 246.644795 -109.593586) (xy 246.599437 -109.561135) (xy 246.559288 -109.522426) (xy 246.525202 -109.478283)
			(xy 246.497906 -109.429648) (xy 246.477983 -109.377557) (xy 246.465857 -109.32312) (xy 246.461786 -109.267498)
			(xy 246.308516 -109.267498) (xy 246.295102 -109.288375) (xy 246.259418 -109.329565) (xy 246.218236 -109.365256)
			(xy 246.172394 -109.394724) (xy 246.122825 -109.417369) (xy 246.070537 -109.432728) (xy 246.016596 -109.44049)
			(xy 245.989348 -109.44098) (xy 245.960666 -109.440469) (xy 245.903953 -109.431852) (xy 245.849166 -109.41485)
			(xy 245.797538 -109.389845) (xy 245.750231 -109.357399) (xy 245.708309 -109.318243) (xy 245.672714 -109.273257)
			(xy 245.644249 -109.223454) (xy 245.623552 -109.169953) (xy 245.611089 -109.113959) (xy 245.608602 -109.08538)
			(xy 245.607171 -109.070849) (xy 245.597053 -109.043471) (xy 245.579603 -109.020073) (xy 245.556247 -109.002566)
			(xy 245.528894 -108.992381) (xy 245.514368 -108.990892) (xy 245.485786 -108.988385) (xy 245.429776 -108.975959)
			(xy 245.376258 -108.955288) (xy 245.326438 -108.926836) (xy 245.28144 -108.891246) (xy 245.242278 -108.849319)
			(xy 245.209834 -108.802002) (xy 245.184842 -108.75036) (xy 245.167863 -108.695558) (xy 245.159281 -108.638832)
			(xy 245.158768 -108.610146) (xy 224.18663 -108.610146) (xy 224.178082 -108.628865) (xy 224.148618 -108.674715)
			(xy 224.112929 -108.715905) (xy 224.071742 -108.751598) (xy 224.025895 -108.781065) (xy 223.976321 -108.803709)
			(xy 223.924029 -108.819067) (xy 223.870084 -108.826828) (xy 223.842834 -108.827316) (xy 223.815464 -108.82685)
			(xy 223.761284 -108.819036) (xy 223.70878 -108.803548) (xy 223.659033 -108.780705) (xy 223.613067 -108.750979)
			(xy 223.592136 -108.733336) (xy 223.591882 -108.733082) (xy 223.584806 -108.72748) (xy 223.567881 -108.721243)
			(xy 223.558862 -108.72089) (xy 223.491806 -108.72089) (xy 223.48279 -108.721252) (xy 223.465873 -108.727496)
			(xy 223.458786 -108.733082) (xy 223.458532 -108.733336) (xy 223.437599 -108.750977) (xy 223.391631 -108.780701)
			(xy 223.341885 -108.803547) (xy 223.289383 -108.819043) (xy 223.235205 -108.826872) (xy 223.180463 -108.826872)
			(xy 223.126285 -108.819043) (xy 223.073783 -108.803547) (xy 223.024037 -108.780701) (xy 222.978069 -108.750977)
			(xy 222.957136 -108.733336) (xy 222.956882 -108.733082) (xy 222.949806 -108.72748) (xy 222.932881 -108.721243)
			(xy 222.923862 -108.72089) (xy 222.856806 -108.72089) (xy 222.84779 -108.721252) (xy 222.830873 -108.727496)
			(xy 222.823786 -108.733082) (xy 222.823786 -108.733336) (xy 222.823532 -108.733336) (xy 222.802599 -108.750977)
			(xy 222.756631 -108.780701) (xy 222.706885 -108.803547) (xy 222.654383 -108.819043) (xy 222.600205 -108.826872)
			(xy 222.545463 -108.826872) (xy 222.491285 -108.819043) (xy 222.438783 -108.803547) (xy 222.389037 -108.780701)
			(xy 222.343069 -108.750977) (xy 222.322136 -108.733336) (xy 222.321882 -108.733082) (xy 222.314806 -108.72748)
			(xy 222.297881 -108.721243) (xy 222.288862 -108.72089) (xy 222.221806 -108.72089) (xy 222.21279 -108.721252)
			(xy 222.195873 -108.727496) (xy 222.188786 -108.733082) (xy 222.188786 -108.733336) (xy 222.188532 -108.733336)
			(xy 222.167603 -108.750979) (xy 222.121629 -108.780689) (xy 222.071881 -108.803524) (xy 222.019379 -108.819014)
			(xy 221.965203 -108.826842) (xy 221.937834 -108.827316) (xy 221.91058 -108.826839) (xy 221.856627 -108.819086)
			(xy 221.804326 -108.803733) (xy 221.754742 -108.781093) (xy 221.708886 -108.751627) (xy 221.66769 -108.715934)
			(xy 221.631994 -108.674741) (xy 221.602523 -108.628887) (xy 221.579879 -108.579306) (xy 221.564521 -108.527007)
			(xy 221.556763 -108.473054) (xy 199.49726 -108.473054) (xy 199.499675 -108.486484) (xy 199.513547 -108.513414)
			(xy 199.534707 -108.53509) (xy 199.547734 -108.542836) (xy 199.573125 -108.557309) (xy 199.619559 -108.592795)
			(xy 199.660042 -108.634944) (xy 199.693626 -108.682772) (xy 199.719528 -108.73516) (xy 199.737142 -108.790884)
			(xy 199.746056 -108.848641) (xy 199.746616 -108.877862) (xy 199.74613 -108.905113) (xy 199.738374 -108.959061)
			(xy 199.723019 -109.011356) (xy 199.700377 -109.060933) (xy 199.670911 -109.106783) (xy 199.63522 -109.147974)
			(xy 199.594029 -109.183665) (xy 199.548179 -109.213131) (xy 199.498602 -109.235773) (xy 199.446307 -109.251128)
			(xy 199.392359 -109.258884) (xy 199.337857 -109.258884) (xy 199.283909 -109.251128) (xy 199.231614 -109.235773)
			(xy 199.182037 -109.213131) (xy 199.136187 -109.183665) (xy 199.094996 -109.147974) (xy 199.059305 -109.106783)
			(xy 199.029839 -109.060933) (xy 199.007197 -109.011356) (xy 198.991842 -108.959061) (xy 198.984086 -108.905113)
			(xy 198.9836 -108.877862) (xy 198.984122 -108.85029) (xy 198.992065 -108.795721) (xy 199.007781 -108.742864)
			(xy 199.030943 -108.692819) (xy 199.061066 -108.64663) (xy 199.097525 -108.605259) (xy 199.13956 -108.569566)
			(xy 199.16267 -108.55452) (xy 199.175246 -108.546064) (xy 199.195105 -108.523192) (xy 199.207383 -108.495502)
			(xy 199.211001 -108.465428) (xy 199.20564 -108.435615) (xy 199.191772 -108.408686) (xy 199.170615 -108.387008)
			(xy 199.15759 -108.37926) (xy 199.132203 -108.36478) (xy 199.085768 -108.329297) (xy 199.045284 -108.287149)
			(xy 199.011698 -108.239323) (xy 198.985795 -108.186935) (xy 198.968181 -108.131212) (xy 198.959268 -108.073455)
			(xy 198.958708 -108.044234) (xy 198.796083 -108.044234) (xy 198.474642 -110.631732) (xy 209.194654 -110.631732)
			(xy 209.195149 -110.602992) (xy 209.20378 -110.546164) (xy 209.220838 -110.491273) (xy 209.245935 -110.439562)
			(xy 209.278505 -110.392201) (xy 209.297778 -110.370874) (xy 209.304382 -110.364016) (xy 209.311494 -110.345982)
			(xy 209.311494 -110.257082) (xy 209.304382 -110.239048) (xy 209.297778 -110.23219) (xy 209.278541 -110.210835)
			(xy 209.245979 -110.163476) (xy 209.220888 -110.111768) (xy 209.203838 -110.056882) (xy 209.195214 -110.00006)
			(xy 209.19521 -109.942587) (xy 209.203828 -109.885763) (xy 209.220871 -109.830875) (xy 209.245955 -109.779165)
			(xy 209.278512 -109.731802) (xy 209.297778 -109.710474) (xy 209.304382 -109.703616) (xy 209.311494 -109.685582)
			(xy 209.311494 -109.596682) (xy 209.304382 -109.578648) (xy 209.297778 -109.57179) (xy 209.278529 -109.550444)
			(xy 209.245958 -109.503088) (xy 209.220861 -109.451381) (xy 209.203805 -109.396494) (xy 209.195177 -109.33967)
			(xy 209.194654 -109.310932) (xy 209.19514 -109.283681) (xy 209.202896 -109.229733) (xy 209.218251 -109.177438)
			(xy 209.240893 -109.127861) (xy 209.270359 -109.082011) (xy 209.30605 -109.04082) (xy 209.347241 -109.005129)
			(xy 209.393091 -108.975663) (xy 209.442668 -108.953021) (xy 209.494963 -108.937666) (xy 209.548911 -108.92991)
			(xy 209.603413 -108.92991) (xy 209.657361 -108.937666) (xy 209.709656 -108.953021) (xy 209.759233 -108.975663)
			(xy 209.805083 -109.005129) (xy 209.846274 -109.04082) (xy 209.881965 -109.082011) (xy 209.911431 -109.127861)
			(xy 209.934073 -109.177438) (xy 209.949428 -109.229733) (xy 209.957184 -109.283681) (xy 209.95767 -109.310932)
			(xy 209.957147 -109.339671) (xy 209.948521 -109.396497) (xy 209.93147 -109.451387) (xy 209.906379 -109.503099)
			(xy 209.873815 -109.550462) (xy 209.854546 -109.57179) (xy 209.847942 -109.578648) (xy 209.84083 -109.596682)
			(xy 209.84083 -109.685582) (xy 209.847942 -109.703616) (xy 209.854546 -109.710474) (xy 209.87385 -109.731773)
			(xy 209.906417 -109.779139) (xy 209.931508 -109.830855) (xy 209.948558 -109.885751) (xy 209.957178 -109.942582)
			(xy 209.957174 -110.000064) (xy 209.948547 -110.056895) (xy 209.931491 -110.111788) (xy 209.906393 -110.163501)
			(xy 209.873821 -110.210864) (xy 209.854546 -110.23219) (xy 209.847942 -110.239048) (xy 209.84083 -110.257082)
			(xy 209.84083 -110.345982) (xy 209.847942 -110.364016) (xy 209.854546 -110.370874) (xy 209.873829 -110.39219)
			(xy 209.906394 -110.439555) (xy 209.931485 -110.491269) (xy 209.948532 -110.546163) (xy 209.957151 -110.602992)
			(xy 209.95767 -110.631732) (xy 209.957184 -110.658983) (xy 209.956428 -110.664244) (xy 210.788504 -110.664244)
			(xy 210.788993 -110.635504) (xy 210.797624 -110.578675) (xy 210.814682 -110.523784) (xy 210.839781 -110.472072)
			(xy 210.872354 -110.424712) (xy 210.891628 -110.403386) (xy 210.898232 -110.396528) (xy 210.905344 -110.378494)
			(xy 210.905344 -110.289594) (xy 210.898232 -110.27156) (xy 210.891628 -110.264702) (xy 210.872401 -110.243337)
			(xy 210.839834 -110.195982) (xy 210.814739 -110.144276) (xy 210.797686 -110.089391) (xy 210.789059 -110.032569)
			(xy 210.789054 -109.975095) (xy 210.797671 -109.918272) (xy 210.814716 -109.863384) (xy 210.839801 -109.811674)
			(xy 210.87236 -109.764313) (xy 210.891628 -109.742986) (xy 210.898232 -109.736128) (xy 210.905344 -109.718094)
			(xy 210.905344 -109.629194) (xy 210.898232 -109.61116) (xy 210.891628 -109.604302) (xy 210.872329 -109.582999)
			(xy 210.839767 -109.535631) (xy 210.81468 -109.483913) (xy 210.797636 -109.429017) (xy 210.789021 -109.372185)
			(xy 210.788504 -109.343444) (xy 210.78899 -109.316193) (xy 210.796746 -109.262245) (xy 210.812101 -109.20995)
			(xy 210.834743 -109.160373) (xy 210.864209 -109.114523) (xy 210.8999 -109.073332) (xy 210.941091 -109.037641)
			(xy 210.986941 -109.008175) (xy 211.036518 -108.985533) (xy 211.088813 -108.970178) (xy 211.142761 -108.962422)
			(xy 211.197263 -108.962422) (xy 211.251211 -108.970178) (xy 211.303506 -108.985533) (xy 211.353083 -109.008175)
			(xy 211.398933 -109.037641) (xy 211.440124 -109.073332) (xy 211.475815 -109.114523) (xy 211.505281 -109.160373)
			(xy 211.527923 -109.20995) (xy 211.543278 -109.262245) (xy 211.551034 -109.316193) (xy 211.55152 -109.343444)
			(xy 211.551018 -109.372184) (xy 211.542389 -109.429012) (xy 211.525334 -109.483902) (xy 211.500238 -109.535614)
			(xy 211.467668 -109.582976) (xy 211.448396 -109.604302) (xy 211.441792 -109.61116) (xy 211.43468 -109.629194)
			(xy 211.43468 -109.718094) (xy 211.441792 -109.736128) (xy 211.448396 -109.742986) (xy 211.46771 -109.764275)
			(xy 211.500272 -109.811645) (xy 211.52536 -109.863363) (xy 211.542405 -109.918259) (xy 211.551023 -109.975091)
			(xy 211.551018 -110.032573) (xy 211.542391 -110.089404) (xy 211.525336 -110.144297) (xy 211.500239 -110.196011)
			(xy 211.467669 -110.243375) (xy 211.448396 -110.264702) (xy 211.441792 -110.27156) (xy 211.43468 -110.289594)
			(xy 211.43468 -110.378494) (xy 211.441792 -110.396528) (xy 211.448396 -110.403386) (xy 211.467676 -110.424705)
			(xy 211.500244 -110.472068) (xy 211.525335 -110.523782) (xy 211.542383 -110.578675) (xy 211.551002 -110.635504)
			(xy 211.55152 -110.664244) (xy 211.551034 -110.691495) (xy 211.543278 -110.745443) (xy 211.527923 -110.797738)
			(xy 211.505281 -110.847315) (xy 211.475815 -110.893165) (xy 211.440124 -110.934356) (xy 211.398933 -110.970047)
			(xy 211.353083 -110.999513) (xy 211.303506 -111.022155) (xy 211.251211 -111.03751) (xy 211.197263 -111.045266)
			(xy 211.142761 -111.045266) (xy 211.088813 -111.03751) (xy 211.036518 -111.022155) (xy 210.986941 -110.999513)
			(xy 210.941091 -110.970047) (xy 210.8999 -110.934356) (xy 210.864209 -110.893165) (xy 210.834743 -110.847315)
			(xy 210.812101 -110.797738) (xy 210.796746 -110.745443) (xy 210.78899 -110.691495) (xy 210.788504 -110.664244)
			(xy 209.956428 -110.664244) (xy 209.949428 -110.712931) (xy 209.934073 -110.765226) (xy 209.911431 -110.814803)
			(xy 209.881965 -110.860653) (xy 209.846274 -110.901844) (xy 209.805083 -110.937535) (xy 209.759233 -110.967001)
			(xy 209.709656 -110.989643) (xy 209.657361 -111.004998) (xy 209.603413 -111.012754) (xy 209.548911 -111.012754)
			(xy 209.494963 -111.004998) (xy 209.442668 -110.989643) (xy 209.393091 -110.967001) (xy 209.347241 -110.937535)
			(xy 209.30605 -110.901844) (xy 209.270359 -110.860653) (xy 209.240893 -110.814803) (xy 209.218251 -110.765226)
			(xy 209.202896 -110.712931) (xy 209.19514 -110.658983) (xy 209.194654 -110.631732) (xy 198.474642 -110.631732)
			(xy 198.412885 -111.128853) (xy 221.497087 -111.128853) (xy 221.497087 -111.074347) (xy 221.504845 -111.020397)
			(xy 221.520202 -110.9681) (xy 221.542846 -110.918521) (xy 221.572315 -110.87267) (xy 221.608011 -110.83148)
			(xy 221.649205 -110.795789) (xy 221.69506 -110.766325) (xy 221.744641 -110.743686) (xy 221.79694 -110.728335)
			(xy 221.850891 -110.720584) (xy 221.878144 -110.720124) (xy 221.905513 -110.720617) (xy 221.959691 -110.728427)
			(xy 222.012195 -110.74391) (xy 222.061942 -110.766746) (xy 222.10791 -110.796465) (xy 222.128842 -110.814104)
			(xy 222.129096 -110.814358) (xy 222.136175 -110.819956) (xy 222.153098 -110.826194) (xy 222.162116 -110.82655)
			(xy 222.229172 -110.82655) (xy 222.238189 -110.82619) (xy 222.255106 -110.819946) (xy 222.262192 -110.814358)
			(xy 222.262192 -110.814104) (xy 222.262446 -110.814104) (xy 222.283379 -110.796463) (xy 222.329347 -110.766739)
			(xy 222.379093 -110.743893) (xy 222.431595 -110.728397) (xy 222.485773 -110.720568) (xy 222.540515 -110.720568)
			(xy 222.594693 -110.728397) (xy 222.647195 -110.743893) (xy 222.696941 -110.766739) (xy 222.742909 -110.796463)
			(xy 222.763842 -110.814104) (xy 222.764096 -110.814358) (xy 222.771175 -110.819956) (xy 222.788098 -110.826194)
			(xy 222.797116 -110.82655) (xy 222.864172 -110.82655) (xy 222.873189 -110.82619) (xy 222.890106 -110.819946)
			(xy 222.897192 -110.814358) (xy 222.897192 -110.814104) (xy 222.897446 -110.814104) (xy 222.918379 -110.796463)
			(xy 222.964347 -110.766739) (xy 223.014093 -110.743893) (xy 223.066595 -110.728397) (xy 223.120773 -110.720568)
			(xy 223.175515 -110.720568) (xy 223.229693 -110.728397) (xy 223.282195 -110.743893) (xy 223.331941 -110.766739)
			(xy 223.377909 -110.796463) (xy 223.398842 -110.814104) (xy 223.399096 -110.814358) (xy 223.406175 -110.819956)
			(xy 223.423098 -110.826194) (xy 223.432116 -110.82655) (xy 223.499172 -110.82655) (xy 223.508189 -110.82619)
			(xy 223.525106 -110.819946) (xy 223.532192 -110.814358) (xy 223.532192 -110.814104) (xy 223.532446 -110.814104)
			(xy 223.553388 -110.796477) (xy 223.599358 -110.766764) (xy 223.649103 -110.743925) (xy 223.701602 -110.728431)
			(xy 223.755776 -110.7206) (xy 223.783144 -110.720124) (xy 223.810395 -110.720549) (xy 223.864343 -110.728311)
			(xy 223.916637 -110.743671) (xy 223.966213 -110.766317) (xy 224.012061 -110.795787) (xy 224.05325 -110.831481)
			(xy 224.08894 -110.872674) (xy 224.118404 -110.918526) (xy 224.134218 -110.953156) (xy 233.725619 -110.953156)
			(xy 233.725619 -110.898644) (xy 233.733377 -110.844686) (xy 233.748736 -110.792381) (xy 233.771382 -110.742795)
			(xy 233.800855 -110.696937) (xy 233.836554 -110.65574) (xy 233.877753 -110.620043) (xy 233.923613 -110.590572)
			(xy 233.9732 -110.567929) (xy 234.025505 -110.552573) (xy 234.079464 -110.544818) (xy 234.10672 -110.544356)
			(xy 234.133035 -110.544792) (xy 234.185166 -110.552031) (xy 234.23581 -110.566355) (xy 234.284009 -110.587493)
			(xy 234.328852 -110.615046) (xy 234.369489 -110.648491) (xy 234.387644 -110.667546) (xy 234.395155 -110.674961)
			(xy 234.414443 -110.68348) (xy 234.424982 -110.684056) (xy 234.499658 -110.684056) (xy 234.510208 -110.683531)
			(xy 234.529505 -110.674994) (xy 234.536996 -110.667546) (xy 234.556816 -110.646758) (xy 234.601588 -110.610783)
			(xy 234.651246 -110.581923) (xy 234.704668 -110.56083) (xy 234.760647 -110.547981) (xy 234.81792 -110.543666)
			(xy 234.875193 -110.547981) (xy 234.931172 -110.56083) (xy 234.984594 -110.581923) (xy 235.034252 -110.610783)
			(xy 235.079024 -110.646758) (xy 235.098844 -110.667546) (xy 235.106355 -110.674961) (xy 235.125643 -110.68348)
			(xy 235.136182 -110.684056) (xy 235.210858 -110.684056) (xy 235.221408 -110.683531) (xy 235.240705 -110.674994)
			(xy 235.248196 -110.667546) (xy 235.26635 -110.648489) (xy 235.306981 -110.615034) (xy 235.351822 -110.587477)
			(xy 235.400023 -110.566339) (xy 235.45067 -110.552021) (xy 235.502804 -110.544795) (xy 235.52912 -110.544356)
			(xy 235.556368 -110.544916) (xy 235.610308 -110.552674) (xy 235.662595 -110.568029) (xy 235.712165 -110.590669)
			(xy 235.758009 -110.620133) (xy 235.799193 -110.655821) (xy 235.834879 -110.697007) (xy 235.86434 -110.742852)
			(xy 235.886978 -110.792423) (xy 235.902331 -110.844711) (xy 235.910086 -110.898652) (xy 235.910086 -110.953148)
			(xy 235.902331 -111.007089) (xy 235.886978 -111.059377) (xy 235.86434 -111.108948) (xy 235.834879 -111.154793)
			(xy 235.799193 -111.195979) (xy 235.758009 -111.231667) (xy 235.712165 -111.261131) (xy 235.662595 -111.283771)
			(xy 235.610308 -111.299126) (xy 235.556368 -111.306884) (xy 235.52912 -111.307372) (xy 235.502806 -111.3069)
			(xy 235.450677 -111.299667) (xy 235.400034 -111.28535) (xy 235.351835 -111.264218) (xy 235.306992 -111.236673)
			(xy 235.266352 -111.203234) (xy 235.248196 -111.184182) (xy 235.24068 -111.176774) (xy 235.221396 -111.168254)
			(xy 235.210858 -111.167672) (xy 235.136182 -111.167672) (xy 235.125637 -111.16824) (xy 235.106342 -111.176749)
			(xy 235.098844 -111.184182) (xy 235.079024 -111.20497) (xy 235.034252 -111.240945) (xy 234.984594 -111.269805)
			(xy 234.931172 -111.290898) (xy 234.875193 -111.303747) (xy 234.81792 -111.308062) (xy 234.760647 -111.303747)
			(xy 234.704668 -111.290898) (xy 234.651246 -111.269805) (xy 234.601588 -111.240945) (xy 234.556816 -111.20497)
			(xy 234.536996 -111.184182) (xy 234.52948 -111.176774) (xy 234.510196 -111.168254) (xy 234.499658 -111.167672)
			(xy 234.424982 -111.167672) (xy 234.414437 -111.16824) (xy 234.395142 -111.176749) (xy 234.387644 -111.184182)
			(xy 234.369505 -111.203254) (xy 234.328872 -111.236711) (xy 234.284029 -111.264268) (xy 234.235824 -111.285404)
			(xy 234.185174 -111.299717) (xy 234.133037 -111.306936) (xy 234.10672 -111.307372) (xy 234.079464 -111.306982)
			(xy 234.025505 -111.299227) (xy 233.9732 -111.283871) (xy 233.923613 -111.261228) (xy 233.877753 -111.231757)
			(xy 233.836554 -111.19606) (xy 233.800855 -111.154863) (xy 233.771382 -111.109005) (xy 233.748736 -111.059419)
			(xy 233.733377 -111.007114) (xy 233.725619 -110.953156) (xy 224.134218 -110.953156) (xy 224.141044 -110.968104)
			(xy 224.156398 -111.0204) (xy 224.164154 -111.074348) (xy 224.164154 -111.128852) (xy 224.156398 -111.1828)
			(xy 224.141044 -111.235096) (xy 224.118404 -111.284674) (xy 224.08894 -111.330526) (xy 224.05325 -111.371719)
			(xy 224.012061 -111.407413) (xy 223.966213 -111.436883) (xy 223.916637 -111.459529) (xy 223.864343 -111.474889)
			(xy 223.810395 -111.482651) (xy 223.783144 -111.48314) (xy 223.755774 -111.482663) (xy 223.701595 -111.47485)
			(xy 223.649091 -111.459364) (xy 223.599344 -111.436525) (xy 223.553377 -111.406801) (xy 223.532446 -111.38916)
			(xy 223.532192 -111.388906) (xy 223.525111 -111.383311) (xy 223.50819 -111.377069) (xy 223.499172 -111.376714)
			(xy 223.432116 -111.376714) (xy 223.4231 -111.377075) (xy 223.406182 -111.38332) (xy 223.399096 -111.388906)
			(xy 223.398842 -111.38916) (xy 223.377909 -111.406801) (xy 223.331941 -111.436525) (xy 223.282195 -111.459371)
			(xy 223.229693 -111.474867) (xy 223.175515 -111.482696) (xy 223.120773 -111.482696) (xy 223.066595 -111.474867)
			(xy 223.014093 -111.459371) (xy 222.964347 -111.436525) (xy 222.918379 -111.406801) (xy 222.897446 -111.38916)
			(xy 222.897192 -111.388906) (xy 222.890111 -111.383311) (xy 222.87319 -111.377069) (xy 222.864172 -111.376714)
			(xy 222.797116 -111.376714) (xy 222.7881 -111.377075) (xy 222.771182 -111.38332) (xy 222.764096 -111.388906)
			(xy 222.764096 -111.38916) (xy 222.763842 -111.38916) (xy 222.742909 -111.406801) (xy 222.696941 -111.436525)
			(xy 222.647195 -111.459371) (xy 222.594693 -111.474867) (xy 222.540515 -111.482696) (xy 222.485773 -111.482696)
			(xy 222.431595 -111.474867) (xy 222.379093 -111.459371) (xy 222.329347 -111.436525) (xy 222.283379 -111.406801)
			(xy 222.262446 -111.38916) (xy 222.262192 -111.388906) (xy 222.255111 -111.383311) (xy 222.23819 -111.377069)
			(xy 222.229172 -111.376714) (xy 222.162116 -111.376714) (xy 222.1531 -111.377075) (xy 222.136182 -111.38332)
			(xy 222.129096 -111.388906) (xy 222.129096 -111.38916) (xy 222.128842 -111.38916) (xy 222.1079 -111.406787)
			(xy 222.06193 -111.436502) (xy 222.012186 -111.459341) (xy 221.959687 -111.474835) (xy 221.905513 -111.482665)
			(xy 221.878144 -111.48314) (xy 221.850891 -111.482616) (xy 221.79694 -111.474865) (xy 221.744641 -111.459514)
			(xy 221.69506 -111.436875) (xy 221.649205 -111.407411) (xy 221.608011 -111.37172) (xy 221.572315 -111.33053)
			(xy 221.542846 -111.284679) (xy 221.520202 -111.2351) (xy 221.504845 -111.182803) (xy 221.497087 -111.128853)
			(xy 198.412885 -111.128853) (xy 198.235015 -112.560653) (xy 205.549185 -112.560653) (xy 205.549185 -112.506147)
			(xy 205.556943 -112.452196) (xy 205.5723 -112.399899) (xy 205.594944 -112.35032) (xy 205.624414 -112.304468)
			(xy 205.66011 -112.263277) (xy 205.701305 -112.227587) (xy 205.74716 -112.198122) (xy 205.796742 -112.175484)
			(xy 205.849041 -112.160133) (xy 205.902993 -112.152382) (xy 205.930246 -112.151922) (xy 205.9305 -112.151922)
			(xy 205.95846 -112.152404) (xy 206.013778 -112.160584) (xy 206.067304 -112.17677) (xy 206.092806 -112.188244)
			(xy 206.104265 -112.193019) (xy 206.12904 -112.191947) (xy 206.14005 -112.186212) (xy 206.21244 -112.144302)
			(xy 206.222682 -112.137528) (xy 206.235819 -112.116829) (xy 206.237586 -112.104678) (xy 206.237586 -112.10417)
			(xy 206.240354 -112.075838) (xy 206.253235 -112.020389) (xy 206.274214 -111.967471) (xy 206.302826 -111.918258)
			(xy 206.338433 -111.873844) (xy 206.380246 -111.835216) (xy 206.427336 -111.803231) (xy 206.478657 -111.7786)
			(xy 206.533068 -111.761871) (xy 206.589361 -111.753414) (xy 206.617824 -111.752888) (xy 206.647802 -111.753455)
			(xy 206.707019 -111.76285) (xy 206.764038 -111.78139) (xy 206.817456 -111.808618) (xy 206.865959 -111.843864)
			(xy 206.887572 -111.864648) (xy 206.887826 -111.864902) (xy 206.895317 -111.871548) (xy 206.913886 -111.878995)
			(xy 206.923894 -111.87938) (xy 207.007206 -111.878364) (xy 207.025748 -111.87049) (xy 207.03286 -111.86287)
			(xy 207.050958 -111.844577) (xy 207.09117 -111.812468) (xy 207.13533 -111.786052) (xy 207.182639 -111.765808)
			(xy 207.232238 -111.752102) (xy 207.283229 -111.745184) (xy 207.308958 -111.74476) (xy 207.336208 -111.745294)
			(xy 207.390155 -111.753045) (xy 207.44245 -111.768394) (xy 207.492028 -111.791029) (xy 207.537879 -111.82049)
			(xy 207.579072 -111.856176) (xy 207.614766 -111.897361) (xy 207.644235 -111.943207) (xy 207.66688 -111.992781)
			(xy 207.68224 -112.045073) (xy 207.69 -112.099018) (xy 207.690466 -112.126268) (xy 207.690035 -112.152714)
			(xy 207.682721 -112.205097) (xy 207.668242 -112.255968) (xy 207.646877 -112.304352) (xy 207.619034 -112.349322)
			(xy 207.585248 -112.390016) (xy 207.546165 -112.425653) (xy 207.524604 -112.440974) (xy 207.51593 -112.447449)
			(xy 207.504608 -112.46587) (xy 207.50276 -112.476534) (xy 207.49895 -112.508792) (xy 207.498044 -112.519483)
			(xy 207.504222 -112.540009) (xy 207.510888 -112.548416) (xy 207.52435 -112.564672) (xy 207.531976 -112.573458)
			(xy 207.552863 -112.58365) (xy 207.564482 -112.58423) (xy 207.644238 -112.58423) (xy 207.655875 -112.583723)
			(xy 207.676785 -112.573514) (xy 207.68437 -112.564672) (xy 207.702571 -112.542197) (xy 207.744589 -112.502463)
			(xy 207.792123 -112.469523) (xy 207.844082 -112.444134) (xy 207.899277 -112.426875) (xy 207.956445 -112.418143)
			(xy 207.98536 -112.417606) (xy 208.012616 -112.418038) (xy 208.066573 -112.425791) (xy 208.118878 -112.441144)
			(xy 208.168465 -112.463785) (xy 208.214325 -112.493253) (xy 208.255524 -112.528948) (xy 208.291223 -112.570143)
			(xy 208.320696 -112.616) (xy 208.343342 -112.665585) (xy 208.358701 -112.717888) (xy 208.359022 -112.72012)
			(xy 232.673906 -112.72012) (xy 232.674382 -112.69275) (xy 232.682197 -112.638571) (xy 232.697684 -112.586068)
			(xy 232.720524 -112.536321) (xy 232.750246 -112.490354) (xy 232.767886 -112.469422) (xy 232.76814 -112.469168)
			(xy 232.773709 -112.46207) (xy 232.779965 -112.445162) (xy 232.780332 -112.436148) (xy 232.780332 -112.369092)
			(xy 232.779972 -112.360076) (xy 232.773726 -112.343159) (xy 232.76814 -112.336072) (xy 232.767886 -112.336072)
			(xy 232.767886 -112.335818) (xy 232.75024 -112.314892) (xy 232.720529 -112.268917) (xy 232.697695 -112.219168)
			(xy 232.682206 -112.166666) (xy 232.674379 -112.11249) (xy 232.673906 -112.08512) (xy 232.674392 -112.057869)
			(xy 232.682148 -112.003921) (xy 232.697503 -111.951626) (xy 232.720145 -111.902049) (xy 232.749611 -111.856199)
			(xy 232.785302 -111.815008) (xy 232.826493 -111.779317) (xy 232.872343 -111.749851) (xy 232.92192 -111.727209)
			(xy 232.974215 -111.711854) (xy 233.028163 -111.704098) (xy 233.082665 -111.704098) (xy 233.136613 -111.711854)
			(xy 233.188908 -111.727209) (xy 233.238485 -111.749851) (xy 233.284335 -111.779317) (xy 233.325526 -111.815008)
			(xy 233.361217 -111.856199) (xy 233.390683 -111.902049) (xy 233.413325 -111.951626) (xy 233.427314 -111.999268)
			(xy 238.85347 -111.999268) (xy 238.857541 -111.943646) (xy 238.869667 -111.889209) (xy 238.88959 -111.837118)
			(xy 238.916886 -111.788483) (xy 238.950972 -111.74434) (xy 238.991121 -111.705631) (xy 239.036479 -111.67318)
			(xy 239.086079 -111.647679) (xy 239.138863 -111.629672) (xy 239.193706 -111.619542) (xy 239.24944 -111.617505)
			(xy 239.304877 -111.623605) (xy 239.358834 -111.637711) (xy 239.410163 -111.659523) (xy 239.457769 -111.688577)
			(xy 239.500637 -111.724252) (xy 239.537854 -111.765789) (xy 239.568627 -111.812302) (xy 239.592299 -111.862799)
			(xy 239.608367 -111.916206) (xy 239.616487 -111.971382) (xy 239.616996 -111.999268) (xy 239.616487 -112.027154)
			(xy 239.608367 -112.08233) (xy 239.592299 -112.135737) (xy 239.568627 -112.186234) (xy 239.537854 -112.232747)
			(xy 239.500637 -112.274284) (xy 239.457769 -112.309959) (xy 239.410163 -112.339013) (xy 239.358834 -112.360825)
			(xy 239.304877 -112.374931) (xy 239.24944 -112.381031) (xy 239.193706 -112.378994) (xy 239.138863 -112.368864)
			(xy 239.086079 -112.350857) (xy 239.036479 -112.325356) (xy 238.991121 -112.292905) (xy 238.950972 -112.254196)
			(xy 238.916886 -112.210053) (xy 238.88959 -112.161418) (xy 238.869667 -112.109327) (xy 238.857541 -112.05489)
			(xy 238.85347 -111.999268) (xy 233.427314 -111.999268) (xy 233.42868 -112.003921) (xy 233.436436 -112.057869)
			(xy 233.436922 -112.08512) (xy 233.436487 -112.112492) (xy 233.428664 -112.166673) (xy 233.413169 -112.219177)
			(xy 233.39032 -112.268923) (xy 233.360587 -112.314888) (xy 233.342942 -112.335818) (xy 233.342688 -112.336072)
			(xy 233.337106 -112.343161) (xy 233.330857 -112.360076) (xy 233.330496 -112.369092) (xy 233.330496 -112.436148)
			(xy 233.330879 -112.445162) (xy 233.337109 -112.462079) (xy 233.342688 -112.469168) (xy 233.342942 -112.469168)
			(xy 233.342942 -112.469422) (xy 233.360565 -112.490367) (xy 233.367713 -112.501426) (xy 244.173246 -112.501426)
			(xy 244.177317 -112.445804) (xy 244.189443 -112.391367) (xy 244.209366 -112.339276) (xy 244.236662 -112.290641)
			(xy 244.270748 -112.246498) (xy 244.310897 -112.207789) (xy 244.356255 -112.175338) (xy 244.405855 -112.149837)
			(xy 244.458639 -112.13183) (xy 244.513482 -112.1217) (xy 244.569216 -112.119663) (xy 244.624653 -112.125763)
			(xy 244.67861 -112.139869) (xy 244.729939 -112.161681) (xy 244.777545 -112.190735) (xy 244.820413 -112.22641)
			(xy 244.85763 -112.267947) (xy 244.888403 -112.31446) (xy 244.912075 -112.364957) (xy 244.928143 -112.418364)
			(xy 244.936263 -112.47354) (xy 244.936772 -112.501426) (xy 244.936263 -112.529312) (xy 244.928143 -112.584488)
			(xy 244.914771 -112.628934) (xy 256.713734 -112.628934) (xy 256.717805 -112.573312) (xy 256.729931 -112.518875)
			(xy 256.749854 -112.466784) (xy 256.77715 -112.418149) (xy 256.811236 -112.374006) (xy 256.851385 -112.335297)
			(xy 256.896743 -112.302846) (xy 256.946343 -112.277345) (xy 256.999127 -112.259338) (xy 257.05397 -112.249208)
			(xy 257.109704 -112.247171) (xy 257.165141 -112.253271) (xy 257.219098 -112.267377) (xy 257.270427 -112.289189)
			(xy 257.318033 -112.318243) (xy 257.360901 -112.353918) (xy 257.398118 -112.395455) (xy 257.428891 -112.441968)
			(xy 257.452563 -112.492465) (xy 257.468631 -112.545872) (xy 257.476751 -112.601048) (xy 257.47726 -112.628934)
			(xy 257.476751 -112.65682) (xy 257.468631 -112.711996) (xy 257.452563 -112.765403) (xy 257.428891 -112.8159)
			(xy 257.398118 -112.862413) (xy 257.360901 -112.90395) (xy 257.318033 -112.939625) (xy 257.270427 -112.968679)
			(xy 257.219098 -112.990491) (xy 257.165141 -113.004597) (xy 257.109704 -113.010697) (xy 257.05397 -113.00866)
			(xy 256.999127 -112.99853) (xy 256.946343 -112.980523) (xy 256.896743 -112.955022) (xy 256.851385 -112.922571)
			(xy 256.811236 -112.883862) (xy 256.77715 -112.839719) (xy 256.749854 -112.791084) (xy 256.729931 -112.738993)
			(xy 256.717805 -112.684556) (xy 256.713734 -112.628934) (xy 244.914771 -112.628934) (xy 244.912075 -112.637895)
			(xy 244.888403 -112.688392) (xy 244.85763 -112.734905) (xy 244.820413 -112.776442) (xy 244.777545 -112.812117)
			(xy 244.729939 -112.841171) (xy 244.67861 -112.862983) (xy 244.624653 -112.877089) (xy 244.569216 -112.883189)
			(xy 244.513482 -112.881152) (xy 244.458639 -112.871022) (xy 244.405855 -112.853015) (xy 244.356255 -112.827514)
			(xy 244.310897 -112.795063) (xy 244.270748 -112.756354) (xy 244.236662 -112.712211) (xy 244.209366 -112.663576)
			(xy 244.189443 -112.611485) (xy 244.177317 -112.557048) (xy 244.173246 -112.501426) (xy 233.367713 -112.501426)
			(xy 233.390278 -112.536337) (xy 233.413116 -112.586081) (xy 233.428611 -112.638579) (xy 233.436445 -112.692752)
			(xy 233.436922 -112.72012) (xy 233.436436 -112.747371) (xy 233.42868 -112.801319) (xy 233.413325 -112.853614)
			(xy 233.390683 -112.903191) (xy 233.361217 -112.949041) (xy 233.325526 -112.990232) (xy 233.284335 -113.025923)
			(xy 233.238485 -113.055389) (xy 233.188908 -113.078031) (xy 233.136613 -113.093386) (xy 233.082665 -113.101142)
			(xy 233.028163 -113.101142) (xy 232.974215 -113.093386) (xy 232.92192 -113.078031) (xy 232.872343 -113.055389)
			(xy 232.826493 -113.025923) (xy 232.785302 -112.990232) (xy 232.749611 -112.949041) (xy 232.720145 -112.903191)
			(xy 232.697503 -112.853614) (xy 232.682148 -112.801319) (xy 232.674392 -112.747371) (xy 232.673906 -112.72012)
			(xy 208.359022 -112.72012) (xy 208.366459 -112.771844) (xy 208.366459 -112.826356) (xy 208.358701 -112.880312)
			(xy 208.343342 -112.932615) (xy 208.320696 -112.9822) (xy 208.291223 -113.028057) (xy 208.255524 -113.069252)
			(xy 208.214325 -113.104947) (xy 208.168465 -113.134415) (xy 208.118878 -113.157056) (xy 208.066573 -113.172409)
			(xy 208.012616 -113.180162) (xy 207.98536 -113.180622) (xy 207.956443 -113.18009) (xy 207.899271 -113.171368)
			(xy 207.844072 -113.154115) (xy 207.792109 -113.128726) (xy 207.744575 -113.095783) (xy 207.702559 -113.056042)
			(xy 207.68437 -113.033556) (xy 207.676774 -113.024738) (xy 207.655864 -113.014562) (xy 207.644238 -113.013998)
			(xy 207.564482 -113.013998) (xy 207.552851 -113.014542) (xy 207.531941 -113.024727) (xy 207.52435 -113.033556)
			(xy 207.50612 -113.056006) (xy 207.464109 -113.095746) (xy 207.416583 -113.12869) (xy 207.364629 -113.154084)
			(xy 207.309438 -113.171347) (xy 207.252274 -113.180083) (xy 207.22336 -113.180622) (xy 207.196108 -113.180159)
			(xy 207.142161 -113.172398) (xy 207.089866 -113.157038) (xy 207.04029 -113.134394) (xy 206.99444 -113.104924)
			(xy 206.953251 -113.069231) (xy 206.91756 -113.028039) (xy 206.888094 -112.982187) (xy 206.865453 -112.932609)
			(xy 206.850097 -112.880314) (xy 206.842339 -112.826366) (xy 206.841852 -112.799114) (xy 206.842337 -112.77267)
			(xy 206.849641 -112.720289) (xy 206.864109 -112.669418) (xy 206.885465 -112.621034) (xy 206.9133 -112.576063)
			(xy 206.94708 -112.535369) (xy 206.986156 -112.49973) (xy 207.007714 -112.484408) (xy 207.016398 -112.477945)
			(xy 207.027714 -112.459515) (xy 207.029558 -112.448848) (xy 207.033622 -112.41659) (xy 207.034441 -112.405878)
			(xy 207.028135 -112.38536) (xy 207.02143 -112.376966) (xy 207.021176 -112.376712) (xy 207.013541 -112.368696)
			(xy 206.993377 -112.359614) (xy 206.982314 -112.359186) (xy 206.949802 -112.359694) (xy 206.938787 -112.360335)
			(xy 206.918897 -112.36984) (xy 206.911448 -112.377982) (xy 206.893221 -112.399159) (xy 206.851659 -112.436499)
			(xy 206.805096 -112.467377) (xy 206.754527 -112.491135) (xy 206.701033 -112.507262) (xy 206.64576 -112.515414)
			(xy 206.617824 -112.515904) (xy 206.61757 -112.515904) (xy 206.58961 -112.515431) (xy 206.534291 -112.507246)
			(xy 206.480765 -112.491058) (xy 206.455264 -112.479582) (xy 206.44381 -112.474794) (xy 206.419032 -112.475877)
			(xy 206.40802 -112.481614) (xy 206.33563 -112.523524) (xy 206.325391 -112.530303) (xy 206.312249 -112.550997)
			(xy 206.310484 -112.563148) (xy 206.310484 -112.563656) (xy 206.307683 -112.591985) (xy 206.294811 -112.647435)
			(xy 206.273839 -112.700356) (xy 206.245234 -112.749571) (xy 206.20963 -112.793987) (xy 206.16782 -112.832616)
			(xy 206.120732 -112.864602) (xy 206.069412 -112.889232) (xy 206.015001 -112.90596) (xy 205.958708 -112.914414)
			(xy 205.930246 -112.914938) (xy 205.902993 -112.914418) (xy 205.849041 -112.906667) (xy 205.796742 -112.891316)
			(xy 205.74716 -112.868678) (xy 205.701305 -112.839213) (xy 205.66011 -112.803523) (xy 205.624414 -112.762332)
			(xy 205.594944 -112.71648) (xy 205.5723 -112.666901) (xy 205.556943 -112.614604) (xy 205.549185 -112.560653)
			(xy 198.235015 -112.560653) (xy 198.15683 -113.19002) (xy 198.156679 -113.197458) (xy 198.160166 -113.211915)
			(xy 198.163688 -113.218468) (xy 198.163942 -113.218976) (xy 198.17661 -113.241147) (xy 198.196556 -113.288154)
			(xy 198.210054 -113.337401) (xy 198.21686 -113.388008) (xy 198.217282 -113.41354) (xy 198.217282 -113.413794)
			(xy 198.216705 -113.443629) (xy 198.207413 -113.50257) (xy 198.189055 -113.559346) (xy 198.162079 -113.612569)
			(xy 198.127144 -113.660942) (xy 198.106538 -113.682526) (xy 198.103998 -113.685066) (xy 198.099262 -113.690878)
			(xy 198.093188 -113.704578) (xy 198.09206 -113.71199) (xy 198.071595 -113.876836) (xy 203.360526 -113.876836)
			(xy 203.364597 -113.821214) (xy 203.376723 -113.766777) (xy 203.396646 -113.714686) (xy 203.423942 -113.666051)
			(xy 203.458028 -113.621908) (xy 203.498177 -113.583199) (xy 203.543535 -113.550748) (xy 203.593135 -113.525247)
			(xy 203.645919 -113.50724) (xy 203.700762 -113.49711) (xy 203.756496 -113.495073) (xy 203.811933 -113.501173)
			(xy 203.86589 -113.515279) (xy 203.917219 -113.537091) (xy 203.964825 -113.566145) (xy 204.007693 -113.60182)
			(xy 204.04491 -113.643357) (xy 204.075683 -113.68987) (xy 204.099355 -113.740367) (xy 204.115423 -113.793774)
			(xy 204.123161 -113.846356) (xy 205.461106 -113.846356) (xy 205.465177 -113.790734) (xy 205.477303 -113.736297)
			(xy 205.497226 -113.684206) (xy 205.524522 -113.635571) (xy 205.558608 -113.591428) (xy 205.598757 -113.552719)
			(xy 205.644115 -113.520268) (xy 205.693715 -113.494767) (xy 205.746499 -113.47676) (xy 205.801342 -113.46663)
			(xy 205.857076 -113.464593) (xy 205.912513 -113.470693) (xy 205.96647 -113.484799) (xy 206.017799 -113.506611)
			(xy 206.065405 -113.535665) (xy 206.108273 -113.57134) (xy 206.14549 -113.612877) (xy 206.172076 -113.653062)
			(xy 235.227366 -113.653062) (xy 235.231437 -113.59744) (xy 235.243563 -113.543003) (xy 235.263486 -113.490912)
			(xy 235.290782 -113.442277) (xy 235.324868 -113.398134) (xy 235.365017 -113.359425) (xy 235.410375 -113.326974)
			(xy 235.459975 -113.301473) (xy 235.512759 -113.283466) (xy 235.567602 -113.273336) (xy 235.623336 -113.271299)
			(xy 235.678773 -113.277399) (xy 235.73273 -113.291505) (xy 235.757507 -113.302034) (xy 246.513602 -113.302034)
			(xy 246.517673 -113.246412) (xy 246.529799 -113.191975) (xy 246.549722 -113.139884) (xy 246.577018 -113.091249)
			(xy 246.611104 -113.047106) (xy 246.651253 -113.008397) (xy 246.696611 -112.975946) (xy 246.746211 -112.950445)
			(xy 246.798995 -112.932438) (xy 246.853838 -112.922308) (xy 246.909572 -112.920271) (xy 246.965009 -112.926371)
			(xy 247.018966 -112.940477) (xy 247.070295 -112.962289) (xy 247.117901 -112.991343) (xy 247.160769 -113.027018)
			(xy 247.197986 -113.068555) (xy 247.228759 -113.115068) (xy 247.252431 -113.165565) (xy 247.257725 -113.183162)
			(xy 248.515122 -113.183162) (xy 248.519193 -113.12754) (xy 248.531319 -113.073103) (xy 248.551242 -113.021012)
			(xy 248.578538 -112.972377) (xy 248.612624 -112.928234) (xy 248.652773 -112.889525) (xy 248.698131 -112.857074)
			(xy 248.747731 -112.831573) (xy 248.800515 -112.813566) (xy 248.855358 -112.803436) (xy 248.911092 -112.801399)
			(xy 248.966529 -112.807499) (xy 249.020486 -112.821605) (xy 249.071815 -112.843417) (xy 249.119421 -112.872471)
			(xy 249.162289 -112.908146) (xy 249.199506 -112.949683) (xy 249.230279 -112.996196) (xy 249.253951 -113.046693)
			(xy 249.270019 -113.1001) (xy 249.278139 -113.155276) (xy 249.278648 -113.183162) (xy 249.278139 -113.211048)
			(xy 249.270019 -113.266224) (xy 249.253951 -113.319631) (xy 249.230279 -113.370128) (xy 249.199506 -113.416641)
			(xy 249.162289 -113.458178) (xy 249.119421 -113.493853) (xy 249.071815 -113.522907) (xy 249.020486 -113.544719)
			(xy 248.966529 -113.558825) (xy 248.911092 -113.564925) (xy 248.855358 -113.562888) (xy 248.800515 -113.552758)
			(xy 248.747731 -113.534751) (xy 248.698131 -113.50925) (xy 248.652773 -113.476799) (xy 248.612624 -113.43809)
			(xy 248.578538 -113.393947) (xy 248.551242 -113.345312) (xy 248.531319 -113.293221) (xy 248.519193 -113.238784)
			(xy 248.515122 -113.183162) (xy 247.257725 -113.183162) (xy 247.268499 -113.218972) (xy 247.276619 -113.274148)
			(xy 247.277128 -113.302034) (xy 247.276619 -113.32992) (xy 247.268499 -113.385096) (xy 247.252431 -113.438503)
			(xy 247.228759 -113.489) (xy 247.197986 -113.535513) (xy 247.160769 -113.57705) (xy 247.117901 -113.612725)
			(xy 247.070295 -113.641779) (xy 247.018966 -113.663591) (xy 246.965009 -113.677697) (xy 246.909572 -113.683797)
			(xy 246.853838 -113.68176) (xy 246.798995 -113.67163) (xy 246.746211 -113.653623) (xy 246.696611 -113.628122)
			(xy 246.651253 -113.595671) (xy 246.611104 -113.556962) (xy 246.577018 -113.512819) (xy 246.549722 -113.464184)
			(xy 246.529799 -113.412093) (xy 246.517673 -113.357656) (xy 246.513602 -113.302034) (xy 235.757507 -113.302034)
			(xy 235.784059 -113.313317) (xy 235.831665 -113.342371) (xy 235.874533 -113.378046) (xy 235.91175 -113.419583)
			(xy 235.942523 -113.466096) (xy 235.966195 -113.516593) (xy 235.982263 -113.57) (xy 235.990383 -113.625176)
			(xy 235.990892 -113.653062) (xy 235.990383 -113.680948) (xy 235.982263 -113.736124) (xy 235.966195 -113.789531)
			(xy 235.942523 -113.840028) (xy 235.91175 -113.886541) (xy 235.874533 -113.928078) (xy 235.831665 -113.963753)
			(xy 235.784059 -113.992807) (xy 235.73273 -114.014619) (xy 235.678773 -114.028725) (xy 235.623336 -114.034825)
			(xy 235.567602 -114.032788) (xy 235.512759 -114.022658) (xy 235.459975 -114.004651) (xy 235.410375 -113.97915)
			(xy 235.365017 -113.946699) (xy 235.324868 -113.90799) (xy 235.290782 -113.863847) (xy 235.263486 -113.815212)
			(xy 235.243563 -113.763121) (xy 235.231437 -113.708684) (xy 235.227366 -113.653062) (xy 206.172076 -113.653062)
			(xy 206.176263 -113.65939) (xy 206.199935 -113.709887) (xy 206.216003 -113.763294) (xy 206.224123 -113.81847)
			(xy 206.224632 -113.846356) (xy 206.224123 -113.874242) (xy 206.216003 -113.929418) (xy 206.199935 -113.982825)
			(xy 206.176263 -114.033322) (xy 206.14549 -114.079835) (xy 206.108273 -114.121372) (xy 206.065405 -114.157047)
			(xy 206.017799 -114.186101) (xy 205.96647 -114.207913) (xy 205.912513 -114.222019) (xy 205.857076 -114.228119)
			(xy 205.801342 -114.226082) (xy 205.746499 -114.215952) (xy 205.693715 -114.197945) (xy 205.644115 -114.172444)
			(xy 205.598757 -114.139993) (xy 205.558608 -114.101284) (xy 205.524522 -114.057141) (xy 205.497226 -114.008506)
			(xy 205.477303 -113.956415) (xy 205.465177 -113.901978) (xy 205.461106 -113.846356) (xy 204.123161 -113.846356)
			(xy 204.123543 -113.84895) (xy 204.124052 -113.876836) (xy 204.123543 -113.904722) (xy 204.115423 -113.959898)
			(xy 204.099355 -114.013305) (xy 204.075683 -114.063802) (xy 204.04491 -114.110315) (xy 204.007693 -114.151852)
			(xy 203.964825 -114.187527) (xy 203.917219 -114.216581) (xy 203.86589 -114.238393) (xy 203.811933 -114.252499)
			(xy 203.756496 -114.258599) (xy 203.700762 -114.256562) (xy 203.645919 -114.246432) (xy 203.593135 -114.228425)
			(xy 203.543535 -114.202924) (xy 203.498177 -114.170473) (xy 203.458028 -114.131764) (xy 203.423942 -114.087621)
			(xy 203.396646 -114.038986) (xy 203.376723 -113.986895) (xy 203.364597 -113.932458) (xy 203.360526 -113.876836)
			(xy 198.071595 -113.876836) (xy 198.045832 -114.084354) (xy 198.048118 -114.08918) (xy 198.056754 -114.094514)
			(xy 198.07301 -114.10442) (xy 198.096659 -114.119519) (xy 198.139656 -114.155564) (xy 198.176896 -114.19753)
			(xy 198.192644 -114.220752) (xy 198.208285 -114.245625) (xy 198.232558 -114.299132) (xy 198.248342 -114.355726)
			(xy 198.252334 -114.384836) (xy 198.253604 -114.395504) (xy 198.255128 -114.42954) (xy 201.337924 -114.42954)
			(xy 201.341995 -114.373918) (xy 201.354121 -114.319481) (xy 201.374044 -114.26739) (xy 201.40134 -114.218755)
			(xy 201.435426 -114.174612) (xy 201.475575 -114.135903) (xy 201.520933 -114.103452) (xy 201.570533 -114.077951)
			(xy 201.623317 -114.059944) (xy 201.67816 -114.049814) (xy 201.733894 -114.047777) (xy 201.789331 -114.053877)
			(xy 201.843288 -114.067983) (xy 201.894617 -114.089795) (xy 201.942223 -114.118849) (xy 201.985091 -114.154524)
			(xy 202.022308 -114.196061) (xy 202.053081 -114.242574) (xy 202.076753 -114.293071) (xy 202.081436 -114.308636)
			(xy 209.079082 -114.308636) (xy 209.083153 -114.253014) (xy 209.095279 -114.198577) (xy 209.115202 -114.146486)
			(xy 209.142498 -114.097851) (xy 209.176584 -114.053708) (xy 209.216733 -114.014999) (xy 209.262091 -113.982548)
			(xy 209.311691 -113.957047) (xy 209.364475 -113.93904) (xy 209.419318 -113.92891) (xy 209.475052 -113.926873)
			(xy 209.530489 -113.932973) (xy 209.584446 -113.947079) (xy 209.635775 -113.968891) (xy 209.683381 -113.997945)
			(xy 209.726249 -114.03362) (xy 209.763466 -114.075157) (xy 209.794239 -114.12167) (xy 209.817911 -114.172167)
			(xy 209.833979 -114.225574) (xy 209.842099 -114.28075) (xy 209.842608 -114.308636) (xy 209.842099 -114.336522)
			(xy 209.833979 -114.391698) (xy 209.817911 -114.445105) (xy 209.794239 -114.495602) (xy 209.763466 -114.542115)
			(xy 209.726249 -114.583652) (xy 209.683381 -114.619327) (xy 209.635775 -114.648381) (xy 209.584446 -114.670193)
			(xy 209.530489 -114.684299) (xy 209.475052 -114.690399) (xy 209.419318 -114.688362) (xy 209.364475 -114.678232)
			(xy 209.311691 -114.660225) (xy 209.262091 -114.634724) (xy 209.216733 -114.602273) (xy 209.176584 -114.563564)
			(xy 209.142498 -114.519421) (xy 209.115202 -114.470786) (xy 209.095279 -114.418695) (xy 209.083153 -114.364258)
			(xy 209.079082 -114.308636) (xy 202.081436 -114.308636) (xy 202.092821 -114.346478) (xy 202.100941 -114.401654)
			(xy 202.10145 -114.42954) (xy 202.100941 -114.457426) (xy 202.092821 -114.512602) (xy 202.076753 -114.566009)
			(xy 202.053081 -114.616506) (xy 202.022308 -114.663019) (xy 201.985091 -114.704556) (xy 201.942223 -114.740231)
			(xy 201.894617 -114.769285) (xy 201.843288 -114.791097) (xy 201.789331 -114.805203) (xy 201.733894 -114.811303)
			(xy 201.67816 -114.809266) (xy 201.623317 -114.799136) (xy 201.570533 -114.781129) (xy 201.520933 -114.755628)
			(xy 201.475575 -114.723177) (xy 201.435426 -114.684468) (xy 201.40134 -114.640325) (xy 201.374044 -114.59169)
			(xy 201.354121 -114.539599) (xy 201.341995 -114.485162) (xy 201.337924 -114.42954) (xy 198.255128 -114.42954)
			(xy 198.254686 -114.455926) (xy 198.247423 -114.508197) (xy 198.233027 -114.558968) (xy 198.211773 -114.607271)
			(xy 198.184067 -114.652185) (xy 198.150436 -114.692853) (xy 198.111523 -114.7285) (xy 198.068069 -114.758445)
			(xy 198.020904 -114.782117) (xy 197.996048 -114.790982) (xy 197.995794 -114.790982) (xy 197.992746 -114.791998)
			(xy 197.99173 -114.792252) (xy 197.989444 -114.793014) (xy 197.988936 -114.793014) (xy 197.985888 -114.79403)
			(xy 197.96379 -114.801142) (xy 197.959726 -114.802412) (xy 197.955916 -114.806476) (xy 197.913737 -115.14582)
			(xy 205.473044 -115.14582) (xy 205.477115 -115.090198) (xy 205.489241 -115.035761) (xy 205.509164 -114.98367)
			(xy 205.53646 -114.935035) (xy 205.570546 -114.890892) (xy 205.610695 -114.852183) (xy 205.656053 -114.819732)
			(xy 205.705653 -114.794231) (xy 205.758437 -114.776224) (xy 205.81328 -114.766094) (xy 205.869014 -114.764057)
			(xy 205.924451 -114.770157) (xy 205.978408 -114.784263) (xy 206.029737 -114.806075) (xy 206.077343 -114.835129)
			(xy 206.120211 -114.870804) (xy 206.157428 -114.912341) (xy 206.188201 -114.958854) (xy 206.211873 -115.009351)
			(xy 206.227941 -115.062758) (xy 206.236061 -115.117934) (xy 206.23657 -115.14582) (xy 206.236061 -115.173706)
			(xy 206.227941 -115.228882) (xy 206.211873 -115.282289) (xy 206.188201 -115.332786) (xy 206.157428 -115.379299)
			(xy 206.120211 -115.420836) (xy 206.077343 -115.456511) (xy 206.029737 -115.485565) (xy 205.978408 -115.507377)
			(xy 205.924451 -115.521483) (xy 205.869014 -115.527583) (xy 205.81328 -115.525546) (xy 205.758437 -115.515416)
			(xy 205.705653 -115.497409) (xy 205.656053 -115.471908) (xy 205.610695 -115.439457) (xy 205.570546 -115.400748)
			(xy 205.53646 -115.356605) (xy 205.509164 -115.30797) (xy 205.489241 -115.255879) (xy 205.477115 -115.201442)
			(xy 205.473044 -115.14582) (xy 197.913737 -115.14582) (xy 197.824165 -115.866447) (xy 206.842418 -115.866447)
			(xy 206.842418 -115.811953) (xy 206.850173 -115.758015) (xy 206.865524 -115.705729) (xy 206.88816 -115.65616)
			(xy 206.917619 -115.610316) (xy 206.953303 -115.569131) (xy 206.994484 -115.533443) (xy 207.040324 -115.503979)
			(xy 207.089891 -115.481338) (xy 207.142176 -115.465981) (xy 207.196114 -115.458221) (xy 207.22336 -115.457732)
			(xy 207.252276 -115.458267) (xy 207.309447 -115.466991) (xy 207.364646 -115.484245) (xy 207.416609 -115.509633)
			(xy 207.464143 -115.542574) (xy 207.50616 -115.582313) (xy 207.52435 -115.604798) (xy 207.531989 -115.613572)
			(xy 207.552865 -115.623774) (xy 207.564482 -115.624356) (xy 207.644238 -115.624356) (xy 207.655873 -115.62384)
			(xy 207.676783 -115.613636) (xy 207.68437 -115.604798) (xy 207.702577 -115.582328) (xy 207.744594 -115.542592)
			(xy 207.792125 -115.509652) (xy 207.844083 -115.484261) (xy 207.899278 -115.467002) (xy 207.956445 -115.458269)
			(xy 207.98536 -115.457732) (xy 208.012618 -115.458112) (xy 208.066579 -115.465865) (xy 208.118887 -115.48122)
			(xy 208.168477 -115.503862) (xy 208.21434 -115.533332) (xy 208.255542 -115.56903) (xy 208.263867 -115.578636)
			(xy 209.079082 -115.578636) (xy 209.083153 -115.523014) (xy 209.095279 -115.468577) (xy 209.115202 -115.416486)
			(xy 209.142498 -115.367851) (xy 209.176584 -115.323708) (xy 209.216733 -115.284999) (xy 209.262091 -115.252548)
			(xy 209.311691 -115.227047) (xy 209.364475 -115.20904) (xy 209.419318 -115.19891) (xy 209.475052 -115.196873)
			(xy 209.530489 -115.202973) (xy 209.584446 -115.217079) (xy 209.635775 -115.238891) (xy 209.683381 -115.267945)
			(xy 209.726249 -115.30362) (xy 209.763466 -115.345157) (xy 209.794239 -115.39167) (xy 209.817911 -115.442167)
			(xy 209.833979 -115.495574) (xy 209.842099 -115.55075) (xy 209.842608 -115.578636) (xy 209.842099 -115.606522)
			(xy 209.833979 -115.661698) (xy 209.817911 -115.715105) (xy 209.794239 -115.765602) (xy 209.763466 -115.812115)
			(xy 209.726249 -115.853652) (xy 209.683381 -115.889327) (xy 209.635775 -115.918381) (xy 209.584446 -115.940193)
			(xy 209.530489 -115.954299) (xy 209.475052 -115.960399) (xy 209.419318 -115.958362) (xy 209.364475 -115.948232)
			(xy 209.311691 -115.930225) (xy 209.262091 -115.904724) (xy 209.216733 -115.872273) (xy 209.176584 -115.833564)
			(xy 209.142498 -115.789421) (xy 209.115202 -115.740786) (xy 209.095279 -115.688695) (xy 209.083153 -115.634258)
			(xy 209.079082 -115.578636) (xy 208.263867 -115.578636) (xy 208.291244 -115.610228) (xy 208.320719 -115.656088)
			(xy 208.343366 -115.705676) (xy 208.358726 -115.757982) (xy 208.366485 -115.811942) (xy 208.366485 -115.866458)
			(xy 208.358726 -115.920418) (xy 208.343366 -115.972724) (xy 208.320719 -116.022312) (xy 208.291244 -116.068172)
			(xy 208.255542 -116.10937) (xy 208.21434 -116.145068) (xy 208.168477 -116.174538) (xy 208.138502 -116.188224)
			(xy 223.368955 -116.188224) (xy 223.373268 -116.130954) (xy 223.386114 -116.074977) (xy 223.407204 -116.021557)
			(xy 223.436062 -115.971901) (xy 223.472035 -115.927131) (xy 223.492822 -115.907312) (xy 223.500224 -115.899791)
			(xy 223.508747 -115.88051) (xy 223.509332 -115.869974) (xy 223.509332 -115.795298) (xy 223.508808 -115.784748)
			(xy 223.500268 -115.765453) (xy 223.492822 -115.75796) (xy 223.473758 -115.739813) (xy 223.440301 -115.699182)
			(xy 223.412743 -115.65434) (xy 223.391605 -115.606137) (xy 223.37729 -115.555488) (xy 223.370069 -115.503353)
			(xy 223.369632 -115.477036) (xy 223.370118 -115.449785) (xy 223.377874 -115.395837) (xy 223.393229 -115.343542)
			(xy 223.415871 -115.293965) (xy 223.445337 -115.248115) (xy 223.481028 -115.206924) (xy 223.522219 -115.171233)
			(xy 223.568069 -115.141767) (xy 223.617646 -115.119125) (xy 223.669941 -115.10377) (xy 223.723889 -115.096014)
			(xy 223.778391 -115.096014) (xy 223.832339 -115.10377) (xy 223.884634 -115.119125) (xy 223.934211 -115.141767)
			(xy 223.980061 -115.171233) (xy 224.021252 -115.206924) (xy 224.056943 -115.248115) (xy 224.086409 -115.293965)
			(xy 224.109051 -115.343542) (xy 224.124406 -115.395837) (xy 224.132162 -115.449785) (xy 224.132648 -115.477036)
			(xy 224.132221 -115.503352) (xy 224.12498 -115.555482) (xy 224.110654 -115.606127) (xy 224.089514 -115.654326)
			(xy 224.06196 -115.699168) (xy 224.028514 -115.739805) (xy 224.009458 -115.75796) (xy 224.002081 -115.765502)
			(xy 223.99354 -115.784766) (xy 223.992948 -115.795298) (xy 223.992948 -115.869974) (xy 223.993464 -115.880526)
			(xy 224.002007 -115.899822) (xy 224.009458 -115.907312) (xy 224.03028 -115.927097) (xy 224.066251 -115.971876)
			(xy 224.095107 -116.021539) (xy 224.116195 -116.074966) (xy 224.12904 -116.130949) (xy 224.133352 -116.188224)
			(xy 225.907203 -116.188224) (xy 225.911514 -116.130957) (xy 225.924357 -116.074981) (xy 225.945443 -116.021562)
			(xy 225.974294 -115.971906) (xy 226.010261 -115.927133) (xy 226.031044 -115.907312) (xy 226.038434 -115.89978)
			(xy 226.046967 -115.880508) (xy 226.047554 -115.869974) (xy 226.047554 -115.795298) (xy 226.047053 -115.784745)
			(xy 226.0385 -115.765449) (xy 226.031044 -115.75796) (xy 226.011965 -115.739828) (xy 225.978512 -115.699192)
			(xy 225.950958 -115.654346) (xy 225.929824 -115.606141) (xy 225.915511 -115.55549) (xy 225.90829 -115.503353)
			(xy 225.907854 -115.477036) (xy 225.90834 -115.449785) (xy 225.916096 -115.395837) (xy 225.931451 -115.343542)
			(xy 225.954093 -115.293965) (xy 225.983559 -115.248115) (xy 226.01925 -115.206924) (xy 226.060441 -115.171233)
			(xy 226.106291 -115.141767) (xy 226.155868 -115.119125) (xy 226.208163 -115.10377) (xy 226.262111 -115.096014)
			(xy 226.316613 -115.096014) (xy 226.370561 -115.10377) (xy 226.422856 -115.119125) (xy 226.472433 -115.141767)
			(xy 226.518283 -115.171233) (xy 226.559474 -115.206924) (xy 226.595165 -115.248115) (xy 226.624631 -115.293965)
			(xy 226.647273 -115.343542) (xy 226.662628 -115.395837) (xy 226.670384 -115.449785) (xy 226.67087 -115.477036)
			(xy 226.670436 -115.503351) (xy 226.663196 -115.555482) (xy 226.648871 -115.606125) (xy 226.627732 -115.654324)
			(xy 226.60018 -115.699167) (xy 226.566735 -115.739805) (xy 226.54768 -115.75796) (xy 226.540291 -115.765492)
			(xy 226.53176 -115.784764) (xy 226.53117 -115.795298) (xy 226.53117 -115.869974) (xy 226.531708 -115.880522)
			(xy 226.540238 -115.899817) (xy 226.54768 -115.907312) (xy 226.568506 -115.927095) (xy 226.604484 -115.971871)
			(xy 226.633345 -116.021534) (xy 226.654438 -116.074961) (xy 226.667286 -116.130946) (xy 226.668309 -116.144533)
			(xy 230.110137 -116.144533) (xy 230.114448 -116.087265) (xy 230.127291 -116.03129) (xy 230.148377 -115.977871)
			(xy 230.17723 -115.928215) (xy 230.213198 -115.883444) (xy 230.233982 -115.863624) (xy 230.241372 -115.856093)
			(xy 230.249904 -115.83682) (xy 230.250492 -115.826286) (xy 230.250492 -115.75161) (xy 230.249973 -115.741059)
			(xy 230.241431 -115.721764) (xy 230.233982 -115.714272) (xy 230.213242 -115.694404) (xy 230.177267 -115.649638)
			(xy 230.148405 -115.599988) (xy 230.12731 -115.546573) (xy 230.114457 -115.4906) (xy 230.110137 -115.433333)
			(xy 230.114448 -115.376065) (xy 230.127291 -115.32009) (xy 230.148377 -115.266671) (xy 230.17723 -115.217015)
			(xy 230.213198 -115.172244) (xy 230.233982 -115.152424) (xy 230.241372 -115.144893) (xy 230.249904 -115.12562)
			(xy 230.250492 -115.115086) (xy 230.250492 -115.04041) (xy 230.249973 -115.029859) (xy 230.241431 -115.010564)
			(xy 230.233982 -115.003072) (xy 230.214916 -114.984927) (xy 230.181461 -114.944294) (xy 230.153904 -114.899452)
			(xy 230.132767 -114.851249) (xy 230.118452 -114.8006) (xy 230.111229 -114.748465) (xy 230.110792 -114.722148)
			(xy 230.1113 -114.694896) (xy 230.11905 -114.640947) (xy 230.1344 -114.58865) (xy 230.157037 -114.53907)
			(xy 230.1865 -114.493217) (xy 230.222189 -114.452023) (xy 230.263378 -114.416329) (xy 230.309228 -114.38686)
			(xy 230.358805 -114.364217) (xy 230.4111 -114.348861) (xy 230.465048 -114.341103) (xy 230.4923 -114.34064)
			(xy 230.518615 -114.341095) (xy 230.570744 -114.34833) (xy 230.621388 -114.362651) (xy 230.669587 -114.383786)
			(xy 230.71443 -114.411335) (xy 230.755068 -114.444777) (xy 230.773224 -114.46383) (xy 230.780744 -114.471234)
			(xy 230.800025 -114.479759) (xy 230.810562 -114.48034) (xy 230.885238 -114.48034) (xy 230.895784 -114.479779)
			(xy 230.915079 -114.471265) (xy 230.922576 -114.46383) (xy 230.940756 -114.444799) (xy 230.98138 -114.411338)
			(xy 231.026215 -114.383775) (xy 231.074411 -114.362632) (xy 231.125054 -114.34831) (xy 231.177185 -114.341081)
			(xy 231.2035 -114.34064) (xy 231.230755 -114.341055) (xy 231.28471 -114.348814) (xy 231.337012 -114.364172)
			(xy 231.386595 -114.386818) (xy 231.426389 -114.412395) (xy 232.727135 -114.412395) (xy 232.727135 -114.360405)
			(xy 232.735269 -114.309056) (xy 232.751336 -114.259612) (xy 232.774941 -114.21329) (xy 232.805502 -114.171231)
			(xy 232.842266 -114.134472) (xy 232.884329 -114.103917) (xy 232.930654 -114.080318) (xy 232.980101 -114.064258)
			(xy 233.031451 -114.056132) (xy 233.057446 -114.055652) (xy 233.084091 -114.056131) (xy 233.136694 -114.064663)
			(xy 233.187244 -114.081529) (xy 233.234431 -114.106293) (xy 233.277029 -114.138312) (xy 233.313934 -114.176754)
			(xy 233.32948 -114.1984) (xy 233.337844 -114.209686) (xy 233.359517 -114.227541) (xy 233.385231 -114.238824)
			(xy 233.413046 -114.242682) (xy 233.440861 -114.238824) (xy 233.466575 -114.227541) (xy 233.488248 -114.209686)
			(xy 233.496612 -114.1984) (xy 233.512202 -114.176793) (xy 233.549115 -114.138375) (xy 233.59171 -114.106373)
			(xy 233.638886 -114.081616) (xy 233.689421 -114.064743) (xy 233.742007 -114.056191) (xy 233.768646 -114.055652)
			(xy 233.794628 -114.056245) (xy 233.84595 -114.064381) (xy 233.895369 -114.080444) (xy 233.941666 -114.104039)
			(xy 233.983703 -114.134586) (xy 234.020444 -114.171332) (xy 234.050985 -114.213373) (xy 234.074574 -114.259674)
			(xy 234.09063 -114.309095) (xy 234.098758 -114.360418) (xy 234.098758 -114.412382) (xy 234.09063 -114.463705)
			(xy 234.074574 -114.513126) (xy 234.050985 -114.559427) (xy 234.020444 -114.601468) (xy 233.983703 -114.638214)
			(xy 233.945097 -114.666268) (xy 236.640876 -114.666268) (xy 236.644947 -114.610646) (xy 236.657073 -114.556209)
			(xy 236.676996 -114.504118) (xy 236.704292 -114.455483) (xy 236.738378 -114.41134) (xy 236.778527 -114.372631)
			(xy 236.823885 -114.34018) (xy 236.873485 -114.314679) (xy 236.926269 -114.296672) (xy 236.981112 -114.286542)
			(xy 237.036846 -114.284505) (xy 237.092283 -114.290605) (xy 237.14624 -114.304711) (xy 237.197569 -114.326523)
			(xy 237.245175 -114.355577) (xy 237.288043 -114.391252) (xy 237.32526 -114.432789) (xy 237.356033 -114.479302)
			(xy 237.379705 -114.529799) (xy 237.395773 -114.583206) (xy 237.403893 -114.638382) (xy 237.404295 -114.660426)
			(xy 244.161308 -114.660426) (xy 244.165379 -114.604804) (xy 244.177505 -114.550367) (xy 244.197428 -114.498276)
			(xy 244.224724 -114.449641) (xy 244.25881 -114.405498) (xy 244.298959 -114.366789) (xy 244.344317 -114.334338)
			(xy 244.393917 -114.308837) (xy 244.446701 -114.29083) (xy 244.501544 -114.2807) (xy 244.557278 -114.278663)
			(xy 244.612715 -114.284763) (xy 244.666672 -114.298869) (xy 244.718001 -114.320681) (xy 244.765607 -114.349735)
			(xy 244.808475 -114.38541) (xy 244.845692 -114.426947) (xy 244.876465 -114.47346) (xy 244.900137 -114.523957)
			(xy 244.916205 -114.577364) (xy 244.924325 -114.63254) (xy 244.924834 -114.660426) (xy 244.924325 -114.688312)
			(xy 244.916205 -114.743488) (xy 244.900137 -114.796895) (xy 244.876465 -114.847392) (xy 244.845692 -114.893905)
			(xy 244.808475 -114.935442) (xy 244.765607 -114.971117) (xy 244.718001 -115.000171) (xy 244.666672 -115.021983)
			(xy 244.612715 -115.036089) (xy 244.557278 -115.042189) (xy 244.501544 -115.040152) (xy 244.446701 -115.030022)
			(xy 244.393917 -115.012015) (xy 244.344317 -114.986514) (xy 244.298959 -114.954063) (xy 244.25881 -114.915354)
			(xy 244.224724 -114.871211) (xy 244.197428 -114.822576) (xy 244.177505 -114.770485) (xy 244.165379 -114.716048)
			(xy 244.161308 -114.660426) (xy 237.404295 -114.660426) (xy 237.404402 -114.666268) (xy 237.403893 -114.694154)
			(xy 237.395773 -114.74933) (xy 237.379705 -114.802737) (xy 237.356033 -114.853234) (xy 237.32526 -114.899747)
			(xy 237.288043 -114.941284) (xy 237.245175 -114.976959) (xy 237.197569 -115.006013) (xy 237.14624 -115.027825)
			(xy 237.092283 -115.041931) (xy 237.036846 -115.048031) (xy 236.981112 -115.045994) (xy 236.926269 -115.035864)
			(xy 236.873485 -115.017857) (xy 236.823885 -114.992356) (xy 236.778527 -114.959905) (xy 236.738378 -114.921196)
			(xy 236.704292 -114.877053) (xy 236.676996 -114.828418) (xy 236.657073 -114.776327) (xy 236.644947 -114.72189)
			(xy 236.640876 -114.666268) (xy 233.945097 -114.666268) (xy 233.941666 -114.668761) (xy 233.895369 -114.692356)
			(xy 233.84595 -114.708419) (xy 233.794628 -114.716555) (xy 233.768646 -114.717068) (xy 233.742001 -114.716586)
			(xy 233.689399 -114.708054) (xy 233.638849 -114.691187) (xy 233.591663 -114.666424) (xy 233.549064 -114.634406)
			(xy 233.512158 -114.595965) (xy 233.496612 -114.57432) (xy 233.488248 -114.563034) (xy 233.466575 -114.545179)
			(xy 233.440861 -114.533896) (xy 233.413046 -114.530038) (xy 233.385231 -114.533896) (xy 233.359517 -114.545179)
			(xy 233.337844 -114.563034) (xy 233.32948 -114.57432) (xy 233.3139 -114.595935) (xy 233.276985 -114.634351)
			(xy 233.234387 -114.666352) (xy 233.18721 -114.691108) (xy 233.136673 -114.707979) (xy 233.084085 -114.716529)
			(xy 233.057446 -114.717068) (xy 233.031451 -114.716668) (xy 232.980101 -114.708542) (xy 232.930654 -114.692482)
			(xy 232.884329 -114.668883) (xy 232.842266 -114.638328) (xy 232.805502 -114.601569) (xy 232.774941 -114.55951)
			(xy 232.751336 -114.513188) (xy 232.735269 -114.463744) (xy 232.727135 -114.412395) (xy 231.426389 -114.412395)
			(xy 231.432451 -114.416291) (xy 231.473645 -114.451989) (xy 231.509338 -114.493188) (xy 231.538805 -114.539047)
			(xy 231.561445 -114.588633) (xy 231.576797 -114.640937) (xy 231.584548 -114.694893) (xy 231.585008 -114.722148)
			(xy 231.58457 -114.748463) (xy 231.577329 -114.800593) (xy 231.563004 -114.851236) (xy 231.541866 -114.899435)
			(xy 231.514315 -114.944277) (xy 231.480872 -114.984916) (xy 231.461818 -115.003072) (xy 231.454429 -115.010604)
			(xy 231.445897 -115.029876) (xy 231.445308 -115.04041) (xy 231.445308 -115.115086) (xy 231.445829 -115.125637)
			(xy 231.45437 -115.144932) (xy 231.461818 -115.152424) (xy 231.482654 -115.172196) (xy 231.518629 -115.216975)
			(xy 231.547487 -115.26664) (xy 231.565585 -115.312489) (xy 232.727211 -115.312489) (xy 232.727211 -115.260511)
			(xy 232.735343 -115.209174) (xy 232.751406 -115.159741) (xy 232.775005 -115.113429) (xy 232.805559 -115.071381)
			(xy 232.842316 -115.034629) (xy 232.884369 -115.004081) (xy 232.930683 -114.980489) (xy 232.980119 -114.964432)
			(xy 233.031457 -114.956308) (xy 233.057446 -114.955828) (xy 233.084091 -114.956318) (xy 233.136692 -114.964848)
			(xy 233.187242 -114.981713) (xy 233.234428 -115.006475) (xy 233.277027 -115.038492) (xy 233.313933 -115.076932)
			(xy 233.32948 -115.098576) (xy 233.337844 -115.109862) (xy 233.359517 -115.127717) (xy 233.385231 -115.139)
			(xy 233.413046 -115.142858) (xy 233.440861 -115.139) (xy 233.466575 -115.127717) (xy 233.488248 -115.109862)
			(xy 233.496612 -115.098576) (xy 233.512195 -115.076964) (xy 233.54911 -115.038547) (xy 233.591707 -115.006547)
			(xy 233.638884 -114.98179) (xy 233.68942 -114.964918) (xy 233.742007 -114.956367) (xy 233.768646 -114.955828)
			(xy 233.794634 -114.956269) (xy 233.845968 -114.964406) (xy 233.895398 -114.980473) (xy 233.941706 -115.004074)
			(xy 233.983753 -115.034628) (xy 234.020502 -115.071383) (xy 234.05105 -115.113433) (xy 234.074645 -115.159745)
			(xy 234.090705 -115.209177) (xy 234.098835 -115.260512) (xy 234.098835 -115.312488) (xy 234.090704 -115.363823)
			(xy 234.074645 -115.413255) (xy 234.05105 -115.459567) (xy 234.020502 -115.501617) (xy 233.983753 -115.538372)
			(xy 233.941706 -115.568926) (xy 233.895398 -115.592527) (xy 233.845968 -115.608594) (xy 233.794634 -115.616731)
			(xy 233.768646 -115.617244) (xy 233.742 -115.616772) (xy 233.689397 -115.608239) (xy 233.638847 -115.591372)
			(xy 233.59166 -115.566606) (xy 233.549062 -115.534586) (xy 233.512158 -115.496142) (xy 233.496612 -115.474496)
			(xy 233.488248 -115.46321) (xy 233.466575 -115.445355) (xy 233.440861 -115.434072) (xy 233.413046 -115.430214)
			(xy 233.385231 -115.434072) (xy 233.359517 -115.445355) (xy 233.337844 -115.46321) (xy 233.32948 -115.474496)
			(xy 233.313923 -115.496128) (xy 233.277 -115.53454) (xy 233.234397 -115.566536) (xy 233.187215 -115.591288)
			(xy 233.136676 -115.608157) (xy 233.084086 -115.616705) (xy 233.057446 -115.617244) (xy 233.031457 -115.616692)
			(xy 232.980119 -115.608568) (xy 232.930683 -115.592511) (xy 232.884369 -115.568919) (xy 232.842316 -115.538371)
			(xy 232.805559 -115.501619) (xy 232.775005 -115.45957) (xy 232.751406 -115.413259) (xy 232.735343 -115.363826)
			(xy 232.727211 -115.312489) (xy 231.565585 -115.312489) (xy 231.568577 -115.320069) (xy 231.581422 -115.376054)
			(xy 231.585733 -115.433333) (xy 231.581413 -115.49061) (xy 231.568557 -115.546594) (xy 231.547458 -115.600018)
			(xy 231.518592 -115.649678) (xy 231.482609 -115.694452) (xy 231.461818 -115.714272) (xy 231.454429 -115.721804)
			(xy 231.445897 -115.741076) (xy 231.445308 -115.75161) (xy 231.445308 -115.826286) (xy 231.445829 -115.836837)
			(xy 231.45437 -115.856132) (xy 231.461818 -115.863624) (xy 231.482654 -115.883396) (xy 231.518629 -115.928175)
			(xy 231.547487 -115.97784) (xy 231.568577 -116.031269) (xy 231.581422 -116.087254) (xy 231.585733 -116.144533)
			(xy 231.581413 -116.20181) (xy 231.578959 -116.212495) (xy 232.727133 -116.212495) (xy 232.727133 -116.160505)
			(xy 232.735267 -116.109156) (xy 232.751334 -116.059711) (xy 232.774939 -116.013389) (xy 232.8055 -115.97133)
			(xy 232.842265 -115.93457) (xy 232.884328 -115.904015) (xy 232.930653 -115.880417) (xy 232.9801 -115.864356)
			(xy 233.031451 -115.85623) (xy 233.057446 -115.85575) (xy 233.084091 -115.85623) (xy 233.136694 -115.864762)
			(xy 233.187244 -115.881628) (xy 233.23443 -115.906392) (xy 233.277029 -115.93841) (xy 233.313934 -115.976852)
			(xy 233.32948 -115.998498) (xy 233.337844 -116.009784) (xy 233.359517 -116.027639) (xy 233.385231 -116.038922)
			(xy 233.413046 -116.04278) (xy 233.440861 -116.038922) (xy 233.466575 -116.027639) (xy 233.488248 -116.009784)
			(xy 233.496612 -115.998498) (xy 233.512202 -115.976891) (xy 233.549115 -115.938473) (xy 233.59171 -115.906471)
			(xy 233.638886 -115.881714) (xy 233.689421 -115.864841) (xy 233.742007 -115.856289) (xy 233.768646 -115.85575)
			(xy 233.794627 -115.856347) (xy 233.84595 -115.864483) (xy 233.895368 -115.880546) (xy 233.941665 -115.904141)
			(xy 233.983702 -115.934687) (xy 233.985283 -115.936268) (xy 235.270546 -115.936268) (xy 235.274617 -115.880646)
			(xy 235.286743 -115.826209) (xy 235.306666 -115.774118) (xy 235.333962 -115.725483) (xy 235.368048 -115.68134)
			(xy 235.408197 -115.642631) (xy 235.453555 -115.61018) (xy 235.503155 -115.584679) (xy 235.555939 -115.566672)
			(xy 235.610782 -115.556542) (xy 235.666516 -115.554505) (xy 235.721953 -115.560605) (xy 235.77591 -115.574711)
			(xy 235.827239 -115.596523) (xy 235.874845 -115.625577) (xy 235.917713 -115.661252) (xy 235.95493 -115.702789)
			(xy 235.985703 -115.749302) (xy 236.009375 -115.799799) (xy 236.025443 -115.853206) (xy 236.033563 -115.908382)
			(xy 236.034072 -115.936268) (xy 236.033563 -115.964154) (xy 236.025443 -116.01933) (xy 236.009375 -116.072737)
			(xy 235.985703 -116.123234) (xy 235.95493 -116.169747) (xy 235.917713 -116.211284) (xy 235.874845 -116.246959)
			(xy 235.827239 -116.276013) (xy 235.77591 -116.297825) (xy 235.721953 -116.311931) (xy 235.666516 -116.318031)
			(xy 235.610782 -116.315994) (xy 235.555939 -116.305864) (xy 235.503155 -116.287857) (xy 235.453555 -116.262356)
			(xy 235.408197 -116.229905) (xy 235.368048 -116.191196) (xy 235.333962 -116.147053) (xy 235.306666 -116.098418)
			(xy 235.286743 -116.046327) (xy 235.274617 -115.99189) (xy 235.270546 -115.936268) (xy 233.985283 -115.936268)
			(xy 234.020442 -115.971434) (xy 234.050983 -116.013474) (xy 234.074572 -116.059775) (xy 234.090628 -116.109195)
			(xy 234.098756 -116.160518) (xy 234.098756 -116.212482) (xy 234.090628 -116.263805) (xy 234.074572 -116.313225)
			(xy 234.050983 -116.359526) (xy 234.020442 -116.401566) (xy 233.983702 -116.438313) (xy 233.970963 -116.44757)
			(xy 236.707678 -116.44757) (xy 236.711749 -116.391948) (xy 236.723875 -116.337511) (xy 236.743798 -116.28542)
			(xy 236.771094 -116.236785) (xy 236.80518 -116.192642) (xy 236.845329 -116.153933) (xy 236.890687 -116.121482)
			(xy 236.940287 -116.095981) (xy 236.993071 -116.077974) (xy 237.047914 -116.067844) (xy 237.103648 -116.065807)
			(xy 237.159085 -116.071907) (xy 237.213042 -116.086013) (xy 237.264371 -116.107825) (xy 237.311977 -116.136879)
			(xy 237.354845 -116.172554) (xy 237.392062 -116.214091) (xy 237.422835 -116.260604) (xy 237.446507 -116.311101)
			(xy 237.462575 -116.364508) (xy 237.470695 -116.419684) (xy 237.471204 -116.44757) (xy 237.470695 -116.475456)
			(xy 237.462575 -116.530632) (xy 237.446507 -116.584039) (xy 237.422835 -116.634536) (xy 237.392062 -116.681049)
			(xy 237.354845 -116.722586) (xy 237.311977 -116.758261) (xy 237.264371 -116.787315) (xy 237.213042 -116.809127)
			(xy 237.159085 -116.823233) (xy 237.103648 -116.829333) (xy 237.047914 -116.827296) (xy 236.993071 -116.817166)
			(xy 236.940287 -116.799159) (xy 236.890687 -116.773658) (xy 236.845329 -116.741207) (xy 236.80518 -116.702498)
			(xy 236.771094 -116.658355) (xy 236.743798 -116.60972) (xy 236.723875 -116.557629) (xy 236.711749 -116.503192)
			(xy 236.707678 -116.44757) (xy 233.970963 -116.44757) (xy 233.941665 -116.468859) (xy 233.895368 -116.492454)
			(xy 233.84595 -116.508517) (xy 233.794627 -116.516653) (xy 233.768646 -116.517166) (xy 233.742001 -116.516685)
			(xy 233.689399 -116.508153) (xy 233.638849 -116.491286) (xy 233.591663 -116.466523) (xy 233.549064 -116.434505)
			(xy 233.512158 -116.396063) (xy 233.496612 -116.374418) (xy 233.488248 -116.363132) (xy 233.466575 -116.345277)
			(xy 233.440861 -116.333994) (xy 233.413046 -116.330136) (xy 233.385231 -116.333994) (xy 233.359517 -116.345277)
			(xy 233.337844 -116.363132) (xy 233.32948 -116.374418) (xy 233.3139 -116.396033) (xy 233.276984 -116.434449)
			(xy 233.234387 -116.46645) (xy 233.187209 -116.491206) (xy 233.136673 -116.508077) (xy 233.084085 -116.516627)
			(xy 233.057446 -116.517166) (xy 233.031451 -116.51677) (xy 232.9801 -116.508644) (xy 232.930654 -116.492583)
			(xy 232.884328 -116.468985) (xy 232.842265 -116.43843) (xy 232.8055 -116.40167) (xy 232.774939 -116.359611)
			(xy 232.751334 -116.313289) (xy 232.735267 -116.263844) (xy 232.727133 -116.212495) (xy 231.578959 -116.212495)
			(xy 231.568557 -116.257794) (xy 231.547458 -116.311218) (xy 231.518592 -116.360878) (xy 231.482609 -116.405652)
			(xy 231.461818 -116.425472) (xy 231.454429 -116.433004) (xy 231.445897 -116.452276) (xy 231.445308 -116.46281)
			(xy 231.445308 -116.537486) (xy 231.445829 -116.548037) (xy 231.45437 -116.567332) (xy 231.461818 -116.574824)
			(xy 231.480882 -116.592971) (xy 231.514337 -116.633603) (xy 231.541895 -116.678445) (xy 231.563032 -116.726648)
			(xy 231.577347 -116.777296) (xy 231.58457 -116.829431) (xy 231.585008 -116.855748) (xy 231.584567 -116.883)
			(xy 231.576804 -116.93695) (xy 231.561443 -116.989245) (xy 231.538796 -117.038823) (xy 231.509325 -117.084673)
			(xy 231.485302 -117.112393) (xy 232.727155 -117.112393) (xy 232.727155 -117.060407) (xy 232.735289 -117.009061)
			(xy 232.751355 -116.959619) (xy 232.774958 -116.9133) (xy 232.805517 -116.871244) (xy 232.842279 -116.834487)
			(xy 232.88434 -116.803934) (xy 232.930662 -116.780337) (xy 232.980106 -116.764278) (xy 233.031453 -116.756152)
			(xy 233.057446 -116.755672) (xy 233.084092 -116.756143) (xy 233.136695 -116.764675) (xy 233.187246 -116.781542)
			(xy 233.234433 -116.806308) (xy 233.277031 -116.838328) (xy 233.313935 -116.876773) (xy 233.32948 -116.89842)
			(xy 233.337844 -116.909706) (xy 233.359517 -116.927561) (xy 233.385231 -116.938844) (xy 233.413046 -116.942702)
			(xy 233.440861 -116.938844) (xy 233.466575 -116.927561) (xy 233.488248 -116.909706) (xy 233.496612 -116.89842)
			(xy 233.512179 -116.876796) (xy 233.549099 -116.838383) (xy 233.5917 -116.806385) (xy 233.63888 -116.781631)
			(xy 233.689418 -116.764761) (xy 233.742006 -116.756211) (xy 233.768646 -116.755672) (xy 233.794629 -116.756225)
			(xy 233.845955 -116.764361) (xy 233.895376 -116.780425) (xy 233.941677 -116.804022) (xy 233.983716 -116.83457)
			(xy 234.02046 -116.871319) (xy 234.051002 -116.913362) (xy 234.074593 -116.959666) (xy 234.09065 -117.00909)
			(xy 234.098779 -117.060417) (xy 234.098779 -117.112383) (xy 234.09065 -117.16371) (xy 234.074593 -117.213134)
			(xy 234.051002 -117.259438) (xy 234.02046 -117.301481) (xy 233.983716 -117.33823) (xy 233.941677 -117.368778)
			(xy 233.895376 -117.392375) (xy 233.845955 -117.408439) (xy 233.794629 -117.416575) (xy 233.768646 -117.417088)
			(xy 233.742001 -117.416597) (xy 233.6894 -117.408066) (xy 233.638851 -117.391201) (xy 233.591665 -117.366439)
			(xy 233.549066 -117.334423) (xy 233.512159 -117.295984) (xy 233.496612 -117.27434) (xy 233.488248 -117.263054)
			(xy 233.466575 -117.245199) (xy 233.440861 -117.233916) (xy 233.413046 -117.230058) (xy 233.385231 -117.233916)
			(xy 233.359517 -117.245199) (xy 233.337844 -117.263054) (xy 233.32948 -117.27434) (xy 233.313906 -117.295959)
			(xy 233.276989 -117.334375) (xy 233.23439 -117.366374) (xy 233.187211 -117.391129) (xy 233.136674 -117.408)
			(xy 233.084085 -117.416549) (xy 233.057446 -117.417088) (xy 233.031453 -117.416648) (xy 232.980106 -117.408522)
			(xy 232.930662 -117.392463) (xy 232.88434 -117.368866) (xy 232.842279 -117.338313) (xy 232.805517 -117.301556)
			(xy 232.774958 -117.2595) (xy 232.751355 -117.213181) (xy 232.735289 -117.163739) (xy 232.727155 -117.112393)
			(xy 231.485302 -117.112393) (xy 231.473629 -117.125863) (xy 231.432434 -117.161553) (xy 231.386581 -117.191019)
			(xy 231.337 -117.213659) (xy 231.284703 -117.229014) (xy 231.230752 -117.23677) (xy 231.2035 -117.237256)
			(xy 231.177185 -117.236803) (xy 231.125056 -117.229567) (xy 231.074412 -117.215246) (xy 231.026213 -117.194111)
			(xy 230.98137 -117.166562) (xy 230.940732 -117.133119) (xy 230.922576 -117.114066) (xy 230.915056 -117.106662)
			(xy 230.895775 -117.098136) (xy 230.885238 -117.097556) (xy 230.810562 -117.097556) (xy 230.800017 -117.098118)
			(xy 230.780722 -117.106632) (xy 230.773224 -117.114066) (xy 230.755063 -117.133116) (xy 230.714433 -117.166571)
			(xy 230.669593 -117.194129) (xy 230.621394 -117.215268) (xy 230.570748 -117.229587) (xy 230.518616 -117.236815)
			(xy 230.4923 -117.237256) (xy 230.465051 -117.236722) (xy 230.411107 -117.228967) (xy 230.358816 -117.213614)
			(xy 230.309242 -117.190977) (xy 230.263394 -117.161515) (xy 230.222205 -117.125829) (xy 230.186514 -117.084644)
			(xy 230.157046 -117.0388) (xy 230.134402 -116.989229) (xy 230.119043 -116.93694) (xy 230.111281 -116.882997)
			(xy 230.110792 -116.855748) (xy 230.111227 -116.829433) (xy 230.118469 -116.777303) (xy 230.132795 -116.72666)
			(xy 230.153933 -116.678461) (xy 230.181485 -116.633618) (xy 230.214928 -116.59298) (xy 230.233982 -116.574824)
			(xy 230.241372 -116.567293) (xy 230.249904 -116.54802) (xy 230.250492 -116.537486) (xy 230.250492 -116.46281)
			(xy 230.249973 -116.452259) (xy 230.241431 -116.432964) (xy 230.233982 -116.425472) (xy 230.213242 -116.405604)
			(xy 230.177267 -116.360838) (xy 230.148405 -116.311188) (xy 230.12731 -116.257773) (xy 230.114457 -116.2018)
			(xy 230.110137 -116.144533) (xy 226.668309 -116.144533) (xy 226.671599 -116.188224) (xy 226.667279 -116.245502)
			(xy 226.654424 -116.301485) (xy 226.633324 -116.35491) (xy 226.604456 -116.404569) (xy 226.568472 -116.449341)
			(xy 226.54768 -116.46916) (xy 226.540291 -116.476692) (xy 226.53176 -116.495964) (xy 226.53117 -116.506498)
			(xy 226.53117 -116.581174) (xy 226.531708 -116.591722) (xy 226.540238 -116.611017) (xy 226.54768 -116.618512)
			(xy 226.566731 -116.636673) (xy 226.600189 -116.677301) (xy 226.627749 -116.72214) (xy 226.648889 -116.77034)
			(xy 226.663207 -116.820987) (xy 226.670432 -116.87312) (xy 226.67087 -116.899436) (xy 226.670384 -116.926687)
			(xy 226.662628 -116.980635) (xy 226.647273 -117.03293) (xy 226.624631 -117.082507) (xy 226.595165 -117.128357)
			(xy 226.559474 -117.169548) (xy 226.518283 -117.205239) (xy 226.472433 -117.234705) (xy 226.422856 -117.257347)
			(xy 226.370561 -117.272702) (xy 226.316613 -117.280458) (xy 226.262111 -117.280458) (xy 226.208163 -117.272702)
			(xy 226.155868 -117.257347) (xy 226.106291 -117.234705) (xy 226.060441 -117.205239) (xy 226.01925 -117.169548)
			(xy 225.983559 -117.128357) (xy 225.954093 -117.082507) (xy 225.931451 -117.03293) (xy 225.916096 -116.980635)
			(xy 225.90834 -116.926687) (xy 225.907854 -116.899436) (xy 225.908262 -116.87312) (xy 225.915506 -116.820988)
			(xy 225.929836 -116.770343) (xy 225.950979 -116.722144) (xy 225.978537 -116.677302) (xy 226.011987 -116.636666)
			(xy 226.031044 -116.618512) (xy 226.038434 -116.61098) (xy 226.046967 -116.591708) (xy 226.047554 -116.581174)
			(xy 226.047554 -116.506498) (xy 226.047053 -116.495945) (xy 226.0385 -116.476649) (xy 226.031044 -116.46916)
			(xy 226.010294 -116.449303) (xy 225.974322 -116.404534) (xy 225.945464 -116.354882) (xy 225.924372 -116.301465)
			(xy 225.911521 -116.245492) (xy 225.907203 -116.188224) (xy 224.133352 -116.188224) (xy 224.129033 -116.2455)
			(xy 224.11618 -116.301481) (xy 224.095085 -116.354905) (xy 224.066223 -116.404564) (xy 224.030247 -116.449339)
			(xy 224.009458 -116.46916) (xy 224.002081 -116.476702) (xy 223.99354 -116.495966) (xy 223.992948 -116.506498)
			(xy 223.992948 -116.581174) (xy 223.993464 -116.591726) (xy 224.002007 -116.611022) (xy 224.009458 -116.618512)
			(xy 224.028523 -116.636657) (xy 224.061977 -116.677291) (xy 224.089534 -116.722133) (xy 224.11067 -116.770336)
			(xy 224.124986 -116.820985) (xy 224.13221 -116.873119) (xy 224.132648 -116.899436) (xy 224.132162 -116.926687)
			(xy 224.124406 -116.980635) (xy 224.109051 -117.03293) (xy 224.086409 -117.082507) (xy 224.056943 -117.128357)
			(xy 224.021252 -117.169548) (xy 223.980061 -117.205239) (xy 223.934211 -117.234705) (xy 223.884634 -117.257347)
			(xy 223.832339 -117.272702) (xy 223.778391 -117.280458) (xy 223.723889 -117.280458) (xy 223.669941 -117.272702)
			(xy 223.617646 -117.257347) (xy 223.568069 -117.234705) (xy 223.522219 -117.205239) (xy 223.481028 -117.169548)
			(xy 223.445337 -117.128357) (xy 223.415871 -117.082507) (xy 223.393229 -117.03293) (xy 223.377874 -116.980635)
			(xy 223.370118 -116.926687) (xy 223.369632 -116.899436) (xy 223.370047 -116.87312) (xy 223.377291 -116.820989)
			(xy 223.39162 -116.770345) (xy 223.412762 -116.722146) (xy 223.440318 -116.677304) (xy 223.473766 -116.636667)
			(xy 223.492822 -116.618512) (xy 223.500224 -116.610991) (xy 223.508747 -116.59171) (xy 223.509332 -116.581174)
			(xy 223.509332 -116.506498) (xy 223.508808 -116.495948) (xy 223.500268 -116.476653) (xy 223.492822 -116.46916)
			(xy 223.472068 -116.449305) (xy 223.436089 -116.404539) (xy 223.407225 -116.354887) (xy 223.386128 -116.30147)
			(xy 223.373275 -116.245494) (xy 223.368955 -116.188224) (xy 208.138502 -116.188224) (xy 208.118887 -116.19718)
			(xy 208.066579 -116.212535) (xy 208.012618 -116.220288) (xy 207.98536 -116.220748) (xy 207.956444 -116.220207)
			(xy 207.899273 -116.211485) (xy 207.844073 -116.194233) (xy 207.792111 -116.168846) (xy 207.744577 -116.135905)
			(xy 207.70256 -116.096167) (xy 207.68437 -116.073682) (xy 207.676769 -116.064868) (xy 207.655864 -116.054689)
			(xy 207.644238 -116.054124) (xy 207.564482 -116.054124) (xy 207.552849 -116.054659) (xy 207.531939 -116.06485)
			(xy 207.52435 -116.073682) (xy 207.506126 -116.096138) (xy 207.464114 -116.135876) (xy 207.416586 -116.168818)
			(xy 207.364631 -116.194212) (xy 207.309439 -116.211474) (xy 207.252274 -116.220209) (xy 207.22336 -116.220748)
			(xy 207.196114 -116.220179) (xy 207.142176 -116.212419) (xy 207.089891 -116.197062) (xy 207.040324 -116.174421)
			(xy 206.994484 -116.144957) (xy 206.953303 -116.109269) (xy 206.917619 -116.068084) (xy 206.88816 -116.02224)
			(xy 206.865524 -115.972671) (xy 206.850173 -115.920385) (xy 206.842418 -115.866447) (xy 197.824165 -115.866447)
			(xy 197.659523 -117.191028) (xy 213.616792 -117.191028) (xy 213.620863 -117.135406) (xy 213.632989 -117.080969)
			(xy 213.652912 -117.028878) (xy 213.680208 -116.980243) (xy 213.714294 -116.9361) (xy 213.754443 -116.897391)
			(xy 213.799801 -116.86494) (xy 213.849401 -116.839439) (xy 213.902185 -116.821432) (xy 213.957028 -116.811302)
			(xy 214.012762 -116.809265) (xy 214.068199 -116.815365) (xy 214.122156 -116.829471) (xy 214.173485 -116.851283)
			(xy 214.221091 -116.880337) (xy 214.263959 -116.916012) (xy 214.301176 -116.957549) (xy 214.331949 -117.004062)
			(xy 214.355621 -117.054559) (xy 214.371689 -117.107966) (xy 214.379809 -117.163142) (xy 214.380318 -117.191028)
			(xy 214.379809 -117.218914) (xy 214.371689 -117.27409) (xy 214.365424 -117.294914) (xy 216.75852 -117.294914)
			(xy 216.75899 -117.2686) (xy 216.766224 -117.216471) (xy 216.780542 -117.165828) (xy 216.801674 -117.117629)
			(xy 216.82922 -117.072786) (xy 216.862658 -117.032146) (xy 216.88171 -117.01399) (xy 216.88912 -117.006475)
			(xy 216.897639 -116.98719) (xy 216.89822 -116.976652) (xy 216.89822 -116.901976) (xy 216.897658 -116.89143)
			(xy 216.889145 -116.872135) (xy 216.88171 -116.864638) (xy 216.862633 -116.846504) (xy 216.829178 -116.80587)
			(xy 216.801621 -116.761025) (xy 216.780486 -116.71282) (xy 216.766174 -116.662169) (xy 216.758955 -116.610031)
			(xy 216.75852 -116.583714) (xy 216.759006 -116.556463) (xy 216.766762 -116.502515) (xy 216.782117 -116.45022)
			(xy 216.804759 -116.400643) (xy 216.834225 -116.354793) (xy 216.869916 -116.313602) (xy 216.911107 -116.277911)
			(xy 216.956957 -116.248445) (xy 217.006534 -116.225803) (xy 217.058829 -116.210448) (xy 217.112777 -116.202692)
			(xy 217.167279 -116.202692) (xy 217.221227 -116.210448) (xy 217.273522 -116.225803) (xy 217.323099 -116.248445)
			(xy 217.368949 -116.277911) (xy 217.41014 -116.313602) (xy 217.445831 -116.354793) (xy 217.475297 -116.400643)
			(xy 217.497939 -116.45022) (xy 217.513294 -116.502515) (xy 217.52105 -116.556463) (xy 217.521536 -116.583714)
			(xy 217.521066 -116.610028) (xy 217.51383 -116.662156) (xy 217.499511 -116.712798) (xy 217.478379 -116.760997)
			(xy 217.450834 -116.80584) (xy 217.417397 -116.846481) (xy 217.398346 -116.864638) (xy 217.390933 -116.87215)
			(xy 217.382413 -116.891437) (xy 217.381836 -116.901976) (xy 217.381836 -116.976652) (xy 217.382367 -116.987202)
			(xy 217.3909 -117.006498) (xy 217.398346 -117.01399) (xy 217.417398 -117.032148) (xy 217.450854 -117.072779)
			(xy 217.478412 -117.117619) (xy 217.499551 -117.165819) (xy 217.513869 -117.216465) (xy 217.521096 -117.268598)
			(xy 217.521536 -117.294914) (xy 218.79052 -117.294914) (xy 218.79099 -117.2686) (xy 218.798224 -117.216471)
			(xy 218.812542 -117.165828) (xy 218.833674 -117.117629) (xy 218.86122 -117.072786) (xy 218.894658 -117.032146)
			(xy 218.91371 -117.01399) (xy 218.92112 -117.006475) (xy 218.929639 -116.98719) (xy 218.93022 -116.976652)
			(xy 218.93022 -116.901976) (xy 218.929658 -116.89143) (xy 218.921145 -116.872135) (xy 218.91371 -116.864638)
			(xy 218.894633 -116.846504) (xy 218.861178 -116.80587) (xy 218.833621 -116.761025) (xy 218.812486 -116.71282)
			(xy 218.798174 -116.662169) (xy 218.790955 -116.610031) (xy 218.79052 -116.583714) (xy 218.791006 -116.556463)
			(xy 218.798762 -116.502515) (xy 218.814117 -116.45022) (xy 218.836759 -116.400643) (xy 218.866225 -116.354793)
			(xy 218.901916 -116.313602) (xy 218.943107 -116.277911) (xy 218.988957 -116.248445) (xy 219.038534 -116.225803)
			(xy 219.090829 -116.210448) (xy 219.144777 -116.202692) (xy 219.199279 -116.202692) (xy 219.253227 -116.210448)
			(xy 219.305522 -116.225803) (xy 219.355099 -116.248445) (xy 219.400949 -116.277911) (xy 219.44214 -116.313602)
			(xy 219.477831 -116.354793) (xy 219.507297 -116.400643) (xy 219.529939 -116.45022) (xy 219.545294 -116.502515)
			(xy 219.55305 -116.556463) (xy 219.553536 -116.583714) (xy 219.553066 -116.610028) (xy 219.54583 -116.662156)
			(xy 219.531511 -116.712798) (xy 219.510379 -116.760997) (xy 219.482834 -116.80584) (xy 219.449397 -116.846481)
			(xy 219.430346 -116.864638) (xy 219.422933 -116.87215) (xy 219.414413 -116.891437) (xy 219.413836 -116.901976)
			(xy 219.413836 -116.976652) (xy 219.414367 -116.987202) (xy 219.4229 -117.006498) (xy 219.430346 -117.01399)
			(xy 219.449398 -117.032148) (xy 219.482854 -117.072779) (xy 219.510412 -117.117619) (xy 219.531551 -117.165819)
			(xy 219.545869 -117.216465) (xy 219.553096 -117.268598) (xy 219.553536 -117.294914) (xy 220.82252 -117.294914)
			(xy 220.82299 -117.2686) (xy 220.830224 -117.216471) (xy 220.844542 -117.165828) (xy 220.865674 -117.117629)
			(xy 220.89322 -117.072786) (xy 220.926658 -117.032146) (xy 220.94571 -117.01399) (xy 220.95312 -117.006475)
			(xy 220.961639 -116.98719) (xy 220.96222 -116.976652) (xy 220.96222 -116.901976) (xy 220.961658 -116.89143)
			(xy 220.953145 -116.872135) (xy 220.94571 -116.864638) (xy 220.926633 -116.846504) (xy 220.893178 -116.80587)
			(xy 220.865621 -116.761025) (xy 220.844486 -116.71282) (xy 220.830174 -116.662169) (xy 220.822955 -116.610031)
			(xy 220.82252 -116.583714) (xy 220.823006 -116.556463) (xy 220.830762 -116.502515) (xy 220.846117 -116.45022)
			(xy 220.868759 -116.400643) (xy 220.898225 -116.354793) (xy 220.933916 -116.313602) (xy 220.975107 -116.277911)
			(xy 221.020957 -116.248445) (xy 221.070534 -116.225803) (xy 221.122829 -116.210448) (xy 221.176777 -116.202692)
			(xy 221.231279 -116.202692) (xy 221.285227 -116.210448) (xy 221.337522 -116.225803) (xy 221.387099 -116.248445)
			(xy 221.432949 -116.277911) (xy 221.47414 -116.313602) (xy 221.509831 -116.354793) (xy 221.539297 -116.400643)
			(xy 221.561939 -116.45022) (xy 221.577294 -116.502515) (xy 221.58505 -116.556463) (xy 221.585536 -116.583714)
			(xy 221.585066 -116.610028) (xy 221.57783 -116.662156) (xy 221.563511 -116.712798) (xy 221.542379 -116.760997)
			(xy 221.514834 -116.80584) (xy 221.481397 -116.846481) (xy 221.462346 -116.864638) (xy 221.454933 -116.87215)
			(xy 221.446413 -116.891437) (xy 221.445836 -116.901976) (xy 221.445836 -116.976652) (xy 221.446367 -116.987202)
			(xy 221.4549 -117.006498) (xy 221.462346 -117.01399) (xy 221.481398 -117.032148) (xy 221.514854 -117.072779)
			(xy 221.542412 -117.117619) (xy 221.563551 -117.165819) (xy 221.577869 -117.216465) (xy 221.585096 -117.268598)
			(xy 221.585536 -117.294914) (xy 221.58505 -117.322165) (xy 221.577294 -117.376113) (xy 221.561939 -117.428408)
			(xy 221.539297 -117.477985) (xy 221.509831 -117.523835) (xy 221.47414 -117.565026) (xy 221.432949 -117.600717)
			(xy 221.387099 -117.630183) (xy 221.337522 -117.652825) (xy 221.285227 -117.66818) (xy 221.231279 -117.675936)
			(xy 221.176777 -117.675936) (xy 221.122829 -117.66818) (xy 221.070534 -117.652825) (xy 221.020957 -117.630183)
			(xy 220.975107 -117.600717) (xy 220.933916 -117.565026) (xy 220.898225 -117.523835) (xy 220.868759 -117.477985)
			(xy 220.846117 -117.428408) (xy 220.830762 -117.376113) (xy 220.823006 -117.322165) (xy 220.82252 -117.294914)
			(xy 219.553536 -117.294914) (xy 219.55305 -117.322165) (xy 219.545294 -117.376113) (xy 219.529939 -117.428408)
			(xy 219.507297 -117.477985) (xy 219.477831 -117.523835) (xy 219.44214 -117.565026) (xy 219.400949 -117.600717)
			(xy 219.355099 -117.630183) (xy 219.305522 -117.652825) (xy 219.253227 -117.66818) (xy 219.199279 -117.675936)
			(xy 219.144777 -117.675936) (xy 219.090829 -117.66818) (xy 219.038534 -117.652825) (xy 218.988957 -117.630183)
			(xy 218.943107 -117.600717) (xy 218.901916 -117.565026) (xy 218.866225 -117.523835) (xy 218.836759 -117.477985)
			(xy 218.814117 -117.428408) (xy 218.798762 -117.376113) (xy 218.791006 -117.322165) (xy 218.79052 -117.294914)
			(xy 217.521536 -117.294914) (xy 217.52105 -117.322165) (xy 217.513294 -117.376113) (xy 217.497939 -117.428408)
			(xy 217.475297 -117.477985) (xy 217.445831 -117.523835) (xy 217.41014 -117.565026) (xy 217.368949 -117.600717)
			(xy 217.323099 -117.630183) (xy 217.273522 -117.652825) (xy 217.221227 -117.66818) (xy 217.167279 -117.675936)
			(xy 217.112777 -117.675936) (xy 217.058829 -117.66818) (xy 217.006534 -117.652825) (xy 216.956957 -117.630183)
			(xy 216.911107 -117.600717) (xy 216.869916 -117.565026) (xy 216.834225 -117.523835) (xy 216.804759 -117.477985)
			(xy 216.782117 -117.428408) (xy 216.766762 -117.376113) (xy 216.759006 -117.322165) (xy 216.75852 -117.294914)
			(xy 214.365424 -117.294914) (xy 214.355621 -117.327497) (xy 214.331949 -117.377994) (xy 214.301176 -117.424507)
			(xy 214.263959 -117.466044) (xy 214.221091 -117.501719) (xy 214.173485 -117.530773) (xy 214.122156 -117.552585)
			(xy 214.068199 -117.566691) (xy 214.012762 -117.572791) (xy 213.957028 -117.570754) (xy 213.902185 -117.560624)
			(xy 213.849401 -117.542617) (xy 213.799801 -117.517116) (xy 213.754443 -117.484665) (xy 213.714294 -117.445956)
			(xy 213.680208 -117.401813) (xy 213.652912 -117.353178) (xy 213.632989 -117.301087) (xy 213.620863 -117.24665)
			(xy 213.616792 -117.191028) (xy 197.659523 -117.191028) (xy 197.619112 -117.516148) (xy 197.593889 -117.719348)
			(xy 236.702598 -117.719348) (xy 236.706669 -117.663726) (xy 236.718795 -117.609289) (xy 236.738718 -117.557198)
			(xy 236.766014 -117.508563) (xy 236.8001 -117.46442) (xy 236.840249 -117.425711) (xy 236.885607 -117.39326)
			(xy 236.935207 -117.367759) (xy 236.987991 -117.349752) (xy 237.042834 -117.339622) (xy 237.098568 -117.337585)
			(xy 237.154005 -117.343685) (xy 237.207962 -117.357791) (xy 237.259291 -117.379603) (xy 237.306897 -117.408657)
			(xy 237.337477 -117.434106) (xy 245.576852 -117.434106) (xy 245.577309 -117.406735) (xy 245.585127 -117.352555)
			(xy 245.600618 -117.300052) (xy 245.623462 -117.250305) (xy 245.653189 -117.204339) (xy 245.670832 -117.183408)
			(xy 245.671086 -117.183154) (xy 245.676655 -117.176055) (xy 245.682913 -117.159148) (xy 245.683278 -117.150134)
			(xy 245.683278 -117.083078) (xy 245.682936 -117.074059) (xy 245.676679 -117.057142) (xy 245.671086 -117.050058)
			(xy 245.670832 -117.050058) (xy 245.670832 -117.049804) (xy 245.653197 -117.028867) (xy 245.623472 -116.9829)
			(xy 245.600626 -116.933154) (xy 245.585129 -116.880653) (xy 245.577299 -116.826475) (xy 245.577299 -116.771734)
			(xy 245.585127 -116.717556) (xy 245.600622 -116.665054) (xy 245.623467 -116.615308) (xy 245.653192 -116.569341)
			(xy 245.670832 -116.548408) (xy 245.671086 -116.548154) (xy 245.676655 -116.541055) (xy 245.682913 -116.524148)
			(xy 245.683278 -116.515134) (xy 245.683278 -116.448078) (xy 245.682936 -116.439059) (xy 245.676679 -116.422142)
			(xy 245.671086 -116.415058) (xy 245.670832 -116.415058) (xy 245.670832 -116.414804) (xy 245.653186 -116.393877)
			(xy 245.623474 -116.347903) (xy 245.600639 -116.298155) (xy 245.58515 -116.245653) (xy 245.577324 -116.191476)
			(xy 245.576852 -116.164106) (xy 245.577383 -116.136857) (xy 245.585138 -116.082913) (xy 245.60049 -116.030621)
			(xy 245.623128 -115.981047) (xy 245.65259 -115.935198) (xy 245.688276 -115.894009) (xy 245.729461 -115.858317)
			(xy 245.775306 -115.82885) (xy 245.824878 -115.806206) (xy 245.877168 -115.790848) (xy 245.931111 -115.783087)
			(xy 245.95836 -115.782598) (xy 245.985729 -115.783088) (xy 246.039907 -115.7909) (xy 246.09241 -115.806384)
			(xy 246.142157 -115.82922) (xy 246.188125 -115.858939) (xy 246.209058 -115.876578) (xy 246.209312 -115.876832)
			(xy 246.216388 -115.882433) (xy 246.233313 -115.88867) (xy 246.242332 -115.889024) (xy 246.309388 -115.889024)
			(xy 246.318404 -115.888656) (xy 246.33532 -115.882415) (xy 246.342408 -115.876832) (xy 246.342408 -115.876578)
			(xy 246.342662 -115.876578) (xy 246.363595 -115.85894) (xy 246.409568 -115.829229) (xy 246.459315 -115.806393)
			(xy 246.511815 -115.790901) (xy 246.565991 -115.783073) (xy 246.59336 -115.782598) (xy 246.620612 -115.783093)
			(xy 246.674562 -115.790844) (xy 246.72686 -115.806195) (xy 246.77644 -115.828834) (xy 246.822294 -115.858298)
			(xy 246.863487 -115.893989) (xy 246.899181 -115.935179) (xy 246.92865 -115.98103) (xy 246.951293 -116.030608)
			(xy 246.966649 -116.082904) (xy 246.974405 -116.136854) (xy 246.974868 -116.164106) (xy 246.974413 -116.191477)
			(xy 246.966594 -116.245657) (xy 246.951103 -116.29816) (xy 246.928258 -116.347907) (xy 246.898531 -116.393873)
			(xy 246.880888 -116.414804) (xy 246.880634 -116.415058) (xy 246.875051 -116.422147) (xy 246.868804 -116.439062)
			(xy 246.868442 -116.448078) (xy 246.868442 -116.515134) (xy 246.868774 -116.524154) (xy 246.875038 -116.541071)
			(xy 246.880634 -116.548154) (xy 246.880888 -116.548154) (xy 246.880888 -116.548408) (xy 246.898534 -116.569336)
			(xy 246.928257 -116.615305) (xy 246.951101 -116.665052) (xy 246.966597 -116.717555) (xy 246.974424 -116.771734)
			(xy 246.974424 -116.826475) (xy 246.966595 -116.880654) (xy 246.951098 -116.933156) (xy 246.928253 -116.982903)
			(xy 246.898528 -117.028871) (xy 246.880888 -117.049804) (xy 246.880634 -117.050058) (xy 246.875051 -117.057147)
			(xy 246.868804 -117.074062) (xy 246.868442 -117.083078) (xy 246.868442 -117.150134) (xy 246.868774 -117.159154)
			(xy 246.875038 -117.176071) (xy 246.880634 -117.183154) (xy 246.880888 -117.183154) (xy 246.880888 -117.183408)
			(xy 246.898542 -117.204328) (xy 246.928252 -117.250304) (xy 246.951086 -117.300054) (xy 246.966573 -117.352558)
			(xy 246.974397 -117.406736) (xy 246.974868 -117.434106) (xy 246.97473 -117.442234) (xy 247.85904 -117.442234)
			(xy 247.863111 -117.386612) (xy 247.875237 -117.332175) (xy 247.89516 -117.280084) (xy 247.922456 -117.231449)
			(xy 247.956542 -117.187306) (xy 247.996691 -117.148597) (xy 248.042049 -117.116146) (xy 248.091649 -117.090645)
			(xy 248.144433 -117.072638) (xy 248.199276 -117.062508) (xy 248.25501 -117.060471) (xy 248.310447 -117.066571)
			(xy 248.364404 -117.080677) (xy 248.415733 -117.102489) (xy 248.463339 -117.131543) (xy 248.506207 -117.167218)
			(xy 248.543424 -117.208755) (xy 248.574197 -117.255268) (xy 248.597869 -117.305765) (xy 248.613937 -117.359172)
			(xy 248.622057 -117.414348) (xy 248.622566 -117.442234) (xy 248.622057 -117.47012) (xy 248.613937 -117.525296)
			(xy 248.597869 -117.578703) (xy 248.574197 -117.6292) (xy 248.543424 -117.675713) (xy 248.506207 -117.71725)
			(xy 248.463339 -117.752925) (xy 248.415733 -117.781979) (xy 248.364404 -117.803791) (xy 248.310447 -117.817897)
			(xy 248.25501 -117.823997) (xy 248.199276 -117.82196) (xy 248.144433 -117.81183) (xy 248.091649 -117.793823)
			(xy 248.042049 -117.768322) (xy 247.996691 -117.735871) (xy 247.956542 -117.697162) (xy 247.922456 -117.653019)
			(xy 247.89516 -117.604384) (xy 247.875237 -117.552293) (xy 247.863111 -117.497856) (xy 247.85904 -117.442234)
			(xy 246.97473 -117.442234) (xy 246.974416 -117.460663) (xy 246.967047 -117.513262) (xy 246.952452 -117.564331)
			(xy 246.942102 -117.588792) (xy 246.937753 -117.60016) (xy 246.939101 -117.624434) (xy 246.944642 -117.635274)
			(xy 246.986044 -117.706394) (xy 246.99276 -117.716478) (xy 247.013181 -117.729461) (xy 247.02516 -117.731286)
			(xy 247.053143 -117.73446) (xy 247.107807 -117.747998) (xy 247.159886 -117.769425) (xy 247.208249 -117.798277)
			(xy 247.251844 -117.833926) (xy 247.289724 -117.875598) (xy 247.321066 -117.922386) (xy 247.345188 -117.973274)
			(xy 247.361565 -118.027155) (xy 247.367007 -118.063772) (xy 249.006104 -118.063772) (xy 249.010175 -118.00815)
			(xy 249.022301 -117.953713) (xy 249.042224 -117.901622) (xy 249.06952 -117.852987) (xy 249.103606 -117.808844)
			(xy 249.143755 -117.770135) (xy 249.189113 -117.737684) (xy 249.238713 -117.712183) (xy 249.291497 -117.694176)
			(xy 249.34634 -117.684046) (xy 249.402074 -117.682009) (xy 249.457511 -117.688109) (xy 249.511468 -117.702215)
			(xy 249.562797 -117.724027) (xy 249.610403 -117.753081) (xy 249.653271 -117.788756) (xy 249.690488 -117.830293)
			(xy 249.721261 -117.876806) (xy 249.744933 -117.927303) (xy 249.761001 -117.98071) (xy 249.76702 -118.021608)
			(xy 249.885454 -118.021608) (xy 249.885912 -117.994237) (xy 249.893729 -117.940057) (xy 249.90922 -117.887554)
			(xy 249.932064 -117.837807) (xy 249.961791 -117.791841) (xy 249.979434 -117.77091) (xy 249.979688 -117.770656)
			(xy 249.985256 -117.763557) (xy 249.991514 -117.74665) (xy 249.99188 -117.737636) (xy 249.99188 -117.67058)
			(xy 249.991537 -117.661562) (xy 249.98528 -117.644645) (xy 249.979688 -117.63756) (xy 249.979434 -117.63756)
			(xy 249.979434 -117.637306) (xy 249.961801 -117.616367) (xy 249.932075 -117.570401) (xy 249.909229 -117.520655)
			(xy 249.893732 -117.468154) (xy 249.885902 -117.413976) (xy 249.885901 -117.359236) (xy 249.893729 -117.305058)
			(xy 249.909225 -117.252556) (xy 249.932069 -117.20281) (xy 249.961794 -117.156843) (xy 249.979434 -117.13591)
			(xy 249.979688 -117.135656) (xy 249.985256 -117.128557) (xy 249.991514 -117.11165) (xy 249.99188 -117.102636)
			(xy 249.99188 -117.03558) (xy 249.991537 -117.026562) (xy 249.98528 -117.009645) (xy 249.979688 -117.00256)
			(xy 249.979434 -117.00256) (xy 249.979434 -117.002306) (xy 249.96179 -116.981378) (xy 249.932077 -116.935405)
			(xy 249.909242 -116.885656) (xy 249.893752 -116.833154) (xy 249.885926 -116.778978) (xy 249.885454 -116.751608)
			(xy 249.885985 -116.724359) (xy 249.89374 -116.670415) (xy 249.909092 -116.618123) (xy 249.931729 -116.568548)
			(xy 249.961191 -116.5227) (xy 249.996878 -116.48151) (xy 250.038063 -116.445819) (xy 250.083908 -116.416351)
			(xy 250.13348 -116.393708) (xy 250.18577 -116.378349) (xy 250.239713 -116.370588) (xy 250.266962 -116.3701)
			(xy 250.294331 -116.370588) (xy 250.34851 -116.378401) (xy 250.401012 -116.393885) (xy 250.45076 -116.416721)
			(xy 250.496728 -116.446441) (xy 250.51766 -116.46408) (xy 250.517914 -116.464334) (xy 250.52499 -116.469936)
			(xy 250.541915 -116.476172) (xy 250.550934 -116.476526) (xy 250.61799 -116.476526) (xy 250.627006 -116.476158)
			(xy 250.643922 -116.469918) (xy 250.65101 -116.464334) (xy 250.65101 -116.46408) (xy 250.651264 -116.46408)
			(xy 250.672196 -116.446441) (xy 250.718169 -116.41673) (xy 250.767917 -116.393894) (xy 250.820417 -116.378403)
			(xy 250.874593 -116.370574) (xy 250.901962 -116.3701) (xy 250.929214 -116.370591) (xy 250.983165 -116.378343)
			(xy 251.035462 -116.393694) (xy 251.085043 -116.416333) (xy 251.130897 -116.445798) (xy 251.17209 -116.481489)
			(xy 251.207784 -116.522679) (xy 251.237253 -116.568531) (xy 251.259895 -116.618109) (xy 251.275251 -116.670406)
			(xy 251.283007 -116.724356) (xy 251.28347 -116.751608) (xy 251.283016 -116.778979) (xy 251.275196 -116.833159)
			(xy 251.259705 -116.885662) (xy 251.23686 -116.935409) (xy 251.207133 -116.981375) (xy 251.18949 -117.002306)
			(xy 251.189236 -117.00256) (xy 251.183652 -117.009648) (xy 251.177406 -117.026564) (xy 251.177044 -117.03558)
			(xy 251.177044 -117.102636) (xy 251.177374 -117.111656) (xy 251.183639 -117.128573) (xy 251.189236 -117.135656)
			(xy 251.18949 -117.135656) (xy 251.18949 -117.13591) (xy 251.207138 -117.156837) (xy 251.236861 -117.202806)
			(xy 251.259705 -117.252553) (xy 251.2752 -117.305056) (xy 251.283027 -117.359235) (xy 251.283026 -117.413977)
			(xy 251.275197 -117.468156) (xy 251.259701 -117.520658) (xy 251.236855 -117.570405) (xy 251.207131 -117.616373)
			(xy 251.18949 -117.637306) (xy 251.189236 -117.63756) (xy 251.183652 -117.644648) (xy 251.177406 -117.661564)
			(xy 251.177044 -117.67058) (xy 251.177044 -117.737636) (xy 251.177374 -117.746656) (xy 251.183639 -117.763573)
			(xy 251.189236 -117.770656) (xy 251.18949 -117.770656) (xy 251.18949 -117.77091) (xy 251.207146 -117.791829)
			(xy 251.236855 -117.837805) (xy 251.259688 -117.887556) (xy 251.275175 -117.94006) (xy 251.282999 -117.994238)
			(xy 251.28347 -118.021608) (xy 251.283052 -118.048863) (xy 251.275293 -118.102817) (xy 251.259934 -118.155118)
			(xy 251.237288 -118.204701) (xy 251.207815 -118.250556) (xy 251.172117 -118.291749) (xy 251.130919 -118.327443)
			(xy 251.085061 -118.35691) (xy 251.035475 -118.37955) (xy 250.983172 -118.394903) (xy 250.929217 -118.402655)
			(xy 250.901962 -118.403116) (xy 250.874592 -118.402634) (xy 250.820413 -118.394823) (xy 250.767909 -118.379339)
			(xy 250.718162 -118.3565) (xy 250.672195 -118.326777) (xy 250.651264 -118.309136) (xy 250.65101 -118.308882)
			(xy 250.643926 -118.303291) (xy 250.627007 -118.297048) (xy 250.61799 -118.29669) (xy 250.550934 -118.29669)
			(xy 250.541919 -118.297065) (xy 250.525002 -118.3033) (xy 250.517914 -118.308882) (xy 250.517914 -118.309136)
			(xy 250.51766 -118.309136) (xy 250.496721 -118.326766) (xy 250.450749 -118.356478) (xy 250.401004 -118.379315)
			(xy 250.348505 -118.394808) (xy 250.294331 -118.40264) (xy 250.266962 -118.403116) (xy 250.23971 -118.402658)
			(xy 250.185762 -118.394896) (xy 250.133467 -118.379537) (xy 250.08389 -118.356892) (xy 250.03804 -118.327422)
			(xy 249.996851 -118.291728) (xy 249.96116 -118.250535) (xy 249.931694 -118.204683) (xy 249.909053 -118.155105)
			(xy 249.893698 -118.102809) (xy 249.88594 -118.04886) (xy 249.885454 -118.021608) (xy 249.76702 -118.021608)
			(xy 249.769121 -118.035886) (xy 249.76963 -118.063772) (xy 249.769121 -118.091658) (xy 249.761001 -118.146834)
			(xy 249.744933 -118.200241) (xy 249.721261 -118.250738) (xy 249.690488 -118.297251) (xy 249.653271 -118.338788)
			(xy 249.610403 -118.374463) (xy 249.562797 -118.403517) (xy 249.511468 -118.425329) (xy 249.457511 -118.439435)
			(xy 249.402074 -118.445535) (xy 249.34634 -118.443498) (xy 249.291497 -118.433368) (xy 249.238713 -118.415361)
			(xy 249.189113 -118.38986) (xy 249.143755 -118.357409) (xy 249.103606 -118.3187) (xy 249.06952 -118.274557)
			(xy 249.042224 -118.225922) (xy 249.022301 -118.173831) (xy 249.010175 -118.119394) (xy 249.006104 -118.063772)
			(xy 247.367007 -118.063772) (xy 247.369843 -118.082858) (xy 247.370346 -118.111016) (xy 247.36986 -118.138267)
			(xy 247.362104 -118.192215) (xy 247.346749 -118.24451) (xy 247.324107 -118.294087) (xy 247.294641 -118.339937)
			(xy 247.25895 -118.381128) (xy 247.217759 -118.416819) (xy 247.171909 -118.446285) (xy 247.122332 -118.468927)
			(xy 247.070037 -118.484282) (xy 247.016089 -118.492038) (xy 246.961587 -118.492038) (xy 246.907639 -118.484282)
			(xy 246.855344 -118.468927) (xy 246.805767 -118.446285) (xy 246.759917 -118.416819) (xy 246.718726 -118.381128)
			(xy 246.683035 -118.339937) (xy 246.653569 -118.294087) (xy 246.630927 -118.24451) (xy 246.615572 -118.192215)
			(xy 246.607816 -118.138267) (xy 246.60733 -118.111016) (xy 246.60779 -118.08446) (xy 246.615156 -118.03186)
			(xy 246.629747 -117.980791) (xy 246.640096 -117.95633) (xy 246.644431 -117.944957) (xy 246.643093 -117.920688)
			(xy 246.637556 -117.909848) (xy 246.596154 -117.838728) (xy 246.58941 -117.828667) (xy 246.569009 -117.815676)
			(xy 246.557038 -117.813836) (xy 246.527564 -117.810453) (xy 246.470096 -117.795736) (xy 246.415599 -117.772298)
			(xy 246.365389 -117.740703) (xy 246.342662 -117.721634) (xy 246.342408 -117.72138) (xy 246.335325 -117.715788)
			(xy 246.318405 -117.709545) (xy 246.309388 -117.709188) (xy 246.242332 -117.709188) (xy 246.233317 -117.709563)
			(xy 246.2164 -117.715798) (xy 246.209312 -117.72138) (xy 246.209312 -117.721634) (xy 246.209058 -117.721634)
			(xy 246.188119 -117.739265) (xy 246.142148 -117.768977) (xy 246.092402 -117.791814) (xy 246.039903 -117.807307)
			(xy 245.985729 -117.815138) (xy 245.95836 -117.815614) (xy 245.931108 -117.815159) (xy 245.87716 -117.807398)
			(xy 245.824865 -117.792038) (xy 245.775288 -117.769392) (xy 245.729438 -117.739922) (xy 245.688248 -117.704228)
			(xy 245.652557 -117.663035) (xy 245.623091 -117.617183) (xy 245.60045 -117.567604) (xy 245.585095 -117.515307)
			(xy 245.577338 -117.461358) (xy 245.576852 -117.434106) (xy 237.337477 -117.434106) (xy 237.349765 -117.444332)
			(xy 237.386982 -117.485869) (xy 237.417755 -117.532382) (xy 237.441427 -117.582879) (xy 237.457495 -117.636286)
			(xy 237.465615 -117.691462) (xy 237.466124 -117.719348) (xy 237.465615 -117.747234) (xy 237.457495 -117.80241)
			(xy 237.441427 -117.855817) (xy 237.417755 -117.906314) (xy 237.386982 -117.952827) (xy 237.349765 -117.994364)
			(xy 237.306897 -118.030039) (xy 237.259291 -118.059093) (xy 237.207962 -118.080905) (xy 237.175368 -118.089426)
			(xy 242.395246 -118.089426) (xy 242.399317 -118.033804) (xy 242.411443 -117.979367) (xy 242.431366 -117.927276)
			(xy 242.458662 -117.878641) (xy 242.492748 -117.834498) (xy 242.532897 -117.795789) (xy 242.578255 -117.763338)
			(xy 242.627855 -117.737837) (xy 242.680639 -117.71983) (xy 242.735482 -117.7097) (xy 242.791216 -117.707663)
			(xy 242.846653 -117.713763) (xy 242.90061 -117.727869) (xy 242.951939 -117.749681) (xy 242.999545 -117.778735)
			(xy 243.042413 -117.81441) (xy 243.07963 -117.855947) (xy 243.110403 -117.90246) (xy 243.134075 -117.952957)
			(xy 243.136924 -117.962426) (xy 244.427246 -117.962426) (xy 244.431317 -117.906804) (xy 244.443443 -117.852367)
			(xy 244.463366 -117.800276) (xy 244.490662 -117.751641) (xy 244.524748 -117.707498) (xy 244.564897 -117.668789)
			(xy 244.610255 -117.636338) (xy 244.659855 -117.610837) (xy 244.712639 -117.59283) (xy 244.767482 -117.5827)
			(xy 244.823216 -117.580663) (xy 244.878653 -117.586763) (xy 244.93261 -117.600869) (xy 244.983939 -117.622681)
			(xy 245.031545 -117.651735) (xy 245.074413 -117.68741) (xy 245.11163 -117.728947) (xy 245.142403 -117.77546)
			(xy 245.166075 -117.825957) (xy 245.182143 -117.879364) (xy 245.190263 -117.93454) (xy 245.190772 -117.962426)
			(xy 245.190263 -117.990312) (xy 245.182143 -118.045488) (xy 245.166075 -118.098895) (xy 245.142403 -118.149392)
			(xy 245.11163 -118.195905) (xy 245.074413 -118.237442) (xy 245.031545 -118.273117) (xy 244.983939 -118.302171)
			(xy 244.93261 -118.323983) (xy 244.878653 -118.338089) (xy 244.823216 -118.344189) (xy 244.767482 -118.342152)
			(xy 244.712639 -118.332022) (xy 244.659855 -118.314015) (xy 244.610255 -118.288514) (xy 244.564897 -118.256063)
			(xy 244.524748 -118.217354) (xy 244.490662 -118.173211) (xy 244.463366 -118.124576) (xy 244.443443 -118.072485)
			(xy 244.431317 -118.018048) (xy 244.427246 -117.962426) (xy 243.136924 -117.962426) (xy 243.150143 -118.006364)
			(xy 243.158263 -118.06154) (xy 243.158772 -118.089426) (xy 243.158263 -118.117312) (xy 243.150143 -118.172488)
			(xy 243.134075 -118.225895) (xy 243.110403 -118.276392) (xy 243.07963 -118.322905) (xy 243.042413 -118.364442)
			(xy 242.999545 -118.400117) (xy 242.951939 -118.429171) (xy 242.90061 -118.450983) (xy 242.846653 -118.465089)
			(xy 242.791216 -118.471189) (xy 242.735482 -118.469152) (xy 242.680639 -118.459022) (xy 242.627855 -118.441015)
			(xy 242.578255 -118.415514) (xy 242.532897 -118.383063) (xy 242.492748 -118.344354) (xy 242.458662 -118.300211)
			(xy 242.431366 -118.251576) (xy 242.411443 -118.199485) (xy 242.399317 -118.145048) (xy 242.395246 -118.089426)
			(xy 237.175368 -118.089426) (xy 237.154005 -118.095011) (xy 237.098568 -118.101111) (xy 237.042834 -118.099074)
			(xy 236.987991 -118.088944) (xy 236.935207 -118.070937) (xy 236.885607 -118.045436) (xy 236.840249 -118.012985)
			(xy 236.8001 -117.974276) (xy 236.766014 -117.930133) (xy 236.738718 -117.881498) (xy 236.718795 -117.829407)
			(xy 236.706669 -117.77497) (xy 236.702598 -117.719348) (xy 197.593889 -117.719348) (xy 197.551294 -118.062502)
			(xy 197.55104 -118.066566) (xy 197.548246 -118.132098) (xy 197.547484 -118.149624) (xy 197.547918 -118.158841)
			(xy 197.554559 -118.17604) (xy 197.560438 -118.183152) (xy 197.581484 -118.207028) (xy 215.707974 -118.207028)
			(xy 215.712045 -118.151406) (xy 215.724171 -118.096969) (xy 215.744094 -118.044878) (xy 215.77139 -117.996243)
			(xy 215.805476 -117.9521) (xy 215.845625 -117.913391) (xy 215.890983 -117.88094) (xy 215.940583 -117.855439)
			(xy 215.993367 -117.837432) (xy 216.04821 -117.827302) (xy 216.103944 -117.825265) (xy 216.159381 -117.831365)
			(xy 216.213338 -117.845471) (xy 216.264667 -117.867283) (xy 216.312273 -117.896337) (xy 216.355141 -117.932012)
			(xy 216.392358 -117.973549) (xy 216.423131 -118.020062) (xy 216.446803 -118.070559) (xy 216.462871 -118.123966)
			(xy 216.470983 -118.179088) (xy 230.817926 -118.179088) (xy 230.821997 -118.123466) (xy 230.834123 -118.069029)
			(xy 230.854046 -118.016938) (xy 230.881342 -117.968303) (xy 230.915428 -117.92416) (xy 230.955577 -117.885451)
			(xy 231.000935 -117.853) (xy 231.050535 -117.827499) (xy 231.103319 -117.809492) (xy 231.158162 -117.799362)
			(xy 231.213896 -117.797325) (xy 231.269333 -117.803425) (xy 231.32329 -117.817531) (xy 231.374619 -117.839343)
			(xy 231.422225 -117.868397) (xy 231.465093 -117.904072) (xy 231.50231 -117.945609) (xy 231.533083 -117.992122)
			(xy 231.556755 -118.042619) (xy 231.572823 -118.096026) (xy 231.580943 -118.151202) (xy 231.581452 -118.179088)
			(xy 231.580943 -118.206974) (xy 231.572823 -118.26215) (xy 231.556755 -118.315557) (xy 231.533083 -118.366054)
			(xy 231.50231 -118.412567) (xy 231.465093 -118.454104) (xy 231.422225 -118.489779) (xy 231.374619 -118.518833)
			(xy 231.32329 -118.540645) (xy 231.269333 -118.554751) (xy 231.213896 -118.560851) (xy 231.158162 -118.558814)
			(xy 231.103319 -118.548684) (xy 231.050535 -118.530677) (xy 231.000935 -118.505176) (xy 230.955577 -118.472725)
			(xy 230.915428 -118.434016) (xy 230.881342 -118.389873) (xy 230.854046 -118.341238) (xy 230.834123 -118.289147)
			(xy 230.821997 -118.23471) (xy 230.817926 -118.179088) (xy 216.470983 -118.179088) (xy 216.470991 -118.179142)
			(xy 216.4715 -118.207028) (xy 216.470991 -118.234914) (xy 216.462871 -118.29009) (xy 216.446803 -118.343497)
			(xy 216.423131 -118.393994) (xy 216.392358 -118.440507) (xy 216.355141 -118.482044) (xy 216.312273 -118.517719)
			(xy 216.264667 -118.546773) (xy 216.213338 -118.568585) (xy 216.159381 -118.582691) (xy 216.103944 -118.588791)
			(xy 216.04821 -118.586754) (xy 215.993367 -118.576624) (xy 215.940583 -118.558617) (xy 215.890983 -118.533116)
			(xy 215.845625 -118.500665) (xy 215.805476 -118.461956) (xy 215.77139 -118.417813) (xy 215.744094 -118.369178)
			(xy 215.724171 -118.317087) (xy 215.712045 -118.26265) (xy 215.707974 -118.207028) (xy 197.581484 -118.207028)
			(xy 197.590664 -118.217442) (xy 197.593712 -118.220998) (xy 197.597303 -118.224846) (xy 197.605756 -118.231115)
			(xy 197.610476 -118.233444) (xy 197.620636 -118.238016) (xy 197.631558 -118.238016) (xy 197.661558 -118.238438)
			(xy 197.721055 -118.246182) (xy 197.77903 -118.261633) (xy 197.834489 -118.284527) (xy 197.886482 -118.314471)
			(xy 197.934116 -118.350952) (xy 197.976574 -118.393344) (xy 198.01313 -118.440921) (xy 198.043156 -118.492866)
			(xy 198.066137 -118.548289) (xy 198.081678 -118.60624) (xy 198.083529 -118.620286) (xy 213.718646 -118.620286)
			(xy 213.722717 -118.564664) (xy 213.734843 -118.510227) (xy 213.754766 -118.458136) (xy 213.782062 -118.409501)
			(xy 213.816148 -118.365358) (xy 213.856297 -118.326649) (xy 213.901655 -118.294198) (xy 213.951255 -118.268697)
			(xy 214.004039 -118.25069) (xy 214.058882 -118.24056) (xy 214.114616 -118.238523) (xy 214.170053 -118.244623)
			(xy 214.22401 -118.258729) (xy 214.275339 -118.280541) (xy 214.322945 -118.309595) (xy 214.365813 -118.34527)
			(xy 214.40303 -118.386807) (xy 214.433803 -118.43332) (xy 214.457475 -118.483817) (xy 214.473543 -118.537224)
			(xy 214.481663 -118.5924) (xy 214.482172 -118.620286) (xy 214.481663 -118.648172) (xy 214.473543 -118.703348)
			(xy 214.457475 -118.756755) (xy 214.433803 -118.807252) (xy 214.40303 -118.853765) (xy 214.365813 -118.895302)
			(xy 214.322945 -118.930977) (xy 214.275339 -118.960031) (xy 214.22401 -118.981843) (xy 214.170053 -118.995949)
			(xy 214.114616 -119.002049) (xy 214.058882 -119.000012) (xy 214.004039 -118.989882) (xy 213.951255 -118.971875)
			(xy 213.901655 -118.946374) (xy 213.856297 -118.913923) (xy 213.816148 -118.875214) (xy 213.782062 -118.831071)
			(xy 213.754766 -118.782436) (xy 213.734843 -118.730345) (xy 213.722717 -118.675908) (xy 213.718646 -118.620286)
			(xy 198.083529 -118.620286) (xy 198.089515 -118.665725) (xy 198.090028 -118.695724) (xy 198.090028 -119.559324)
			(xy 198.089536 -119.589291) (xy 198.081711 -119.648712) (xy 198.066197 -119.706604) (xy 198.043259 -119.761975)
			(xy 198.013291 -119.813879) (xy 197.976805 -119.861428) (xy 197.934425 -119.903807) (xy 197.886876 -119.940293)
			(xy 197.834972 -119.970261) (xy 197.7796 -119.993198) (xy 197.721708 -120.008712) (xy 197.662287 -120.016537)
			(xy 197.63232 -120.017032) (xy 197.618828 -120.016961) (xy 197.591886 -120.015435) (xy 197.578472 -120.013984)
			(xy 197.55993 -120.011444) (xy 197.528434 -120.005348) (xy 197.523862 -120.004332) (xy 197.51929 -120.004078)
			(xy 197.5101 -120.004055) (xy 197.492646 -120.009762) (xy 197.478335 -120.02127) (xy 197.473316 -120.02897)
			(xy 197.470305 -120.034434) (xy 197.466704 -120.046374) (xy 197.466204 -120.052592) (xy 197.410245 -121.365772)
			(xy 199.81672 -121.365772) (xy 199.81672 -120.502172) (xy 199.81721 -120.472204) (xy 199.825033 -120.412782)
			(xy 199.840546 -120.354889) (xy 199.863482 -120.299516) (xy 199.893449 -120.24761) (xy 199.929936 -120.20006)
			(xy 199.972316 -120.15768) (xy 200.019866 -120.121193) (xy 200.071772 -120.091226) (xy 200.127145 -120.06829)
			(xy 200.185038 -120.052777) (xy 200.24446 -120.044954) (xy 200.304396 -120.044954) (xy 200.363818 -120.052777)
			(xy 200.421711 -120.06829) (xy 200.477084 -120.091226) (xy 200.52899 -120.121193) (xy 200.57654 -120.15768)
			(xy 200.61892 -120.20006) (xy 200.655407 -120.24761) (xy 200.685374 -120.299516) (xy 200.70831 -120.354889)
			(xy 200.723823 -120.412782) (xy 200.731646 -120.472204) (xy 200.732136 -120.502172) (xy 200.732136 -120.922034)
			(xy 205.550516 -120.922034) (xy 205.550998 -120.894664) (xy 205.558811 -120.840486) (xy 205.574297 -120.787983)
			(xy 205.597135 -120.738236) (xy 205.626856 -120.692268) (xy 205.644496 -120.671336) (xy 205.64475 -120.671082)
			(xy 205.650356 -120.664009) (xy 205.65659 -120.647082) (xy 205.656942 -120.638062) (xy 205.656942 -120.571006)
			(xy 205.656595 -120.561988) (xy 205.650342 -120.54507) (xy 205.64475 -120.537986) (xy 205.644496 -120.537986)
			(xy 205.644496 -120.537732) (xy 205.62689 -120.516772) (xy 205.597166 -120.470808) (xy 205.574321 -120.421066)
			(xy 205.558823 -120.368568) (xy 205.550992 -120.314394) (xy 205.550988 -120.259657) (xy 205.558812 -120.205482)
			(xy 205.574303 -120.152982) (xy 205.597141 -120.103237) (xy 205.626859 -120.057269) (xy 205.644496 -120.036336)
			(xy 205.64475 -120.036082) (xy 205.650356 -120.029009) (xy 205.65659 -120.012082) (xy 205.656942 -120.003062)
			(xy 205.656942 -119.936006) (xy 205.656595 -119.926988) (xy 205.650342 -119.91007) (xy 205.64475 -119.902986)
			(xy 205.644496 -119.902986) (xy 205.644496 -119.902732) (xy 205.62689 -119.881772) (xy 205.597166 -119.835808)
			(xy 205.574321 -119.786066) (xy 205.558823 -119.733568) (xy 205.550992 -119.679394) (xy 205.550988 -119.624657)
			(xy 205.558812 -119.570482) (xy 205.574303 -119.517982) (xy 205.597141 -119.468237) (xy 205.626859 -119.422269)
			(xy 205.644496 -119.401336) (xy 205.64475 -119.401082) (xy 205.650356 -119.394009) (xy 205.65659 -119.377082)
			(xy 205.656942 -119.368062) (xy 205.656942 -119.301006) (xy 205.656595 -119.291988) (xy 205.650342 -119.27507)
			(xy 205.64475 -119.267986) (xy 205.644496 -119.267986) (xy 205.644496 -119.267732) (xy 205.626858 -119.246799)
			(xy 205.597146 -119.200827) (xy 205.57431 -119.151079) (xy 205.558819 -119.098579) (xy 205.55099 -119.044403)
			(xy 205.550516 -119.017034) (xy 205.551002 -118.989783) (xy 205.558758 -118.935835) (xy 205.574113 -118.88354)
			(xy 205.596755 -118.833963) (xy 205.626221 -118.788113) (xy 205.661912 -118.746922) (xy 205.703103 -118.711231)
			(xy 205.748953 -118.681765) (xy 205.79853 -118.659123) (xy 205.850825 -118.643768) (xy 205.904773 -118.636012)
			(xy 205.959275 -118.636012) (xy 206.013223 -118.643768) (xy 206.065518 -118.659123) (xy 206.115095 -118.681765)
			(xy 206.160945 -118.711231) (xy 206.202136 -118.746922) (xy 206.237827 -118.788113) (xy 206.267293 -118.833963)
			(xy 206.289935 -118.88354) (xy 206.30529 -118.935835) (xy 206.313046 -118.989783) (xy 206.313532 -119.017034)
			(xy 206.313102 -119.044406) (xy 206.308435 -119.076724) (xy 206.521812 -119.076724) (xy 206.522278 -119.049471)
			(xy 206.530032 -118.995519) (xy 206.545386 -118.94322) (xy 206.568027 -118.893639) (xy 206.597494 -118.847784)
			(xy 206.633188 -118.806591) (xy 206.674381 -118.770897) (xy 206.720235 -118.741429) (xy 206.769816 -118.718787)
			(xy 206.822115 -118.703433) (xy 206.876067 -118.695678) (xy 206.90332 -118.695216) (xy 206.929635 -118.695665)
			(xy 206.981764 -118.702903) (xy 207.032407 -118.717225) (xy 207.080606 -118.738361) (xy 207.125449 -118.765911)
			(xy 207.166088 -118.799353) (xy 207.184244 -118.818406) (xy 207.191747 -118.82583) (xy 207.211041 -118.834341)
			(xy 207.221582 -118.834916) (xy 207.296258 -118.834916) (xy 207.306806 -118.834373) (xy 207.326101 -118.825847)
			(xy 207.333596 -118.818406) (xy 207.351762 -118.799361) (xy 207.392389 -118.765902) (xy 207.437227 -118.738342)
			(xy 207.485426 -118.717201) (xy 207.536072 -118.702882) (xy 207.588204 -118.695656) (xy 207.61452 -118.695216)
			(xy 207.641774 -118.695636) (xy 207.695728 -118.703397) (xy 207.748028 -118.718756) (xy 207.79761 -118.741403)
			(xy 207.843464 -118.770875) (xy 207.884658 -118.806574) (xy 207.920351 -118.847771) (xy 207.949818 -118.893628)
			(xy 207.972459 -118.943213) (xy 207.987813 -118.995515) (xy 207.995567 -119.049469) (xy 207.996028 -119.076724)
			(xy 207.995484 -119.105052) (xy 207.987121 -119.161088) (xy 207.970565 -119.215272) (xy 207.966867 -119.223028)
			(xy 215.70391 -119.223028) (xy 215.707981 -119.167406) (xy 215.720107 -119.112969) (xy 215.74003 -119.060878)
			(xy 215.767326 -119.012243) (xy 215.801412 -118.9681) (xy 215.841561 -118.929391) (xy 215.886919 -118.89694)
			(xy 215.936519 -118.871439) (xy 215.989303 -118.853432) (xy 216.044146 -118.843302) (xy 216.09988 -118.841265)
			(xy 216.155317 -118.847365) (xy 216.209274 -118.861471) (xy 216.260603 -118.883283) (xy 216.308209 -118.912337)
			(xy 216.351077 -118.948012) (xy 216.388294 -118.989549) (xy 216.419067 -119.036062) (xy 216.442739 -119.086559)
			(xy 216.458807 -119.139966) (xy 216.461985 -119.16156) (xy 232.432604 -119.16156) (xy 232.436675 -119.105938)
			(xy 232.448801 -119.051501) (xy 232.468724 -118.99941) (xy 232.49602 -118.950775) (xy 232.530106 -118.906632)
			(xy 232.570255 -118.867923) (xy 232.615613 -118.835472) (xy 232.665213 -118.809971) (xy 232.717997 -118.791964)
			(xy 232.77284 -118.781834) (xy 232.828574 -118.779797) (xy 232.884011 -118.785897) (xy 232.937968 -118.800003)
			(xy 232.989297 -118.821815) (xy 233.036903 -118.850869) (xy 233.079771 -118.886544) (xy 233.116988 -118.928081)
			(xy 233.147761 -118.974594) (xy 233.171433 -119.025091) (xy 233.187501 -119.078498) (xy 233.195621 -119.133674)
			(xy 233.19613 -119.16156) (xy 233.195621 -119.189446) (xy 233.192697 -119.209312) (xy 233.799124 -119.209312)
			(xy 233.803195 -119.15369) (xy 233.815321 -119.099253) (xy 233.835244 -119.047162) (xy 233.86254 -118.998527)
			(xy 233.896626 -118.954384) (xy 233.936775 -118.915675) (xy 233.982133 -118.883224) (xy 234.031733 -118.857723)
			(xy 234.084517 -118.839716) (xy 234.13936 -118.829586) (xy 234.195094 -118.827549) (xy 234.250531 -118.833649)
			(xy 234.304488 -118.847755) (xy 234.355817 -118.869567) (xy 234.403423 -118.898621) (xy 234.446291 -118.934296)
			(xy 234.483508 -118.975833) (xy 234.514281 -119.022346) (xy 234.537953 -119.072843) (xy 234.554021 -119.12625)
			(xy 234.55619 -119.140986) (xy 235.177836 -119.140986) (xy 235.181907 -119.085364) (xy 235.194033 -119.030927)
			(xy 235.213956 -118.978836) (xy 235.241252 -118.930201) (xy 235.275338 -118.886058) (xy 235.315487 -118.847349)
			(xy 235.360845 -118.814898) (xy 235.410445 -118.789397) (xy 235.463229 -118.77139) (xy 235.518072 -118.76126)
			(xy 235.573806 -118.759223) (xy 235.629243 -118.765323) (xy 235.6832 -118.779429) (xy 235.734529 -118.801241)
			(xy 235.782135 -118.830295) (xy 235.825003 -118.86597) (xy 235.86222 -118.907507) (xy 235.892993 -118.95402)
			(xy 235.916665 -119.004517) (xy 235.932733 -119.057924) (xy 235.940583 -119.111268) (xy 236.70463 -119.111268)
			(xy 236.708701 -119.055646) (xy 236.720827 -119.001209) (xy 236.74075 -118.949118) (xy 236.768046 -118.900483)
			(xy 236.802132 -118.85634) (xy 236.842281 -118.817631) (xy 236.887639 -118.78518) (xy 236.937239 -118.759679)
			(xy 236.990023 -118.741672) (xy 237.044866 -118.731542) (xy 237.1006 -118.729505) (xy 237.156037 -118.735605)
			(xy 237.209994 -118.749711) (xy 237.261323 -118.771523) (xy 237.308929 -118.800577) (xy 237.351797 -118.836252)
			(xy 237.389014 -118.877789) (xy 237.419787 -118.924302) (xy 237.443459 -118.974799) (xy 237.459527 -119.028206)
			(xy 237.467647 -119.083382) (xy 237.468156 -119.111268) (xy 237.467647 -119.139154) (xy 237.459527 -119.19433)
			(xy 237.443459 -119.247737) (xy 237.419787 -119.298234) (xy 237.389014 -119.344747) (xy 237.351797 -119.386284)
			(xy 237.308929 -119.421959) (xy 237.261323 -119.451013) (xy 237.209994 -119.472825) (xy 237.156037 -119.486931)
			(xy 237.1006 -119.493031) (xy 237.044866 -119.490994) (xy 236.990023 -119.480864) (xy 236.937239 -119.462857)
			(xy 236.887639 -119.437356) (xy 236.842281 -119.404905) (xy 236.802132 -119.366196) (xy 236.768046 -119.322053)
			(xy 236.74075 -119.273418) (xy 236.720827 -119.221327) (xy 236.708701 -119.16689) (xy 236.70463 -119.111268)
			(xy 235.940583 -119.111268) (xy 235.940853 -119.1131) (xy 235.941362 -119.140986) (xy 235.940853 -119.168872)
			(xy 235.932733 -119.224048) (xy 235.916665 -119.277455) (xy 235.892993 -119.327952) (xy 235.86222 -119.374465)
			(xy 235.825003 -119.416002) (xy 235.782135 -119.451677) (xy 235.734529 -119.480731) (xy 235.6832 -119.502543)
			(xy 235.629243 -119.516649) (xy 235.573806 -119.522749) (xy 235.518072 -119.520712) (xy 235.463229 -119.510582)
			(xy 235.410445 -119.492575) (xy 235.360845 -119.467074) (xy 235.315487 -119.434623) (xy 235.275338 -119.395914)
			(xy 235.241252 -119.351771) (xy 235.213956 -119.303136) (xy 235.194033 -119.251045) (xy 235.181907 -119.196608)
			(xy 235.177836 -119.140986) (xy 234.55619 -119.140986) (xy 234.562141 -119.181426) (xy 234.56265 -119.209312)
			(xy 234.562141 -119.237198) (xy 234.554021 -119.292374) (xy 234.537953 -119.345781) (xy 234.514281 -119.396278)
			(xy 234.483508 -119.442791) (xy 234.446291 -119.484328) (xy 234.403423 -119.520003) (xy 234.355817 -119.549057)
			(xy 234.304488 -119.570869) (xy 234.250531 -119.584975) (xy 234.195094 -119.591075) (xy 234.13936 -119.589038)
			(xy 234.084517 -119.578908) (xy 234.031733 -119.560901) (xy 233.982133 -119.5354) (xy 233.936775 -119.502949)
			(xy 233.896626 -119.46424) (xy 233.86254 -119.420097) (xy 233.835244 -119.371462) (xy 233.815321 -119.319371)
			(xy 233.803195 -119.264934) (xy 233.799124 -119.209312) (xy 233.192697 -119.209312) (xy 233.187501 -119.244622)
			(xy 233.171433 -119.298029) (xy 233.147761 -119.348526) (xy 233.116988 -119.395039) (xy 233.079771 -119.436576)
			(xy 233.036903 -119.472251) (xy 232.989297 -119.501305) (xy 232.937968 -119.523117) (xy 232.884011 -119.537223)
			(xy 232.828574 -119.543323) (xy 232.77284 -119.541286) (xy 232.717997 -119.531156) (xy 232.665213 -119.513149)
			(xy 232.615613 -119.487648) (xy 232.570255 -119.455197) (xy 232.530106 -119.416488) (xy 232.49602 -119.372345)
			(xy 232.468724 -119.32371) (xy 232.448801 -119.271619) (xy 232.436675 -119.217182) (xy 232.432604 -119.16156)
			(xy 216.461985 -119.16156) (xy 216.466927 -119.195142) (xy 216.467436 -119.223028) (xy 216.466927 -119.250914)
			(xy 216.458807 -119.30609) (xy 216.442739 -119.359497) (xy 216.419067 -119.409994) (xy 216.388294 -119.456507)
			(xy 216.351077 -119.498044) (xy 216.308209 -119.533719) (xy 216.260603 -119.562773) (xy 216.209274 -119.584585)
			(xy 216.155317 -119.598691) (xy 216.09988 -119.604791) (xy 216.044146 -119.602754) (xy 215.989303 -119.592624)
			(xy 215.936519 -119.574617) (xy 215.886919 -119.549116) (xy 215.841561 -119.516665) (xy 215.801412 -119.477956)
			(xy 215.767326 -119.433813) (xy 215.74003 -119.385178) (xy 215.720107 -119.333087) (xy 215.707981 -119.27865)
			(xy 215.70391 -119.223028) (xy 207.966867 -119.223028) (xy 207.946183 -119.266414) (xy 207.914508 -119.31339)
			(xy 207.876238 -119.355167) (xy 207.832213 -119.390828) (xy 207.808068 -119.405654) (xy 207.800771 -119.410375)
			(xy 207.789587 -119.423659) (xy 207.783456 -119.439907) (xy 207.782922 -119.44858) (xy 207.781652 -119.535194)
			(xy 207.781921 -119.543867) (xy 207.787448 -119.560299) (xy 207.798142 -119.573943) (xy 207.805274 -119.578882)
			(xy 207.828199 -119.593999) (xy 207.869907 -119.629718) (xy 207.906067 -119.671043) (xy 207.935935 -119.717122)
			(xy 207.958893 -119.767004) (xy 207.974469 -119.819661) (xy 207.982341 -119.874006) (xy 207.98282 -119.901462)
			(xy 207.982309 -119.928713) (xy 207.974558 -119.982662) (xy 207.959207 -120.034958) (xy 207.93657 -120.084537)
			(xy 207.907107 -120.13039) (xy 207.871418 -120.171583) (xy 207.83023 -120.207277) (xy 207.784381 -120.236746)
			(xy 207.734805 -120.25939) (xy 207.682511 -120.274747) (xy 207.628563 -120.282506) (xy 207.601312 -120.28297)
			(xy 207.573942 -120.282504) (xy 207.519762 -120.274687) (xy 207.467259 -120.259199) (xy 207.417512 -120.236357)
			(xy 207.371545 -120.206632) (xy 207.350614 -120.18899) (xy 207.35036 -120.188736) (xy 207.343266 -120.183161)
			(xy 207.326355 -120.176909) (xy 207.31734 -120.176544) (xy 207.250284 -120.176544) (xy 207.241265 -120.176884)
			(xy 207.224348 -120.183142) (xy 207.217264 -120.188736) (xy 207.217264 -120.18899) (xy 207.21701 -120.18899)
			(xy 207.196084 -120.206636) (xy 207.150109 -120.236347) (xy 207.100361 -120.259182) (xy 207.047858 -120.274671)
			(xy 206.993682 -120.282497) (xy 206.966312 -120.28297) (xy 206.939058 -120.282533) (xy 206.885104 -120.274777)
			(xy 206.832803 -120.259421) (xy 206.783221 -120.236777) (xy 206.737366 -120.207306) (xy 206.696172 -120.17161)
			(xy 206.660478 -120.130414) (xy 206.631011 -120.084557) (xy 206.60837 -120.034972) (xy 206.593017 -119.982671)
			(xy 206.585265 -119.928716) (xy 206.584804 -119.901462) (xy 206.585272 -119.875526) (xy 206.592293 -119.824132)
			(xy 206.606213 -119.774163) (xy 206.626776 -119.726542) (xy 206.653603 -119.682146) (xy 206.686198 -119.641795)
			(xy 206.723961 -119.606233) (xy 206.744824 -119.59082) (xy 206.755746 -119.5832) (xy 206.766922 -119.55907)
			(xy 206.759556 -119.458994) (xy 206.758535 -119.450283) (xy 206.751384 -119.43428) (xy 206.739282 -119.421601)
			(xy 206.731616 -119.417338) (xy 206.708293 -119.405108) (xy 206.664963 -119.375173) (xy 206.626166 -119.339561)
			(xy 206.592639 -119.298948) (xy 206.56502 -119.254107) (xy 206.543835 -119.205892) (xy 206.529488 -119.15522)
			(xy 206.52225 -119.103056) (xy 206.521812 -119.076724) (xy 206.308435 -119.076724) (xy 206.305278 -119.098587)
			(xy 206.289782 -119.151091) (xy 206.266931 -119.200838) (xy 206.237198 -119.246802) (xy 206.219552 -119.267732)
			(xy 206.219298 -119.267986) (xy 206.213711 -119.275072) (xy 206.207465 -119.291989) (xy 206.207106 -119.301006)
			(xy 206.207106 -119.368062) (xy 206.20748 -119.377077) (xy 206.213716 -119.393994) (xy 206.219298 -119.401082)
			(xy 206.219552 -119.401082) (xy 206.219552 -119.401336) (xy 206.237227 -119.422241) (xy 206.266952 -119.468213)
			(xy 206.289797 -119.517964) (xy 206.305291 -119.57047) (xy 206.313117 -119.624653) (xy 206.313113 -119.679398)
			(xy 206.30528 -119.73358) (xy 206.289779 -119.786084) (xy 206.266927 -119.835832) (xy 206.237196 -119.8818)
			(xy 206.219552 -119.902732) (xy 206.219298 -119.902986) (xy 206.213711 -119.910072) (xy 206.207465 -119.926989)
			(xy 206.207106 -119.936006) (xy 206.207106 -120.003062) (xy 206.20748 -120.012077) (xy 206.213716 -120.028994)
			(xy 206.219298 -120.036082) (xy 206.219552 -120.036082) (xy 206.219552 -120.036336) (xy 206.237227 -120.057241)
			(xy 206.266952 -120.103213) (xy 206.289797 -120.152964) (xy 206.305291 -120.20547) (xy 206.313117 -120.259653)
			(xy 206.313113 -120.314398) (xy 206.310753 -120.330722) (xy 208.104232 -120.330722) (xy 208.104703 -120.303352)
			(xy 208.112519 -120.249173) (xy 208.128006 -120.196669) (xy 208.150847 -120.146922) (xy 208.180571 -120.100956)
			(xy 208.198212 -120.080024) (xy 208.198466 -120.07977) (xy 208.204037 -120.072673) (xy 208.210291 -120.055764)
			(xy 208.210658 -120.04675) (xy 208.210658 -119.979694) (xy 208.210313 -119.970676) (xy 208.204058 -119.953759)
			(xy 208.198466 -119.946674) (xy 208.198212 -119.946674) (xy 208.198212 -119.94642) (xy 208.180571 -119.92549)
			(xy 208.150859 -119.879517) (xy 208.128023 -119.829769) (xy 208.112533 -119.777268) (xy 208.104705 -119.723091)
			(xy 208.104232 -119.695722) (xy 208.104676 -119.668468) (xy 208.112431 -119.614514) (xy 208.127786 -119.562214)
			(xy 208.150429 -119.512631) (xy 208.179898 -119.466776) (xy 208.215594 -119.425582) (xy 208.25679 -119.389888)
			(xy 208.302647 -119.36042) (xy 208.35223 -119.33778) (xy 208.404532 -119.322427) (xy 208.458486 -119.314675)
			(xy 208.48574 -119.314214) (xy 208.514863 -119.314748) (xy 208.572435 -119.32358) (xy 208.627995 -119.341064)
			(xy 208.680251 -119.366792) (xy 208.727987 -119.400166) (xy 208.770093 -119.440411) (xy 208.80559 -119.48659)
			(xy 208.833653 -119.53763) (xy 208.853629 -119.592343) (xy 208.859882 -119.620792) (xy 208.862168 -119.632476)
			(xy 208.876646 -119.651272) (xy 208.96072 -119.691658) (xy 208.971533 -119.696221) (xy 208.994973 -119.69596)
			(xy 209.005678 -119.69115) (xy 209.006186 -119.69115) (xy 209.033242 -119.677863) (xy 209.090519 -119.659086)
			(xy 209.150038 -119.649569) (xy 209.180176 -119.648986) (xy 209.207428 -119.649478) (xy 209.261378 -119.657231)
			(xy 209.313675 -119.672584) (xy 209.363254 -119.695223) (xy 209.409107 -119.724688) (xy 209.4503 -119.760379)
			(xy 209.485994 -119.801569) (xy 209.515462 -119.847419) (xy 209.538106 -119.896997) (xy 209.553462 -119.949293)
			(xy 209.56122 -120.003242) (xy 209.561684 -120.030494) (xy 209.561218 -120.057864) (xy 209.553401 -120.112044)
			(xy 209.538869 -120.161304) (xy 213.683848 -120.161304) (xy 213.687919 -120.105682) (xy 213.700045 -120.051245)
			(xy 213.719968 -119.999154) (xy 213.747264 -119.950519) (xy 213.78135 -119.906376) (xy 213.821499 -119.867667)
			(xy 213.866857 -119.835216) (xy 213.916457 -119.809715) (xy 213.969241 -119.791708) (xy 214.024084 -119.781578)
			(xy 214.079818 -119.779541) (xy 214.135255 -119.785641) (xy 214.189212 -119.799747) (xy 214.240541 -119.821559)
			(xy 214.288147 -119.850613) (xy 214.331015 -119.886288) (xy 214.368232 -119.927825) (xy 214.399005 -119.974338)
			(xy 214.422677 -120.024835) (xy 214.438745 -120.078242) (xy 214.446865 -120.133418) (xy 214.447374 -120.161304)
			(xy 214.446865 -120.18919) (xy 214.438745 -120.244366) (xy 214.437524 -120.248426) (xy 242.395246 -120.248426)
			(xy 242.399317 -120.192804) (xy 242.411443 -120.138367) (xy 242.431366 -120.086276) (xy 242.458662 -120.037641)
			(xy 242.492748 -119.993498) (xy 242.532897 -119.954789) (xy 242.578255 -119.922338) (xy 242.627855 -119.896837)
			(xy 242.680639 -119.87883) (xy 242.735482 -119.8687) (xy 242.791216 -119.866663) (xy 242.846653 -119.872763)
			(xy 242.90061 -119.886869) (xy 242.951939 -119.908681) (xy 242.999545 -119.937735) (xy 243.042413 -119.97341)
			(xy 243.07963 -120.014947) (xy 243.110403 -120.06146) (xy 243.134075 -120.111957) (xy 243.135854 -120.11787)
			(xy 243.411246 -120.11787) (xy 243.415317 -120.062248) (xy 243.427443 -120.007811) (xy 243.447366 -119.95572)
			(xy 243.474662 -119.907085) (xy 243.508748 -119.862942) (xy 243.548897 -119.824233) (xy 243.594255 -119.791782)
			(xy 243.643855 -119.766281) (xy 243.696639 -119.748274) (xy 243.751482 -119.738144) (xy 243.807216 -119.736107)
			(xy 243.862653 -119.742207) (xy 243.91661 -119.756313) (xy 243.967939 -119.778125) (xy 244.015545 -119.807179)
			(xy 244.058413 -119.842854) (xy 244.09563 -119.884391) (xy 244.126403 -119.930904) (xy 244.150075 -119.981401)
			(xy 244.166143 -120.034808) (xy 244.174263 -120.089984) (xy 244.174772 -120.11787) (xy 244.427246 -120.11787)
			(xy 244.431317 -120.062248) (xy 244.443443 -120.007811) (xy 244.463366 -119.95572) (xy 244.490662 -119.907085)
			(xy 244.524748 -119.862942) (xy 244.564897 -119.824233) (xy 244.610255 -119.791782) (xy 244.659855 -119.766281)
			(xy 244.712639 -119.748274) (xy 244.767482 -119.738144) (xy 244.823216 -119.736107) (xy 244.878653 -119.742207)
			(xy 244.93261 -119.756313) (xy 244.983939 -119.778125) (xy 245.031545 -119.807179) (xy 245.074413 -119.842854)
			(xy 245.11163 -119.884391) (xy 245.142403 -119.930904) (xy 245.166075 -119.981401) (xy 245.182143 -120.034808)
			(xy 245.190263 -120.089984) (xy 245.190772 -120.11787) (xy 245.190263 -120.145756) (xy 245.189134 -120.15343)
			(xy 247.62282 -120.15343) (xy 247.626891 -120.097808) (xy 247.639017 -120.043371) (xy 247.65894 -119.99128)
			(xy 247.686236 -119.942645) (xy 247.720322 -119.898502) (xy 247.760471 -119.859793) (xy 247.805829 -119.827342)
			(xy 247.855429 -119.801841) (xy 247.908213 -119.783834) (xy 247.963056 -119.773704) (xy 248.01879 -119.771667)
			(xy 248.074227 -119.777767) (xy 248.128184 -119.791873) (xy 248.179513 -119.813685) (xy 248.227119 -119.842739)
			(xy 248.269987 -119.878414) (xy 248.307204 -119.919951) (xy 248.337977 -119.966464) (xy 248.361649 -120.016961)
			(xy 248.377717 -120.070368) (xy 248.385837 -120.125544) (xy 248.386346 -120.15343) (xy 248.385837 -120.181316)
			(xy 248.377717 -120.236492) (xy 248.361649 -120.289899) (xy 248.337977 -120.340396) (xy 248.307204 -120.386909)
			(xy 248.269987 -120.428446) (xy 248.227119 -120.464121) (xy 248.179513 -120.493175) (xy 248.128184 -120.514987)
			(xy 248.074227 -120.529093) (xy 248.01879 -120.535193) (xy 247.963056 -120.533156) (xy 247.908213 -120.523026)
			(xy 247.855429 -120.505019) (xy 247.805829 -120.479518) (xy 247.760471 -120.447067) (xy 247.720322 -120.408358)
			(xy 247.686236 -120.364215) (xy 247.65894 -120.31558) (xy 247.639017 -120.263489) (xy 247.626891 -120.209052)
			(xy 247.62282 -120.15343) (xy 245.189134 -120.15343) (xy 245.182143 -120.200932) (xy 245.166075 -120.254339)
			(xy 245.142403 -120.304836) (xy 245.11163 -120.351349) (xy 245.074413 -120.392886) (xy 245.031545 -120.428561)
			(xy 244.983939 -120.457615) (xy 244.93261 -120.479427) (xy 244.878653 -120.493533) (xy 244.823216 -120.499633)
			(xy 244.767482 -120.497596) (xy 244.712639 -120.487466) (xy 244.659855 -120.469459) (xy 244.610255 -120.443958)
			(xy 244.564897 -120.411507) (xy 244.524748 -120.372798) (xy 244.490662 -120.328655) (xy 244.463366 -120.28002)
			(xy 244.443443 -120.227929) (xy 244.431317 -120.173492) (xy 244.427246 -120.11787) (xy 244.174772 -120.11787)
			(xy 244.174263 -120.145756) (xy 244.166143 -120.200932) (xy 244.150075 -120.254339) (xy 244.126403 -120.304836)
			(xy 244.09563 -120.351349) (xy 244.058413 -120.392886) (xy 244.015545 -120.428561) (xy 243.967939 -120.457615)
			(xy 243.91661 -120.479427) (xy 243.862653 -120.493533) (xy 243.807216 -120.499633) (xy 243.751482 -120.497596)
			(xy 243.696639 -120.487466) (xy 243.643855 -120.469459) (xy 243.594255 -120.443958) (xy 243.548897 -120.411507)
			(xy 243.508748 -120.372798) (xy 243.474662 -120.328655) (xy 243.447366 -120.28002) (xy 243.427443 -120.227929)
			(xy 243.415317 -120.173492) (xy 243.411246 -120.11787) (xy 243.135854 -120.11787) (xy 243.150143 -120.165364)
			(xy 243.158263 -120.22054) (xy 243.158772 -120.248426) (xy 243.158263 -120.276312) (xy 243.150143 -120.331488)
			(xy 243.134075 -120.384895) (xy 243.110403 -120.435392) (xy 243.07963 -120.481905) (xy 243.042413 -120.523442)
			(xy 242.999545 -120.559117) (xy 242.951939 -120.588171) (xy 242.90061 -120.609983) (xy 242.846653 -120.624089)
			(xy 242.791216 -120.630189) (xy 242.735482 -120.628152) (xy 242.680639 -120.618022) (xy 242.627855 -120.600015)
			(xy 242.578255 -120.574514) (xy 242.532897 -120.542063) (xy 242.492748 -120.503354) (xy 242.458662 -120.459211)
			(xy 242.431366 -120.410576) (xy 242.411443 -120.358485) (xy 242.399317 -120.304048) (xy 242.395246 -120.248426)
			(xy 214.437524 -120.248426) (xy 214.422677 -120.297773) (xy 214.399005 -120.34827) (xy 214.368232 -120.394783)
			(xy 214.331015 -120.43632) (xy 214.288147 -120.471995) (xy 214.240541 -120.501049) (xy 214.189212 -120.522861)
			(xy 214.135255 -120.536967) (xy 214.079818 -120.543067) (xy 214.024084 -120.54103) (xy 213.969241 -120.5309)
			(xy 213.916457 -120.512893) (xy 213.866857 -120.487392) (xy 213.821499 -120.454941) (xy 213.78135 -120.416232)
			(xy 213.747264 -120.372089) (xy 213.719968 -120.323454) (xy 213.700045 -120.271363) (xy 213.687919 -120.216926)
			(xy 213.683848 -120.161304) (xy 209.538869 -120.161304) (xy 209.537912 -120.164547) (xy 209.51507 -120.214294)
			(xy 209.485345 -120.26026) (xy 209.467704 -120.281192) (xy 209.46745 -120.281446) (xy 209.461874 -120.28854)
			(xy 209.455622 -120.305451) (xy 209.455258 -120.314466) (xy 209.455258 -120.381522) (xy 209.455592 -120.390541)
			(xy 209.461854 -120.407459) (xy 209.46745 -120.414542) (xy 209.467704 -120.414542) (xy 209.467704 -120.414796)
			(xy 209.485355 -120.435718) (xy 209.515065 -120.481694) (xy 209.537899 -120.531444) (xy 209.553387 -120.583947)
			(xy 209.561212 -120.638124) (xy 209.561684 -120.665494) (xy 209.561239 -120.692748) (xy 209.553482 -120.746701)
			(xy 209.543765 -120.779794) (xy 230.950768 -120.779794) (xy 230.954839 -120.724172) (xy 230.966965 -120.669735)
			(xy 230.986888 -120.617644) (xy 231.014184 -120.569009) (xy 231.04827 -120.524866) (xy 231.088419 -120.486157)
			(xy 231.133777 -120.453706) (xy 231.183377 -120.428205) (xy 231.236161 -120.410198) (xy 231.291004 -120.400068)
			(xy 231.346738 -120.398031) (xy 231.402175 -120.404131) (xy 231.456132 -120.418237) (xy 231.507461 -120.440049)
			(xy 231.555067 -120.469103) (xy 231.597935 -120.504778) (xy 231.635152 -120.546315) (xy 231.665925 -120.592828)
			(xy 231.689597 -120.643325) (xy 231.705665 -120.696732) (xy 231.713785 -120.751908) (xy 231.714294 -120.779794)
			(xy 231.713785 -120.80768) (xy 231.705665 -120.862856) (xy 231.689597 -120.916263) (xy 231.665925 -120.96676)
			(xy 231.635152 -121.013273) (xy 231.597935 -121.05481) (xy 231.555067 -121.090485) (xy 231.507461 -121.119539)
			(xy 231.456132 -121.141351) (xy 231.402175 -121.155457) (xy 231.346738 -121.161557) (xy 231.291004 -121.15952)
			(xy 231.236161 -121.14939) (xy 231.183377 -121.131383) (xy 231.133777 -121.105882) (xy 231.088419 -121.073431)
			(xy 231.04827 -121.034722) (xy 231.014184 -120.990579) (xy 230.986888 -120.941944) (xy 230.966965 -120.889853)
			(xy 230.954839 -120.835416) (xy 230.950768 -120.779794) (xy 209.543765 -120.779794) (xy 209.538126 -120.799)
			(xy 209.515482 -120.848582) (xy 209.486013 -120.894436) (xy 209.450317 -120.93563) (xy 209.409122 -120.971323)
			(xy 209.363266 -121.000791) (xy 209.313683 -121.023432) (xy 209.261383 -121.038786) (xy 209.20743 -121.04654)
			(xy 209.180176 -121.047002) (xy 209.151054 -121.046441) (xy 209.093484 -121.037611) (xy 209.037925 -121.020131)
			(xy 208.98567 -120.994406) (xy 208.937935 -120.961035) (xy 208.895828 -120.920794) (xy 208.86033 -120.874618)
			(xy 208.832266 -120.823582) (xy 208.812288 -120.768872) (xy 208.806034 -120.740424) (xy 208.803748 -120.72874)
			(xy 208.78927 -120.709944) (xy 208.705196 -120.669558) (xy 208.694379 -120.665004) (xy 208.670943 -120.665258)
			(xy 208.660238 -120.670066) (xy 208.65973 -120.670066) (xy 208.632671 -120.683349) (xy 208.575396 -120.702127)
			(xy 208.515877 -120.711646) (xy 208.48574 -120.71223) (xy 208.458489 -120.711708) (xy 208.404541 -120.703957)
			(xy 208.352246 -120.688607) (xy 208.302668 -120.665971) (xy 208.256815 -120.636509) (xy 208.215623 -120.600821)
			(xy 208.179928 -120.559634) (xy 208.150459 -120.513787) (xy 208.127815 -120.464212) (xy 208.112457 -120.411919)
			(xy 208.104697 -120.357973) (xy 208.104232 -120.330722) (xy 206.310753 -120.330722) (xy 206.30528 -120.36858)
			(xy 206.289779 -120.421084) (xy 206.266927 -120.470832) (xy 206.237196 -120.5168) (xy 206.219552 -120.537732)
			(xy 206.219298 -120.537986) (xy 206.213711 -120.545072) (xy 206.207465 -120.561989) (xy 206.207106 -120.571006)
			(xy 206.207106 -120.638062) (xy 206.20748 -120.647077) (xy 206.213716 -120.663994) (xy 206.219298 -120.671082)
			(xy 206.219552 -120.671082) (xy 206.219552 -120.671336) (xy 206.237167 -120.692288) (xy 206.266884 -120.738254)
			(xy 206.289726 -120.787997) (xy 206.305222 -120.840493) (xy 206.313055 -120.894666) (xy 206.313532 -120.922034)
			(xy 206.313046 -120.949285) (xy 206.30529 -121.003233) (xy 206.289935 -121.055528) (xy 206.267293 -121.105105)
			(xy 206.237827 -121.150955) (xy 206.202136 -121.192146) (xy 206.160945 -121.227837) (xy 206.115095 -121.257303)
			(xy 206.065518 -121.279945) (xy 206.013223 -121.2953) (xy 205.959275 -121.303056) (xy 205.904773 -121.303056)
			(xy 205.850825 -121.2953) (xy 205.79853 -121.279945) (xy 205.748953 -121.257303) (xy 205.703103 -121.227837)
			(xy 205.661912 -121.192146) (xy 205.626221 -121.150955) (xy 205.596755 -121.105105) (xy 205.574113 -121.055528)
			(xy 205.558758 -121.003233) (xy 205.551002 -120.949285) (xy 205.550516 -120.922034) (xy 200.732136 -120.922034)
			(xy 200.732136 -121.365772) (xy 200.731646 -121.39574) (xy 200.723823 -121.455162) (xy 200.70831 -121.513055)
			(xy 200.685374 -121.568428) (xy 200.655407 -121.620334) (xy 200.61892 -121.667884) (xy 200.57654 -121.710264)
			(xy 200.52899 -121.746751) (xy 200.477084 -121.776718) (xy 200.421711 -121.799654) (xy 200.363818 -121.815167)
			(xy 200.304396 -121.82299) (xy 200.24446 -121.82299) (xy 200.185038 -121.815167) (xy 200.127145 -121.799654)
			(xy 200.071772 -121.776718) (xy 200.019866 -121.746751) (xy 199.972316 -121.710264) (xy 199.929936 -121.667884)
			(xy 199.893449 -121.620334) (xy 199.863482 -121.568428) (xy 199.840546 -121.513055) (xy 199.825033 -121.455162)
			(xy 199.81721 -121.39574) (xy 199.81672 -121.365772) (xy 197.410245 -121.365772) (xy 197.393814 -121.751344)
			(xy 197.394454 -121.762612) (xy 197.404203 -121.782933) (xy 197.41261 -121.79046) (xy 197.475602 -121.842022)
			(xy 197.48035 -121.845647) (xy 197.491132 -121.850778) (xy 197.496938 -121.852182) (xy 197.508114 -121.854722)
			(xy 197.51929 -121.851928) (xy 197.520052 -121.851674) (xy 197.521068 -121.85142) (xy 197.53453 -121.848372)
			(xy 197.535292 -121.848372) (xy 197.559183 -121.843437) (xy 197.607674 -121.838087) (xy 197.632066 -121.837704)
			(xy 197.651116 -121.837704) (xy 197.656196 -121.837958) (xy 197.680834 -121.840244) (xy 197.686422 -121.841006)
			(xy 197.71638 -121.845079) (xy 197.774945 -121.860099) (xy 197.831025 -121.882692) (xy 197.883645 -121.912467)
			(xy 197.93189 -121.948907) (xy 197.974922 -121.991377) (xy 198.011992 -122.039139) (xy 198.042457 -122.091363)
			(xy 198.043789 -122.094549) (xy 210.164198 -122.094549) (xy 210.164198 -122.040051) (xy 210.171954 -121.986109)
			(xy 210.187306 -121.933819) (xy 210.209944 -121.884247) (xy 210.239406 -121.8384) (xy 210.275093 -121.797213)
			(xy 210.316278 -121.761523) (xy 210.362122 -121.732058) (xy 210.411693 -121.709416) (xy 210.463982 -121.694059)
			(xy 210.517924 -121.6863) (xy 210.545172 -121.685812) (xy 210.572542 -121.686292) (xy 210.62672 -121.694106)
			(xy 210.679223 -121.709591) (xy 210.728971 -121.73243) (xy 210.774938 -121.762152) (xy 210.79587 -121.779792)
			(xy 210.796124 -121.780046) (xy 210.803196 -121.785654) (xy 210.820124 -121.791887) (xy 210.829144 -121.792238)
			(xy 210.8962 -121.792238) (xy 210.905216 -121.791873) (xy 210.922132 -121.78563) (xy 210.92922 -121.780046)
			(xy 210.92922 -121.779792) (xy 210.929474 -121.779792) (xy 210.950407 -121.762151) (xy 210.996375 -121.732427)
			(xy 211.046121 -121.709581) (xy 211.098623 -121.694085) (xy 211.152801 -121.686256) (xy 211.207543 -121.686256)
			(xy 211.261721 -121.694085) (xy 211.314223 -121.709581) (xy 211.363969 -121.732427) (xy 211.409937 -121.762151)
			(xy 211.43087 -121.779792) (xy 211.431124 -121.780046) (xy 211.438196 -121.785654) (xy 211.455124 -121.791887)
			(xy 211.464144 -121.792238) (xy 211.5312 -121.792238) (xy 211.540216 -121.791873) (xy 211.557132 -121.78563)
			(xy 211.56422 -121.780046) (xy 211.56422 -121.779792) (xy 211.564474 -121.779792) (xy 211.585404 -121.76215)
			(xy 211.631378 -121.732439) (xy 211.681126 -121.709604) (xy 211.733627 -121.694113) (xy 211.787803 -121.686286)
			(xy 211.815172 -121.685812) (xy 211.842428 -121.686233) (xy 211.896384 -121.693987) (xy 211.948688 -121.709342)
			(xy 211.998275 -121.731984) (xy 212.044134 -121.761452) (xy 212.085332 -121.797148) (xy 212.121031 -121.838344)
			(xy 212.150503 -121.884201) (xy 212.173149 -121.933785) (xy 212.188507 -121.986088) (xy 212.196265 -122.040044)
			(xy 212.196265 -122.094556) (xy 212.188507 -122.148512) (xy 212.173149 -122.200815) (xy 212.150503 -122.250399)
			(xy 212.121031 -122.296256) (xy 212.085332 -122.337452) (xy 212.044134 -122.373148) (xy 211.998275 -122.402616)
			(xy 211.948688 -122.425258) (xy 211.896384 -122.440613) (xy 211.842428 -122.448367) (xy 211.815172 -122.448828)
			(xy 211.7878 -122.448396) (xy 211.733619 -122.440573) (xy 211.681115 -122.425077) (xy 211.631369 -122.402227)
			(xy 211.585404 -122.372494) (xy 211.564474 -122.354848) (xy 211.56422 -122.354594) (xy 211.557132 -122.349009)
			(xy 211.540216 -122.342762) (xy 211.5312 -122.342402) (xy 211.464144 -122.342402) (xy 211.455129 -122.34278)
			(xy 211.438212 -122.349013) (xy 211.431124 -122.354594) (xy 211.43087 -122.354848) (xy 211.409937 -122.372489)
			(xy 211.363969 -122.402213) (xy 211.314223 -122.425059) (xy 211.261721 -122.440555) (xy 211.207543 -122.448384)
			(xy 211.152801 -122.448384) (xy 211.098623 -122.440555) (xy 211.046121 -122.425059) (xy 210.996375 -122.402213)
			(xy 210.950407 -122.372489) (xy 210.929474 -122.354848) (xy 210.92922 -122.354594) (xy 210.922132 -122.349009)
			(xy 210.905216 -122.342762) (xy 210.8962 -122.342402) (xy 210.829144 -122.342402) (xy 210.820129 -122.34278)
			(xy 210.803212 -122.349013) (xy 210.796124 -122.354594) (xy 210.796124 -122.354848) (xy 210.79587 -122.354848)
			(xy 210.774916 -122.37246) (xy 210.72895 -122.402177) (xy 210.679208 -122.425019) (xy 210.626712 -122.440517)
			(xy 210.57254 -122.448351) (xy 210.545172 -122.448828) (xy 210.517924 -122.4483) (xy 210.463982 -122.440541)
			(xy 210.411693 -122.425184) (xy 210.362122 -122.402542) (xy 210.316278 -122.373077) (xy 210.275093 -122.337387)
			(xy 210.239406 -122.2962) (xy 210.209944 -122.250353) (xy 210.187306 -122.200781) (xy 210.171954 -122.148491)
			(xy 210.164198 -122.094549) (xy 198.043789 -122.094549) (xy 198.065785 -122.147141) (xy 198.081573 -122.205504)
			(xy 198.089545 -122.265436) (xy 198.090028 -122.295666) (xy 198.090028 -122.525028) (xy 213.607396 -122.525028)
			(xy 213.607877 -122.49828) (xy 213.615373 -122.44531) (xy 213.630194 -122.393907) (xy 213.65205 -122.345077)
			(xy 213.680512 -122.29978) (xy 213.715021 -122.258901) (xy 213.754902 -122.223244) (xy 213.799373 -122.193506)
			(xy 213.847561 -122.170271) (xy 213.898522 -122.153995) (xy 213.951257 -122.144996) (xy 213.977982 -122.143774)
			(xy 213.991505 -122.142968) (xy 214.017415 -122.135085) (xy 214.040341 -122.120668) (xy 214.058671 -122.100731)
			(xy 214.071115 -122.076676) (xy 214.076798 -122.050197) (xy 214.075319 -122.023155) (xy 214.071454 -122.01017)
			(xy 214.062467 -121.98108) (xy 214.052766 -121.920976) (xy 214.05215 -121.890536) (xy 214.05215 -121.890028)
			(xy 214.052636 -121.862777) (xy 214.060392 -121.808829) (xy 214.075747 -121.756534) (xy 214.098389 -121.706957)
			(xy 214.127855 -121.661107) (xy 214.163546 -121.619916) (xy 214.204737 -121.584225) (xy 214.250587 -121.554759)
			(xy 214.300164 -121.532117) (xy 214.352459 -121.516762) (xy 214.406407 -121.509006) (xy 214.460909 -121.509006)
			(xy 214.514857 -121.516762) (xy 214.567152 -121.532117) (xy 214.616729 -121.554759) (xy 214.662579 -121.584225)
			(xy 214.70377 -121.619916) (xy 214.739461 -121.661107) (xy 214.768927 -121.706957) (xy 214.785371 -121.742962)
			(xy 220.459298 -121.742962) (xy 220.463369 -121.68734) (xy 220.475495 -121.632903) (xy 220.495418 -121.580812)
			(xy 220.522714 -121.532177) (xy 220.5568 -121.488034) (xy 220.596949 -121.449325) (xy 220.642307 -121.416874)
			(xy 220.691907 -121.391373) (xy 220.744691 -121.373366) (xy 220.799534 -121.363236) (xy 220.855268 -121.361199)
			(xy 220.910705 -121.367299) (xy 220.964662 -121.381405) (xy 221.005578 -121.398792) (xy 233.551728 -121.398792)
			(xy 233.555799 -121.34317) (xy 233.567925 -121.288733) (xy 233.587848 -121.236642) (xy 233.615144 -121.188007)
			(xy 233.64923 -121.143864) (xy 233.689379 -121.105155) (xy 233.734737 -121.072704) (xy 233.784337 -121.047203)
			(xy 233.837121 -121.029196) (xy 233.891964 -121.019066) (xy 233.947698 -121.017029) (xy 234.003135 -121.023129)
			(xy 234.057092 -121.037235) (xy 234.108421 -121.059047) (xy 234.156027 -121.088101) (xy 234.198895 -121.123776)
			(xy 234.236112 -121.165313) (xy 234.266885 -121.211826) (xy 234.290557 -121.262323) (xy 234.306625 -121.31573)
			(xy 234.314745 -121.370906) (xy 234.315254 -121.398792) (xy 234.567728 -121.398792) (xy 234.571799 -121.34317)
			(xy 234.583925 -121.288733) (xy 234.603848 -121.236642) (xy 234.631144 -121.188007) (xy 234.66523 -121.143864)
			(xy 234.705379 -121.105155) (xy 234.750737 -121.072704) (xy 234.800337 -121.047203) (xy 234.853121 -121.029196)
			(xy 234.907964 -121.019066) (xy 234.963698 -121.017029) (xy 235.019135 -121.023129) (xy 235.073092 -121.037235)
			(xy 235.124421 -121.059047) (xy 235.172027 -121.088101) (xy 235.214895 -121.123776) (xy 235.252112 -121.165313)
			(xy 235.282885 -121.211826) (xy 235.306557 -121.262323) (xy 235.322625 -121.31573) (xy 235.330745 -121.370906)
			(xy 235.331254 -121.398792) (xy 235.583728 -121.398792) (xy 235.587799 -121.34317) (xy 235.599925 -121.288733)
			(xy 235.619848 -121.236642) (xy 235.647144 -121.188007) (xy 235.68123 -121.143864) (xy 235.721379 -121.105155)
			(xy 235.766737 -121.072704) (xy 235.816337 -121.047203) (xy 235.869121 -121.029196) (xy 235.923964 -121.019066)
			(xy 235.979698 -121.017029) (xy 236.035135 -121.023129) (xy 236.089092 -121.037235) (xy 236.140421 -121.059047)
			(xy 236.188027 -121.088101) (xy 236.230895 -121.123776) (xy 236.268112 -121.165313) (xy 236.298885 -121.211826)
			(xy 236.322557 -121.262323) (xy 236.338625 -121.31573) (xy 236.346745 -121.370906) (xy 236.347254 -121.398792)
			(xy 236.346745 -121.426678) (xy 236.338625 -121.481854) (xy 236.322557 -121.535261) (xy 236.30592 -121.57075)
			(xy 245.81993 -121.57075) (xy 245.820355 -121.544434) (xy 245.827597 -121.492304) (xy 245.841924 -121.44166)
			(xy 245.863064 -121.393461) (xy 245.890618 -121.348618) (xy 245.924065 -121.307981) (xy 245.94312 -121.289826)
			(xy 245.950515 -121.282299) (xy 245.959043 -121.263023) (xy 245.95963 -121.252488) (xy 245.95963 -121.177812)
			(xy 245.959099 -121.167263) (xy 245.950564 -121.147968) (xy 245.94312 -121.140474) (xy 245.924063 -121.12232)
			(xy 245.890605 -121.081691) (xy 245.863046 -121.03685) (xy 245.841907 -120.988649) (xy 245.827591 -120.938001)
			(xy 245.820368 -120.885866) (xy 245.81993 -120.85955) (xy 245.820416 -120.832299) (xy 245.828172 -120.778351)
			(xy 245.843527 -120.726056) (xy 245.866169 -120.676479) (xy 245.895635 -120.630629) (xy 245.931326 -120.589438)
			(xy 245.972517 -120.553747) (xy 246.018367 -120.524281) (xy 246.067944 -120.501639) (xy 246.120239 -120.486284)
			(xy 246.174187 -120.478528) (xy 246.228689 -120.478528) (xy 246.282637 -120.486284) (xy 246.334932 -120.501639)
			(xy 246.384509 -120.524281) (xy 246.430359 -120.553747) (xy 246.47155 -120.589438) (xy 246.507241 -120.630629)
			(xy 246.536707 -120.676479) (xy 246.559349 -120.726056) (xy 246.574704 -120.778351) (xy 246.58246 -120.832299)
			(xy 246.582946 -120.85955) (xy 246.582529 -120.885866) (xy 246.575286 -120.937997) (xy 246.560959 -120.988642)
			(xy 246.539817 -121.036841) (xy 246.512261 -121.081683) (xy 246.478812 -121.12232) (xy 246.459756 -121.140474)
			(xy 246.452372 -121.148011) (xy 246.443836 -121.167279) (xy 246.443246 -121.177812) (xy 246.443246 -121.252488)
			(xy 246.443754 -121.26304) (xy 246.452303 -121.282337) (xy 246.459756 -121.289826) (xy 246.478828 -121.307965)
			(xy 246.512281 -121.348599) (xy 246.539837 -121.393444) (xy 246.560972 -121.441647) (xy 246.575286 -121.492297)
			(xy 246.582509 -121.544433) (xy 246.582946 -121.57075) (xy 246.58246 -121.598001) (xy 246.574704 -121.651949)
			(xy 246.559349 -121.704244) (xy 246.536707 -121.753821) (xy 246.507241 -121.799671) (xy 246.47155 -121.840862)
			(xy 246.430359 -121.876553) (xy 246.384509 -121.906019) (xy 246.334932 -121.928661) (xy 246.282637 -121.944016)
			(xy 246.228689 -121.951772) (xy 246.174187 -121.951772) (xy 246.120239 -121.944016) (xy 246.067944 -121.928661)
			(xy 246.018367 -121.906019) (xy 245.972517 -121.876553) (xy 245.931326 -121.840862) (xy 245.895635 -121.799671)
			(xy 245.866169 -121.753821) (xy 245.843527 -121.704244) (xy 245.828172 -121.651949) (xy 245.820416 -121.598001)
			(xy 245.81993 -121.57075) (xy 236.30592 -121.57075) (xy 236.298885 -121.585758) (xy 236.268112 -121.632271)
			(xy 236.230895 -121.673808) (xy 236.188027 -121.709483) (xy 236.140421 -121.738537) (xy 236.089092 -121.760349)
			(xy 236.035135 -121.774455) (xy 235.979698 -121.780555) (xy 235.923964 -121.778518) (xy 235.869121 -121.768388)
			(xy 235.816337 -121.750381) (xy 235.766737 -121.72488) (xy 235.721379 -121.692429) (xy 235.68123 -121.65372)
			(xy 235.647144 -121.609577) (xy 235.619848 -121.560942) (xy 235.599925 -121.508851) (xy 235.587799 -121.454414)
			(xy 235.583728 -121.398792) (xy 235.331254 -121.398792) (xy 235.330745 -121.426678) (xy 235.322625 -121.481854)
			(xy 235.306557 -121.535261) (xy 235.282885 -121.585758) (xy 235.252112 -121.632271) (xy 235.214895 -121.673808)
			(xy 235.172027 -121.709483) (xy 235.124421 -121.738537) (xy 235.073092 -121.760349) (xy 235.019135 -121.774455)
			(xy 234.963698 -121.780555) (xy 234.907964 -121.778518) (xy 234.853121 -121.768388) (xy 234.800337 -121.750381)
			(xy 234.750737 -121.72488) (xy 234.705379 -121.692429) (xy 234.66523 -121.65372) (xy 234.631144 -121.609577)
			(xy 234.603848 -121.560942) (xy 234.583925 -121.508851) (xy 234.571799 -121.454414) (xy 234.567728 -121.398792)
			(xy 234.315254 -121.398792) (xy 234.314745 -121.426678) (xy 234.306625 -121.481854) (xy 234.290557 -121.535261)
			(xy 234.266885 -121.585758) (xy 234.236112 -121.632271) (xy 234.198895 -121.673808) (xy 234.156027 -121.709483)
			(xy 234.108421 -121.738537) (xy 234.057092 -121.760349) (xy 234.003135 -121.774455) (xy 233.947698 -121.780555)
			(xy 233.891964 -121.778518) (xy 233.837121 -121.768388) (xy 233.784337 -121.750381) (xy 233.734737 -121.72488)
			(xy 233.689379 -121.692429) (xy 233.64923 -121.65372) (xy 233.615144 -121.609577) (xy 233.587848 -121.560942)
			(xy 233.567925 -121.508851) (xy 233.555799 -121.454414) (xy 233.551728 -121.398792) (xy 221.005578 -121.398792)
			(xy 221.015991 -121.403217) (xy 221.063597 -121.432271) (xy 221.106465 -121.467946) (xy 221.143682 -121.509483)
			(xy 221.174455 -121.555996) (xy 221.198127 -121.606493) (xy 221.214195 -121.6599) (xy 221.222315 -121.715076)
			(xy 221.222824 -121.742962) (xy 221.222315 -121.770848) (xy 221.214195 -121.826024) (xy 221.198127 -121.879431)
			(xy 221.174455 -121.929928) (xy 221.143682 -121.976441) (xy 221.106465 -122.017978) (xy 221.063597 -122.053653)
			(xy 221.015991 -122.082707) (xy 220.964662 -122.104519) (xy 220.910705 -122.118625) (xy 220.855268 -122.124725)
			(xy 220.799534 -122.122688) (xy 220.744691 -122.112558) (xy 220.691907 -122.094551) (xy 220.642307 -122.06905)
			(xy 220.596949 -122.036599) (xy 220.5568 -121.99789) (xy 220.522714 -121.953747) (xy 220.495418 -121.905112)
			(xy 220.475495 -121.853021) (xy 220.463369 -121.798584) (xy 220.459298 -121.742962) (xy 214.785371 -121.742962)
			(xy 214.791569 -121.756534) (xy 214.806924 -121.808829) (xy 214.81468 -121.862777) (xy 214.815166 -121.890028)
			(xy 214.814681 -121.916777) (xy 214.80719 -121.969748) (xy 214.792372 -122.021154) (xy 214.770519 -122.069985)
			(xy 214.742059 -122.115285) (xy 214.707549 -122.156165) (xy 214.667667 -122.191823) (xy 214.623195 -122.221561)
			(xy 214.575005 -122.244794) (xy 214.524042 -122.261067) (xy 214.471305 -122.270062) (xy 214.44458 -122.271282)
			(xy 214.431061 -122.272115) (xy 214.40516 -122.280002) (xy 214.385103 -122.292618) (xy 241.98021 -122.292618)
			(xy 241.984281 -122.236996) (xy 241.996407 -122.182559) (xy 242.01633 -122.130468) (xy 242.043626 -122.081833)
			(xy 242.077712 -122.03769) (xy 242.117861 -121.998981) (xy 242.163219 -121.96653) (xy 242.212819 -121.941029)
			(xy 242.265603 -121.923022) (xy 242.320446 -121.912892) (xy 242.37618 -121.910855) (xy 242.431617 -121.916955)
			(xy 242.485574 -121.931061) (xy 242.536903 -121.952873) (xy 242.584509 -121.981927) (xy 242.627377 -122.017602)
			(xy 242.664594 -122.059139) (xy 242.695367 -122.105652) (xy 242.719039 -122.156149) (xy 242.735107 -122.209556)
			(xy 242.743227 -122.264732) (xy 242.743736 -122.292618) (xy 242.743227 -122.320504) (xy 242.735107 -122.37568)
			(xy 242.719039 -122.429087) (xy 242.699902 -122.46991) (xy 243.136926 -122.46991) (xy 243.140997 -122.414288)
			(xy 243.153123 -122.359851) (xy 243.173046 -122.30776) (xy 243.200342 -122.259125) (xy 243.234428 -122.214982)
			(xy 243.274577 -122.176273) (xy 243.319935 -122.143822) (xy 243.369535 -122.118321) (xy 243.422319 -122.100314)
			(xy 243.477162 -122.090184) (xy 243.532896 -122.088147) (xy 243.588333 -122.094247) (xy 243.64229 -122.108353)
			(xy 243.693619 -122.130165) (xy 243.741225 -122.159219) (xy 243.784093 -122.194894) (xy 243.82131 -122.236431)
			(xy 243.852083 -122.282944) (xy 243.875755 -122.333441) (xy 243.891823 -122.386848) (xy 243.899943 -122.442024)
			(xy 243.900452 -122.46991) (xy 243.899943 -122.497796) (xy 243.891823 -122.552972) (xy 243.875755 -122.606379)
			(xy 243.852083 -122.656876) (xy 243.82131 -122.703389) (xy 243.784093 -122.744926) (xy 243.741225 -122.780601)
			(xy 243.693619 -122.809655) (xy 243.64229 -122.831467) (xy 243.588333 -122.845573) (xy 243.532896 -122.851673)
			(xy 243.477162 -122.849636) (xy 243.422319 -122.839506) (xy 243.369535 -122.821499) (xy 243.319935 -122.795998)
			(xy 243.274577 -122.763547) (xy 243.234428 -122.724838) (xy 243.200342 -122.680695) (xy 243.173046 -122.63206)
			(xy 243.153123 -122.579969) (xy 243.140997 -122.525532) (xy 243.136926 -122.46991) (xy 242.699902 -122.46991)
			(xy 242.695367 -122.479584) (xy 242.664594 -122.526097) (xy 242.627377 -122.567634) (xy 242.584509 -122.603309)
			(xy 242.536903 -122.632363) (xy 242.485574 -122.654175) (xy 242.431617 -122.668281) (xy 242.37618 -122.674381)
			(xy 242.320446 -122.672344) (xy 242.265603 -122.662214) (xy 242.212819 -122.644207) (xy 242.163219 -122.618706)
			(xy 242.117861 -122.586255) (xy 242.077712 -122.547546) (xy 242.043626 -122.503403) (xy 242.01633 -122.454768)
			(xy 241.996407 -122.402677) (xy 241.984281 -122.34824) (xy 241.98021 -122.292618) (xy 214.385103 -122.292618)
			(xy 214.382241 -122.294418) (xy 214.363916 -122.314349) (xy 214.351472 -122.338396) (xy 214.345783 -122.364867)
			(xy 214.34725 -122.391903) (xy 214.351108 -122.404886) (xy 214.360107 -122.433973) (xy 214.3698 -122.494079)
			(xy 214.370412 -122.52452) (xy 214.370412 -122.525028) (xy 214.369926 -122.552279) (xy 214.36217 -122.606227)
			(xy 214.346815 -122.658522) (xy 214.324173 -122.708099) (xy 214.294707 -122.753949) (xy 214.290363 -122.758962)
			(xy 218.430854 -122.758962) (xy 218.434925 -122.70334) (xy 218.447051 -122.648903) (xy 218.466974 -122.596812)
			(xy 218.49427 -122.548177) (xy 218.528356 -122.504034) (xy 218.568505 -122.465325) (xy 218.613863 -122.432874)
			(xy 218.663463 -122.407373) (xy 218.716247 -122.389366) (xy 218.77109 -122.379236) (xy 218.826824 -122.377199)
			(xy 218.882261 -122.383299) (xy 218.936218 -122.397405) (xy 218.987547 -122.419217) (xy 219.035153 -122.448271)
			(xy 219.078021 -122.483946) (xy 219.115238 -122.525483) (xy 219.146011 -122.571996) (xy 219.169683 -122.622493)
			(xy 219.185751 -122.6759) (xy 219.193871 -122.731076) (xy 219.19438 -122.758962) (xy 219.193871 -122.786848)
			(xy 219.185751 -122.842024) (xy 219.169683 -122.895431) (xy 219.146011 -122.945928) (xy 219.115238 -122.992441)
			(xy 219.078021 -123.033978) (xy 219.035153 -123.069653) (xy 218.987547 -123.098707) (xy 218.936218 -123.120519)
			(xy 218.882261 -123.134625) (xy 218.826824 -123.140725) (xy 218.77109 -123.138688) (xy 218.716247 -123.128558)
			(xy 218.663463 -123.110551) (xy 218.613863 -123.08505) (xy 218.568505 -123.052599) (xy 218.528356 -123.01389)
			(xy 218.49427 -122.969747) (xy 218.466974 -122.921112) (xy 218.447051 -122.869021) (xy 218.434925 -122.814584)
			(xy 218.430854 -122.758962) (xy 214.290363 -122.758962) (xy 214.259016 -122.79514) (xy 214.217825 -122.830831)
			(xy 214.171975 -122.860297) (xy 214.122398 -122.882939) (xy 214.070103 -122.898294) (xy 214.016155 -122.90605)
			(xy 213.961653 -122.90605) (xy 213.907705 -122.898294) (xy 213.85541 -122.882939) (xy 213.805833 -122.860297)
			(xy 213.759983 -122.830831) (xy 213.718792 -122.79514) (xy 213.683101 -122.753949) (xy 213.653635 -122.708099)
			(xy 213.630993 -122.658522) (xy 213.615638 -122.606227) (xy 213.607882 -122.552279) (xy 213.607396 -122.525028)
			(xy 198.090028 -122.525028) (xy 198.090028 -122.972347) (xy 210.707522 -122.972347) (xy 210.707522 -122.917853)
			(xy 210.715277 -122.863913) (xy 210.730629 -122.811626) (xy 210.753266 -122.762057) (xy 210.782727 -122.716213)
			(xy 210.818412 -122.675028) (xy 210.859595 -122.63934) (xy 210.905437 -122.609877) (xy 210.955006 -122.587237)
			(xy 211.007292 -122.571882) (xy 211.061231 -122.564124) (xy 211.088478 -122.563636) (xy 211.116082 -122.564094)
			(xy 211.170715 -122.572036) (xy 211.223632 -122.587773) (xy 211.273727 -122.610975) (xy 211.319953 -122.641157)
			(xy 211.361345 -122.677689) (xy 211.397036 -122.719807) (xy 211.412074 -122.74296) (xy 211.420048 -122.754782)
			(xy 211.441213 -122.773872) (xy 211.466832 -122.786362) (xy 211.494906 -122.791279) (xy 211.523245 -122.78824)
			(xy 211.549637 -122.77748) (xy 211.572024 -122.759841) (xy 211.58073 -122.748548) (xy 211.596147 -122.7278)
			(xy 211.631687 -122.690264) (xy 211.67197 -122.657871) (xy 211.716258 -122.631215) (xy 211.76374 -122.610784)
			(xy 211.813546 -122.596953) (xy 211.864764 -122.589973) (xy 211.89061 -122.589544) (xy 211.917857 -122.590127)
			(xy 211.971797 -122.597884) (xy 212.024084 -122.613238) (xy 212.073654 -122.635876) (xy 212.119497 -122.665339)
			(xy 212.160681 -122.701026) (xy 212.196367 -122.742211) (xy 212.225828 -122.788055) (xy 212.248466 -122.837625)
			(xy 212.263819 -122.889913) (xy 212.271574 -122.943853) (xy 212.271574 -122.998347) (xy 212.263819 -123.052287)
			(xy 212.248466 -123.104575) (xy 212.225828 -123.154145) (xy 212.196367 -123.199989) (xy 212.160681 -123.241174)
			(xy 212.119497 -123.276861) (xy 212.073654 -123.306324) (xy 212.024084 -123.328962) (xy 211.971797 -123.344316)
			(xy 211.917857 -123.352073) (xy 211.89061 -123.35256) (xy 211.863008 -123.352036) (xy 211.808378 -123.344106)
			(xy 211.755463 -123.328381) (xy 211.705368 -123.30519) (xy 211.659141 -123.275018) (xy 211.617747 -123.238495)
			(xy 211.582053 -123.196385) (xy 211.567014 -123.173236) (xy 211.559055 -123.161403) (xy 211.537887 -123.142314)
			(xy 211.512265 -123.129824) (xy 211.484188 -123.124908) (xy 211.455847 -123.12795) (xy 211.429452 -123.138712)
			(xy 211.407064 -123.156354) (xy 211.398358 -123.167648) (xy 211.382947 -123.188401) (xy 211.347407 -123.225937)
			(xy 211.307123 -123.258329) (xy 211.262833 -123.284985) (xy 211.21535 -123.305415) (xy 211.165543 -123.319246)
			(xy 211.114324 -123.326223) (xy 211.088478 -123.326652) (xy 211.061231 -123.326076) (xy 211.007292 -123.318318)
			(xy 210.955006 -123.302963) (xy 210.905437 -123.280323) (xy 210.859595 -123.25086) (xy 210.818412 -123.215172)
			(xy 210.782727 -123.173987) (xy 210.753266 -123.128143) (xy 210.730629 -123.078574) (xy 210.715277 -123.026287)
			(xy 210.707522 -122.972347) (xy 198.090028 -122.972347) (xy 198.090028 -123.159266) (xy 198.089561 -123.189252)
			(xy 198.081737 -123.248712) (xy 198.066218 -123.306642) (xy 198.043269 -123.36205) (xy 198.013284 -123.413989)
			(xy 197.976776 -123.461569) (xy 197.934369 -123.503976) (xy 197.886789 -123.540484) (xy 197.83485 -123.570469)
			(xy 197.779442 -123.593418) (xy 197.721512 -123.608937) (xy 197.662052 -123.616761) (xy 197.632066 -123.617228)
			(xy 197.626986 -123.617228) (xy 197.621652 -123.616974) (xy 197.62089 -123.616974) (xy 197.605709 -123.616451)
			(xy 197.575458 -123.613656) (xy 197.560438 -123.611386) (xy 197.54088 -123.60783) (xy 197.506854 -123.600288)
			(xy 197.441419 -123.576309) (xy 197.410578 -123.560078) (xy 197.40499 -123.55703) (xy 197.37959 -123.550426)
			(xy 197.37324 -123.550934) (xy 197.335648 -123.559062) (xy 197.330345 -123.560757) (xy 197.320603 -123.566144)
			(xy 197.316344 -123.56973) (xy 197.256822 -124.965714) (xy 199.81672 -124.965714) (xy 199.81672 -124.102114)
			(xy 199.81721 -124.072146) (xy 199.825033 -124.012724) (xy 199.840546 -123.954831) (xy 199.863482 -123.899458)
			(xy 199.893449 -123.847552) (xy 199.929936 -123.800002) (xy 199.972316 -123.757622) (xy 200.019866 -123.721135)
			(xy 200.071772 -123.691168) (xy 200.127145 -123.668232) (xy 200.185038 -123.652719) (xy 200.24446 -123.644896)
			(xy 200.304396 -123.644896) (xy 200.363818 -123.652719) (xy 200.421711 -123.668232) (xy 200.477084 -123.691168)
			(xy 200.52899 -123.721135) (xy 200.57654 -123.757622) (xy 200.61892 -123.800002) (xy 200.655407 -123.847552)
			(xy 200.685374 -123.899458) (xy 200.70831 -123.954831) (xy 200.723823 -124.012724) (xy 200.731646 -124.072146)
			(xy 200.732136 -124.102114) (xy 200.732136 -124.621544) (xy 211.274914 -124.621544) (xy 211.27534 -124.595229)
			(xy 211.282582 -124.543098) (xy 211.296909 -124.492454) (xy 211.31805 -124.444255) (xy 211.345603 -124.399413)
			(xy 211.379049 -124.358775) (xy 211.398104 -124.34062) (xy 211.405499 -124.333093) (xy 211.414027 -124.313817)
			(xy 211.414614 -124.303282) (xy 211.414614 -124.228606) (xy 211.414091 -124.218056) (xy 211.405551 -124.198761)
			(xy 211.398104 -124.191268) (xy 211.379041 -124.17312) (xy 211.345584 -124.132489) (xy 211.318026 -124.087647)
			(xy 211.296889 -124.039445) (xy 211.282573 -123.988796) (xy 211.275351 -123.936661) (xy 211.274914 -123.910344)
			(xy 211.2754 -123.883093) (xy 211.283156 -123.829145) (xy 211.298511 -123.77685) (xy 211.321153 -123.727273)
			(xy 211.350619 -123.681423) (xy 211.38631 -123.640232) (xy 211.427501 -123.604541) (xy 211.473351 -123.575075)
			(xy 211.522928 -123.552433) (xy 211.575223 -123.537078) (xy 211.629171 -123.529322) (xy 211.683673 -123.529322)
			(xy 211.737621 -123.537078) (xy 211.789916 -123.552433) (xy 211.839493 -123.575075) (xy 211.885343 -123.604541)
			(xy 211.926534 -123.640232) (xy 211.962225 -123.681423) (xy 211.991691 -123.727273) (xy 212.013471 -123.774962)
			(xy 218.430854 -123.774962) (xy 218.434925 -123.71934) (xy 218.447051 -123.664903) (xy 218.466974 -123.612812)
			(xy 218.49427 -123.564177) (xy 218.528356 -123.520034) (xy 218.568505 -123.481325) (xy 218.613863 -123.448874)
			(xy 218.663463 -123.423373) (xy 218.716247 -123.405366) (xy 218.77109 -123.395236) (xy 218.826824 -123.393199)
			(xy 218.882261 -123.399299) (xy 218.936218 -123.413405) (xy 218.987547 -123.435217) (xy 219.035153 -123.464271)
			(xy 219.078021 -123.499946) (xy 219.115238 -123.541483) (xy 219.146011 -123.587996) (xy 219.169683 -123.638493)
			(xy 219.185751 -123.6919) (xy 219.193871 -123.747076) (xy 219.19438 -123.774962) (xy 220.586298 -123.774962)
			(xy 220.590369 -123.71934) (xy 220.602495 -123.664903) (xy 220.622418 -123.612812) (xy 220.649714 -123.564177)
			(xy 220.6838 -123.520034) (xy 220.723949 -123.481325) (xy 220.769307 -123.448874) (xy 220.818907 -123.423373)
			(xy 220.871691 -123.405366) (xy 220.926534 -123.395236) (xy 220.982268 -123.393199) (xy 221.037705 -123.399299)
			(xy 221.091662 -123.413405) (xy 221.142991 -123.435217) (xy 221.190597 -123.464271) (xy 221.233465 -123.499946)
			(xy 221.241599 -123.509024) (xy 223.888298 -123.509024) (xy 223.892369 -123.453402) (xy 223.904495 -123.398965)
			(xy 223.924418 -123.346874) (xy 223.951714 -123.298239) (xy 223.9858 -123.254096) (xy 224.025949 -123.215387)
			(xy 224.071307 -123.182936) (xy 224.120907 -123.157435) (xy 224.173691 -123.139428) (xy 224.228534 -123.129298)
			(xy 224.284268 -123.127261) (xy 224.339705 -123.133361) (xy 224.393662 -123.147467) (xy 224.444991 -123.169279)
			(xy 224.492597 -123.198333) (xy 224.535465 -123.234008) (xy 224.572682 -123.275545) (xy 224.603455 -123.322058)
			(xy 224.627127 -123.372555) (xy 224.643195 -123.425962) (xy 224.651315 -123.481138) (xy 224.651824 -123.509024)
			(xy 224.651606 -123.520962) (xy 226.047298 -123.520962) (xy 226.051369 -123.46534) (xy 226.063495 -123.410903)
			(xy 226.083418 -123.358812) (xy 226.110714 -123.310177) (xy 226.1448 -123.266034) (xy 226.184949 -123.227325)
			(xy 226.230307 -123.194874) (xy 226.279907 -123.169373) (xy 226.332691 -123.151366) (xy 226.387534 -123.141236)
			(xy 226.443268 -123.139199) (xy 226.498705 -123.145299) (xy 226.552662 -123.159405) (xy 226.603991 -123.181217)
			(xy 226.651597 -123.210271) (xy 226.694465 -123.245946) (xy 226.697875 -123.249752) (xy 244.109967 -123.249752)
			(xy 244.109967 -123.195248) (xy 244.117724 -123.141299) (xy 244.13308 -123.089002) (xy 244.155722 -123.039423)
			(xy 244.185189 -122.993572) (xy 244.220882 -122.95238) (xy 244.262073 -122.916688) (xy 244.307925 -122.887221)
			(xy 244.357504 -122.864579) (xy 244.4098 -122.849224) (xy 244.46375 -122.841467) (xy 244.491002 -122.841004)
			(xy 244.518032 -122.841498) (xy 244.571549 -122.849136) (xy 244.623451 -122.864259) (xy 244.672695 -122.886564)
			(xy 244.718294 -122.915602) (xy 244.759332 -122.950791) (xy 244.777514 -122.970798) (xy 244.777768 -122.971052)
			(xy 244.785208 -122.978703) (xy 244.804695 -122.987369) (xy 244.81536 -122.987816) (xy 244.90299 -122.988324)
			(xy 244.922548 -122.979688) (xy 244.929914 -122.971306) (xy 244.948074 -122.951582) (xy 244.988975 -122.916918)
			(xy 245.034331 -122.88833) (xy 245.083246 -122.866381) (xy 245.134755 -122.851505) (xy 245.187841 -122.843997)
			(xy 245.214648 -122.843544) (xy 245.242018 -122.84403) (xy 245.296196 -122.851841) (xy 245.3487 -122.867325)
			(xy 245.398447 -122.890163) (xy 245.444414 -122.919884) (xy 245.465346 -122.937524) (xy 245.4656 -122.937778)
			(xy 245.472676 -122.94338) (xy 245.489601 -122.949615) (xy 245.49862 -122.94997) (xy 245.565676 -122.94997)
			(xy 245.574692 -122.949608) (xy 245.59161 -122.943364) (xy 245.598696 -122.937778) (xy 245.598696 -122.937524)
			(xy 245.59895 -122.937524) (xy 245.619883 -122.919883) (xy 245.665851 -122.890159) (xy 245.715597 -122.867313)
			(xy 245.768099 -122.851817) (xy 245.822277 -122.843988) (xy 245.877019 -122.843988) (xy 245.931197 -122.851817)
			(xy 245.983699 -122.867313) (xy 246.033445 -122.890159) (xy 246.079413 -122.919883) (xy 246.100346 -122.937524)
			(xy 246.1006 -122.937778) (xy 246.107676 -122.94338) (xy 246.124601 -122.949615) (xy 246.13362 -122.94997)
			(xy 246.200676 -122.94997) (xy 246.209692 -122.949608) (xy 246.22661 -122.943364) (xy 246.233696 -122.937778)
			(xy 246.234204 -122.937524) (xy 246.246938 -122.926579) (xy 246.274029 -122.906738) (xy 246.288306 -122.8979)
			(xy 246.297196 -122.892566) (xy 246.309388 -122.875548) (xy 246.329708 -122.78233) (xy 246.32539 -122.761756)
			(xy 246.319548 -122.75312) (xy 246.303548 -122.729056) (xy 246.278207 -122.677124) (xy 246.260982 -122.621966)
			(xy 246.252266 -122.564842) (xy 246.25173 -122.53595) (xy 246.252216 -122.508699) (xy 246.259972 -122.454751)
			(xy 246.275327 -122.402456) (xy 246.297969 -122.352879) (xy 246.327435 -122.307029) (xy 246.363126 -122.265838)
			(xy 246.404317 -122.230147) (xy 246.450167 -122.200681) (xy 246.499744 -122.178039) (xy 246.552039 -122.162684)
			(xy 246.605987 -122.154928) (xy 246.660489 -122.154928) (xy 246.714437 -122.162684) (xy 246.766732 -122.178039)
			(xy 246.816309 -122.200681) (xy 246.862159 -122.230147) (xy 246.90335 -122.265838) (xy 246.939041 -122.307029)
			(xy 246.968507 -122.352879) (xy 246.991149 -122.402456) (xy 247.006504 -122.454751) (xy 247.01426 -122.508699)
			(xy 247.014746 -122.53595) (xy 247.014198 -122.56404) (xy 247.005979 -122.619614) (xy 246.989696 -122.673381)
			(xy 246.965702 -122.724178) (xy 246.934515 -122.770905) (xy 246.896812 -122.812552) (xy 246.853407 -122.848217)
			(xy 246.82958 -122.863102) (xy 246.82069 -122.868436) (xy 246.808498 -122.885454) (xy 246.788178 -122.978672)
			(xy 246.792496 -122.999246) (xy 246.798338 -123.007882) (xy 246.814337 -123.031946) (xy 246.839679 -123.083878)
			(xy 246.856905 -123.139036) (xy 246.865621 -123.19616) (xy 246.866156 -123.225052) (xy 246.865577 -123.2523)
			(xy 246.857829 -123.306242) (xy 246.842482 -123.358532) (xy 246.81985 -123.408106) (xy 246.790393 -123.453954)
			(xy 246.754711 -123.495143) (xy 246.713531 -123.530836) (xy 246.66769 -123.560304) (xy 246.618122 -123.582948)
			(xy 246.565836 -123.598308) (xy 246.511896 -123.60607) (xy 246.484648 -123.60656) (xy 246.457278 -123.606076)
			(xy 246.4031 -123.598264) (xy 246.350596 -123.582779) (xy 246.300849 -123.559942) (xy 246.254882 -123.53022)
			(xy 246.23395 -123.51258) (xy 246.233696 -123.512326) (xy 246.226621 -123.506723) (xy 246.209695 -123.500488)
			(xy 246.200676 -123.500134) (xy 246.13362 -123.500134) (xy 246.124603 -123.500493) (xy 246.107686 -123.506739)
			(xy 246.1006 -123.512326) (xy 246.100346 -123.51258) (xy 246.079413 -123.530221) (xy 246.033445 -123.559945)
			(xy 245.983699 -123.582791) (xy 245.931197 -123.598287) (xy 245.877019 -123.606116) (xy 245.822277 -123.606116)
			(xy 245.768099 -123.598287) (xy 245.715597 -123.582791) (xy 245.665851 -123.559945) (xy 245.619883 -123.530221)
			(xy 245.59895 -123.51258) (xy 245.598696 -123.512326) (xy 245.591621 -123.506723) (xy 245.574695 -123.500488)
			(xy 245.565676 -123.500134) (xy 245.49862 -123.500134) (xy 245.489603 -123.500493) (xy 245.472686 -123.506739)
			(xy 245.4656 -123.512326) (xy 245.4656 -123.51258) (xy 245.465346 -123.51258) (xy 245.444405 -123.530208)
			(xy 245.398435 -123.559922) (xy 245.34869 -123.582761) (xy 245.296191 -123.598254) (xy 245.242017 -123.606085)
			(xy 245.214648 -123.60656) (xy 245.187618 -123.606078) (xy 245.134101 -123.598435) (xy 245.0822 -123.583308)
			(xy 245.032957 -123.561001) (xy 244.987358 -123.531961) (xy 244.946319 -123.496772) (xy 244.928136 -123.476766)
			(xy 244.927882 -123.476512) (xy 244.920414 -123.468893) (xy 244.900949 -123.460207) (xy 244.89029 -123.459748)
			(xy 244.80266 -123.45924) (xy 244.783102 -123.467876) (xy 244.775736 -123.476258) (xy 244.757564 -123.49597)
			(xy 244.716664 -123.530633) (xy 244.67131 -123.559221) (xy 244.622398 -123.581172) (xy 244.570891 -123.59605)
			(xy 244.517808 -123.603564) (xy 244.491002 -123.60402) (xy 244.46375 -123.603533) (xy 244.4098 -123.595776)
			(xy 244.357504 -123.580421) (xy 244.307925 -123.557779) (xy 244.262073 -123.528312) (xy 244.220882 -123.49262)
			(xy 244.185189 -123.451428) (xy 244.155722 -123.405577) (xy 244.13308 -123.355998) (xy 244.117724 -123.303701)
			(xy 244.109967 -123.249752) (xy 226.697875 -123.249752) (xy 226.731682 -123.287483) (xy 226.762455 -123.333996)
			(xy 226.786127 -123.384493) (xy 226.802195 -123.4379) (xy 226.810315 -123.493076) (xy 226.810824 -123.520962)
			(xy 226.810315 -123.548848) (xy 226.802195 -123.604024) (xy 226.786127 -123.657431) (xy 226.762455 -123.707928)
			(xy 226.731682 -123.754441) (xy 226.694465 -123.795978) (xy 226.651597 -123.831653) (xy 226.603991 -123.860707)
			(xy 226.552662 -123.882519) (xy 226.498705 -123.896625) (xy 226.443268 -123.902725) (xy 226.387534 -123.900688)
			(xy 226.332691 -123.890558) (xy 226.279907 -123.872551) (xy 226.230307 -123.84705) (xy 226.184949 -123.814599)
			(xy 226.1448 -123.77589) (xy 226.110714 -123.731747) (xy 226.083418 -123.683112) (xy 226.063495 -123.631021)
			(xy 226.051369 -123.576584) (xy 226.047298 -123.520962) (xy 224.651606 -123.520962) (xy 224.651315 -123.53691)
			(xy 224.643195 -123.592086) (xy 224.627127 -123.645493) (xy 224.603455 -123.69599) (xy 224.572682 -123.742503)
			(xy 224.535465 -123.78404) (xy 224.492597 -123.819715) (xy 224.444991 -123.848769) (xy 224.393662 -123.870581)
			(xy 224.339705 -123.884687) (xy 224.284268 -123.890787) (xy 224.228534 -123.88875) (xy 224.173691 -123.87862)
			(xy 224.120907 -123.860613) (xy 224.071307 -123.835112) (xy 224.025949 -123.802661) (xy 223.9858 -123.763952)
			(xy 223.951714 -123.719809) (xy 223.924418 -123.671174) (xy 223.904495 -123.619083) (xy 223.892369 -123.564646)
			(xy 223.888298 -123.509024) (xy 221.241599 -123.509024) (xy 221.270682 -123.541483) (xy 221.301455 -123.587996)
			(xy 221.325127 -123.638493) (xy 221.341195 -123.6919) (xy 221.349315 -123.747076) (xy 221.349824 -123.774962)
			(xy 221.349315 -123.802848) (xy 221.341195 -123.858024) (xy 221.325127 -123.911431) (xy 221.301455 -123.961928)
			(xy 221.270682 -124.008441) (xy 221.233465 -124.049978) (xy 221.190597 -124.085653) (xy 221.142991 -124.114707)
			(xy 221.091662 -124.136519) (xy 221.037705 -124.150625) (xy 220.982268 -124.156725) (xy 220.926534 -124.154688)
			(xy 220.871691 -124.144558) (xy 220.818907 -124.126551) (xy 220.769307 -124.10105) (xy 220.723949 -124.068599)
			(xy 220.6838 -124.02989) (xy 220.649714 -123.985747) (xy 220.622418 -123.937112) (xy 220.602495 -123.885021)
			(xy 220.590369 -123.830584) (xy 220.586298 -123.774962) (xy 219.19438 -123.774962) (xy 219.193871 -123.802848)
			(xy 219.185751 -123.858024) (xy 219.169683 -123.911431) (xy 219.146011 -123.961928) (xy 219.115238 -124.008441)
			(xy 219.078021 -124.049978) (xy 219.035153 -124.085653) (xy 218.987547 -124.114707) (xy 218.936218 -124.136519)
			(xy 218.882261 -124.150625) (xy 218.826824 -124.156725) (xy 218.77109 -124.154688) (xy 218.716247 -124.144558)
			(xy 218.663463 -124.126551) (xy 218.613863 -124.10105) (xy 218.568505 -124.068599) (xy 218.528356 -124.02989)
			(xy 218.49427 -123.985747) (xy 218.466974 -123.937112) (xy 218.447051 -123.885021) (xy 218.434925 -123.830584)
			(xy 218.430854 -123.774962) (xy 212.013471 -123.774962) (xy 212.014333 -123.77685) (xy 212.029688 -123.829145)
			(xy 212.037444 -123.883093) (xy 212.03793 -123.910344) (xy 212.037482 -123.936659) (xy 212.030242 -123.988788)
			(xy 212.015918 -124.03943) (xy 211.994782 -124.087629) (xy 211.967233 -124.132472) (xy 211.933792 -124.173111)
			(xy 211.91474 -124.191268) (xy 211.907357 -124.198805) (xy 211.898821 -124.218073) (xy 211.89823 -124.228606)
			(xy 211.89823 -124.303282) (xy 211.898746 -124.313833) (xy 211.90729 -124.333129) (xy 211.91474 -124.34062)
			(xy 211.933806 -124.358765) (xy 211.967261 -124.399398) (xy 211.994817 -124.444241) (xy 212.015954 -124.492443)
			(xy 212.030269 -124.543092) (xy 212.037492 -124.595227) (xy 212.03793 -124.621544) (xy 212.037444 -124.648795)
			(xy 212.029688 -124.702743) (xy 212.014333 -124.755038) (xy 211.991691 -124.804615) (xy 211.962225 -124.850465)
			(xy 211.926534 -124.891656) (xy 211.885343 -124.927347) (xy 211.839493 -124.956813) (xy 211.825009 -124.963428)
			(xy 240.873024 -124.963428) (xy 240.877095 -124.907806) (xy 240.889221 -124.853369) (xy 240.909144 -124.801278)
			(xy 240.93644 -124.752643) (xy 240.970526 -124.7085) (xy 241.010675 -124.669791) (xy 241.056033 -124.63734)
			(xy 241.105633 -124.611839) (xy 241.158417 -124.593832) (xy 241.21326 -124.583702) (xy 241.268994 -124.581665)
			(xy 241.324431 -124.587765) (xy 241.378388 -124.601871) (xy 241.429717 -124.623683) (xy 241.477323 -124.652737)
			(xy 241.520191 -124.688412) (xy 241.557408 -124.729949) (xy 241.588181 -124.776462) (xy 241.611853 -124.826959)
			(xy 241.627921 -124.880366) (xy 241.636041 -124.935542) (xy 241.63655 -124.963428) (xy 241.636041 -124.991314)
			(xy 241.627921 -125.04649) (xy 241.624483 -125.057916) (xy 242.981478 -125.057916) (xy 242.985549 -125.002294)
			(xy 242.997675 -124.947857) (xy 243.017598 -124.895766) (xy 243.044894 -124.847131) (xy 243.07898 -124.802988)
			(xy 243.119129 -124.764279) (xy 243.164487 -124.731828) (xy 243.214087 -124.706327) (xy 243.266871 -124.68832)
			(xy 243.321714 -124.67819) (xy 243.377448 -124.676153) (xy 243.432885 -124.682253) (xy 243.486842 -124.696359)
			(xy 243.538171 -124.718171) (xy 243.585777 -124.747225) (xy 243.628645 -124.7829) (xy 243.665862 -124.824437)
			(xy 243.696635 -124.87095) (xy 243.720307 -124.921447) (xy 243.736375 -124.974854) (xy 243.744495 -125.03003)
			(xy 243.745004 -125.057916) (xy 243.744495 -125.085802) (xy 243.736375 -125.140978) (xy 243.720307 -125.194385)
			(xy 243.696635 -125.244882) (xy 243.665862 -125.291395) (xy 243.628645 -125.332932) (xy 243.585777 -125.368607)
			(xy 243.538171 -125.397661) (xy 243.524769 -125.403356) (xy 247.744234 -125.403356) (xy 247.744725 -125.375987)
			(xy 247.752535 -125.321808) (xy 247.768018 -125.269305) (xy 247.790855 -125.219558) (xy 247.820575 -125.17359)
			(xy 247.838214 -125.152658) (xy 247.838468 -125.152404) (xy 247.844067 -125.145326) (xy 247.850304 -125.128402)
			(xy 247.85066 -125.119384) (xy 247.85066 -125.052328) (xy 247.850298 -125.043311) (xy 247.844055 -125.026394)
			(xy 247.838468 -125.019308) (xy 247.838214 -125.019308) (xy 247.838214 -125.019054) (xy 247.820589 -124.998111)
			(xy 247.790875 -124.952141) (xy 247.768036 -124.902397) (xy 247.752541 -124.849898) (xy 247.74471 -124.795724)
			(xy 247.744234 -124.768356) (xy 247.74472 -124.741105) (xy 247.752476 -124.687157) (xy 247.767831 -124.634862)
			(xy 247.790473 -124.585285) (xy 247.819939 -124.539435) (xy 247.85563 -124.498244) (xy 247.896821 -124.462553)
			(xy 247.942671 -124.433087) (xy 247.992248 -124.410445) (xy 248.044543 -124.39509) (xy 248.098491 -124.387334)
			(xy 248.152993 -124.387334) (xy 248.206941 -124.39509) (xy 248.259236 -124.410445) (xy 248.308813 -124.433087)
			(xy 248.354663 -124.462553) (xy 248.395854 -124.498244) (xy 248.431545 -124.539435) (xy 248.461011 -124.585285)
			(xy 248.483653 -124.634862) (xy 248.499008 -124.687157) (xy 248.506764 -124.741105) (xy 248.50725 -124.768356)
			(xy 248.50677 -124.795726) (xy 248.498958 -124.849905) (xy 248.483472 -124.902408) (xy 248.460633 -124.952155)
			(xy 248.430911 -124.998122) (xy 248.41327 -125.019054) (xy 248.413016 -125.019308) (xy 248.407422 -125.026389)
			(xy 248.401179 -125.04331) (xy 248.400824 -125.052328) (xy 248.400824 -125.119384) (xy 248.401184 -125.128401)
			(xy 248.407429 -125.145318) (xy 248.413016 -125.152404) (xy 248.41327 -125.152404) (xy 248.41327 -125.152658)
			(xy 248.430898 -125.173599) (xy 248.460613 -125.219569) (xy 248.483451 -125.269314) (xy 248.498945 -125.321813)
			(xy 248.506775 -125.375987) (xy 248.50725 -125.403356) (xy 248.506764 -125.430607) (xy 248.499008 -125.484555)
			(xy 248.483653 -125.53685) (xy 248.461011 -125.586427) (xy 248.431545 -125.632277) (xy 248.395854 -125.673468)
			(xy 248.354663 -125.709159) (xy 248.308813 -125.738625) (xy 248.259236 -125.761267) (xy 248.206941 -125.776622)
			(xy 248.152993 -125.784378) (xy 248.098491 -125.784378) (xy 248.044543 -125.776622) (xy 247.992248 -125.761267)
			(xy 247.942671 -125.738625) (xy 247.896821 -125.709159) (xy 247.85563 -125.673468) (xy 247.819939 -125.632277)
			(xy 247.790473 -125.586427) (xy 247.767831 -125.53685) (xy 247.752476 -125.484555) (xy 247.74472 -125.430607)
			(xy 247.744234 -125.403356) (xy 243.524769 -125.403356) (xy 243.486842 -125.419473) (xy 243.432885 -125.433579)
			(xy 243.377448 -125.439679) (xy 243.321714 -125.437642) (xy 243.266871 -125.427512) (xy 243.214087 -125.409505)
			(xy 243.164487 -125.384004) (xy 243.119129 -125.351553) (xy 243.07898 -125.312844) (xy 243.044894 -125.268701)
			(xy 243.017598 -125.220066) (xy 242.997675 -125.167975) (xy 242.985549 -125.113538) (xy 242.981478 -125.057916)
			(xy 241.624483 -125.057916) (xy 241.611853 -125.099897) (xy 241.588181 -125.150394) (xy 241.557408 -125.196907)
			(xy 241.520191 -125.238444) (xy 241.477323 -125.274119) (xy 241.429717 -125.303173) (xy 241.378388 -125.324985)
			(xy 241.324431 -125.339091) (xy 241.268994 -125.345191) (xy 241.21326 -125.343154) (xy 241.158417 -125.333024)
			(xy 241.105633 -125.315017) (xy 241.056033 -125.289516) (xy 241.010675 -125.257065) (xy 240.970526 -125.218356)
			(xy 240.93644 -125.174213) (xy 240.909144 -125.125578) (xy 240.889221 -125.073487) (xy 240.877095 -125.01905)
			(xy 240.873024 -124.963428) (xy 211.825009 -124.963428) (xy 211.789916 -124.979455) (xy 211.737621 -124.99481)
			(xy 211.683673 -125.002566) (xy 211.629171 -125.002566) (xy 211.575223 -124.99481) (xy 211.522928 -124.979455)
			(xy 211.473351 -124.956813) (xy 211.427501 -124.927347) (xy 211.38631 -124.891656) (xy 211.350619 -124.850465)
			(xy 211.321153 -124.804615) (xy 211.298511 -124.755038) (xy 211.283156 -124.702743) (xy 211.2754 -124.648795)
			(xy 211.274914 -124.621544) (xy 200.732136 -124.621544) (xy 200.732136 -124.965714) (xy 200.731646 -124.995682)
			(xy 200.723823 -125.055104) (xy 200.70831 -125.112997) (xy 200.685374 -125.16837) (xy 200.655407 -125.220276)
			(xy 200.61892 -125.267826) (xy 200.57654 -125.310206) (xy 200.52899 -125.346693) (xy 200.477084 -125.37666)
			(xy 200.421711 -125.399596) (xy 200.363818 -125.415109) (xy 200.304396 -125.422932) (xy 200.24446 -125.422932)
			(xy 200.185038 -125.415109) (xy 200.127145 -125.399596) (xy 200.071772 -125.37666) (xy 200.019866 -125.346693)
			(xy 199.972316 -125.310206) (xy 199.929936 -125.267826) (xy 199.893449 -125.220276) (xy 199.863482 -125.16837)
			(xy 199.840546 -125.112997) (xy 199.825033 -125.055104) (xy 199.81721 -124.995682) (xy 199.81672 -124.965714)
			(xy 197.256822 -124.965714) (xy 197.223888 -125.738128) (xy 217.592908 -125.738128) (xy 217.596979 -125.682506)
			(xy 217.609105 -125.628069) (xy 217.629028 -125.575978) (xy 217.656324 -125.527343) (xy 217.69041 -125.4832)
			(xy 217.730559 -125.444491) (xy 217.775917 -125.41204) (xy 217.825517 -125.386539) (xy 217.878301 -125.368532)
			(xy 217.933144 -125.358402) (xy 217.988878 -125.356365) (xy 218.044315 -125.362465) (xy 218.098272 -125.376571)
			(xy 218.149601 -125.398383) (xy 218.197207 -125.427437) (xy 218.240075 -125.463112) (xy 218.277292 -125.504649)
			(xy 218.308065 -125.551162) (xy 218.331737 -125.601659) (xy 218.347805 -125.655066) (xy 218.355925 -125.710242)
			(xy 218.356434 -125.738128) (xy 218.355925 -125.766014) (xy 218.347805 -125.82119) (xy 218.331737 -125.874597)
			(xy 218.308065 -125.925094) (xy 218.277292 -125.971607) (xy 218.270284 -125.979428) (xy 240.873024 -125.979428)
			(xy 240.877095 -125.923806) (xy 240.889221 -125.869369) (xy 240.909144 -125.817278) (xy 240.93644 -125.768643)
			(xy 240.970526 -125.7245) (xy 241.010675 -125.685791) (xy 241.056033 -125.65334) (xy 241.105633 -125.627839)
			(xy 241.158417 -125.609832) (xy 241.21326 -125.599702) (xy 241.268994 -125.597665) (xy 241.324431 -125.603765)
			(xy 241.378388 -125.617871) (xy 241.429717 -125.639683) (xy 241.477323 -125.668737) (xy 241.520191 -125.704412)
			(xy 241.557408 -125.745949) (xy 241.588181 -125.792462) (xy 241.611853 -125.842959) (xy 241.627921 -125.896366)
			(xy 241.636041 -125.951542) (xy 241.63655 -125.979428) (xy 241.636041 -126.007314) (xy 241.627921 -126.06249)
			(xy 241.614396 -126.107444) (xy 243.356382 -126.107444) (xy 243.360453 -126.051822) (xy 243.372579 -125.997385)
			(xy 243.392502 -125.945294) (xy 243.419798 -125.896659) (xy 243.453884 -125.852516) (xy 243.494033 -125.813807)
			(xy 243.539391 -125.781356) (xy 243.588991 -125.755855) (xy 243.641775 -125.737848) (xy 243.696618 -125.727718)
			(xy 243.752352 -125.725681) (xy 243.807789 -125.731781) (xy 243.861746 -125.745887) (xy 243.913075 -125.767699)
			(xy 243.960681 -125.796753) (xy 244.003549 -125.832428) (xy 244.022607 -125.853698) (xy 248.684796 -125.853698)
			(xy 248.685262 -125.826328) (xy 248.69308 -125.772149) (xy 248.708569 -125.719646) (xy 248.731411 -125.669899)
			(xy 248.761135 -125.623932) (xy 248.778776 -125.603) (xy 248.77903 -125.602746) (xy 248.784607 -125.595653)
			(xy 248.790858 -125.578741) (xy 248.791222 -125.569726) (xy 248.791222 -125.50267) (xy 248.790875 -125.493652)
			(xy 248.78462 -125.476736) (xy 248.77903 -125.46965) (xy 248.778776 -125.46965) (xy 248.778776 -125.469396)
			(xy 248.761118 -125.448479) (xy 248.73141 -125.402502) (xy 248.708578 -125.35275) (xy 248.693091 -125.300247)
			(xy 248.685268 -125.246068) (xy 248.684796 -125.218698) (xy 248.685282 -125.191447) (xy 248.693038 -125.137499)
			(xy 248.708393 -125.085204) (xy 248.731035 -125.035627) (xy 248.760501 -124.989777) (xy 248.796192 -124.948586)
			(xy 248.837383 -124.912895) (xy 248.883233 -124.883429) (xy 248.93281 -124.860787) (xy 248.985105 -124.845432)
			(xy 249.039053 -124.837676) (xy 249.093555 -124.837676) (xy 249.147503 -124.845432) (xy 249.199798 -124.860787)
			(xy 249.249375 -124.883429) (xy 249.295225 -124.912895) (xy 249.336416 -124.948586) (xy 249.372107 -124.989777)
			(xy 249.401573 -125.035627) (xy 249.424215 -125.085204) (xy 249.43957 -125.137499) (xy 249.447326 -125.191447)
			(xy 249.447812 -125.218698) (xy 249.447342 -125.246068) (xy 249.439525 -125.300247) (xy 249.424036 -125.35275)
			(xy 249.401196 -125.402497) (xy 249.371472 -125.448464) (xy 249.353832 -125.469396) (xy 249.353578 -125.46965)
			(xy 249.348004 -125.476745) (xy 249.34175 -125.493655) (xy 249.341386 -125.50267) (xy 249.341386 -125.569726)
			(xy 249.341734 -125.578744) (xy 249.347988 -125.59566) (xy 249.353578 -125.602746) (xy 249.353832 -125.602746)
			(xy 249.353832 -125.603) (xy 249.37149 -125.623917) (xy 249.401198 -125.669895) (xy 249.424029 -125.719646)
			(xy 249.439516 -125.77215) (xy 249.44734 -125.826328) (xy 249.447812 -125.853698) (xy 249.447326 -125.880949)
			(xy 249.43957 -125.934897) (xy 249.424215 -125.987192) (xy 249.401573 -126.036769) (xy 249.372107 -126.082619)
			(xy 249.336416 -126.12381) (xy 249.295225 -126.159501) (xy 249.249375 -126.188967) (xy 249.199798 -126.211609)
			(xy 249.147503 -126.226964) (xy 249.093555 -126.23472) (xy 249.039053 -126.23472) (xy 248.985105 -126.226964)
			(xy 248.93281 -126.211609) (xy 248.883233 -126.188967) (xy 248.837383 -126.159501) (xy 248.796192 -126.12381)
			(xy 248.760501 -126.082619) (xy 248.731035 -126.036769) (xy 248.708393 -125.987192) (xy 248.693038 -125.934897)
			(xy 248.685282 -125.880949) (xy 248.684796 -125.853698) (xy 244.022607 -125.853698) (xy 244.040766 -125.873965)
			(xy 244.071539 -125.920478) (xy 244.095211 -125.970975) (xy 244.111279 -126.024382) (xy 244.119399 -126.079558)
			(xy 244.119908 -126.107444) (xy 244.119399 -126.13533) (xy 244.111279 -126.190506) (xy 244.095211 -126.243913)
			(xy 244.071539 -126.29441) (xy 244.040766 -126.340923) (xy 244.003549 -126.38246) (xy 243.960681 -126.418135)
			(xy 243.913075 -126.447189) (xy 243.861746 -126.469001) (xy 243.807789 -126.483107) (xy 243.752352 -126.489207)
			(xy 243.696618 -126.48717) (xy 243.641775 -126.47704) (xy 243.588991 -126.459033) (xy 243.539391 -126.433532)
			(xy 243.494033 -126.401081) (xy 243.453884 -126.362372) (xy 243.419798 -126.318229) (xy 243.392502 -126.269594)
			(xy 243.372579 -126.217503) (xy 243.360453 -126.163066) (xy 243.356382 -126.107444) (xy 241.614396 -126.107444)
			(xy 241.611853 -126.115897) (xy 241.588181 -126.166394) (xy 241.557408 -126.212907) (xy 241.520191 -126.254444)
			(xy 241.477323 -126.290119) (xy 241.429717 -126.319173) (xy 241.378388 -126.340985) (xy 241.324431 -126.355091)
			(xy 241.268994 -126.361191) (xy 241.21326 -126.359154) (xy 241.158417 -126.349024) (xy 241.105633 -126.331017)
			(xy 241.056033 -126.305516) (xy 241.010675 -126.273065) (xy 240.970526 -126.234356) (xy 240.93644 -126.190213)
			(xy 240.909144 -126.141578) (xy 240.889221 -126.089487) (xy 240.877095 -126.03505) (xy 240.873024 -125.979428)
			(xy 218.270284 -125.979428) (xy 218.240075 -126.013144) (xy 218.197207 -126.048819) (xy 218.149601 -126.077873)
			(xy 218.098272 -126.099685) (xy 218.044315 -126.113791) (xy 217.988878 -126.119891) (xy 217.933144 -126.117854)
			(xy 217.878301 -126.107724) (xy 217.825517 -126.089717) (xy 217.775917 -126.064216) (xy 217.730559 -126.031765)
			(xy 217.69041 -125.993056) (xy 217.656324 -125.948913) (xy 217.629028 -125.900278) (xy 217.609105 -125.848187)
			(xy 217.596979 -125.79375) (xy 217.592908 -125.738128) (xy 197.223888 -125.738128) (xy 197.215506 -125.934724)
			(xy 197.19012 -126.530354) (xy 249.893328 -126.530354) (xy 249.893869 -126.50269) (xy 249.901862 -126.447941)
			(xy 249.917672 -126.39492) (xy 249.94097 -126.344735) (xy 249.971267 -126.298439) (xy 250.007929 -126.257001)
			(xy 250.050188 -126.221287) (xy 250.073414 -126.20625) (xy 250.083065 -126.199582) (xy 250.095524 -126.179744)
			(xy 250.09729 -126.16815) (xy 250.105164 -126.08814) (xy 250.105759 -126.076503) (xy 250.097704 -126.054668)
			(xy 250.08967 -126.04623) (xy 250.089416 -126.045976) (xy 250.070844 -126.027886) (xy 250.038264 -125.987556)
			(xy 250.011449 -125.943184) (xy 249.990895 -125.895587) (xy 249.97698 -125.845644) (xy 249.969961 -125.794277)
			(xy 249.969528 -125.768354) (xy 249.969935 -125.7411) (xy 249.977699 -125.687148) (xy 249.993062 -125.634849)
			(xy 250.015711 -125.585269) (xy 250.045185 -125.539417) (xy 250.080885 -125.498227) (xy 250.122083 -125.462536)
			(xy 250.167941 -125.433071) (xy 250.217526 -125.410433) (xy 250.269828 -125.395081) (xy 250.323782 -125.387329)
			(xy 250.351036 -125.386846) (xy 250.378408 -125.38728) (xy 250.432588 -125.395104) (xy 250.485092 -125.4106)
			(xy 250.534839 -125.433449) (xy 250.580804 -125.463181) (xy 250.601734 -125.480826) (xy 250.601988 -125.48108)
			(xy 250.609067 -125.486677) (xy 250.62599 -125.492915) (xy 250.635008 -125.493272) (xy 250.702064 -125.493272)
			(xy 250.71108 -125.492904) (xy 250.727997 -125.486665) (xy 250.735084 -125.48108) (xy 250.735084 -125.480826)
			(xy 250.735338 -125.480826) (xy 250.756286 -125.463207) (xy 250.802254 -125.433491) (xy 250.851997 -125.410651)
			(xy 250.904495 -125.395155) (xy 250.958668 -125.387322) (xy 250.986036 -125.386846) (xy 251.013286 -125.387344)
			(xy 251.067231 -125.395104) (xy 251.119523 -125.410462) (xy 251.169097 -125.433104) (xy 251.214945 -125.462569)
			(xy 251.256134 -125.498259) (xy 251.291824 -125.539447) (xy 251.321291 -125.585294) (xy 251.343935 -125.634868)
			(xy 251.359293 -125.687159) (xy 251.367055 -125.741104) (xy 251.367544 -125.768354) (xy 251.367014 -125.797271)
			(xy 251.35829 -125.854442) (xy 251.341036 -125.909642) (xy 251.315647 -125.961604) (xy 251.282704 -126.009138)
			(xy 251.242964 -126.051155) (xy 251.220478 -126.069344) (xy 251.211657 -126.076938) (xy 251.201482 -126.097849)
			(xy 251.20092 -126.109476) (xy 251.20092 -126.189232) (xy 251.201448 -126.200865) (xy 251.211644 -126.221775)
			(xy 251.220478 -126.229364) (xy 251.24294 -126.247581) (xy 251.282677 -126.289595) (xy 251.315619 -126.337124)
			(xy 251.341012 -126.38908) (xy 251.358273 -126.444273) (xy 251.367006 -126.501439) (xy 251.367544 -126.530354)
			(xy 251.367002 -126.557604) (xy 251.359252 -126.61155) (xy 251.347151 -126.652782) (xy 251.638816 -126.652782)
			(xy 251.639268 -126.625411) (xy 251.647088 -126.571231) (xy 251.662581 -126.518728) (xy 251.685426 -126.468981)
			(xy 251.715153 -126.423015) (xy 251.732796 -126.402084) (xy 251.73305 -126.40183) (xy 251.738636 -126.394743)
			(xy 251.744882 -126.377826) (xy 251.745242 -126.36881) (xy 251.745242 -126.301754) (xy 251.744872 -126.292738)
			(xy 251.738635 -126.27582) (xy 251.73305 -126.268734) (xy 251.732796 -126.268734) (xy 251.732796 -126.26848)
			(xy 251.715139 -126.247561) (xy 251.685417 -126.20159) (xy 251.662575 -126.151841) (xy 251.647081 -126.099337)
			(xy 251.639255 -126.045158) (xy 251.639257 -125.990415) (xy 251.647087 -125.936236) (xy 251.662584 -125.883733)
			(xy 251.68543 -125.833986) (xy 251.715155 -125.788017) (xy 251.732796 -125.767084) (xy 251.73305 -125.76683)
			(xy 251.738636 -125.759743) (xy 251.744882 -125.742826) (xy 251.745242 -125.73381) (xy 251.745242 -125.666754)
			(xy 251.744872 -125.657738) (xy 251.738635 -125.64082) (xy 251.73305 -125.633734) (xy 251.732796 -125.633734)
			(xy 251.732796 -125.63348) (xy 251.715139 -125.612561) (xy 251.685417 -125.56659) (xy 251.662575 -125.516841)
			(xy 251.647081 -125.464337) (xy 251.639255 -125.410158) (xy 251.639257 -125.355415) (xy 251.647087 -125.301236)
			(xy 251.662584 -125.248733) (xy 251.68543 -125.198986) (xy 251.715155 -125.153017) (xy 251.732796 -125.132084)
			(xy 251.73305 -125.13183) (xy 251.738636 -125.124743) (xy 251.744882 -125.107826) (xy 251.745242 -125.09881)
			(xy 251.745242 -125.031754) (xy 251.744872 -125.022738) (xy 251.738635 -125.00582) (xy 251.73305 -124.998734)
			(xy 251.732796 -124.998734) (xy 251.732796 -124.99848) (xy 251.71518 -124.977529) (xy 251.685465 -124.931561)
			(xy 251.662625 -124.881819) (xy 251.647128 -124.829322) (xy 251.639294 -124.77515) (xy 251.638816 -124.747782)
			(xy 251.639302 -124.720531) (xy 251.647058 -124.666583) (xy 251.662413 -124.614288) (xy 251.685055 -124.564711)
			(xy 251.714521 -124.518861) (xy 251.750212 -124.47767) (xy 251.791403 -124.441979) (xy 251.837253 -124.412513)
			(xy 251.88683 -124.389871) (xy 251.939125 -124.374516) (xy 251.993073 -124.36676) (xy 252.047575 -124.36676)
			(xy 252.101523 -124.374516) (xy 252.153818 -124.389871) (xy 252.203395 -124.412513) (xy 252.249245 -124.441979)
			(xy 252.290436 -124.47767) (xy 252.326127 -124.518861) (xy 252.355593 -124.564711) (xy 252.378235 -124.614288)
			(xy 252.39359 -124.666583) (xy 252.401346 -124.720531) (xy 252.401832 -124.747782) (xy 252.401372 -124.775153)
			(xy 252.393555 -124.829333) (xy 252.378066 -124.881836) (xy 252.355222 -124.931583) (xy 252.325495 -124.977549)
			(xy 252.307852 -124.99848) (xy 252.307598 -124.998734) (xy 252.302033 -125.005835) (xy 252.295773 -125.022741)
			(xy 252.295406 -125.031754) (xy 252.295406 -125.09881) (xy 252.295757 -125.107828) (xy 252.302009 -125.124744)
			(xy 252.307598 -125.13183) (xy 252.307852 -125.13183) (xy 252.307852 -125.132084) (xy 252.325476 -125.153031)
			(xy 252.355203 -125.198995) (xy 252.378051 -125.248739) (xy 252.393549 -125.301239) (xy 252.40138 -125.355416)
			(xy 252.401382 -125.410156) (xy 252.393555 -125.464334) (xy 252.37806 -125.516835) (xy 252.355216 -125.566581)
			(xy 252.325492 -125.612548) (xy 252.307852 -125.63348) (xy 252.307598 -125.633734) (xy 252.302033 -125.640835)
			(xy 252.295773 -125.657741) (xy 252.295406 -125.666754) (xy 252.295406 -125.73381) (xy 252.295757 -125.742828)
			(xy 252.302009 -125.759744) (xy 252.307598 -125.76683) (xy 252.307852 -125.76683) (xy 252.307852 -125.767084)
			(xy 252.325476 -125.788031) (xy 252.355203 -125.833995) (xy 252.378051 -125.883739) (xy 252.393549 -125.936239)
			(xy 252.40138 -125.990416) (xy 252.401382 -126.045156) (xy 252.393555 -126.099334) (xy 252.37806 -126.151835)
			(xy 252.355216 -126.201581) (xy 252.325492 -126.247548) (xy 252.307852 -126.26848) (xy 252.307598 -126.268734)
			(xy 252.302033 -126.275835) (xy 252.295773 -126.292741) (xy 252.295406 -126.301754) (xy 252.295406 -126.36881)
			(xy 252.295757 -126.377828) (xy 252.302009 -126.394744) (xy 252.307598 -126.40183) (xy 252.307852 -126.40183)
			(xy 252.307852 -126.402084) (xy 252.32549 -126.423017) (xy 252.355203 -126.468989) (xy 252.37804 -126.518736)
			(xy 252.393532 -126.571237) (xy 252.401359 -126.625413) (xy 252.401832 -126.652782) (xy 252.401346 -126.680033)
			(xy 252.39359 -126.733981) (xy 252.378235 -126.786276) (xy 252.355593 -126.835853) (xy 252.326127 -126.881703)
			(xy 252.290436 -126.922894) (xy 252.249245 -126.958585) (xy 252.203395 -126.988051) (xy 252.153818 -127.010693)
			(xy 252.101523 -127.026048) (xy 252.047575 -127.033804) (xy 251.993073 -127.033804) (xy 251.939125 -127.026048)
			(xy 251.88683 -127.010693) (xy 251.837253 -126.988051) (xy 251.791403 -126.958585) (xy 251.750212 -126.922894)
			(xy 251.714521 -126.881703) (xy 251.685055 -126.835853) (xy 251.662413 -126.786276) (xy 251.647058 -126.733981)
			(xy 251.639302 -126.680033) (xy 251.638816 -126.652782) (xy 251.347151 -126.652782) (xy 251.343904 -126.663845)
			(xy 251.321269 -126.713422) (xy 251.291809 -126.759274) (xy 251.256124 -126.800466) (xy 251.214939 -126.83616)
			(xy 251.169094 -126.86563) (xy 251.119521 -126.888275) (xy 251.067231 -126.903635) (xy 251.013286 -126.911396)
			(xy 250.986036 -126.911862) (xy 250.95972 -126.911449) (xy 250.907589 -126.904205) (xy 250.856944 -126.889876)
			(xy 250.808745 -126.868733) (xy 250.763903 -126.841177) (xy 250.723267 -126.807728) (xy 250.705112 -126.788672)
			(xy 250.697578 -126.781284) (xy 250.678308 -126.772749) (xy 250.667774 -126.772162) (xy 250.593098 -126.772162)
			(xy 250.582548 -126.772688) (xy 250.563254 -126.781227) (xy 250.55576 -126.788672) (xy 250.537611 -126.807735)
			(xy 250.496981 -126.841192) (xy 250.452139 -126.868751) (xy 250.403937 -126.889888) (xy 250.353288 -126.904204)
			(xy 250.301153 -126.911425) (xy 250.274836 -126.911862) (xy 250.247582 -126.911411) (xy 250.193628 -126.903658)
			(xy 250.141327 -126.888304) (xy 250.091744 -126.865662) (xy 250.045889 -126.836194) (xy 250.004694 -126.800499)
			(xy 249.969 -126.759303) (xy 249.939533 -126.713447) (xy 249.916892 -126.663863) (xy 249.90154 -126.611562)
			(xy 249.893788 -126.557608) (xy 249.893328 -126.530354) (xy 197.19012 -126.530354) (xy 197.167916 -127.051308)
			(xy 242.94414 -127.051308) (xy 242.948211 -126.995686) (xy 242.960337 -126.941249) (xy 242.98026 -126.889158)
			(xy 243.007556 -126.840523) (xy 243.041642 -126.79638) (xy 243.081791 -126.757671) (xy 243.127149 -126.72522)
			(xy 243.176749 -126.699719) (xy 243.229533 -126.681712) (xy 243.284376 -126.671582) (xy 243.34011 -126.669545)
			(xy 243.395547 -126.675645) (xy 243.449504 -126.689751) (xy 243.500833 -126.711563) (xy 243.548439 -126.740617)
			(xy 243.591307 -126.776292) (xy 243.628524 -126.817829) (xy 243.659297 -126.864342) (xy 243.682969 -126.914839)
			(xy 243.699037 -126.968246) (xy 243.707157 -127.023422) (xy 243.707666 -127.051308) (xy 243.707157 -127.079194)
			(xy 243.699037 -127.13437) (xy 243.682969 -127.187777) (xy 243.659297 -127.238274) (xy 243.628524 -127.284787)
			(xy 243.591307 -127.326324) (xy 243.548439 -127.361999) (xy 243.500833 -127.391053) (xy 243.449504 -127.412865)
			(xy 243.395547 -127.426971) (xy 243.34011 -127.433071) (xy 243.284376 -127.431034) (xy 243.229533 -127.420904)
			(xy 243.176749 -127.402897) (xy 243.127149 -127.377396) (xy 243.081791 -127.344945) (xy 243.041642 -127.306236)
			(xy 243.007556 -127.262093) (xy 242.98026 -127.213458) (xy 242.960337 -127.161367) (xy 242.948211 -127.10693)
			(xy 242.94414 -127.051308) (xy 197.167916 -127.051308) (xy 197.11671 -128.252747) (xy 241.928428 -128.252747)
			(xy 241.928428 -128.198253) (xy 241.936184 -128.144312) (xy 241.951536 -128.092025) (xy 241.974174 -128.042454)
			(xy 242.003636 -127.99661) (xy 242.039323 -127.955426) (xy 242.080507 -127.919739) (xy 242.126351 -127.890276)
			(xy 242.175921 -127.867638) (xy 242.228208 -127.852284) (xy 242.282149 -127.844528) (xy 242.309396 -127.844042)
			(xy 242.336767 -127.8445) (xy 242.390946 -127.852318) (xy 242.44345 -127.867809) (xy 242.493197 -127.890652)
			(xy 242.539163 -127.920379) (xy 242.560094 -127.938022) (xy 242.560348 -127.938276) (xy 242.567439 -127.943856)
			(xy 242.584353 -127.950105) (xy 242.593368 -127.950468) (xy 242.660424 -127.950468) (xy 242.669443 -127.950129)
			(xy 242.68636 -127.94387) (xy 242.693444 -127.938276) (xy 242.693444 -127.938022) (xy 242.693698 -127.938022)
			(xy 242.714631 -127.920381) (xy 242.760599 -127.890657) (xy 242.810345 -127.867811) (xy 242.862847 -127.852315)
			(xy 242.917025 -127.844486) (xy 242.971767 -127.844486) (xy 243.025945 -127.852315) (xy 243.078447 -127.867811)
			(xy 243.128193 -127.890657) (xy 243.174161 -127.920381) (xy 243.195094 -127.938022) (xy 243.195348 -127.938276)
			(xy 243.202439 -127.943856) (xy 243.219353 -127.950105) (xy 243.228368 -127.950468) (xy 243.295424 -127.950468)
			(xy 243.304443 -127.950129) (xy 243.32136 -127.94387) (xy 243.328444 -127.938276) (xy 243.328444 -127.938022)
			(xy 243.328698 -127.938022) (xy 243.349623 -127.920374) (xy 243.395597 -127.890663) (xy 243.445347 -127.867828)
			(xy 243.497849 -127.852339) (xy 243.552026 -127.844514) (xy 243.579396 -127.844042) (xy 243.606653 -127.844405)
			(xy 243.660611 -127.852162) (xy 243.712916 -127.86752) (xy 243.762504 -127.890165) (xy 243.808363 -127.919637)
			(xy 243.849562 -127.955335) (xy 243.885261 -127.996534) (xy 243.914733 -128.042393) (xy 243.937379 -128.09198)
			(xy 243.952737 -128.144285) (xy 243.960495 -128.198243) (xy 243.960495 -128.252757) (xy 243.952737 -128.306715)
			(xy 243.937379 -128.35902) (xy 243.914733 -128.408607) (xy 243.885261 -128.454466) (xy 243.849562 -128.495665)
			(xy 243.808363 -128.531363) (xy 243.762504 -128.560835) (xy 243.712916 -128.58348) (xy 243.660611 -128.598838)
			(xy 243.606653 -128.606595) (xy 243.579396 -128.607058) (xy 243.552025 -128.606605) (xy 243.497845 -128.598785)
			(xy 243.445342 -128.583294) (xy 243.395595 -128.560449) (xy 243.349629 -128.530721) (xy 243.328698 -128.513078)
			(xy 243.328444 -128.512824) (xy 243.321355 -128.507241) (xy 243.30444 -128.500994) (xy 243.295424 -128.500632)
			(xy 243.228368 -128.500632) (xy 243.219349 -128.500967) (xy 243.202432 -128.507229) (xy 243.195348 -128.512824)
			(xy 243.195094 -128.513078) (xy 243.174161 -128.530719) (xy 243.128193 -128.560443) (xy 243.078447 -128.583289)
			(xy 243.025945 -128.598785) (xy 242.971767 -128.606614) (xy 242.917025 -128.606614) (xy 242.862847 -128.598785)
			(xy 242.810345 -128.583289) (xy 242.760599 -128.560443) (xy 242.714631 -128.530719) (xy 242.693698 -128.513078)
			(xy 242.693444 -128.512824) (xy 242.686355 -128.507241) (xy 242.66944 -128.500994) (xy 242.660424 -128.500632)
			(xy 242.593368 -128.500632) (xy 242.584349 -128.500967) (xy 242.567432 -128.507229) (xy 242.560348 -128.512824)
			(xy 242.560348 -128.513078) (xy 242.560094 -128.513078) (xy 242.539172 -128.53073) (xy 242.493197 -128.560441)
			(xy 242.443447 -128.583274) (xy 242.390944 -128.598762) (xy 242.336766 -128.606586) (xy 242.309396 -128.607058)
			(xy 242.282149 -128.606472) (xy 242.228208 -128.598716) (xy 242.175921 -128.583362) (xy 242.126351 -128.560724)
			(xy 242.080507 -128.531261) (xy 242.039323 -128.495574) (xy 242.003636 -128.45439) (xy 241.974174 -128.408546)
			(xy 241.951536 -128.358975) (xy 241.936184 -128.306688) (xy 241.928428 -128.252747) (xy 197.11671 -128.252747)
			(xy 197.097755 -128.697482) (xy 211.268308 -128.697482) (xy 211.272379 -128.64186) (xy 211.284505 -128.587423)
			(xy 211.304428 -128.535332) (xy 211.331724 -128.486697) (xy 211.36581 -128.442554) (xy 211.405959 -128.403845)
			(xy 211.451317 -128.371394) (xy 211.500917 -128.345893) (xy 211.553701 -128.327886) (xy 211.608544 -128.317756)
			(xy 211.664278 -128.315719) (xy 211.719715 -128.321819) (xy 211.773672 -128.335925) (xy 211.825001 -128.357737)
			(xy 211.872607 -128.386791) (xy 211.915475 -128.422466) (xy 211.952692 -128.464003) (xy 211.983465 -128.510516)
			(xy 212.007137 -128.561013) (xy 212.023205 -128.61442) (xy 212.031325 -128.669596) (xy 212.031834 -128.697482)
			(xy 212.031325 -128.725368) (xy 212.023205 -128.780544) (xy 212.007137 -128.833951) (xy 211.983465 -128.884448)
			(xy 211.952692 -128.930961) (xy 211.915475 -128.972498) (xy 211.872607 -129.008173) (xy 211.825001 -129.037227)
			(xy 211.773672 -129.059039) (xy 211.719715 -129.073145) (xy 211.664278 -129.079245) (xy 211.608544 -129.077208)
			(xy 211.553701 -129.067078) (xy 211.500917 -129.049071) (xy 211.451317 -129.02357) (xy 211.405959 -128.991119)
			(xy 211.36581 -128.95241) (xy 211.331724 -128.908267) (xy 211.304428 -128.859632) (xy 211.284505 -128.807541)
			(xy 211.272379 -128.753104) (xy 211.268308 -128.697482) (xy 197.097755 -128.697482) (xy 197.07225 -129.295906)
			(xy 197.073128 -129.306397) (xy 197.082218 -129.325361) (xy 197.098159 -129.339077) (xy 197.108064 -129.342642)
			(xy 197.108318 -129.342642) (xy 197.133876 -129.350815) (xy 197.18258 -129.373337) (xy 197.227644 -129.402466)
			(xy 197.268179 -129.437625) (xy 197.303383 -129.478122) (xy 197.318376 -129.500376) (xy 197.319392 -129.502154)
			(xy 197.324218 -129.508504) (xy 197.324472 -129.508758) (xy 197.332015 -129.516272) (xy 197.351434 -129.524942)
			(xy 197.362064 -129.525522) (xy 197.38848 -129.517902) (xy 197.394322 -129.514346) (xy 197.42132 -129.498499)
			(xy 197.478726 -129.473525) (xy 197.539001 -129.456613) (xy 197.601019 -129.448079) (xy 197.63232 -129.447544)
			(xy 197.67169 -129.449322) (xy 197.67804 -129.450084) (xy 197.708449 -129.453629) (xy 197.768005 -129.467813)
			(xy 197.825139 -129.489809) (xy 197.878831 -129.519225) (xy 197.928122 -129.555535) (xy 197.972133 -129.598093)
			(xy 198.010079 -129.646137) (xy 198.041281 -129.69881) (xy 198.065183 -129.755173) (xy 198.081359 -129.81422)
			(xy 198.089519 -129.874895) (xy 198.090028 -129.905506) (xy 198.090028 -130.769106) (xy 198.089538 -130.799079)
			(xy 198.081715 -130.858511) (xy 198.066204 -130.916415) (xy 198.04327 -130.9718) (xy 198.013306 -131.023719)
			(xy 197.976822 -131.071284) (xy 197.934445 -131.113681) (xy 197.886897 -131.150187) (xy 197.834992 -131.180176)
			(xy 197.779618 -131.203136) (xy 197.721721 -131.218674) (xy 197.662292 -131.226524) (xy 197.63232 -131.227068)
			(xy 197.601023 -131.22651) (xy 197.539016 -131.217944) (xy 197.478751 -131.201023) (xy 197.421347 -131.176062)
			(xy 197.394322 -131.160266) (xy 197.38848 -131.15671) (xy 197.362318 -131.14909) (xy 197.353777 -131.149451)
			(xy 197.337671 -131.155151) (xy 197.330822 -131.160266) (xy 197.319646 -131.172204) (xy 197.31736 -131.17576)
			(xy 197.301075 -131.199673) (xy 197.26245 -131.242744) (xy 197.21776 -131.279484) (xy 197.168031 -131.309047)
			(xy 197.114405 -131.330755) (xy 197.058115 -131.34411) (xy 197.029324 -131.346956) (xy 197.02907 -131.346956)
			(xy 197.019967 -131.348172) (xy 197.003442 -131.356155) (xy 196.990774 -131.369434) (xy 196.98358 -131.386317)
			(xy 196.982842 -131.39547) (xy 196.932456 -132.575808) (xy 199.81672 -132.575808) (xy 199.81672 -131.712208)
			(xy 199.81721 -131.68224) (xy 199.825033 -131.622818) (xy 199.840546 -131.564925) (xy 199.863482 -131.509552)
			(xy 199.893449 -131.457646) (xy 199.929936 -131.410096) (xy 199.972316 -131.367716) (xy 200.019866 -131.331229)
			(xy 200.071772 -131.301262) (xy 200.127145 -131.278326) (xy 200.185038 -131.262813) (xy 200.24446 -131.25499)
			(xy 200.304396 -131.25499) (xy 200.363818 -131.262813) (xy 200.421711 -131.278326) (xy 200.477084 -131.301262)
			(xy 200.52899 -131.331229) (xy 200.57654 -131.367716) (xy 200.61892 -131.410096) (xy 200.647358 -131.447157)
			(xy 241.913309 -131.447157) (xy 241.913309 -131.392643) (xy 241.921067 -131.338685) (xy 241.936426 -131.28638)
			(xy 241.959072 -131.236793) (xy 241.988544 -131.190934) (xy 242.024243 -131.149736) (xy 242.065442 -131.114038)
			(xy 242.111302 -131.084567) (xy 242.160889 -131.061922) (xy 242.213195 -131.046565) (xy 242.267153 -131.038808)
			(xy 242.29441 -131.038346) (xy 242.321781 -131.038795) (xy 242.375961 -131.046615) (xy 242.428465 -131.062108)
			(xy 242.478212 -131.084953) (xy 242.524177 -131.114682) (xy 242.545108 -131.132326) (xy 242.545362 -131.13258)
			(xy 242.552448 -131.138166) (xy 242.569366 -131.144411) (xy 242.578382 -131.144772) (xy 242.645438 -131.144772)
			(xy 242.654457 -131.144439) (xy 242.671375 -131.138175) (xy 242.678458 -131.13258) (xy 242.678458 -131.132326)
			(xy 242.678712 -131.132326) (xy 242.699645 -131.114685) (xy 242.745613 -131.084961) (xy 242.795359 -131.062115)
			(xy 242.847861 -131.046619) (xy 242.902039 -131.03879) (xy 242.956781 -131.03879) (xy 243.010959 -131.046619)
			(xy 243.063461 -131.062115) (xy 243.113207 -131.084961) (xy 243.159175 -131.114685) (xy 243.180108 -131.132326)
			(xy 243.180362 -131.13258) (xy 243.187448 -131.138166) (xy 243.204366 -131.144411) (xy 243.213382 -131.144772)
			(xy 243.280438 -131.144772) (xy 243.289457 -131.144439) (xy 243.306375 -131.138175) (xy 243.313458 -131.13258)
			(xy 243.313458 -131.132326) (xy 243.313712 -131.132326) (xy 243.33467 -131.114719) (xy 243.380635 -131.085001)
			(xy 243.430376 -131.062159) (xy 243.482871 -131.04666) (xy 243.537043 -131.038824) (xy 243.56441 -131.038346)
			(xy 243.591657 -131.038925) (xy 243.645598 -131.046682) (xy 243.697885 -131.062036) (xy 243.747455 -131.084675)
			(xy 243.793298 -131.114138) (xy 243.834482 -131.149825) (xy 243.870168 -131.19101) (xy 243.89963 -131.236854)
			(xy 243.922268 -131.286425) (xy 243.937621 -131.338712) (xy 243.945376 -131.392653) (xy 243.945376 -131.447147)
			(xy 243.937621 -131.501088) (xy 243.922268 -131.553375) (xy 243.89963 -131.602946) (xy 243.870168 -131.64879)
			(xy 243.834482 -131.689975) (xy 243.793298 -131.725662) (xy 243.747455 -131.755125) (xy 243.697885 -131.777764)
			(xy 243.645598 -131.793118) (xy 243.591657 -131.800875) (xy 243.56441 -131.801362) (xy 243.53704 -131.800899)
			(xy 243.48286 -131.793082) (xy 243.430356 -131.777593) (xy 243.38061 -131.75475) (xy 243.334643 -131.725024)
			(xy 243.313712 -131.707382) (xy 243.313458 -131.707128) (xy 243.306365 -131.701551) (xy 243.289453 -131.695301)
			(xy 243.280438 -131.694936) (xy 243.213382 -131.694936) (xy 243.204363 -131.695276) (xy 243.187446 -131.701535)
			(xy 243.180362 -131.707128) (xy 243.180108 -131.707382) (xy 243.159175 -131.725023) (xy 243.113207 -131.754747)
			(xy 243.063461 -131.777593) (xy 243.010959 -131.793089) (xy 242.956781 -131.800918) (xy 242.902039 -131.800918)
			(xy 242.847861 -131.793089) (xy 242.795359 -131.777593) (xy 242.745613 -131.754747) (xy 242.699645 -131.725023)
			(xy 242.678712 -131.707382) (xy 242.678458 -131.707128) (xy 242.671365 -131.701551) (xy 242.654453 -131.695301)
			(xy 242.645438 -131.694936) (xy 242.578382 -131.694936) (xy 242.569363 -131.695276) (xy 242.552446 -131.701535)
			(xy 242.545362 -131.707128) (xy 242.545362 -131.707382) (xy 242.545108 -131.707382) (xy 242.524181 -131.725028)
			(xy 242.478207 -131.754739) (xy 242.428459 -131.777574) (xy 242.375957 -131.793064) (xy 242.32178 -131.800889)
			(xy 242.29441 -131.801362) (xy 242.267153 -131.800992) (xy 242.213195 -131.793235) (xy 242.160889 -131.777878)
			(xy 242.111302 -131.755233) (xy 242.065442 -131.725762) (xy 242.024243 -131.690064) (xy 241.988544 -131.648866)
			(xy 241.959072 -131.603007) (xy 241.936426 -131.55342) (xy 241.921067 -131.501115) (xy 241.913309 -131.447157)
			(xy 200.647358 -131.447157) (xy 200.655407 -131.457646) (xy 200.685374 -131.509552) (xy 200.70831 -131.564925)
			(xy 200.723823 -131.622818) (xy 200.731646 -131.68224) (xy 200.732136 -131.712208) (xy 200.732136 -132.575808)
			(xy 200.731646 -132.605776) (xy 200.723823 -132.665198) (xy 200.70831 -132.723091) (xy 200.685374 -132.778464)
			(xy 200.655407 -132.83037) (xy 200.61892 -132.87792) (xy 200.57654 -132.9203) (xy 200.52899 -132.956787)
			(xy 200.477084 -132.986754) (xy 200.421711 -133.00969) (xy 200.363818 -133.025203) (xy 200.304396 -133.033026)
			(xy 200.24446 -133.033026) (xy 200.185038 -133.025203) (xy 200.127145 -133.00969) (xy 200.071772 -132.986754)
			(xy 200.019866 -132.956787) (xy 199.972316 -132.9203) (xy 199.929936 -132.87792) (xy 199.893449 -132.83037)
			(xy 199.863482 -132.778464) (xy 199.840546 -132.723091) (xy 199.825033 -132.665198) (xy 199.81721 -132.605776)
			(xy 199.81672 -132.575808) (xy 196.932456 -132.575808) (xy 196.855896 -134.369302) (xy 197.174612 -134.369302)
			(xy 197.174612 -133.505702) (xy 197.175102 -133.475734) (xy 197.182925 -133.416312) (xy 197.198438 -133.358419)
			(xy 197.221374 -133.303046) (xy 197.251341 -133.25114) (xy 197.287828 -133.20359) (xy 197.330208 -133.16121)
			(xy 197.377758 -133.124723) (xy 197.429664 -133.094756) (xy 197.485037 -133.07182) (xy 197.54293 -133.056307)
			(xy 197.602352 -133.048484) (xy 197.662288 -133.048484) (xy 197.72171 -133.056307) (xy 197.779603 -133.07182)
			(xy 197.834976 -133.094756) (xy 197.886882 -133.124723) (xy 197.934432 -133.16121) (xy 197.976812 -133.20359)
			(xy 198.013299 -133.25114) (xy 198.043266 -133.303046) (xy 198.066202 -133.358419) (xy 198.081715 -133.416312)
			(xy 198.089538 -133.475734) (xy 198.090028 -133.505702) (xy 198.090028 -133.816344) (xy 237.527844 -133.816344)
			(xy 237.531915 -133.760722) (xy 237.544041 -133.706285) (xy 237.563964 -133.654194) (xy 237.59126 -133.605559)
			(xy 237.625346 -133.561416) (xy 237.665495 -133.522707) (xy 237.710853 -133.490256) (xy 237.760453 -133.464755)
			(xy 237.813237 -133.446748) (xy 237.86808 -133.436618) (xy 237.923814 -133.434581) (xy 237.979251 -133.440681)
			(xy 237.990898 -133.443726) (xy 243.322856 -133.443726) (xy 243.323323 -133.417412) (xy 243.330555 -133.365283)
			(xy 243.344873 -133.314639) (xy 243.366006 -133.26644) (xy 243.393553 -133.221596) (xy 243.426993 -133.180958)
			(xy 243.446046 -133.162802) (xy 243.453441 -133.155274) (xy 243.461971 -133.135999) (xy 243.462556 -133.125464)
			(xy 243.462556 -133.050788) (xy 243.46206 -133.040234) (xy 243.453503 -133.020938) (xy 243.446046 -133.01345)
			(xy 243.426963 -132.995322) (xy 243.39351 -132.954685) (xy 243.365956 -132.909839) (xy 243.344823 -132.861633)
			(xy 243.330511 -132.810981) (xy 243.323292 -132.758844) (xy 243.322856 -132.732526) (xy 243.323342 -132.705275)
			(xy 243.331098 -132.651327) (xy 243.346453 -132.599032) (xy 243.369095 -132.549455) (xy 243.398561 -132.503605)
			(xy 243.434252 -132.462414) (xy 243.475443 -132.426723) (xy 243.521293 -132.397257) (xy 243.57087 -132.374615)
			(xy 243.623165 -132.35926) (xy 243.677113 -132.351504) (xy 243.731615 -132.351504) (xy 243.785563 -132.35926)
			(xy 243.837858 -132.374615) (xy 243.887435 -132.397257) (xy 243.933285 -132.426723) (xy 243.974476 -132.462414)
			(xy 244.010167 -132.503605) (xy 244.039633 -132.549455) (xy 244.062275 -132.599032) (xy 244.07763 -132.651327)
			(xy 244.085386 -132.705275) (xy 244.085872 -132.732526) (xy 244.085431 -132.758841) (xy 244.078192 -132.810971)
			(xy 244.063868 -132.861615) (xy 244.042731 -132.909814) (xy 244.01518 -132.954656) (xy 243.981736 -132.995295)
			(xy 243.962682 -133.01345) (xy 243.955254 -133.020949) (xy 243.946745 -133.040246) (xy 243.946172 -133.050788)
			(xy 243.946172 -133.125464) (xy 243.946716 -133.136012) (xy 243.955242 -133.155307) (xy 243.962682 -133.162802)
			(xy 243.981728 -133.180967) (xy 244.015187 -133.221594) (xy 244.042747 -133.266433) (xy 244.063888 -133.314631)
			(xy 244.078207 -133.365277) (xy 244.085433 -133.41741) (xy 244.085872 -133.443726) (xy 244.085386 -133.470977)
			(xy 244.07763 -133.524925) (xy 244.062275 -133.57722) (xy 244.039633 -133.626797) (xy 244.010167 -133.672647)
			(xy 243.974476 -133.713838) (xy 243.933285 -133.749529) (xy 243.887435 -133.778995) (xy 243.837858 -133.801637)
			(xy 243.785563 -133.816992) (xy 243.731615 -133.824748) (xy 243.677113 -133.824748) (xy 243.623165 -133.816992)
			(xy 243.57087 -133.801637) (xy 243.521293 -133.778995) (xy 243.475443 -133.749529) (xy 243.434252 -133.713838)
			(xy 243.398561 -133.672647) (xy 243.369095 -133.626797) (xy 243.346453 -133.57722) (xy 243.331098 -133.524925)
			(xy 243.323342 -133.470977) (xy 243.322856 -133.443726) (xy 237.990898 -133.443726) (xy 238.033208 -133.454787)
			(xy 238.084537 -133.476599) (xy 238.132143 -133.505653) (xy 238.175011 -133.541328) (xy 238.212228 -133.582865)
			(xy 238.243001 -133.629378) (xy 238.266673 -133.679875) (xy 238.282741 -133.733282) (xy 238.290861 -133.788458)
			(xy 238.29137 -133.816344) (xy 238.290861 -133.84423) (xy 238.282741 -133.899406) (xy 238.266673 -133.952813)
			(xy 238.243001 -134.00331) (xy 238.217136 -134.042404) (xy 238.37595 -134.042404) (xy 238.380021 -133.986782)
			(xy 238.392147 -133.932345) (xy 238.41207 -133.880254) (xy 238.439366 -133.831619) (xy 238.473452 -133.787476)
			(xy 238.513601 -133.748767) (xy 238.558959 -133.716316) (xy 238.608559 -133.690815) (xy 238.661343 -133.672808)
			(xy 238.716186 -133.662678) (xy 238.77192 -133.660641) (xy 238.827357 -133.666741) (xy 238.881314 -133.680847)
			(xy 238.932643 -133.702659) (xy 238.980249 -133.731713) (xy 239.023117 -133.767388) (xy 239.060334 -133.808925)
			(xy 239.091107 -133.855438) (xy 239.114779 -133.905935) (xy 239.130847 -133.959342) (xy 239.138967 -134.014518)
			(xy 239.139476 -134.042404) (xy 239.138967 -134.07029) (xy 239.130847 -134.125466) (xy 239.114779 -134.178873)
			(xy 239.091107 -134.22937) (xy 239.060334 -134.275883) (xy 239.023117 -134.31742) (xy 238.980249 -134.353095)
			(xy 238.932643 -134.382149) (xy 238.881314 -134.403961) (xy 238.827357 -134.418067) (xy 238.77192 -134.424167)
			(xy 238.716186 -134.42213) (xy 238.661343 -134.412) (xy 238.608559 -134.393993) (xy 238.558959 -134.368492)
			(xy 238.513601 -134.336041) (xy 238.473452 -134.297332) (xy 238.439366 -134.253189) (xy 238.41207 -134.204554)
			(xy 238.392147 -134.152463) (xy 238.380021 -134.098026) (xy 238.37595 -134.042404) (xy 238.217136 -134.042404)
			(xy 238.212228 -134.049823) (xy 238.175011 -134.09136) (xy 238.132143 -134.127035) (xy 238.084537 -134.156089)
			(xy 238.033208 -134.177901) (xy 237.979251 -134.192007) (xy 237.923814 -134.198107) (xy 237.86808 -134.19607)
			(xy 237.813237 -134.18594) (xy 237.760453 -134.167933) (xy 237.710853 -134.142432) (xy 237.665495 -134.109981)
			(xy 237.625346 -134.071272) (xy 237.59126 -134.027129) (xy 237.563964 -133.978494) (xy 237.544041 -133.926403)
			(xy 237.531915 -133.871966) (xy 237.527844 -133.816344) (xy 198.090028 -133.816344) (xy 198.090028 -134.369302)
			(xy 198.089538 -134.39927) (xy 198.081715 -134.458692) (xy 198.066202 -134.516585) (xy 198.043266 -134.571958)
			(xy 198.013299 -134.623864) (xy 197.976812 -134.671414) (xy 197.934432 -134.713794) (xy 197.886882 -134.750281)
			(xy 197.839331 -134.777734) (xy 211.442044 -134.777734) (xy 211.446115 -134.722112) (xy 211.458241 -134.667675)
			(xy 211.478164 -134.615584) (xy 211.50546 -134.566949) (xy 211.539546 -134.522806) (xy 211.579695 -134.484097)
			(xy 211.625053 -134.451646) (xy 211.674653 -134.426145) (xy 211.727437 -134.408138) (xy 211.78228 -134.398008)
			(xy 211.838014 -134.395971) (xy 211.893451 -134.402071) (xy 211.947408 -134.416177) (xy 211.998737 -134.437989)
			(xy 212.046343 -134.467043) (xy 212.089211 -134.502718) (xy 212.126428 -134.544255) (xy 212.157201 -134.590768)
			(xy 212.180873 -134.641265) (xy 212.196941 -134.694672) (xy 212.205061 -134.749848) (xy 212.20557 -134.777734)
			(xy 212.205061 -134.80562) (xy 212.204231 -134.811262) (xy 228.099112 -134.811262) (xy 228.099598 -134.784011)
			(xy 228.107354 -134.730063) (xy 228.122709 -134.677768) (xy 228.145351 -134.628191) (xy 228.174817 -134.582341)
			(xy 228.210508 -134.54115) (xy 228.251699 -134.505459) (xy 228.297549 -134.475993) (xy 228.347126 -134.453351)
			(xy 228.399421 -134.437996) (xy 228.453369 -134.43024) (xy 228.507871 -134.43024) (xy 228.561819 -134.437996)
			(xy 228.614114 -134.453351) (xy 228.663691 -134.475993) (xy 228.709541 -134.505459) (xy 228.750732 -134.54115)
			(xy 228.786423 -134.582341) (xy 228.815889 -134.628191) (xy 228.838531 -134.677768) (xy 228.853886 -134.730063)
			(xy 228.861642 -134.784011) (xy 228.862128 -134.811262) (xy 228.861712 -134.837579) (xy 228.854481 -134.889714)
			(xy 228.840151 -134.940359) (xy 228.818993 -134.988553) (xy 228.791411 -135.033381) (xy 228.757927 -135.073991)
			(xy 228.719178 -135.109611) (xy 228.69779 -135.124952) (xy 228.68662 -135.133118) (xy 228.679148 -135.142051)
			(xy 241.56187 -135.142051) (xy 241.56187 -135.087549) (xy 241.569626 -135.033603) (xy 241.58498 -134.981309)
			(xy 241.60762 -134.931732) (xy 241.637084 -134.885882) (xy 241.672774 -134.844692) (xy 241.713962 -134.809)
			(xy 241.75981 -134.779532) (xy 241.809385 -134.756889) (xy 241.861677 -134.741531) (xy 241.915623 -134.733772)
			(xy 241.942874 -134.733284) (xy 241.971792 -134.733789) (xy 242.028965 -134.742516) (xy 242.084166 -134.759775)
			(xy 242.136128 -134.785169) (xy 242.183661 -134.818116) (xy 242.225676 -134.857862) (xy 242.243864 -134.88035)
			(xy 242.251656 -134.889338) (xy 242.273122 -134.899526) (xy 242.285012 -134.899908) (xy 242.378484 -134.897876)
			(xy 242.39982 -134.8867) (xy 242.406678 -134.876794) (xy 242.422076 -134.855884) (xy 242.457654 -134.818057)
			(xy 242.498033 -134.785405) (xy 242.542468 -134.75853) (xy 242.590136 -134.73793) (xy 242.640158 -134.723985)
			(xy 242.691609 -134.716952) (xy 242.717574 -134.71652) (xy 242.744944 -134.716996) (xy 242.799123 -134.724811)
			(xy 242.851626 -134.740297) (xy 242.901373 -134.763137) (xy 242.94734 -134.79286) (xy 242.968272 -134.8105)
			(xy 242.968526 -134.810754) (xy 242.975625 -134.816322) (xy 242.992532 -134.822579) (xy 243.001546 -134.822946)
			(xy 243.068602 -134.822946) (xy 243.07762 -134.822601) (xy 243.094538 -134.816346) (xy 243.101622 -134.810754)
			(xy 243.101622 -134.8105) (xy 243.101876 -134.8105) (xy 243.122809 -134.792859) (xy 243.168777 -134.763135)
			(xy 243.218523 -134.740289) (xy 243.271025 -134.724793) (xy 243.325203 -134.716964) (xy 243.379945 -134.716964)
			(xy 243.434123 -134.724793) (xy 243.486625 -134.740289) (xy 243.536371 -134.763135) (xy 243.582339 -134.792859)
			(xy 243.603272 -134.8105) (xy 243.603526 -134.810754) (xy 243.610625 -134.816322) (xy 243.627532 -134.822579)
			(xy 243.636546 -134.822946) (xy 243.703602 -134.822946) (xy 243.71262 -134.822601) (xy 243.729538 -134.816346)
			(xy 243.736622 -134.810754) (xy 243.73713 -134.8105) (xy 243.749868 -134.79956) (xy 243.776957 -134.779716)
			(xy 243.791232 -134.770876) (xy 243.800122 -134.765542) (xy 243.812314 -134.748524) (xy 243.832634 -134.655306)
			(xy 243.828316 -134.634732) (xy 243.822474 -134.626096) (xy 243.806467 -134.602037) (xy 243.781127 -134.550103)
			(xy 243.763903 -134.494944) (xy 243.75519 -134.437819) (xy 243.754656 -134.408926) (xy 243.755142 -134.381675)
			(xy 243.762898 -134.327727) (xy 243.778253 -134.275432) (xy 243.800895 -134.225855) (xy 243.830361 -134.180005)
			(xy 243.866052 -134.138814) (xy 243.907243 -134.103123) (xy 243.953093 -134.073657) (xy 244.00267 -134.051015)
			(xy 244.054965 -134.03566) (xy 244.108913 -134.027904) (xy 244.163415 -134.027904) (xy 244.217363 -134.03566)
			(xy 244.269658 -134.051015) (xy 244.319235 -134.073657) (xy 244.365085 -134.103123) (xy 244.406276 -134.138814)
			(xy 244.441967 -134.180005) (xy 244.471433 -134.225855) (xy 244.494075 -134.275432) (xy 244.50943 -134.327727)
			(xy 244.517186 -134.381675) (xy 244.517672 -134.408926) (xy 244.51722 -134.437019) (xy 244.508988 -134.492599)
			(xy 244.492691 -134.546371) (xy 244.468682 -134.597169) (xy 244.43748 -134.643895) (xy 244.399761 -134.685539)
			(xy 244.35634 -134.721198) (xy 244.332506 -134.736078) (xy 244.323616 -134.741412) (xy 244.311424 -134.75843)
			(xy 244.291104 -134.851648) (xy 244.295422 -134.872222) (xy 244.301264 -134.880858) (xy 244.317244 -134.904934)
			(xy 244.342592 -134.956861) (xy 244.359824 -135.012015) (xy 244.368545 -135.069136) (xy 244.369082 -135.098028)
			(xy 244.368648 -135.125281) (xy 244.360887 -135.179232) (xy 244.345527 -135.231529) (xy 244.322881 -135.281108)
			(xy 244.293409 -135.32696) (xy 244.257712 -135.368151) (xy 244.216517 -135.403842) (xy 244.170661 -135.433307)
			(xy 244.121079 -135.455946) (xy 244.068779 -135.471299) (xy 244.014827 -135.479052) (xy 243.987574 -135.479536)
			(xy 243.960202 -135.479101) (xy 243.906021 -135.471278) (xy 243.853517 -135.455782) (xy 243.803771 -135.432933)
			(xy 243.757806 -135.403201) (xy 243.736876 -135.385556) (xy 243.736622 -135.385302) (xy 243.729533 -135.379719)
			(xy 243.712618 -135.37347) (xy 243.703602 -135.37311) (xy 243.636546 -135.37311) (xy 243.627531 -135.373487)
			(xy 243.610614 -135.379721) (xy 243.603526 -135.385302) (xy 243.603526 -135.385556) (xy 243.603272 -135.385556)
			(xy 243.582339 -135.403197) (xy 243.536371 -135.432921) (xy 243.486625 -135.455767) (xy 243.434123 -135.471263)
			(xy 243.379945 -135.479092) (xy 243.325203 -135.479092) (xy 243.271025 -135.471263) (xy 243.218523 -135.455767)
			(xy 243.168777 -135.432921) (xy 243.122809 -135.403197) (xy 243.101876 -135.385556) (xy 243.101622 -135.385302)
			(xy 243.094533 -135.379719) (xy 243.077618 -135.37347) (xy 243.068602 -135.37311) (xy 243.001546 -135.37311)
			(xy 242.992531 -135.373487) (xy 242.975614 -135.379721) (xy 242.968526 -135.385302) (xy 242.968526 -135.385556)
			(xy 242.968272 -135.385556) (xy 242.947318 -135.403168) (xy 242.901352 -135.432885) (xy 242.85161 -135.455727)
			(xy 242.799114 -135.471225) (xy 242.744942 -135.479059) (xy 242.717574 -135.479536) (xy 242.688658 -135.478989)
			(xy 242.631487 -135.470269) (xy 242.576288 -135.453018) (xy 242.524325 -135.427632) (xy 242.476791 -135.394693)
			(xy 242.434774 -135.354954) (xy 242.416584 -135.33247) (xy 242.408767 -135.323508) (xy 242.38732 -135.313305)
			(xy 242.375436 -135.312912) (xy 242.281964 -135.314944) (xy 242.260628 -135.32612) (xy 242.25377 -135.336026)
			(xy 242.238348 -135.356918) (xy 242.202774 -135.394744) (xy 242.162398 -135.427397) (xy 242.117968 -135.454274)
			(xy 242.070303 -135.474877) (xy 242.020285 -135.488827) (xy 241.968837 -135.495865) (xy 241.942874 -135.4963)
			(xy 241.915623 -135.495828) (xy 241.861677 -135.488069) (xy 241.809385 -135.472711) (xy 241.75981 -135.450068)
			(xy 241.713962 -135.4206) (xy 241.672774 -135.384908) (xy 241.637084 -135.343718) (xy 241.60762 -135.297868)
			(xy 241.58498 -135.248291) (xy 241.569626 -135.195997) (xy 241.56187 -135.142051) (xy 228.679148 -135.142051)
			(xy 228.668872 -135.154336) (xy 228.657474 -135.17954) (xy 228.653263 -135.206879) (xy 228.65655 -135.234345)
			(xy 228.667091 -135.25992) (xy 228.684114 -135.281723) (xy 228.706367 -135.298155) (xy 228.719126 -135.303514)
			(xy 228.745788 -135.314237) (xy 228.795756 -135.342623) (xy 228.840898 -135.378186) (xy 228.880192 -135.420121)
			(xy 228.912748 -135.467477) (xy 228.937827 -135.519184) (xy 228.954863 -135.574068) (xy 228.96347 -135.630888)
			(xy 228.963982 -135.659622) (xy 228.963496 -135.686873) (xy 228.963105 -135.689594) (xy 239.483136 -135.689594)
			(xy 239.487207 -135.633972) (xy 239.499333 -135.579535) (xy 239.519256 -135.527444) (xy 239.546552 -135.478809)
			(xy 239.580638 -135.434666) (xy 239.620787 -135.395957) (xy 239.666145 -135.363506) (xy 239.715745 -135.338005)
			(xy 239.768529 -135.319998) (xy 239.823372 -135.309868) (xy 239.879106 -135.307831) (xy 239.934543 -135.313931)
			(xy 239.9885 -135.328037) (xy 240.039829 -135.349849) (xy 240.087435 -135.378903) (xy 240.130303 -135.414578)
			(xy 240.16752 -135.456115) (xy 240.198293 -135.502628) (xy 240.221965 -135.553125) (xy 240.238033 -135.606532)
			(xy 240.246153 -135.661708) (xy 240.246662 -135.689594) (xy 240.246153 -135.71748) (xy 240.238033 -135.772656)
			(xy 240.221965 -135.826063) (xy 240.202828 -135.866886) (xy 240.639852 -135.866886) (xy 240.643923 -135.811264)
			(xy 240.656049 -135.756827) (xy 240.675972 -135.704736) (xy 240.703268 -135.656101) (xy 240.737354 -135.611958)
			(xy 240.777503 -135.573249) (xy 240.822861 -135.540798) (xy 240.872461 -135.515297) (xy 240.925245 -135.49729)
			(xy 240.980088 -135.48716) (xy 241.035822 -135.485123) (xy 241.091259 -135.491223) (xy 241.145216 -135.505329)
			(xy 241.196545 -135.527141) (xy 241.244151 -135.556195) (xy 241.287019 -135.59187) (xy 241.324236 -135.633407)
			(xy 241.355009 -135.67992) (xy 241.378681 -135.730417) (xy 241.394749 -135.783824) (xy 241.402869 -135.839)
			(xy 241.403378 -135.866886) (xy 241.402869 -135.894772) (xy 241.394749 -135.949948) (xy 241.378681 -136.003355)
			(xy 241.355009 -136.053852) (xy 241.324236 -136.100365) (xy 241.287019 -136.141902) (xy 241.244151 -136.177577)
			(xy 241.196545 -136.206631) (xy 241.145216 -136.228443) (xy 241.091259 -136.242549) (xy 241.035822 -136.248649)
			(xy 240.980088 -136.246612) (xy 240.925245 -136.236482) (xy 240.872461 -136.218475) (xy 240.822861 -136.192974)
			(xy 240.777503 -136.160523) (xy 240.737354 -136.121814) (xy 240.703268 -136.077671) (xy 240.675972 -136.029036)
			(xy 240.656049 -135.976945) (xy 240.643923 -135.922508) (xy 240.639852 -135.866886) (xy 240.202828 -135.866886)
			(xy 240.198293 -135.87656) (xy 240.16752 -135.923073) (xy 240.130303 -135.96461) (xy 240.087435 -136.000285)
			(xy 240.039829 -136.029339) (xy 239.9885 -136.051151) (xy 239.934543 -136.065257) (xy 239.879106 -136.071357)
			(xy 239.823372 -136.06932) (xy 239.768529 -136.05919) (xy 239.715745 -136.041183) (xy 239.666145 -136.015682)
			(xy 239.620787 -135.983231) (xy 239.580638 -135.944522) (xy 239.546552 -135.900379) (xy 239.519256 -135.851744)
			(xy 239.499333 -135.799653) (xy 239.487207 -135.745216) (xy 239.483136 -135.689594) (xy 228.963105 -135.689594)
			(xy 228.95574 -135.740821) (xy 228.940385 -135.793116) (xy 228.917743 -135.842693) (xy 228.888277 -135.888543)
			(xy 228.852586 -135.929734) (xy 228.811395 -135.965425) (xy 228.765545 -135.994891) (xy 228.715968 -136.017533)
			(xy 228.663673 -136.032888) (xy 228.609725 -136.040644) (xy 228.555223 -136.040644) (xy 228.501275 -136.032888)
			(xy 228.44898 -136.017533) (xy 228.399403 -135.994891) (xy 228.353553 -135.965425) (xy 228.312362 -135.929734)
			(xy 228.276671 -135.888543) (xy 228.247205 -135.842693) (xy 228.224563 -135.793116) (xy 228.209208 -135.740821)
			(xy 228.201452 -135.686873) (xy 228.200966 -135.659622) (xy 228.201372 -135.633305) (xy 228.208605 -135.58117)
			(xy 228.222937 -135.530524) (xy 228.244096 -135.48233) (xy 228.27168 -135.437502) (xy 228.305165 -135.396893)
			(xy 228.343916 -135.361273) (xy 228.365304 -135.345932) (xy 228.376388 -135.337656) (xy 228.394134 -135.316461)
			(xy 228.405536 -135.291279) (xy 228.409755 -135.263959) (xy 228.406481 -135.236511) (xy 228.395955 -135.21095)
			(xy 228.37895 -135.189155) (xy 228.356717 -135.172729) (xy 228.343968 -135.16737) (xy 228.317335 -135.15658)
			(xy 228.26737 -135.128202) (xy 228.222229 -135.092648) (xy 228.182935 -135.050723) (xy 228.150376 -135.003376)
			(xy 228.125291 -134.951679) (xy 228.108247 -134.896804) (xy 228.099631 -134.839993) (xy 228.099112 -134.811262)
			(xy 212.204231 -134.811262) (xy 212.196941 -134.860796) (xy 212.180873 -134.914203) (xy 212.157201 -134.9647)
			(xy 212.126428 -135.011213) (xy 212.089211 -135.05275) (xy 212.046343 -135.088425) (xy 211.998737 -135.117479)
			(xy 211.947408 -135.139291) (xy 211.893451 -135.153397) (xy 211.838014 -135.159497) (xy 211.78228 -135.15746)
			(xy 211.727437 -135.14733) (xy 211.674653 -135.129323) (xy 211.625053 -135.103822) (xy 211.579695 -135.071371)
			(xy 211.539546 -135.032662) (xy 211.50546 -134.988519) (xy 211.478164 -134.939884) (xy 211.458241 -134.887793)
			(xy 211.446115 -134.833356) (xy 211.442044 -134.777734) (xy 197.839331 -134.777734) (xy 197.834976 -134.780248)
			(xy 197.779603 -134.803184) (xy 197.72171 -134.818697) (xy 197.662288 -134.82652) (xy 197.602352 -134.82652)
			(xy 197.54293 -134.818697) (xy 197.485037 -134.803184) (xy 197.429664 -134.780248) (xy 197.377758 -134.750281)
			(xy 197.330208 -134.713794) (xy 197.287828 -134.671414) (xy 197.251341 -134.623864) (xy 197.221374 -134.571958)
			(xy 197.198438 -134.516585) (xy 197.182925 -134.458692) (xy 197.175102 -134.39927) (xy 197.174612 -134.369302)
			(xy 196.855896 -134.369302) (xy 196.795644 -135.78078) (xy 196.795644 -136.17575) (xy 199.81672 -136.17575)
			(xy 199.81672 -135.31215) (xy 199.81721 -135.282182) (xy 199.825033 -135.22276) (xy 199.840546 -135.164867)
			(xy 199.863482 -135.109494) (xy 199.893449 -135.057588) (xy 199.929936 -135.010038) (xy 199.972316 -134.967658)
			(xy 200.019866 -134.931171) (xy 200.071772 -134.901204) (xy 200.127145 -134.878268) (xy 200.185038 -134.862755)
			(xy 200.24446 -134.854932) (xy 200.304396 -134.854932) (xy 200.363818 -134.862755) (xy 200.421711 -134.878268)
			(xy 200.477084 -134.901204) (xy 200.52899 -134.931171) (xy 200.57654 -134.967658) (xy 200.61892 -135.010038)
			(xy 200.655407 -135.057588) (xy 200.685374 -135.109494) (xy 200.70831 -135.164867) (xy 200.723823 -135.22276)
			(xy 200.731646 -135.282182) (xy 200.732136 -135.31215) (xy 200.732136 -135.4074) (xy 209.750406 -135.4074)
			(xy 209.750892 -135.380149) (xy 209.758648 -135.326201) (xy 209.774003 -135.273906) (xy 209.796645 -135.224329)
			(xy 209.826111 -135.178479) (xy 209.861802 -135.137288) (xy 209.902993 -135.101597) (xy 209.948843 -135.072131)
			(xy 209.99842 -135.049489) (xy 210.050715 -135.034134) (xy 210.104663 -135.026378) (xy 210.159165 -135.026378)
			(xy 210.213113 -135.034134) (xy 210.265408 -135.049489) (xy 210.314985 -135.072131) (xy 210.360835 -135.101597)
			(xy 210.402026 -135.137288) (xy 210.437717 -135.178479) (xy 210.467183 -135.224329) (xy 210.489825 -135.273906)
			(xy 210.50518 -135.326201) (xy 210.512936 -135.380149) (xy 210.513422 -135.4074) (xy 210.512735 -135.440197)
			(xy 210.5015 -135.504822) (xy 210.49107 -135.535924) (xy 210.488341 -135.544914) (xy 210.488861 -135.563676)
			(xy 210.492086 -135.5725) (xy 210.522058 -135.644636) (xy 210.534758 -135.658098) (xy 210.537901 -135.659622)
			(xy 224.644456 -135.659622) (xy 224.648527 -135.604) (xy 224.660653 -135.549563) (xy 224.680576 -135.497472)
			(xy 224.707872 -135.448837) (xy 224.741958 -135.404694) (xy 224.782107 -135.365985) (xy 224.827465 -135.333534)
			(xy 224.877065 -135.308033) (xy 224.929849 -135.290026) (xy 224.984692 -135.279896) (xy 225.040426 -135.277859)
			(xy 225.095863 -135.283959) (xy 225.14982 -135.298065) (xy 225.201149 -135.319877) (xy 225.248755 -135.348931)
			(xy 225.291623 -135.384606) (xy 225.32884 -135.426143) (xy 225.359613 -135.472656) (xy 225.383285 -135.523153)
			(xy 225.399353 -135.57656) (xy 225.407473 -135.631736) (xy 225.407982 -135.659622) (xy 226.422456 -135.659622)
			(xy 226.426527 -135.604) (xy 226.438653 -135.549563) (xy 226.458576 -135.497472) (xy 226.485872 -135.448837)
			(xy 226.519958 -135.404694) (xy 226.560107 -135.365985) (xy 226.605465 -135.333534) (xy 226.655065 -135.308033)
			(xy 226.707849 -135.290026) (xy 226.762692 -135.279896) (xy 226.818426 -135.277859) (xy 226.873863 -135.283959)
			(xy 226.92782 -135.298065) (xy 226.979149 -135.319877) (xy 227.026755 -135.348931) (xy 227.069623 -135.384606)
			(xy 227.10684 -135.426143) (xy 227.137613 -135.472656) (xy 227.161285 -135.523153) (xy 227.177353 -135.57656)
			(xy 227.185473 -135.631736) (xy 227.185982 -135.659622) (xy 227.185473 -135.687508) (xy 227.177353 -135.742684)
			(xy 227.161285 -135.796091) (xy 227.137613 -135.846588) (xy 227.10684 -135.893101) (xy 227.069623 -135.934638)
			(xy 227.026755 -135.970313) (xy 226.979149 -135.999367) (xy 226.92782 -136.021179) (xy 226.873863 -136.035285)
			(xy 226.818426 -136.041385) (xy 226.762692 -136.039348) (xy 226.707849 -136.029218) (xy 226.655065 -136.011211)
			(xy 226.605465 -135.98571) (xy 226.560107 -135.953259) (xy 226.519958 -135.91455) (xy 226.485872 -135.870407)
			(xy 226.458576 -135.821772) (xy 226.438653 -135.769681) (xy 226.426527 -135.715244) (xy 226.422456 -135.659622)
			(xy 225.407982 -135.659622) (xy 225.407473 -135.687508) (xy 225.399353 -135.742684) (xy 225.383285 -135.796091)
			(xy 225.359613 -135.846588) (xy 225.32884 -135.893101) (xy 225.291623 -135.934638) (xy 225.248755 -135.970313)
			(xy 225.201149 -135.999367) (xy 225.14982 -136.021179) (xy 225.095863 -136.035285) (xy 225.040426 -136.041385)
			(xy 224.984692 -136.039348) (xy 224.929849 -136.029218) (xy 224.877065 -136.011211) (xy 224.827465 -135.98571)
			(xy 224.782107 -135.953259) (xy 224.741958 -135.91455) (xy 224.707872 -135.870407) (xy 224.680576 -135.821772)
			(xy 224.660653 -135.769681) (xy 224.648527 -135.715244) (xy 224.644456 -135.659622) (xy 210.537901 -135.659622)
			(xy 210.54314 -135.662162) (xy 210.543648 -135.662162) (xy 210.567833 -135.674112) (xy 210.612907 -135.703744)
			(xy 210.65336 -135.73943) (xy 210.688383 -135.780456) (xy 210.71728 -135.826006) (xy 210.739474 -135.875172)
			(xy 210.754523 -135.926973) (xy 210.762127 -135.980377) (xy 210.762596 -136.007348) (xy 210.76211 -136.034599)
			(xy 210.754354 -136.088547) (xy 210.738999 -136.140842) (xy 210.727696 -136.16559) (xy 211.52561 -136.16559)
			(xy 211.529681 -136.109968) (xy 211.541807 -136.055531) (xy 211.56173 -136.00344) (xy 211.589026 -135.954805)
			(xy 211.623112 -135.910662) (xy 211.663261 -135.871953) (xy 211.708619 -135.839502) (xy 211.758219 -135.814001)
			(xy 211.811003 -135.795994) (xy 211.865846 -135.785864) (xy 211.92158 -135.783827) (xy 211.977017 -135.789927)
			(xy 212.030974 -135.804033) (xy 212.082303 -135.825845) (xy 212.129909 -135.854899) (xy 212.172777 -135.890574)
			(xy 212.209994 -135.932111) (xy 212.240767 -135.978624) (xy 212.264439 -136.029121) (xy 212.280507 -136.082528)
			(xy 212.288627 -136.137704) (xy 212.289136 -136.16559) (xy 212.288627 -136.193476) (xy 212.280507 -136.248652)
			(xy 212.264439 -136.302059) (xy 212.240767 -136.352556) (xy 212.209994 -136.399069) (xy 212.172777 -136.440606)
			(xy 212.129909 -136.476281) (xy 212.082303 -136.505335) (xy 212.030974 -136.527147) (xy 211.977017 -136.541253)
			(xy 211.92158 -136.547353) (xy 211.865846 -136.545316) (xy 211.811003 -136.535186) (xy 211.758219 -136.517179)
			(xy 211.708619 -136.491678) (xy 211.663261 -136.459227) (xy 211.623112 -136.420518) (xy 211.589026 -136.376375)
			(xy 211.56173 -136.32774) (xy 211.541807 -136.275649) (xy 211.529681 -136.221212) (xy 211.52561 -136.16559)
			(xy 210.727696 -136.16559) (xy 210.716357 -136.190419) (xy 210.686891 -136.236269) (xy 210.6512 -136.27746)
			(xy 210.610009 -136.313151) (xy 210.564159 -136.342617) (xy 210.514582 -136.365259) (xy 210.462287 -136.380614)
			(xy 210.408339 -136.38837) (xy 210.353837 -136.38837) (xy 210.299889 -136.380614) (xy 210.247594 -136.365259)
			(xy 210.198017 -136.342617) (xy 210.152167 -136.313151) (xy 210.110976 -136.27746) (xy 210.075285 -136.236269)
			(xy 210.045819 -136.190419) (xy 210.023177 -136.140842) (xy 210.007822 -136.088547) (xy 210.000066 -136.034599)
			(xy 209.99958 -136.007348) (xy 210.000253 -135.97455) (xy 210.011498 -135.909925) (xy 210.021932 -135.878824)
			(xy 210.024688 -135.869841) (xy 210.02415 -135.851072) (xy 210.020916 -135.842248) (xy 209.990944 -135.770112)
			(xy 209.978244 -135.75665) (xy 209.969862 -135.752586) (xy 209.969354 -135.752586) (xy 209.945148 -135.740676)
			(xy 209.900073 -135.711038) (xy 209.859621 -135.675347) (xy 209.824598 -135.634315) (xy 209.795704 -135.588759)
			(xy 209.773514 -135.539588) (xy 209.75847 -135.487782) (xy 209.750872 -135.434373) (xy 209.750406 -135.4074)
			(xy 200.732136 -135.4074) (xy 200.732136 -136.17575) (xy 200.731646 -136.205718) (xy 200.723823 -136.26514)
			(xy 200.70831 -136.323033) (xy 200.685374 -136.378406) (xy 200.655407 -136.430312) (xy 200.61892 -136.477862)
			(xy 200.57654 -136.520242) (xy 200.52899 -136.556729) (xy 200.477084 -136.586696) (xy 200.421711 -136.609632)
			(xy 200.363818 -136.625145) (xy 200.304396 -136.632968) (xy 200.24446 -136.632968) (xy 200.185038 -136.625145)
			(xy 200.127145 -136.609632) (xy 200.071772 -136.586696) (xy 200.019866 -136.556729) (xy 199.972316 -136.520242)
			(xy 199.929936 -136.477862) (xy 199.893449 -136.430312) (xy 199.863482 -136.378406) (xy 199.840546 -136.323033)
			(xy 199.825033 -136.26514) (xy 199.81721 -136.205718) (xy 199.81672 -136.17575) (xy 196.795644 -136.17575)
			(xy 196.795644 -136.524746) (xy 196.795898 -136.528302) (xy 196.797071 -136.538958) (xy 196.807062 -136.557904)
			(xy 196.815202 -136.564878) (xy 196.881496 -136.6139) (xy 196.88645 -136.617415) (xy 196.897627 -136.622162)
			(xy 196.903594 -136.623298) (xy 196.915278 -136.625076) (xy 196.926708 -136.62152) (xy 196.954154 -136.613557)
			(xy 197.010657 -136.605009) (xy 197.03923 -136.604502) (xy 197.039484 -136.604502) (xy 197.066737 -136.604964)
			(xy 197.120688 -136.612719) (xy 197.172987 -136.628073) (xy 197.222567 -136.650714) (xy 197.268421 -136.680181)
			(xy 197.309615 -136.715874) (xy 197.345309 -136.757066) (xy 197.374778 -136.802919) (xy 197.397421 -136.852498)
			(xy 197.412777 -136.904796) (xy 197.420401 -136.957816) (xy 223.695512 -136.957816) (xy 223.699583 -136.902194)
			(xy 223.711709 -136.847757) (xy 223.731632 -136.795666) (xy 223.758928 -136.747031) (xy 223.793014 -136.702888)
			(xy 223.833163 -136.664179) (xy 223.878521 -136.631728) (xy 223.928121 -136.606227) (xy 223.980905 -136.58822)
			(xy 224.035748 -136.57809) (xy 224.091482 -136.576053) (xy 224.146919 -136.582153) (xy 224.200876 -136.596259)
			(xy 224.252205 -136.618071) (xy 224.299811 -136.647125) (xy 224.342679 -136.6828) (xy 224.379896 -136.724337)
			(xy 224.410669 -136.77085) (xy 224.434341 -136.821347) (xy 224.450409 -136.874754) (xy 224.458529 -136.92993)
			(xy 224.459038 -136.957816) (xy 224.458529 -136.985702) (xy 224.450409 -137.040878) (xy 224.434341 -137.094285)
			(xy 224.410669 -137.144782) (xy 224.379896 -137.191295) (xy 224.342679 -137.232832) (xy 224.299811 -137.268507)
			(xy 224.252205 -137.297561) (xy 224.200876 -137.319373) (xy 224.146919 -137.333479) (xy 224.091482 -137.339579)
			(xy 224.035748 -137.337542) (xy 223.980905 -137.327412) (xy 223.928121 -137.309405) (xy 223.878521 -137.283904)
			(xy 223.833163 -137.251453) (xy 223.793014 -137.212744) (xy 223.758928 -137.168601) (xy 223.731632 -137.119966)
			(xy 223.711709 -137.067875) (xy 223.699583 -137.013438) (xy 223.695512 -136.957816) (xy 197.420401 -136.957816)
			(xy 197.420535 -136.958747) (xy 197.420535 -137.013253) (xy 197.412777 -137.067204) (xy 197.397421 -137.119502)
			(xy 197.374778 -137.169081) (xy 197.345309 -137.214934) (xy 197.309615 -137.256126) (xy 197.268421 -137.291819)
			(xy 197.222567 -137.321286) (xy 197.172987 -137.343927) (xy 197.120688 -137.359281) (xy 197.066737 -137.367036)
			(xy 197.039484 -137.367518) (xy 197.038976 -137.367518) (xy 197.010541 -137.367016) (xy 196.954297 -137.358604)
			(xy 196.926962 -137.350754) (xy 196.915532 -137.347198) (xy 196.891656 -137.351008) (xy 196.816218 -137.406888)
			(xy 196.807002 -137.414504) (xy 196.796286 -137.435841) (xy 196.795644 -137.447782) (xy 196.795644 -137.44829)
			(xy 240.54511 -137.44829) (xy 240.549181 -137.392668) (xy 240.561307 -137.338231) (xy 240.58123 -137.28614)
			(xy 240.608526 -137.237505) (xy 240.642612 -137.193362) (xy 240.682761 -137.154653) (xy 240.728119 -137.122202)
			(xy 240.777719 -137.096701) (xy 240.830503 -137.078694) (xy 240.885346 -137.068564) (xy 240.94108 -137.066527)
			(xy 240.996517 -137.072627) (xy 241.050474 -137.086733) (xy 241.101803 -137.108545) (xy 241.149409 -137.137599)
			(xy 241.192277 -137.173274) (xy 241.229494 -137.214811) (xy 241.260267 -137.261324) (xy 241.267302 -137.276332)
			(xy 245.24716 -137.276332) (xy 245.247563 -137.250016) (xy 245.254808 -137.197884) (xy 245.269139 -137.147239)
			(xy 245.290283 -137.09904) (xy 245.317842 -137.054198) (xy 245.351292 -137.013562) (xy 245.37035 -136.995408)
			(xy 245.377743 -136.987879) (xy 245.386274 -136.968605) (xy 245.38686 -136.95807) (xy 245.38686 -136.883394)
			(xy 245.386359 -136.872841) (xy 245.377805 -136.853545) (xy 245.37035 -136.846056) (xy 245.351271 -136.827925)
			(xy 245.317818 -136.787289) (xy 245.290263 -136.742443) (xy 245.269129 -136.694238) (xy 245.254816 -136.643586)
			(xy 245.247596 -136.591449) (xy 245.24716 -136.565132) (xy 245.247646 -136.537881) (xy 245.255402 -136.483933)
			(xy 245.270757 -136.431638) (xy 245.293399 -136.382061) (xy 245.322865 -136.336211) (xy 245.358556 -136.29502)
			(xy 245.399747 -136.259329) (xy 245.445597 -136.229863) (xy 245.495174 -136.207221) (xy 245.547469 -136.191866)
			(xy 245.601417 -136.18411) (xy 245.655919 -136.18411) (xy 245.709867 -136.191866) (xy 245.762162 -136.207221)
			(xy 245.811739 -136.229863) (xy 245.857589 -136.259329) (xy 245.89878 -136.29502) (xy 245.934471 -136.336211)
			(xy 245.963937 -136.382061) (xy 245.986579 -136.431638) (xy 246.001934 -136.483933) (xy 246.00969 -136.537881)
			(xy 246.010176 -136.565132) (xy 246.009738 -136.591447) (xy 246.002498 -136.643577) (xy 245.988174 -136.694221)
			(xy 245.967036 -136.74242) (xy 245.939484 -136.787262) (xy 245.90604 -136.827901) (xy 245.886986 -136.846056)
			(xy 245.8796 -136.85359) (xy 245.871067 -136.872861) (xy 245.870476 -136.883394) (xy 245.870476 -136.95807)
			(xy 245.871015 -136.968618) (xy 245.879544 -136.987913) (xy 245.886986 -136.995408) (xy 245.906036 -137.013569)
			(xy 245.939494 -137.054198) (xy 245.967054 -137.099036) (xy 245.988194 -137.147236) (xy 246.002512 -137.197883)
			(xy 246.009737 -137.250016) (xy 246.010176 -137.276332) (xy 246.00969 -137.303583) (xy 246.001934 -137.357531)
			(xy 245.986579 -137.409826) (xy 245.963937 -137.459403) (xy 245.934471 -137.505253) (xy 245.89878 -137.546444)
			(xy 245.857589 -137.582135) (xy 245.811739 -137.611601) (xy 245.762162 -137.634243) (xy 245.709867 -137.649598)
			(xy 245.655919 -137.657354) (xy 245.601417 -137.657354) (xy 245.547469 -137.649598) (xy 245.495174 -137.634243)
			(xy 245.445597 -137.611601) (xy 245.399747 -137.582135) (xy 245.358556 -137.546444) (xy 245.322865 -137.505253)
			(xy 245.293399 -137.459403) (xy 245.270757 -137.409826) (xy 245.255402 -137.357531) (xy 245.247646 -137.303583)
			(xy 245.24716 -137.276332) (xy 241.267302 -137.276332) (xy 241.283939 -137.311821) (xy 241.300007 -137.365228)
			(xy 241.308127 -137.420404) (xy 241.308636 -137.44829) (xy 241.308127 -137.476176) (xy 241.300007 -137.531352)
			(xy 241.283939 -137.584759) (xy 241.260267 -137.635256) (xy 241.229494 -137.681769) (xy 241.192277 -137.723306)
			(xy 241.18823 -137.726674) (xy 246.187722 -137.726674) (xy 246.188167 -137.699303) (xy 246.195989 -137.645123)
			(xy 246.211483 -137.592619) (xy 246.234329 -137.542873) (xy 246.264059 -137.496907) (xy 246.281702 -137.475976)
			(xy 246.281956 -137.475722) (xy 246.287546 -137.468638) (xy 246.293789 -137.451719) (xy 246.294148 -137.442702)
			(xy 246.294148 -137.375646) (xy 246.29378 -137.36663) (xy 246.287541 -137.349712) (xy 246.281956 -137.342626)
			(xy 246.281702 -137.342626) (xy 246.281702 -137.342372) (xy 246.264084 -137.321423) (xy 246.234369 -137.275455)
			(xy 246.211529 -137.225712) (xy 246.196033 -137.173215) (xy 246.188199 -137.119042) (xy 246.187722 -137.091674)
			(xy 246.188208 -137.064423) (xy 246.195964 -137.010475) (xy 246.211319 -136.95818) (xy 246.233961 -136.908603)
			(xy 246.263427 -136.862753) (xy 246.299118 -136.821562) (xy 246.340309 -136.785871) (xy 246.386159 -136.756405)
			(xy 246.435736 -136.733763) (xy 246.488031 -136.718408) (xy 246.541979 -136.710652) (xy 246.596481 -136.710652)
			(xy 246.650429 -136.718408) (xy 246.702724 -136.733763) (xy 246.752301 -136.756405) (xy 246.798151 -136.785871)
			(xy 246.839342 -136.821562) (xy 246.875033 -136.862753) (xy 246.904499 -136.908603) (xy 246.927141 -136.95818)
			(xy 246.942496 -137.010475) (xy 246.950252 -137.064423) (xy 246.950738 -137.091674) (xy 246.950272 -137.119044)
			(xy 246.942456 -137.173224) (xy 246.926968 -137.225728) (xy 246.904126 -137.275475) (xy 246.8744 -137.321441)
			(xy 246.856758 -137.342372) (xy 246.856504 -137.342626) (xy 246.850943 -137.34973) (xy 246.844681 -137.366633)
			(xy 246.844312 -137.375646) (xy 246.844312 -137.442702) (xy 246.844665 -137.451719) (xy 246.850915 -137.468636)
			(xy 246.856504 -137.475722) (xy 246.856758 -137.475722) (xy 246.856758 -137.475976) (xy 246.874393 -137.496912)
			(xy 246.904107 -137.542883) (xy 246.926944 -137.592629) (xy 246.942436 -137.645129) (xy 246.950264 -137.699305)
			(xy 246.950738 -137.726674) (xy 246.950252 -137.753925) (xy 246.942496 -137.807873) (xy 246.927141 -137.860168)
			(xy 246.904499 -137.909745) (xy 246.875033 -137.955595) (xy 246.839342 -137.996786) (xy 246.798151 -138.032477)
			(xy 246.752301 -138.061943) (xy 246.702724 -138.084585) (xy 246.650429 -138.09994) (xy 246.596481 -138.107696)
			(xy 246.541979 -138.107696) (xy 246.488031 -138.09994) (xy 246.435736 -138.084585) (xy 246.386159 -138.061943)
			(xy 246.340309 -138.032477) (xy 246.299118 -137.996786) (xy 246.263427 -137.955595) (xy 246.233961 -137.909745)
			(xy 246.211319 -137.860168) (xy 246.195964 -137.807873) (xy 246.188208 -137.753925) (xy 246.187722 -137.726674)
			(xy 241.18823 -137.726674) (xy 241.149409 -137.758981) (xy 241.101803 -137.788035) (xy 241.050474 -137.809847)
			(xy 240.996517 -137.823953) (xy 240.94108 -137.830053) (xy 240.885346 -137.828016) (xy 240.830503 -137.817886)
			(xy 240.777719 -137.799879) (xy 240.728119 -137.774378) (xy 240.682761 -137.741927) (xy 240.642612 -137.703218)
			(xy 240.608526 -137.659075) (xy 240.58123 -137.61044) (xy 240.561307 -137.558349) (xy 240.549181 -137.503912)
			(xy 240.54511 -137.44829) (xy 196.795644 -137.44829) (xy 196.795644 -138.434318) (xy 198.100948 -138.434318)
			(xy 198.105019 -138.378696) (xy 198.117145 -138.324259) (xy 198.137068 -138.272168) (xy 198.164364 -138.223533)
			(xy 198.19845 -138.17939) (xy 198.238599 -138.140681) (xy 198.283957 -138.10823) (xy 198.333557 -138.082729)
			(xy 198.386341 -138.064722) (xy 198.441184 -138.054592) (xy 198.496918 -138.052555) (xy 198.552355 -138.058655)
			(xy 198.606312 -138.072761) (xy 198.648423 -138.090656) (xy 224.549206 -138.090656) (xy 224.553277 -138.035034)
			(xy 224.565403 -137.980597) (xy 224.585326 -137.928506) (xy 224.612622 -137.879871) (xy 224.646708 -137.835728)
			(xy 224.686857 -137.797019) (xy 224.732215 -137.764568) (xy 224.781815 -137.739067) (xy 224.834599 -137.72106)
			(xy 224.889442 -137.71093) (xy 224.945176 -137.708893) (xy 225.000613 -137.714993) (xy 225.05457 -137.729099)
			(xy 225.105899 -137.750911) (xy 225.153505 -137.779965) (xy 225.196373 -137.81564) (xy 225.23359 -137.857177)
			(xy 225.264363 -137.90369) (xy 225.288035 -137.954187) (xy 225.304103 -138.007594) (xy 225.312223 -138.06277)
			(xy 225.312732 -138.090656) (xy 225.312223 -138.118542) (xy 225.304103 -138.173718) (xy 225.288035 -138.227125)
			(xy 225.273304 -138.25855) (xy 232.741976 -138.25855) (xy 232.746047 -138.202928) (xy 232.758173 -138.148491)
			(xy 232.778096 -138.0964) (xy 232.805392 -138.047765) (xy 232.839478 -138.003622) (xy 232.879627 -137.964913)
			(xy 232.924985 -137.932462) (xy 232.974585 -137.906961) (xy 233.027369 -137.888954) (xy 233.082212 -137.878824)
			(xy 233.137946 -137.876787) (xy 233.193383 -137.882887) (xy 233.24734 -137.896993) (xy 233.298669 -137.918805)
			(xy 233.346275 -137.947859) (xy 233.389143 -137.983534) (xy 233.42636 -138.025071) (xy 233.457133 -138.071584)
			(xy 233.480805 -138.122081) (xy 233.496873 -138.175488) (xy 233.504993 -138.230664) (xy 233.505502 -138.25855)
			(xy 233.504993 -138.286436) (xy 233.496873 -138.341612) (xy 233.491219 -138.360404) (xy 238.37595 -138.360404)
			(xy 238.380021 -138.304782) (xy 238.392147 -138.250345) (xy 238.41207 -138.198254) (xy 238.439366 -138.149619)
			(xy 238.473452 -138.105476) (xy 238.513601 -138.066767) (xy 238.558959 -138.034316) (xy 238.608559 -138.008815)
			(xy 238.661343 -137.990808) (xy 238.716186 -137.980678) (xy 238.77192 -137.978641) (xy 238.827357 -137.984741)
			(xy 238.881314 -137.998847) (xy 238.932643 -138.020659) (xy 238.980249 -138.049713) (xy 239.023117 -138.085388)
			(xy 239.060334 -138.126925) (xy 239.091107 -138.173438) (xy 239.114779 -138.223935) (xy 239.130847 -138.277342)
			(xy 239.138967 -138.332518) (xy 239.139476 -138.360404) (xy 239.138967 -138.38829) (xy 239.136754 -138.40333)
			(xy 247.396254 -138.40333) (xy 247.396765 -138.375665) (xy 247.404761 -138.320914) (xy 247.420576 -138.267891)
			(xy 247.443879 -138.217707) (xy 247.474181 -138.171411) (xy 247.510848 -138.129973) (xy 247.553112 -138.094262)
			(xy 247.57634 -138.079226) (xy 247.586005 -138.072575) (xy 247.598456 -138.052725) (xy 247.600216 -138.041126)
			(xy 247.60809 -137.961116) (xy 247.608693 -137.949479) (xy 247.600631 -137.927644) (xy 247.592596 -137.919206)
			(xy 247.592342 -137.918952) (xy 247.573763 -137.900868) (xy 247.541183 -137.860538) (xy 247.514369 -137.816164)
			(xy 247.493815 -137.768566) (xy 247.479902 -137.718622) (xy 247.472885 -137.667253) (xy 247.472454 -137.64133)
			(xy 247.473006 -137.614081) (xy 247.480757 -137.560138) (xy 247.496107 -137.507847) (xy 247.518742 -137.458272)
			(xy 247.548201 -137.412424) (xy 247.583886 -137.371234) (xy 247.625069 -137.335542) (xy 247.670913 -137.306074)
			(xy 247.720483 -137.283431) (xy 247.772771 -137.268072) (xy 247.826713 -137.260311) (xy 247.853962 -137.259822)
			(xy 247.881332 -137.260305) (xy 247.93551 -137.268118) (xy 247.988013 -137.283603) (xy 248.037761 -137.306441)
			(xy 248.083728 -137.336162) (xy 248.10466 -137.353802) (xy 248.104914 -137.354056) (xy 248.111988 -137.359661)
			(xy 248.128915 -137.365895) (xy 248.137934 -137.366248) (xy 248.20499 -137.366248) (xy 248.214008 -137.365897)
			(xy 248.230925 -137.359647) (xy 248.23801 -137.354056) (xy 248.23801 -137.353802) (xy 248.238264 -137.353802)
			(xy 248.259199 -137.336167) (xy 248.305171 -137.306454) (xy 248.354918 -137.283617) (xy 248.407418 -137.268126)
			(xy 248.461593 -137.260296) (xy 248.488962 -137.259822) (xy 248.516215 -137.260291) (xy 248.570168 -137.268043)
			(xy 248.622467 -137.283396) (xy 248.672049 -137.306036) (xy 248.717904 -137.335503) (xy 248.759098 -137.371197)
			(xy 248.794792 -137.41239) (xy 248.82426 -137.458244) (xy 248.846901 -137.507825) (xy 248.862255 -137.560125)
			(xy 248.870009 -137.614077) (xy 248.87047 -137.64133) (xy 248.869913 -137.670246) (xy 248.861194 -137.727416)
			(xy 248.843944 -137.782614) (xy 248.81856 -137.834576) (xy 248.785623 -137.882111) (xy 248.745887 -137.924129)
			(xy 248.723404 -137.94232) (xy 248.714598 -137.949929) (xy 248.704414 -137.970828) (xy 248.703846 -137.982452)
			(xy 248.703846 -138.062208) (xy 248.704379 -138.073841) (xy 248.71457 -138.094752) (xy 248.723404 -138.10234)
			(xy 248.745907 -138.120507) (xy 248.785641 -138.162532) (xy 248.818578 -138.210072) (xy 248.843963 -138.262038)
			(xy 248.861215 -138.31724) (xy 248.869938 -138.374413) (xy 248.87047 -138.40333) (xy 248.870073 -138.430585)
			(xy 248.862311 -138.484541) (xy 248.850205 -138.525758) (xy 249.141742 -138.525758) (xy 249.142232 -138.498389)
			(xy 249.150042 -138.44421) (xy 249.165525 -138.391707) (xy 249.188362 -138.341959) (xy 249.218082 -138.295992)
			(xy 249.235722 -138.27506) (xy 249.235976 -138.274806) (xy 249.241575 -138.267728) (xy 249.247812 -138.250804)
			(xy 249.248168 -138.241786) (xy 249.248168 -138.17473) (xy 249.247803 -138.165714) (xy 249.241562 -138.148796)
			(xy 249.235976 -138.14171) (xy 249.235722 -138.14171) (xy 249.235722 -138.141456) (xy 249.21804 -138.120556)
			(xy 249.188318 -138.074583) (xy 249.165475 -138.024831) (xy 249.149982 -137.972324) (xy 249.142158 -137.918141)
			(xy 249.142162 -137.863396) (xy 249.149996 -137.809214) (xy 249.165497 -137.75671) (xy 249.188348 -137.706962)
			(xy 249.218079 -137.660993) (xy 249.235722 -137.64006) (xy 249.235976 -137.639806) (xy 249.241575 -137.632728)
			(xy 249.247812 -137.615804) (xy 249.248168 -137.606786) (xy 249.248168 -137.53973) (xy 249.247803 -137.530714)
			(xy 249.241562 -137.513796) (xy 249.235976 -137.50671) (xy 249.235722 -137.50671) (xy 249.235722 -137.506456)
			(xy 249.21804 -137.485556) (xy 249.188318 -137.439583) (xy 249.165475 -137.389831) (xy 249.149982 -137.337324)
			(xy 249.142158 -137.283141) (xy 249.142162 -137.228396) (xy 249.149996 -137.174214) (xy 249.165497 -137.12171)
			(xy 249.188348 -137.071962) (xy 249.218079 -137.025993) (xy 249.235722 -137.00506) (xy 249.235976 -137.004806)
			(xy 249.241575 -136.997728) (xy 249.247812 -136.980804) (xy 249.248168 -136.971786) (xy 249.248168 -136.90473)
			(xy 249.247803 -136.895714) (xy 249.241562 -136.878796) (xy 249.235976 -136.87171) (xy 249.235722 -136.87171)
			(xy 249.235722 -136.871456) (xy 249.218099 -136.850511) (xy 249.188384 -136.804542) (xy 249.165545 -136.754798)
			(xy 249.15005 -136.7023) (xy 249.142218 -136.648126) (xy 249.141742 -136.620758) (xy 249.142228 -136.593507)
			(xy 249.149984 -136.539559) (xy 249.165339 -136.487264) (xy 249.187981 -136.437687) (xy 249.217447 -136.391837)
			(xy 249.253138 -136.350646) (xy 249.294329 -136.314955) (xy 249.340179 -136.285489) (xy 249.389756 -136.262847)
			(xy 249.442051 -136.247492) (xy 249.495999 -136.239736) (xy 249.550501 -136.239736) (xy 249.604449 -136.247492)
			(xy 249.656744 -136.262847) (xy 249.706321 -136.285489) (xy 249.752171 -136.314955) (xy 249.793362 -136.350646)
			(xy 249.829053 -136.391837) (xy 249.858519 -136.437687) (xy 249.881161 -136.487264) (xy 249.896516 -136.539559)
			(xy 249.904272 -136.593507) (xy 249.904758 -136.620758) (xy 249.904278 -136.648128) (xy 249.896465 -136.702307)
			(xy 249.88098 -136.75481) (xy 249.858141 -136.804557) (xy 249.828418 -136.850524) (xy 249.810778 -136.871456)
			(xy 249.810524 -136.87171) (xy 249.804918 -136.878783) (xy 249.798685 -136.895711) (xy 249.798332 -136.90473)
			(xy 249.798332 -136.971786) (xy 249.798689 -136.980803) (xy 249.804936 -136.99772) (xy 249.810524 -137.004806)
			(xy 249.810778 -137.004806) (xy 249.810778 -137.00506) (xy 249.828377 -137.026026) (xy 249.858103 -137.071988)
			(xy 249.880951 -137.121729) (xy 249.89645 -137.174226) (xy 249.904283 -137.2284) (xy 249.904287 -137.283137)
			(xy 249.896464 -137.337312) (xy 249.880973 -137.389812) (xy 249.858134 -137.439556) (xy 249.828415 -137.485523)
			(xy 249.810778 -137.506456) (xy 249.810524 -137.50671) (xy 249.804918 -137.513783) (xy 249.798685 -137.530711)
			(xy 249.798332 -137.53973) (xy 249.798332 -137.606786) (xy 249.798689 -137.615803) (xy 249.804936 -137.63272)
			(xy 249.810524 -137.639806) (xy 249.810778 -137.639806) (xy 249.810778 -137.64006) (xy 249.828377 -137.661026)
			(xy 249.858103 -137.706988) (xy 249.880951 -137.756729) (xy 249.89645 -137.809226) (xy 249.904283 -137.8634)
			(xy 249.904287 -137.918137) (xy 249.896464 -137.972312) (xy 249.880973 -138.024812) (xy 249.858134 -138.074556)
			(xy 249.828415 -138.120523) (xy 249.810778 -138.141456) (xy 249.810524 -138.14171) (xy 249.804918 -138.148783)
			(xy 249.798685 -138.165711) (xy 249.798332 -138.17473) (xy 249.798332 -138.241786) (xy 249.798689 -138.250803)
			(xy 249.804936 -138.26772) (xy 249.810524 -138.274806) (xy 249.810778 -138.274806) (xy 249.810778 -138.27506)
			(xy 249.828408 -138.295999) (xy 249.858122 -138.34197) (xy 249.88096 -138.391715) (xy 249.896453 -138.444215)
			(xy 249.904283 -138.498389) (xy 249.904758 -138.525758) (xy 249.904257 -138.554374) (xy 249.895719 -138.610964)
			(xy 249.878815 -138.665642) (xy 249.853924 -138.717177) (xy 249.821605 -138.764409) (xy 249.782587 -138.806278)
			(xy 249.760486 -138.824462) (xy 249.760232 -138.824716) (xy 249.751694 -138.832326) (xy 249.741807 -138.852918)
			(xy 249.741182 -138.86434) (xy 249.74169 -138.94435) (xy 249.742292 -138.955914) (xy 249.752465 -138.976685)
			(xy 249.761248 -138.984228) (xy 249.77725 -138.997436) (xy 249.777504 -138.99769) (xy 249.784586 -139.003283)
			(xy 249.801506 -139.009526) (xy 249.810524 -139.009882) (xy 249.87758 -139.009882) (xy 249.886596 -139.00952)
			(xy 249.903514 -139.003276) (xy 249.9106 -138.99769) (xy 249.9106 -138.997436) (xy 249.910854 -138.997436)
			(xy 249.931787 -138.979795) (xy 249.977755 -138.950071) (xy 250.027501 -138.927225) (xy 250.080003 -138.911729)
			(xy 250.134181 -138.9039) (xy 250.188923 -138.9039) (xy 250.243101 -138.911729) (xy 250.295603 -138.927225)
			(xy 250.345349 -138.950071) (xy 250.391317 -138.979795) (xy 250.41225 -138.997436) (xy 250.412504 -138.99769)
			(xy 250.419586 -139.003283) (xy 250.436506 -139.009526) (xy 250.445524 -139.009882) (xy 250.51258 -139.009882)
			(xy 250.521596 -139.00952) (xy 250.538514 -139.003276) (xy 250.5456 -138.99769) (xy 250.5456 -138.997436)
			(xy 250.545854 -138.997436) (xy 250.566787 -138.979795) (xy 250.612755 -138.950071) (xy 250.662501 -138.927225)
			(xy 250.715003 -138.911729) (xy 250.769181 -138.9039) (xy 250.823923 -138.9039) (xy 250.878101 -138.911729)
			(xy 250.930603 -138.927225) (xy 250.980349 -138.950071) (xy 251.026317 -138.979795) (xy 251.04725 -138.997436)
			(xy 251.047504 -138.99769) (xy 251.054586 -139.003283) (xy 251.071506 -139.009526) (xy 251.080524 -139.009882)
			(xy 251.14758 -139.009882) (xy 251.156596 -139.00952) (xy 251.173514 -139.003276) (xy 251.1806 -138.99769)
			(xy 251.1806 -138.997436) (xy 251.180854 -138.997436) (xy 251.201797 -138.979811) (xy 251.247766 -138.950095)
			(xy 251.297511 -138.927256) (xy 251.350009 -138.911762) (xy 251.404183 -138.903931) (xy 251.431552 -138.903456)
			(xy 251.458805 -138.903988) (xy 251.512756 -138.911739) (xy 251.565054 -138.927089) (xy 251.614636 -138.949727)
			(xy 251.660491 -138.979191) (xy 251.701685 -139.014881) (xy 251.737381 -139.056071) (xy 251.76685 -139.101922)
			(xy 251.789494 -139.151501) (xy 251.804851 -139.203797) (xy 251.812609 -139.257748) (xy 251.812609 -139.312252)
			(xy 251.804851 -139.366203) (xy 251.789494 -139.418499) (xy 251.76685 -139.468078) (xy 251.737381 -139.513929)
			(xy 251.701685 -139.555119) (xy 251.660491 -139.590809) (xy 251.614636 -139.620273) (xy 251.565054 -139.642911)
			(xy 251.512756 -139.658261) (xy 251.458805 -139.666012) (xy 251.431552 -139.666472) (xy 251.404183 -139.665982)
			(xy 251.350004 -139.658171) (xy 251.297501 -139.642688) (xy 251.247754 -139.619851) (xy 251.201786 -139.590131)
			(xy 251.180854 -139.572492) (xy 251.1806 -139.572238) (xy 251.173523 -139.566638) (xy 251.156599 -139.560401)
			(xy 251.14758 -139.560046) (xy 251.080524 -139.560046) (xy 251.071507 -139.560405) (xy 251.05459 -139.56665)
			(xy 251.047504 -139.572238) (xy 251.04725 -139.572492) (xy 251.026317 -139.590133) (xy 250.980349 -139.619857)
			(xy 250.930603 -139.642703) (xy 250.878101 -139.658199) (xy 250.823923 -139.666028) (xy 250.769181 -139.666028)
			(xy 250.715003 -139.658199) (xy 250.662501 -139.642703) (xy 250.612755 -139.619857) (xy 250.566787 -139.590133)
			(xy 250.545854 -139.572492) (xy 250.5456 -139.572238) (xy 250.538523 -139.566638) (xy 250.521599 -139.560401)
			(xy 250.51258 -139.560046) (xy 250.445524 -139.560046) (xy 250.436507 -139.560405) (xy 250.41959 -139.56665)
			(xy 250.412504 -139.572238) (xy 250.412504 -139.572492) (xy 250.41225 -139.572492) (xy 250.391317 -139.590133)
			(xy 250.345349 -139.619857) (xy 250.295603 -139.642703) (xy 250.243101 -139.658199) (xy 250.188923 -139.666028)
			(xy 250.134181 -139.666028) (xy 250.080003 -139.658199) (xy 250.027501 -139.642703) (xy 249.977755 -139.619857)
			(xy 249.931787 -139.590133) (xy 249.910854 -139.572492) (xy 249.9106 -139.572238) (xy 249.903523 -139.566638)
			(xy 249.886599 -139.560401) (xy 249.87758 -139.560046) (xy 249.810524 -139.560046) (xy 249.801507 -139.560405)
			(xy 249.78459 -139.56665) (xy 249.777504 -139.572238) (xy 249.777504 -139.572492) (xy 249.77725 -139.572492)
			(xy 249.756309 -139.59012) (xy 249.710339 -139.619834) (xy 249.660593 -139.642672) (xy 249.608095 -139.658166)
			(xy 249.553921 -139.665997) (xy 249.526552 -139.666472) (xy 249.499298 -139.666067) (xy 249.445345 -139.658303)
			(xy 249.393047 -139.64294) (xy 249.343467 -139.62029) (xy 249.297615 -139.590816) (xy 249.256425 -139.555116)
			(xy 249.220734 -139.513917) (xy 249.191269 -139.468059) (xy 249.168631 -139.418474) (xy 249.153279 -139.366172)
			(xy 249.145527 -139.312218) (xy 249.145044 -139.284964) (xy 249.14556 -139.256349) (xy 249.154094 -139.199759)
			(xy 249.170996 -139.145081) (xy 249.195884 -139.093547) (xy 249.2282 -139.046313) (xy 249.267216 -139.004444)
			(xy 249.289316 -138.98626) (xy 249.28957 -138.986006) (xy 249.298099 -138.978387) (xy 249.307991 -138.957802)
			(xy 249.30862 -138.946382) (xy 249.308112 -138.866372) (xy 249.307496 -138.85481) (xy 249.297333 -138.834039)
			(xy 249.288554 -138.826494) (xy 249.266101 -138.808313) (xy 249.226429 -138.766317) (xy 249.193545 -138.718817)
			(xy 249.168202 -138.666901) (xy 249.150979 -138.611756) (xy 249.142272 -138.554644) (xy 249.141742 -138.525758)
			(xy 248.850205 -138.525758) (xy 248.846949 -138.536842) (xy 248.8243 -138.586425) (xy 248.794826 -138.63228)
			(xy 248.759125 -138.673473) (xy 248.717925 -138.709166) (xy 248.672065 -138.738633) (xy 248.622478 -138.761273)
			(xy 248.570174 -138.776625) (xy 248.516217 -138.784378) (xy 248.488962 -138.784838) (xy 248.462646 -138.784416)
			(xy 248.410515 -138.777174) (xy 248.359871 -138.762848) (xy 248.311671 -138.741707) (xy 248.266829 -138.714152)
			(xy 248.226192 -138.680704) (xy 248.208038 -138.661648) (xy 248.200498 -138.654268) (xy 248.181232 -138.64573)
			(xy 248.1707 -138.645138) (xy 248.096024 -138.645138) (xy 248.085473 -138.645655) (xy 248.066177 -138.654197)
			(xy 248.058686 -138.661648) (xy 248.04054 -138.680712) (xy 247.999907 -138.714167) (xy 247.955064 -138.741724)
			(xy 247.906862 -138.76286) (xy 247.856213 -138.777176) (xy 247.804079 -138.7844) (xy 247.777762 -138.784838)
			(xy 247.750511 -138.784358) (xy 247.696565 -138.776597) (xy 247.644272 -138.761238) (xy 247.594696 -138.738595)
			(xy 247.548848 -138.709127) (xy 247.507659 -138.673436) (xy 247.471968 -138.632246) (xy 247.442501 -138.586397)
			(xy 247.419859 -138.536821) (xy 247.404502 -138.484527) (xy 247.396742 -138.430581) (xy 247.396254 -138.40333)
			(xy 239.136754 -138.40333) (xy 239.130847 -138.443466) (xy 239.114779 -138.496873) (xy 239.091107 -138.54737)
			(xy 239.060334 -138.593883) (xy 239.023117 -138.63542) (xy 238.980249 -138.671095) (xy 238.932643 -138.700149)
			(xy 238.881314 -138.721961) (xy 238.827357 -138.736067) (xy 238.77192 -138.742167) (xy 238.716186 -138.74013)
			(xy 238.661343 -138.73) (xy 238.608559 -138.711993) (xy 238.558959 -138.686492) (xy 238.513601 -138.654041)
			(xy 238.473452 -138.615332) (xy 238.439366 -138.571189) (xy 238.41207 -138.522554) (xy 238.392147 -138.470463)
			(xy 238.380021 -138.416026) (xy 238.37595 -138.360404) (xy 233.491219 -138.360404) (xy 233.480805 -138.395019)
			(xy 233.457133 -138.445516) (xy 233.42636 -138.492029) (xy 233.389143 -138.533566) (xy 233.346275 -138.569241)
			(xy 233.298669 -138.598295) (xy 233.24734 -138.620107) (xy 233.193383 -138.634213) (xy 233.137946 -138.640313)
			(xy 233.082212 -138.638276) (xy 233.027369 -138.628146) (xy 232.974585 -138.610139) (xy 232.924985 -138.584638)
			(xy 232.879627 -138.552187) (xy 232.839478 -138.513478) (xy 232.805392 -138.469335) (xy 232.778096 -138.4207)
			(xy 232.758173 -138.368609) (xy 232.746047 -138.314172) (xy 232.741976 -138.25855) (xy 225.273304 -138.25855)
			(xy 225.264363 -138.277622) (xy 225.23359 -138.324135) (xy 225.196373 -138.365672) (xy 225.153505 -138.401347)
			(xy 225.105899 -138.430401) (xy 225.05457 -138.452213) (xy 225.000613 -138.466319) (xy 224.945176 -138.472419)
			(xy 224.889442 -138.470382) (xy 224.834599 -138.460252) (xy 224.781815 -138.442245) (xy 224.732215 -138.416744)
			(xy 224.686857 -138.384293) (xy 224.646708 -138.345584) (xy 224.612622 -138.301441) (xy 224.585326 -138.252806)
			(xy 224.565403 -138.200715) (xy 224.553277 -138.146278) (xy 224.549206 -138.090656) (xy 198.648423 -138.090656)
			(xy 198.657641 -138.094573) (xy 198.705247 -138.123627) (xy 198.748115 -138.159302) (xy 198.785332 -138.200839)
			(xy 198.816105 -138.247352) (xy 198.839777 -138.297849) (xy 198.855845 -138.351256) (xy 198.863965 -138.406432)
			(xy 198.864474 -138.434318) (xy 198.863965 -138.462204) (xy 198.85764 -138.505184) (xy 221.778828 -138.505184)
			(xy 221.782899 -138.449562) (xy 221.795025 -138.395125) (xy 221.814948 -138.343034) (xy 221.842244 -138.294399)
			(xy 221.87633 -138.250256) (xy 221.916479 -138.211547) (xy 221.961837 -138.179096) (xy 222.011437 -138.153595)
			(xy 222.064221 -138.135588) (xy 222.119064 -138.125458) (xy 222.174798 -138.123421) (xy 222.230235 -138.129521)
			(xy 222.284192 -138.143627) (xy 222.335521 -138.165439) (xy 222.383127 -138.194493) (xy 222.425995 -138.230168)
			(xy 222.463212 -138.271705) (xy 222.493985 -138.318218) (xy 222.517657 -138.368715) (xy 222.533725 -138.422122)
			(xy 222.541845 -138.477298) (xy 222.542354 -138.505184) (xy 222.541845 -138.53307) (xy 222.533725 -138.588246)
			(xy 222.517657 -138.641653) (xy 222.493985 -138.69215) (xy 222.463212 -138.738663) (xy 222.425995 -138.7802)
			(xy 222.383127 -138.815875) (xy 222.335521 -138.844929) (xy 222.284192 -138.866741) (xy 222.230235 -138.880847)
			(xy 222.174798 -138.886947) (xy 222.119064 -138.88491) (xy 222.064221 -138.87478) (xy 222.011437 -138.856773)
			(xy 221.961837 -138.831272) (xy 221.916479 -138.798821) (xy 221.87633 -138.760112) (xy 221.842244 -138.715969)
			(xy 221.814948 -138.667334) (xy 221.795025 -138.615243) (xy 221.782899 -138.560806) (xy 221.778828 -138.505184)
			(xy 198.85764 -138.505184) (xy 198.855845 -138.51738) (xy 198.839777 -138.570787) (xy 198.816105 -138.621284)
			(xy 198.785332 -138.667797) (xy 198.748115 -138.709334) (xy 198.705247 -138.745009) (xy 198.657641 -138.774063)
			(xy 198.606312 -138.795875) (xy 198.552355 -138.809981) (xy 198.496918 -138.816081) (xy 198.441184 -138.814044)
			(xy 198.386341 -138.803914) (xy 198.333557 -138.785907) (xy 198.283957 -138.760406) (xy 198.238599 -138.727955)
			(xy 198.19845 -138.689246) (xy 198.164364 -138.645103) (xy 198.137068 -138.596468) (xy 198.117145 -138.544377)
			(xy 198.105019 -138.48994) (xy 198.100948 -138.434318) (xy 196.795644 -138.434318) (xy 196.795644 -139.057455)
			(xy 226.046957 -139.057455) (xy 226.046957 -139.002945) (xy 226.054716 -138.948991) (xy 226.070074 -138.896689)
			(xy 226.09272 -138.847106) (xy 226.122192 -138.801251) (xy 226.15789 -138.760058) (xy 226.199088 -138.724364)
			(xy 226.244947 -138.694898) (xy 226.294532 -138.672258) (xy 226.346836 -138.656906) (xy 226.400791 -138.649154)
			(xy 226.428046 -138.648694) (xy 226.455415 -138.649193) (xy 226.509593 -138.657003) (xy 226.562095 -138.672485)
			(xy 226.611843 -138.695319) (xy 226.657811 -138.725036) (xy 226.678744 -138.742674) (xy 226.678998 -138.742928)
			(xy 226.686079 -138.748523) (xy 226.703 -138.754764) (xy 226.712018 -138.75512) (xy 226.779074 -138.75512)
			(xy 226.788089 -138.754746) (xy 226.805006 -138.74851) (xy 226.812094 -138.742928) (xy 226.812094 -138.742674)
			(xy 226.812348 -138.742674) (xy 226.833286 -138.725042) (xy 226.879257 -138.69533) (xy 226.929003 -138.672493)
			(xy 226.981503 -138.657) (xy 227.035677 -138.64917) (xy 227.063046 -138.648694) (xy 227.090295 -138.649179)
			(xy 227.144238 -138.656941) (xy 227.196528 -138.6723) (xy 227.246099 -138.694944) (xy 227.291944 -138.724412)
			(xy 227.333129 -138.760103) (xy 227.368816 -138.801293) (xy 227.383704 -138.824462) (xy 240.561874 -138.824462)
			(xy 240.565945 -138.76884) (xy 240.578071 -138.714403) (xy 240.597994 -138.662312) (xy 240.62529 -138.613677)
			(xy 240.659376 -138.569534) (xy 240.699525 -138.530825) (xy 240.744883 -138.498374) (xy 240.794483 -138.472873)
			(xy 240.847267 -138.454866) (xy 240.90211 -138.444736) (xy 240.957844 -138.442699) (xy 241.013281 -138.448799)
			(xy 241.067238 -138.462905) (xy 241.118567 -138.484717) (xy 241.166173 -138.513771) (xy 241.209041 -138.549446)
			(xy 241.246258 -138.590983) (xy 241.277031 -138.637496) (xy 241.300703 -138.687993) (xy 241.316771 -138.7414)
			(xy 241.324891 -138.796576) (xy 241.3254 -138.824462) (xy 241.324891 -138.852348) (xy 241.316771 -138.907524)
			(xy 241.300703 -138.960931) (xy 241.277031 -139.011428) (xy 241.246258 -139.057941) (xy 241.209041 -139.099478)
			(xy 241.166173 -139.135153) (xy 241.118567 -139.164207) (xy 241.067238 -139.186019) (xy 241.013281 -139.200125)
			(xy 240.957844 -139.206225) (xy 240.90211 -139.204188) (xy 240.847267 -139.194058) (xy 240.794483 -139.176051)
			(xy 240.744883 -139.15055) (xy 240.699525 -139.118099) (xy 240.659376 -139.07939) (xy 240.62529 -139.035247)
			(xy 240.597994 -138.986612) (xy 240.578071 -138.934521) (xy 240.565945 -138.880084) (xy 240.561874 -138.824462)
			(xy 227.383704 -138.824462) (xy 227.398278 -138.847141) (xy 227.420916 -138.896715) (xy 227.436269 -138.949007)
			(xy 227.444024 -139.002951) (xy 227.444024 -139.057449) (xy 227.436269 -139.111393) (xy 227.420916 -139.163685)
			(xy 227.398278 -139.213259) (xy 227.368816 -139.259107) (xy 227.333129 -139.300297) (xy 227.291944 -139.335988)
			(xy 227.246099 -139.365456) (xy 227.222132 -139.376404) (xy 238.37595 -139.376404) (xy 238.380021 -139.320782)
			(xy 238.392147 -139.266345) (xy 238.41207 -139.214254) (xy 238.439366 -139.165619) (xy 238.473452 -139.121476)
			(xy 238.513601 -139.082767) (xy 238.558959 -139.050316) (xy 238.608559 -139.024815) (xy 238.661343 -139.006808)
			(xy 238.716186 -138.996678) (xy 238.77192 -138.994641) (xy 238.827357 -139.000741) (xy 238.881314 -139.014847)
			(xy 238.932643 -139.036659) (xy 238.980249 -139.065713) (xy 239.023117 -139.101388) (xy 239.060334 -139.142925)
			(xy 239.091107 -139.189438) (xy 239.114779 -139.239935) (xy 239.130847 -139.293342) (xy 239.138967 -139.348518)
			(xy 239.139476 -139.376404) (xy 239.138967 -139.40429) (xy 239.130847 -139.459466) (xy 239.114779 -139.512873)
			(xy 239.091107 -139.56337) (xy 239.060334 -139.609883) (xy 239.023117 -139.65142) (xy 238.980249 -139.687095)
			(xy 238.932643 -139.716149) (xy 238.881314 -139.737961) (xy 238.827357 -139.752067) (xy 238.77192 -139.758167)
			(xy 238.716186 -139.75613) (xy 238.661343 -139.746) (xy 238.608559 -139.727993) (xy 238.558959 -139.702492)
			(xy 238.513601 -139.670041) (xy 238.473452 -139.631332) (xy 238.439366 -139.587189) (xy 238.41207 -139.538554)
			(xy 238.392147 -139.486463) (xy 238.380021 -139.432026) (xy 238.37595 -139.376404) (xy 227.222132 -139.376404)
			(xy 227.196528 -139.3881) (xy 227.144238 -139.403459) (xy 227.090295 -139.411221) (xy 227.063046 -139.41171)
			(xy 227.035677 -139.411215) (xy 226.981499 -139.403403) (xy 226.928996 -139.387921) (xy 226.879249 -139.365086)
			(xy 226.833281 -139.335368) (xy 226.812348 -139.31773) (xy 226.812094 -139.317476) (xy 226.805015 -139.311878)
			(xy 226.788092 -139.305639) (xy 226.779074 -139.305284) (xy 226.712018 -139.305284) (xy 226.703002 -139.305653)
			(xy 226.686086 -139.311893) (xy 226.678998 -139.317476) (xy 226.678998 -139.31773) (xy 226.678744 -139.31773)
			(xy 226.65781 -139.335367) (xy 226.611837 -139.365078) (xy 226.56209 -139.387914) (xy 226.50959 -139.403405)
			(xy 226.455415 -139.411235) (xy 226.428046 -139.41171) (xy 226.400791 -139.411246) (xy 226.346836 -139.403494)
			(xy 226.294532 -139.388142) (xy 226.244947 -139.365502) (xy 226.199088 -139.336036) (xy 226.15789 -139.300342)
			(xy 226.122192 -139.259149) (xy 226.09272 -139.213294) (xy 226.070074 -139.163711) (xy 226.054716 -139.111409)
			(xy 226.046957 -139.057455) (xy 196.795644 -139.057455) (xy 196.795644 -139.641834) (xy 219.820234 -139.641834)
			(xy 219.824305 -139.586212) (xy 219.836431 -139.531775) (xy 219.856354 -139.479684) (xy 219.88365 -139.431049)
			(xy 219.917736 -139.386906) (xy 219.957885 -139.348197) (xy 220.003243 -139.315746) (xy 220.052843 -139.290245)
			(xy 220.105627 -139.272238) (xy 220.16047 -139.262108) (xy 220.216204 -139.260071) (xy 220.271641 -139.266171)
			(xy 220.325598 -139.280277) (xy 220.376927 -139.302089) (xy 220.424533 -139.331143) (xy 220.467401 -139.366818)
			(xy 220.504618 -139.408355) (xy 220.535391 -139.454868) (xy 220.559063 -139.505365) (xy 220.575131 -139.558772)
			(xy 220.583251 -139.613948) (xy 220.58376 -139.641834) (xy 220.583251 -139.66972) (xy 220.575131 -139.724896)
			(xy 220.559063 -139.778303) (xy 220.53683 -139.82573) (xy 231.704894 -139.82573) (xy 231.708965 -139.770108)
			(xy 231.721091 -139.715671) (xy 231.741014 -139.66358) (xy 231.76831 -139.614945) (xy 231.802396 -139.570802)
			(xy 231.842545 -139.532093) (xy 231.887903 -139.499642) (xy 231.937503 -139.474141) (xy 231.990287 -139.456134)
			(xy 232.04513 -139.446004) (xy 232.100864 -139.443967) (xy 232.156301 -139.450067) (xy 232.210258 -139.464173)
			(xy 232.261587 -139.485985) (xy 232.309193 -139.515039) (xy 232.352061 -139.550714) (xy 232.389278 -139.592251)
			(xy 232.420051 -139.638764) (xy 232.443723 -139.689261) (xy 232.459791 -139.742668) (xy 232.467911 -139.797844)
			(xy 232.46842 -139.82573) (xy 232.467911 -139.853616) (xy 232.459791 -139.908792) (xy 232.443723 -139.962199)
			(xy 232.420051 -140.012696) (xy 232.389278 -140.059209) (xy 232.352061 -140.100746) (xy 232.309193 -140.136421)
			(xy 232.261587 -140.165475) (xy 232.210258 -140.187287) (xy 232.156301 -140.201393) (xy 232.100864 -140.207493)
			(xy 232.04513 -140.205456) (xy 231.990287 -140.195326) (xy 231.937503 -140.177319) (xy 231.887903 -140.151818)
			(xy 231.842545 -140.119367) (xy 231.802396 -140.080658) (xy 231.76831 -140.036515) (xy 231.741014 -139.98788)
			(xy 231.721091 -139.935789) (xy 231.708965 -139.881352) (xy 231.704894 -139.82573) (xy 220.53683 -139.82573)
			(xy 220.535391 -139.8288) (xy 220.504618 -139.875313) (xy 220.467401 -139.91685) (xy 220.424533 -139.952525)
			(xy 220.376927 -139.981579) (xy 220.325598 -140.003391) (xy 220.271641 -140.017497) (xy 220.216204 -140.023597)
			(xy 220.16047 -140.02156) (xy 220.105627 -140.01143) (xy 220.052843 -139.993423) (xy 220.003243 -139.967922)
			(xy 219.957885 -139.935471) (xy 219.917736 -139.896762) (xy 219.88365 -139.852619) (xy 219.856354 -139.803984)
			(xy 219.836431 -139.751893) (xy 219.824305 -139.697456) (xy 219.820234 -139.641834) (xy 196.795644 -139.641834)
			(xy 196.795644 -140.534898) (xy 197.155814 -140.534898) (xy 197.159885 -140.479276) (xy 197.172011 -140.424839)
			(xy 197.191934 -140.372748) (xy 197.21923 -140.324113) (xy 197.253316 -140.27997) (xy 197.293465 -140.241261)
			(xy 197.338823 -140.20881) (xy 197.388423 -140.183309) (xy 197.441207 -140.165302) (xy 197.49605 -140.155172)
			(xy 197.551784 -140.153135) (xy 197.607221 -140.159235) (xy 197.661178 -140.173341) (xy 197.712507 -140.195153)
			(xy 197.760113 -140.224207) (xy 197.802981 -140.259882) (xy 197.840198 -140.301419) (xy 197.870971 -140.347932)
			(xy 197.894643 -140.398429) (xy 197.910711 -140.451836) (xy 197.915982 -140.487654) (xy 201.801982 -140.487654)
			(xy 201.806053 -140.432032) (xy 201.818179 -140.377595) (xy 201.838102 -140.325504) (xy 201.865398 -140.276869)
			(xy 201.899484 -140.232726) (xy 201.939633 -140.194017) (xy 201.984991 -140.161566) (xy 202.034591 -140.136065)
			(xy 202.087375 -140.118058) (xy 202.142218 -140.107928) (xy 202.197952 -140.105891) (xy 202.253389 -140.111991)
			(xy 202.307346 -140.126097) (xy 202.358675 -140.147909) (xy 202.406281 -140.176963) (xy 202.449149 -140.212638)
			(xy 202.486366 -140.254175) (xy 202.517139 -140.300688) (xy 202.540811 -140.351185) (xy 202.556879 -140.404592)
			(xy 202.564999 -140.459768) (xy 202.565508 -140.487654) (xy 202.564999 -140.51554) (xy 202.556879 -140.570716)
			(xy 202.540811 -140.624123) (xy 202.517139 -140.67462) (xy 202.486366 -140.721133) (xy 202.449149 -140.76267)
			(xy 202.406281 -140.798345) (xy 202.358675 -140.827399) (xy 202.307346 -140.849211) (xy 202.253389 -140.863317)
			(xy 202.197952 -140.869417) (xy 202.142218 -140.86738) (xy 202.087375 -140.85725) (xy 202.034591 -140.839243)
			(xy 201.984991 -140.813742) (xy 201.939633 -140.781291) (xy 201.899484 -140.742582) (xy 201.865398 -140.698439)
			(xy 201.838102 -140.649804) (xy 201.818179 -140.597713) (xy 201.806053 -140.543276) (xy 201.801982 -140.487654)
			(xy 197.915982 -140.487654) (xy 197.918831 -140.507012) (xy 197.91934 -140.534898) (xy 197.918831 -140.562784)
			(xy 197.910711 -140.61796) (xy 197.894643 -140.671367) (xy 197.870971 -140.721864) (xy 197.840198 -140.768377)
			(xy 197.802981 -140.809914) (xy 197.760113 -140.845589) (xy 197.712507 -140.874643) (xy 197.665633 -140.894562)
			(xy 219.859604 -140.894562) (xy 219.863675 -140.83894) (xy 219.875801 -140.784503) (xy 219.895724 -140.732412)
			(xy 219.92302 -140.683777) (xy 219.957106 -140.639634) (xy 219.997255 -140.600925) (xy 220.042613 -140.568474)
			(xy 220.092213 -140.542973) (xy 220.144997 -140.524966) (xy 220.19984 -140.514836) (xy 220.255574 -140.512799)
			(xy 220.311011 -140.518899) (xy 220.364968 -140.533005) (xy 220.416297 -140.554817) (xy 220.463903 -140.583871)
			(xy 220.506771 -140.619546) (xy 220.543988 -140.661083) (xy 220.574761 -140.707596) (xy 220.598433 -140.758093)
			(xy 220.614501 -140.8115) (xy 220.622621 -140.866676) (xy 220.62313 -140.894562) (xy 220.622621 -140.922448)
			(xy 220.617791 -140.955268) (xy 222.72701 -140.955268) (xy 222.731081 -140.899646) (xy 222.743207 -140.845209)
			(xy 222.76313 -140.793118) (xy 222.790426 -140.744483) (xy 222.824512 -140.70034) (xy 222.864661 -140.661631)
			(xy 222.910019 -140.62918) (xy 222.959619 -140.603679) (xy 223.012403 -140.585672) (xy 223.067246 -140.575542)
			(xy 223.12298 -140.573505) (xy 223.178417 -140.579605) (xy 223.232374 -140.593711) (xy 223.283703 -140.615523)
			(xy 223.331309 -140.644577) (xy 223.374177 -140.680252) (xy 223.397787 -140.706602) (xy 224.801428 -140.706602)
			(xy 224.805499 -140.65098) (xy 224.817625 -140.596543) (xy 224.837548 -140.544452) (xy 224.864844 -140.495817)
			(xy 224.89893 -140.451674) (xy 224.939079 -140.412965) (xy 224.984437 -140.380514) (xy 225.034037 -140.355013)
			(xy 225.086821 -140.337006) (xy 225.141664 -140.326876) (xy 225.197398 -140.324839) (xy 225.252835 -140.330939)
			(xy 225.306792 -140.345045) (xy 225.358121 -140.366857) (xy 225.399981 -140.392404) (xy 240.567716 -140.392404)
			(xy 240.571787 -140.336782) (xy 240.583913 -140.282345) (xy 240.603836 -140.230254) (xy 240.631132 -140.181619)
			(xy 240.665218 -140.137476) (xy 240.705367 -140.098767) (xy 240.750725 -140.066316) (xy 240.800325 -140.040815)
			(xy 240.853109 -140.022808) (xy 240.907952 -140.012678) (xy 240.963686 -140.010641) (xy 241.019123 -140.016741)
			(xy 241.07308 -140.030847) (xy 241.124409 -140.052659) (xy 241.172015 -140.081713) (xy 241.214883 -140.117388)
			(xy 241.2521 -140.158925) (xy 241.282873 -140.205438) (xy 241.306545 -140.255935) (xy 241.322613 -140.309342)
			(xy 241.330733 -140.364518) (xy 241.331242 -140.392404) (xy 241.330733 -140.42029) (xy 241.322613 -140.475466)
			(xy 241.306545 -140.528873) (xy 241.282873 -140.57937) (xy 241.2521 -140.625883) (xy 241.214883 -140.66742)
			(xy 241.172015 -140.703095) (xy 241.124409 -140.732149) (xy 241.07308 -140.753961) (xy 241.019123 -140.768067)
			(xy 240.963686 -140.774167) (xy 240.907952 -140.77213) (xy 240.853109 -140.762) (xy 240.800325 -140.743993)
			(xy 240.750725 -140.718492) (xy 240.705367 -140.686041) (xy 240.665218 -140.647332) (xy 240.631132 -140.603189)
			(xy 240.603836 -140.554554) (xy 240.583913 -140.502463) (xy 240.571787 -140.448026) (xy 240.567716 -140.392404)
			(xy 225.399981 -140.392404) (xy 225.405727 -140.395911) (xy 225.448595 -140.431586) (xy 225.485812 -140.473123)
			(xy 225.516585 -140.519636) (xy 225.540257 -140.570133) (xy 225.556325 -140.62354) (xy 225.564445 -140.678716)
			(xy 225.564954 -140.706602) (xy 225.564445 -140.734488) (xy 225.556325 -140.789664) (xy 225.540257 -140.843071)
			(xy 225.516585 -140.893568) (xy 225.485812 -140.940081) (xy 225.448595 -140.981618) (xy 225.405727 -141.017293)
			(xy 225.358121 -141.046347) (xy 225.357641 -141.046551) (xy 242.955054 -141.046551) (xy 242.955054 -140.992049)
			(xy 242.96281 -140.938101) (xy 242.978164 -140.885806) (xy 243.000804 -140.836228) (xy 243.030269 -140.790376)
			(xy 243.065959 -140.749184) (xy 243.107147 -140.71349) (xy 243.152996 -140.684021) (xy 243.202572 -140.661377)
			(xy 243.254865 -140.646017) (xy 243.308813 -140.638256) (xy 243.336064 -140.637768) (xy 243.362379 -140.638203)
			(xy 243.414508 -140.645446) (xy 243.465151 -140.659772) (xy 243.51335 -140.680911) (xy 243.558193 -140.708462)
			(xy 243.598832 -140.741905) (xy 243.616988 -140.760958) (xy 243.624518 -140.76835) (xy 243.643791 -140.776881)
			(xy 243.654326 -140.777468) (xy 243.729002 -140.777468) (xy 243.739555 -140.776963) (xy 243.75885 -140.768412)
			(xy 243.76634 -140.760958) (xy 243.784475 -140.741882) (xy 243.82511 -140.708428) (xy 243.869955 -140.680873)
			(xy 243.91816 -140.659738) (xy 243.96881 -140.645425) (xy 244.020947 -140.638204) (xy 244.047264 -140.637768)
			(xy 244.074517 -140.638277) (xy 244.128468 -140.646029) (xy 244.180767 -140.661381) (xy 244.230349 -140.68402)
			(xy 244.276203 -140.713485) (xy 244.317398 -140.749177) (xy 244.353093 -140.790368) (xy 244.382563 -140.83622)
			(xy 244.405206 -140.885799) (xy 244.420563 -140.938097) (xy 244.428321 -140.992047) (xy 244.428321 -141.046553)
			(xy 244.420563 -141.100503) (xy 244.405206 -141.152801) (xy 244.382563 -141.20238) (xy 244.353093 -141.248232)
			(xy 244.317398 -141.289423) (xy 244.276203 -141.325115) (xy 244.230349 -141.35458) (xy 244.180767 -141.377219)
			(xy 244.128468 -141.392571) (xy 244.074517 -141.400323) (xy 244.047264 -141.400784) (xy 244.020949 -141.400346)
			(xy 243.968819 -141.393106) (xy 243.918176 -141.378781) (xy 243.869977 -141.357643) (xy 243.825134 -141.330092)
			(xy 243.784496 -141.296648) (xy 243.76634 -141.277594) (xy 243.758806 -141.270207) (xy 243.739535 -141.261675)
			(xy 243.729002 -141.261084) (xy 243.654326 -141.261084) (xy 243.643777 -141.261619) (xy 243.624482 -141.270151)
			(xy 243.616988 -141.277594) (xy 243.59883 -141.296647) (xy 243.558201 -141.330105) (xy 243.513361 -141.357664)
			(xy 243.465161 -141.378803) (xy 243.414514 -141.393121) (xy 243.36238 -141.400346) (xy 243.336064 -141.400784)
			(xy 243.308813 -141.400344) (xy 243.254865 -141.392583) (xy 243.202572 -141.377223) (xy 243.152996 -141.354579)
			(xy 243.107147 -141.32511) (xy 243.065959 -141.289416) (xy 243.030269 -141.248224) (xy 243.000804 -141.202372)
			(xy 242.978164 -141.152794) (xy 242.96281 -141.100499) (xy 242.955054 -141.046551) (xy 225.357641 -141.046551)
			(xy 225.306792 -141.068159) (xy 225.252835 -141.082265) (xy 225.197398 -141.088365) (xy 225.141664 -141.086328)
			(xy 225.086821 -141.076198) (xy 225.034037 -141.058191) (xy 224.984437 -141.03269) (xy 224.939079 -141.000239)
			(xy 224.89893 -140.96153) (xy 224.864844 -140.917387) (xy 224.837548 -140.868752) (xy 224.817625 -140.816661)
			(xy 224.805499 -140.762224) (xy 224.801428 -140.706602) (xy 223.397787 -140.706602) (xy 223.411394 -140.721789)
			(xy 223.442167 -140.768302) (xy 223.465839 -140.818799) (xy 223.481907 -140.872206) (xy 223.490027 -140.927382)
			(xy 223.490536 -140.955268) (xy 223.490027 -140.983154) (xy 223.481907 -141.03833) (xy 223.465839 -141.091737)
			(xy 223.442167 -141.142234) (xy 223.411394 -141.188747) (xy 223.374177 -141.230284) (xy 223.331309 -141.265959)
			(xy 223.283703 -141.295013) (xy 223.232374 -141.316825) (xy 223.178417 -141.330931) (xy 223.12298 -141.337031)
			(xy 223.067246 -141.334994) (xy 223.012403 -141.324864) (xy 222.959619 -141.306857) (xy 222.910019 -141.281356)
			(xy 222.864661 -141.248905) (xy 222.824512 -141.210196) (xy 222.790426 -141.166053) (xy 222.76313 -141.117418)
			(xy 222.743207 -141.065327) (xy 222.731081 -141.01089) (xy 222.72701 -140.955268) (xy 220.617791 -140.955268)
			(xy 220.614501 -140.977624) (xy 220.598433 -141.031031) (xy 220.574761 -141.081528) (xy 220.543988 -141.128041)
			(xy 220.506771 -141.169578) (xy 220.463903 -141.205253) (xy 220.416297 -141.234307) (xy 220.364968 -141.256119)
			(xy 220.311011 -141.270225) (xy 220.255574 -141.276325) (xy 220.19984 -141.274288) (xy 220.144997 -141.264158)
			(xy 220.092213 -141.246151) (xy 220.042613 -141.22065) (xy 219.997255 -141.188199) (xy 219.957106 -141.14949)
			(xy 219.92302 -141.105347) (xy 219.895724 -141.056712) (xy 219.875801 -141.004621) (xy 219.863675 -140.950184)
			(xy 219.859604 -140.894562) (xy 197.665633 -140.894562) (xy 197.661178 -140.896455) (xy 197.607221 -140.910561)
			(xy 197.551784 -140.916661) (xy 197.49605 -140.914624) (xy 197.441207 -140.904494) (xy 197.388423 -140.886487)
			(xy 197.338823 -140.860986) (xy 197.293465 -140.828535) (xy 197.253316 -140.789826) (xy 197.21923 -140.745683)
			(xy 197.191934 -140.697048) (xy 197.172011 -140.644957) (xy 197.159885 -140.59052) (xy 197.155814 -140.534898)
			(xy 196.795644 -140.534898) (xy 196.795644 -140.798042) (xy 196.795204 -140.838368) (xy 196.788603 -140.918749)
			(xy 196.77552 -140.998332) (xy 196.76618 -141.037564) (xy 196.76618 -141.038072) (xy 196.76491 -141.04366)
			(xy 196.674994 -141.430756) (xy 196.596455 -141.768322) (xy 231.849166 -141.768322) (xy 231.853237 -141.7127)
			(xy 231.865363 -141.658263) (xy 231.885286 -141.606172) (xy 231.912582 -141.557537) (xy 231.946668 -141.513394)
			(xy 231.986817 -141.474685) (xy 232.032175 -141.442234) (xy 232.081775 -141.416733) (xy 232.134559 -141.398726)
			(xy 232.189402 -141.388596) (xy 232.245136 -141.386559) (xy 232.300573 -141.392659) (xy 232.35453 -141.406765)
			(xy 232.405859 -141.428577) (xy 232.453465 -141.457631) (xy 232.496333 -141.493306) (xy 232.53355 -141.534843)
			(xy 232.564323 -141.581356) (xy 232.587995 -141.631853) (xy 232.590691 -141.640814) (xy 236.25124 -141.640814)
			(xy 236.255311 -141.585192) (xy 236.267437 -141.530755) (xy 236.28736 -141.478664) (xy 236.314656 -141.430029)
			(xy 236.348742 -141.385886) (xy 236.388891 -141.347177) (xy 236.434249 -141.314726) (xy 236.483849 -141.289225)
			(xy 236.536633 -141.271218) (xy 236.591476 -141.261088) (xy 236.64721 -141.259051) (xy 236.702647 -141.265151)
			(xy 236.756604 -141.279257) (xy 236.807933 -141.301069) (xy 236.855539 -141.330123) (xy 236.898407 -141.365798)
			(xy 236.935624 -141.407335) (xy 236.966397 -141.453848) (xy 236.990069 -141.504345) (xy 237.006137 -141.557752)
			(xy 237.014257 -141.612928) (xy 237.014766 -141.640814) (xy 237.014257 -141.6687) (xy 237.006137 -141.723876)
			(xy 236.990069 -141.777283) (xy 236.966397 -141.82778) (xy 236.935624 -141.874293) (xy 236.898407 -141.91583)
			(xy 236.855539 -141.951505) (xy 236.807933 -141.980559) (xy 236.756604 -142.002371) (xy 236.702647 -142.016477)
			(xy 236.64721 -142.022577) (xy 236.591476 -142.02054) (xy 236.536633 -142.01041) (xy 236.483849 -141.992403)
			(xy 236.434249 -141.966902) (xy 236.388891 -141.934451) (xy 236.348742 -141.895742) (xy 236.314656 -141.851599)
			(xy 236.28736 -141.802964) (xy 236.267437 -141.750873) (xy 236.255311 -141.696436) (xy 236.25124 -141.640814)
			(xy 232.590691 -141.640814) (xy 232.604063 -141.68526) (xy 232.612183 -141.740436) (xy 232.612692 -141.768322)
			(xy 232.612183 -141.796208) (xy 232.604063 -141.851384) (xy 232.587995 -141.904791) (xy 232.564323 -141.955288)
			(xy 232.53355 -142.001801) (xy 232.496333 -142.043338) (xy 232.453465 -142.079013) (xy 232.405859 -142.108067)
			(xy 232.35453 -142.129879) (xy 232.300573 -142.143985) (xy 232.245136 -142.150085) (xy 232.189402 -142.148048)
			(xy 232.134559 -142.137918) (xy 232.081775 -142.119911) (xy 232.032175 -142.09441) (xy 231.986817 -142.061959)
			(xy 231.946668 -142.02325) (xy 231.912582 -141.979107) (xy 231.885286 -141.930472) (xy 231.865363 -141.878381)
			(xy 231.853237 -141.823944) (xy 231.849166 -141.768322) (xy 196.596455 -141.768322) (xy 196.528436 -142.060676)
			(xy 196.527928 -142.065756) (xy 196.467625 -143.479266) (xy 197.174612 -143.479266) (xy 197.174612 -142.615666)
			(xy 197.175102 -142.585698) (xy 197.182925 -142.526276) (xy 197.198438 -142.468383) (xy 197.221374 -142.41301)
			(xy 197.251341 -142.361104) (xy 197.287828 -142.313554) (xy 197.330208 -142.271174) (xy 197.377758 -142.234687)
			(xy 197.429664 -142.20472) (xy 197.485037 -142.181784) (xy 197.54293 -142.166271) (xy 197.602352 -142.158448)
			(xy 197.662288 -142.158448) (xy 197.72171 -142.166271) (xy 197.779603 -142.181784) (xy 197.834976 -142.20472)
			(xy 197.886882 -142.234687) (xy 197.900095 -142.244826) (xy 228.06736 -142.244826) (xy 228.071431 -142.189204)
			(xy 228.083557 -142.134767) (xy 228.10348 -142.082676) (xy 228.130776 -142.034041) (xy 228.164862 -141.989898)
			(xy 228.205011 -141.951189) (xy 228.250369 -141.918738) (xy 228.299969 -141.893237) (xy 228.352753 -141.87523)
			(xy 228.407596 -141.8651) (xy 228.46333 -141.863063) (xy 228.518767 -141.869163) (xy 228.572724 -141.883269)
			(xy 228.624053 -141.905081) (xy 228.671659 -141.934135) (xy 228.714527 -141.96981) (xy 228.751744 -142.011347)
			(xy 228.782517 -142.05786) (xy 228.806189 -142.108357) (xy 228.822257 -142.161764) (xy 228.830377 -142.21694)
			(xy 228.830886 -142.244826) (xy 228.830399 -142.271496) (xy 230.464866 -142.271496) (xy 230.468937 -142.215874)
			(xy 230.481063 -142.161437) (xy 230.500986 -142.109346) (xy 230.528282 -142.060711) (xy 230.562368 -142.016568)
			(xy 230.602517 -141.977859) (xy 230.647875 -141.945408) (xy 230.697475 -141.919907) (xy 230.750259 -141.9019)
			(xy 230.805102 -141.89177) (xy 230.860836 -141.889733) (xy 230.916273 -141.895833) (xy 230.97023 -141.909939)
			(xy 231.021559 -141.931751) (xy 231.069165 -141.960805) (xy 231.112033 -141.99648) (xy 231.14925 -142.038017)
			(xy 231.180023 -142.08453) (xy 231.203695 -142.135027) (xy 231.219763 -142.188434) (xy 231.227883 -142.24361)
			(xy 231.228392 -142.271496) (xy 231.227883 -142.299382) (xy 231.219763 -142.354558) (xy 231.203695 -142.407965)
			(xy 231.180023 -142.458462) (xy 231.14925 -142.504975) (xy 231.112033 -142.546512) (xy 231.069165 -142.582187)
			(xy 231.021559 -142.611241) (xy 230.97023 -142.633053) (xy 230.940551 -142.640812) (xy 234.22305 -142.640812)
			(xy 234.227121 -142.58519) (xy 234.239247 -142.530753) (xy 234.25917 -142.478662) (xy 234.286466 -142.430027)
			(xy 234.320552 -142.385884) (xy 234.360701 -142.347175) (xy 234.406059 -142.314724) (xy 234.455659 -142.289223)
			(xy 234.508443 -142.271216) (xy 234.563286 -142.261086) (xy 234.61902 -142.259049) (xy 234.674457 -142.265149)
			(xy 234.728414 -142.279255) (xy 234.779743 -142.301067) (xy 234.827349 -142.330121) (xy 234.870217 -142.365796)
			(xy 234.907434 -142.407333) (xy 234.938207 -142.453846) (xy 234.961879 -142.504343) (xy 234.977947 -142.55775)
			(xy 234.986067 -142.612926) (xy 234.986576 -142.640812) (xy 234.986067 -142.668698) (xy 234.977947 -142.723874)
			(xy 234.961879 -142.777281) (xy 234.938207 -142.827778) (xy 234.907434 -142.874291) (xy 234.870217 -142.915828)
			(xy 234.827349 -142.951503) (xy 234.779743 -142.980557) (xy 234.728414 -143.002369) (xy 234.674457 -143.016475)
			(xy 234.61902 -143.022575) (xy 234.563286 -143.020538) (xy 234.508443 -143.010408) (xy 234.455659 -142.992401)
			(xy 234.406059 -142.9669) (xy 234.360701 -142.934449) (xy 234.320552 -142.89574) (xy 234.286466 -142.851597)
			(xy 234.25917 -142.802962) (xy 234.239247 -142.750871) (xy 234.227121 -142.696434) (xy 234.22305 -142.640812)
			(xy 230.940551 -142.640812) (xy 230.916273 -142.647159) (xy 230.860836 -142.653259) (xy 230.805102 -142.651222)
			(xy 230.750259 -142.641092) (xy 230.697475 -142.623085) (xy 230.647875 -142.597584) (xy 230.602517 -142.565133)
			(xy 230.562368 -142.526424) (xy 230.528282 -142.482281) (xy 230.500986 -142.433646) (xy 230.481063 -142.381555)
			(xy 230.468937 -142.327118) (xy 230.464866 -142.271496) (xy 228.830399 -142.271496) (xy 228.830377 -142.272712)
			(xy 228.822257 -142.327888) (xy 228.806189 -142.381295) (xy 228.782517 -142.431792) (xy 228.751744 -142.478305)
			(xy 228.714527 -142.519842) (xy 228.671659 -142.555517) (xy 228.624053 -142.584571) (xy 228.572724 -142.606383)
			(xy 228.518767 -142.620489) (xy 228.46333 -142.626589) (xy 228.407596 -142.624552) (xy 228.352753 -142.614422)
			(xy 228.299969 -142.596415) (xy 228.250369 -142.570914) (xy 228.205011 -142.538463) (xy 228.164862 -142.499754)
			(xy 228.130776 -142.455611) (xy 228.10348 -142.406976) (xy 228.083557 -142.354885) (xy 228.071431 -142.300448)
			(xy 228.06736 -142.244826) (xy 197.900095 -142.244826) (xy 197.934432 -142.271174) (xy 197.976812 -142.313554)
			(xy 198.013299 -142.361104) (xy 198.043266 -142.41301) (xy 198.066202 -142.468383) (xy 198.081715 -142.526276)
			(xy 198.089538 -142.585698) (xy 198.090028 -142.615666) (xy 198.090028 -143.078551) (xy 242.955054 -143.078551)
			(xy 242.955054 -143.024049) (xy 242.96281 -142.970101) (xy 242.978164 -142.917806) (xy 243.000804 -142.868228)
			(xy 243.030269 -142.822376) (xy 243.065959 -142.781184) (xy 243.107147 -142.74549) (xy 243.152996 -142.716021)
			(xy 243.202572 -142.693377) (xy 243.254865 -142.678017) (xy 243.308813 -142.670256) (xy 243.336064 -142.669768)
			(xy 243.362379 -142.670203) (xy 243.414508 -142.677446) (xy 243.465151 -142.691772) (xy 243.51335 -142.712911)
			(xy 243.558193 -142.740462) (xy 243.598832 -142.773905) (xy 243.616988 -142.792958) (xy 243.624518 -142.80035)
			(xy 243.643791 -142.808881) (xy 243.654326 -142.809468) (xy 243.729002 -142.809468) (xy 243.739555 -142.808963)
			(xy 243.75885 -142.800412) (xy 243.76634 -142.792958) (xy 243.784475 -142.773882) (xy 243.82511 -142.740428)
			(xy 243.869955 -142.712873) (xy 243.91816 -142.691738) (xy 243.96881 -142.677425) (xy 244.020947 -142.670204)
			(xy 244.047264 -142.669768) (xy 244.074517 -142.670277) (xy 244.128468 -142.678029) (xy 244.180767 -142.693381)
			(xy 244.230349 -142.71602) (xy 244.276203 -142.745485) (xy 244.317398 -142.781177) (xy 244.353093 -142.822368)
			(xy 244.382563 -142.86822) (xy 244.405206 -142.917799) (xy 244.420563 -142.970097) (xy 244.428321 -143.024047)
			(xy 244.428321 -143.078553) (xy 244.420563 -143.132503) (xy 244.405206 -143.184801) (xy 244.382563 -143.23438)
			(xy 244.353093 -143.280232) (xy 244.317398 -143.321423) (xy 244.276203 -143.357115) (xy 244.230349 -143.38658)
			(xy 244.180767 -143.409219) (xy 244.128468 -143.424571) (xy 244.074517 -143.432323) (xy 244.047264 -143.432784)
			(xy 244.020949 -143.432346) (xy 243.968819 -143.425106) (xy 243.918176 -143.410781) (xy 243.869977 -143.389643)
			(xy 243.825134 -143.362092) (xy 243.784496 -143.328648) (xy 243.76634 -143.309594) (xy 243.758806 -143.302207)
			(xy 243.739535 -143.293675) (xy 243.729002 -143.293084) (xy 243.654326 -143.293084) (xy 243.643777 -143.293619)
			(xy 243.624482 -143.302151) (xy 243.616988 -143.309594) (xy 243.59883 -143.328647) (xy 243.558201 -143.362105)
			(xy 243.513361 -143.389664) (xy 243.465161 -143.410803) (xy 243.414514 -143.425121) (xy 243.36238 -143.432346)
			(xy 243.336064 -143.432784) (xy 243.308813 -143.432344) (xy 243.254865 -143.424583) (xy 243.202572 -143.409223)
			(xy 243.152996 -143.386579) (xy 243.107147 -143.35711) (xy 243.065959 -143.321416) (xy 243.030269 -143.280224)
			(xy 243.000804 -143.234372) (xy 242.978164 -143.184794) (xy 242.96281 -143.132499) (xy 242.955054 -143.078551)
			(xy 198.090028 -143.078551) (xy 198.090028 -143.479266) (xy 198.089538 -143.509234) (xy 198.081715 -143.568656)
			(xy 198.066202 -143.626549) (xy 198.043266 -143.681922) (xy 198.013299 -143.733828) (xy 197.976812 -143.781378)
			(xy 197.934432 -143.823758) (xy 197.886882 -143.860245) (xy 197.834976 -143.890212) (xy 197.779603 -143.913148)
			(xy 197.72171 -143.928661) (xy 197.662288 -143.936484) (xy 197.602352 -143.936484) (xy 197.54293 -143.928661)
			(xy 197.485037 -143.913148) (xy 197.429664 -143.890212) (xy 197.377758 -143.860245) (xy 197.330208 -143.823758)
			(xy 197.287828 -143.781378) (xy 197.251341 -143.733828) (xy 197.221374 -143.681922) (xy 197.198438 -143.626549)
			(xy 197.182925 -143.568656) (xy 197.175102 -143.509234) (xy 197.174612 -143.479266) (xy 196.467625 -143.479266)
			(xy 196.447751 -143.945102) (xy 225.0219 -143.945102) (xy 225.025971 -143.88948) (xy 225.038097 -143.835043)
			(xy 225.05802 -143.782952) (xy 225.085316 -143.734317) (xy 225.119402 -143.690174) (xy 225.159551 -143.651465)
			(xy 225.204909 -143.619014) (xy 225.254509 -143.593513) (xy 225.307293 -143.575506) (xy 225.362136 -143.565376)
			(xy 225.41787 -143.563339) (xy 225.473307 -143.569439) (xy 225.527264 -143.583545) (xy 225.578593 -143.605357)
			(xy 225.626199 -143.634411) (xy 225.669067 -143.670086) (xy 225.706284 -143.711623) (xy 225.737057 -143.758136)
			(xy 225.760729 -143.808633) (xy 225.776797 -143.86204) (xy 225.784917 -143.917216) (xy 225.785426 -143.945102)
			(xy 225.785037 -143.966438) (xy 251.664216 -143.966438) (xy 251.664626 -143.940462) (xy 251.671676 -143.88899)
			(xy 251.685652 -143.838952) (xy 251.706293 -143.791276) (xy 251.733218 -143.746845) (xy 251.765928 -143.706483)
			(xy 251.803816 -143.670936) (xy 251.824744 -143.655542) (xy 251.834235 -143.64791) (xy 251.84538 -143.626298)
			(xy 251.84608 -143.61414) (xy 251.84608 -143.531336) (xy 251.845388 -143.519174) (xy 251.834248 -143.497553)
			(xy 251.824744 -143.489934) (xy 251.803825 -143.474531) (xy 251.765949 -143.438978) (xy 251.733248 -143.398614)
			(xy 251.70633 -143.354184) (xy 251.685691 -143.306511) (xy 251.671714 -143.256479) (xy 251.664658 -143.205012)
			(xy 251.664216 -143.179038) (xy 251.664724 -143.150299) (xy 251.673354 -143.093472) (xy 251.690409 -143.038582)
			(xy 251.715503 -142.98687) (xy 251.748069 -142.939507) (xy 251.76734 -142.91818) (xy 251.773944 -142.911322)
			(xy 251.781056 -142.893288) (xy 251.781056 -142.804388) (xy 251.773944 -142.786354) (xy 251.76734 -142.779496)
			(xy 251.748106 -142.758137) (xy 251.715538 -142.71078) (xy 251.690444 -142.659074) (xy 251.67339 -142.604188)
			(xy 251.664763 -142.547365) (xy 251.664759 -142.489891) (xy 251.673378 -142.433066) (xy 251.690423 -142.378178)
			(xy 251.71551 -142.326468) (xy 251.748071 -142.279106) (xy 251.76734 -142.25778) (xy 251.773944 -142.250922)
			(xy 251.781056 -142.232888) (xy 251.781056 -142.143988) (xy 251.773944 -142.125954) (xy 251.76734 -142.119096)
			(xy 251.748106 -142.097737) (xy 251.715538 -142.05038) (xy 251.690444 -141.998674) (xy 251.67339 -141.943788)
			(xy 251.664763 -141.886965) (xy 251.664759 -141.829491) (xy 251.673378 -141.772666) (xy 251.690423 -141.717778)
			(xy 251.71551 -141.666068) (xy 251.748071 -141.618706) (xy 251.76734 -141.59738) (xy 251.773944 -141.590522)
			(xy 251.781056 -141.572488) (xy 251.781056 -141.483588) (xy 251.773944 -141.465554) (xy 251.76734 -141.458696)
			(xy 251.748106 -141.437337) (xy 251.715538 -141.38998) (xy 251.690444 -141.338274) (xy 251.67339 -141.283388)
			(xy 251.664763 -141.226565) (xy 251.664759 -141.169091) (xy 251.673378 -141.112266) (xy 251.690423 -141.057378)
			(xy 251.71551 -141.005668) (xy 251.748071 -140.958306) (xy 251.76734 -140.93698) (xy 251.773944 -140.930122)
			(xy 251.781056 -140.912088) (xy 251.781056 -140.823188) (xy 251.773944 -140.805154) (xy 251.76734 -140.798296)
			(xy 251.748088 -140.776953) (xy 251.715519 -140.729595) (xy 251.690423 -140.677888) (xy 251.673368 -140.623001)
			(xy 251.66474 -140.566176) (xy 251.664216 -140.537438) (xy 251.664702 -140.510187) (xy 251.672458 -140.456239)
			(xy 251.687813 -140.403944) (xy 251.710455 -140.354367) (xy 251.739921 -140.308517) (xy 251.775612 -140.267326)
			(xy 251.816803 -140.231635) (xy 251.862653 -140.202169) (xy 251.91223 -140.179527) (xy 251.964525 -140.164172)
			(xy 252.018473 -140.156416) (xy 252.072975 -140.156416) (xy 252.126923 -140.164172) (xy 252.179218 -140.179527)
			(xy 252.228795 -140.202169) (xy 252.274645 -140.231635) (xy 252.315836 -140.267326) (xy 252.351527 -140.308517)
			(xy 252.380993 -140.354367) (xy 252.403635 -140.403944) (xy 252.41899 -140.456239) (xy 252.426746 -140.510187)
			(xy 252.427232 -140.537438) (xy 252.426723 -140.566177) (xy 252.418095 -140.623005) (xy 252.401041 -140.677896)
			(xy 252.375947 -140.729607) (xy 252.34338 -140.776969) (xy 252.324108 -140.798296) (xy 252.317504 -140.805154)
			(xy 252.310392 -140.823188) (xy 252.310392 -140.912088) (xy 252.317504 -140.930122) (xy 252.324108 -140.93698)
			(xy 252.343415 -140.958275) (xy 252.375976 -141.005644) (xy 252.401064 -141.057361) (xy 252.418109 -141.112256)
			(xy 252.426728 -141.169087) (xy 252.426724 -141.226568) (xy 252.418097 -141.283398) (xy 252.401043 -141.338291)
			(xy 252.375948 -141.390004) (xy 252.34338 -141.437368) (xy 252.324108 -141.458696) (xy 252.317504 -141.465554)
			(xy 252.310392 -141.483588) (xy 252.310392 -141.572488) (xy 252.317504 -141.590522) (xy 252.324108 -141.59738)
			(xy 252.343415 -141.618675) (xy 252.375976 -141.666044) (xy 252.401064 -141.717761) (xy 252.418109 -141.772656)
			(xy 252.426728 -141.829487) (xy 252.426724 -141.886968) (xy 252.418097 -141.943798) (xy 252.401043 -141.998691)
			(xy 252.375948 -142.050404) (xy 252.34338 -142.097768) (xy 252.324108 -142.119096) (xy 252.317504 -142.125954)
			(xy 252.310392 -142.143988) (xy 252.310392 -142.232888) (xy 252.317504 -142.250922) (xy 252.324108 -142.25778)
			(xy 252.343415 -142.279075) (xy 252.375976 -142.326444) (xy 252.401064 -142.378161) (xy 252.418109 -142.433056)
			(xy 252.426728 -142.489887) (xy 252.426724 -142.547368) (xy 252.418097 -142.604198) (xy 252.401043 -142.659091)
			(xy 252.375948 -142.710804) (xy 252.34338 -142.758168) (xy 252.324108 -142.779496) (xy 252.317504 -142.786354)
			(xy 252.310392 -142.804388) (xy 252.310392 -142.893288) (xy 252.317504 -142.911322) (xy 252.324108 -142.91818)
			(xy 252.343387 -142.9395) (xy 252.375954 -142.986863) (xy 252.401046 -143.038576) (xy 252.418094 -143.093469)
			(xy 252.426713 -143.150298) (xy 252.427232 -143.179038) (xy 252.426826 -143.205015) (xy 252.419777 -143.256488)
			(xy 252.405803 -143.306526) (xy 252.385161 -143.354203) (xy 252.358235 -143.398634) (xy 252.325524 -143.438996)
			(xy 252.287633 -143.474541) (xy 252.266704 -143.489934) (xy 252.257233 -143.497587) (xy 252.246075 -143.519183)
			(xy 252.245368 -143.531336) (xy 252.245368 -143.61414) (xy 252.246056 -143.626303) (xy 252.257197 -143.647925)
			(xy 252.266704 -143.655542) (xy 252.287622 -143.670946) (xy 252.325497 -143.7065) (xy 252.358195 -143.746865)
			(xy 252.385113 -143.791295) (xy 252.405752 -143.838966) (xy 252.41973 -143.888998) (xy 252.426789 -143.940464)
			(xy 252.427232 -143.966438) (xy 252.426746 -143.993689) (xy 252.41899 -144.047637) (xy 252.403635 -144.099932)
			(xy 252.380993 -144.149509) (xy 252.351527 -144.195359) (xy 252.315836 -144.23655) (xy 252.274645 -144.272241)
			(xy 252.228795 -144.301707) (xy 252.179218 -144.324349) (xy 252.126923 -144.339704) (xy 252.072975 -144.34746)
			(xy 252.018473 -144.34746) (xy 251.964525 -144.339704) (xy 251.91223 -144.324349) (xy 251.862653 -144.301707)
			(xy 251.816803 -144.272241) (xy 251.775612 -144.23655) (xy 251.739921 -144.195359) (xy 251.710455 -144.149509)
			(xy 251.687813 -144.099932) (xy 251.672458 -144.047637) (xy 251.664702 -143.993689) (xy 251.664216 -143.966438)
			(xy 225.785037 -143.966438) (xy 225.784917 -143.972988) (xy 225.776797 -144.028164) (xy 225.760729 -144.081571)
			(xy 225.737057 -144.132068) (xy 225.706284 -144.178581) (xy 225.669067 -144.220118) (xy 225.626199 -144.255793)
			(xy 225.578593 -144.284847) (xy 225.527264 -144.306659) (xy 225.473307 -144.320765) (xy 225.41787 -144.326865)
			(xy 225.362136 -144.324828) (xy 225.307293 -144.314698) (xy 225.254509 -144.296691) (xy 225.204909 -144.27119)
			(xy 225.159551 -144.238739) (xy 225.119402 -144.20003) (xy 225.085316 -144.155887) (xy 225.05802 -144.107252)
			(xy 225.038097 -144.055161) (xy 225.025971 -144.000724) (xy 225.0219 -143.945102) (xy 196.447751 -143.945102)
			(xy 196.390558 -145.285714) (xy 199.81672 -145.285714) (xy 199.81672 -144.422114) (xy 199.81721 -144.392146)
			(xy 199.825033 -144.332724) (xy 199.840546 -144.274831) (xy 199.863482 -144.219458) (xy 199.893449 -144.167552)
			(xy 199.929936 -144.120002) (xy 199.972316 -144.077622) (xy 200.019866 -144.041135) (xy 200.071772 -144.011168)
			(xy 200.127145 -143.988232) (xy 200.185038 -143.972719) (xy 200.24446 -143.964896) (xy 200.304396 -143.964896)
			(xy 200.363818 -143.972719) (xy 200.421711 -143.988232) (xy 200.477084 -144.011168) (xy 200.52899 -144.041135)
			(xy 200.57654 -144.077622) (xy 200.61892 -144.120002) (xy 200.655407 -144.167552) (xy 200.685374 -144.219458)
			(xy 200.70831 -144.274831) (xy 200.723823 -144.332724) (xy 200.731646 -144.392146) (xy 200.732136 -144.422114)
			(xy 200.732136 -144.672812) (xy 234.175044 -144.672812) (xy 234.179115 -144.61719) (xy 234.191241 -144.562753)
			(xy 234.211164 -144.510662) (xy 234.23846 -144.462027) (xy 234.272546 -144.417884) (xy 234.312695 -144.379175)
			(xy 234.358053 -144.346724) (xy 234.407653 -144.321223) (xy 234.460437 -144.303216) (xy 234.51528 -144.293086)
			(xy 234.571014 -144.291049) (xy 234.626451 -144.297149) (xy 234.680408 -144.311255) (xy 234.731737 -144.333067)
			(xy 234.779343 -144.362121) (xy 234.822211 -144.397796) (xy 234.859428 -144.439333) (xy 234.890201 -144.485846)
			(xy 234.913873 -144.536343) (xy 234.929941 -144.58975) (xy 234.938061 -144.644926) (xy 234.93857 -144.672812)
			(xy 236.25124 -144.672812) (xy 236.255311 -144.61719) (xy 236.267437 -144.562753) (xy 236.28736 -144.510662)
			(xy 236.314656 -144.462027) (xy 236.348742 -144.417884) (xy 236.388891 -144.379175) (xy 236.434249 -144.346724)
			(xy 236.483849 -144.321223) (xy 236.536633 -144.303216) (xy 236.591476 -144.293086) (xy 236.64721 -144.291049)
			(xy 236.702647 -144.297149) (xy 236.756604 -144.311255) (xy 236.807933 -144.333067) (xy 236.855539 -144.362121)
			(xy 236.898407 -144.397796) (xy 236.935624 -144.439333) (xy 236.966397 -144.485846) (xy 236.990069 -144.536343)
			(xy 237.006137 -144.58975) (xy 237.014257 -144.644926) (xy 237.014766 -144.672812) (xy 237.014257 -144.700698)
			(xy 237.006137 -144.755874) (xy 236.990069 -144.809281) (xy 236.966397 -144.859778) (xy 236.935624 -144.906291)
			(xy 236.898407 -144.947828) (xy 236.855539 -144.983503) (xy 236.807933 -145.012557) (xy 236.756604 -145.034369)
			(xy 236.702647 -145.048475) (xy 236.64721 -145.054575) (xy 236.591476 -145.052538) (xy 236.536633 -145.042408)
			(xy 236.483849 -145.024401) (xy 236.434249 -144.9989) (xy 236.388891 -144.966449) (xy 236.348742 -144.92774)
			(xy 236.314656 -144.883597) (xy 236.28736 -144.834962) (xy 236.267437 -144.782871) (xy 236.255311 -144.728434)
			(xy 236.25124 -144.672812) (xy 234.93857 -144.672812) (xy 234.938061 -144.700698) (xy 234.929941 -144.755874)
			(xy 234.913873 -144.809281) (xy 234.890201 -144.859778) (xy 234.859428 -144.906291) (xy 234.822211 -144.947828)
			(xy 234.779343 -144.983503) (xy 234.731737 -145.012557) (xy 234.680408 -145.034369) (xy 234.626451 -145.048475)
			(xy 234.571014 -145.054575) (xy 234.51528 -145.052538) (xy 234.460437 -145.042408) (xy 234.407653 -145.024401)
			(xy 234.358053 -144.9989) (xy 234.312695 -144.966449) (xy 234.272546 -144.92774) (xy 234.23846 -144.883597)
			(xy 234.211164 -144.834962) (xy 234.191241 -144.782871) (xy 234.179115 -144.728434) (xy 234.175044 -144.672812)
			(xy 200.732136 -144.672812) (xy 200.732136 -145.140426) (xy 222.363028 -145.140426) (xy 222.367099 -145.084804)
			(xy 222.379225 -145.030367) (xy 222.399148 -144.978276) (xy 222.426444 -144.929641) (xy 222.46053 -144.885498)
			(xy 222.500679 -144.846789) (xy 222.546037 -144.814338) (xy 222.595637 -144.788837) (xy 222.648421 -144.77083)
			(xy 222.703264 -144.7607) (xy 222.758998 -144.758663) (xy 222.814435 -144.764763) (xy 222.868392 -144.778869)
			(xy 222.919721 -144.800681) (xy 222.967327 -144.829735) (xy 223.010195 -144.86541) (xy 223.047412 -144.906947)
			(xy 223.078185 -144.95346) (xy 223.101857 -145.003957) (xy 223.117925 -145.057364) (xy 223.125752 -145.110551)
			(xy 242.955054 -145.110551) (xy 242.955054 -145.056049) (xy 242.96281 -145.002101) (xy 242.978164 -144.949806)
			(xy 243.000804 -144.900228) (xy 243.030269 -144.854376) (xy 243.065959 -144.813184) (xy 243.107147 -144.77749)
			(xy 243.152996 -144.748021) (xy 243.202572 -144.725377) (xy 243.254865 -144.710017) (xy 243.308813 -144.702256)
			(xy 243.336064 -144.701768) (xy 243.362379 -144.702203) (xy 243.414508 -144.709446) (xy 243.465151 -144.723772)
			(xy 243.51335 -144.744911) (xy 243.558193 -144.772462) (xy 243.598832 -144.805905) (xy 243.616988 -144.824958)
			(xy 243.624518 -144.83235) (xy 243.643791 -144.840881) (xy 243.654326 -144.841468) (xy 243.729002 -144.841468)
			(xy 243.739555 -144.840963) (xy 243.75885 -144.832412) (xy 243.76634 -144.824958) (xy 243.784475 -144.805882)
			(xy 243.82511 -144.772428) (xy 243.869955 -144.744873) (xy 243.91816 -144.723738) (xy 243.96881 -144.709425)
			(xy 244.020947 -144.702204) (xy 244.047264 -144.701768) (xy 244.074517 -144.702277) (xy 244.128468 -144.710029)
			(xy 244.180767 -144.725381) (xy 244.230349 -144.74802) (xy 244.276203 -144.777485) (xy 244.317398 -144.813177)
			(xy 244.353093 -144.854368) (xy 244.382563 -144.90022) (xy 244.405206 -144.949799) (xy 244.406511 -144.954244)
			(xy 250.138946 -144.954244) (xy 250.139519 -144.926996) (xy 250.147268 -144.873054) (xy 250.162616 -144.820764)
			(xy 250.185248 -144.77119) (xy 250.214706 -144.725341) (xy 250.250388 -144.684152) (xy 250.291569 -144.64846)
			(xy 250.337411 -144.618991) (xy 250.386979 -144.596347) (xy 250.439266 -144.580988) (xy 250.493206 -144.573225)
			(xy 250.520454 -144.572736) (xy 250.549228 -144.573258) (xy 250.606123 -144.581908) (xy 250.661074 -144.599005)
			(xy 250.712834 -144.624159) (xy 250.76023 -144.656801) (xy 250.781566 -144.676114) (xy 250.78944 -144.68348)
			(xy 250.809252 -144.690592) (xy 250.905518 -144.683226) (xy 250.924314 -144.67332) (xy 250.930918 -144.664938)
			(xy 250.949154 -144.642763) (xy 250.991086 -144.603551) (xy 251.03842 -144.571064) (xy 251.090085 -144.546034)
			(xy 251.144918 -144.529026) (xy 251.201679 -144.520423) (xy 251.230384 -144.519904) (xy 251.257637 -144.52037)
			(xy 251.311588 -144.528125) (xy 251.363887 -144.54348) (xy 251.413468 -144.566121) (xy 251.459322 -144.595589)
			(xy 251.500515 -144.631282) (xy 251.536209 -144.672475) (xy 251.565677 -144.718329) (xy 251.588319 -144.767909)
			(xy 251.603674 -144.820208) (xy 251.611429 -144.874159) (xy 251.611892 -144.901412) (xy 251.611444 -144.928315)
			(xy 251.603871 -144.981586) (xy 251.588889 -145.033265) (xy 251.566797 -145.082327) (xy 251.538032 -145.127799)
			(xy 251.503165 -145.16878) (xy 251.462887 -145.204457) (xy 251.440696 -145.219674) (xy 251.429774 -145.226786)
			(xy 251.417836 -145.249646) (xy 251.419868 -145.361914) (xy 251.432822 -145.384266) (xy 251.443998 -145.391124)
			(xy 251.467599 -145.406047) (xy 251.510551 -145.441725) (xy 251.547844 -145.483283) (xy 251.578682 -145.529833)
			(xy 251.602406 -145.58038) (xy 251.618508 -145.633846) (xy 251.626646 -145.689087) (xy 251.627132 -145.717006)
			(xy 251.626677 -145.744) (xy 251.61907 -145.797448) (xy 251.604009 -145.849292) (xy 251.581793 -145.898496)
			(xy 251.552867 -145.94408) (xy 251.535692 -145.96491) (xy 251.52858 -145.973038) (xy 251.522484 -145.993612)
			(xy 251.533406 -146.078956) (xy 251.535196 -146.089497) (xy 251.546239 -146.107781) (xy 251.554742 -146.114262)
			(xy 251.575947 -146.129649) (xy 251.614401 -146.16523) (xy 251.647622 -146.205741) (xy 251.674984 -146.250418)
			(xy 251.695972 -146.298421) (xy 251.71019 -146.348845) (xy 251.717371 -146.400741) (xy 251.71781 -146.426936)
			(xy 251.717324 -146.454187) (xy 251.709568 -146.508135) (xy 251.694213 -146.56043) (xy 251.671571 -146.610007)
			(xy 251.642105 -146.655857) (xy 251.606414 -146.697048) (xy 251.565223 -146.732739) (xy 251.519373 -146.762205)
			(xy 251.469796 -146.784847) (xy 251.417501 -146.800202) (xy 251.363553 -146.807958) (xy 251.309051 -146.807958)
			(xy 251.255103 -146.800202) (xy 251.202808 -146.784847) (xy 251.153231 -146.762205) (xy 251.107381 -146.732739)
			(xy 251.06619 -146.697048) (xy 251.030499 -146.655857) (xy 251.001033 -146.610007) (xy 250.978391 -146.56043)
			(xy 250.963036 -146.508135) (xy 250.95528 -146.454187) (xy 250.954794 -146.426936) (xy 250.955291 -146.399944)
			(xy 250.96289 -146.346498) (xy 250.977943 -146.294656) (xy 251.000149 -146.245451) (xy 251.029064 -146.199864)
			(xy 251.046234 -146.179032) (xy 251.053346 -146.170904) (xy 251.059442 -146.15033) (xy 251.04852 -146.064986)
			(xy 251.046749 -146.054441) (xy 251.035691 -146.036159) (xy 251.027184 -146.02968) (xy 251.002883 -146.012068)
			(xy 250.959624 -145.970472) (xy 250.941078 -145.946876) (xy 250.935236 -145.939002) (xy 250.91771 -145.928588)
			(xy 250.827286 -145.91538) (xy 250.807982 -145.920206) (xy 250.800108 -145.926048) (xy 250.799854 -145.926048)
			(xy 250.775111 -145.943553) (xy 250.721258 -145.971356) (xy 250.663686 -145.990292) (xy 250.603843 -145.999883)
			(xy 250.57354 -146.00047) (xy 250.546286 -146.000007) (xy 250.492333 -145.992255) (xy 250.440033 -145.976902)
			(xy 250.390451 -145.954261) (xy 250.344596 -145.924794) (xy 250.303401 -145.8891) (xy 250.267707 -145.847906)
			(xy 250.23824 -145.802051) (xy 250.215599 -145.752469) (xy 250.200246 -145.700168) (xy 250.192493 -145.646216)
			(xy 250.192032 -145.618962) (xy 250.192467 -145.592928) (xy 250.199559 -145.541345) (xy 250.213591 -145.491203)
			(xy 250.234305 -145.443433) (xy 250.261315 -145.398918) (xy 250.277376 -145.378424) (xy 250.283116 -145.370666)
			(xy 250.288858 -145.352256) (xy 250.288552 -145.34261) (xy 250.282202 -145.262854) (xy 250.273566 -145.245074)
			(xy 250.2662 -145.238724) (xy 250.246561 -145.220536) (xy 250.212035 -145.179632) (xy 250.183562 -145.134305)
			(xy 250.161703 -145.085445) (xy 250.146885 -145.034009) (xy 250.1394 -144.981008) (xy 250.138946 -144.954244)
			(xy 244.406511 -144.954244) (xy 244.420563 -145.002097) (xy 244.428321 -145.056047) (xy 244.428321 -145.110553)
			(xy 244.420563 -145.164503) (xy 244.405206 -145.216801) (xy 244.382563 -145.26638) (xy 244.353093 -145.312232)
			(xy 244.317398 -145.353423) (xy 244.276203 -145.389115) (xy 244.230349 -145.41858) (xy 244.180767 -145.441219)
			(xy 244.128468 -145.456571) (xy 244.074517 -145.464323) (xy 244.047264 -145.464784) (xy 244.020949 -145.464346)
			(xy 243.968819 -145.457106) (xy 243.918176 -145.442781) (xy 243.869977 -145.421643) (xy 243.825134 -145.394092)
			(xy 243.784496 -145.360648) (xy 243.76634 -145.341594) (xy 243.758806 -145.334207) (xy 243.739535 -145.325675)
			(xy 243.729002 -145.325084) (xy 243.654326 -145.325084) (xy 243.643777 -145.325619) (xy 243.624482 -145.334151)
			(xy 243.616988 -145.341594) (xy 243.59883 -145.360647) (xy 243.558201 -145.394105) (xy 243.513361 -145.421664)
			(xy 243.465161 -145.442803) (xy 243.414514 -145.457121) (xy 243.36238 -145.464346) (xy 243.336064 -145.464784)
			(xy 243.308813 -145.464344) (xy 243.254865 -145.456583) (xy 243.202572 -145.441223) (xy 243.152996 -145.418579)
			(xy 243.107147 -145.38911) (xy 243.065959 -145.353416) (xy 243.030269 -145.312224) (xy 243.000804 -145.266372)
			(xy 242.978164 -145.216794) (xy 242.96281 -145.164499) (xy 242.955054 -145.110551) (xy 223.125752 -145.110551)
			(xy 223.126045 -145.11254) (xy 223.126554 -145.140426) (xy 223.126045 -145.168312) (xy 223.117925 -145.223488)
			(xy 223.101857 -145.276895) (xy 223.078185 -145.327392) (xy 223.047412 -145.373905) (xy 223.010195 -145.415442)
			(xy 222.967327 -145.451117) (xy 222.919721 -145.480171) (xy 222.868392 -145.501983) (xy 222.814435 -145.516089)
			(xy 222.758998 -145.522189) (xy 222.703264 -145.520152) (xy 222.648421 -145.510022) (xy 222.595637 -145.492015)
			(xy 222.546037 -145.466514) (xy 222.500679 -145.434063) (xy 222.46053 -145.395354) (xy 222.426444 -145.351211)
			(xy 222.399148 -145.302576) (xy 222.379225 -145.250485) (xy 222.367099 -145.196048) (xy 222.363028 -145.140426)
			(xy 200.732136 -145.140426) (xy 200.732136 -145.285714) (xy 200.731646 -145.315682) (xy 200.723823 -145.375104)
			(xy 200.70831 -145.432997) (xy 200.685374 -145.48837) (xy 200.655407 -145.540276) (xy 200.61892 -145.587826)
			(xy 200.57654 -145.630206) (xy 200.52899 -145.666693) (xy 200.477084 -145.69666) (xy 200.421711 -145.719596)
			(xy 200.363818 -145.735109) (xy 200.304396 -145.742932) (xy 200.24446 -145.742932) (xy 200.185038 -145.735109)
			(xy 200.127145 -145.719596) (xy 200.071772 -145.69666) (xy 200.019866 -145.666693) (xy 199.972316 -145.630206)
			(xy 199.929936 -145.587826) (xy 199.893449 -145.540276) (xy 199.863482 -145.48837) (xy 199.840546 -145.432997)
			(xy 199.825033 -145.375104) (xy 199.81721 -145.315682) (xy 199.81672 -145.285714) (xy 196.390558 -145.285714)
			(xy 196.362828 -145.9357) (xy 196.34708 -146.302984) (xy 196.346826 -146.30908) (xy 196.346826 -146.309588)
			(xy 196.34454 -146.342354) (xy 196.283917 -147.079208) (xy 197.174612 -147.079208) (xy 197.174612 -146.215608)
			(xy 197.175102 -146.18564) (xy 197.182925 -146.126218) (xy 197.198438 -146.068325) (xy 197.221374 -146.012952)
			(xy 197.251341 -145.961046) (xy 197.287828 -145.913496) (xy 197.330208 -145.871116) (xy 197.377758 -145.834629)
			(xy 197.429664 -145.804662) (xy 197.485037 -145.781726) (xy 197.54293 -145.766213) (xy 197.602352 -145.75839)
			(xy 197.662288 -145.75839) (xy 197.72171 -145.766213) (xy 197.779603 -145.781726) (xy 197.834976 -145.804662)
			(xy 197.886882 -145.834629) (xy 197.934432 -145.871116) (xy 197.976812 -145.913496) (xy 198.013299 -145.961046)
			(xy 198.021102 -145.974562) (xy 219.859604 -145.974562) (xy 219.863675 -145.91894) (xy 219.875801 -145.864503)
			(xy 219.895724 -145.812412) (xy 219.92302 -145.763777) (xy 219.957106 -145.719634) (xy 219.997255 -145.680925)
			(xy 220.042613 -145.648474) (xy 220.092213 -145.622973) (xy 220.144997 -145.604966) (xy 220.19984 -145.594836)
			(xy 220.255574 -145.592799) (xy 220.311011 -145.598899) (xy 220.364968 -145.613005) (xy 220.416297 -145.634817)
			(xy 220.463903 -145.663871) (xy 220.493873 -145.688812) (xy 236.25124 -145.688812) (xy 236.255311 -145.63319)
			(xy 236.267437 -145.578753) (xy 236.28736 -145.526662) (xy 236.314656 -145.478027) (xy 236.348742 -145.433884)
			(xy 236.388891 -145.395175) (xy 236.434249 -145.362724) (xy 236.483849 -145.337223) (xy 236.536633 -145.319216)
			(xy 236.591476 -145.309086) (xy 236.64721 -145.307049) (xy 236.702647 -145.313149) (xy 236.756604 -145.327255)
			(xy 236.807933 -145.349067) (xy 236.855539 -145.378121) (xy 236.898407 -145.413796) (xy 236.935624 -145.455333)
			(xy 236.966397 -145.501846) (xy 236.990069 -145.552343) (xy 237.006137 -145.60575) (xy 237.014257 -145.660926)
			(xy 237.014766 -145.688812) (xy 237.014257 -145.716698) (xy 237.006137 -145.771874) (xy 236.990069 -145.825281)
			(xy 236.966397 -145.875778) (xy 236.935624 -145.922291) (xy 236.898407 -145.963828) (xy 236.855539 -145.999503)
			(xy 236.807933 -146.028557) (xy 236.756604 -146.050369) (xy 236.702647 -146.064475) (xy 236.64721 -146.070575)
			(xy 236.591476 -146.068538) (xy 236.536633 -146.058408) (xy 236.483849 -146.040401) (xy 236.434249 -146.0149)
			(xy 236.388891 -145.982449) (xy 236.348742 -145.94374) (xy 236.314656 -145.899597) (xy 236.28736 -145.850962)
			(xy 236.267437 -145.798871) (xy 236.255311 -145.744434) (xy 236.25124 -145.688812) (xy 220.493873 -145.688812)
			(xy 220.506771 -145.699546) (xy 220.543988 -145.741083) (xy 220.574761 -145.787596) (xy 220.598433 -145.838093)
			(xy 220.614501 -145.8915) (xy 220.622621 -145.946676) (xy 220.62313 -145.974562) (xy 220.622621 -146.002448)
			(xy 220.614501 -146.057624) (xy 220.598433 -146.111031) (xy 220.574761 -146.161528) (xy 220.543988 -146.208041)
			(xy 220.506771 -146.249578) (xy 220.463903 -146.285253) (xy 220.416297 -146.314307) (xy 220.364968 -146.336119)
			(xy 220.311011 -146.350225) (xy 220.255574 -146.356325) (xy 220.19984 -146.354288) (xy 220.144997 -146.344158)
			(xy 220.092213 -146.326151) (xy 220.042613 -146.30065) (xy 219.997255 -146.268199) (xy 219.957106 -146.22949)
			(xy 219.92302 -146.185347) (xy 219.895724 -146.136712) (xy 219.875801 -146.084621) (xy 219.863675 -146.030184)
			(xy 219.859604 -145.974562) (xy 198.021102 -145.974562) (xy 198.043266 -146.012952) (xy 198.066202 -146.068325)
			(xy 198.081715 -146.126218) (xy 198.089538 -146.18564) (xy 198.090028 -146.215608) (xy 198.090028 -146.990562)
			(xy 221.941642 -146.990562) (xy 221.945713 -146.93494) (xy 221.957839 -146.880503) (xy 221.977762 -146.828412)
			(xy 222.005058 -146.779777) (xy 222.039144 -146.735634) (xy 222.079293 -146.696925) (xy 222.124651 -146.664474)
			(xy 222.174251 -146.638973) (xy 222.227035 -146.620966) (xy 222.281878 -146.610836) (xy 222.337612 -146.608799)
			(xy 222.393049 -146.614899) (xy 222.447006 -146.629005) (xy 222.48852 -146.646646) (xy 223.425256 -146.646646)
			(xy 223.429327 -146.591024) (xy 223.441453 -146.536587) (xy 223.461376 -146.484496) (xy 223.488672 -146.435861)
			(xy 223.522758 -146.391718) (xy 223.562907 -146.353009) (xy 223.608265 -146.320558) (xy 223.657865 -146.295057)
			(xy 223.710649 -146.27705) (xy 223.765492 -146.26692) (xy 223.821226 -146.264883) (xy 223.876663 -146.270983)
			(xy 223.93062 -146.285089) (xy 223.981949 -146.306901) (xy 224.029555 -146.335955) (xy 224.072423 -146.37163)
			(xy 224.10964 -146.413167) (xy 224.140413 -146.45968) (xy 224.164085 -146.510177) (xy 224.180153 -146.563584)
			(xy 224.188273 -146.61876) (xy 224.188782 -146.646646) (xy 224.188273 -146.674532) (xy 224.180153 -146.729708)
			(xy 224.164085 -146.783115) (xy 224.140413 -146.833612) (xy 224.10964 -146.880125) (xy 224.072423 -146.921662)
			(xy 224.029555 -146.957337) (xy 223.981949 -146.986391) (xy 223.93062 -147.008203) (xy 223.876663 -147.022309)
			(xy 223.821226 -147.028409) (xy 223.765492 -147.026372) (xy 223.710649 -147.016242) (xy 223.657865 -146.998235)
			(xy 223.608265 -146.972734) (xy 223.562907 -146.940283) (xy 223.522758 -146.901574) (xy 223.488672 -146.857431)
			(xy 223.461376 -146.808796) (xy 223.441453 -146.756705) (xy 223.429327 -146.702268) (xy 223.425256 -146.646646)
			(xy 222.48852 -146.646646) (xy 222.498335 -146.650817) (xy 222.545941 -146.679871) (xy 222.588809 -146.715546)
			(xy 222.626026 -146.757083) (xy 222.656799 -146.803596) (xy 222.680471 -146.854093) (xy 222.696539 -146.9075)
			(xy 222.704659 -146.962676) (xy 222.705168 -146.990562) (xy 222.704659 -147.018448) (xy 222.696539 -147.073624)
			(xy 222.680471 -147.127031) (xy 222.656799 -147.177528) (xy 222.649045 -147.189248) (xy 233.05469 -147.189248)
			(xy 233.05469 -147.134752) (xy 233.062445 -147.08081) (xy 233.077797 -147.028521) (xy 233.100434 -146.978948)
			(xy 233.129895 -146.933102) (xy 233.16558 -146.891914) (xy 233.206763 -146.856224) (xy 233.252606 -146.826757)
			(xy 233.302176 -146.804114) (xy 233.354463 -146.788755) (xy 233.408404 -146.780994) (xy 233.435652 -146.780504)
			(xy 233.467273 -146.781113) (xy 233.529646 -146.791567) (xy 233.589436 -146.812179) (xy 233.617516 -146.826732)
			(xy 233.625869 -146.830746) (xy 233.644237 -146.833091) (xy 233.65333 -146.831304) (xy 233.728514 -146.813524)
			(xy 233.744262 -146.802856) (xy 233.749342 -146.795236) (xy 233.764731 -146.773932) (xy 233.80036 -146.735302)
			(xy 233.840952 -146.701925) (xy 233.885739 -146.674433) (xy 233.933874 -146.653344) (xy 233.984447 -146.639058)
			(xy 234.036502 -146.631846) (xy 234.062778 -146.631406) (xy 234.090033 -146.631839) (xy 234.143988 -146.639594)
			(xy 234.196291 -146.654949) (xy 234.245876 -146.677591) (xy 234.288236 -146.704812) (xy 236.25124 -146.704812)
			(xy 236.255311 -146.64919) (xy 236.267437 -146.594753) (xy 236.28736 -146.542662) (xy 236.314656 -146.494027)
			(xy 236.348742 -146.449884) (xy 236.388891 -146.411175) (xy 236.434249 -146.378724) (xy 236.483849 -146.353223)
			(xy 236.536633 -146.335216) (xy 236.591476 -146.325086) (xy 236.64721 -146.323049) (xy 236.702647 -146.329149)
			(xy 236.756604 -146.343255) (xy 236.807933 -146.365067) (xy 236.855539 -146.394121) (xy 236.898407 -146.429796)
			(xy 236.935624 -146.471333) (xy 236.966397 -146.517846) (xy 236.990069 -146.568343) (xy 237.006137 -146.62175)
			(xy 237.014257 -146.676926) (xy 237.014766 -146.704812) (xy 237.014257 -146.732698) (xy 237.006137 -146.787874)
			(xy 236.990069 -146.841281) (xy 236.966397 -146.891778) (xy 236.951119 -146.91487) (xy 251.816106 -146.91487)
			(xy 251.820177 -146.859248) (xy 251.832303 -146.804811) (xy 251.852226 -146.75272) (xy 251.879522 -146.704085)
			(xy 251.913608 -146.659942) (xy 251.953757 -146.621233) (xy 251.999115 -146.588782) (xy 252.048715 -146.563281)
			(xy 252.101499 -146.545274) (xy 252.156342 -146.535144) (xy 252.212076 -146.533107) (xy 252.267513 -146.539207)
			(xy 252.32147 -146.553313) (xy 252.372799 -146.575125) (xy 252.420405 -146.604179) (xy 252.463273 -146.639854)
			(xy 252.50049 -146.681391) (xy 252.531263 -146.727904) (xy 252.554935 -146.778401) (xy 252.571003 -146.831808)
			(xy 252.579123 -146.886984) (xy 252.579632 -146.91487) (xy 252.579123 -146.942756) (xy 252.571003 -146.997932)
			(xy 252.554935 -147.051339) (xy 252.549729 -147.062444) (xy 253.19431 -147.062444) (xy 253.198381 -147.006822)
			(xy 253.210507 -146.952385) (xy 253.23043 -146.900294) (xy 253.257726 -146.851659) (xy 253.291812 -146.807516)
			(xy 253.331961 -146.768807) (xy 253.377319 -146.736356) (xy 253.426919 -146.710855) (xy 253.479703 -146.692848)
			(xy 253.534546 -146.682718) (xy 253.59028 -146.680681) (xy 253.645717 -146.686781) (xy 253.699674 -146.700887)
			(xy 253.751003 -146.722699) (xy 253.798609 -146.751753) (xy 253.841477 -146.787428) (xy 253.878694 -146.828965)
			(xy 253.909467 -146.875478) (xy 253.933139 -146.925975) (xy 253.949207 -146.979382) (xy 253.957327 -147.034558)
			(xy 253.957836 -147.062444) (xy 253.957327 -147.09033) (xy 253.949207 -147.145506) (xy 253.933139 -147.198913)
			(xy 253.909467 -147.24941) (xy 253.878694 -147.295923) (xy 253.841477 -147.33746) (xy 253.798609 -147.373135)
			(xy 253.751003 -147.402189) (xy 253.699674 -147.424001) (xy 253.645717 -147.438107) (xy 253.59028 -147.444207)
			(xy 253.534546 -147.44217) (xy 253.479703 -147.43204) (xy 253.426919 -147.414033) (xy 253.377319 -147.388532)
			(xy 253.331961 -147.356081) (xy 253.291812 -147.317372) (xy 253.257726 -147.273229) (xy 253.23043 -147.224594)
			(xy 253.210507 -147.172503) (xy 253.198381 -147.118066) (xy 253.19431 -147.062444) (xy 252.549729 -147.062444)
			(xy 252.531263 -147.101836) (xy 252.50049 -147.148349) (xy 252.463273 -147.189886) (xy 252.420405 -147.225561)
			(xy 252.372799 -147.254615) (xy 252.32147 -147.276427) (xy 252.267513 -147.290533) (xy 252.212076 -147.296633)
			(xy 252.156342 -147.294596) (xy 252.101499 -147.284466) (xy 252.048715 -147.266459) (xy 251.999115 -147.240958)
			(xy 251.953757 -147.208507) (xy 251.913608 -147.169798) (xy 251.879522 -147.125655) (xy 251.852226 -147.07702)
			(xy 251.832303 -147.024929) (xy 251.820177 -146.970492) (xy 251.816106 -146.91487) (xy 236.951119 -146.91487)
			(xy 236.935624 -146.938291) (xy 236.898407 -146.979828) (xy 236.855539 -147.015503) (xy 236.807933 -147.044557)
			(xy 236.756604 -147.066369) (xy 236.702647 -147.080475) (xy 236.64721 -147.086575) (xy 236.591476 -147.084538)
			(xy 236.536633 -147.074408) (xy 236.483849 -147.056401) (xy 236.434249 -147.0309) (xy 236.388891 -146.998449)
			(xy 236.348742 -146.95974) (xy 236.314656 -146.915597) (xy 236.28736 -146.866962) (xy 236.267437 -146.814871)
			(xy 236.255311 -146.760434) (xy 236.25124 -146.704812) (xy 234.288236 -146.704812) (xy 234.291733 -146.707059)
			(xy 234.33293 -146.742754) (xy 234.368627 -146.783949) (xy 234.398099 -146.829805) (xy 234.420743 -146.879389)
			(xy 234.436101 -146.93169) (xy 234.443859 -146.985645) (xy 234.443859 -147.040155) (xy 234.436101 -147.09411)
			(xy 234.420743 -147.146411) (xy 234.398099 -147.195995) (xy 234.368627 -147.241851) (xy 234.33293 -147.283046)
			(xy 234.291733 -147.318741) (xy 234.245876 -147.348209) (xy 234.196291 -147.370851) (xy 234.143988 -147.386206)
			(xy 234.090033 -147.393961) (xy 234.062778 -147.394422) (xy 234.031157 -147.393809) (xy 233.968784 -147.383359)
			(xy 233.908994 -147.362748) (xy 233.880914 -147.348194) (xy 233.872555 -147.344195) (xy 233.854192 -147.34184)
			(xy 233.8451 -147.343622) (xy 233.769916 -147.361402) (xy 233.754168 -147.37207) (xy 233.749088 -147.37969)
			(xy 233.733751 -147.401032) (xy 233.698112 -147.43966) (xy 233.657511 -147.473033) (xy 233.612715 -147.500521)
			(xy 233.564572 -147.521603) (xy 233.513991 -147.535881) (xy 233.461931 -147.543085) (xy 233.435652 -147.54352)
			(xy 233.408404 -147.543006) (xy 233.354463 -147.535245) (xy 233.302176 -147.519886) (xy 233.252606 -147.497243)
			(xy 233.206763 -147.467776) (xy 233.16558 -147.432086) (xy 233.129895 -147.390898) (xy 233.100434 -147.345052)
			(xy 233.077797 -147.295479) (xy 233.062445 -147.24319) (xy 233.05469 -147.189248) (xy 222.649045 -147.189248)
			(xy 222.626026 -147.224041) (xy 222.588809 -147.265578) (xy 222.545941 -147.301253) (xy 222.498335 -147.330307)
			(xy 222.447006 -147.352119) (xy 222.393049 -147.366225) (xy 222.337612 -147.372325) (xy 222.281878 -147.370288)
			(xy 222.227035 -147.360158) (xy 222.174251 -147.342151) (xy 222.124651 -147.31665) (xy 222.079293 -147.284199)
			(xy 222.039144 -147.24549) (xy 222.005058 -147.201347) (xy 221.977762 -147.152712) (xy 221.957839 -147.100621)
			(xy 221.945713 -147.046184) (xy 221.941642 -146.990562) (xy 198.090028 -146.990562) (xy 198.090028 -147.079208)
			(xy 198.089538 -147.109176) (xy 198.081715 -147.168598) (xy 198.066202 -147.226491) (xy 198.043266 -147.281864)
			(xy 198.013299 -147.33377) (xy 197.976812 -147.38132) (xy 197.934432 -147.4237) (xy 197.886882 -147.460187)
			(xy 197.834976 -147.490154) (xy 197.779603 -147.51309) (xy 197.72171 -147.528603) (xy 197.662288 -147.536426)
			(xy 197.602352 -147.536426) (xy 197.54293 -147.528603) (xy 197.485037 -147.51309) (xy 197.429664 -147.490154)
			(xy 197.377758 -147.460187) (xy 197.330208 -147.4237) (xy 197.287828 -147.38132) (xy 197.251341 -147.33377)
			(xy 197.221374 -147.281864) (xy 197.198438 -147.226491) (xy 197.182925 -147.168598) (xy 197.175102 -147.109176)
			(xy 197.174612 -147.079208) (xy 196.283917 -147.079208) (xy 196.135274 -148.88591) (xy 199.81672 -148.88591)
			(xy 199.81672 -148.02231) (xy 199.81721 -147.992342) (xy 199.825033 -147.93292) (xy 199.840546 -147.875027)
			(xy 199.863482 -147.819654) (xy 199.893449 -147.767748) (xy 199.929936 -147.720198) (xy 199.972316 -147.677818)
			(xy 200.019866 -147.641331) (xy 200.071772 -147.611364) (xy 200.127145 -147.588428) (xy 200.185038 -147.572915)
			(xy 200.24446 -147.565092) (xy 200.304396 -147.565092) (xy 200.363818 -147.572915) (xy 200.421711 -147.588428)
			(xy 200.477084 -147.611364) (xy 200.52899 -147.641331) (xy 200.57654 -147.677818) (xy 200.61892 -147.720198)
			(xy 200.619391 -147.720812) (xy 234.212128 -147.720812) (xy 234.216199 -147.66519) (xy 234.228325 -147.610753)
			(xy 234.248248 -147.558662) (xy 234.275544 -147.510027) (xy 234.30963 -147.465884) (xy 234.349779 -147.427175)
			(xy 234.395137 -147.394724) (xy 234.444737 -147.369223) (xy 234.497521 -147.351216) (xy 234.552364 -147.341086)
			(xy 234.608098 -147.339049) (xy 234.663535 -147.345149) (xy 234.717492 -147.359255) (xy 234.768821 -147.381067)
			(xy 234.816427 -147.410121) (xy 234.859295 -147.445796) (xy 234.896512 -147.487333) (xy 234.927285 -147.533846)
			(xy 234.950957 -147.584343) (xy 234.967025 -147.63775) (xy 234.975145 -147.692926) (xy 234.975654 -147.720812)
			(xy 236.25124 -147.720812) (xy 236.255311 -147.66519) (xy 236.267437 -147.610753) (xy 236.28736 -147.558662)
			(xy 236.314656 -147.510027) (xy 236.348742 -147.465884) (xy 236.388891 -147.427175) (xy 236.434249 -147.394724)
			(xy 236.483849 -147.369223) (xy 236.536633 -147.351216) (xy 236.591476 -147.341086) (xy 236.64721 -147.339049)
			(xy 236.702647 -147.345149) (xy 236.756604 -147.359255) (xy 236.807933 -147.381067) (xy 236.855539 -147.410121)
			(xy 236.898407 -147.445796) (xy 236.935624 -147.487333) (xy 236.966397 -147.533846) (xy 236.990069 -147.584343)
			(xy 237.006137 -147.63775) (xy 237.009066 -147.657656) (xy 243.350443 -147.657656) (xy 243.350443 -147.603144)
			(xy 243.358201 -147.549188) (xy 243.37356 -147.496885) (xy 243.396206 -147.447301) (xy 243.425679 -147.401444)
			(xy 243.461379 -147.360249) (xy 243.502578 -147.324554) (xy 243.548437 -147.295086) (xy 243.598024 -147.272445)
			(xy 243.650329 -147.257092) (xy 243.704286 -147.24934) (xy 243.731542 -147.24888) (xy 243.757857 -147.249326)
			(xy 243.809986 -147.256566) (xy 243.860629 -147.27089) (xy 243.908827 -147.292026) (xy 243.95367 -147.319576)
			(xy 243.99431 -147.353017) (xy 244.012466 -147.37207) (xy 244.020002 -147.379454) (xy 244.039271 -147.38799)
			(xy 244.049804 -147.38858) (xy 244.12448 -147.38858) (xy 244.135031 -147.38806) (xy 244.154327 -147.379519)
			(xy 244.161818 -147.37207) (xy 244.181638 -147.351282) (xy 244.22641 -147.315307) (xy 244.276068 -147.286447)
			(xy 244.32949 -147.265354) (xy 244.385469 -147.252505) (xy 244.442742 -147.24819) (xy 244.500015 -147.252505)
			(xy 244.555994 -147.265354) (xy 244.609416 -147.286447) (xy 244.659074 -147.315307) (xy 244.703846 -147.351282)
			(xy 244.723666 -147.37207) (xy 244.731202 -147.379454) (xy 244.750471 -147.38799) (xy 244.761004 -147.38858)
			(xy 244.83568 -147.38858) (xy 244.846231 -147.38806) (xy 244.865527 -147.379519) (xy 244.873018 -147.37207)
			(xy 244.891166 -147.353007) (xy 244.931798 -147.319552) (xy 244.97664 -147.291994) (xy 245.024842 -147.270857)
			(xy 245.075491 -147.256542) (xy 245.127626 -147.249318) (xy 245.153942 -147.24888) (xy 245.18119 -147.249393)
			(xy 245.235132 -147.257154) (xy 245.28742 -147.272512) (xy 245.33699 -147.295155) (xy 245.382834 -147.324622)
			(xy 245.424018 -147.360312) (xy 245.459703 -147.4015) (xy 245.489165 -147.447347) (xy 245.511802 -147.49692)
			(xy 245.527155 -147.549209) (xy 245.53491 -147.603152) (xy 245.53491 -147.657648) (xy 245.527155 -147.711591)
			(xy 245.511802 -147.76388) (xy 245.489165 -147.813453) (xy 245.459703 -147.8593) (xy 245.424018 -147.900488)
			(xy 245.382834 -147.936178) (xy 245.33699 -147.965645) (xy 245.28742 -147.988288) (xy 245.235132 -148.003646)
			(xy 245.18119 -148.011407) (xy 245.153942 -148.011896) (xy 245.127627 -148.011469) (xy 245.075496 -148.004226)
			(xy 245.024853 -147.989899) (xy 244.976654 -147.968759) (xy 244.931811 -147.941206) (xy 244.891174 -147.907761)
			(xy 244.873018 -147.888706) (xy 244.865491 -147.881311) (xy 244.846215 -147.872783) (xy 244.83568 -147.872196)
			(xy 244.761004 -147.872196) (xy 244.750453 -147.872715) (xy 244.731158 -147.881257) (xy 244.723666 -147.888706)
			(xy 244.703846 -147.909494) (xy 244.659074 -147.945469) (xy 244.609416 -147.974329) (xy 244.555994 -147.995422)
			(xy 244.500015 -148.008271) (xy 244.442742 -148.012586) (xy 244.385469 -148.008271) (xy 244.32949 -147.995422)
			(xy 244.276068 -147.974329) (xy 244.22641 -147.945469) (xy 244.181638 -147.909494) (xy 244.161818 -147.888706)
			(xy 244.154291 -147.881311) (xy 244.135015 -147.872783) (xy 244.12448 -147.872196) (xy 244.049804 -147.872196)
			(xy 244.039253 -147.872715) (xy 244.019958 -147.881257) (xy 244.012466 -147.888706) (xy 243.994321 -147.907772)
			(xy 243.953689 -147.941228) (xy 243.908846 -147.968786) (xy 243.860644 -147.989922) (xy 243.809994 -148.004237)
			(xy 243.757859 -148.011459) (xy 243.731542 -148.011896) (xy 243.704286 -148.01146) (xy 243.650329 -148.003708)
			(xy 243.598024 -147.988355) (xy 243.548437 -147.965714) (xy 243.502578 -147.936246) (xy 243.461379 -147.900551)
			(xy 243.425679 -147.859356) (xy 243.396206 -147.813499) (xy 243.37356 -147.763915) (xy 243.358201 -147.711612)
			(xy 243.350443 -147.657656) (xy 237.009066 -147.657656) (xy 237.014257 -147.692926) (xy 237.014766 -147.720812)
			(xy 237.014257 -147.748698) (xy 237.006137 -147.803874) (xy 236.990069 -147.857281) (xy 236.966397 -147.907778)
			(xy 236.935624 -147.954291) (xy 236.898407 -147.995828) (xy 236.872079 -148.017738) (xy 248.177556 -148.017738)
			(xy 248.181627 -147.962116) (xy 248.193753 -147.907679) (xy 248.213676 -147.855588) (xy 248.240972 -147.806953)
			(xy 248.275058 -147.76281) (xy 248.315207 -147.724101) (xy 248.360565 -147.69165) (xy 248.410165 -147.666149)
			(xy 248.462949 -147.648142) (xy 248.517792 -147.638012) (xy 248.573526 -147.635975) (xy 248.628963 -147.642075)
			(xy 248.68292 -147.656181) (xy 248.734249 -147.677993) (xy 248.781855 -147.707047) (xy 248.823118 -147.741386)
			(xy 254.081532 -147.741386) (xy 254.085603 -147.685764) (xy 254.097729 -147.631327) (xy 254.117652 -147.579236)
			(xy 254.144948 -147.530601) (xy 254.179034 -147.486458) (xy 254.219183 -147.447749) (xy 254.264541 -147.415298)
			(xy 254.314141 -147.389797) (xy 254.366925 -147.37179) (xy 254.421768 -147.36166) (xy 254.477502 -147.359623)
			(xy 254.532939 -147.365723) (xy 254.586896 -147.379829) (xy 254.638225 -147.401641) (xy 254.685831 -147.430695)
			(xy 254.728699 -147.46637) (xy 254.765916 -147.507907) (xy 254.796689 -147.55442) (xy 254.820361 -147.604917)
			(xy 254.836429 -147.658324) (xy 254.844549 -147.7135) (xy 254.845058 -147.741386) (xy 254.844549 -147.769272)
			(xy 254.836429 -147.824448) (xy 254.820361 -147.877855) (xy 254.796689 -147.928352) (xy 254.765916 -147.974865)
			(xy 254.728699 -148.016402) (xy 254.685831 -148.052077) (xy 254.638225 -148.081131) (xy 254.586896 -148.102943)
			(xy 254.532939 -148.117049) (xy 254.477502 -148.123149) (xy 254.421768 -148.121112) (xy 254.366925 -148.110982)
			(xy 254.314141 -148.092975) (xy 254.264541 -148.067474) (xy 254.219183 -148.035023) (xy 254.179034 -147.996314)
			(xy 254.144948 -147.952171) (xy 254.117652 -147.903536) (xy 254.097729 -147.851445) (xy 254.085603 -147.797008)
			(xy 254.081532 -147.741386) (xy 248.823118 -147.741386) (xy 248.824723 -147.742722) (xy 248.86194 -147.784259)
			(xy 248.892713 -147.830772) (xy 248.916385 -147.881269) (xy 248.932453 -147.934676) (xy 248.940573 -147.989852)
			(xy 248.941082 -148.017738) (xy 248.940573 -148.045624) (xy 248.932453 -148.1008) (xy 248.916385 -148.154207)
			(xy 248.892713 -148.204704) (xy 248.86194 -148.251217) (xy 248.824723 -148.292754) (xy 248.781855 -148.328429)
			(xy 248.734249 -148.357483) (xy 248.68292 -148.379295) (xy 248.628963 -148.393401) (xy 248.573526 -148.399501)
			(xy 248.517792 -148.397464) (xy 248.462949 -148.387334) (xy 248.410165 -148.369327) (xy 248.360565 -148.343826)
			(xy 248.315207 -148.311375) (xy 248.275058 -148.272666) (xy 248.240972 -148.228523) (xy 248.213676 -148.179888)
			(xy 248.193753 -148.127797) (xy 248.181627 -148.07336) (xy 248.177556 -148.017738) (xy 236.872079 -148.017738)
			(xy 236.855539 -148.031503) (xy 236.807933 -148.060557) (xy 236.756604 -148.082369) (xy 236.702647 -148.096475)
			(xy 236.64721 -148.102575) (xy 236.591476 -148.100538) (xy 236.536633 -148.090408) (xy 236.483849 -148.072401)
			(xy 236.434249 -148.0469) (xy 236.388891 -148.014449) (xy 236.348742 -147.97574) (xy 236.314656 -147.931597)
			(xy 236.28736 -147.882962) (xy 236.267437 -147.830871) (xy 236.255311 -147.776434) (xy 236.25124 -147.720812)
			(xy 234.975654 -147.720812) (xy 234.975145 -147.748698) (xy 234.967025 -147.803874) (xy 234.950957 -147.857281)
			(xy 234.927285 -147.907778) (xy 234.896512 -147.954291) (xy 234.859295 -147.995828) (xy 234.816427 -148.031503)
			(xy 234.768821 -148.060557) (xy 234.717492 -148.082369) (xy 234.663535 -148.096475) (xy 234.608098 -148.102575)
			(xy 234.552364 -148.100538) (xy 234.497521 -148.090408) (xy 234.444737 -148.072401) (xy 234.395137 -148.0469)
			(xy 234.349779 -148.014449) (xy 234.30963 -147.97574) (xy 234.275544 -147.931597) (xy 234.248248 -147.882962)
			(xy 234.228325 -147.830871) (xy 234.216199 -147.776434) (xy 234.212128 -147.720812) (xy 200.619391 -147.720812)
			(xy 200.655407 -147.767748) (xy 200.685374 -147.819654) (xy 200.70831 -147.875027) (xy 200.723823 -147.93292)
			(xy 200.731646 -147.992342) (xy 200.732136 -148.02231) (xy 200.732136 -148.88591) (xy 200.731646 -148.915878)
			(xy 200.723823 -148.9753) (xy 200.70831 -149.033193) (xy 200.699562 -149.054312) (xy 219.859604 -149.054312)
			(xy 219.863675 -148.99869) (xy 219.875801 -148.944253) (xy 219.895724 -148.892162) (xy 219.92302 -148.843527)
			(xy 219.957106 -148.799384) (xy 219.997255 -148.760675) (xy 220.042613 -148.728224) (xy 220.092213 -148.702723)
			(xy 220.144997 -148.684716) (xy 220.19984 -148.674586) (xy 220.255574 -148.672549) (xy 220.311011 -148.678649)
			(xy 220.364968 -148.692755) (xy 220.416297 -148.714567) (xy 220.463903 -148.743621) (xy 220.506771 -148.779296)
			(xy 220.543988 -148.820833) (xy 220.574761 -148.867346) (xy 220.598433 -148.917843) (xy 220.614501 -148.97125)
			(xy 220.622621 -149.026426) (xy 220.62313 -149.054312) (xy 220.622621 -149.082198) (xy 220.614501 -149.137374)
			(xy 220.598433 -149.190781) (xy 220.574761 -149.241278) (xy 220.543988 -149.287791) (xy 220.506771 -149.329328)
			(xy 220.463903 -149.365003) (xy 220.416297 -149.394057) (xy 220.394527 -149.403308) (xy 223.512886 -149.403308)
			(xy 223.516957 -149.347686) (xy 223.529083 -149.293249) (xy 223.549006 -149.241158) (xy 223.576302 -149.192523)
			(xy 223.610388 -149.14838) (xy 223.650537 -149.109671) (xy 223.695895 -149.07722) (xy 223.745495 -149.051719)
			(xy 223.798279 -149.033712) (xy 223.853122 -149.023582) (xy 223.908856 -149.021545) (xy 223.964293 -149.027645)
			(xy 224.01825 -149.041751) (xy 224.069579 -149.063563) (xy 224.117185 -149.092617) (xy 224.160053 -149.128292)
			(xy 224.19727 -149.169829) (xy 224.228043 -149.216342) (xy 224.251715 -149.266839) (xy 224.258038 -149.287857)
			(xy 233.065215 -149.287857) (xy 233.065215 -149.233343) (xy 233.072973 -149.179385) (xy 233.088332 -149.12708)
			(xy 233.110978 -149.077493) (xy 233.140451 -149.031634) (xy 233.176151 -148.990437) (xy 233.21735 -148.954739)
			(xy 233.263211 -148.925269) (xy 233.312799 -148.902625) (xy 233.365105 -148.887269) (xy 233.419063 -148.879514)
			(xy 233.44632 -148.879052) (xy 233.473193 -148.879488) (xy 233.526406 -148.887047) (xy 233.578032 -148.901998)
			(xy 233.627049 -148.924046) (xy 233.672487 -148.952753) (xy 233.713447 -148.987553) (xy 233.749118 -149.027757)
			(xy 233.778795 -149.072568) (xy 233.80189 -149.1211) (xy 233.817946 -149.172393) (xy 233.822748 -149.198838)
			(xy 233.824272 -149.208744) (xy 233.834686 -149.225508) (xy 233.899964 -149.273514) (xy 233.908092 -149.278969)
			(xy 233.927045 -149.283799) (xy 233.936794 -149.282912) (xy 233.937048 -149.282912) (xy 233.949938 -149.281253)
			(xy 233.975868 -149.279475) (xy 233.988864 -149.279356) (xy 233.989118 -149.279356) (xy 234.016366 -149.279915)
			(xy 234.070306 -149.287673) (xy 234.122594 -149.303028) (xy 234.172164 -149.325668) (xy 234.218008 -149.355132)
			(xy 234.259192 -149.390821) (xy 234.294878 -149.432006) (xy 234.32434 -149.477852) (xy 234.346978 -149.527423)
			(xy 234.362331 -149.579711) (xy 234.370086 -149.633652) (xy 234.370086 -149.688148) (xy 234.369627 -149.691344)
			(xy 236.708188 -149.691344) (xy 236.708188 -148.827744) (xy 236.708678 -148.79776) (xy 236.716506 -148.738304)
			(xy 236.732027 -148.680379) (xy 236.754976 -148.624975) (xy 236.78496 -148.573041) (xy 236.821466 -148.525465)
			(xy 236.863871 -148.48306) (xy 236.911447 -148.446554) (xy 236.963381 -148.41657) (xy 237.018785 -148.393621)
			(xy 237.07671 -148.3781) (xy 237.136166 -148.370272) (xy 237.196134 -148.370272) (xy 237.25559 -148.3781)
			(xy 237.313515 -148.393621) (xy 237.368919 -148.41657) (xy 237.420853 -148.446554) (xy 237.468429 -148.48306)
			(xy 237.510834 -148.525465) (xy 237.54734 -148.573041) (xy 237.577324 -148.624975) (xy 237.600273 -148.680379)
			(xy 237.615794 -148.738304) (xy 237.623622 -148.79776) (xy 237.624112 -148.827744) (xy 237.624112 -149.691344)
			(xy 237.623622 -149.721328) (xy 237.615794 -149.780784) (xy 237.600273 -149.838709) (xy 237.577324 -149.894113)
			(xy 237.54734 -149.946047) (xy 237.510834 -149.993623) (xy 237.468429 -150.036028) (xy 237.420853 -150.072534)
			(xy 237.368919 -150.102518) (xy 237.313515 -150.125467) (xy 237.25559 -150.140988) (xy 237.196134 -150.148816)
			(xy 237.136166 -150.148816) (xy 237.07671 -150.140988) (xy 237.018785 -150.125467) (xy 236.963381 -150.102518)
			(xy 236.911447 -150.072534) (xy 236.863871 -150.036028) (xy 236.821466 -149.993623) (xy 236.78496 -149.946047)
			(xy 236.754976 -149.894113) (xy 236.732027 -149.838709) (xy 236.716506 -149.780784) (xy 236.708678 -149.721328)
			(xy 236.708188 -149.691344) (xy 234.369627 -149.691344) (xy 234.362331 -149.742089) (xy 234.346978 -149.794377)
			(xy 234.32434 -149.843948) (xy 234.294878 -149.889794) (xy 234.259192 -149.930979) (xy 234.218008 -149.966668)
			(xy 234.172164 -149.996131) (xy 234.122594 -150.018772) (xy 234.070306 -150.034127) (xy 234.016366 -150.041885)
			(xy 233.989118 -150.042372) (xy 233.962247 -150.041881) (xy 233.909037 -150.034328) (xy 233.857413 -150.019383)
			(xy 233.808398 -149.997342) (xy 233.762961 -149.96864) (xy 233.722001 -149.933846) (xy 233.686329 -149.893649)
			(xy 233.65665 -149.848843) (xy 233.633553 -149.800316) (xy 233.617494 -149.749029) (xy 233.61269 -149.722586)
			(xy 233.611166 -149.71268) (xy 233.600752 -149.695916) (xy 233.535474 -149.64791) (xy 233.527334 -149.642476)
			(xy 233.508391 -149.637632) (xy 233.498644 -149.638512) (xy 233.49839 -149.638512) (xy 233.4855 -149.640167)
			(xy 233.45957 -149.641948) (xy 233.446574 -149.642068) (xy 233.44632 -149.642068) (xy 233.419063 -149.641686)
			(xy 233.365105 -149.633931) (xy 233.312799 -149.618575) (xy 233.263211 -149.595931) (xy 233.21735 -149.566461)
			(xy 233.176151 -149.530763) (xy 233.140451 -149.489566) (xy 233.110978 -149.443707) (xy 233.088332 -149.39412)
			(xy 233.072973 -149.341815) (xy 233.065215 -149.287857) (xy 224.258038 -149.287857) (xy 224.267783 -149.320246)
			(xy 224.275903 -149.375422) (xy 224.276412 -149.403308) (xy 224.275903 -149.431194) (xy 224.267783 -149.48637)
			(xy 224.251715 -149.539777) (xy 224.228043 -149.590274) (xy 224.19727 -149.636787) (xy 224.160053 -149.678324)
			(xy 224.117185 -149.713999) (xy 224.069579 -149.743053) (xy 224.01825 -149.764865) (xy 223.964293 -149.778971)
			(xy 223.908856 -149.785071) (xy 223.853122 -149.783034) (xy 223.798279 -149.772904) (xy 223.745495 -149.754897)
			(xy 223.695895 -149.729396) (xy 223.650537 -149.696945) (xy 223.610388 -149.658236) (xy 223.576302 -149.614093)
			(xy 223.549006 -149.565458) (xy 223.529083 -149.513367) (xy 223.516957 -149.45893) (xy 223.512886 -149.403308)
			(xy 220.394527 -149.403308) (xy 220.364968 -149.415869) (xy 220.311011 -149.429975) (xy 220.255574 -149.436075)
			(xy 220.19984 -149.434038) (xy 220.144997 -149.423908) (xy 220.092213 -149.405901) (xy 220.042613 -149.3804)
			(xy 219.997255 -149.347949) (xy 219.957106 -149.30924) (xy 219.92302 -149.265097) (xy 219.895724 -149.216462)
			(xy 219.875801 -149.164371) (xy 219.863675 -149.109934) (xy 219.859604 -149.054312) (xy 200.699562 -149.054312)
			(xy 200.685374 -149.088566) (xy 200.655407 -149.140472) (xy 200.61892 -149.188022) (xy 200.57654 -149.230402)
			(xy 200.52899 -149.266889) (xy 200.477084 -149.296856) (xy 200.421711 -149.319792) (xy 200.363818 -149.335305)
			(xy 200.304396 -149.343128) (xy 200.24446 -149.343128) (xy 200.185038 -149.335305) (xy 200.127145 -149.319792)
			(xy 200.071772 -149.296856) (xy 200.019866 -149.266889) (xy 199.972316 -149.230402) (xy 199.929936 -149.188022)
			(xy 199.893449 -149.140472) (xy 199.863482 -149.088566) (xy 199.840546 -149.033193) (xy 199.825033 -148.9753)
			(xy 199.81721 -148.915878) (xy 199.81672 -148.88591) (xy 196.135274 -148.88591) (xy 195.987738 -150.67915)
			(xy 197.174612 -150.67915) (xy 197.174612 -149.81555) (xy 197.175102 -149.785582) (xy 197.182925 -149.72616)
			(xy 197.198438 -149.668267) (xy 197.221374 -149.612894) (xy 197.251341 -149.560988) (xy 197.287828 -149.513438)
			(xy 197.330208 -149.471058) (xy 197.377758 -149.434571) (xy 197.429664 -149.404604) (xy 197.485037 -149.381668)
			(xy 197.54293 -149.366155) (xy 197.602352 -149.358332) (xy 197.662288 -149.358332) (xy 197.72171 -149.366155)
			(xy 197.779603 -149.381668) (xy 197.834976 -149.404604) (xy 197.886882 -149.434571) (xy 197.934432 -149.471058)
			(xy 197.976812 -149.513438) (xy 198.013299 -149.560988) (xy 198.043266 -149.612894) (xy 198.066202 -149.668267)
			(xy 198.081715 -149.72616) (xy 198.089538 -149.785582) (xy 198.090028 -149.81555) (xy 198.090028 -150.195854)
			(xy 243.350465 -150.195854) (xy 243.350465 -150.141346) (xy 243.358223 -150.087393) (xy 243.373581 -150.035093)
			(xy 243.396226 -149.985511) (xy 243.425697 -149.939657) (xy 243.461394 -149.898465) (xy 243.502591 -149.862772)
			(xy 243.548448 -149.833306) (xy 243.598032 -149.810666) (xy 243.650334 -149.795314) (xy 243.704288 -149.787562)
			(xy 243.731542 -149.787102) (xy 243.757857 -149.787541) (xy 243.809987 -149.794781) (xy 243.86063 -149.809106)
			(xy 243.908829 -149.830244) (xy 243.953672 -149.857795) (xy 243.99431 -149.891238) (xy 244.012466 -149.910292)
			(xy 244.019999 -149.917679) (xy 244.03927 -149.926212) (xy 244.049804 -149.926802) (xy 244.12448 -149.926802)
			(xy 244.13503 -149.926275) (xy 244.154325 -149.917738) (xy 244.161818 -149.910292) (xy 244.181638 -149.889504)
			(xy 244.22641 -149.853529) (xy 244.276068 -149.824669) (xy 244.32949 -149.803576) (xy 244.385469 -149.790727)
			(xy 244.442742 -149.786412) (xy 244.500015 -149.790727) (xy 244.555994 -149.803576) (xy 244.609416 -149.824669)
			(xy 244.659074 -149.853529) (xy 244.703846 -149.889504) (xy 244.723666 -149.910292) (xy 244.731199 -149.917679)
			(xy 244.75047 -149.926212) (xy 244.761004 -149.926802) (xy 244.83568 -149.926802) (xy 244.84623 -149.926275)
			(xy 244.865525 -149.917738) (xy 244.873018 -149.910292) (xy 244.89117 -149.891233) (xy 244.931801 -149.857777)
			(xy 244.976642 -149.830218) (xy 245.024843 -149.80908) (xy 245.075491 -149.794764) (xy 245.127626 -149.78754)
			(xy 245.153942 -149.787102) (xy 245.181192 -149.787571) (xy 245.235137 -149.795332) (xy 245.287428 -149.810691)
			(xy 245.337001 -149.833336) (xy 245.382847 -149.862804) (xy 245.424034 -149.898496) (xy 245.459721 -149.939686)
			(xy 245.489185 -149.985536) (xy 245.511823 -150.035112) (xy 245.520145 -150.063454) (xy 248.03811 -150.063454)
			(xy 248.042181 -150.007832) (xy 248.054307 -149.953395) (xy 248.07423 -149.901304) (xy 248.101526 -149.852669)
			(xy 248.135612 -149.808526) (xy 248.175761 -149.769817) (xy 248.221119 -149.737366) (xy 248.270719 -149.711865)
			(xy 248.323503 -149.693858) (xy 248.378346 -149.683728) (xy 248.43408 -149.681691) (xy 248.489517 -149.687791)
			(xy 248.543474 -149.701897) (xy 248.594803 -149.723709) (xy 248.642409 -149.752763) (xy 248.685277 -149.788438)
			(xy 248.722494 -149.829975) (xy 248.753267 -149.876488) (xy 248.776939 -149.926985) (xy 248.793007 -149.980392)
			(xy 248.801127 -150.035568) (xy 248.801636 -150.063454) (xy 248.801127 -150.09134) (xy 248.793007 -150.146516)
			(xy 248.776939 -150.199923) (xy 248.753267 -150.25042) (xy 248.722494 -150.296933) (xy 248.685277 -150.33847)
			(xy 248.642409 -150.374145) (xy 248.594803 -150.403199) (xy 248.543474 -150.425011) (xy 248.489517 -150.439117)
			(xy 248.43408 -150.445217) (xy 248.378346 -150.44318) (xy 248.323503 -150.43305) (xy 248.270719 -150.415043)
			(xy 248.221119 -150.389542) (xy 248.175761 -150.357091) (xy 248.135612 -150.318382) (xy 248.101526 -150.274239)
			(xy 248.07423 -150.225604) (xy 248.054307 -150.173513) (xy 248.042181 -150.119076) (xy 248.03811 -150.063454)
			(xy 245.520145 -150.063454) (xy 245.527177 -150.087404) (xy 245.534932 -150.14135) (xy 245.534932 -150.19585)
			(xy 245.527177 -150.249796) (xy 245.511823 -150.302088) (xy 245.489185 -150.351664) (xy 245.459721 -150.397514)
			(xy 245.424034 -150.438704) (xy 245.382847 -150.474396) (xy 245.337001 -150.503864) (xy 245.287428 -150.526509)
			(xy 245.235137 -150.541868) (xy 245.181192 -150.549629) (xy 245.153942 -150.550118) (xy 245.127627 -150.549683)
			(xy 245.075497 -150.542441) (xy 245.024854 -150.528115) (xy 244.976655 -150.506976) (xy 244.931813 -150.479425)
			(xy 244.891174 -150.445982) (xy 244.873018 -150.426928) (xy 244.865488 -150.419536) (xy 244.846215 -150.411005)
			(xy 244.83568 -150.410418) (xy 244.761004 -150.410418) (xy 244.750452 -150.410931) (xy 244.731157 -150.419477)
			(xy 244.723666 -150.426928) (xy 244.703846 -150.447716) (xy 244.659074 -150.483691) (xy 244.609416 -150.512551)
			(xy 244.555994 -150.533644) (xy 244.500015 -150.546493) (xy 244.442742 -150.550808) (xy 244.385469 -150.546493)
			(xy 244.32949 -150.533644) (xy 244.276068 -150.512551) (xy 244.22641 -150.483691) (xy 244.181638 -150.447716)
			(xy 244.161818 -150.426928) (xy 244.154288 -150.419536) (xy 244.135015 -150.411005) (xy 244.12448 -150.410418)
			(xy 244.049804 -150.410418) (xy 244.039252 -150.410931) (xy 244.019957 -150.419477) (xy 244.012466 -150.426928)
			(xy 243.994325 -150.445998) (xy 243.953692 -150.479453) (xy 243.908848 -150.507009) (xy 243.860645 -150.528145)
			(xy 243.809995 -150.542459) (xy 243.757859 -150.549681) (xy 243.731542 -150.550118) (xy 243.704288 -150.549638)
			(xy 243.650334 -150.541886) (xy 243.598032 -150.526534) (xy 243.548448 -150.503894) (xy 243.502591 -150.474428)
			(xy 243.461394 -150.438735) (xy 243.425697 -150.397543) (xy 243.396226 -150.351689) (xy 243.373581 -150.302107)
			(xy 243.358223 -150.249807) (xy 243.350465 -150.195854) (xy 198.090028 -150.195854) (xy 198.090028 -150.67915)
			(xy 198.089538 -150.709118) (xy 198.081715 -150.76854) (xy 198.066202 -150.826433) (xy 198.043266 -150.881806)
			(xy 198.013299 -150.933712) (xy 197.976812 -150.981262) (xy 197.934432 -151.023642) (xy 197.886882 -151.060129)
			(xy 197.834976 -151.090096) (xy 197.779603 -151.113032) (xy 197.72171 -151.128545) (xy 197.662288 -151.136368)
			(xy 197.602352 -151.136368) (xy 197.54293 -151.128545) (xy 197.485037 -151.113032) (xy 197.429664 -151.090096)
			(xy 197.377758 -151.060129) (xy 197.330208 -151.023642) (xy 197.287828 -150.981262) (xy 197.251341 -150.933712)
			(xy 197.221374 -150.881806) (xy 197.198438 -150.826433) (xy 197.182925 -150.76854) (xy 197.175102 -150.709118)
			(xy 197.174612 -150.67915) (xy 195.987738 -150.67915) (xy 195.839095 -152.485852) (xy 199.81672 -152.485852)
			(xy 199.81672 -151.622252) (xy 199.81721 -151.592284) (xy 199.825033 -151.532862) (xy 199.840546 -151.474969)
			(xy 199.863482 -151.419596) (xy 199.893449 -151.36769) (xy 199.929936 -151.32014) (xy 199.972316 -151.27776)
			(xy 200.019866 -151.241273) (xy 200.071772 -151.211306) (xy 200.127145 -151.18837) (xy 200.185038 -151.172857)
			(xy 200.24446 -151.165034) (xy 200.304396 -151.165034) (xy 200.363818 -151.172857) (xy 200.421711 -151.18837)
			(xy 200.477084 -151.211306) (xy 200.52899 -151.241273) (xy 200.57654 -151.27776) (xy 200.61892 -151.32014)
			(xy 200.655407 -151.36769) (xy 200.685374 -151.419596) (xy 200.70831 -151.474969) (xy 200.723823 -151.532862)
			(xy 200.731646 -151.592284) (xy 200.732136 -151.622252) (xy 200.732136 -151.664162) (xy 231.773474 -151.664162)
			(xy 231.777545 -151.60854) (xy 231.789671 -151.554103) (xy 231.809594 -151.502012) (xy 231.83689 -151.453377)
			(xy 231.870976 -151.409234) (xy 231.911125 -151.370525) (xy 231.956483 -151.338074) (xy 232.006083 -151.312573)
			(xy 232.058867 -151.294566) (xy 232.11371 -151.284436) (xy 232.169444 -151.282399) (xy 232.224881 -151.288499)
			(xy 232.278838 -151.302605) (xy 232.330167 -151.324417) (xy 232.377773 -151.353471) (xy 232.420641 -151.389146)
			(xy 232.457858 -151.430683) (xy 232.488631 -151.477196) (xy 232.512303 -151.527693) (xy 232.528371 -151.5811)
			(xy 232.536491 -151.636276) (xy 232.537 -151.664162) (xy 232.536491 -151.692048) (xy 232.528371 -151.747224)
			(xy 232.512303 -151.800631) (xy 232.488631 -151.851128) (xy 232.457858 -151.897641) (xy 232.443113 -151.914098)
			(xy 236.712252 -151.914098) (xy 236.712252 -151.050498) (xy 236.712742 -151.020514) (xy 236.72057 -150.961058)
			(xy 236.736091 -150.903133) (xy 236.75904 -150.847729) (xy 236.789024 -150.795795) (xy 236.82553 -150.748219)
			(xy 236.867935 -150.705814) (xy 236.915511 -150.669308) (xy 236.967445 -150.639324) (xy 237.022849 -150.616375)
			(xy 237.080774 -150.600854) (xy 237.14023 -150.593026) (xy 237.200198 -150.593026) (xy 237.259654 -150.600854)
			(xy 237.317579 -150.616375) (xy 237.372983 -150.639324) (xy 237.424917 -150.669308) (xy 237.472493 -150.705814)
			(xy 237.514898 -150.748219) (xy 237.551404 -150.795795) (xy 237.581388 -150.847729) (xy 237.604337 -150.903133)
			(xy 237.619858 -150.961058) (xy 237.627686 -151.020514) (xy 237.628176 -151.050498) (xy 237.628176 -151.67102)
			(xy 247.99366 -151.67102) (xy 247.997731 -151.615398) (xy 248.009857 -151.560961) (xy 248.02978 -151.50887)
			(xy 248.057076 -151.460235) (xy 248.091162 -151.416092) (xy 248.131311 -151.377383) (xy 248.176669 -151.344932)
			(xy 248.226269 -151.319431) (xy 248.279053 -151.301424) (xy 248.333896 -151.291294) (xy 248.38963 -151.289257)
			(xy 248.445067 -151.295357) (xy 248.499024 -151.309463) (xy 248.550353 -151.331275) (xy 248.597959 -151.360329)
			(xy 248.640827 -151.396004) (xy 248.678044 -151.437541) (xy 248.708817 -151.484054) (xy 248.732489 -151.534551)
			(xy 248.748557 -151.587958) (xy 248.756677 -151.643134) (xy 248.757186 -151.67102) (xy 248.756713 -151.696928)
			(xy 249.00966 -151.696928) (xy 249.013731 -151.641306) (xy 249.025857 -151.586869) (xy 249.04578 -151.534778)
			(xy 249.073076 -151.486143) (xy 249.107162 -151.442) (xy 249.147311 -151.403291) (xy 249.192669 -151.37084)
			(xy 249.242269 -151.345339) (xy 249.295053 -151.327332) (xy 249.349896 -151.317202) (xy 249.40563 -151.315165)
			(xy 249.461067 -151.321265) (xy 249.515024 -151.335371) (xy 249.566353 -151.357183) (xy 249.613959 -151.386237)
			(xy 249.638435 -151.406606) (xy 250.236734 -151.406606) (xy 250.240805 -151.350984) (xy 250.252931 -151.296547)
			(xy 250.272854 -151.244456) (xy 250.30015 -151.195821) (xy 250.334236 -151.151678) (xy 250.374385 -151.112969)
			(xy 250.419743 -151.080518) (xy 250.469343 -151.055017) (xy 250.522127 -151.03701) (xy 250.57697 -151.02688)
			(xy 250.632704 -151.024843) (xy 250.688141 -151.030943) (xy 250.742098 -151.045049) (xy 250.793427 -151.066861)
			(xy 250.841033 -151.095915) (xy 250.883901 -151.13159) (xy 250.921118 -151.173127) (xy 250.951891 -151.21964)
			(xy 250.975563 -151.270137) (xy 250.991631 -151.323544) (xy 250.999751 -151.37872) (xy 251.00026 -151.406606)
			(xy 250.999751 -151.434492) (xy 250.991631 -151.489668) (xy 250.975563 -151.543075) (xy 250.957021 -151.582628)
			(xy 251.56236 -151.582628) (xy 251.566431 -151.527006) (xy 251.578557 -151.472569) (xy 251.59848 -151.420478)
			(xy 251.625776 -151.371843) (xy 251.659862 -151.3277) (xy 251.700011 -151.288991) (xy 251.745369 -151.25654)
			(xy 251.794969 -151.231039) (xy 251.847753 -151.213032) (xy 251.902596 -151.202902) (xy 251.95833 -151.200865)
			(xy 252.013767 -151.206965) (xy 252.067724 -151.221071) (xy 252.119053 -151.242883) (xy 252.166659 -151.271937)
			(xy 252.209527 -151.307612) (xy 252.246744 -151.349149) (xy 252.277517 -151.395662) (xy 252.301189 -151.446159)
			(xy 252.317257 -151.499566) (xy 252.325377 -151.554742) (xy 252.32564 -151.569166) (xy 253.07366 -151.569166)
			(xy 253.077731 -151.513544) (xy 253.089857 -151.459107) (xy 253.10978 -151.407016) (xy 253.137076 -151.358381)
			(xy 253.171162 -151.314238) (xy 253.211311 -151.275529) (xy 253.256669 -151.243078) (xy 253.306269 -151.217577)
			(xy 253.359053 -151.19957) (xy 253.413896 -151.18944) (xy 253.46963 -151.187403) (xy 253.525067 -151.193503)
			(xy 253.579024 -151.207609) (xy 253.630353 -151.229421) (xy 253.677959 -151.258475) (xy 253.720827 -151.29415)
			(xy 253.758044 -151.335687) (xy 253.788817 -151.3822) (xy 253.812489 -151.432697) (xy 253.828557 -151.486104)
			(xy 253.836677 -151.54128) (xy 253.837186 -151.569166) (xy 253.836677 -151.597052) (xy 253.828557 -151.652228)
			(xy 253.812489 -151.705635) (xy 253.788817 -151.756132) (xy 253.758044 -151.802645) (xy 253.720827 -151.844182)
			(xy 253.677959 -151.879857) (xy 253.630353 -151.908911) (xy 253.579024 -151.930723) (xy 253.525067 -151.944829)
			(xy 253.46963 -151.950929) (xy 253.413896 -151.948892) (xy 253.359053 -151.938762) (xy 253.306269 -151.920755)
			(xy 253.256669 -151.895254) (xy 253.211311 -151.862803) (xy 253.171162 -151.824094) (xy 253.137076 -151.779951)
			(xy 253.10978 -151.731316) (xy 253.089857 -151.679225) (xy 253.077731 -151.624788) (xy 253.07366 -151.569166)
			(xy 252.32564 -151.569166) (xy 252.325886 -151.582628) (xy 252.325377 -151.610514) (xy 252.317257 -151.66569)
			(xy 252.301189 -151.719097) (xy 252.277517 -151.769594) (xy 252.246744 -151.816107) (xy 252.209527 -151.857644)
			(xy 252.166659 -151.893319) (xy 252.119053 -151.922373) (xy 252.067724 -151.944185) (xy 252.013767 -151.958291)
			(xy 251.95833 -151.964391) (xy 251.902596 -151.962354) (xy 251.847753 -151.952224) (xy 251.794969 -151.934217)
			(xy 251.745369 -151.908716) (xy 251.700011 -151.876265) (xy 251.659862 -151.837556) (xy 251.625776 -151.793413)
			(xy 251.59848 -151.744778) (xy 251.578557 -151.692687) (xy 251.566431 -151.63825) (xy 251.56236 -151.582628)
			(xy 250.957021 -151.582628) (xy 250.951891 -151.593572) (xy 250.921118 -151.640085) (xy 250.883901 -151.681622)
			(xy 250.841033 -151.717297) (xy 250.793427 -151.746351) (xy 250.742098 -151.768163) (xy 250.688141 -151.782269)
			(xy 250.632704 -151.788369) (xy 250.57697 -151.786332) (xy 250.522127 -151.776202) (xy 250.469343 -151.758195)
			(xy 250.419743 -151.732694) (xy 250.374385 -151.700243) (xy 250.334236 -151.661534) (xy 250.30015 -151.617391)
			(xy 250.272854 -151.568756) (xy 250.252931 -151.516665) (xy 250.240805 -151.462228) (xy 250.236734 -151.406606)
			(xy 249.638435 -151.406606) (xy 249.656827 -151.421912) (xy 249.694044 -151.463449) (xy 249.724817 -151.509962)
			(xy 249.748489 -151.560459) (xy 249.764557 -151.613866) (xy 249.772677 -151.669042) (xy 249.773186 -151.696928)
			(xy 249.772677 -151.724814) (xy 249.764557 -151.77999) (xy 249.748489 -151.833397) (xy 249.724817 -151.883894)
			(xy 249.694044 -151.930407) (xy 249.656827 -151.971944) (xy 249.613959 -152.007619) (xy 249.566353 -152.036673)
			(xy 249.515024 -152.058485) (xy 249.461067 -152.072591) (xy 249.40563 -152.078691) (xy 249.349896 -152.076654)
			(xy 249.295053 -152.066524) (xy 249.242269 -152.048517) (xy 249.192669 -152.023016) (xy 249.147311 -151.990565)
			(xy 249.107162 -151.951856) (xy 249.073076 -151.907713) (xy 249.04578 -151.859078) (xy 249.025857 -151.806987)
			(xy 249.013731 -151.75255) (xy 249.00966 -151.696928) (xy 248.756713 -151.696928) (xy 248.756677 -151.698906)
			(xy 248.748557 -151.754082) (xy 248.732489 -151.807489) (xy 248.708817 -151.857986) (xy 248.678044 -151.904499)
			(xy 248.640827 -151.946036) (xy 248.597959 -151.981711) (xy 248.550353 -152.010765) (xy 248.499024 -152.032577)
			(xy 248.445067 -152.046683) (xy 248.38963 -152.052783) (xy 248.333896 -152.050746) (xy 248.279053 -152.040616)
			(xy 248.226269 -152.022609) (xy 248.176669 -151.997108) (xy 248.131311 -151.964657) (xy 248.091162 -151.925948)
			(xy 248.057076 -151.881805) (xy 248.02978 -151.83317) (xy 248.009857 -151.781079) (xy 247.997731 -151.726642)
			(xy 247.99366 -151.67102) (xy 237.628176 -151.67102) (xy 237.628176 -151.914098) (xy 237.627686 -151.944082)
			(xy 237.619858 -152.003538) (xy 237.604337 -152.061463) (xy 237.581388 -152.116867) (xy 237.551404 -152.168801)
			(xy 237.514898 -152.216377) (xy 237.472493 -152.258782) (xy 237.424917 -152.295288) (xy 237.372983 -152.325272)
			(xy 237.317579 -152.348221) (xy 237.259654 -152.363742) (xy 237.200198 -152.37157) (xy 237.14023 -152.37157)
			(xy 237.080774 -152.363742) (xy 237.022849 -152.348221) (xy 236.967445 -152.325272) (xy 236.915511 -152.295288)
			(xy 236.867935 -152.258782) (xy 236.82553 -152.216377) (xy 236.789024 -152.168801) (xy 236.75904 -152.116867)
			(xy 236.736091 -152.061463) (xy 236.72057 -152.003538) (xy 236.712742 -151.944082) (xy 236.712252 -151.914098)
			(xy 232.443113 -151.914098) (xy 232.420641 -151.939178) (xy 232.377773 -151.974853) (xy 232.330167 -152.003907)
			(xy 232.278838 -152.025719) (xy 232.224881 -152.039825) (xy 232.169444 -152.045925) (xy 232.11371 -152.043888)
			(xy 232.058867 -152.033758) (xy 232.006083 -152.015751) (xy 231.956483 -151.99025) (xy 231.911125 -151.957799)
			(xy 231.870976 -151.91909) (xy 231.83689 -151.874947) (xy 231.809594 -151.826312) (xy 231.789671 -151.774221)
			(xy 231.777545 -151.719784) (xy 231.773474 -151.664162) (xy 200.732136 -151.664162) (xy 200.732136 -152.412446)
			(xy 226.102924 -152.412446) (xy 226.106995 -152.356824) (xy 226.119121 -152.302387) (xy 226.139044 -152.250296)
			(xy 226.16634 -152.201661) (xy 226.200426 -152.157518) (xy 226.240575 -152.118809) (xy 226.285933 -152.086358)
			(xy 226.335533 -152.060857) (xy 226.388317 -152.04285) (xy 226.44316 -152.03272) (xy 226.498894 -152.030683)
			(xy 226.554331 -152.036783) (xy 226.608288 -152.050889) (xy 226.659617 -152.072701) (xy 226.707223 -152.101755)
			(xy 226.750091 -152.13743) (xy 226.787308 -152.178967) (xy 226.818081 -152.22548) (xy 226.841753 -152.275977)
			(xy 226.857821 -152.329384) (xy 226.864139 -152.372314) (xy 227.76256 -152.372314) (xy 227.766631 -152.316692)
			(xy 227.778757 -152.262255) (xy 227.79868 -152.210164) (xy 227.825976 -152.161529) (xy 227.860062 -152.117386)
			(xy 227.900211 -152.078677) (xy 227.945569 -152.046226) (xy 227.995169 -152.020725) (xy 228.047953 -152.002718)
			(xy 228.102796 -151.992588) (xy 228.15853 -151.990551) (xy 228.213967 -151.996651) (xy 228.267924 -152.010757)
			(xy 228.319253 -152.032569) (xy 228.366859 -152.061623) (xy 228.38462 -152.076404) (xy 230.958388 -152.076404)
			(xy 230.962459 -152.020782) (xy 230.974585 -151.966345) (xy 230.994508 -151.914254) (xy 231.021804 -151.865619)
			(xy 231.05589 -151.821476) (xy 231.096039 -151.782767) (xy 231.141397 -151.750316) (xy 231.190997 -151.724815)
			(xy 231.243781 -151.706808) (xy 231.298624 -151.696678) (xy 231.354358 -151.694641) (xy 231.409795 -151.700741)
			(xy 231.463752 -151.714847) (xy 231.515081 -151.736659) (xy 231.562687 -151.765713) (xy 231.605555 -151.801388)
			(xy 231.642772 -151.842925) (xy 231.673545 -151.889438) (xy 231.697217 -151.939935) (xy 231.713285 -151.993342)
			(xy 231.721405 -152.048518) (xy 231.721914 -152.076404) (xy 231.721405 -152.10429) (xy 231.713285 -152.159466)
			(xy 231.697217 -152.212873) (xy 231.673545 -152.26337) (xy 231.642772 -152.309883) (xy 231.605555 -152.35142)
			(xy 231.562687 -152.387095) (xy 231.515081 -152.416149) (xy 231.463752 -152.437961) (xy 231.409795 -152.452067)
			(xy 231.354358 -152.458167) (xy 231.298624 -152.45613) (xy 231.243781 -152.446) (xy 231.190997 -152.427993)
			(xy 231.141397 -152.402492) (xy 231.096039 -152.370041) (xy 231.05589 -152.331332) (xy 231.021804 -152.287189)
			(xy 230.994508 -152.238554) (xy 230.974585 -152.186463) (xy 230.962459 -152.132026) (xy 230.958388 -152.076404)
			(xy 228.38462 -152.076404) (xy 228.409727 -152.097298) (xy 228.446944 -152.138835) (xy 228.477717 -152.185348)
			(xy 228.501389 -152.235845) (xy 228.517457 -152.289252) (xy 228.525577 -152.344428) (xy 228.526086 -152.372314)
			(xy 228.525577 -152.4002) (xy 228.517457 -152.455376) (xy 228.501389 -152.508783) (xy 228.477717 -152.55928)
			(xy 228.446944 -152.605793) (xy 228.409727 -152.64733) (xy 228.366859 -152.683005) (xy 228.319253 -152.712059)
			(xy 228.267924 -152.733871) (xy 228.213967 -152.747977) (xy 228.15853 -152.754077) (xy 228.102796 -152.75204)
			(xy 228.047953 -152.74191) (xy 227.995169 -152.723903) (xy 227.945569 -152.698402) (xy 227.900211 -152.665951)
			(xy 227.860062 -152.627242) (xy 227.825976 -152.583099) (xy 227.79868 -152.534464) (xy 227.778757 -152.482373)
			(xy 227.766631 -152.427936) (xy 227.76256 -152.372314) (xy 226.864139 -152.372314) (xy 226.865941 -152.38456)
			(xy 226.86645 -152.412446) (xy 226.865941 -152.440332) (xy 226.857821 -152.495508) (xy 226.841753 -152.548915)
			(xy 226.818081 -152.599412) (xy 226.787308 -152.645925) (xy 226.750091 -152.687462) (xy 226.707223 -152.723137)
			(xy 226.659617 -152.752191) (xy 226.608288 -152.774003) (xy 226.554331 -152.788109) (xy 226.498894 -152.794209)
			(xy 226.44316 -152.792172) (xy 226.388317 -152.782042) (xy 226.335533 -152.764035) (xy 226.285933 -152.738534)
			(xy 226.240575 -152.706083) (xy 226.200426 -152.667374) (xy 226.16634 -152.623231) (xy 226.139044 -152.574596)
			(xy 226.119121 -152.522505) (xy 226.106995 -152.468068) (xy 226.102924 -152.412446) (xy 200.732136 -152.412446)
			(xy 200.732136 -152.485852) (xy 200.731646 -152.51582) (xy 200.723823 -152.575242) (xy 200.70831 -152.633135)
			(xy 200.685374 -152.688508) (xy 200.655407 -152.740414) (xy 200.61892 -152.787964) (xy 200.57654 -152.830344)
			(xy 200.52899 -152.866831) (xy 200.477084 -152.896798) (xy 200.421711 -152.919734) (xy 200.363818 -152.935247)
			(xy 200.304396 -152.94307) (xy 200.24446 -152.94307) (xy 200.185038 -152.935247) (xy 200.127145 -152.919734)
			(xy 200.071772 -152.896798) (xy 200.019866 -152.866831) (xy 199.972316 -152.830344) (xy 199.929936 -152.787964)
			(xy 199.893449 -152.740414) (xy 199.863482 -152.688508) (xy 199.840546 -152.633135) (xy 199.825033 -152.575242)
			(xy 199.81721 -152.51582) (xy 199.81672 -152.485852) (xy 195.839095 -152.485852) (xy 195.718684 -153.9494)
			(xy 195.71335 -153.99893) (xy 195.676201 -154.279346) (xy 197.174612 -154.279346) (xy 197.174612 -153.415746)
			(xy 197.175102 -153.385778) (xy 197.182925 -153.326356) (xy 197.198438 -153.268463) (xy 197.221374 -153.21309)
			(xy 197.251341 -153.161184) (xy 197.287828 -153.113634) (xy 197.330208 -153.071254) (xy 197.377758 -153.034767)
			(xy 197.429664 -153.0048) (xy 197.485037 -152.981864) (xy 197.54293 -152.966351) (xy 197.602352 -152.958528)
			(xy 197.662288 -152.958528) (xy 197.72171 -152.966351) (xy 197.779603 -152.981864) (xy 197.834976 -153.0048)
			(xy 197.886882 -153.034767) (xy 197.934432 -153.071254) (xy 197.976812 -153.113634) (xy 198.013299 -153.161184)
			(xy 198.043266 -153.21309) (xy 198.066202 -153.268463) (xy 198.081715 -153.326356) (xy 198.089538 -153.385778)
			(xy 198.090028 -153.415746) (xy 198.090028 -153.675842) (xy 222.211136 -153.675842) (xy 222.215207 -153.62022)
			(xy 222.227333 -153.565783) (xy 222.247256 -153.513692) (xy 222.274552 -153.465057) (xy 222.308638 -153.420914)
			(xy 222.348787 -153.382205) (xy 222.394145 -153.349754) (xy 222.443745 -153.324253) (xy 222.496529 -153.306246)
			(xy 222.551372 -153.296116) (xy 222.607106 -153.294079) (xy 222.662543 -153.300179) (xy 222.7165 -153.314285)
			(xy 222.767829 -153.336097) (xy 222.815435 -153.365151) (xy 222.858303 -153.400826) (xy 222.89552 -153.442363)
			(xy 222.926293 -153.488876) (xy 222.949965 -153.539373) (xy 222.966033 -153.59278) (xy 222.974153 -153.647956)
			(xy 222.974662 -153.675842) (xy 222.974153 -153.703728) (xy 222.966033 -153.758904) (xy 222.958927 -153.782522)
			(xy 246.97766 -153.782522) (xy 246.981731 -153.7269) (xy 246.993857 -153.672463) (xy 247.01378 -153.620372)
			(xy 247.041076 -153.571737) (xy 247.075162 -153.527594) (xy 247.115311 -153.488885) (xy 247.160669 -153.456434)
			(xy 247.210269 -153.430933) (xy 247.263053 -153.412926) (xy 247.317896 -153.402796) (xy 247.37363 -153.400759)
			(xy 247.429067 -153.406859) (xy 247.483024 -153.420965) (xy 247.534353 -153.442777) (xy 247.581959 -153.471831)
			(xy 247.624827 -153.507506) (xy 247.662044 -153.549043) (xy 247.692817 -153.595556) (xy 247.716489 -153.646053)
			(xy 247.732557 -153.69946) (xy 247.740677 -153.754636) (xy 247.741186 -153.782522) (xy 247.99366 -153.782522)
			(xy 247.997731 -153.7269) (xy 248.009857 -153.672463) (xy 248.02978 -153.620372) (xy 248.057076 -153.571737)
			(xy 248.091162 -153.527594) (xy 248.131311 -153.488885) (xy 248.176669 -153.456434) (xy 248.226269 -153.430933)
			(xy 248.279053 -153.412926) (xy 248.333896 -153.402796) (xy 248.38963 -153.400759) (xy 248.445067 -153.406859)
			(xy 248.499024 -153.420965) (xy 248.550353 -153.442777) (xy 248.597959 -153.471831) (xy 248.640827 -153.507506)
			(xy 248.678044 -153.549043) (xy 248.708817 -153.595556) (xy 248.732489 -153.646053) (xy 248.748557 -153.69946)
			(xy 248.756677 -153.754636) (xy 248.757186 -153.782522) (xy 248.756677 -153.810408) (xy 248.753529 -153.831798)
			(xy 249.00966 -153.831798) (xy 249.013731 -153.776176) (xy 249.025857 -153.721739) (xy 249.04578 -153.669648)
			(xy 249.073076 -153.621013) (xy 249.107162 -153.57687) (xy 249.147311 -153.538161) (xy 249.192669 -153.50571)
			(xy 249.242269 -153.480209) (xy 249.295053 -153.462202) (xy 249.349896 -153.452072) (xy 249.40563 -153.450035)
			(xy 249.461067 -153.456135) (xy 249.515024 -153.470241) (xy 249.566353 -153.492053) (xy 249.613959 -153.521107)
			(xy 249.656827 -153.556782) (xy 249.694044 -153.598319) (xy 249.724817 -153.644832) (xy 249.748489 -153.695329)
			(xy 249.764557 -153.748736) (xy 249.769529 -153.782522) (xy 252.05766 -153.782522) (xy 252.061731 -153.7269)
			(xy 252.073857 -153.672463) (xy 252.09378 -153.620372) (xy 252.121076 -153.571737) (xy 252.155162 -153.527594)
			(xy 252.195311 -153.488885) (xy 252.240669 -153.456434) (xy 252.290269 -153.430933) (xy 252.343053 -153.412926)
			(xy 252.397896 -153.402796) (xy 252.45363 -153.400759) (xy 252.509067 -153.406859) (xy 252.563024 -153.420965)
			(xy 252.614353 -153.442777) (xy 252.661959 -153.471831) (xy 252.704827 -153.507506) (xy 252.742044 -153.549043)
			(xy 252.772817 -153.595556) (xy 252.796489 -153.646053) (xy 252.812557 -153.69946) (xy 252.820677 -153.754636)
			(xy 252.821186 -153.782522) (xy 254.08966 -153.782522) (xy 254.093731 -153.7269) (xy 254.105857 -153.672463)
			(xy 254.12578 -153.620372) (xy 254.153076 -153.571737) (xy 254.187162 -153.527594) (xy 254.227311 -153.488885)
			(xy 254.272669 -153.456434) (xy 254.322269 -153.430933) (xy 254.375053 -153.412926) (xy 254.429896 -153.402796)
			(xy 254.48563 -153.400759) (xy 254.541067 -153.406859) (xy 254.595024 -153.420965) (xy 254.646353 -153.442777)
			(xy 254.693959 -153.471831) (xy 254.736827 -153.507506) (xy 254.774044 -153.549043) (xy 254.804817 -153.595556)
			(xy 254.828489 -153.646053) (xy 254.844557 -153.69946) (xy 254.852677 -153.754636) (xy 254.853186 -153.782522)
			(xy 254.852677 -153.810408) (xy 254.844557 -153.865584) (xy 254.828489 -153.918991) (xy 254.804817 -153.969488)
			(xy 254.774044 -154.016001) (xy 254.736827 -154.057538) (xy 254.693959 -154.093213) (xy 254.646353 -154.122267)
			(xy 254.595024 -154.144079) (xy 254.541067 -154.158185) (xy 254.48563 -154.164285) (xy 254.429896 -154.162248)
			(xy 254.375053 -154.152118) (xy 254.322269 -154.134111) (xy 254.272669 -154.10861) (xy 254.227311 -154.076159)
			(xy 254.187162 -154.03745) (xy 254.153076 -153.993307) (xy 254.12578 -153.944672) (xy 254.105857 -153.892581)
			(xy 254.093731 -153.838144) (xy 254.08966 -153.782522) (xy 252.821186 -153.782522) (xy 252.820677 -153.810408)
			(xy 252.812557 -153.865584) (xy 252.796489 -153.918991) (xy 252.772817 -153.969488) (xy 252.742044 -154.016001)
			(xy 252.704827 -154.057538) (xy 252.661959 -154.093213) (xy 252.614353 -154.122267) (xy 252.563024 -154.144079)
			(xy 252.509067 -154.158185) (xy 252.45363 -154.164285) (xy 252.397896 -154.162248) (xy 252.343053 -154.152118)
			(xy 252.290269 -154.134111) (xy 252.240669 -154.10861) (xy 252.195311 -154.076159) (xy 252.155162 -154.03745)
			(xy 252.121076 -153.993307) (xy 252.09378 -153.944672) (xy 252.073857 -153.892581) (xy 252.061731 -153.838144)
			(xy 252.05766 -153.782522) (xy 249.769529 -153.782522) (xy 249.772677 -153.803912) (xy 249.773186 -153.831798)
			(xy 249.772677 -153.859684) (xy 249.764557 -153.91486) (xy 249.748489 -153.968267) (xy 249.724817 -154.018764)
			(xy 249.694044 -154.065277) (xy 249.656827 -154.106814) (xy 249.613959 -154.142489) (xy 249.566353 -154.171543)
			(xy 249.515024 -154.193355) (xy 249.461067 -154.207461) (xy 249.40563 -154.213561) (xy 249.349896 -154.211524)
			(xy 249.295053 -154.201394) (xy 249.242269 -154.183387) (xy 249.192669 -154.157886) (xy 249.147311 -154.125435)
			(xy 249.107162 -154.086726) (xy 249.073076 -154.042583) (xy 249.04578 -153.993948) (xy 249.025857 -153.941857)
			(xy 249.013731 -153.88742) (xy 249.00966 -153.831798) (xy 248.753529 -153.831798) (xy 248.748557 -153.865584)
			(xy 248.732489 -153.918991) (xy 248.708817 -153.969488) (xy 248.678044 -154.016001) (xy 248.640827 -154.057538)
			(xy 248.597959 -154.093213) (xy 248.550353 -154.122267) (xy 248.499024 -154.144079) (xy 248.445067 -154.158185)
			(xy 248.38963 -154.164285) (xy 248.333896 -154.162248) (xy 248.279053 -154.152118) (xy 248.226269 -154.134111)
			(xy 248.176669 -154.10861) (xy 248.131311 -154.076159) (xy 248.091162 -154.03745) (xy 248.057076 -153.993307)
			(xy 248.02978 -153.944672) (xy 248.009857 -153.892581) (xy 247.997731 -153.838144) (xy 247.99366 -153.782522)
			(xy 247.741186 -153.782522) (xy 247.740677 -153.810408) (xy 247.732557 -153.865584) (xy 247.716489 -153.918991)
			(xy 247.692817 -153.969488) (xy 247.662044 -154.016001) (xy 247.624827 -154.057538) (xy 247.581959 -154.093213)
			(xy 247.534353 -154.122267) (xy 247.483024 -154.144079) (xy 247.429067 -154.158185) (xy 247.37363 -154.164285)
			(xy 247.317896 -154.162248) (xy 247.263053 -154.152118) (xy 247.210269 -154.134111) (xy 247.160669 -154.10861)
			(xy 247.115311 -154.076159) (xy 247.075162 -154.03745) (xy 247.041076 -153.993307) (xy 247.01378 -153.944672)
			(xy 246.993857 -153.892581) (xy 246.981731 -153.838144) (xy 246.97766 -153.782522) (xy 222.958927 -153.782522)
			(xy 222.949965 -153.812311) (xy 222.926293 -153.862808) (xy 222.89552 -153.909321) (xy 222.858303 -153.950858)
			(xy 222.815435 -153.986533) (xy 222.767829 -154.015587) (xy 222.7165 -154.037399) (xy 222.662543 -154.051505)
			(xy 222.607106 -154.057605) (xy 222.551372 -154.055568) (xy 222.496529 -154.045438) (xy 222.443745 -154.027431)
			(xy 222.394145 -154.00193) (xy 222.348787 -153.969479) (xy 222.308638 -153.93077) (xy 222.274552 -153.886627)
			(xy 222.247256 -153.837992) (xy 222.227333 -153.785901) (xy 222.215207 -153.731464) (xy 222.211136 -153.675842)
			(xy 198.090028 -153.675842) (xy 198.090028 -154.279346) (xy 198.089538 -154.309314) (xy 198.081715 -154.368736)
			(xy 198.066202 -154.426629) (xy 198.043266 -154.482002) (xy 198.013299 -154.533908) (xy 197.989562 -154.564842)
			(xy 222.211136 -154.564842) (xy 222.215207 -154.50922) (xy 222.227333 -154.454783) (xy 222.247256 -154.402692)
			(xy 222.274552 -154.354057) (xy 222.308638 -154.309914) (xy 222.348787 -154.271205) (xy 222.394145 -154.238754)
			(xy 222.443745 -154.213253) (xy 222.496529 -154.195246) (xy 222.551372 -154.185116) (xy 222.607106 -154.183079)
			(xy 222.662543 -154.189179) (xy 222.7165 -154.203285) (xy 222.767829 -154.225097) (xy 222.815435 -154.254151)
			(xy 222.858303 -154.289826) (xy 222.89552 -154.331363) (xy 222.926293 -154.377876) (xy 222.949965 -154.428373)
			(xy 222.966033 -154.48178) (xy 222.974153 -154.536956) (xy 222.974662 -154.564842) (xy 222.974153 -154.592728)
			(xy 222.966033 -154.647904) (xy 222.949965 -154.701311) (xy 222.926293 -154.751808) (xy 222.89552 -154.798321)
			(xy 222.858303 -154.839858) (xy 222.830755 -154.862784) (xy 227.184964 -154.862784) (xy 227.189035 -154.807162)
			(xy 227.201161 -154.752725) (xy 227.221084 -154.700634) (xy 227.24838 -154.651999) (xy 227.282466 -154.607856)
			(xy 227.322615 -154.569147) (xy 227.367973 -154.536696) (xy 227.417573 -154.511195) (xy 227.470357 -154.493188)
			(xy 227.5252 -154.483058) (xy 227.580934 -154.481021) (xy 227.636371 -154.487121) (xy 227.690328 -154.501227)
			(xy 227.741657 -154.523039) (xy 227.789263 -154.552093) (xy 227.832131 -154.587768) (xy 227.869348 -154.629305)
			(xy 227.883835 -154.651202) (xy 234.809028 -154.651202) (xy 234.813099 -154.59558) (xy 234.825225 -154.541143)
			(xy 234.845148 -154.489052) (xy 234.872444 -154.440417) (xy 234.90653 -154.396274) (xy 234.946679 -154.357565)
			(xy 234.992037 -154.325114) (xy 235.041637 -154.299613) (xy 235.094421 -154.281606) (xy 235.149264 -154.271476)
			(xy 235.204998 -154.269439) (xy 235.260435 -154.275539) (xy 235.314392 -154.289645) (xy 235.365721 -154.311457)
			(xy 235.413327 -154.340511) (xy 235.456195 -154.376186) (xy 235.493412 -154.417723) (xy 235.524185 -154.464236)
			(xy 235.547857 -154.514733) (xy 235.563925 -154.56814) (xy 235.572045 -154.623316) (xy 235.572554 -154.651202)
			(xy 235.572045 -154.679088) (xy 235.563925 -154.734264) (xy 235.547857 -154.787671) (xy 235.524185 -154.838168)
			(xy 235.493412 -154.884681) (xy 235.456195 -154.926218) (xy 235.413327 -154.961893) (xy 235.365721 -154.990947)
			(xy 235.314392 -155.012759) (xy 235.260435 -155.026865) (xy 235.204998 -155.032965) (xy 235.149264 -155.030928)
			(xy 235.094421 -155.020798) (xy 235.041637 -155.002791) (xy 234.992037 -154.97729) (xy 234.946679 -154.944839)
			(xy 234.90653 -154.90613) (xy 234.872444 -154.861987) (xy 234.845148 -154.813352) (xy 234.825225 -154.761261)
			(xy 234.813099 -154.706824) (xy 234.809028 -154.651202) (xy 227.883835 -154.651202) (xy 227.900121 -154.675818)
			(xy 227.923793 -154.726315) (xy 227.939861 -154.779722) (xy 227.947981 -154.834898) (xy 227.94849 -154.862784)
			(xy 227.947981 -154.89067) (xy 227.939861 -154.945846) (xy 227.923793 -154.999253) (xy 227.900121 -155.04975)
			(xy 227.869348 -155.096263) (xy 227.832131 -155.1378) (xy 227.789263 -155.173475) (xy 227.741657 -155.202529)
			(xy 227.690328 -155.224341) (xy 227.636371 -155.238447) (xy 227.580934 -155.244547) (xy 227.5252 -155.24251)
			(xy 227.470357 -155.23238) (xy 227.417573 -155.214373) (xy 227.367973 -155.188872) (xy 227.322615 -155.156421)
			(xy 227.282466 -155.117712) (xy 227.24838 -155.073569) (xy 227.221084 -155.024934) (xy 227.201161 -154.972843)
			(xy 227.189035 -154.918406) (xy 227.184964 -154.862784) (xy 222.830755 -154.862784) (xy 222.815435 -154.875533)
			(xy 222.767829 -154.904587) (xy 222.7165 -154.926399) (xy 222.662543 -154.940505) (xy 222.607106 -154.946605)
			(xy 222.551372 -154.944568) (xy 222.496529 -154.934438) (xy 222.443745 -154.916431) (xy 222.394145 -154.89093)
			(xy 222.348787 -154.858479) (xy 222.308638 -154.81977) (xy 222.274552 -154.775627) (xy 222.247256 -154.726992)
			(xy 222.227333 -154.674901) (xy 222.215207 -154.620464) (xy 222.211136 -154.564842) (xy 197.989562 -154.564842)
			(xy 197.976812 -154.581458) (xy 197.934432 -154.623838) (xy 197.886882 -154.660325) (xy 197.834976 -154.690292)
			(xy 197.779603 -154.713228) (xy 197.72171 -154.728741) (xy 197.662288 -154.736564) (xy 197.602352 -154.736564)
			(xy 197.54293 -154.728741) (xy 197.485037 -154.713228) (xy 197.429664 -154.690292) (xy 197.377758 -154.660325)
			(xy 197.330208 -154.623838) (xy 197.287828 -154.581458) (xy 197.251341 -154.533908) (xy 197.221374 -154.482002)
			(xy 197.198438 -154.426629) (xy 197.182925 -154.368736) (xy 197.175102 -154.309314) (xy 197.174612 -154.279346)
			(xy 195.676201 -154.279346) (xy 195.626736 -154.652726) (xy 195.591938 -154.916124) (xy 195.591684 -154.918664)
			(xy 195.494022 -156.085794) (xy 199.81672 -156.085794) (xy 199.81672 -155.222194) (xy 199.81721 -155.192226)
			(xy 199.825033 -155.132804) (xy 199.840546 -155.074911) (xy 199.863482 -155.019538) (xy 199.893449 -154.967632)
			(xy 199.929936 -154.920082) (xy 199.972316 -154.877702) (xy 200.019866 -154.841215) (xy 200.071772 -154.811248)
			(xy 200.127145 -154.788312) (xy 200.185038 -154.772799) (xy 200.24446 -154.764976) (xy 200.304396 -154.764976)
			(xy 200.363818 -154.772799) (xy 200.421711 -154.788312) (xy 200.477084 -154.811248) (xy 200.52899 -154.841215)
			(xy 200.57654 -154.877702) (xy 200.61892 -154.920082) (xy 200.655407 -154.967632) (xy 200.685374 -155.019538)
			(xy 200.70831 -155.074911) (xy 200.723823 -155.132804) (xy 200.731646 -155.192226) (xy 200.732136 -155.222194)
			(xy 200.732136 -155.540202) (xy 234.809028 -155.540202) (xy 234.813099 -155.48458) (xy 234.825225 -155.430143)
			(xy 234.845148 -155.378052) (xy 234.872444 -155.329417) (xy 234.90653 -155.285274) (xy 234.946679 -155.246565)
			(xy 234.992037 -155.214114) (xy 235.041637 -155.188613) (xy 235.094421 -155.170606) (xy 235.149264 -155.160476)
			(xy 235.204998 -155.158439) (xy 235.260435 -155.164539) (xy 235.314392 -155.178645) (xy 235.365721 -155.200457)
			(xy 235.38469 -155.212034) (xy 239.469166 -155.212034) (xy 239.473237 -155.156412) (xy 239.485363 -155.101975)
			(xy 239.505286 -155.049884) (xy 239.532582 -155.001249) (xy 239.566668 -154.957106) (xy 239.606817 -154.918397)
			(xy 239.652175 -154.885946) (xy 239.701775 -154.860445) (xy 239.754559 -154.842438) (xy 239.809402 -154.832308)
			(xy 239.865136 -154.830271) (xy 239.920573 -154.836371) (xy 239.97453 -154.850477) (xy 240.025859 -154.872289)
			(xy 240.073465 -154.901343) (xy 240.116333 -154.937018) (xy 240.15355 -154.978555) (xy 240.184323 -155.025068)
			(xy 240.207995 -155.075565) (xy 240.209086 -155.079192) (xy 242.069872 -155.079192) (xy 242.073943 -155.02357)
			(xy 242.086069 -154.969133) (xy 242.105992 -154.917042) (xy 242.133288 -154.868407) (xy 242.167374 -154.824264)
			(xy 242.207523 -154.785555) (xy 242.252881 -154.753104) (xy 242.302481 -154.727603) (xy 242.355265 -154.709596)
			(xy 242.410108 -154.699466) (xy 242.465842 -154.697429) (xy 242.521279 -154.703529) (xy 242.575236 -154.717635)
			(xy 242.626565 -154.739447) (xy 242.674171 -154.768501) (xy 242.717039 -154.804176) (xy 242.754256 -154.845713)
			(xy 242.785029 -154.892226) (xy 242.808701 -154.942723) (xy 242.824769 -154.99613) (xy 242.832889 -155.051306)
			(xy 242.833398 -155.079192) (xy 242.833333 -155.082748) (xy 243.393722 -155.082748) (xy 243.394148 -155.056433)
			(xy 243.40139 -155.004302) (xy 243.415717 -154.953658) (xy 243.436857 -154.905459) (xy 243.464411 -154.860617)
			(xy 243.497857 -154.819979) (xy 243.516912 -154.801824) (xy 243.524307 -154.794297) (xy 243.532835 -154.775021)
			(xy 243.533422 -154.764486) (xy 243.533422 -154.68981) (xy 243.532895 -154.67926) (xy 243.524358 -154.659965)
			(xy 243.516912 -154.652472) (xy 243.497852 -154.634321) (xy 243.464395 -154.59369) (xy 243.436836 -154.548849)
			(xy 243.415698 -154.500648) (xy 243.401382 -154.449999) (xy 243.394159 -154.397864) (xy 243.393722 -154.371548)
			(xy 243.3942 -154.344295) (xy 243.401951 -154.290343) (xy 243.417303 -154.238044) (xy 243.439942 -154.188462)
			(xy 243.469408 -154.142607) (xy 243.5051 -154.101413) (xy 243.546292 -154.065718) (xy 243.592146 -154.03625)
			(xy 243.641727 -154.013609) (xy 243.694025 -153.998255) (xy 243.747977 -153.990501) (xy 243.77523 -153.99004)
			(xy 243.801545 -153.990475) (xy 243.853676 -153.997714) (xy 243.90432 -154.012039) (xy 243.952519 -154.033178)
			(xy 243.997361 -154.06073) (xy 244.037999 -154.094175) (xy 244.056154 -154.11323) (xy 244.063663 -154.120647)
			(xy 244.082952 -154.129165) (xy 244.093492 -154.12974) (xy 244.168168 -154.12974) (xy 244.178716 -154.129195)
			(xy 244.19801 -154.12067) (xy 244.205506 -154.11323) (xy 244.225326 -154.092442) (xy 244.270098 -154.056467)
			(xy 244.319756 -154.027607) (xy 244.373178 -154.006514) (xy 244.429157 -153.993665) (xy 244.48643 -153.98935)
			(xy 244.543703 -153.993665) (xy 244.599682 -154.006514) (xy 244.653104 -154.027607) (xy 244.702762 -154.056467)
			(xy 244.747534 -154.092442) (xy 244.767354 -154.11323) (xy 244.774863 -154.120647) (xy 244.794152 -154.129165)
			(xy 244.804692 -154.12974) (xy 244.879368 -154.12974) (xy 244.889916 -154.129195) (xy 244.90921 -154.12067)
			(xy 244.916706 -154.11323) (xy 244.936526 -154.092442) (xy 244.981298 -154.056467) (xy 245.030956 -154.027607)
			(xy 245.084378 -154.006514) (xy 245.140357 -153.993665) (xy 245.19763 -153.98935) (xy 245.254903 -153.993665)
			(xy 245.310882 -154.006514) (xy 245.364304 -154.027607) (xy 245.413962 -154.056467) (xy 245.458734 -154.092442)
			(xy 245.478554 -154.11323) (xy 245.486063 -154.120647) (xy 245.505352 -154.129165) (xy 245.515892 -154.12974)
			(xy 245.590568 -154.12974) (xy 245.601116 -154.129195) (xy 245.62041 -154.12067) (xy 245.627906 -154.11323)
			(xy 245.646072 -154.094184) (xy 245.686698 -154.060725) (xy 245.731536 -154.033164) (xy 245.779735 -154.012024)
			(xy 245.830381 -153.997705) (xy 245.882514 -153.990479) (xy 245.90883 -153.99004) (xy 245.936086 -153.990427)
			(xy 245.990042 -153.998189) (xy 246.042344 -154.013552) (xy 246.091928 -154.036201) (xy 246.137783 -154.065677)
			(xy 246.178977 -154.101379) (xy 246.21467 -154.142579) (xy 246.244136 -154.188441) (xy 246.266776 -154.238029)
			(xy 246.282127 -154.290334) (xy 246.289878 -154.344292) (xy 246.290338 -154.371548) (xy 246.289922 -154.397864)
			(xy 246.28268 -154.449996) (xy 246.268352 -154.50064) (xy 246.24721 -154.548839) (xy 246.219654 -154.593681)
			(xy 246.186205 -154.634318) (xy 246.167148 -154.652472) (xy 246.159764 -154.660009) (xy 246.151228 -154.679277)
			(xy 246.150638 -154.68981) (xy 246.150638 -154.764486) (xy 246.15115 -154.775038) (xy 246.159696 -154.794334)
			(xy 246.167148 -154.801824) (xy 246.186217 -154.819965) (xy 246.219671 -154.860599) (xy 246.247227 -154.905443)
			(xy 246.268363 -154.953646) (xy 246.282678 -155.004296) (xy 246.2899 -155.056431) (xy 246.290338 -155.082748)
			(xy 246.289867 -155.109999) (xy 246.282105 -155.163946) (xy 246.266745 -155.216239) (xy 246.2441 -155.265814)
			(xy 246.214632 -155.311663) (xy 246.178939 -155.352852) (xy 246.137749 -155.388543) (xy 246.091899 -155.418009)
			(xy 246.042322 -155.440651) (xy 245.990028 -155.456008) (xy 245.936081 -155.463768) (xy 245.90883 -155.464256)
			(xy 245.882514 -155.463849) (xy 245.830382 -155.456604) (xy 245.779738 -155.442274) (xy 245.731539 -155.42113)
			(xy 245.686697 -155.393573) (xy 245.64606 -155.360123) (xy 245.627906 -155.341066) (xy 245.620375 -155.333675)
			(xy 245.601103 -155.325142) (xy 245.590568 -155.324556) (xy 245.515892 -155.324556) (xy 245.505342 -155.32508)
			(xy 245.486048 -155.33362) (xy 245.478554 -155.341066) (xy 245.458734 -155.361854) (xy 245.413962 -155.397829)
			(xy 245.364304 -155.426689) (xy 245.310882 -155.447782) (xy 245.254903 -155.460631) (xy 245.19763 -155.464946)
			(xy 245.140357 -155.460631) (xy 245.084378 -155.447782) (xy 245.030956 -155.426689) (xy 244.981298 -155.397829)
			(xy 244.936526 -155.361854) (xy 244.916706 -155.341066) (xy 244.909175 -155.333675) (xy 244.889903 -155.325142)
			(xy 244.879368 -155.324556) (xy 244.804692 -155.324556) (xy 244.794142 -155.32508) (xy 244.774848 -155.33362)
			(xy 244.767354 -155.341066) (xy 244.747534 -155.361854) (xy 244.702762 -155.397829) (xy 244.653104 -155.426689)
			(xy 244.599682 -155.447782) (xy 244.543703 -155.460631) (xy 244.48643 -155.464946) (xy 244.429157 -155.460631)
			(xy 244.373178 -155.447782) (xy 244.319756 -155.426689) (xy 244.270098 -155.397829) (xy 244.225326 -155.361854)
			(xy 244.205506 -155.341066) (xy 244.197975 -155.333675) (xy 244.178703 -155.325142) (xy 244.168168 -155.324556)
			(xy 244.093492 -155.324556) (xy 244.082942 -155.32508) (xy 244.063648 -155.33362) (xy 244.056154 -155.341066)
			(xy 244.038027 -155.360149) (xy 243.997389 -155.393602) (xy 243.952543 -155.421155) (xy 243.904337 -155.442288)
			(xy 243.853685 -155.4566) (xy 243.801548 -155.46382) (xy 243.77523 -155.464256) (xy 243.747982 -155.463694)
			(xy 243.694039 -155.455943) (xy 243.641749 -155.440594) (xy 243.592175 -155.41796) (xy 243.546327 -155.388501)
			(xy 243.505138 -155.352818) (xy 243.469446 -155.311636) (xy 243.439978 -155.265793) (xy 243.417333 -155.216224)
			(xy 243.401974 -155.163937) (xy 243.394212 -155.109996) (xy 243.393722 -155.082748) (xy 242.833333 -155.082748)
			(xy 242.832889 -155.107078) (xy 242.824769 -155.162254) (xy 242.808701 -155.215661) (xy 242.785029 -155.266158)
			(xy 242.754256 -155.312671) (xy 242.717039 -155.354208) (xy 242.674171 -155.389883) (xy 242.626565 -155.418937)
			(xy 242.575236 -155.440749) (xy 242.521279 -155.454855) (xy 242.465842 -155.460955) (xy 242.410108 -155.458918)
			(xy 242.355265 -155.448788) (xy 242.302481 -155.430781) (xy 242.252881 -155.40528) (xy 242.207523 -155.372829)
			(xy 242.167374 -155.33412) (xy 242.133288 -155.289977) (xy 242.105992 -155.241342) (xy 242.086069 -155.189251)
			(xy 242.073943 -155.134814) (xy 242.069872 -155.079192) (xy 240.209086 -155.079192) (xy 240.224063 -155.128972)
			(xy 240.232183 -155.184148) (xy 240.232692 -155.212034) (xy 240.232183 -155.23992) (xy 240.224063 -155.295096)
			(xy 240.207995 -155.348503) (xy 240.184323 -155.399) (xy 240.15355 -155.445513) (xy 240.116333 -155.48705)
			(xy 240.073465 -155.522725) (xy 240.025859 -155.551779) (xy 239.97453 -155.573591) (xy 239.920573 -155.587697)
			(xy 239.865136 -155.593797) (xy 239.809402 -155.59176) (xy 239.754559 -155.58163) (xy 239.701775 -155.563623)
			(xy 239.652175 -155.538122) (xy 239.606817 -155.505671) (xy 239.566668 -155.466962) (xy 239.532582 -155.422819)
			(xy 239.505286 -155.374184) (xy 239.485363 -155.322093) (xy 239.473237 -155.267656) (xy 239.469166 -155.212034)
			(xy 235.38469 -155.212034) (xy 235.413327 -155.229511) (xy 235.456195 -155.265186) (xy 235.493412 -155.306723)
			(xy 235.524185 -155.353236) (xy 235.547857 -155.403733) (xy 235.563925 -155.45714) (xy 235.572045 -155.512316)
			(xy 235.572554 -155.540202) (xy 235.572045 -155.568088) (xy 235.563925 -155.623264) (xy 235.547857 -155.676671)
			(xy 235.524185 -155.727168) (xy 235.493412 -155.773681) (xy 235.456195 -155.815218) (xy 235.413327 -155.850893)
			(xy 235.365721 -155.879947) (xy 235.314392 -155.901759) (xy 235.260435 -155.915865) (xy 235.204998 -155.921965)
			(xy 235.149264 -155.919928) (xy 235.094421 -155.909798) (xy 235.041637 -155.891791) (xy 234.992037 -155.86629)
			(xy 234.946679 -155.833839) (xy 234.90653 -155.79513) (xy 234.872444 -155.750987) (xy 234.845148 -155.702352)
			(xy 234.825225 -155.650261) (xy 234.813099 -155.595824) (xy 234.809028 -155.540202) (xy 200.732136 -155.540202)
			(xy 200.732136 -156.085794) (xy 200.731646 -156.115762) (xy 200.723823 -156.175184) (xy 200.70831 -156.233077)
			(xy 200.685374 -156.28845) (xy 200.655407 -156.340356) (xy 200.61892 -156.387906) (xy 200.57654 -156.430286)
			(xy 200.52899 -156.466773) (xy 200.477084 -156.49674) (xy 200.421711 -156.519676) (xy 200.363818 -156.535189)
			(xy 200.304396 -156.543012) (xy 200.24446 -156.543012) (xy 200.185038 -156.535189) (xy 200.127145 -156.519676)
			(xy 200.071772 -156.49674) (xy 200.019866 -156.466773) (xy 199.972316 -156.430286) (xy 199.929936 -156.387906)
			(xy 199.893449 -156.340356) (xy 199.863482 -156.28845) (xy 199.840546 -156.233077) (xy 199.825033 -156.175184)
			(xy 199.81721 -156.115762) (xy 199.81672 -156.085794) (xy 195.494022 -156.085794) (xy 195.416827 -157.008322)
			(xy 226.168964 -157.008322) (xy 226.173035 -156.9527) (xy 226.185161 -156.898263) (xy 226.205084 -156.846172)
			(xy 226.23238 -156.797537) (xy 226.266466 -156.753394) (xy 226.306615 -156.714685) (xy 226.351973 -156.682234)
			(xy 226.401573 -156.656733) (xy 226.454357 -156.638726) (xy 226.5092 -156.628596) (xy 226.564934 -156.626559)
			(xy 226.620371 -156.632659) (xy 226.674328 -156.646765) (xy 226.725657 -156.668577) (xy 226.7671 -156.69387)
			(xy 241.0874 -156.69387) (xy 241.091471 -156.638248) (xy 241.103597 -156.583811) (xy 241.12352 -156.53172)
			(xy 241.150816 -156.483085) (xy 241.184902 -156.438942) (xy 241.225051 -156.400233) (xy 241.270409 -156.367782)
			(xy 241.320009 -156.342281) (xy 241.372793 -156.324274) (xy 241.427636 -156.314144) (xy 241.48337 -156.312107)
			(xy 241.538807 -156.318207) (xy 241.592764 -156.332313) (xy 241.644093 -156.354125) (xy 241.691699 -156.383179)
			(xy 241.734567 -156.418854) (xy 241.771784 -156.460391) (xy 241.802557 -156.506904) (xy 241.826229 -156.557401)
			(xy 241.842297 -156.610808) (xy 241.850417 -156.665984) (xy 241.850926 -156.69387) (xy 241.850417 -156.721756)
			(xy 241.842297 -156.776932) (xy 241.826229 -156.830339) (xy 241.802557 -156.880836) (xy 241.771784 -156.927349)
			(xy 241.734567 -156.968886) (xy 241.691699 -157.004561) (xy 241.644093 -157.033615) (xy 241.592764 -157.055427)
			(xy 241.538807 -157.069533) (xy 241.48337 -157.075633) (xy 241.427636 -157.073596) (xy 241.372793 -157.063466)
			(xy 241.320009 -157.045459) (xy 241.270409 -157.019958) (xy 241.225051 -156.987507) (xy 241.184902 -156.948798)
			(xy 241.150816 -156.904655) (xy 241.12352 -156.85602) (xy 241.103597 -156.803929) (xy 241.091471 -156.749492)
			(xy 241.0874 -156.69387) (xy 226.7671 -156.69387) (xy 226.773263 -156.697631) (xy 226.816131 -156.733306)
			(xy 226.853348 -156.774843) (xy 226.884121 -156.821356) (xy 226.907793 -156.871853) (xy 226.923861 -156.92526)
			(xy 226.931981 -156.980436) (xy 226.93249 -157.008322) (xy 226.931981 -157.036208) (xy 226.923861 -157.091384)
			(xy 226.907793 -157.144791) (xy 226.884121 -157.195288) (xy 226.853348 -157.241801) (xy 226.816131 -157.283338)
			(xy 226.773263 -157.319013) (xy 226.725657 -157.348067) (xy 226.674328 -157.369879) (xy 226.620371 -157.383985)
			(xy 226.564934 -157.390085) (xy 226.5092 -157.388048) (xy 226.454357 -157.377918) (xy 226.401573 -157.359911)
			(xy 226.351973 -157.33441) (xy 226.306615 -157.301959) (xy 226.266466 -157.26325) (xy 226.23238 -157.219107)
			(xy 226.205084 -157.170472) (xy 226.185161 -157.118381) (xy 226.173035 -157.063944) (xy 226.168964 -157.008322)
			(xy 195.416827 -157.008322) (xy 195.365116 -157.626304) (xy 195.365116 -157.62732) (xy 195.362898 -157.65126)
			(xy 195.356418 -157.698907) (xy 195.352162 -157.72257) (xy 195.260855 -158.219648) (xy 197.282052 -158.219648)
			(xy 197.286123 -158.164026) (xy 197.298249 -158.109589) (xy 197.318172 -158.057498) (xy 197.345468 -158.008863)
			(xy 197.379554 -157.96472) (xy 197.419703 -157.926011) (xy 197.465061 -157.89356) (xy 197.514661 -157.868059)
			(xy 197.567445 -157.850052) (xy 197.622288 -157.839922) (xy 197.678022 -157.837885) (xy 197.733459 -157.843985)
			(xy 197.787416 -157.858091) (xy 197.838745 -157.879903) (xy 197.871783 -157.900066) (xy 228.314505 -157.900066)
			(xy 228.314505 -157.840134) (xy 228.322328 -157.780714) (xy 228.33784 -157.722823) (xy 228.360775 -157.667453)
			(xy 228.390741 -157.61555) (xy 228.427226 -157.568002) (xy 228.469605 -157.525624) (xy 228.517153 -157.489139)
			(xy 228.569056 -157.459173) (xy 228.624427 -157.436238) (xy 228.682318 -157.420727) (xy 228.741738 -157.412905)
			(xy 228.771704 -157.412436) (xy 229.635304 -157.412436) (xy 229.665274 -157.412838) (xy 229.724702 -157.420663)
			(xy 229.7826 -157.436177) (xy 229.837978 -157.459116) (xy 229.889888 -157.489086) (xy 229.937442 -157.525576)
			(xy 229.979827 -157.567961) (xy 230.016316 -157.615515) (xy 230.046286 -157.667425) (xy 230.069224 -157.722803)
			(xy 230.084738 -157.780702) (xy 230.092562 -157.84013) (xy 230.092562 -157.90007) (xy 230.089876 -157.920473)
			(xy 230.557725 -157.920473) (xy 230.557725 -157.860527) (xy 230.56555 -157.801095) (xy 230.581066 -157.743192)
			(xy 230.604007 -157.68781) (xy 230.633981 -157.635897) (xy 230.670475 -157.58834) (xy 230.712864 -157.545953)
			(xy 230.760423 -157.509463) (xy 230.812339 -157.479493) (xy 230.867722 -157.456555) (xy 230.925626 -157.441044)
			(xy 230.985059 -157.433223) (xy 231.015032 -157.432756) (xy 231.878632 -157.432756) (xy 231.908596 -157.43332)
			(xy 231.968011 -157.441146) (xy 232.025896 -157.45666) (xy 232.081261 -157.479596) (xy 232.133158 -157.509563)
			(xy 232.180701 -157.546046) (xy 232.223075 -157.588423) (xy 232.259555 -157.635968) (xy 232.289518 -157.687868)
			(xy 232.31245 -157.743235) (xy 232.32796 -157.801121) (xy 232.329523 -157.812994) (xy 238.850168 -157.812994)
			(xy 238.854239 -157.757372) (xy 238.866365 -157.702935) (xy 238.886288 -157.650844) (xy 238.913584 -157.602209)
			(xy 238.94767 -157.558066) (xy 238.987819 -157.519357) (xy 239.033177 -157.486906) (xy 239.082777 -157.461405)
			(xy 239.135561 -157.443398) (xy 239.190404 -157.433268) (xy 239.246138 -157.431231) (xy 239.301575 -157.437331)
			(xy 239.355532 -157.451437) (xy 239.406861 -157.473249) (xy 239.454467 -157.502303) (xy 239.497335 -157.537978)
			(xy 239.534552 -157.579515) (xy 239.565325 -157.626028) (xy 239.575575 -157.647894) (xy 243.21389 -157.647894)
			(xy 243.214426 -157.621251) (xy 243.222949 -157.568653) (xy 243.239806 -157.518105) (xy 243.264559 -157.470919)
			(xy 243.296567 -157.428318) (xy 243.334998 -157.391409) (xy 243.356638 -157.37586) (xy 243.367927 -157.367502)
			(xy 243.385779 -157.345826) (xy 243.397058 -157.320111) (xy 243.400914 -157.292297) (xy 243.397056 -157.264483)
			(xy 243.385775 -157.238768) (xy 243.367922 -157.217094) (xy 243.356638 -157.208728) (xy 243.335036 -157.193131)
			(xy 243.296621 -157.156218) (xy 243.264621 -157.113623) (xy 243.239863 -157.066449) (xy 243.222988 -157.015916)
			(xy 243.214432 -156.963332) (xy 243.21389 -156.936694) (xy 243.2144 -156.910707) (xy 243.22253 -156.859372)
			(xy 243.238591 -156.809942) (xy 243.262187 -156.763632) (xy 243.292737 -156.721584) (xy 243.329488 -156.684833)
			(xy 243.371536 -156.654283) (xy 243.417846 -156.630687) (xy 243.467276 -156.614626) (xy 243.518611 -156.606496)
			(xy 243.570585 -156.606496) (xy 243.62192 -156.614626) (xy 243.67135 -156.630687) (xy 243.71766 -156.654283)
			(xy 243.759708 -156.684833) (xy 243.796459 -156.721584) (xy 243.827009 -156.763632) (xy 243.850605 -156.809942)
			(xy 243.866666 -156.859372) (xy 243.874796 -156.910707) (xy 243.875306 -156.936694) (xy 243.874763 -156.963336)
			(xy 243.866242 -157.015935) (xy 243.849386 -157.066483) (xy 243.824634 -157.113669) (xy 243.792628 -157.156269)
			(xy 243.754198 -157.193179) (xy 243.732558 -157.208728) (xy 243.721281 -157.217101) (xy 243.70343 -157.238774)
			(xy 243.692151 -157.264486) (xy 243.688293 -157.292297) (xy 243.692149 -157.320108) (xy 243.703427 -157.34582)
			(xy 243.721276 -157.367494) (xy 243.732558 -157.37586) (xy 243.754153 -157.391465) (xy 243.792569 -157.428377)
			(xy 243.82457 -157.47097) (xy 243.849329 -157.518142) (xy 243.866205 -157.568673) (xy 243.874763 -157.621257)
			(xy 243.875306 -157.647894) (xy 244.113812 -157.647894) (xy 244.114338 -157.621251) (xy 244.122862 -157.568651)
			(xy 244.13972 -157.518103) (xy 244.164475 -157.470916) (xy 244.196485 -157.428316) (xy 244.234919 -157.391408)
			(xy 244.25656 -157.37586) (xy 244.267847 -157.3675) (xy 244.285695 -157.345824) (xy 244.296971 -157.320109)
			(xy 244.300827 -157.292297) (xy 244.29697 -157.264484) (xy 244.285691 -157.23877) (xy 244.267842 -157.217095)
			(xy 244.25656 -157.208728) (xy 244.234963 -157.193125) (xy 244.196547 -157.156213) (xy 244.164545 -157.11362)
			(xy 244.139786 -157.066447) (xy 244.122911 -157.015915) (xy 244.114354 -156.963332) (xy 244.113812 -156.936694)
			(xy 244.114322 -156.910707) (xy 244.122452 -156.859372) (xy 244.138513 -156.809942) (xy 244.162109 -156.763632)
			(xy 244.192659 -156.721584) (xy 244.22941 -156.684833) (xy 244.271458 -156.654283) (xy 244.317768 -156.630687)
			(xy 244.367198 -156.614626) (xy 244.418533 -156.606496) (xy 244.470507 -156.606496) (xy 244.521842 -156.614626)
			(xy 244.571272 -156.630687) (xy 244.617582 -156.654283) (xy 244.65963 -156.684833) (xy 244.696381 -156.721584)
			(xy 244.726931 -156.763632) (xy 244.750527 -156.809942) (xy 244.766588 -156.859372) (xy 244.774718 -156.910707)
			(xy 244.775228 -156.936694) (xy 244.774719 -156.963338) (xy 244.766195 -157.01594) (xy 244.749335 -157.06649)
			(xy 244.724577 -157.113677) (xy 244.692563 -157.156276) (xy 244.654124 -157.193182) (xy 244.63248 -157.208728)
			(xy 244.621201 -157.2171) (xy 244.603346 -157.238771) (xy 244.592064 -157.264484) (xy 244.588206 -157.292297)
			(xy 244.592063 -157.320109) (xy 244.603343 -157.345823) (xy 244.621196 -157.367495) (xy 244.63248 -157.37586)
			(xy 244.65408 -157.391459) (xy 244.692494 -157.428373) (xy 244.724494 -157.470967) (xy 244.749252 -157.518141)
			(xy 244.766128 -157.568673) (xy 244.774685 -157.621256) (xy 244.775228 -157.647894) (xy 245.013734 -157.647894)
			(xy 245.014251 -157.62125) (xy 245.022775 -157.56865) (xy 245.039635 -157.518101) (xy 245.064392 -157.470914)
			(xy 245.096403 -157.428315) (xy 245.134839 -157.391407) (xy 245.156482 -157.37586) (xy 245.167776 -157.367505)
			(xy 245.185637 -157.345832) (xy 245.196923 -157.320115) (xy 245.200782 -157.292297) (xy 245.196921 -157.264479)
			(xy 245.185634 -157.238763) (xy 245.167771 -157.217091) (xy 245.156482 -157.208728) (xy 245.13489 -157.193118)
			(xy 245.096472 -157.156209) (xy 245.06447 -157.113617) (xy 245.03971 -157.066446) (xy 245.022833 -157.015915)
			(xy 245.014276 -156.963331) (xy 245.013734 -156.936694) (xy 245.014244 -156.910707) (xy 245.022374 -156.859372)
			(xy 245.038435 -156.809942) (xy 245.062031 -156.763632) (xy 245.092581 -156.721584) (xy 245.129332 -156.684833)
			(xy 245.17138 -156.654283) (xy 245.21769 -156.630687) (xy 245.26712 -156.614626) (xy 245.318455 -156.606496)
			(xy 245.370429 -156.606496) (xy 245.421764 -156.614626) (xy 245.471194 -156.630687) (xy 245.517504 -156.654283)
			(xy 245.559552 -156.684833) (xy 245.596303 -156.721584) (xy 245.626853 -156.763632) (xy 245.650449 -156.809942)
			(xy 245.66651 -156.859372) (xy 245.67464 -156.910707) (xy 245.67515 -156.936694) (xy 245.674631 -156.963338)
			(xy 245.666108 -157.015938) (xy 245.649249 -157.066488) (xy 245.624493 -157.113675) (xy 245.592481 -157.156274)
			(xy 245.554045 -157.193181) (xy 245.532402 -157.208728) (xy 245.521121 -157.217099) (xy 245.503263 -157.238769)
			(xy 245.491978 -157.264483) (xy 245.488119 -157.292297) (xy 245.491976 -157.320111) (xy 245.503259 -157.345825)
			(xy 245.521116 -157.367496) (xy 245.532402 -157.37586) (xy 245.553985 -157.391482) (xy 245.592404 -157.428388)
			(xy 245.624408 -157.470977) (xy 245.64917 -157.518146) (xy 245.666048 -157.568676) (xy 245.674607 -157.621257)
			(xy 245.67515 -157.647894) (xy 245.91391 -157.647894) (xy 245.914437 -157.621251) (xy 245.922961 -157.568652)
			(xy 245.939819 -157.518103) (xy 245.964574 -157.470917) (xy 245.996583 -157.428317) (xy 246.035017 -157.391408)
			(xy 246.056658 -157.37586) (xy 246.067946 -157.3675) (xy 246.085793 -157.345824) (xy 246.09707 -157.320109)
			(xy 246.100926 -157.292297) (xy 246.097068 -157.264484) (xy 246.08579 -157.23877) (xy 246.067941 -157.217095)
			(xy 246.056658 -157.208728) (xy 246.035061 -157.193125) (xy 245.996645 -157.156214) (xy 245.964643 -157.11362)
			(xy 245.939884 -157.066447) (xy 245.923009 -157.015915) (xy 245.914452 -156.963332) (xy 245.91391 -156.936694)
			(xy 245.91442 -156.910707) (xy 245.92255 -156.859372) (xy 245.938611 -156.809942) (xy 245.962207 -156.763632)
			(xy 245.992757 -156.721584) (xy 246.029508 -156.684833) (xy 246.071556 -156.654283) (xy 246.117866 -156.630687)
			(xy 246.167296 -156.614626) (xy 246.218631 -156.606496) (xy 246.270605 -156.606496) (xy 246.32194 -156.614626)
			(xy 246.37137 -156.630687) (xy 246.41768 -156.654283) (xy 246.459728 -156.684833) (xy 246.496479 -156.721584)
			(xy 246.527029 -156.763632) (xy 246.550625 -156.809942) (xy 246.566686 -156.859372) (xy 246.574816 -156.910707)
			(xy 246.575326 -156.936694) (xy 246.574817 -156.963338) (xy 246.566294 -157.01594) (xy 246.549434 -157.06649)
			(xy 246.524675 -157.113677) (xy 246.492661 -157.156276) (xy 246.454222 -157.193182) (xy 246.432578 -157.208728)
			(xy 246.421299 -157.2171) (xy 246.403445 -157.238772) (xy 246.392163 -157.264484) (xy 246.388305 -157.292297)
			(xy 246.392161 -157.320109) (xy 246.403441 -157.345823) (xy 246.421294 -157.367495) (xy 246.432578 -157.37586)
			(xy 246.454178 -157.391459) (xy 246.492592 -157.428373) (xy 246.524592 -157.470967) (xy 246.54935 -157.518141)
			(xy 246.566226 -157.568673) (xy 246.574783 -157.621256) (xy 246.575285 -157.645862) (xy 247.52935 -157.645862)
			(xy 247.529776 -157.619546) (xy 247.537017 -157.567416) (xy 247.551343 -157.516771) (xy 247.572483 -157.468572)
			(xy 247.600038 -157.42373) (xy 247.633484 -157.383093) (xy 247.65254 -157.364938) (xy 247.659918 -157.357396)
			(xy 247.668458 -157.338132) (xy 247.66905 -157.3276) (xy 247.66905 -157.252924) (xy 247.668507 -157.242376)
			(xy 247.65998 -157.223082) (xy 247.65254 -157.215586) (xy 247.633473 -157.197442) (xy 247.600019 -157.156808)
			(xy 247.572463 -157.111965) (xy 247.551327 -157.063763) (xy 247.537012 -157.013114) (xy 247.529788 -156.960979)
			(xy 247.52935 -156.934662) (xy 247.529836 -156.907411) (xy 247.537592 -156.853463) (xy 247.552947 -156.801168)
			(xy 247.575589 -156.751591) (xy 247.605055 -156.705741) (xy 247.640746 -156.66455) (xy 247.681937 -156.628859)
			(xy 247.727787 -156.599393) (xy 247.777364 -156.576751) (xy 247.829659 -156.561396) (xy 247.883607 -156.55364)
			(xy 247.938109 -156.55364) (xy 247.992057 -156.561396) (xy 248.044352 -156.576751) (xy 248.093929 -156.599393)
			(xy 248.139779 -156.628859) (xy 248.158524 -156.645101) (xy 249.513918 -156.645101) (xy 249.518234 -156.587828)
			(xy 249.531084 -156.531849) (xy 249.552177 -156.478427) (xy 249.581038 -156.428769) (xy 249.617015 -156.383997)
			(xy 249.637804 -156.364178) (xy 249.645218 -156.356667) (xy 249.653735 -156.337379) (xy 249.654314 -156.32684)
			(xy 249.654314 -156.252164) (xy 249.65376 -156.241617) (xy 249.645242 -156.222322) (xy 249.637804 -156.214826)
			(xy 249.618769 -156.19665) (xy 249.58531 -156.156025) (xy 249.557748 -156.111189) (xy 249.536606 -156.062992)
			(xy 249.522284 -156.012348) (xy 249.515055 -155.960217) (xy 249.514614 -155.933902) (xy 249.5151 -155.906651)
			(xy 249.522856 -155.852703) (xy 249.538211 -155.800408) (xy 249.560853 -155.750831) (xy 249.590319 -155.704981)
			(xy 249.62601 -155.66379) (xy 249.667201 -155.628099) (xy 249.713051 -155.598633) (xy 249.762628 -155.575991)
			(xy 249.814923 -155.560636) (xy 249.868871 -155.55288) (xy 249.923373 -155.55288) (xy 249.977321 -155.560636)
			(xy 250.029616 -155.575991) (xy 250.079193 -155.598633) (xy 250.125043 -155.628099) (xy 250.166234 -155.66379)
			(xy 250.201925 -155.704981) (xy 250.231391 -155.750831) (xy 250.254033 -155.800408) (xy 250.269388 -155.852703)
			(xy 250.277144 -155.906651) (xy 250.27763 -155.933902) (xy 250.277154 -155.960216) (xy 250.26992 -156.012343)
			(xy 250.255602 -156.062986) (xy 250.234471 -156.111184) (xy 250.206927 -156.156028) (xy 250.17349 -156.196669)
			(xy 250.15444 -156.214826) (xy 250.147031 -156.222341) (xy 250.13851 -156.241626) (xy 250.13793 -156.252164)
			(xy 250.13793 -156.32684) (xy 250.138469 -156.337389) (xy 250.146996 -156.356685) (xy 250.15444 -156.364178)
			(xy 250.175229 -156.383997) (xy 250.211202 -156.42877) (xy 250.24006 -156.478428) (xy 250.261151 -156.53185)
			(xy 250.273999 -156.587829) (xy 250.278314 -156.645101) (xy 250.273999 -156.702374) (xy 250.272863 -156.707322)
			(xy 252.579727 -156.707322) (xy 252.584039 -156.650052) (xy 252.596884 -156.594076) (xy 252.617973 -156.540656)
			(xy 252.646828 -156.491) (xy 252.682798 -156.446228) (xy 252.703584 -156.426408) (xy 252.710982 -156.418883)
			(xy 252.719509 -156.399606) (xy 252.720094 -156.38907) (xy 252.720094 -156.314394) (xy 252.719584 -156.303842)
			(xy 252.711036 -156.284547) (xy 252.703584 -156.277056) (xy 252.684511 -156.258918) (xy 252.651056 -156.218284)
			(xy 252.6235 -156.17344) (xy 252.602364 -156.125236) (xy 252.588051 -156.074586) (xy 252.58083 -156.022449)
			(xy 252.580394 -155.996132) (xy 252.58088 -155.968881) (xy 252.588636 -155.914933) (xy 252.603991 -155.862638)
			(xy 252.626633 -155.813061) (xy 252.656099 -155.767211) (xy 252.69179 -155.72602) (xy 252.732981 -155.690329)
			(xy 252.778831 -155.660863) (xy 252.828408 -155.638221) (xy 252.880703 -155.622866) (xy 252.934651 -155.61511)
			(xy 252.989153 -155.61511) (xy 253.043101 -155.622866) (xy 253.095396 -155.638221) (xy 253.144973 -155.660863)
			(xy 253.190823 -155.690329) (xy 253.232014 -155.72602) (xy 253.267705 -155.767211) (xy 253.297171 -155.813061)
			(xy 253.319813 -155.862638) (xy 253.335168 -155.914933) (xy 253.342924 -155.968881) (xy 253.34341 -155.996132)
			(xy 253.342961 -156.022447) (xy 253.335722 -156.074576) (xy 253.321399 -156.125219) (xy 253.300263 -156.173417)
			(xy 253.272714 -156.218261) (xy 253.239273 -156.2589) (xy 253.22022 -156.277056) (xy 253.212839 -156.284595)
			(xy 253.204302 -156.303862) (xy 253.20371 -156.314394) (xy 253.20371 -156.38907) (xy 253.204239 -156.39962)
			(xy 253.212774 -156.418915) (xy 253.22022 -156.426408) (xy 253.24104 -156.446196) (xy 253.277014 -156.490973)
			(xy 253.305873 -156.540636) (xy 253.326964 -156.594062) (xy 253.33981 -156.650045) (xy 253.344123 -156.707322)
			(xy 253.339804 -156.764598) (xy 253.326951 -156.82058) (xy 253.305854 -156.874003) (xy 253.27699 -156.923663)
			(xy 253.24101 -156.968436) (xy 253.22022 -156.988256) (xy 253.212839 -156.995795) (xy 253.204302 -157.015062)
			(xy 253.20371 -157.025594) (xy 253.20371 -157.10027) (xy 253.204239 -157.11082) (xy 253.212774 -157.130115)
			(xy 253.22022 -157.137608) (xy 253.239276 -157.155763) (xy 253.272733 -157.196393) (xy 253.300291 -157.241234)
			(xy 253.321429 -157.289435) (xy 253.335746 -157.340082) (xy 253.342971 -157.392216) (xy 253.34341 -157.418532)
			(xy 253.342924 -157.445783) (xy 253.335168 -157.499731) (xy 253.319813 -157.552026) (xy 253.297171 -157.601603)
			(xy 253.267705 -157.647453) (xy 253.232014 -157.688644) (xy 253.190823 -157.724335) (xy 253.144973 -157.753801)
			(xy 253.095396 -157.776443) (xy 253.043101 -157.791798) (xy 252.989153 -157.799554) (xy 252.934651 -157.799554)
			(xy 252.880703 -157.791798) (xy 252.828408 -157.776443) (xy 252.778831 -157.753801) (xy 252.732981 -157.724335)
			(xy 252.69179 -157.688644) (xy 252.656099 -157.647453) (xy 252.626633 -157.601603) (xy 252.603991 -157.552026)
			(xy 252.588636 -157.499731) (xy 252.58088 -157.445783) (xy 252.580394 -157.418532) (xy 252.580818 -157.392217)
			(xy 252.588062 -157.340086) (xy 252.60239 -157.289443) (xy 252.62353 -157.241244) (xy 252.651084 -157.196402)
			(xy 252.684529 -157.155764) (xy 252.703584 -157.137608) (xy 252.710982 -157.130083) (xy 252.719509 -157.110806)
			(xy 252.720094 -157.10027) (xy 252.720094 -157.025594) (xy 252.719584 -157.015042) (xy 252.711036 -156.995747)
			(xy 252.703584 -156.988256) (xy 252.682828 -156.968404) (xy 252.646852 -156.923636) (xy 252.617991 -156.873983)
			(xy 252.596897 -156.820566) (xy 252.584045 -156.764591) (xy 252.579727 -156.707322) (xy 250.272863 -156.707322)
			(xy 250.26115 -156.758353) (xy 250.240059 -156.811774) (xy 250.2112 -156.861432) (xy 250.175227 -156.906205)
			(xy 250.15444 -156.926026) (xy 250.147031 -156.933541) (xy 250.13851 -156.952826) (xy 250.13793 -156.963364)
			(xy 250.13793 -157.03804) (xy 250.138469 -157.048589) (xy 250.146996 -157.067885) (xy 250.15444 -157.075378)
			(xy 250.173486 -157.093543) (xy 250.206942 -157.134172) (xy 250.234501 -157.17901) (xy 250.255641 -157.227209)
			(xy 250.269961 -157.277854) (xy 250.277189 -157.329987) (xy 250.27763 -157.356302) (xy 250.277144 -157.383553)
			(xy 250.269388 -157.437501) (xy 250.254033 -157.489796) (xy 250.231391 -157.539373) (xy 250.201925 -157.585223)
			(xy 250.166234 -157.626414) (xy 250.125043 -157.662105) (xy 250.079193 -157.691571) (xy 250.029616 -157.714213)
			(xy 249.977321 -157.729568) (xy 249.923373 -157.737324) (xy 249.868871 -157.737324) (xy 249.814923 -157.729568)
			(xy 249.762628 -157.714213) (xy 249.713051 -157.691571) (xy 249.667201 -157.662105) (xy 249.62601 -157.626414)
			(xy 249.590319 -157.585223) (xy 249.560853 -157.539373) (xy 249.538211 -157.489796) (xy 249.522856 -157.437501)
			(xy 249.5151 -157.383553) (xy 249.514614 -157.356302) (xy 249.515078 -157.329988) (xy 249.522313 -157.277859)
			(xy 249.536633 -157.227216) (xy 249.557766 -157.179017) (xy 249.585312 -157.134174) (xy 249.618752 -157.093534)
			(xy 249.637804 -157.075378) (xy 249.645218 -157.067867) (xy 249.653735 -157.048579) (xy 249.654314 -157.03804)
			(xy 249.654314 -156.963364) (xy 249.65376 -156.952817) (xy 249.645242 -156.933522) (xy 249.637804 -156.926026)
			(xy 249.617017 -156.906205) (xy 249.58104 -156.861433) (xy 249.552178 -156.811776) (xy 249.531084 -156.758354)
			(xy 249.518234 -156.702374) (xy 249.513918 -156.645101) (xy 248.158524 -156.645101) (xy 248.18097 -156.66455)
			(xy 248.216661 -156.705741) (xy 248.246127 -156.751591) (xy 248.268769 -156.801168) (xy 248.284124 -156.853463)
			(xy 248.29188 -156.907411) (xy 248.292366 -156.934662) (xy 248.291951 -156.960978) (xy 248.284707 -157.013109)
			(xy 248.270378 -157.063753) (xy 248.249236 -157.111952) (xy 248.22168 -157.156794) (xy 248.188232 -157.197431)
			(xy 248.169176 -157.215586) (xy 248.16179 -157.223121) (xy 248.153254 -157.24239) (xy 248.152666 -157.252924)
			(xy 248.152666 -157.3276) (xy 248.153192 -157.33815) (xy 248.16173 -157.357444) (xy 248.169176 -157.364938)
			(xy 248.188238 -157.383087) (xy 248.221696 -157.423717) (xy 248.249255 -157.468559) (xy 248.270392 -157.516761)
			(xy 248.284707 -157.56741) (xy 248.291929 -157.619545) (xy 248.292366 -157.645862) (xy 248.29188 -157.673113)
			(xy 248.284124 -157.727061) (xy 248.268769 -157.779356) (xy 248.246127 -157.828933) (xy 248.216661 -157.874783)
			(xy 248.18097 -157.915974) (xy 248.139779 -157.951665) (xy 248.093929 -157.981131) (xy 248.044352 -158.003773)
			(xy 247.992057 -158.019128) (xy 247.938109 -158.026884) (xy 247.883607 -158.026884) (xy 247.829659 -158.019128)
			(xy 247.777364 -158.003773) (xy 247.727787 -157.981131) (xy 247.681937 -157.951665) (xy 247.640746 -157.915974)
			(xy 247.605055 -157.874783) (xy 247.575589 -157.828933) (xy 247.552947 -157.779356) (xy 247.537592 -157.727061)
			(xy 247.529836 -157.673113) (xy 247.52935 -157.645862) (xy 246.575285 -157.645862) (xy 246.575326 -157.647894)
			(xy 246.574816 -157.673881) (xy 246.566686 -157.725216) (xy 246.550625 -157.774646) (xy 246.527029 -157.820956)
			(xy 246.496479 -157.863004) (xy 246.459728 -157.899755) (xy 246.41768 -157.930305) (xy 246.37137 -157.953901)
			(xy 246.32194 -157.969962) (xy 246.270605 -157.978092) (xy 246.218631 -157.978092) (xy 246.167296 -157.969962)
			(xy 246.117866 -157.953901) (xy 246.071556 -157.930305) (xy 246.029508 -157.899755) (xy 245.992757 -157.863004)
			(xy 245.962207 -157.820956) (xy 245.938611 -157.774646) (xy 245.92255 -157.725216) (xy 245.91442 -157.673881)
			(xy 245.91391 -157.647894) (xy 245.67515 -157.647894) (xy 245.67464 -157.673881) (xy 245.66651 -157.725216)
			(xy 245.650449 -157.774646) (xy 245.626853 -157.820956) (xy 245.596303 -157.863004) (xy 245.559552 -157.899755)
			(xy 245.517504 -157.930305) (xy 245.471194 -157.953901) (xy 245.421764 -157.969962) (xy 245.370429 -157.978092)
			(xy 245.318455 -157.978092) (xy 245.26712 -157.969962) (xy 245.21769 -157.953901) (xy 245.17138 -157.930305)
			(xy 245.129332 -157.899755) (xy 245.092581 -157.863004) (xy 245.062031 -157.820956) (xy 245.038435 -157.774646)
			(xy 245.022374 -157.725216) (xy 245.014244 -157.673881) (xy 245.013734 -157.647894) (xy 244.775228 -157.647894)
			(xy 244.774718 -157.673881) (xy 244.766588 -157.725216) (xy 244.750527 -157.774646) (xy 244.726931 -157.820956)
			(xy 244.696381 -157.863004) (xy 244.65963 -157.899755) (xy 244.617582 -157.930305) (xy 244.571272 -157.953901)
			(xy 244.521842 -157.969962) (xy 244.470507 -157.978092) (xy 244.418533 -157.978092) (xy 244.367198 -157.969962)
			(xy 244.317768 -157.953901) (xy 244.271458 -157.930305) (xy 244.22941 -157.899755) (xy 244.192659 -157.863004)
			(xy 244.162109 -157.820956) (xy 244.138513 -157.774646) (xy 244.122452 -157.725216) (xy 244.114322 -157.673881)
			(xy 244.113812 -157.647894) (xy 243.875306 -157.647894) (xy 243.874796 -157.673881) (xy 243.866666 -157.725216)
			(xy 243.850605 -157.774646) (xy 243.827009 -157.820956) (xy 243.796459 -157.863004) (xy 243.759708 -157.899755)
			(xy 243.71766 -157.930305) (xy 243.67135 -157.953901) (xy 243.62192 -157.969962) (xy 243.570585 -157.978092)
			(xy 243.518611 -157.978092) (xy 243.467276 -157.969962) (xy 243.417846 -157.953901) (xy 243.371536 -157.930305)
			(xy 243.329488 -157.899755) (xy 243.292737 -157.863004) (xy 243.262187 -157.820956) (xy 243.238591 -157.774646)
			(xy 243.22253 -157.725216) (xy 243.2144 -157.673881) (xy 243.21389 -157.647894) (xy 239.575575 -157.647894)
			(xy 239.588997 -157.676525) (xy 239.605065 -157.729932) (xy 239.613185 -157.785108) (xy 239.613694 -157.812994)
			(xy 239.613185 -157.84088) (xy 239.605065 -157.896056) (xy 239.588997 -157.949463) (xy 239.565325 -157.99996)
			(xy 239.534552 -158.046473) (xy 239.522082 -158.06039) (xy 241.039648 -158.06039) (xy 241.043719 -158.004768)
			(xy 241.055845 -157.950331) (xy 241.075768 -157.89824) (xy 241.103064 -157.849605) (xy 241.13715 -157.805462)
			(xy 241.177299 -157.766753) (xy 241.222657 -157.734302) (xy 241.272257 -157.708801) (xy 241.325041 -157.690794)
			(xy 241.379884 -157.680664) (xy 241.435618 -157.678627) (xy 241.491055 -157.684727) (xy 241.545012 -157.698833)
			(xy 241.596341 -157.720645) (xy 241.643947 -157.749699) (xy 241.686815 -157.785374) (xy 241.724032 -157.826911)
			(xy 241.754805 -157.873424) (xy 241.778477 -157.923921) (xy 241.794545 -157.977328) (xy 241.802665 -158.032504)
			(xy 241.803174 -158.06039) (xy 241.802665 -158.088276) (xy 241.797947 -158.120334) (xy 254.350264 -158.120334)
			(xy 254.354335 -158.064712) (xy 254.366461 -158.010275) (xy 254.386384 -157.958184) (xy 254.41368 -157.909549)
			(xy 254.447766 -157.865406) (xy 254.487915 -157.826697) (xy 254.533273 -157.794246) (xy 254.582873 -157.768745)
			(xy 254.635657 -157.750738) (xy 254.6905 -157.740608) (xy 254.746234 -157.738571) (xy 254.801671 -157.744671)
			(xy 254.855628 -157.758777) (xy 254.906957 -157.780589) (xy 254.954563 -157.809643) (xy 254.997431 -157.845318)
			(xy 255.034648 -157.886855) (xy 255.065421 -157.933368) (xy 255.089093 -157.983865) (xy 255.105161 -158.037272)
			(xy 255.113281 -158.092448) (xy 255.11379 -158.120334) (xy 255.113281 -158.14822) (xy 255.105161 -158.203396)
			(xy 255.089093 -158.256803) (xy 255.065421 -158.3073) (xy 255.034648 -158.353813) (xy 254.997431 -158.39535)
			(xy 254.954563 -158.431025) (xy 254.906957 -158.460079) (xy 254.855628 -158.481891) (xy 254.801671 -158.495997)
			(xy 254.746234 -158.502097) (xy 254.6905 -158.50006) (xy 254.635657 -158.48993) (xy 254.582873 -158.471923)
			(xy 254.533273 -158.446422) (xy 254.487915 -158.413971) (xy 254.447766 -158.375262) (xy 254.41368 -158.331119)
			(xy 254.386384 -158.282484) (xy 254.366461 -158.230393) (xy 254.354335 -158.175956) (xy 254.350264 -158.120334)
			(xy 241.797947 -158.120334) (xy 241.794545 -158.143452) (xy 241.778477 -158.196859) (xy 241.754805 -158.247356)
			(xy 241.724032 -158.293869) (xy 241.686815 -158.335406) (xy 241.643947 -158.371081) (xy 241.596341 -158.400135)
			(xy 241.545012 -158.421947) (xy 241.491055 -158.436053) (xy 241.435618 -158.442153) (xy 241.379884 -158.440116)
			(xy 241.325041 -158.429986) (xy 241.272257 -158.411979) (xy 241.222657 -158.386478) (xy 241.177299 -158.354027)
			(xy 241.13715 -158.315318) (xy 241.103064 -158.271175) (xy 241.075768 -158.22254) (xy 241.055845 -158.170449)
			(xy 241.043719 -158.116012) (xy 241.039648 -158.06039) (xy 239.522082 -158.06039) (xy 239.497335 -158.08801)
			(xy 239.454467 -158.123685) (xy 239.406861 -158.152739) (xy 239.355532 -158.174551) (xy 239.301575 -158.188657)
			(xy 239.246138 -158.194757) (xy 239.190404 -158.19272) (xy 239.135561 -158.18259) (xy 239.082777 -158.164583)
			(xy 239.033177 -158.139082) (xy 238.987819 -158.106631) (xy 238.94767 -158.067922) (xy 238.913584 -158.023779)
			(xy 238.886288 -157.975144) (xy 238.866365 -157.923053) (xy 238.854239 -157.868616) (xy 238.850168 -157.812994)
			(xy 232.329523 -157.812994) (xy 232.335782 -157.860536) (xy 232.335782 -157.920464) (xy 232.32796 -157.979879)
			(xy 232.31245 -158.037765) (xy 232.289518 -158.093132) (xy 232.259555 -158.145032) (xy 232.223075 -158.192577)
			(xy 232.180701 -158.234954) (xy 232.133158 -158.271437) (xy 232.081261 -158.301404) (xy 232.025896 -158.32434)
			(xy 231.968011 -158.339854) (xy 231.908596 -158.34768) (xy 231.878632 -158.348172) (xy 231.015032 -158.348172)
			(xy 230.985059 -158.347777) (xy 230.925626 -158.339956) (xy 230.867722 -158.324445) (xy 230.812339 -158.301507)
			(xy 230.760423 -158.271537) (xy 230.712864 -158.235047) (xy 230.670475 -158.19266) (xy 230.633981 -158.145103)
			(xy 230.604007 -158.09319) (xy 230.581066 -158.037808) (xy 230.56555 -157.979905) (xy 230.557725 -157.920473)
			(xy 230.089876 -157.920473) (xy 230.084738 -157.959498) (xy 230.069224 -158.017397) (xy 230.046286 -158.072775)
			(xy 230.016316 -158.124685) (xy 229.979827 -158.172239) (xy 229.937442 -158.214624) (xy 229.889888 -158.251114)
			(xy 229.837978 -158.281084) (xy 229.7826 -158.304023) (xy 229.724702 -158.319537) (xy 229.665274 -158.327362)
			(xy 229.635304 -158.327852) (xy 228.771704 -158.327852) (xy 228.741738 -158.327295) (xy 228.682318 -158.319473)
			(xy 228.624427 -158.303962) (xy 228.569056 -158.281027) (xy 228.517153 -158.251061) (xy 228.469605 -158.214576)
			(xy 228.427226 -158.172198) (xy 228.390741 -158.12465) (xy 228.360775 -158.072747) (xy 228.33784 -158.017377)
			(xy 228.322328 -157.959486) (xy 228.314505 -157.900066) (xy 197.871783 -157.900066) (xy 197.886351 -157.908957)
			(xy 197.929219 -157.944632) (xy 197.966436 -157.986169) (xy 197.997209 -158.032682) (xy 198.020881 -158.083179)
			(xy 198.036949 -158.136586) (xy 198.045069 -158.191762) (xy 198.045578 -158.219648) (xy 198.045069 -158.247534)
			(xy 198.036949 -158.30271) (xy 198.020881 -158.356117) (xy 197.997209 -158.406614) (xy 197.966436 -158.453127)
			(xy 197.929219 -158.494664) (xy 197.886351 -158.530339) (xy 197.838745 -158.559393) (xy 197.787416 -158.581205)
			(xy 197.733459 -158.595311) (xy 197.678022 -158.601411) (xy 197.622288 -158.599374) (xy 197.567445 -158.589244)
			(xy 197.514661 -158.571237) (xy 197.465061 -158.545736) (xy 197.419703 -158.513285) (xy 197.379554 -158.474576)
			(xy 197.345468 -158.430433) (xy 197.318172 -158.381798) (xy 197.298249 -158.329707) (xy 197.286123 -158.27527)
			(xy 197.282052 -158.219648) (xy 195.260855 -158.219648) (xy 195.148926 -158.828994) (xy 238.850168 -158.828994)
			(xy 238.854239 -158.773372) (xy 238.866365 -158.718935) (xy 238.886288 -158.666844) (xy 238.913584 -158.618209)
			(xy 238.94767 -158.574066) (xy 238.987819 -158.535357) (xy 239.033177 -158.502906) (xy 239.082777 -158.477405)
			(xy 239.135561 -158.459398) (xy 239.190404 -158.449268) (xy 239.246138 -158.447231) (xy 239.301575 -158.453331)
			(xy 239.355532 -158.467437) (xy 239.406861 -158.489249) (xy 239.454467 -158.518303) (xy 239.497335 -158.553978)
			(xy 239.534552 -158.595515) (xy 239.565325 -158.642028) (xy 239.588997 -158.692525) (xy 239.605065 -158.745932)
			(xy 239.60615 -158.753302) (xy 248.716544 -158.753302) (xy 248.720615 -158.69768) (xy 248.732741 -158.643243)
			(xy 248.752664 -158.591152) (xy 248.77996 -158.542517) (xy 248.814046 -158.498374) (xy 248.854195 -158.459665)
			(xy 248.899553 -158.427214) (xy 248.949153 -158.401713) (xy 249.001937 -158.383706) (xy 249.05678 -158.373576)
			(xy 249.112514 -158.371539) (xy 249.167951 -158.377639) (xy 249.221908 -158.391745) (xy 249.273237 -158.413557)
			(xy 249.320843 -158.442611) (xy 249.363711 -158.478286) (xy 249.400928 -158.519823) (xy 249.431701 -158.566336)
			(xy 249.455373 -158.616833) (xy 249.471441 -158.67024) (xy 249.479561 -158.725416) (xy 249.48007 -158.753302)
			(xy 249.479561 -158.781188) (xy 249.471441 -158.836364) (xy 249.455373 -158.889771) (xy 249.431701 -158.940268)
			(xy 249.400928 -158.986781) (xy 249.363711 -159.028318) (xy 249.320843 -159.063993) (xy 249.273237 -159.093047)
			(xy 249.221908 -159.114859) (xy 249.167951 -159.128965) (xy 249.112514 -159.135065) (xy 249.05678 -159.133028)
			(xy 249.001937 -159.122898) (xy 248.949153 -159.104891) (xy 248.899553 -159.07939) (xy 248.854195 -159.046939)
			(xy 248.814046 -159.00823) (xy 248.77996 -158.964087) (xy 248.752664 -158.915452) (xy 248.732741 -158.863361)
			(xy 248.720615 -158.808924) (xy 248.716544 -158.753302) (xy 239.60615 -158.753302) (xy 239.613185 -158.801108)
			(xy 239.613694 -158.828994) (xy 239.613185 -158.85688) (xy 239.605065 -158.912056) (xy 239.588997 -158.965463)
			(xy 239.565325 -159.01596) (xy 239.534552 -159.062473) (xy 239.497335 -159.10401) (xy 239.454467 -159.139685)
			(xy 239.406861 -159.168739) (xy 239.355532 -159.190551) (xy 239.301575 -159.204657) (xy 239.246138 -159.210757)
			(xy 239.190404 -159.20872) (xy 239.135561 -159.19859) (xy 239.082777 -159.180583) (xy 239.033177 -159.155082)
			(xy 238.987819 -159.122631) (xy 238.94767 -159.083922) (xy 238.913584 -159.039779) (xy 238.886288 -158.991144)
			(xy 238.866365 -158.939053) (xy 238.854239 -158.884616) (xy 238.850168 -158.828994) (xy 195.148926 -158.828994)
			(xy 195.074229 -159.235648) (xy 197.448422 -159.235648) (xy 197.452493 -159.180026) (xy 197.464619 -159.125589)
			(xy 197.484542 -159.073498) (xy 197.511838 -159.024863) (xy 197.545924 -158.98072) (xy 197.586073 -158.942011)
			(xy 197.631431 -158.90956) (xy 197.681031 -158.884059) (xy 197.733815 -158.866052) (xy 197.788658 -158.855922)
			(xy 197.844392 -158.853885) (xy 197.899829 -158.859985) (xy 197.953786 -158.874091) (xy 198.005115 -158.895903)
			(xy 198.052721 -158.924957) (xy 198.095589 -158.960632) (xy 198.132806 -159.002169) (xy 198.163579 -159.048682)
			(xy 198.187251 -159.099179) (xy 198.203319 -159.152586) (xy 198.211439 -159.207762) (xy 198.211948 -159.235648)
			(xy 198.211439 -159.263534) (xy 198.203319 -159.31871) (xy 198.187251 -159.372117) (xy 198.163579 -159.422614)
			(xy 198.152671 -159.439102) (xy 241.107974 -159.439102) (xy 241.112045 -159.38348) (xy 241.124171 -159.329043)
			(xy 241.144094 -159.276952) (xy 241.17139 -159.228317) (xy 241.205476 -159.184174) (xy 241.245625 -159.145465)
			(xy 241.290983 -159.113014) (xy 241.340583 -159.087513) (xy 241.393367 -159.069506) (xy 241.44821 -159.059376)
			(xy 241.503944 -159.057339) (xy 241.559381 -159.063439) (xy 241.613338 -159.077545) (xy 241.664667 -159.099357)
			(xy 241.712273 -159.128411) (xy 241.755141 -159.164086) (xy 241.792358 -159.205623) (xy 241.823131 -159.252136)
			(xy 241.846803 -159.302633) (xy 241.862871 -159.35604) (xy 241.870991 -159.411216) (xy 241.8715 -159.439102)
			(xy 241.870991 -159.466988) (xy 241.862871 -159.522164) (xy 241.859968 -159.531812) (xy 244.312692 -159.531812)
			(xy 244.316763 -159.47619) (xy 244.328889 -159.421753) (xy 244.348812 -159.369662) (xy 244.376108 -159.321027)
			(xy 244.410194 -159.276884) (xy 244.450343 -159.238175) (xy 244.495701 -159.205724) (xy 244.545301 -159.180223)
			(xy 244.598085 -159.162216) (xy 244.652928 -159.152086) (xy 244.708662 -159.150049) (xy 244.764099 -159.156149)
			(xy 244.818056 -159.170255) (xy 244.869385 -159.192067) (xy 244.916991 -159.221121) (xy 244.959859 -159.256796)
			(xy 244.997076 -159.298333) (xy 245.027849 -159.344846) (xy 245.051521 -159.395343) (xy 245.067589 -159.44875)
			(xy 245.073458 -159.488632) (xy 246.595898 -159.488632) (xy 246.599969 -159.43301) (xy 246.612095 -159.378573)
			(xy 246.632018 -159.326482) (xy 246.659314 -159.277847) (xy 246.6934 -159.233704) (xy 246.733549 -159.194995)
			(xy 246.778907 -159.162544) (xy 246.828507 -159.137043) (xy 246.881291 -159.119036) (xy 246.936134 -159.108906)
			(xy 246.991868 -159.106869) (xy 247.047305 -159.112969) (xy 247.101262 -159.127075) (xy 247.152591 -159.148887)
			(xy 247.200197 -159.177941) (xy 247.243065 -159.213616) (xy 247.280282 -159.255153) (xy 247.311055 -159.301666)
			(xy 247.334727 -159.352163) (xy 247.350795 -159.40557) (xy 247.355708 -159.438952) (xy 254.026648 -159.438952)
			(xy 254.026648 -159.384448) (xy 254.034404 -159.330499) (xy 254.049759 -159.278202) (xy 254.0724 -159.228623)
			(xy 254.101865 -159.18277) (xy 254.137557 -159.141578) (xy 254.178746 -159.105883) (xy 254.224597 -159.076414)
			(xy 254.274174 -159.053769) (xy 254.326469 -159.03841) (xy 254.380418 -159.03065) (xy 254.40767 -159.030162)
			(xy 254.435751 -159.030658) (xy 254.491306 -159.038901) (xy 254.545052 -159.0552) (xy 254.595828 -159.079201)
			(xy 254.642537 -159.110386) (xy 254.68417 -159.148082) (xy 254.719827 -159.191473) (xy 254.748738 -159.239623)
			(xy 254.759968 -159.265366) (xy 254.759968 -159.26562) (xy 254.763928 -159.273997) (xy 254.776689 -159.287413)
			(xy 254.78486 -159.291782) (xy 254.846328 -159.320992) (xy 254.854941 -159.324636) (xy 254.873575 -159.326052)
			(xy 254.88265 -159.323786) (xy 254.908861 -159.316581) (xy 254.96266 -159.308809) (xy 254.989838 -159.308292)
			(xy 254.9906 -159.308292) (xy 255.017851 -159.308778) (xy 255.071799 -159.316534) (xy 255.124094 -159.331889)
			(xy 255.173671 -159.354531) (xy 255.219521 -159.383997) (xy 255.260712 -159.419688) (xy 255.296403 -159.460879)
			(xy 255.325869 -159.506729) (xy 255.348511 -159.556306) (xy 255.363866 -159.608601) (xy 255.371622 -159.662549)
			(xy 255.371622 -159.717051) (xy 255.363866 -159.770999) (xy 255.348511 -159.823294) (xy 255.325869 -159.872871)
			(xy 255.296403 -159.918721) (xy 255.260712 -159.959912) (xy 255.219521 -159.995603) (xy 255.173671 -160.025069)
			(xy 255.124094 -160.047711) (xy 255.071799 -160.063066) (xy 255.017851 -160.070822) (xy 254.9906 -160.071308)
			(xy 254.96252 -160.070794) (xy 254.906968 -160.062549) (xy 254.853225 -160.04625) (xy 254.802451 -160.02225)
			(xy 254.755743 -159.991067) (xy 254.71411 -159.953376) (xy 254.67845 -159.909989) (xy 254.649535 -159.861844)
			(xy 254.638302 -159.836104) (xy 254.638302 -159.83585) (xy 254.634361 -159.827462) (xy 254.621587 -159.814052)
			(xy 254.61341 -159.809688) (xy 254.551942 -159.780478) (xy 254.543317 -159.77687) (xy 254.524693 -159.775432)
			(xy 254.51562 -159.777684) (xy 254.489406 -159.784874) (xy 254.435609 -159.792656) (xy 254.408432 -159.793178)
			(xy 254.40767 -159.793178) (xy 254.380418 -159.79275) (xy 254.326469 -159.78499) (xy 254.274174 -159.769631)
			(xy 254.224597 -159.746986) (xy 254.178746 -159.717517) (xy 254.137557 -159.681822) (xy 254.101865 -159.64063)
			(xy 254.0724 -159.594777) (xy 254.049759 -159.545198) (xy 254.034404 -159.492901) (xy 254.026648 -159.438952)
			(xy 247.355708 -159.438952) (xy 247.358915 -159.460746) (xy 247.359424 -159.488632) (xy 247.358915 -159.516518)
			(xy 247.350795 -159.571694) (xy 247.334727 -159.625101) (xy 247.311055 -159.675598) (xy 247.280282 -159.722111)
			(xy 247.243065 -159.763648) (xy 247.200197 -159.799323) (xy 247.152591 -159.828377) (xy 247.101262 -159.850189)
			(xy 247.047305 -159.864295) (xy 246.991868 -159.870395) (xy 246.936134 -159.868358) (xy 246.881291 -159.858228)
			(xy 246.828507 -159.840221) (xy 246.778907 -159.81472) (xy 246.733549 -159.782269) (xy 246.6934 -159.74356)
			(xy 246.659314 -159.699417) (xy 246.632018 -159.650782) (xy 246.612095 -159.598691) (xy 246.599969 -159.544254)
			(xy 246.595898 -159.488632) (xy 245.073458 -159.488632) (xy 245.075709 -159.503926) (xy 245.076218 -159.531812)
			(xy 245.075709 -159.559698) (xy 245.067589 -159.614874) (xy 245.051521 -159.668281) (xy 245.027849 -159.718778)
			(xy 244.997076 -159.765291) (xy 244.959859 -159.806828) (xy 244.916991 -159.842503) (xy 244.869385 -159.871557)
			(xy 244.818056 -159.893369) (xy 244.764099 -159.907475) (xy 244.708662 -159.913575) (xy 244.652928 -159.911538)
			(xy 244.598085 -159.901408) (xy 244.545301 -159.883401) (xy 244.495701 -159.8579) (xy 244.450343 -159.825449)
			(xy 244.410194 -159.78674) (xy 244.376108 -159.742597) (xy 244.348812 -159.693962) (xy 244.328889 -159.641871)
			(xy 244.316763 -159.587434) (xy 244.312692 -159.531812) (xy 241.859968 -159.531812) (xy 241.846803 -159.575571)
			(xy 241.823131 -159.626068) (xy 241.792358 -159.672581) (xy 241.755141 -159.714118) (xy 241.712273 -159.749793)
			(xy 241.664667 -159.778847) (xy 241.613338 -159.800659) (xy 241.559381 -159.814765) (xy 241.503944 -159.820865)
			(xy 241.44821 -159.818828) (xy 241.393367 -159.808698) (xy 241.340583 -159.790691) (xy 241.290983 -159.76519)
			(xy 241.245625 -159.732739) (xy 241.205476 -159.69403) (xy 241.17139 -159.649887) (xy 241.144094 -159.601252)
			(xy 241.124171 -159.549161) (xy 241.112045 -159.494724) (xy 241.107974 -159.439102) (xy 198.152671 -159.439102)
			(xy 198.132806 -159.469127) (xy 198.095589 -159.510664) (xy 198.052721 -159.546339) (xy 198.005115 -159.575393)
			(xy 197.953786 -159.597205) (xy 197.899829 -159.611311) (xy 197.844392 -159.617411) (xy 197.788658 -159.615374)
			(xy 197.733815 -159.605244) (xy 197.681031 -159.587237) (xy 197.631431 -159.561736) (xy 197.586073 -159.529285)
			(xy 197.545924 -159.490576) (xy 197.511838 -159.446433) (xy 197.484542 -159.397798) (xy 197.464619 -159.345707)
			(xy 197.452493 -159.29127) (xy 197.448422 -159.235648) (xy 195.074229 -159.235648) (xy 194.873372 -160.329118)
			(xy 194.872864 -160.331658) (xy 194.814609 -160.770062) (xy 216.531698 -160.770062) (xy 216.532201 -160.742693)
			(xy 216.54001 -160.688516) (xy 216.55549 -160.636013) (xy 216.578324 -160.586265) (xy 216.608041 -160.540297)
			(xy 216.625678 -160.519364) (xy 216.625932 -160.51911) (xy 216.631524 -160.512027) (xy 216.637766 -160.495107)
			(xy 216.638124 -160.48609) (xy 216.638124 -160.419034) (xy 216.637746 -160.410019) (xy 216.631512 -160.393103)
			(xy 216.625932 -160.386014) (xy 216.625678 -160.386014) (xy 216.625678 -160.38576) (xy 216.60805 -160.364819)
			(xy 216.578337 -160.318848) (xy 216.5555 -160.269103) (xy 216.540006 -160.216604) (xy 216.532174 -160.16243)
			(xy 216.531698 -160.135062) (xy 216.532184 -160.107811) (xy 216.53994 -160.053863) (xy 216.555295 -160.001568)
			(xy 216.577937 -159.951991) (xy 216.607403 -159.906141) (xy 216.643094 -159.86495) (xy 216.684285 -159.829259)
			(xy 216.730135 -159.799793) (xy 216.779712 -159.777151) (xy 216.832007 -159.761796) (xy 216.885955 -159.75404)
			(xy 216.940457 -159.75404) (xy 216.994405 -159.761796) (xy 217.0467 -159.777151) (xy 217.096277 -159.799793)
			(xy 217.142127 -159.829259) (xy 217.183318 -159.86495) (xy 217.219009 -159.906141) (xy 217.248475 -159.951991)
			(xy 217.25718 -159.971051) (xy 232.232178 -159.971051) (xy 232.232178 -159.916549) (xy 232.239934 -159.862601)
			(xy 232.255289 -159.810306) (xy 232.277931 -159.760729) (xy 232.307397 -159.714879) (xy 232.343088 -159.673688)
			(xy 232.384279 -159.637997) (xy 232.430129 -159.608531) (xy 232.479706 -159.585889) (xy 232.532001 -159.570534)
			(xy 232.585949 -159.562778) (xy 232.6132 -159.562292) (xy 232.64057 -159.56276) (xy 232.694749 -159.570578)
			(xy 232.747252 -159.586066) (xy 232.796999 -159.608908) (xy 232.842966 -159.638631) (xy 232.863898 -159.656272)
			(xy 232.864152 -159.656526) (xy 232.871246 -159.662102) (xy 232.888157 -159.668354) (xy 232.897172 -159.668718)
			(xy 232.964228 -159.668718) (xy 232.973246 -159.668371) (xy 232.990163 -159.662116) (xy 232.997248 -159.656526)
			(xy 232.997248 -159.656272) (xy 232.997502 -159.656272) (xy 233.018419 -159.638614) (xy 233.064396 -159.608906)
			(xy 233.114148 -159.586074) (xy 233.166652 -159.570587) (xy 233.22083 -159.562764) (xy 233.2482 -159.562292)
			(xy 233.275451 -159.562778) (xy 233.329399 -159.570534) (xy 233.381694 -159.585889) (xy 233.431271 -159.608531)
			(xy 233.477121 -159.637997) (xy 233.518312 -159.673688) (xy 233.554003 -159.714879) (xy 233.583469 -159.760729)
			(xy 233.606111 -159.810306) (xy 233.616296 -159.844994) (xy 238.850168 -159.844994) (xy 238.854239 -159.789372)
			(xy 238.866365 -159.734935) (xy 238.886288 -159.682844) (xy 238.913584 -159.634209) (xy 238.94767 -159.590066)
			(xy 238.987819 -159.551357) (xy 239.033177 -159.518906) (xy 239.082777 -159.493405) (xy 239.135561 -159.475398)
			(xy 239.190404 -159.465268) (xy 239.246138 -159.463231) (xy 239.301575 -159.469331) (xy 239.355532 -159.483437)
			(xy 239.406861 -159.505249) (xy 239.454467 -159.534303) (xy 239.497335 -159.569978) (xy 239.534552 -159.611515)
			(xy 239.565325 -159.658028) (xy 239.588997 -159.708525) (xy 239.605065 -159.761932) (xy 239.613185 -159.817108)
			(xy 239.613694 -159.844994) (xy 239.613185 -159.87288) (xy 239.605065 -159.928056) (xy 239.588997 -159.981463)
			(xy 239.565325 -160.03196) (xy 239.534552 -160.078473) (xy 239.497335 -160.12001) (xy 239.454467 -160.155685)
			(xy 239.406861 -160.184739) (xy 239.355532 -160.206551) (xy 239.301575 -160.220657) (xy 239.246138 -160.226757)
			(xy 239.190404 -160.22472) (xy 239.135561 -160.21459) (xy 239.082777 -160.196583) (xy 239.033177 -160.171082)
			(xy 238.987819 -160.138631) (xy 238.94767 -160.099922) (xy 238.913584 -160.055779) (xy 238.886288 -160.007144)
			(xy 238.866365 -159.955053) (xy 238.854239 -159.900616) (xy 238.850168 -159.844994) (xy 233.616296 -159.844994)
			(xy 233.621466 -159.862601) (xy 233.629222 -159.916549) (xy 233.629222 -159.971051) (xy 233.621466 -160.024999)
			(xy 233.606111 -160.077294) (xy 233.583469 -160.126871) (xy 233.554003 -160.172721) (xy 233.518312 -160.213912)
			(xy 233.477121 -160.249603) (xy 233.431271 -160.279069) (xy 233.381694 -160.301711) (xy 233.329399 -160.317066)
			(xy 233.275451 -160.324822) (xy 233.2482 -160.325308) (xy 233.22083 -160.32484) (xy 233.166651 -160.317022)
			(xy 233.114148 -160.301534) (xy 233.064401 -160.278692) (xy 233.018434 -160.248969) (xy 232.997502 -160.231328)
			(xy 232.997248 -160.231074) (xy 232.990154 -160.225498) (xy 232.973243 -160.219246) (xy 232.964228 -160.218882)
			(xy 232.897172 -160.218882) (xy 232.888154 -160.219229) (xy 232.871237 -160.225484) (xy 232.864152 -160.231074)
			(xy 232.864152 -160.231328) (xy 232.863898 -160.231328) (xy 232.842981 -160.248986) (xy 232.797004 -160.278694)
			(xy 232.747252 -160.301526) (xy 232.694748 -160.317013) (xy 232.64057 -160.324836) (xy 232.6132 -160.325308)
			(xy 232.585949 -160.324822) (xy 232.532001 -160.317066) (xy 232.479706 -160.301711) (xy 232.430129 -160.279069)
			(xy 232.384279 -160.249603) (xy 232.343088 -160.213912) (xy 232.307397 -160.172721) (xy 232.277931 -160.126871)
			(xy 232.255289 -160.077294) (xy 232.239934 -160.024999) (xy 232.232178 -159.971051) (xy 217.25718 -159.971051)
			(xy 217.271117 -160.001568) (xy 217.286472 -160.053863) (xy 217.294228 -160.107811) (xy 217.294714 -160.135062)
			(xy 217.294222 -160.162431) (xy 217.28641 -160.216609) (xy 217.270927 -160.269112) (xy 217.248091 -160.318859)
			(xy 217.218372 -160.364827) (xy 217.200734 -160.38576) (xy 217.20048 -160.386014) (xy 217.194879 -160.393091)
			(xy 217.188642 -160.410015) (xy 217.188288 -160.419034) (xy 217.188288 -160.48609) (xy 217.188652 -160.495106)
			(xy 217.194895 -160.512023) (xy 217.20048 -160.51911) (xy 217.200734 -160.51911) (xy 217.200734 -160.519364)
			(xy 217.218375 -160.540294) (xy 217.248085 -160.586268) (xy 217.27092 -160.636016) (xy 217.280419 -160.668208)
			(xy 222.918272 -160.668208) (xy 222.922343 -160.612586) (xy 222.934469 -160.558149) (xy 222.954392 -160.506058)
			(xy 222.981688 -160.457423) (xy 223.015774 -160.41328) (xy 223.055923 -160.374571) (xy 223.101281 -160.34212)
			(xy 223.150881 -160.316619) (xy 223.203665 -160.298612) (xy 223.258508 -160.288482) (xy 223.314242 -160.286445)
			(xy 223.369679 -160.292545) (xy 223.423636 -160.306651) (xy 223.474965 -160.328463) (xy 223.522571 -160.357517)
			(xy 223.565439 -160.393192) (xy 223.602656 -160.434729) (xy 223.633429 -160.481242) (xy 223.657101 -160.531739)
			(xy 223.673169 -160.585146) (xy 223.681289 -160.640322) (xy 223.681798 -160.668208) (xy 223.681289 -160.696094)
			(xy 223.673169 -160.75127) (xy 223.657101 -160.804677) (xy 223.633429 -160.855174) (xy 223.602656 -160.901687)
			(xy 223.565439 -160.943224) (xy 223.523546 -160.978088) (xy 233.964986 -160.978088) (xy 233.969057 -160.922466)
			(xy 233.981183 -160.868029) (xy 234.001106 -160.815938) (xy 234.028402 -160.767303) (xy 234.062488 -160.72316)
			(xy 234.102637 -160.684451) (xy 234.147995 -160.652) (xy 234.197595 -160.626499) (xy 234.250379 -160.608492)
			(xy 234.305222 -160.598362) (xy 234.360956 -160.596325) (xy 234.416393 -160.602425) (xy 234.47035 -160.616531)
			(xy 234.521679 -160.638343) (xy 234.569285 -160.667397) (xy 234.598064 -160.691347) (xy 239.187022 -160.691347)
			(xy 239.187022 -160.636853) (xy 239.194777 -160.582914) (xy 239.210129 -160.530627) (xy 239.232766 -160.481058)
			(xy 239.262226 -160.435214) (xy 239.297911 -160.394029) (xy 239.339093 -160.358342) (xy 239.384935 -160.328878)
			(xy 239.434503 -160.306238) (xy 239.486789 -160.290883) (xy 239.540727 -160.283124) (xy 239.567974 -160.282636)
			(xy 239.594502 -160.283086) (xy 239.647047 -160.290421) (xy 239.698069 -160.304967) (xy 239.746583 -160.326443)
			(xy 239.791653 -160.354435) (xy 239.832409 -160.388402) (xy 239.868064 -160.427689) (xy 239.897931 -160.471539)
			(xy 239.921434 -160.519104) (xy 239.938118 -160.569467) (xy 239.947662 -160.621657) (xy 239.949228 -160.648142)
			(xy 239.950231 -160.662657) (xy 239.959576 -160.690203) (xy 239.976316 -160.713991) (xy 239.999091 -160.732086)
			(xy 240.026047 -160.743015) (xy 240.054993 -160.745891) (xy 240.06937 -160.743646) (xy 240.086858 -160.740549)
			(xy 240.122223 -160.737244) (xy 240.139982 -160.737042) (xy 240.140236 -160.737042) (xy 240.167489 -160.73743)
			(xy 240.22144 -160.745192) (xy 240.273737 -160.760552) (xy 240.323316 -160.783198) (xy 240.369168 -160.81267)
			(xy 240.41036 -160.848366) (xy 240.446052 -160.88956) (xy 240.475519 -160.935415) (xy 240.489438 -160.965896)
			(xy 241.137692 -160.965896) (xy 241.141763 -160.910274) (xy 241.153889 -160.855837) (xy 241.173812 -160.803746)
			(xy 241.201108 -160.755111) (xy 241.235194 -160.710968) (xy 241.275343 -160.672259) (xy 241.320701 -160.639808)
			(xy 241.370301 -160.614307) (xy 241.423085 -160.5963) (xy 241.477928 -160.58617) (xy 241.533662 -160.584133)
			(xy 241.589099 -160.590233) (xy 241.643056 -160.604339) (xy 241.694385 -160.626151) (xy 241.741991 -160.655205)
			(xy 241.784859 -160.69088) (xy 241.822076 -160.732417) (xy 241.852849 -160.77893) (xy 241.876521 -160.829427)
			(xy 241.892589 -160.882834) (xy 241.900709 -160.93801) (xy 241.901181 -160.963864) (xy 242.529612 -160.963864)
			(xy 242.533683 -160.908242) (xy 242.545809 -160.853805) (xy 242.565732 -160.801714) (xy 242.593028 -160.753079)
			(xy 242.627114 -160.708936) (xy 242.667263 -160.670227) (xy 242.712621 -160.637776) (xy 242.762221 -160.612275)
			(xy 242.815005 -160.594268) (xy 242.869848 -160.584138) (xy 242.925582 -160.582101) (xy 242.981019 -160.588201)
			(xy 243.034976 -160.602307) (xy 243.086305 -160.624119) (xy 243.133911 -160.653173) (xy 243.176779 -160.688848)
			(xy 243.213996 -160.730385) (xy 243.244769 -160.776898) (xy 243.268441 -160.827395) (xy 243.284509 -160.880802)
			(xy 243.292629 -160.935978) (xy 243.293138 -160.963864) (xy 243.293045 -160.968944) (xy 243.80139 -160.968944)
			(xy 243.805461 -160.913322) (xy 243.817587 -160.858885) (xy 243.83751 -160.806794) (xy 243.864806 -160.758159)
			(xy 243.898892 -160.714016) (xy 243.939041 -160.675307) (xy 243.984399 -160.642856) (xy 244.033999 -160.617355)
			(xy 244.086783 -160.599348) (xy 244.141626 -160.589218) (xy 244.19736 -160.587181) (xy 244.252797 -160.593281)
			(xy 244.306754 -160.607387) (xy 244.358083 -160.629199) (xy 244.405689 -160.658253) (xy 244.448557 -160.693928)
			(xy 244.485774 -160.735465) (xy 244.516547 -160.781978) (xy 244.540219 -160.832475) (xy 244.556287 -160.885882)
			(xy 244.55868 -160.902142) (xy 245.582692 -160.902142) (xy 245.586763 -160.84652) (xy 245.598889 -160.792083)
			(xy 245.618812 -160.739992) (xy 245.646108 -160.691357) (xy 245.680194 -160.647214) (xy 245.720343 -160.608505)
			(xy 245.765701 -160.576054) (xy 245.815301 -160.550553) (xy 245.868085 -160.532546) (xy 245.922928 -160.522416)
			(xy 245.978662 -160.520379) (xy 246.034099 -160.526479) (xy 246.088056 -160.540585) (xy 246.139385 -160.562397)
			(xy 246.186991 -160.591451) (xy 246.229859 -160.627126) (xy 246.267076 -160.668663) (xy 246.297849 -160.715176)
			(xy 246.321521 -160.765673) (xy 246.337589 -160.81908) (xy 246.345709 -160.874256) (xy 246.346218 -160.902142)
			(xy 246.345709 -160.930028) (xy 246.337589 -160.985204) (xy 246.321521 -161.038611) (xy 246.297849 -161.089108)
			(xy 246.267076 -161.135621) (xy 246.229859 -161.177158) (xy 246.186991 -161.212833) (xy 246.139385 -161.241887)
			(xy 246.088056 -161.263699) (xy 246.034099 -161.277805) (xy 245.978662 -161.283905) (xy 245.922928 -161.281868)
			(xy 245.868085 -161.271738) (xy 245.815301 -161.253731) (xy 245.765701 -161.22823) (xy 245.720343 -161.195779)
			(xy 245.680194 -161.15707) (xy 245.646108 -161.112927) (xy 245.618812 -161.064292) (xy 245.598889 -161.012201)
			(xy 245.586763 -160.957764) (xy 245.582692 -160.902142) (xy 244.55868 -160.902142) (xy 244.564407 -160.941058)
			(xy 244.564916 -160.968944) (xy 244.564407 -160.99683) (xy 244.556287 -161.052006) (xy 244.540219 -161.105413)
			(xy 244.516547 -161.15591) (xy 244.485774 -161.202423) (xy 244.448557 -161.24396) (xy 244.405689 -161.279635)
			(xy 244.358083 -161.308689) (xy 244.306754 -161.330501) (xy 244.252797 -161.344607) (xy 244.19736 -161.350707)
			(xy 244.141626 -161.34867) (xy 244.086783 -161.33854) (xy 244.033999 -161.320533) (xy 243.984399 -161.295032)
			(xy 243.939041 -161.262581) (xy 243.898892 -161.223872) (xy 243.864806 -161.179729) (xy 243.83751 -161.131094)
			(xy 243.817587 -161.079003) (xy 243.805461 -161.024566) (xy 243.80139 -160.968944) (xy 243.293045 -160.968944)
			(xy 243.292629 -160.99175) (xy 243.284509 -161.046926) (xy 243.268441 -161.100333) (xy 243.244769 -161.15083)
			(xy 243.213996 -161.197343) (xy 243.176779 -161.23888) (xy 243.133911 -161.274555) (xy 243.086305 -161.303609)
			(xy 243.034976 -161.325421) (xy 242.981019 -161.339527) (xy 242.925582 -161.345627) (xy 242.869848 -161.34359)
			(xy 242.815005 -161.33346) (xy 242.762221 -161.315453) (xy 242.712621 -161.289952) (xy 242.667263 -161.257501)
			(xy 242.627114 -161.218792) (xy 242.593028 -161.174649) (xy 242.565732 -161.126014) (xy 242.545809 -161.073923)
			(xy 242.533683 -161.019486) (xy 242.529612 -160.963864) (xy 241.901181 -160.963864) (xy 241.901218 -160.965896)
			(xy 241.900709 -160.993782) (xy 241.892589 -161.048958) (xy 241.876521 -161.102365) (xy 241.852849 -161.152862)
			(xy 241.822076 -161.199375) (xy 241.784859 -161.240912) (xy 241.741991 -161.276587) (xy 241.694385 -161.305641)
			(xy 241.643056 -161.327453) (xy 241.589099 -161.341559) (xy 241.533662 -161.347659) (xy 241.477928 -161.345622)
			(xy 241.423085 -161.335492) (xy 241.370301 -161.317485) (xy 241.320701 -161.291984) (xy 241.275343 -161.259533)
			(xy 241.235194 -161.220824) (xy 241.201108 -161.176681) (xy 241.173812 -161.128046) (xy 241.153889 -161.075955)
			(xy 241.141763 -161.021518) (xy 241.137692 -160.965896) (xy 240.489438 -160.965896) (xy 240.49816 -160.984996)
			(xy 240.513516 -161.037295) (xy 240.521272 -161.091247) (xy 240.521272 -161.145753) (xy 240.513516 -161.199705)
			(xy 240.49816 -161.252004) (xy 240.475519 -161.301585) (xy 240.446052 -161.34744) (xy 240.41036 -161.388634)
			(xy 240.369168 -161.42433) (xy 240.323316 -161.453802) (xy 240.273737 -161.476448) (xy 240.22144 -161.491808)
			(xy 240.167489 -161.49957) (xy 240.140236 -161.500058) (xy 240.113708 -161.499604) (xy 240.061163 -161.492271)
			(xy 240.010141 -161.477726) (xy 239.961626 -161.456251) (xy 239.916556 -161.428259) (xy 239.8758 -161.394292)
			(xy 239.840144 -161.355005) (xy 239.810277 -161.311156) (xy 239.786775 -161.26359) (xy 239.770091 -161.213227)
			(xy 239.760548 -161.161037) (xy 239.758982 -161.134552) (xy 239.757972 -161.120038) (xy 239.748627 -161.092494)
			(xy 239.731888 -161.068707) (xy 239.709115 -161.050613) (xy 239.68216 -161.039682) (xy 239.653217 -161.036805)
			(xy 239.63884 -161.039048) (xy 239.621351 -161.042143) (xy 239.585987 -161.04545) (xy 239.568228 -161.045652)
			(xy 239.567974 -161.045652) (xy 239.540727 -161.045076) (xy 239.486789 -161.037317) (xy 239.434503 -161.021962)
			(xy 239.384935 -160.999322) (xy 239.339093 -160.969858) (xy 239.297911 -160.934171) (xy 239.262226 -160.892986)
			(xy 239.232766 -160.847142) (xy 239.210129 -160.797573) (xy 239.194777 -160.745286) (xy 239.187022 -160.691347)
			(xy 234.598064 -160.691347) (xy 234.612153 -160.703072) (xy 234.64937 -160.744609) (xy 234.680143 -160.791122)
			(xy 234.703815 -160.841619) (xy 234.719883 -160.895026) (xy 234.728003 -160.950202) (xy 234.728512 -160.978088)
			(xy 234.728003 -161.005974) (xy 234.719883 -161.06115) (xy 234.703815 -161.114557) (xy 234.680143 -161.165054)
			(xy 234.64937 -161.211567) (xy 234.612153 -161.253104) (xy 234.569285 -161.288779) (xy 234.521679 -161.317833)
			(xy 234.47035 -161.339645) (xy 234.416393 -161.353751) (xy 234.360956 -161.359851) (xy 234.305222 -161.357814)
			(xy 234.250379 -161.347684) (xy 234.197595 -161.329677) (xy 234.147995 -161.304176) (xy 234.102637 -161.271725)
			(xy 234.062488 -161.233016) (xy 234.028402 -161.188873) (xy 234.001106 -161.140238) (xy 233.981183 -161.088147)
			(xy 233.969057 -161.03371) (xy 233.964986 -160.978088) (xy 223.523546 -160.978088) (xy 223.522571 -160.978899)
			(xy 223.474965 -161.007953) (xy 223.423636 -161.029765) (xy 223.369679 -161.043871) (xy 223.314242 -161.049971)
			(xy 223.258508 -161.047934) (xy 223.203665 -161.037804) (xy 223.150881 -161.019797) (xy 223.101281 -160.994296)
			(xy 223.055923 -160.961845) (xy 223.015774 -160.923136) (xy 222.981688 -160.878993) (xy 222.954392 -160.830358)
			(xy 222.934469 -160.778267) (xy 222.922343 -160.72383) (xy 222.918272 -160.668208) (xy 217.280419 -160.668208)
			(xy 217.286411 -160.688517) (xy 217.29424 -160.742693) (xy 217.294714 -160.770062) (xy 217.294228 -160.797313)
			(xy 217.286472 -160.851261) (xy 217.271117 -160.903556) (xy 217.248475 -160.953133) (xy 217.219009 -160.998983)
			(xy 217.183318 -161.040174) (xy 217.142127 -161.075865) (xy 217.096277 -161.105331) (xy 217.0467 -161.127973)
			(xy 216.994405 -161.143328) (xy 216.940457 -161.151084) (xy 216.885955 -161.151084) (xy 216.832007 -161.143328)
			(xy 216.779712 -161.127973) (xy 216.730135 -161.105331) (xy 216.684285 -161.075865) (xy 216.643094 -161.040174)
			(xy 216.607403 -160.998983) (xy 216.577937 -160.953133) (xy 216.555295 -160.903556) (xy 216.53994 -160.851261)
			(xy 216.532184 -160.797313) (xy 216.531698 -160.770062) (xy 194.814609 -160.770062) (xy 194.758818 -161.189924)
			(xy 194.758818 -161.190432) (xy 194.754754 -161.218626) (xy 194.754754 -161.219134) (xy 194.751198 -161.2392)
			(xy 194.620484 -161.9504) (xy 255.091182 -161.9504) (xy 255.095253 -161.894778) (xy 255.107379 -161.840341)
			(xy 255.127302 -161.78825) (xy 255.154598 -161.739615) (xy 255.188684 -161.695472) (xy 255.228833 -161.656763)
			(xy 255.274191 -161.624312) (xy 255.323791 -161.598811) (xy 255.376575 -161.580804) (xy 255.431418 -161.570674)
			(xy 255.487152 -161.568637) (xy 255.542589 -161.574737) (xy 255.596546 -161.588843) (xy 255.647875 -161.610655)
			(xy 255.695481 -161.639709) (xy 255.738349 -161.675384) (xy 255.775566 -161.716921) (xy 255.806339 -161.763434)
			(xy 255.830011 -161.813931) (xy 255.846079 -161.867338) (xy 255.854199 -161.922514) (xy 255.854708 -161.9504)
			(xy 255.854199 -161.978286) (xy 255.846079 -162.033462) (xy 255.830011 -162.086869) (xy 255.806339 -162.137366)
			(xy 255.775566 -162.183879) (xy 255.738349 -162.225416) (xy 255.695481 -162.261091) (xy 255.647875 -162.290145)
			(xy 255.596546 -162.311957) (xy 255.542589 -162.326063) (xy 255.487152 -162.332163) (xy 255.431418 -162.330126)
			(xy 255.376575 -162.319996) (xy 255.323791 -162.301989) (xy 255.274191 -162.276488) (xy 255.228833 -162.244037)
			(xy 255.188684 -162.205328) (xy 255.154598 -162.161185) (xy 255.127302 -162.11255) (xy 255.107379 -162.060459)
			(xy 255.095253 -162.006022) (xy 255.091182 -161.9504) (xy 194.620484 -161.9504) (xy 194.406486 -163.114736)
			(xy 248.249692 -163.114736) (xy 248.253763 -163.059114) (xy 248.265889 -163.004677) (xy 248.285812 -162.952586)
			(xy 248.313108 -162.903951) (xy 248.347194 -162.859808) (xy 248.387343 -162.821099) (xy 248.432701 -162.788648)
			(xy 248.482301 -162.763147) (xy 248.535085 -162.74514) (xy 248.589928 -162.73501) (xy 248.645662 -162.732973)
			(xy 248.701099 -162.739073) (xy 248.755056 -162.753179) (xy 248.806385 -162.774991) (xy 248.853991 -162.804045)
			(xy 248.896859 -162.83972) (xy 248.934076 -162.881257) (xy 248.964849 -162.92777) (xy 248.988521 -162.978267)
			(xy 249.004589 -163.031674) (xy 249.012709 -163.08685) (xy 249.013218 -163.114736) (xy 249.012709 -163.142622)
			(xy 249.004589 -163.197798) (xy 248.988521 -163.251205) (xy 248.964849 -163.301702) (xy 248.934076 -163.348215)
			(xy 248.896859 -163.389752) (xy 248.853991 -163.425427) (xy 248.806385 -163.454481) (xy 248.755056 -163.476293)
			(xy 248.701099 -163.490399) (xy 248.645662 -163.496499) (xy 248.589928 -163.494462) (xy 248.535085 -163.484332)
			(xy 248.482301 -163.466325) (xy 248.432701 -163.440824) (xy 248.387343 -163.408373) (xy 248.347194 -163.369664)
			(xy 248.313108 -163.325521) (xy 248.285812 -163.276886) (xy 248.265889 -163.224795) (xy 248.253763 -163.170358)
			(xy 248.249692 -163.114736) (xy 194.406486 -163.114736) (xy 194.190107 -164.292026) (xy 216.864182 -164.292026)
			(xy 216.868253 -164.236404) (xy 216.880379 -164.181967) (xy 216.900302 -164.129876) (xy 216.927598 -164.081241)
			(xy 216.961684 -164.037098) (xy 217.001833 -163.998389) (xy 217.047191 -163.965938) (xy 217.096791 -163.940437)
			(xy 217.149575 -163.92243) (xy 217.204418 -163.9123) (xy 217.260152 -163.910263) (xy 217.315589 -163.916363)
			(xy 217.369546 -163.930469) (xy 217.420875 -163.952281) (xy 217.468481 -163.981335) (xy 217.511349 -164.01701)
			(xy 217.548566 -164.058547) (xy 217.579339 -164.10506) (xy 217.603011 -164.155557) (xy 217.619079 -164.208964)
			(xy 217.625098 -164.249862) (xy 218.480384 -164.249862) (xy 218.484455 -164.19424) (xy 218.496581 -164.139803)
			(xy 218.516504 -164.087712) (xy 218.5438 -164.039077) (xy 218.577886 -163.994934) (xy 218.618035 -163.956225)
			(xy 218.663393 -163.923774) (xy 218.712993 -163.898273) (xy 218.765777 -163.880266) (xy 218.82062 -163.870136)
			(xy 218.876354 -163.868099) (xy 218.931791 -163.874199) (xy 218.985748 -163.888305) (xy 219.037077 -163.910117)
			(xy 219.084683 -163.939171) (xy 219.127551 -163.974846) (xy 219.164768 -164.016383) (xy 219.195541 -164.062896)
			(xy 219.219213 -164.113393) (xy 219.235281 -164.1668) (xy 219.243401 -164.221976) (xy 219.24391 -164.249862)
			(xy 219.243401 -164.277748) (xy 219.235281 -164.332924) (xy 219.219213 -164.386331) (xy 219.195541 -164.436828)
			(xy 219.164768 -164.483341) (xy 219.127551 -164.524878) (xy 219.084683 -164.560553) (xy 219.037077 -164.589607)
			(xy 218.985748 -164.611419) (xy 218.931791 -164.625525) (xy 218.876354 -164.631625) (xy 218.82062 -164.629588)
			(xy 218.765777 -164.619458) (xy 218.712993 -164.601451) (xy 218.663393 -164.57595) (xy 218.618035 -164.543499)
			(xy 218.577886 -164.50479) (xy 218.5438 -164.460647) (xy 218.516504 -164.412012) (xy 218.496581 -164.359921)
			(xy 218.484455 -164.305484) (xy 218.480384 -164.249862) (xy 217.625098 -164.249862) (xy 217.627199 -164.26414)
			(xy 217.627708 -164.292026) (xy 217.627199 -164.319912) (xy 217.619079 -164.375088) (xy 217.603011 -164.428495)
			(xy 217.579339 -164.478992) (xy 217.548566 -164.525505) (xy 217.511349 -164.567042) (xy 217.468481 -164.602717)
			(xy 217.420875 -164.631771) (xy 217.369546 -164.653583) (xy 217.315589 -164.667689) (xy 217.260152 -164.673789)
			(xy 217.204418 -164.671752) (xy 217.149575 -164.661622) (xy 217.096791 -164.643615) (xy 217.047191 -164.618114)
			(xy 217.001833 -164.585663) (xy 216.961684 -164.546954) (xy 216.927598 -164.502811) (xy 216.900302 -164.454176)
			(xy 216.880379 -164.402085) (xy 216.868253 -164.347648) (xy 216.864182 -164.292026) (xy 194.190107 -164.292026)
			(xy 193.61011 -167.447722) (xy 213.57539 -167.447722) (xy 213.579461 -167.3921) (xy 213.591587 -167.337663)
			(xy 213.61151 -167.285572) (xy 213.638806 -167.236937) (xy 213.672892 -167.192794) (xy 213.713041 -167.154085)
			(xy 213.758399 -167.121634) (xy 213.807999 -167.096133) (xy 213.860783 -167.078126) (xy 213.915626 -167.067996)
			(xy 213.97136 -167.065959) (xy 214.008303 -167.070024) (xy 215.122758 -167.070024) (xy 215.126829 -167.014402)
			(xy 215.138955 -166.959965) (xy 215.158878 -166.907874) (xy 215.186174 -166.859239) (xy 215.22026 -166.815096)
			(xy 215.260409 -166.776387) (xy 215.305767 -166.743936) (xy 215.355367 -166.718435) (xy 215.408151 -166.700428)
			(xy 215.462994 -166.690298) (xy 215.518728 -166.688261) (xy 215.574165 -166.694361) (xy 215.628122 -166.708467)
			(xy 215.679451 -166.730279) (xy 215.727057 -166.759333) (xy 215.769925 -166.795008) (xy 215.807142 -166.836545)
			(xy 215.837915 -166.883058) (xy 215.861587 -166.933555) (xy 215.877655 -166.986962) (xy 215.880534 -167.006524)
			(xy 216.52941 -167.006524) (xy 216.533481 -166.950902) (xy 216.545607 -166.896465) (xy 216.56553 -166.844374)
			(xy 216.592826 -166.795739) (xy 216.626912 -166.751596) (xy 216.667061 -166.712887) (xy 216.712419 -166.680436)
			(xy 216.762019 -166.654935) (xy 216.814803 -166.636928) (xy 216.869646 -166.626798) (xy 216.92538 -166.624761)
			(xy 216.980817 -166.630861) (xy 217.034774 -166.644967) (xy 217.086103 -166.666779) (xy 217.133709 -166.695833)
			(xy 217.176577 -166.731508) (xy 217.213794 -166.773045) (xy 217.244567 -166.819558) (xy 217.263033 -166.85895)
			(xy 228.409244 -166.85895) (xy 228.413315 -166.803328) (xy 228.425441 -166.748891) (xy 228.445364 -166.6968)
			(xy 228.47266 -166.648165) (xy 228.506746 -166.604022) (xy 228.546895 -166.565313) (xy 228.592253 -166.532862)
			(xy 228.641853 -166.507361) (xy 228.694637 -166.489354) (xy 228.74948 -166.479224) (xy 228.805214 -166.477187)
			(xy 228.860651 -166.483287) (xy 228.914608 -166.497393) (xy 228.965937 -166.519205) (xy 229.013543 -166.548259)
			(xy 229.056411 -166.583934) (xy 229.093628 -166.625471) (xy 229.124401 -166.671984) (xy 229.148073 -166.722481)
			(xy 229.164141 -166.775888) (xy 229.172261 -166.831064) (xy 229.17277 -166.85895) (xy 229.172261 -166.886836)
			(xy 229.164141 -166.942012) (xy 229.148073 -166.995419) (xy 229.124401 -167.045916) (xy 229.093628 -167.092429)
			(xy 229.056411 -167.133966) (xy 229.013543 -167.169641) (xy 228.965937 -167.198695) (xy 228.914608 -167.220507)
			(xy 228.860651 -167.234613) (xy 228.805214 -167.240713) (xy 228.74948 -167.238676) (xy 228.694637 -167.228546)
			(xy 228.641853 -167.210539) (xy 228.592253 -167.185038) (xy 228.546895 -167.152587) (xy 228.506746 -167.113878)
			(xy 228.47266 -167.069735) (xy 228.445364 -167.0211) (xy 228.425441 -166.969009) (xy 228.413315 -166.914572)
			(xy 228.409244 -166.85895) (xy 217.263033 -166.85895) (xy 217.268239 -166.870055) (xy 217.284307 -166.923462)
			(xy 217.292427 -166.978638) (xy 217.292936 -167.006524) (xy 217.292427 -167.03441) (xy 217.284307 -167.089586)
			(xy 217.268239 -167.142993) (xy 217.244567 -167.19349) (xy 217.213794 -167.240003) (xy 217.176577 -167.28154)
			(xy 217.133709 -167.317215) (xy 217.086103 -167.346269) (xy 217.034774 -167.368081) (xy 216.980817 -167.382187)
			(xy 216.92538 -167.388287) (xy 216.869646 -167.38625) (xy 216.814803 -167.37612) (xy 216.762019 -167.358113)
			(xy 216.712419 -167.332612) (xy 216.667061 -167.300161) (xy 216.626912 -167.261452) (xy 216.592826 -167.217309)
			(xy 216.56553 -167.168674) (xy 216.545607 -167.116583) (xy 216.533481 -167.062146) (xy 216.52941 -167.006524)
			(xy 215.880534 -167.006524) (xy 215.885775 -167.042138) (xy 215.886284 -167.070024) (xy 215.885775 -167.09791)
			(xy 215.877655 -167.153086) (xy 215.861587 -167.206493) (xy 215.837915 -167.25699) (xy 215.807142 -167.303503)
			(xy 215.769925 -167.34504) (xy 215.727057 -167.380715) (xy 215.679451 -167.409769) (xy 215.628122 -167.431581)
			(xy 215.574165 -167.445687) (xy 215.518728 -167.451787) (xy 215.462994 -167.44975) (xy 215.408151 -167.43962)
			(xy 215.355367 -167.421613) (xy 215.305767 -167.396112) (xy 215.260409 -167.363661) (xy 215.22026 -167.324952)
			(xy 215.186174 -167.280809) (xy 215.158878 -167.232174) (xy 215.138955 -167.180083) (xy 215.126829 -167.125646)
			(xy 215.122758 -167.070024) (xy 214.008303 -167.070024) (xy 214.026797 -167.072059) (xy 214.080754 -167.086165)
			(xy 214.132083 -167.107977) (xy 214.179689 -167.137031) (xy 214.222557 -167.172706) (xy 214.259774 -167.214243)
			(xy 214.290547 -167.260756) (xy 214.314219 -167.311253) (xy 214.330287 -167.36466) (xy 214.338407 -167.419836)
			(xy 214.338916 -167.447722) (xy 214.338407 -167.475608) (xy 214.330287 -167.530784) (xy 214.314219 -167.584191)
			(xy 214.290547 -167.634688) (xy 214.259774 -167.681201) (xy 214.222557 -167.722738) (xy 214.179689 -167.758413)
			(xy 214.132083 -167.787467) (xy 214.080754 -167.809279) (xy 214.026797 -167.823385) (xy 213.97136 -167.829485)
			(xy 213.915626 -167.827448) (xy 213.860783 -167.817318) (xy 213.807999 -167.799311) (xy 213.758399 -167.77381)
			(xy 213.713041 -167.741359) (xy 213.672892 -167.70265) (xy 213.638806 -167.658507) (xy 213.61151 -167.609872)
			(xy 213.591587 -167.557781) (xy 213.579461 -167.503344) (xy 213.57539 -167.447722) (xy 193.61011 -167.447722)
			(xy 193.392237 -168.63314) (xy 212.28507 -168.63314) (xy 212.289141 -168.577518) (xy 212.301267 -168.523081)
			(xy 212.32119 -168.47099) (xy 212.348486 -168.422355) (xy 212.382572 -168.378212) (xy 212.422721 -168.339503)
			(xy 212.468079 -168.307052) (xy 212.517679 -168.281551) (xy 212.570463 -168.263544) (xy 212.625306 -168.253414)
			(xy 212.68104 -168.251377) (xy 212.736477 -168.257477) (xy 212.790434 -168.271583) (xy 212.841763 -168.293395)
			(xy 212.889369 -168.322449) (xy 212.92819 -168.354756) (xy 213.648542 -168.354756) (xy 213.652613 -168.299134)
			(xy 213.664739 -168.244697) (xy 213.684662 -168.192606) (xy 213.711958 -168.143971) (xy 213.746044 -168.099828)
			(xy 213.786193 -168.061119) (xy 213.831551 -168.028668) (xy 213.881151 -168.003167) (xy 213.933935 -167.98516)
			(xy 213.988778 -167.97503) (xy 214.044512 -167.972993) (xy 214.099949 -167.979093) (xy 214.153906 -167.993199)
			(xy 214.205235 -168.015011) (xy 214.252841 -168.044065) (xy 214.295709 -168.07974) (xy 214.332926 -168.121277)
			(xy 214.363699 -168.16779) (xy 214.387371 -168.218287) (xy 214.403439 -168.271694) (xy 214.411559 -168.32687)
			(xy 214.412068 -168.354756) (xy 214.411559 -168.382642) (xy 214.403439 -168.437818) (xy 214.387371 -168.491225)
			(xy 214.363699 -168.541722) (xy 214.332926 -168.588235) (xy 214.295709 -168.629772) (xy 214.252841 -168.665447)
			(xy 214.205235 -168.694501) (xy 214.153906 -168.716313) (xy 214.099949 -168.730419) (xy 214.044512 -168.736519)
			(xy 213.988778 -168.734482) (xy 213.933935 -168.724352) (xy 213.881151 -168.706345) (xy 213.831551 -168.680844)
			(xy 213.786193 -168.648393) (xy 213.746044 -168.609684) (xy 213.711958 -168.565541) (xy 213.684662 -168.516906)
			(xy 213.664739 -168.464815) (xy 213.652613 -168.410378) (xy 213.648542 -168.354756) (xy 212.92819 -168.354756)
			(xy 212.932237 -168.358124) (xy 212.969454 -168.399661) (xy 213.000227 -168.446174) (xy 213.023899 -168.496671)
			(xy 213.039967 -168.550078) (xy 213.048087 -168.605254) (xy 213.048596 -168.63314) (xy 213.048087 -168.661026)
			(xy 213.039967 -168.716202) (xy 213.023899 -168.769609) (xy 213.000227 -168.820106) (xy 212.969454 -168.866619)
			(xy 212.932237 -168.908156) (xy 212.889369 -168.943831) (xy 212.841763 -168.972885) (xy 212.790434 -168.994697)
			(xy 212.736477 -169.008803) (xy 212.68104 -169.014903) (xy 212.625306 -169.012866) (xy 212.570463 -169.002736)
			(xy 212.517679 -168.984729) (xy 212.468079 -168.959228) (xy 212.422721 -168.926777) (xy 212.382572 -168.888068)
			(xy 212.348486 -168.843925) (xy 212.32119 -168.79529) (xy 212.301267 -168.743199) (xy 212.289141 -168.688762)
			(xy 212.28507 -168.63314) (xy 193.392237 -168.63314) (xy 193.269786 -169.299382) (xy 212.885526 -169.299382)
			(xy 212.889597 -169.24376) (xy 212.901723 -169.189323) (xy 212.921646 -169.137232) (xy 212.948942 -169.088597)
			(xy 212.983028 -169.044454) (xy 213.023177 -169.005745) (xy 213.068535 -168.973294) (xy 213.118135 -168.947793)
			(xy 213.170919 -168.929786) (xy 213.225762 -168.919656) (xy 213.281496 -168.917619) (xy 213.336933 -168.923719)
			(xy 213.39089 -168.937825) (xy 213.442219 -168.959637) (xy 213.489825 -168.988691) (xy 213.532693 -169.024366)
			(xy 213.56991 -169.065903) (xy 213.600683 -169.112416) (xy 213.624355 -169.162913) (xy 213.640423 -169.21632)
			(xy 213.648543 -169.271496) (xy 213.649052 -169.299382) (xy 213.648543 -169.327268) (xy 213.640461 -169.382186)
			(xy 221.32493 -169.382186) (xy 221.329001 -169.326564) (xy 221.341127 -169.272127) (xy 221.36105 -169.220036)
			(xy 221.388346 -169.171401) (xy 221.422432 -169.127258) (xy 221.462581 -169.088549) (xy 221.507939 -169.056098)
			(xy 221.557539 -169.030597) (xy 221.610323 -169.01259) (xy 221.665166 -169.00246) (xy 221.7209 -169.000423)
			(xy 221.776337 -169.006523) (xy 221.830294 -169.020629) (xy 221.881623 -169.042441) (xy 221.929229 -169.071495)
			(xy 221.972097 -169.10717) (xy 222.009314 -169.148707) (xy 222.040087 -169.19522) (xy 222.063759 -169.245717)
			(xy 222.079827 -169.299124) (xy 222.087947 -169.3543) (xy 222.088456 -169.382186) (xy 222.087947 -169.410072)
			(xy 222.080949 -169.457624) (xy 222.853756 -169.457624) (xy 222.857827 -169.402002) (xy 222.869953 -169.347565)
			(xy 222.889876 -169.295474) (xy 222.917172 -169.246839) (xy 222.951258 -169.202696) (xy 222.991407 -169.163987)
			(xy 223.036765 -169.131536) (xy 223.086365 -169.106035) (xy 223.139149 -169.088028) (xy 223.193992 -169.077898)
			(xy 223.249726 -169.075861) (xy 223.305163 -169.081961) (xy 223.35912 -169.096067) (xy 223.410449 -169.117879)
			(xy 223.458055 -169.146933) (xy 223.500923 -169.182608) (xy 223.53814 -169.224145) (xy 223.568913 -169.270658)
			(xy 223.592585 -169.321155) (xy 223.599954 -169.345648) (xy 223.97951 -169.345648) (xy 223.97951 -169.291152)
			(xy 223.987266 -169.23721) (xy 224.002619 -169.184921) (xy 224.025257 -169.135349) (xy 224.054719 -169.089503)
			(xy 224.090406 -169.048316) (xy 224.131591 -169.012628) (xy 224.177436 -168.983164) (xy 224.227007 -168.960524)
			(xy 224.279296 -168.945169) (xy 224.333238 -168.937411) (xy 224.360486 -168.936924) (xy 224.38978 -168.937482)
			(xy 224.447678 -168.946444) (xy 224.503528 -168.964144) (xy 224.556019 -168.990167) (xy 224.60392 -169.023902)
			(xy 224.646105 -169.064558) (xy 224.66427 -169.087546) (xy 224.671702 -169.096428) (xy 224.692337 -169.106885)
			(xy 224.703894 -169.107612) (xy 224.795588 -169.108882) (xy 224.81667 -169.098976) (xy 224.824036 -169.089832)
			(xy 224.842239 -169.068022) (xy 224.884039 -169.029554) (xy 224.931079 -168.997707) (xy 224.982322 -168.973186)
			(xy 225.036633 -168.956532) (xy 225.092812 -168.948113) (xy 225.121216 -168.947592) (xy 225.148467 -168.948079)
			(xy 225.202413 -168.955837) (xy 225.254705 -168.971194) (xy 225.304281 -168.993836) (xy 225.350129 -169.023303)
			(xy 225.391317 -169.058994) (xy 225.427007 -169.100184) (xy 225.456472 -169.146034) (xy 225.479112 -169.19561)
			(xy 225.494466 -169.247903) (xy 225.502222 -169.301849) (xy 225.502222 -169.334434) (xy 226.303076 -169.334434)
			(xy 226.307147 -169.278812) (xy 226.319273 -169.224375) (xy 226.339196 -169.172284) (xy 226.366492 -169.123649)
			(xy 226.400578 -169.079506) (xy 226.440727 -169.040797) (xy 226.486085 -169.008346) (xy 226.535685 -168.982845)
			(xy 226.588469 -168.964838) (xy 226.643312 -168.954708) (xy 226.699046 -168.952671) (xy 226.754483 -168.958771)
			(xy 226.80844 -168.972877) (xy 226.859769 -168.994689) (xy 226.907375 -169.023743) (xy 226.950243 -169.059418)
			(xy 226.98746 -169.100955) (xy 227.018233 -169.147468) (xy 227.041905 -169.197965) (xy 227.057973 -169.251372)
			(xy 227.066093 -169.306548) (xy 227.066602 -169.334434) (xy 227.066403 -169.345356) (xy 233.320842 -169.345356)
			(xy 233.324913 -169.289734) (xy 233.337039 -169.235297) (xy 233.356962 -169.183206) (xy 233.384258 -169.134571)
			(xy 233.418344 -169.090428) (xy 233.458493 -169.051719) (xy 233.503851 -169.019268) (xy 233.553451 -168.993767)
			(xy 233.606235 -168.97576) (xy 233.661078 -168.96563) (xy 233.716812 -168.963593) (xy 233.772249 -168.969693)
			(xy 233.826206 -168.983799) (xy 233.877535 -169.005611) (xy 233.925141 -169.034665) (xy 233.968009 -169.07034)
			(xy 234.005226 -169.111877) (xy 234.035999 -169.15839) (xy 234.059671 -169.208887) (xy 234.075739 -169.262294)
			(xy 234.08344 -169.314622) (xy 235.759242 -169.314622) (xy 235.763313 -169.259) (xy 235.775439 -169.204563)
			(xy 235.795362 -169.152472) (xy 235.822658 -169.103837) (xy 235.856744 -169.059694) (xy 235.896893 -169.020985)
			(xy 235.942251 -168.988534) (xy 235.991851 -168.963033) (xy 236.044635 -168.945026) (xy 236.099478 -168.934896)
			(xy 236.155212 -168.932859) (xy 236.210649 -168.938959) (xy 236.264606 -168.953065) (xy 236.315935 -168.974877)
			(xy 236.363541 -169.003931) (xy 236.406409 -169.039606) (xy 236.443626 -169.081143) (xy 236.474399 -169.127656)
			(xy 236.498071 -169.178153) (xy 236.514139 -169.23156) (xy 236.522259 -169.286736) (xy 236.522768 -169.314622)
			(xy 236.522599 -169.323854) (xy 239.935443 -169.323854) (xy 239.935443 -169.269346) (xy 239.9432 -169.215392)
			(xy 239.958558 -169.163091) (xy 239.981202 -169.113509) (xy 240.010672 -169.067654) (xy 240.046368 -169.026459)
			(xy 240.087563 -168.990765) (xy 240.133419 -168.961296) (xy 240.183003 -168.938653) (xy 240.235304 -168.923298)
			(xy 240.289258 -168.915542) (xy 240.316512 -168.91508) (xy 240.342671 -168.915512) (xy 240.394497 -168.922662)
			(xy 240.444861 -168.936827) (xy 240.492817 -168.957741) (xy 240.537465 -168.985011) (xy 240.577968 -169.018126)
			(xy 240.613566 -169.056465) (xy 240.628932 -169.07764) (xy 240.636951 -169.08824) (xy 240.657293 -169.105325)
			(xy 240.681356 -169.116581) (xy 240.707508 -169.121246) (xy 240.733978 -169.119003) (xy 240.758972 -169.110005)
			(xy 240.780798 -169.09486) (xy 240.789714 -169.085006) (xy 240.807929 -169.064258) (xy 240.849322 -169.027723)
			(xy 240.895548 -168.997536) (xy 240.945643 -168.974326) (xy 240.998559 -168.958577) (xy 241.053193 -168.95062)
			(xy 241.080798 -168.950132) (xy 241.108054 -168.950515) (xy 241.162011 -168.958272) (xy 241.214314 -168.97363)
			(xy 241.2639 -168.996275) (xy 241.309758 -169.025746) (xy 241.350955 -169.061443) (xy 241.386653 -169.10264)
			(xy 241.416124 -169.148498) (xy 241.438769 -169.198084) (xy 241.454127 -169.250387) (xy 241.461885 -169.304344)
			(xy 241.461885 -169.334434) (xy 242.067586 -169.334434) (xy 242.071657 -169.278812) (xy 242.083783 -169.224375)
			(xy 242.103706 -169.172284) (xy 242.131002 -169.123649) (xy 242.165088 -169.079506) (xy 242.205237 -169.040797)
			(xy 242.250595 -169.008346) (xy 242.300195 -168.982845) (xy 242.352979 -168.964838) (xy 242.407822 -168.954708)
			(xy 242.463556 -168.952671) (xy 242.518993 -168.958771) (xy 242.57295 -168.972877) (xy 242.624279 -168.994689)
			(xy 242.671885 -169.023743) (xy 242.714753 -169.059418) (xy 242.75197 -169.100955) (xy 242.782743 -169.147468)
			(xy 242.806415 -169.197965) (xy 242.822483 -169.251372) (xy 242.830603 -169.306548) (xy 242.831112 -169.334434)
			(xy 242.830603 -169.36232) (xy 242.822483 -169.417496) (xy 242.806415 -169.470903) (xy 242.782743 -169.5214)
			(xy 242.75197 -169.567913) (xy 242.714753 -169.60945) (xy 242.709418 -169.61389) (xy 245.108869 -169.61389)
			(xy 245.108869 -169.55391) (xy 245.116699 -169.494444) (xy 245.132223 -169.436508) (xy 245.155178 -169.381095)
			(xy 245.185169 -169.329152) (xy 245.221684 -169.281569) (xy 245.264097 -169.239158) (xy 245.311684 -169.202648)
			(xy 245.363629 -169.172661) (xy 245.419045 -169.149711) (xy 245.476981 -169.134191) (xy 245.536448 -169.126367)
			(xy 245.566438 -169.1259) (xy 246.430038 -169.1259) (xy 246.460018 -169.126468) (xy 246.519465 -169.134299)
			(xy 246.577381 -169.149822) (xy 246.632776 -169.172772) (xy 246.684702 -169.202755) (xy 246.73227 -169.239259)
			(xy 246.774667 -169.281659) (xy 246.811166 -169.32923) (xy 246.841145 -169.381158) (xy 246.86409 -169.436555)
			(xy 246.879608 -169.494472) (xy 246.887434 -169.55392) (xy 246.887434 -169.61388) (xy 246.879608 -169.673328)
			(xy 246.86409 -169.731245) (xy 246.841145 -169.786642) (xy 246.811166 -169.83857) (xy 246.774667 -169.886141)
			(xy 246.73227 -169.928541) (xy 246.684702 -169.965045) (xy 246.632776 -169.995028) (xy 246.577381 -170.017978)
			(xy 246.519465 -170.033501) (xy 246.460018 -170.041332) (xy 246.430038 -170.041824) (xy 245.566438 -170.041824)
			(xy 245.536448 -170.041433) (xy 245.476981 -170.033609) (xy 245.419045 -170.018089) (xy 245.363629 -169.995139)
			(xy 245.311684 -169.965152) (xy 245.264097 -169.928642) (xy 245.221684 -169.886231) (xy 245.185169 -169.838648)
			(xy 245.155178 -169.786705) (xy 245.132223 -169.731292) (xy 245.116699 -169.673356) (xy 245.108869 -169.61389)
			(xy 242.709418 -169.61389) (xy 242.671885 -169.645125) (xy 242.624279 -169.674179) (xy 242.57295 -169.695991)
			(xy 242.518993 -169.710097) (xy 242.463556 -169.716197) (xy 242.407822 -169.71416) (xy 242.352979 -169.70403)
			(xy 242.300195 -169.686023) (xy 242.250595 -169.660522) (xy 242.205237 -169.628071) (xy 242.165088 -169.589362)
			(xy 242.131002 -169.545219) (xy 242.103706 -169.496584) (xy 242.083783 -169.444493) (xy 242.071657 -169.390056)
			(xy 242.067586 -169.334434) (xy 241.461885 -169.334434) (xy 241.461885 -169.358856) (xy 241.454127 -169.412813)
			(xy 241.438769 -169.465116) (xy 241.416124 -169.514702) (xy 241.386653 -169.56056) (xy 241.350955 -169.601757)
			(xy 241.309758 -169.637454) (xy 241.2639 -169.666925) (xy 241.214314 -169.68957) (xy 241.162011 -169.704928)
			(xy 241.108054 -169.712685) (xy 241.080798 -169.713148) (xy 241.05464 -169.712697) (xy 241.002815 -169.705548)
			(xy 240.952452 -169.691386) (xy 240.904497 -169.670475) (xy 240.859849 -169.643208) (xy 240.819345 -169.610096)
			(xy 240.783745 -169.571761) (xy 240.768378 -169.550588) (xy 240.760347 -169.539997) (xy 240.740009 -169.522907)
			(xy 240.715949 -169.511647) (xy 240.689798 -169.50698) (xy 240.663328 -169.509222) (xy 240.638334 -169.518221)
			(xy 240.616511 -169.533367) (xy 240.607596 -169.543222) (xy 240.589382 -169.563971) (xy 240.547988 -169.600504)
			(xy 240.501761 -169.630691) (xy 240.451667 -169.653901) (xy 240.39875 -169.669649) (xy 240.344117 -169.677607)
			(xy 240.316512 -169.678096) (xy 240.289258 -169.677658) (xy 240.235304 -169.669902) (xy 240.183003 -169.654547)
			(xy 240.133419 -169.631904) (xy 240.087563 -169.602435) (xy 240.046368 -169.566741) (xy 240.010672 -169.525546)
			(xy 239.981202 -169.479691) (xy 239.958558 -169.430109) (xy 239.9432 -169.377808) (xy 239.935443 -169.323854)
			(xy 236.522599 -169.323854) (xy 236.522259 -169.342508) (xy 236.514139 -169.397684) (xy 236.498071 -169.451091)
			(xy 236.474399 -169.501588) (xy 236.443626 -169.548101) (xy 236.406409 -169.589638) (xy 236.363541 -169.625313)
			(xy 236.315935 -169.654367) (xy 236.264606 -169.676179) (xy 236.210649 -169.690285) (xy 236.155212 -169.696385)
			(xy 236.099478 -169.694348) (xy 236.044635 -169.684218) (xy 235.991851 -169.666211) (xy 235.942251 -169.64071)
			(xy 235.896893 -169.608259) (xy 235.856744 -169.56955) (xy 235.822658 -169.525407) (xy 235.795362 -169.476772)
			(xy 235.775439 -169.424681) (xy 235.763313 -169.370244) (xy 235.759242 -169.314622) (xy 234.08344 -169.314622)
			(xy 234.083859 -169.31747) (xy 234.084368 -169.345356) (xy 234.083859 -169.373242) (xy 234.075739 -169.428418)
			(xy 234.059671 -169.481825) (xy 234.035999 -169.532322) (xy 234.005226 -169.578835) (xy 233.968009 -169.620372)
			(xy 233.925141 -169.656047) (xy 233.877535 -169.685101) (xy 233.826206 -169.706913) (xy 233.772249 -169.721019)
			(xy 233.716812 -169.727119) (xy 233.661078 -169.725082) (xy 233.606235 -169.714952) (xy 233.553451 -169.696945)
			(xy 233.503851 -169.671444) (xy 233.458493 -169.638993) (xy 233.418344 -169.600284) (xy 233.384258 -169.556141)
			(xy 233.356962 -169.507506) (xy 233.337039 -169.455415) (xy 233.324913 -169.400978) (xy 233.320842 -169.345356)
			(xy 227.066403 -169.345356) (xy 227.066093 -169.36232) (xy 227.057973 -169.417496) (xy 227.041905 -169.470903)
			(xy 227.018233 -169.5214) (xy 226.98746 -169.567913) (xy 226.950243 -169.60945) (xy 226.907375 -169.645125)
			(xy 226.859769 -169.674179) (xy 226.80844 -169.695991) (xy 226.754483 -169.710097) (xy 226.699046 -169.716197)
			(xy 226.643312 -169.71416) (xy 226.588469 -169.70403) (xy 226.535685 -169.686023) (xy 226.486085 -169.660522)
			(xy 226.440727 -169.628071) (xy 226.400578 -169.589362) (xy 226.366492 -169.545219) (xy 226.339196 -169.496584)
			(xy 226.319273 -169.444493) (xy 226.307147 -169.390056) (xy 226.303076 -169.334434) (xy 225.502222 -169.334434)
			(xy 225.502222 -169.356351) (xy 225.494466 -169.410297) (xy 225.479112 -169.46259) (xy 225.456472 -169.512166)
			(xy 225.427007 -169.558016) (xy 225.391317 -169.599206) (xy 225.350129 -169.634897) (xy 225.304281 -169.664364)
			(xy 225.254705 -169.687006) (xy 225.202413 -169.702363) (xy 225.148467 -169.710121) (xy 225.121216 -169.710608)
			(xy 225.091923 -169.710036) (xy 225.034026 -169.701076) (xy 224.978177 -169.683377) (xy 224.925686 -169.657357)
			(xy 224.877785 -169.623625) (xy 224.835598 -169.582973) (xy 224.817432 -169.559986) (xy 224.809993 -169.551111)
			(xy 224.789364 -169.540649) (xy 224.777808 -169.53992) (xy 224.686114 -169.53865) (xy 224.665032 -169.548556)
			(xy 224.657666 -169.5577) (xy 224.63947 -169.579515) (xy 224.597668 -169.617982) (xy 224.550625 -169.649827)
			(xy 224.499382 -169.674347) (xy 224.44507 -169.691) (xy 224.38889 -169.699419) (xy 224.360486 -169.69994)
			(xy 224.333238 -169.699389) (xy 224.279296 -169.691631) (xy 224.227007 -169.676276) (xy 224.177436 -169.653636)
			(xy 224.131591 -169.624172) (xy 224.090406 -169.588484) (xy 224.054719 -169.547297) (xy 224.025257 -169.501451)
			(xy 224.002619 -169.451879) (xy 223.987266 -169.39959) (xy 223.97951 -169.345648) (xy 223.599954 -169.345648)
			(xy 223.608653 -169.374562) (xy 223.616773 -169.429738) (xy 223.617282 -169.457624) (xy 223.616773 -169.48551)
			(xy 223.608653 -169.540686) (xy 223.592585 -169.594093) (xy 223.568913 -169.64459) (xy 223.53814 -169.691103)
			(xy 223.500923 -169.73264) (xy 223.458055 -169.768315) (xy 223.410449 -169.797369) (xy 223.35912 -169.819181)
			(xy 223.305163 -169.833287) (xy 223.249726 -169.839387) (xy 223.193992 -169.83735) (xy 223.139149 -169.82722)
			(xy 223.086365 -169.809213) (xy 223.036765 -169.783712) (xy 222.991407 -169.751261) (xy 222.951258 -169.712552)
			(xy 222.917172 -169.668409) (xy 222.889876 -169.619774) (xy 222.869953 -169.567683) (xy 222.857827 -169.513246)
			(xy 222.853756 -169.457624) (xy 222.080949 -169.457624) (xy 222.079827 -169.465248) (xy 222.063759 -169.518655)
			(xy 222.040087 -169.569152) (xy 222.009314 -169.615665) (xy 221.972097 -169.657202) (xy 221.929229 -169.692877)
			(xy 221.881623 -169.721931) (xy 221.830294 -169.743743) (xy 221.776337 -169.757849) (xy 221.7209 -169.763949)
			(xy 221.665166 -169.761912) (xy 221.610323 -169.751782) (xy 221.557539 -169.733775) (xy 221.507939 -169.708274)
			(xy 221.462581 -169.675823) (xy 221.422432 -169.637114) (xy 221.388346 -169.592971) (xy 221.36105 -169.544336)
			(xy 221.341127 -169.492245) (xy 221.329001 -169.437808) (xy 221.32493 -169.382186) (xy 213.640461 -169.382186)
			(xy 213.640423 -169.382444) (xy 213.624355 -169.435851) (xy 213.600683 -169.486348) (xy 213.56991 -169.532861)
			(xy 213.532693 -169.574398) (xy 213.489825 -169.610073) (xy 213.442219 -169.639127) (xy 213.39089 -169.660939)
			(xy 213.336933 -169.675045) (xy 213.281496 -169.681145) (xy 213.225762 -169.679108) (xy 213.170919 -169.668978)
			(xy 213.118135 -169.650971) (xy 213.068535 -169.62547) (xy 213.023177 -169.593019) (xy 212.983028 -169.55431)
			(xy 212.948942 -169.510167) (xy 212.921646 -169.461532) (xy 212.901723 -169.409441) (xy 212.889597 -169.355004)
			(xy 212.885526 -169.299382) (xy 193.269786 -169.299382) (xy 192.790811 -171.905422) (xy 210.309966 -171.905422)
			(xy 210.314037 -171.8498) (xy 210.326163 -171.795363) (xy 210.346086 -171.743272) (xy 210.373382 -171.694637)
			(xy 210.407468 -171.650494) (xy 210.447617 -171.611785) (xy 210.492975 -171.579334) (xy 210.542575 -171.553833)
			(xy 210.595359 -171.535826) (xy 210.650202 -171.525696) (xy 210.705936 -171.523659) (xy 210.761373 -171.529759)
			(xy 210.81533 -171.543865) (xy 210.866659 -171.565677) (xy 210.914265 -171.594731) (xy 210.957133 -171.630406)
			(xy 210.99435 -171.671943) (xy 211.025123 -171.718456) (xy 211.048795 -171.768953) (xy 211.064863 -171.82236)
			(xy 211.072983 -171.877536) (xy 211.073492 -171.905422) (xy 211.072983 -171.933308) (xy 211.064863 -171.988484)
			(xy 211.048795 -172.041891) (xy 211.025123 -172.092388) (xy 210.99435 -172.138901) (xy 210.957133 -172.180438)
			(xy 210.914629 -172.21581) (xy 217.915996 -172.21581) (xy 217.920067 -172.160188) (xy 217.932193 -172.105751)
			(xy 217.952116 -172.05366) (xy 217.979412 -172.005025) (xy 218.013498 -171.960882) (xy 218.053647 -171.922173)
			(xy 218.099005 -171.889722) (xy 218.148605 -171.864221) (xy 218.201389 -171.846214) (xy 218.256232 -171.836084)
			(xy 218.311966 -171.834047) (xy 218.367403 -171.840147) (xy 218.42136 -171.854253) (xy 218.472689 -171.876065)
			(xy 218.520295 -171.905119) (xy 218.563163 -171.940794) (xy 218.60038 -171.982331) (xy 218.631153 -172.028844)
			(xy 218.654825 -172.079341) (xy 218.670893 -172.132748) (xy 218.674893 -172.15993) (xy 230.571292 -172.15993)
			(xy 230.575363 -172.104308) (xy 230.587489 -172.049871) (xy 230.607412 -171.99778) (xy 230.634708 -171.949145)
			(xy 230.668794 -171.905002) (xy 230.708943 -171.866293) (xy 230.754301 -171.833842) (xy 230.803901 -171.808341)
			(xy 230.856685 -171.790334) (xy 230.911528 -171.780204) (xy 230.967262 -171.778167) (xy 231.022699 -171.784267)
			(xy 231.076656 -171.798373) (xy 231.127985 -171.820185) (xy 231.175591 -171.849239) (xy 231.218459 -171.884914)
			(xy 231.255676 -171.926451) (xy 231.286449 -171.972964) (xy 231.310121 -172.023461) (xy 231.326189 -172.076868)
			(xy 231.334309 -172.132044) (xy 231.334818 -172.15993) (xy 231.334309 -172.187816) (xy 231.330189 -172.21581)
			(xy 254.043686 -172.21581) (xy 254.047757 -172.160188) (xy 254.059883 -172.105751) (xy 254.079806 -172.05366)
			(xy 254.107102 -172.005025) (xy 254.141188 -171.960882) (xy 254.181337 -171.922173) (xy 254.226695 -171.889722)
			(xy 254.276295 -171.864221) (xy 254.329079 -171.846214) (xy 254.383922 -171.836084) (xy 254.439656 -171.834047)
			(xy 254.495093 -171.840147) (xy 254.54905 -171.854253) (xy 254.600379 -171.876065) (xy 254.647985 -171.905119)
			(xy 254.690853 -171.940794) (xy 254.72807 -171.982331) (xy 254.758843 -172.028844) (xy 254.782515 -172.079341)
			(xy 254.798583 -172.132748) (xy 254.806703 -172.187924) (xy 254.807212 -172.21581) (xy 254.806703 -172.243696)
			(xy 254.798583 -172.298872) (xy 254.782515 -172.352279) (xy 254.758843 -172.402776) (xy 254.72807 -172.449289)
			(xy 254.690853 -172.490826) (xy 254.647985 -172.526501) (xy 254.600379 -172.555555) (xy 254.54905 -172.577367)
			(xy 254.495093 -172.591473) (xy 254.439656 -172.597573) (xy 254.383922 -172.595536) (xy 254.329079 -172.585406)
			(xy 254.276295 -172.567399) (xy 254.226695 -172.541898) (xy 254.181337 -172.509447) (xy 254.141188 -172.470738)
			(xy 254.107102 -172.426595) (xy 254.079806 -172.37796) (xy 254.059883 -172.325869) (xy 254.047757 -172.271432)
			(xy 254.043686 -172.21581) (xy 231.330189 -172.21581) (xy 231.326189 -172.242992) (xy 231.310121 -172.296399)
			(xy 231.286449 -172.346896) (xy 231.255676 -172.393409) (xy 231.218459 -172.434946) (xy 231.175591 -172.470621)
			(xy 231.127985 -172.499675) (xy 231.076656 -172.521487) (xy 231.022699 -172.535593) (xy 230.967262 -172.541693)
			(xy 230.911528 -172.539656) (xy 230.856685 -172.529526) (xy 230.803901 -172.511519) (xy 230.754301 -172.486018)
			(xy 230.708943 -172.453567) (xy 230.668794 -172.414858) (xy 230.634708 -172.370715) (xy 230.607412 -172.32208)
			(xy 230.587489 -172.269989) (xy 230.575363 -172.215552) (xy 230.571292 -172.15993) (xy 218.674893 -172.15993)
			(xy 218.679013 -172.187924) (xy 218.679522 -172.21581) (xy 218.679013 -172.243696) (xy 218.670893 -172.298872)
			(xy 218.654825 -172.352279) (xy 218.631153 -172.402776) (xy 218.60038 -172.449289) (xy 218.563163 -172.490826)
			(xy 218.520295 -172.526501) (xy 218.472689 -172.555555) (xy 218.42136 -172.577367) (xy 218.367403 -172.591473)
			(xy 218.311966 -172.597573) (xy 218.256232 -172.595536) (xy 218.201389 -172.585406) (xy 218.148605 -172.567399)
			(xy 218.099005 -172.541898) (xy 218.053647 -172.509447) (xy 218.013498 -172.470738) (xy 217.979412 -172.426595)
			(xy 217.952116 -172.37796) (xy 217.932193 -172.325869) (xy 217.920067 -172.271432) (xy 217.915996 -172.21581)
			(xy 210.914629 -172.21581) (xy 210.914265 -172.216113) (xy 210.866659 -172.245167) (xy 210.81533 -172.266979)
			(xy 210.761373 -172.281085) (xy 210.705936 -172.287185) (xy 210.650202 -172.285148) (xy 210.595359 -172.275018)
			(xy 210.542575 -172.257011) (xy 210.492975 -172.23151) (xy 210.447617 -172.199059) (xy 210.407468 -172.16035)
			(xy 210.373382 -172.116207) (xy 210.346086 -172.067572) (xy 210.326163 -172.015481) (xy 210.314037 -171.961044)
			(xy 210.309966 -171.905422) (xy 192.790811 -171.905422) (xy 192.628912 -172.786294) (xy 235.508798 -172.786294)
			(xy 235.512869 -172.730672) (xy 235.524995 -172.676235) (xy 235.544918 -172.624144) (xy 235.572214 -172.575509)
			(xy 235.6063 -172.531366) (xy 235.646449 -172.492657) (xy 235.691807 -172.460206) (xy 235.741407 -172.434705)
			(xy 235.794191 -172.416698) (xy 235.849034 -172.406568) (xy 235.904768 -172.404531) (xy 235.960205 -172.410631)
			(xy 236.014162 -172.424737) (xy 236.065491 -172.446549) (xy 236.113097 -172.475603) (xy 236.155965 -172.511278)
			(xy 236.193182 -172.552815) (xy 236.223955 -172.599328) (xy 236.247627 -172.649825) (xy 236.263695 -172.703232)
			(xy 236.271815 -172.758408) (xy 236.272324 -172.786294) (xy 236.271815 -172.81418) (xy 236.263695 -172.869356)
			(xy 236.247627 -172.922763) (xy 236.230157 -172.96003) (xy 237.179356 -172.96003) (xy 237.183427 -172.904408)
			(xy 237.195553 -172.849971) (xy 237.215476 -172.79788) (xy 237.242772 -172.749245) (xy 237.276858 -172.705102)
			(xy 237.317007 -172.666393) (xy 237.362365 -172.633942) (xy 237.411965 -172.608441) (xy 237.464749 -172.590434)
			(xy 237.519592 -172.580304) (xy 237.575326 -172.578267) (xy 237.630763 -172.584367) (xy 237.68472 -172.598473)
			(xy 237.736049 -172.620285) (xy 237.783655 -172.649339) (xy 237.826523 -172.685014) (xy 237.86374 -172.726551)
			(xy 237.894513 -172.773064) (xy 237.918185 -172.823561) (xy 237.934253 -172.876968) (xy 237.942373 -172.932144)
			(xy 237.942882 -172.96003) (xy 237.942373 -172.987916) (xy 237.934253 -173.043092) (xy 237.918185 -173.096499)
			(xy 237.894513 -173.146996) (xy 237.86374 -173.193509) (xy 237.826523 -173.235046) (xy 237.783655 -173.270721)
			(xy 237.736049 -173.299775) (xy 237.68472 -173.321587) (xy 237.630763 -173.335693) (xy 237.575326 -173.341793)
			(xy 237.519592 -173.339756) (xy 237.464749 -173.329626) (xy 237.411965 -173.311619) (xy 237.362365 -173.286118)
			(xy 237.317007 -173.253667) (xy 237.276858 -173.214958) (xy 237.242772 -173.170815) (xy 237.215476 -173.12218)
			(xy 237.195553 -173.070089) (xy 237.183427 -173.015652) (xy 237.179356 -172.96003) (xy 236.230157 -172.96003)
			(xy 236.223955 -172.97326) (xy 236.193182 -173.019773) (xy 236.155965 -173.06131) (xy 236.113097 -173.096985)
			(xy 236.065491 -173.126039) (xy 236.014162 -173.147851) (xy 235.960205 -173.161957) (xy 235.904768 -173.168057)
			(xy 235.849034 -173.16602) (xy 235.794191 -173.15589) (xy 235.741407 -173.137883) (xy 235.691807 -173.112382)
			(xy 235.646449 -173.079931) (xy 235.6063 -173.041222) (xy 235.572214 -172.997079) (xy 235.544918 -172.948444)
			(xy 235.524995 -172.896353) (xy 235.512869 -172.841916) (xy 235.508798 -172.786294) (xy 192.628912 -172.786294)
			(xy 192.465099 -173.67758) (xy 231.38333 -173.67758) (xy 231.387401 -173.621958) (xy 231.399527 -173.567521)
			(xy 231.41945 -173.51543) (xy 231.446746 -173.466795) (xy 231.480832 -173.422652) (xy 231.520981 -173.383943)
			(xy 231.566339 -173.351492) (xy 231.615939 -173.325991) (xy 231.668723 -173.307984) (xy 231.723566 -173.297854)
			(xy 231.7793 -173.295817) (xy 231.834737 -173.301917) (xy 231.888694 -173.316023) (xy 231.940023 -173.337835)
			(xy 231.987629 -173.366889) (xy 232.030497 -173.402564) (xy 232.067714 -173.444101) (xy 232.098487 -173.490614)
			(xy 232.100879 -173.495716) (xy 257.519424 -173.495716) (xy 257.519424 -172.632116) (xy 257.519914 -172.602132)
			(xy 257.527742 -172.542676) (xy 257.543263 -172.484751) (xy 257.566212 -172.429347) (xy 257.596196 -172.377413)
			(xy 257.632702 -172.329837) (xy 257.675107 -172.287432) (xy 257.722683 -172.250926) (xy 257.774617 -172.220942)
			(xy 257.830021 -172.197993) (xy 257.887946 -172.182472) (xy 257.947402 -172.174644) (xy 258.00737 -172.174644)
			(xy 258.066826 -172.182472) (xy 258.124751 -172.197993) (xy 258.180155 -172.220942) (xy 258.232089 -172.250926)
			(xy 258.279665 -172.287432) (xy 258.32207 -172.329837) (xy 258.358576 -172.377413) (xy 258.38856 -172.429347)
			(xy 258.411509 -172.484751) (xy 258.42703 -172.542676) (xy 258.434858 -172.602132) (xy 258.435348 -172.632116)
			(xy 258.435348 -173.495716) (xy 258.434858 -173.5257) (xy 258.42703 -173.585156) (xy 258.411509 -173.643081)
			(xy 258.38856 -173.698485) (xy 258.358576 -173.750419) (xy 258.32207 -173.797995) (xy 258.279665 -173.8404)
			(xy 258.232089 -173.876906) (xy 258.180155 -173.90689) (xy 258.124751 -173.929839) (xy 258.066826 -173.94536)
			(xy 258.00737 -173.953188) (xy 257.947402 -173.953188) (xy 257.887946 -173.94536) (xy 257.830021 -173.929839)
			(xy 257.774617 -173.90689) (xy 257.722683 -173.876906) (xy 257.675107 -173.8404) (xy 257.632702 -173.797995)
			(xy 257.596196 -173.750419) (xy 257.566212 -173.698485) (xy 257.543263 -173.643081) (xy 257.527742 -173.585156)
			(xy 257.519914 -173.5257) (xy 257.519424 -173.495716) (xy 232.100879 -173.495716) (xy 232.122159 -173.541111)
			(xy 232.138227 -173.594518) (xy 232.146347 -173.649694) (xy 232.146856 -173.67758) (xy 232.146347 -173.705466)
			(xy 232.138227 -173.760642) (xy 232.122159 -173.814049) (xy 232.098487 -173.864546) (xy 232.067714 -173.911059)
			(xy 232.030497 -173.952596) (xy 231.987629 -173.988271) (xy 231.940023 -174.017325) (xy 231.888694 -174.039137)
			(xy 231.834737 -174.053243) (xy 231.7793 -174.059343) (xy 231.723566 -174.057306) (xy 231.668723 -174.047176)
			(xy 231.615939 -174.029169) (xy 231.566339 -174.003668) (xy 231.520981 -173.971217) (xy 231.480832 -173.932508)
			(xy 231.446746 -173.888365) (xy 231.41945 -173.83973) (xy 231.399527 -173.787639) (xy 231.387401 -173.733202)
			(xy 231.38333 -173.67758) (xy 192.465099 -173.67758) (xy 192.222344 -174.99838) (xy 219.081348 -174.99838)
			(xy 219.085419 -174.942758) (xy 219.097545 -174.888321) (xy 219.117468 -174.83623) (xy 219.144764 -174.787595)
			(xy 219.17885 -174.743452) (xy 219.218999 -174.704743) (xy 219.264357 -174.672292) (xy 219.313957 -174.646791)
			(xy 219.366741 -174.628784) (xy 219.421584 -174.618654) (xy 219.477318 -174.616617) (xy 219.532755 -174.622717)
			(xy 219.586712 -174.636823) (xy 219.638041 -174.658635) (xy 219.685647 -174.687689) (xy 219.692726 -174.69358)
			(xy 231.38333 -174.69358) (xy 231.387401 -174.637958) (xy 231.399527 -174.583521) (xy 231.41945 -174.53143)
			(xy 231.446746 -174.482795) (xy 231.480832 -174.438652) (xy 231.520981 -174.399943) (xy 231.566339 -174.367492)
			(xy 231.615939 -174.341991) (xy 231.668723 -174.323984) (xy 231.723566 -174.313854) (xy 231.7793 -174.311817)
			(xy 231.834737 -174.317917) (xy 231.884276 -174.330868) (xy 235.419644 -174.330868) (xy 235.423715 -174.275246)
			(xy 235.435841 -174.220809) (xy 235.455764 -174.168718) (xy 235.48306 -174.120083) (xy 235.517146 -174.07594)
			(xy 235.557295 -174.037231) (xy 235.602653 -174.00478) (xy 235.652253 -173.979279) (xy 235.705037 -173.961272)
			(xy 235.75988 -173.951142) (xy 235.815614 -173.949105) (xy 235.871051 -173.955205) (xy 235.925008 -173.969311)
			(xy 235.976337 -173.991123) (xy 236.023943 -174.020177) (xy 236.066811 -174.055852) (xy 236.104028 -174.097389)
			(xy 236.134801 -174.143902) (xy 236.158473 -174.194399) (xy 236.174541 -174.247806) (xy 236.182661 -174.302982)
			(xy 236.18317 -174.330868) (xy 236.182661 -174.358754) (xy 236.174541 -174.41393) (xy 236.158473 -174.467337)
			(xy 236.134801 -174.517834) (xy 236.104028 -174.564347) (xy 236.066811 -174.605884) (xy 236.023943 -174.641559)
			(xy 235.976337 -174.670613) (xy 235.925008 -174.692425) (xy 235.871051 -174.706531) (xy 235.815614 -174.712631)
			(xy 235.75988 -174.710594) (xy 235.705037 -174.700464) (xy 235.652253 -174.682457) (xy 235.602653 -174.656956)
			(xy 235.557295 -174.624505) (xy 235.517146 -174.585796) (xy 235.48306 -174.541653) (xy 235.455764 -174.493018)
			(xy 235.435841 -174.440927) (xy 235.423715 -174.38649) (xy 235.419644 -174.330868) (xy 231.884276 -174.330868)
			(xy 231.888694 -174.332023) (xy 231.940023 -174.353835) (xy 231.987629 -174.382889) (xy 232.030497 -174.418564)
			(xy 232.067714 -174.460101) (xy 232.098487 -174.506614) (xy 232.122159 -174.557111) (xy 232.138227 -174.610518)
			(xy 232.146347 -174.665694) (xy 232.146856 -174.69358) (xy 232.146347 -174.721466) (xy 232.138227 -174.776642)
			(xy 232.122159 -174.830049) (xy 232.098487 -174.880546) (xy 232.067714 -174.927059) (xy 232.030497 -174.968596)
			(xy 231.987629 -175.004271) (xy 231.940023 -175.033325) (xy 231.888694 -175.055137) (xy 231.834737 -175.069243)
			(xy 231.7793 -175.075343) (xy 231.723566 -175.073306) (xy 231.668723 -175.063176) (xy 231.615939 -175.045169)
			(xy 231.566339 -175.019668) (xy 231.520981 -174.987217) (xy 231.480832 -174.948508) (xy 231.446746 -174.904365)
			(xy 231.41945 -174.85573) (xy 231.399527 -174.803639) (xy 231.387401 -174.749202) (xy 231.38333 -174.69358)
			(xy 219.692726 -174.69358) (xy 219.728515 -174.723364) (xy 219.765732 -174.764901) (xy 219.796505 -174.811414)
			(xy 219.820177 -174.861911) (xy 219.836245 -174.915318) (xy 219.844365 -174.970494) (xy 219.844874 -174.99838)
			(xy 219.844365 -175.026266) (xy 219.836245 -175.081442) (xy 219.820177 -175.134849) (xy 219.796505 -175.185346)
			(xy 219.765732 -175.231859) (xy 219.728515 -175.273396) (xy 219.685647 -175.309071) (xy 219.638041 -175.338125)
			(xy 219.586712 -175.359937) (xy 219.532755 -175.374043) (xy 219.477318 -175.380143) (xy 219.421584 -175.378106)
			(xy 219.366741 -175.367976) (xy 219.313957 -175.349969) (xy 219.264357 -175.324468) (xy 219.218999 -175.292017)
			(xy 219.17885 -175.253308) (xy 219.144764 -175.209165) (xy 219.117468 -175.16053) (xy 219.097545 -175.108439)
			(xy 219.085419 -175.054002) (xy 219.081348 -174.99838) (xy 192.222344 -174.99838) (xy 192.128977 -175.50638)
			(xy 222.194626 -175.50638) (xy 222.198697 -175.450758) (xy 222.210823 -175.396321) (xy 222.230746 -175.34423)
			(xy 222.258042 -175.295595) (xy 222.292128 -175.251452) (xy 222.332277 -175.212743) (xy 222.377635 -175.180292)
			(xy 222.427235 -175.154791) (xy 222.480019 -175.136784) (xy 222.534862 -175.126654) (xy 222.590596 -175.124617)
			(xy 222.646033 -175.130717) (xy 222.69999 -175.144823) (xy 222.751319 -175.166635) (xy 222.798925 -175.195689)
			(xy 222.841793 -175.231364) (xy 222.87901 -175.272901) (xy 222.909783 -175.319414) (xy 222.915151 -175.330866)
			(xy 224.385376 -175.330866) (xy 224.389447 -175.275244) (xy 224.401573 -175.220807) (xy 224.421496 -175.168716)
			(xy 224.448792 -175.120081) (xy 224.482878 -175.075938) (xy 224.523027 -175.037229) (xy 224.568385 -175.004778)
			(xy 224.617985 -174.979277) (xy 224.670769 -174.96127) (xy 224.725612 -174.95114) (xy 224.781346 -174.949103)
			(xy 224.836783 -174.955203) (xy 224.89074 -174.969309) (xy 224.942069 -174.991121) (xy 224.989675 -175.020175)
			(xy 225.032543 -175.05585) (xy 225.063435 -175.090328) (xy 228.785926 -175.090328) (xy 228.789997 -175.034706)
			(xy 228.802123 -174.980269) (xy 228.822046 -174.928178) (xy 228.849342 -174.879543) (xy 228.883428 -174.8354)
			(xy 228.923577 -174.796691) (xy 228.968935 -174.76424) (xy 229.018535 -174.738739) (xy 229.071319 -174.720732)
			(xy 229.126162 -174.710602) (xy 229.181896 -174.708565) (xy 229.237333 -174.714665) (xy 229.29129 -174.728771)
			(xy 229.342619 -174.750583) (xy 229.390225 -174.779637) (xy 229.433093 -174.815312) (xy 229.47031 -174.856849)
			(xy 229.501083 -174.903362) (xy 229.524755 -174.953859) (xy 229.540823 -175.007266) (xy 229.548943 -175.062442)
			(xy 229.549452 -175.090328) (xy 229.548943 -175.118214) (xy 229.540823 -175.17339) (xy 229.524755 -175.226797)
			(xy 229.501083 -175.277294) (xy 229.47031 -175.323807) (xy 229.433093 -175.365344) (xy 229.390225 -175.401019)
			(xy 229.342619 -175.430073) (xy 229.29129 -175.451885) (xy 229.237333 -175.465991) (xy 229.181896 -175.472091)
			(xy 229.126162 -175.470054) (xy 229.071319 -175.459924) (xy 229.018535 -175.441917) (xy 228.968935 -175.416416)
			(xy 228.923577 -175.383965) (xy 228.883428 -175.345256) (xy 228.849342 -175.301113) (xy 228.822046 -175.252478)
			(xy 228.802123 -175.200387) (xy 228.789997 -175.14595) (xy 228.785926 -175.090328) (xy 225.063435 -175.090328)
			(xy 225.06976 -175.097387) (xy 225.100533 -175.1439) (xy 225.124205 -175.194397) (xy 225.140273 -175.247804)
			(xy 225.148393 -175.30298) (xy 225.148902 -175.330866) (xy 225.148393 -175.358752) (xy 225.140273 -175.413928)
			(xy 225.124205 -175.467335) (xy 225.100533 -175.517832) (xy 225.06976 -175.564345) (xy 225.032543 -175.605882)
			(xy 225.014456 -175.620934) (xy 259.44398 -175.620934) (xy 259.448051 -175.565312) (xy 259.460177 -175.510875)
			(xy 259.4801 -175.458784) (xy 259.507396 -175.410149) (xy 259.541482 -175.366006) (xy 259.581631 -175.327297)
			(xy 259.626989 -175.294846) (xy 259.676589 -175.269345) (xy 259.729373 -175.251338) (xy 259.784216 -175.241208)
			(xy 259.83995 -175.239171) (xy 259.895387 -175.245271) (xy 259.949344 -175.259377) (xy 260.000673 -175.281189)
			(xy 260.048279 -175.310243) (xy 260.091147 -175.345918) (xy 260.128364 -175.387455) (xy 260.159137 -175.433968)
			(xy 260.182809 -175.484465) (xy 260.198877 -175.537872) (xy 260.206997 -175.593048) (xy 260.207506 -175.620934)
			(xy 260.206997 -175.64882) (xy 260.198877 -175.703996) (xy 260.182809 -175.757403) (xy 260.159137 -175.8079)
			(xy 260.128364 -175.854413) (xy 260.091147 -175.89595) (xy 260.048279 -175.931625) (xy 260.000673 -175.960679)
			(xy 259.949344 -175.982491) (xy 259.895387 -175.996597) (xy 259.83995 -176.002697) (xy 259.784216 -176.00066)
			(xy 259.729373 -175.99053) (xy 259.676589 -175.972523) (xy 259.626989 -175.947022) (xy 259.581631 -175.914571)
			(xy 259.541482 -175.875862) (xy 259.507396 -175.831719) (xy 259.4801 -175.783084) (xy 259.460177 -175.730993)
			(xy 259.448051 -175.676556) (xy 259.44398 -175.620934) (xy 225.014456 -175.620934) (xy 224.989675 -175.641557)
			(xy 224.942069 -175.670611) (xy 224.89074 -175.692423) (xy 224.836783 -175.706529) (xy 224.781346 -175.712629)
			(xy 224.725612 -175.710592) (xy 224.670769 -175.700462) (xy 224.617985 -175.682455) (xy 224.568385 -175.656954)
			(xy 224.523027 -175.624503) (xy 224.482878 -175.585794) (xy 224.448792 -175.541651) (xy 224.421496 -175.493016)
			(xy 224.401573 -175.440925) (xy 224.389447 -175.386488) (xy 224.385376 -175.330866) (xy 222.915151 -175.330866)
			(xy 222.933455 -175.369911) (xy 222.949523 -175.423318) (xy 222.957643 -175.478494) (xy 222.958152 -175.50638)
			(xy 222.957643 -175.534266) (xy 222.949523 -175.589442) (xy 222.933455 -175.642849) (xy 222.909783 -175.693346)
			(xy 222.87901 -175.739859) (xy 222.841793 -175.781396) (xy 222.798925 -175.817071) (xy 222.751319 -175.846125)
			(xy 222.69999 -175.867937) (xy 222.646033 -175.882043) (xy 222.590596 -175.888143) (xy 222.534862 -175.886106)
			(xy 222.480019 -175.875976) (xy 222.427235 -175.857969) (xy 222.377635 -175.832468) (xy 222.332277 -175.800017)
			(xy 222.292128 -175.761308) (xy 222.258042 -175.717165) (xy 222.230746 -175.66853) (xy 222.210823 -175.616439)
			(xy 222.198697 -175.562002) (xy 222.194626 -175.50638) (xy 192.128977 -175.50638) (xy 192.047747 -175.94834)
			(xy 216.952066 -175.94834) (xy 216.956137 -175.892718) (xy 216.968263 -175.838281) (xy 216.988186 -175.78619)
			(xy 217.015482 -175.737555) (xy 217.049568 -175.693412) (xy 217.089717 -175.654703) (xy 217.135075 -175.622252)
			(xy 217.184675 -175.596751) (xy 217.237459 -175.578744) (xy 217.292302 -175.568614) (xy 217.348036 -175.566577)
			(xy 217.403473 -175.572677) (xy 217.45743 -175.586783) (xy 217.508759 -175.608595) (xy 217.556365 -175.637649)
			(xy 217.599233 -175.673324) (xy 217.63645 -175.714861) (xy 217.667223 -175.761374) (xy 217.690895 -175.811871)
			(xy 217.706963 -175.865278) (xy 217.715083 -175.920454) (xy 217.715592 -175.94834) (xy 217.715083 -175.976226)
			(xy 217.706963 -176.031402) (xy 217.690895 -176.084809) (xy 217.667223 -176.135306) (xy 217.63645 -176.181819)
			(xy 217.599233 -176.223356) (xy 217.556365 -176.259031) (xy 217.508759 -176.288085) (xy 217.45743 -176.309897)
			(xy 217.403473 -176.324003) (xy 217.348036 -176.330103) (xy 217.292302 -176.328066) (xy 217.237459 -176.317936)
			(xy 217.184675 -176.299929) (xy 217.135075 -176.274428) (xy 217.089717 -176.241977) (xy 217.049568 -176.203268)
			(xy 217.015482 -176.159125) (xy 216.988186 -176.11049) (xy 216.968263 -176.058399) (xy 216.956137 -176.003962)
			(xy 216.952066 -175.94834) (xy 192.047747 -175.94834) (xy 191.950692 -176.476406) (xy 215.436702 -176.476406)
			(xy 215.440773 -176.420784) (xy 215.452899 -176.366347) (xy 215.472822 -176.314256) (xy 215.500118 -176.265621)
			(xy 215.534204 -176.221478) (xy 215.574353 -176.182769) (xy 215.619711 -176.150318) (xy 215.669311 -176.124817)
			(xy 215.722095 -176.10681) (xy 215.776938 -176.09668) (xy 215.832672 -176.094643) (xy 215.888109 -176.100743)
			(xy 215.942066 -176.114849) (xy 215.993395 -176.136661) (xy 216.041001 -176.165715) (xy 216.083869 -176.20139)
			(xy 216.121086 -176.242927) (xy 216.151859 -176.28944) (xy 216.175531 -176.339937) (xy 216.191599 -176.393344)
			(xy 216.199719 -176.44852) (xy 216.200228 -176.476406) (xy 216.199719 -176.504292) (xy 216.197057 -176.52238)
			(xy 222.194626 -176.52238) (xy 222.198697 -176.466758) (xy 222.210823 -176.412321) (xy 222.230746 -176.36023)
			(xy 222.258042 -176.311595) (xy 222.292128 -176.267452) (xy 222.332277 -176.228743) (xy 222.377635 -176.196292)
			(xy 222.427235 -176.170791) (xy 222.480019 -176.152784) (xy 222.534862 -176.142654) (xy 222.590596 -176.140617)
			(xy 222.646033 -176.146717) (xy 222.69999 -176.160823) (xy 222.751319 -176.182635) (xy 222.798925 -176.211689)
			(xy 222.841793 -176.247364) (xy 222.87901 -176.288901) (xy 222.909783 -176.335414) (xy 222.921462 -176.360328)
			(xy 228.785926 -176.360328) (xy 228.789997 -176.304706) (xy 228.802123 -176.250269) (xy 228.822046 -176.198178)
			(xy 228.849342 -176.149543) (xy 228.883428 -176.1054) (xy 228.923577 -176.066691) (xy 228.968935 -176.03424)
			(xy 229.018535 -176.008739) (xy 229.071319 -175.990732) (xy 229.126162 -175.980602) (xy 229.181896 -175.978565)
			(xy 229.237333 -175.984665) (xy 229.29129 -175.998771) (xy 229.342619 -176.020583) (xy 229.390225 -176.049637)
			(xy 229.433093 -176.085312) (xy 229.47031 -176.126849) (xy 229.501083 -176.173362) (xy 229.524755 -176.223859)
			(xy 229.540823 -176.277266) (xy 229.548943 -176.332442) (xy 229.549452 -176.360328) (xy 229.548943 -176.388214)
			(xy 229.540823 -176.44339) (xy 229.524755 -176.496797) (xy 229.501083 -176.547294) (xy 229.47031 -176.593807)
			(xy 229.433093 -176.635344) (xy 229.390225 -176.671019) (xy 229.342619 -176.700073) (xy 229.29129 -176.721885)
			(xy 229.237333 -176.735991) (xy 229.181896 -176.742091) (xy 229.126162 -176.740054) (xy 229.071319 -176.729924)
			(xy 229.018535 -176.711917) (xy 228.968935 -176.686416) (xy 228.923577 -176.653965) (xy 228.883428 -176.615256)
			(xy 228.849342 -176.571113) (xy 228.822046 -176.522478) (xy 228.802123 -176.470387) (xy 228.789997 -176.41595)
			(xy 228.785926 -176.360328) (xy 222.921462 -176.360328) (xy 222.933455 -176.385911) (xy 222.949523 -176.439318)
			(xy 222.957643 -176.494494) (xy 222.958152 -176.52238) (xy 222.957643 -176.550266) (xy 222.949523 -176.605442)
			(xy 222.933455 -176.658849) (xy 222.909783 -176.709346) (xy 222.87901 -176.755859) (xy 222.841793 -176.797396)
			(xy 222.798925 -176.833071) (xy 222.751319 -176.862125) (xy 222.69999 -176.883937) (xy 222.646033 -176.898043)
			(xy 222.590596 -176.904143) (xy 222.534862 -176.902106) (xy 222.480019 -176.891976) (xy 222.427235 -176.873969)
			(xy 222.377635 -176.848468) (xy 222.332277 -176.816017) (xy 222.292128 -176.777308) (xy 222.258042 -176.733165)
			(xy 222.230746 -176.68453) (xy 222.210823 -176.632439) (xy 222.198697 -176.578002) (xy 222.194626 -176.52238)
			(xy 216.197057 -176.52238) (xy 216.191599 -176.559468) (xy 216.175531 -176.612875) (xy 216.151859 -176.663372)
			(xy 216.121086 -176.709885) (xy 216.083869 -176.751422) (xy 216.041001 -176.787097) (xy 215.993395 -176.816151)
			(xy 215.942066 -176.837963) (xy 215.888109 -176.852069) (xy 215.832672 -176.858169) (xy 215.776938 -176.856132)
			(xy 215.722095 -176.846002) (xy 215.669311 -176.827995) (xy 215.619711 -176.802494) (xy 215.574353 -176.770043)
			(xy 215.534204 -176.731334) (xy 215.500118 -176.687191) (xy 215.472822 -176.638556) (xy 215.452899 -176.586465)
			(xy 215.440773 -176.532028) (xy 215.436702 -176.476406) (xy 191.950692 -176.476406) (xy 191.862507 -176.956212)
			(xy 224.383344 -176.956212) (xy 224.387415 -176.90059) (xy 224.399541 -176.846153) (xy 224.419464 -176.794062)
			(xy 224.44676 -176.745427) (xy 224.480846 -176.701284) (xy 224.520995 -176.662575) (xy 224.566353 -176.630124)
			(xy 224.615953 -176.604623) (xy 224.668737 -176.586616) (xy 224.72358 -176.576486) (xy 224.779314 -176.574449)
			(xy 224.834751 -176.580549) (xy 224.888708 -176.594655) (xy 224.940037 -176.616467) (xy 224.987643 -176.645521)
			(xy 225.030511 -176.681196) (xy 225.067728 -176.722733) (xy 225.098501 -176.769246) (xy 225.122173 -176.819743)
			(xy 225.138241 -176.87315) (xy 225.146361 -176.928326) (xy 225.14687 -176.956212) (xy 225.146361 -176.984098)
			(xy 225.138241 -177.039274) (xy 225.122173 -177.092681) (xy 225.098501 -177.143178) (xy 225.067728 -177.189691)
			(xy 225.030511 -177.231228) (xy 224.987643 -177.266903) (xy 224.940037 -177.295957) (xy 224.888708 -177.317769)
			(xy 224.834751 -177.331875) (xy 224.779314 -177.337975) (xy 224.72358 -177.335938) (xy 224.668737 -177.325808)
			(xy 224.615953 -177.307801) (xy 224.566353 -177.2823) (xy 224.520995 -177.249849) (xy 224.480846 -177.21114)
			(xy 224.44676 -177.166997) (xy 224.419464 -177.118362) (xy 224.399541 -177.066271) (xy 224.387415 -177.011834)
			(xy 224.383344 -176.956212) (xy 191.862507 -176.956212) (xy 191.697387 -177.85461) (xy 212.50859 -177.85461)
			(xy 212.512661 -177.798988) (xy 212.524787 -177.744551) (xy 212.54471 -177.69246) (xy 212.572006 -177.643825)
			(xy 212.606092 -177.599682) (xy 212.646241 -177.560973) (xy 212.691599 -177.528522) (xy 212.741199 -177.503021)
			(xy 212.793983 -177.485014) (xy 212.848826 -177.474884) (xy 212.90456 -177.472847) (xy 212.959997 -177.478947)
			(xy 213.013954 -177.493053) (xy 213.065283 -177.514865) (xy 213.103813 -177.53838) (xy 222.194626 -177.53838)
			(xy 222.198697 -177.482758) (xy 222.210823 -177.428321) (xy 222.230746 -177.37623) (xy 222.258042 -177.327595)
			(xy 222.292128 -177.283452) (xy 222.332277 -177.244743) (xy 222.377635 -177.212292) (xy 222.427235 -177.186791)
			(xy 222.480019 -177.168784) (xy 222.534862 -177.158654) (xy 222.590596 -177.156617) (xy 222.646033 -177.162717)
			(xy 222.69999 -177.176823) (xy 222.751319 -177.198635) (xy 222.798925 -177.227689) (xy 222.841793 -177.263364)
			(xy 222.87901 -177.304901) (xy 222.909783 -177.351414) (xy 222.933455 -177.401911) (xy 222.949523 -177.455318)
			(xy 222.957643 -177.510494) (xy 222.958152 -177.53838) (xy 222.957643 -177.566266) (xy 222.949523 -177.621442)
			(xy 222.933455 -177.674849) (xy 222.928368 -177.6857) (xy 240.297206 -177.6857) (xy 240.301277 -177.630078)
			(xy 240.313403 -177.575641) (xy 240.333326 -177.52355) (xy 240.360622 -177.474915) (xy 240.394708 -177.430772)
			(xy 240.434857 -177.392063) (xy 240.480215 -177.359612) (xy 240.529815 -177.334111) (xy 240.582599 -177.316104)
			(xy 240.637442 -177.305974) (xy 240.693176 -177.303937) (xy 240.748613 -177.310037) (xy 240.80257 -177.324143)
			(xy 240.853899 -177.345955) (xy 240.901505 -177.375009) (xy 240.944373 -177.410684) (xy 240.98159 -177.452221)
			(xy 241.012363 -177.498734) (xy 241.031425 -177.539396) (xy 259.176772 -177.539396) (xy 259.180843 -177.483774)
			(xy 259.192969 -177.429337) (xy 259.212892 -177.377246) (xy 259.240188 -177.328611) (xy 259.274274 -177.284468)
			(xy 259.314423 -177.245759) (xy 259.359781 -177.213308) (xy 259.409381 -177.187807) (xy 259.462165 -177.1698)
			(xy 259.517008 -177.15967) (xy 259.572742 -177.157633) (xy 259.628179 -177.163733) (xy 259.682136 -177.177839)
			(xy 259.733465 -177.199651) (xy 259.781071 -177.228705) (xy 259.823939 -177.26438) (xy 259.861156 -177.305917)
			(xy 259.891929 -177.35243) (xy 259.915601 -177.402927) (xy 259.931669 -177.456334) (xy 259.939789 -177.51151)
			(xy 259.940298 -177.539396) (xy 259.939789 -177.567282) (xy 259.931669 -177.622458) (xy 259.915601 -177.675865)
			(xy 259.891929 -177.726362) (xy 259.861156 -177.772875) (xy 259.823939 -177.814412) (xy 259.781071 -177.850087)
			(xy 259.733465 -177.879141) (xy 259.682136 -177.900953) (xy 259.628179 -177.915059) (xy 259.572742 -177.921159)
			(xy 259.517008 -177.919122) (xy 259.462165 -177.908992) (xy 259.409381 -177.890985) (xy 259.359781 -177.865484)
			(xy 259.314423 -177.833033) (xy 259.274274 -177.794324) (xy 259.240188 -177.750181) (xy 259.212892 -177.701546)
			(xy 259.192969 -177.649455) (xy 259.180843 -177.595018) (xy 259.176772 -177.539396) (xy 241.031425 -177.539396)
			(xy 241.036035 -177.549231) (xy 241.052103 -177.602638) (xy 241.060223 -177.657814) (xy 241.060732 -177.6857)
			(xy 241.060223 -177.713586) (xy 241.052103 -177.768762) (xy 241.036035 -177.822169) (xy 241.012363 -177.872666)
			(xy 240.98159 -177.919179) (xy 240.944373 -177.960716) (xy 240.901505 -177.996391) (xy 240.853899 -178.025445)
			(xy 240.80257 -178.047257) (xy 240.748613 -178.061363) (xy 240.693176 -178.067463) (xy 240.637442 -178.065426)
			(xy 240.582599 -178.055296) (xy 240.529815 -178.037289) (xy 240.480215 -178.011788) (xy 240.434857 -177.979337)
			(xy 240.394708 -177.940628) (xy 240.360622 -177.896485) (xy 240.333326 -177.84785) (xy 240.313403 -177.795759)
			(xy 240.301277 -177.741322) (xy 240.297206 -177.6857) (xy 222.928368 -177.6857) (xy 222.909783 -177.725346)
			(xy 222.87901 -177.771859) (xy 222.841793 -177.813396) (xy 222.798925 -177.849071) (xy 222.751319 -177.878125)
			(xy 222.69999 -177.899937) (xy 222.646033 -177.914043) (xy 222.590596 -177.920143) (xy 222.534862 -177.918106)
			(xy 222.480019 -177.907976) (xy 222.427235 -177.889969) (xy 222.377635 -177.864468) (xy 222.332277 -177.832017)
			(xy 222.292128 -177.793308) (xy 222.258042 -177.749165) (xy 222.230746 -177.70053) (xy 222.210823 -177.648439)
			(xy 222.198697 -177.594002) (xy 222.194626 -177.53838) (xy 213.103813 -177.53838) (xy 213.112889 -177.543919)
			(xy 213.155757 -177.579594) (xy 213.192974 -177.621131) (xy 213.223747 -177.667644) (xy 213.247419 -177.718141)
			(xy 213.263487 -177.771548) (xy 213.271607 -177.826724) (xy 213.272116 -177.85461) (xy 213.271607 -177.882496)
			(xy 213.263487 -177.937672) (xy 213.247419 -177.991079) (xy 213.223747 -178.041576) (xy 213.192974 -178.088089)
			(xy 213.184828 -178.09718) (xy 217.597226 -178.09718) (xy 217.601297 -178.041558) (xy 217.613423 -177.987121)
			(xy 217.633346 -177.93503) (xy 217.660642 -177.886395) (xy 217.694728 -177.842252) (xy 217.734877 -177.803543)
			(xy 217.780235 -177.771092) (xy 217.829835 -177.745591) (xy 217.882619 -177.727584) (xy 217.937462 -177.717454)
			(xy 217.993196 -177.715417) (xy 218.048633 -177.721517) (xy 218.10259 -177.735623) (xy 218.153919 -177.757435)
			(xy 218.201525 -177.786489) (xy 218.244393 -177.822164) (xy 218.28161 -177.863701) (xy 218.312383 -177.910214)
			(xy 218.336055 -177.960711) (xy 218.352123 -178.014118) (xy 218.35403 -178.027076) (xy 220.323408 -178.027076)
			(xy 220.327479 -177.971454) (xy 220.339605 -177.917017) (xy 220.359528 -177.864926) (xy 220.386824 -177.816291)
			(xy 220.42091 -177.772148) (xy 220.461059 -177.733439) (xy 220.506417 -177.700988) (xy 220.556017 -177.675487)
			(xy 220.608801 -177.65748) (xy 220.663644 -177.64735) (xy 220.719378 -177.645313) (xy 220.774815 -177.651413)
			(xy 220.828772 -177.665519) (xy 220.880101 -177.687331) (xy 220.927707 -177.716385) (xy 220.970575 -177.75206)
			(xy 221.007792 -177.793597) (xy 221.038565 -177.84011) (xy 221.062237 -177.890607) (xy 221.078305 -177.944014)
			(xy 221.086425 -177.99919) (xy 221.086934 -178.027076) (xy 221.086425 -178.054962) (xy 221.078305 -178.110138)
			(xy 221.062237 -178.163545) (xy 221.038565 -178.214042) (xy 221.007792 -178.260555) (xy 220.970575 -178.302092)
			(xy 220.927707 -178.337767) (xy 220.880101 -178.366821) (xy 220.828772 -178.388633) (xy 220.774815 -178.402739)
			(xy 220.719378 -178.408839) (xy 220.663644 -178.406802) (xy 220.608801 -178.396672) (xy 220.556017 -178.378665)
			(xy 220.506417 -178.353164) (xy 220.461059 -178.320713) (xy 220.42091 -178.282004) (xy 220.386824 -178.237861)
			(xy 220.359528 -178.189226) (xy 220.339605 -178.137135) (xy 220.327479 -178.082698) (xy 220.323408 -178.027076)
			(xy 218.35403 -178.027076) (xy 218.360243 -178.069294) (xy 218.360752 -178.09718) (xy 218.360243 -178.125066)
			(xy 218.352123 -178.180242) (xy 218.336055 -178.233649) (xy 218.312383 -178.284146) (xy 218.28161 -178.330659)
			(xy 218.244393 -178.372196) (xy 218.201525 -178.407871) (xy 218.153919 -178.436925) (xy 218.10259 -178.458737)
			(xy 218.048633 -178.472843) (xy 217.993196 -178.478943) (xy 217.937462 -178.476906) (xy 217.882619 -178.466776)
			(xy 217.829835 -178.448769) (xy 217.780235 -178.423268) (xy 217.734877 -178.390817) (xy 217.694728 -178.352108)
			(xy 217.660642 -178.307965) (xy 217.633346 -178.25933) (xy 217.613423 -178.207239) (xy 217.601297 -178.152802)
			(xy 217.597226 -178.09718) (xy 213.184828 -178.09718) (xy 213.155757 -178.129626) (xy 213.112889 -178.165301)
			(xy 213.065283 -178.194355) (xy 213.013954 -178.216167) (xy 212.959997 -178.230273) (xy 212.90456 -178.236373)
			(xy 212.848826 -178.234336) (xy 212.793983 -178.224206) (xy 212.741199 -178.206199) (xy 212.691599 -178.180698)
			(xy 212.646241 -178.148247) (xy 212.606092 -178.109538) (xy 212.572006 -178.065395) (xy 212.54471 -178.01676)
			(xy 212.524787 -177.964669) (xy 212.512661 -177.910232) (xy 212.50859 -177.85461) (xy 191.697387 -177.85461)
			(xy 191.547999 -178.66741) (xy 208.886042 -178.66741) (xy 208.890113 -178.611788) (xy 208.902239 -178.557351)
			(xy 208.922162 -178.50526) (xy 208.949458 -178.456625) (xy 208.983544 -178.412482) (xy 209.023693 -178.373773)
			(xy 209.069051 -178.341322) (xy 209.118651 -178.315821) (xy 209.171435 -178.297814) (xy 209.226278 -178.287684)
			(xy 209.282012 -178.285647) (xy 209.337449 -178.291747) (xy 209.391406 -178.305853) (xy 209.442735 -178.327665)
			(xy 209.490341 -178.356719) (xy 209.533209 -178.392394) (xy 209.570426 -178.433931) (xy 209.601199 -178.480444)
			(xy 209.624871 -178.530941) (xy 209.640939 -178.584348) (xy 209.649059 -178.639524) (xy 209.649568 -178.66741)
			(xy 209.649059 -178.695296) (xy 209.640939 -178.750472) (xy 209.624871 -178.803879) (xy 209.601199 -178.854376)
			(xy 209.570426 -178.900889) (xy 209.533209 -178.942426) (xy 209.490341 -178.978101) (xy 209.442735 -179.007155)
			(xy 209.391406 -179.028967) (xy 209.337449 -179.043073) (xy 209.282012 -179.049173) (xy 209.226278 -179.047136)
			(xy 209.171435 -179.037006) (xy 209.118651 -179.018999) (xy 209.069051 -178.993498) (xy 209.023693 -178.961047)
			(xy 208.983544 -178.922338) (xy 208.949458 -178.878195) (xy 208.922162 -178.82956) (xy 208.902239 -178.777469)
			(xy 208.890113 -178.723032) (xy 208.886042 -178.66741) (xy 191.547999 -178.66741) (xy 191.451177 -179.194206)
			(xy 210.383118 -179.194206) (xy 210.387189 -179.138584) (xy 210.399315 -179.084147) (xy 210.419238 -179.032056)
			(xy 210.446534 -178.983421) (xy 210.48062 -178.939278) (xy 210.520769 -178.900569) (xy 210.566127 -178.868118)
			(xy 210.615727 -178.842617) (xy 210.668511 -178.82461) (xy 210.723354 -178.81448) (xy 210.779088 -178.812443)
			(xy 210.834525 -178.818543) (xy 210.888482 -178.832649) (xy 210.939811 -178.854461) (xy 210.987417 -178.883515)
			(xy 211.030285 -178.91919) (xy 211.067502 -178.960727) (xy 211.098275 -179.00724) (xy 211.121947 -179.057737)
			(xy 211.138015 -179.111144) (xy 211.146135 -179.16632) (xy 211.146644 -179.194206) (xy 211.146135 -179.222092)
			(xy 211.138015 -179.277268) (xy 211.121947 -179.330675) (xy 211.098275 -179.381172) (xy 211.067502 -179.427685)
			(xy 211.030285 -179.469222) (xy 210.987417 -179.504897) (xy 210.939811 -179.533951) (xy 210.888482 -179.555763)
			(xy 210.834525 -179.569869) (xy 210.779088 -179.575969) (xy 210.723354 -179.573932) (xy 210.668511 -179.563802)
			(xy 210.615727 -179.545795) (xy 210.566127 -179.520294) (xy 210.520769 -179.487843) (xy 210.48062 -179.449134)
			(xy 210.446534 -179.404991) (xy 210.419238 -179.356356) (xy 210.399315 -179.304265) (xy 210.387189 -179.249828)
			(xy 210.383118 -179.194206) (xy 191.451177 -179.194206) (xy 191.329753 -179.85486) (xy 214.447628 -179.85486)
			(xy 214.447628 -179.854606) (xy 214.448175 -179.825868) (xy 214.456795 -179.769043) (xy 214.47384 -179.714153)
			(xy 214.498926 -179.662441) (xy 214.531485 -179.615077) (xy 214.550752 -179.593748) (xy 214.557356 -179.58689)
			(xy 214.564468 -179.568856) (xy 214.564468 -179.479956) (xy 214.557356 -179.461922) (xy 214.550752 -179.455064)
			(xy 214.531486 -179.433732) (xy 214.498919 -179.386372) (xy 214.473825 -179.334661) (xy 214.456773 -179.279772)
			(xy 214.448149 -179.222945) (xy 214.447628 -179.194206) (xy 214.448114 -179.166955) (xy 214.45587 -179.113007)
			(xy 214.471225 -179.060712) (xy 214.493867 -179.011135) (xy 214.523333 -178.965285) (xy 214.559024 -178.924094)
			(xy 214.600215 -178.888403) (xy 214.646065 -178.858937) (xy 214.695642 -178.836295) (xy 214.747937 -178.82094)
			(xy 214.801885 -178.813184) (xy 214.856387 -178.813184) (xy 214.910335 -178.82094) (xy 214.96263 -178.836295)
			(xy 215.012207 -178.858937) (xy 215.058057 -178.888403) (xy 215.099248 -178.924094) (xy 215.134939 -178.965285)
			(xy 215.146082 -178.982624) (xy 226.501196 -178.982624) (xy 226.505267 -178.927002) (xy 226.517393 -178.872565)
			(xy 226.537316 -178.820474) (xy 226.564612 -178.771839) (xy 226.598698 -178.727696) (xy 226.638847 -178.688987)
			(xy 226.684205 -178.656536) (xy 226.733805 -178.631035) (xy 226.786589 -178.613028) (xy 226.841432 -178.602898)
			(xy 226.897166 -178.600861) (xy 226.952603 -178.606961) (xy 227.00656 -178.621067) (xy 227.057889 -178.642879)
			(xy 227.105495 -178.671933) (xy 227.148363 -178.707608) (xy 227.169242 -178.73091) (xy 228.939596 -178.73091)
			(xy 228.943667 -178.675288) (xy 228.955793 -178.620851) (xy 228.975716 -178.56876) (xy 229.003012 -178.520125)
			(xy 229.037098 -178.475982) (xy 229.077247 -178.437273) (xy 229.122605 -178.404822) (xy 229.172205 -178.379321)
			(xy 229.224989 -178.361314) (xy 229.279832 -178.351184) (xy 229.335566 -178.349147) (xy 229.391003 -178.355247)
			(xy 229.44496 -178.369353) (xy 229.470933 -178.38039) (xy 229.967026 -178.38039) (xy 229.971097 -178.324768)
			(xy 229.983223 -178.270331) (xy 230.003146 -178.21824) (xy 230.030442 -178.169605) (xy 230.064528 -178.125462)
			(xy 230.104677 -178.086753) (xy 230.150035 -178.054302) (xy 230.199635 -178.028801) (xy 230.252419 -178.010794)
			(xy 230.307262 -178.000664) (xy 230.362996 -177.998627) (xy 230.418433 -178.004727) (xy 230.47239 -178.018833)
			(xy 230.523719 -178.040645) (xy 230.571325 -178.069699) (xy 230.614193 -178.105374) (xy 230.65141 -178.146911)
			(xy 230.682183 -178.193424) (xy 230.705855 -178.243921) (xy 230.721923 -178.297328) (xy 230.730043 -178.352504)
			(xy 230.730552 -178.38039) (xy 230.730043 -178.408276) (xy 230.721923 -178.463452) (xy 230.705855 -178.516859)
			(xy 230.682183 -178.567356) (xy 230.65141 -178.613869) (xy 230.614193 -178.655406) (xy 230.571325 -178.691081)
			(xy 230.523719 -178.720135) (xy 230.47239 -178.741947) (xy 230.418433 -178.756053) (xy 230.362996 -178.762153)
			(xy 230.307262 -178.760116) (xy 230.252419 -178.749986) (xy 230.199635 -178.731979) (xy 230.150035 -178.706478)
			(xy 230.104677 -178.674027) (xy 230.064528 -178.635318) (xy 230.030442 -178.591175) (xy 230.003146 -178.54254)
			(xy 229.983223 -178.490449) (xy 229.971097 -178.436012) (xy 229.967026 -178.38039) (xy 229.470933 -178.38039)
			(xy 229.496289 -178.391165) (xy 229.543895 -178.420219) (xy 229.586763 -178.455894) (xy 229.62398 -178.497431)
			(xy 229.654753 -178.543944) (xy 229.678425 -178.594441) (xy 229.694493 -178.647848) (xy 229.702613 -178.703024)
			(xy 229.703122 -178.73091) (xy 229.702613 -178.758796) (xy 229.694493 -178.813972) (xy 229.678425 -178.867379)
			(xy 229.654753 -178.917876) (xy 229.62398 -178.964389) (xy 229.586763 -179.005926) (xy 229.543895 -179.041601)
			(xy 229.496289 -179.070655) (xy 229.44496 -179.092467) (xy 229.391003 -179.106573) (xy 229.335566 -179.112673)
			(xy 229.279832 -179.110636) (xy 229.224989 -179.100506) (xy 229.172205 -179.082499) (xy 229.122605 -179.056998)
			(xy 229.077247 -179.024547) (xy 229.037098 -178.985838) (xy 229.003012 -178.941695) (xy 228.975716 -178.89306)
			(xy 228.955793 -178.840969) (xy 228.943667 -178.786532) (xy 228.939596 -178.73091) (xy 227.169242 -178.73091)
			(xy 227.18558 -178.749145) (xy 227.216353 -178.795658) (xy 227.240025 -178.846155) (xy 227.256093 -178.899562)
			(xy 227.264213 -178.954738) (xy 227.264722 -178.982624) (xy 227.264213 -179.01051) (xy 227.256093 -179.065686)
			(xy 227.240025 -179.119093) (xy 227.216353 -179.16959) (xy 227.18558 -179.216103) (xy 227.148363 -179.25764)
			(xy 227.105495 -179.293315) (xy 227.057889 -179.322369) (xy 227.00656 -179.344181) (xy 226.952603 -179.358287)
			(xy 226.897166 -179.364387) (xy 226.841432 -179.36235) (xy 226.786589 -179.35222) (xy 226.733805 -179.334213)
			(xy 226.684205 -179.308712) (xy 226.638847 -179.276261) (xy 226.598698 -179.237552) (xy 226.564612 -179.193409)
			(xy 226.537316 -179.144774) (xy 226.517393 -179.092683) (xy 226.505267 -179.038246) (xy 226.501196 -178.982624)
			(xy 215.146082 -178.982624) (xy 215.164405 -179.011135) (xy 215.187047 -179.060712) (xy 215.202402 -179.113007)
			(xy 215.210158 -179.166955) (xy 215.210644 -179.194206) (xy 215.210112 -179.222944) (xy 215.20149 -179.279771)
			(xy 215.184441 -179.334661) (xy 215.159351 -179.386373) (xy 215.126789 -179.433736) (xy 215.10752 -179.455064)
			(xy 215.100916 -179.461922) (xy 215.093804 -179.479956) (xy 215.093804 -179.568856) (xy 215.100916 -179.58689)
			(xy 215.10752 -179.593748) (xy 215.126787 -179.615079) (xy 215.143908 -179.639976) (xy 217.55049 -179.639976)
			(xy 217.554561 -179.584354) (xy 217.566687 -179.529917) (xy 217.58661 -179.477826) (xy 217.613906 -179.429191)
			(xy 217.647992 -179.385048) (xy 217.688141 -179.346339) (xy 217.733499 -179.313888) (xy 217.783099 -179.288387)
			(xy 217.835883 -179.27038) (xy 217.890726 -179.26025) (xy 217.94646 -179.258213) (xy 218.001897 -179.264313)
			(xy 218.055854 -179.278419) (xy 218.107183 -179.300231) (xy 218.154789 -179.329285) (xy 218.197657 -179.36496)
			(xy 218.234874 -179.406497) (xy 218.265647 -179.45301) (xy 218.289319 -179.503507) (xy 218.304624 -179.554378)
			(xy 242.447824 -179.554378) (xy 242.451895 -179.498756) (xy 242.464021 -179.444319) (xy 242.483944 -179.392228)
			(xy 242.51124 -179.343593) (xy 242.545326 -179.29945) (xy 242.585475 -179.260741) (xy 242.630833 -179.22829)
			(xy 242.680433 -179.202789) (xy 242.733217 -179.184782) (xy 242.78806 -179.174652) (xy 242.843794 -179.172615)
			(xy 242.899231 -179.178715) (xy 242.953188 -179.192821) (xy 243.004517 -179.214633) (xy 243.052123 -179.243687)
			(xy 243.094991 -179.279362) (xy 243.132208 -179.320899) (xy 243.162981 -179.367412) (xy 243.186653 -179.417909)
			(xy 243.202721 -179.471316) (xy 243.210841 -179.526492) (xy 243.21135 -179.554378) (xy 244.924578 -179.554378)
			(xy 244.928649 -179.498756) (xy 244.940775 -179.444319) (xy 244.960698 -179.392228) (xy 244.987994 -179.343593)
			(xy 245.02208 -179.29945) (xy 245.062229 -179.260741) (xy 245.107587 -179.22829) (xy 245.157187 -179.202789)
			(xy 245.209971 -179.184782) (xy 245.264814 -179.174652) (xy 245.320548 -179.172615) (xy 245.375985 -179.178715)
			(xy 245.429942 -179.192821) (xy 245.481271 -179.214633) (xy 245.528877 -179.243687) (xy 245.571745 -179.279362)
			(xy 245.608962 -179.320899) (xy 245.639735 -179.367412) (xy 245.663407 -179.417909) (xy 245.679475 -179.471316)
			(xy 245.687595 -179.526492) (xy 245.688104 -179.554378) (xy 245.687595 -179.582264) (xy 245.679475 -179.63744)
			(xy 245.663407 -179.690847) (xy 245.639735 -179.741344) (xy 245.608962 -179.787857) (xy 245.571745 -179.829394)
			(xy 245.528877 -179.865069) (xy 245.481271 -179.894123) (xy 245.429942 -179.915935) (xy 245.375985 -179.930041)
			(xy 245.320548 -179.936141) (xy 245.264814 -179.934104) (xy 245.209971 -179.923974) (xy 245.157187 -179.905967)
			(xy 245.107587 -179.880466) (xy 245.062229 -179.848015) (xy 245.02208 -179.809306) (xy 244.987994 -179.765163)
			(xy 244.960698 -179.716528) (xy 244.940775 -179.664437) (xy 244.928649 -179.61) (xy 244.924578 -179.554378)
			(xy 243.21135 -179.554378) (xy 243.210841 -179.582264) (xy 243.202721 -179.63744) (xy 243.186653 -179.690847)
			(xy 243.162981 -179.741344) (xy 243.132208 -179.787857) (xy 243.094991 -179.829394) (xy 243.052123 -179.865069)
			(xy 243.004517 -179.894123) (xy 242.953188 -179.915935) (xy 242.899231 -179.930041) (xy 242.843794 -179.936141)
			(xy 242.78806 -179.934104) (xy 242.733217 -179.923974) (xy 242.680433 -179.905967) (xy 242.630833 -179.880466)
			(xy 242.585475 -179.848015) (xy 242.545326 -179.809306) (xy 242.51124 -179.765163) (xy 242.483944 -179.716528)
			(xy 242.464021 -179.664437) (xy 242.451895 -179.61) (xy 242.447824 -179.554378) (xy 218.304624 -179.554378)
			(xy 218.305387 -179.556914) (xy 218.313507 -179.61209) (xy 218.314016 -179.639976) (xy 218.313507 -179.667862)
			(xy 218.305387 -179.723038) (xy 218.289319 -179.776445) (xy 218.265647 -179.826942) (xy 218.234874 -179.873455)
			(xy 218.197657 -179.914992) (xy 218.154789 -179.950667) (xy 218.107183 -179.979721) (xy 218.055854 -180.001533)
			(xy 218.001897 -180.015639) (xy 217.94646 -180.021739) (xy 217.890726 -180.019702) (xy 217.835883 -180.009572)
			(xy 217.783099 -179.991565) (xy 217.733499 -179.966064) (xy 217.688141 -179.933613) (xy 217.647992 -179.894904)
			(xy 217.613906 -179.850761) (xy 217.58661 -179.802126) (xy 217.566687 -179.750035) (xy 217.554561 -179.695598)
			(xy 217.55049 -179.639976) (xy 215.143908 -179.639976) (xy 215.159355 -179.662439) (xy 215.184449 -179.71415)
			(xy 215.2015 -179.76904) (xy 215.210123 -179.825867) (xy 215.210644 -179.854606) (xy 215.210182 -179.881207)
			(xy 215.202806 -179.933894) (xy 215.188183 -179.985045) (xy 215.166598 -180.03367) (xy 215.138468 -180.078826)
			(xy 215.104338 -180.119637) (xy 215.084914 -180.137816) (xy 215.076786 -180.145182) (xy 215.067896 -180.165502)
			(xy 215.070182 -180.264562) (xy 215.079834 -180.284374) (xy 215.08847 -180.291486) (xy 215.109808 -180.309687)
			(xy 215.147418 -180.35129) (xy 215.178527 -180.397954) (xy 215.202463 -180.448673) (xy 215.216544 -180.495194)
			(xy 219.951552 -180.495194) (xy 219.955623 -180.439572) (xy 219.967749 -180.385135) (xy 219.987672 -180.333044)
			(xy 220.014968 -180.284409) (xy 220.049054 -180.240266) (xy 220.089203 -180.201557) (xy 220.134561 -180.169106)
			(xy 220.184161 -180.143605) (xy 220.236945 -180.125598) (xy 220.291788 -180.115468) (xy 220.347522 -180.113431)
			(xy 220.402959 -180.119531) (xy 220.456916 -180.133637) (xy 220.508245 -180.155449) (xy 220.555515 -180.184298)
			(xy 230.427528 -180.184298) (xy 230.431599 -180.128676) (xy 230.443725 -180.074239) (xy 230.463648 -180.022148)
			(xy 230.490944 -179.973513) (xy 230.52503 -179.92937) (xy 230.565179 -179.890661) (xy 230.610537 -179.85821)
			(xy 230.660137 -179.832709) (xy 230.712921 -179.814702) (xy 230.767764 -179.804572) (xy 230.823498 -179.802535)
			(xy 230.878935 -179.808635) (xy 230.932892 -179.822741) (xy 230.984221 -179.844553) (xy 231.031827 -179.873607)
			(xy 231.074695 -179.909282) (xy 231.111912 -179.950819) (xy 231.142685 -179.997332) (xy 231.166357 -180.047829)
			(xy 231.182425 -180.101236) (xy 231.190545 -180.156412) (xy 231.191054 -180.184298) (xy 231.190545 -180.212184)
			(xy 231.182425 -180.26736) (xy 231.166357 -180.320767) (xy 231.142685 -180.371264) (xy 231.111912 -180.417777)
			(xy 231.074695 -180.459314) (xy 231.031827 -180.494989) (xy 230.984221 -180.524043) (xy 230.932892 -180.545855)
			(xy 230.878935 -180.559961) (xy 230.823498 -180.566061) (xy 230.767764 -180.564024) (xy 230.712921 -180.553894)
			(xy 230.660137 -180.535887) (xy 230.610537 -180.510386) (xy 230.565179 -180.477935) (xy 230.52503 -180.439226)
			(xy 230.490944 -180.395083) (xy 230.463648 -180.346448) (xy 230.443725 -180.294357) (xy 230.431599 -180.23992)
			(xy 230.427528 -180.184298) (xy 220.555515 -180.184298) (xy 220.555851 -180.184503) (xy 220.598719 -180.220178)
			(xy 220.635936 -180.261715) (xy 220.666709 -180.308228) (xy 220.690381 -180.358725) (xy 220.706449 -180.412132)
			(xy 220.714569 -180.467308) (xy 220.715078 -180.495194) (xy 220.714569 -180.52308) (xy 220.706449 -180.578256)
			(xy 220.690381 -180.631663) (xy 220.666709 -180.68216) (xy 220.635936 -180.728673) (xy 220.598719 -180.77021)
			(xy 220.577885 -180.787548) (xy 261.208772 -180.787548) (xy 261.212843 -180.731926) (xy 261.224969 -180.677489)
			(xy 261.244892 -180.625398) (xy 261.272188 -180.576763) (xy 261.306274 -180.53262) (xy 261.346423 -180.493911)
			(xy 261.391781 -180.46146) (xy 261.441381 -180.435959) (xy 261.494165 -180.417952) (xy 261.549008 -180.407822)
			(xy 261.604742 -180.405785) (xy 261.660179 -180.411885) (xy 261.714136 -180.425991) (xy 261.765465 -180.447803)
			(xy 261.813071 -180.476857) (xy 261.855939 -180.512532) (xy 261.893156 -180.554069) (xy 261.923929 -180.600582)
			(xy 261.947601 -180.651079) (xy 261.963669 -180.704486) (xy 261.971789 -180.759662) (xy 261.972298 -180.787548)
			(xy 261.971789 -180.815434) (xy 261.963669 -180.87061) (xy 261.947601 -180.924017) (xy 261.923929 -180.974514)
			(xy 261.893156 -181.021027) (xy 261.855939 -181.062564) (xy 261.813071 -181.098239) (xy 261.765465 -181.127293)
			(xy 261.714136 -181.149105) (xy 261.660179 -181.163211) (xy 261.604742 -181.169311) (xy 261.549008 -181.167274)
			(xy 261.494165 -181.157144) (xy 261.441381 -181.139137) (xy 261.391781 -181.113636) (xy 261.346423 -181.081185)
			(xy 261.306274 -181.042476) (xy 261.272188 -180.998333) (xy 261.244892 -180.949698) (xy 261.224969 -180.897607)
			(xy 261.212843 -180.84317) (xy 261.208772 -180.787548) (xy 220.577885 -180.787548) (xy 220.555851 -180.805885)
			(xy 220.508245 -180.834939) (xy 220.456916 -180.856751) (xy 220.402959 -180.870857) (xy 220.347522 -180.876957)
			(xy 220.291788 -180.87492) (xy 220.236945 -180.86479) (xy 220.184161 -180.846783) (xy 220.134561 -180.821282)
			(xy 220.089203 -180.788831) (xy 220.049054 -180.750122) (xy 220.014968 -180.705979) (xy 219.987672 -180.657344)
			(xy 219.967749 -180.605253) (xy 219.955623 -180.550816) (xy 219.951552 -180.495194) (xy 215.216544 -180.495194)
			(xy 215.21871 -180.502351) (xy 215.226916 -180.55783) (xy 215.227408 -180.585872) (xy 215.227408 -180.586126)
			(xy 215.226922 -180.613377) (xy 215.219166 -180.667325) (xy 215.203811 -180.71962) (xy 215.181169 -180.769197)
			(xy 215.151703 -180.815047) (xy 215.116012 -180.856238) (xy 215.074821 -180.891929) (xy 215.028971 -180.921395)
			(xy 214.979394 -180.944037) (xy 214.927099 -180.959392) (xy 214.873151 -180.967148) (xy 214.818649 -180.967148)
			(xy 214.764701 -180.959392) (xy 214.712406 -180.944037) (xy 214.662829 -180.921395) (xy 214.616979 -180.891929)
			(xy 214.575788 -180.856238) (xy 214.540097 -180.815047) (xy 214.510631 -180.769197) (xy 214.487989 -180.71962)
			(xy 214.472634 -180.667325) (xy 214.464878 -180.613377) (xy 214.464392 -180.586126) (xy 214.464863 -180.559526)
			(xy 214.472236 -180.506839) (xy 214.486856 -180.455687) (xy 214.50844 -180.407061) (xy 214.536569 -180.361906)
			(xy 214.570698 -180.321095) (xy 214.590122 -180.302916) (xy 214.59825 -180.29555) (xy 214.60714 -180.27523)
			(xy 214.604854 -180.17617) (xy 214.595202 -180.156358) (xy 214.586566 -180.149246) (xy 214.565251 -180.131019)
			(xy 214.527638 -180.089423) (xy 214.496525 -180.042764) (xy 214.472584 -179.992051) (xy 214.456333 -179.938376)
			(xy 214.448122 -179.8829) (xy 214.447628 -179.85486) (xy 191.329753 -179.85486) (xy 191.215285 -180.477668)
			(xy 208.830162 -180.477668) (xy 208.834233 -180.422046) (xy 208.846359 -180.367609) (xy 208.866282 -180.315518)
			(xy 208.893578 -180.266883) (xy 208.927664 -180.22274) (xy 208.967813 -180.184031) (xy 209.013171 -180.15158)
			(xy 209.062771 -180.126079) (xy 209.115555 -180.108072) (xy 209.170398 -180.097942) (xy 209.226132 -180.095905)
			(xy 209.281569 -180.102005) (xy 209.335526 -180.116111) (xy 209.386855 -180.137923) (xy 209.434461 -180.166977)
			(xy 209.477329 -180.202652) (xy 209.513683 -180.243226) (xy 211.981794 -180.243226) (xy 211.985865 -180.187604)
			(xy 211.997991 -180.133167) (xy 212.017914 -180.081076) (xy 212.04521 -180.032441) (xy 212.079296 -179.988298)
			(xy 212.119445 -179.949589) (xy 212.164803 -179.917138) (xy 212.214403 -179.891637) (xy 212.267187 -179.87363)
			(xy 212.32203 -179.8635) (xy 212.377764 -179.861463) (xy 212.433201 -179.867563) (xy 212.487158 -179.881669)
			(xy 212.538487 -179.903481) (xy 212.586093 -179.932535) (xy 212.628961 -179.96821) (xy 212.666178 -180.009747)
			(xy 212.696951 -180.05626) (xy 212.720623 -180.106757) (xy 212.736691 -180.160164) (xy 212.744811 -180.21534)
			(xy 212.74532 -180.243226) (xy 212.744811 -180.271112) (xy 212.736691 -180.326288) (xy 212.720623 -180.379695)
			(xy 212.696951 -180.430192) (xy 212.666178 -180.476705) (xy 212.628961 -180.518242) (xy 212.586093 -180.553917)
			(xy 212.538487 -180.582971) (xy 212.487158 -180.604783) (xy 212.433201 -180.618889) (xy 212.377764 -180.624989)
			(xy 212.32203 -180.622952) (xy 212.267187 -180.612822) (xy 212.214403 -180.594815) (xy 212.164803 -180.569314)
			(xy 212.119445 -180.536863) (xy 212.079296 -180.498154) (xy 212.04521 -180.454011) (xy 212.017914 -180.405376)
			(xy 211.997991 -180.353285) (xy 211.985865 -180.298848) (xy 211.981794 -180.243226) (xy 209.513683 -180.243226)
			(xy 209.514546 -180.244189) (xy 209.545319 -180.290702) (xy 209.568991 -180.341199) (xy 209.585059 -180.394606)
			(xy 209.593179 -180.449782) (xy 209.593688 -180.477668) (xy 209.593179 -180.505554) (xy 209.585059 -180.56073)
			(xy 209.568991 -180.614137) (xy 209.545319 -180.664634) (xy 209.514546 -180.711147) (xy 209.477329 -180.752684)
			(xy 209.434461 -180.788359) (xy 209.386855 -180.817413) (xy 209.335526 -180.839225) (xy 209.281569 -180.853331)
			(xy 209.226132 -180.859431) (xy 209.170398 -180.857394) (xy 209.115555 -180.847264) (xy 209.062771 -180.829257)
			(xy 209.013171 -180.803756) (xy 208.967813 -180.771305) (xy 208.927664 -180.732596) (xy 208.893578 -180.688453)
			(xy 208.866282 -180.639818) (xy 208.846359 -180.587727) (xy 208.834233 -180.53329) (xy 208.830162 -180.477668)
			(xy 191.215285 -180.477668) (xy 191.065757 -181.29123) (xy 211.95868 -181.29123) (xy 211.962751 -181.235608)
			(xy 211.974877 -181.181171) (xy 211.9948 -181.12908) (xy 212.022096 -181.080445) (xy 212.056182 -181.036302)
			(xy 212.096331 -180.997593) (xy 212.141689 -180.965142) (xy 212.191289 -180.939641) (xy 212.244073 -180.921634)
			(xy 212.298916 -180.911504) (xy 212.35465 -180.909467) (xy 212.410087 -180.915567) (xy 212.464044 -180.929673)
			(xy 212.515373 -180.951485) (xy 212.562979 -180.980539) (xy 212.605847 -181.016214) (xy 212.643064 -181.057751)
			(xy 212.673837 -181.104264) (xy 212.697509 -181.154761) (xy 212.713577 -181.208168) (xy 212.721697 -181.263344)
			(xy 212.722206 -181.29123) (xy 212.721697 -181.319116) (xy 212.713577 -181.374292) (xy 212.703491 -181.407816)
			(xy 231.58272 -181.407816) (xy 231.586791 -181.352194) (xy 231.598917 -181.297757) (xy 231.61884 -181.245666)
			(xy 231.646136 -181.197031) (xy 231.680222 -181.152888) (xy 231.720371 -181.114179) (xy 231.765729 -181.081728)
			(xy 231.815329 -181.056227) (xy 231.868113 -181.03822) (xy 231.922956 -181.02809) (xy 231.97869 -181.026053)
			(xy 232.034127 -181.032153) (xy 232.088084 -181.046259) (xy 232.139413 -181.068071) (xy 232.187019 -181.097125)
			(xy 232.229887 -181.1328) (xy 232.267104 -181.174337) (xy 232.297877 -181.22085) (xy 232.321549 -181.271347)
			(xy 232.337617 -181.324754) (xy 232.345737 -181.37993) (xy 232.346246 -181.407816) (xy 232.345737 -181.435702)
			(xy 232.337617 -181.490878) (xy 232.321549 -181.544285) (xy 232.297877 -181.594782) (xy 232.267104 -181.641295)
			(xy 232.229887 -181.682832) (xy 232.199592 -181.708044) (xy 233.567476 -181.708044) (xy 233.571547 -181.652422)
			(xy 233.583673 -181.597985) (xy 233.603596 -181.545894) (xy 233.630892 -181.497259) (xy 233.664978 -181.453116)
			(xy 233.705127 -181.414407) (xy 233.750485 -181.381956) (xy 233.800085 -181.356455) (xy 233.852869 -181.338448)
			(xy 233.907712 -181.328318) (xy 233.963446 -181.326281) (xy 234.018883 -181.332381) (xy 234.07284 -181.346487)
			(xy 234.124169 -181.368299) (xy 234.171775 -181.397353) (xy 234.214643 -181.433028) (xy 234.25186 -181.474565)
			(xy 234.282633 -181.521078) (xy 234.306305 -181.571575) (xy 234.322373 -181.624982) (xy 234.330493 -181.680158)
			(xy 234.331002 -181.708044) (xy 234.330493 -181.73593) (xy 234.322373 -181.791106) (xy 234.306305 -181.844513)
			(xy 234.282633 -181.89501) (xy 234.25186 -181.941523) (xy 234.214643 -181.98306) (xy 234.171775 -182.018735)
			(xy 234.124169 -182.047789) (xy 234.07284 -182.069601) (xy 234.018883 -182.083707) (xy 233.963446 -182.089807)
			(xy 233.907712 -182.08777) (xy 233.852869 -182.07764) (xy 233.800085 -182.059633) (xy 233.750485 -182.034132)
			(xy 233.705127 -182.001681) (xy 233.664978 -181.962972) (xy 233.630892 -181.918829) (xy 233.603596 -181.870194)
			(xy 233.583673 -181.818103) (xy 233.571547 -181.763666) (xy 233.567476 -181.708044) (xy 232.199592 -181.708044)
			(xy 232.187019 -181.718507) (xy 232.139413 -181.747561) (xy 232.088084 -181.769373) (xy 232.034127 -181.783479)
			(xy 231.97869 -181.789579) (xy 231.922956 -181.787542) (xy 231.868113 -181.777412) (xy 231.815329 -181.759405)
			(xy 231.765729 -181.733904) (xy 231.720371 -181.701453) (xy 231.680222 -181.662744) (xy 231.646136 -181.618601)
			(xy 231.61884 -181.569966) (xy 231.598917 -181.517875) (xy 231.586791 -181.463438) (xy 231.58272 -181.407816)
			(xy 212.703491 -181.407816) (xy 212.697509 -181.427699) (xy 212.673837 -181.478196) (xy 212.643064 -181.524709)
			(xy 212.605847 -181.566246) (xy 212.562979 -181.601921) (xy 212.515373 -181.630975) (xy 212.464044 -181.652787)
			(xy 212.410087 -181.666893) (xy 212.35465 -181.672993) (xy 212.298916 -181.670956) (xy 212.244073 -181.660826)
			(xy 212.191289 -181.642819) (xy 212.141689 -181.617318) (xy 212.096331 -181.584867) (xy 212.056182 -181.546158)
			(xy 212.022096 -181.502015) (xy 211.9948 -181.45338) (xy 211.974877 -181.401289) (xy 211.962751 -181.346852)
			(xy 211.95868 -181.29123) (xy 191.065757 -181.29123) (xy 190.932989 -182.013606) (xy 210.383118 -182.013606)
			(xy 210.387189 -181.957984) (xy 210.399315 -181.903547) (xy 210.419238 -181.851456) (xy 210.446534 -181.802821)
			(xy 210.48062 -181.758678) (xy 210.520769 -181.719969) (xy 210.566127 -181.687518) (xy 210.615727 -181.662017)
			(xy 210.668511 -181.64401) (xy 210.723354 -181.63388) (xy 210.779088 -181.631843) (xy 210.834525 -181.637943)
			(xy 210.888482 -181.652049) (xy 210.939811 -181.673861) (xy 210.987417 -181.702915) (xy 211.030285 -181.73859)
			(xy 211.067502 -181.780127) (xy 211.098275 -181.82664) (xy 211.121947 -181.877137) (xy 211.138015 -181.930544)
			(xy 211.146135 -181.98572) (xy 211.146644 -182.013606) (xy 214.447118 -182.013606) (xy 214.451189 -181.957984)
			(xy 214.463315 -181.903547) (xy 214.483238 -181.851456) (xy 214.510534 -181.802821) (xy 214.54462 -181.758678)
			(xy 214.584769 -181.719969) (xy 214.630127 -181.687518) (xy 214.679727 -181.662017) (xy 214.732511 -181.64401)
			(xy 214.787354 -181.63388) (xy 214.843088 -181.631843) (xy 214.898525 -181.637943) (xy 214.952482 -181.652049)
			(xy 215.003811 -181.673861) (xy 215.051417 -181.702915) (xy 215.094285 -181.73859) (xy 215.131502 -181.780127)
			(xy 215.162275 -181.82664) (xy 215.176217 -181.85638) (xy 224.874326 -181.85638) (xy 224.878397 -181.800758)
			(xy 224.890523 -181.746321) (xy 224.910446 -181.69423) (xy 224.937742 -181.645595) (xy 224.971828 -181.601452)
			(xy 225.011977 -181.562743) (xy 225.057335 -181.530292) (xy 225.106935 -181.504791) (xy 225.159719 -181.486784)
			(xy 225.214562 -181.476654) (xy 225.270296 -181.474617) (xy 225.325733 -181.480717) (xy 225.37969 -181.494823)
			(xy 225.431019 -181.516635) (xy 225.478625 -181.545689) (xy 225.521493 -181.581364) (xy 225.55871 -181.622901)
			(xy 225.589483 -181.669414) (xy 225.613155 -181.719911) (xy 225.629223 -181.773318) (xy 225.637343 -181.828494)
			(xy 225.637852 -181.85638) (xy 225.637343 -181.884266) (xy 225.629223 -181.939442) (xy 225.613155 -181.992849)
			(xy 225.589483 -182.043346) (xy 225.55871 -182.089859) (xy 225.521493 -182.131396) (xy 225.478625 -182.167071)
			(xy 225.431019 -182.196125) (xy 225.37969 -182.217937) (xy 225.325733 -182.232043) (xy 225.270296 -182.238143)
			(xy 225.214562 -182.236106) (xy 225.159719 -182.225976) (xy 225.106935 -182.207969) (xy 225.057335 -182.182468)
			(xy 225.011977 -182.150017) (xy 224.971828 -182.111308) (xy 224.937742 -182.067165) (xy 224.910446 -182.01853)
			(xy 224.890523 -181.966439) (xy 224.878397 -181.912002) (xy 224.874326 -181.85638) (xy 215.176217 -181.85638)
			(xy 215.185947 -181.877137) (xy 215.202015 -181.930544) (xy 215.210135 -181.98572) (xy 215.210644 -182.013606)
			(xy 215.210135 -182.041492) (xy 215.202015 -182.096668) (xy 215.185947 -182.150075) (xy 215.162275 -182.200572)
			(xy 215.131502 -182.247085) (xy 215.101281 -182.280814) (xy 250.214382 -182.280814) (xy 250.218453 -182.225192)
			(xy 250.230579 -182.170755) (xy 250.250502 -182.118664) (xy 250.277798 -182.070029) (xy 250.311884 -182.025886)
			(xy 250.352033 -181.987177) (xy 250.397391 -181.954726) (xy 250.446991 -181.929225) (xy 250.499775 -181.911218)
			(xy 250.554618 -181.901088) (xy 250.610352 -181.899051) (xy 250.665789 -181.905151) (xy 250.719746 -181.919257)
			(xy 250.771075 -181.941069) (xy 250.818681 -181.970123) (xy 250.861549 -182.005798) (xy 250.898766 -182.047335)
			(xy 250.929539 -182.093848) (xy 250.953211 -182.144345) (xy 250.969279 -182.197752) (xy 250.977399 -182.252928)
			(xy 250.977908 -182.280814) (xy 250.977399 -182.3087) (xy 250.969279 -182.363876) (xy 250.953211 -182.417283)
			(xy 250.929539 -182.46778) (xy 250.898766 -182.514293) (xy 250.861549 -182.55583) (xy 250.818681 -182.591505)
			(xy 250.771075 -182.620559) (xy 250.719746 -182.642371) (xy 250.665789 -182.656477) (xy 250.610352 -182.662577)
			(xy 250.554618 -182.66054) (xy 250.499775 -182.65041) (xy 250.446991 -182.632403) (xy 250.397391 -182.606902)
			(xy 250.352033 -182.574451) (xy 250.311884 -182.535742) (xy 250.277798 -182.491599) (xy 250.250502 -182.442964)
			(xy 250.230579 -182.390873) (xy 250.218453 -182.336436) (xy 250.214382 -182.280814) (xy 215.101281 -182.280814)
			(xy 215.094285 -182.288622) (xy 215.051417 -182.324297) (xy 215.003811 -182.353351) (xy 214.952482 -182.375163)
			(xy 214.898525 -182.389269) (xy 214.843088 -182.395369) (xy 214.787354 -182.393332) (xy 214.732511 -182.383202)
			(xy 214.679727 -182.365195) (xy 214.630127 -182.339694) (xy 214.584769 -182.307243) (xy 214.54462 -182.268534)
			(xy 214.510534 -182.224391) (xy 214.483238 -182.175756) (xy 214.463315 -182.123665) (xy 214.451189 -182.069228)
			(xy 214.447118 -182.013606) (xy 211.146644 -182.013606) (xy 211.146135 -182.041492) (xy 211.138015 -182.096668)
			(xy 211.121947 -182.150075) (xy 211.098275 -182.200572) (xy 211.067502 -182.247085) (xy 211.030285 -182.288622)
			(xy 210.987417 -182.324297) (xy 210.939811 -182.353351) (xy 210.888482 -182.375163) (xy 210.834525 -182.389269)
			(xy 210.779088 -182.395369) (xy 210.723354 -182.393332) (xy 210.668511 -182.383202) (xy 210.615727 -182.365195)
			(xy 210.566127 -182.339694) (xy 210.520769 -182.307243) (xy 210.48062 -182.268534) (xy 210.446534 -182.224391)
			(xy 210.419238 -182.175756) (xy 210.399315 -182.123665) (xy 210.387189 -182.069228) (xy 210.383118 -182.013606)
			(xy 190.932989 -182.013606) (xy 190.803115 -182.720234) (xy 236.847378 -182.720234) (xy 236.851449 -182.664612)
			(xy 236.863575 -182.610175) (xy 236.883498 -182.558084) (xy 236.910794 -182.509449) (xy 236.94488 -182.465306)
			(xy 236.985029 -182.426597) (xy 237.030387 -182.394146) (xy 237.079987 -182.368645) (xy 237.132771 -182.350638)
			(xy 237.187614 -182.340508) (xy 237.243348 -182.338471) (xy 237.298785 -182.344571) (xy 237.352742 -182.358677)
			(xy 237.404071 -182.380489) (xy 237.451677 -182.409543) (xy 237.494545 -182.445218) (xy 237.531762 -182.486755)
			(xy 237.562535 -182.533268) (xy 237.586207 -182.583765) (xy 237.602275 -182.637172) (xy 237.610395 -182.692348)
			(xy 237.610904 -182.720234) (xy 237.610395 -182.74812) (xy 237.602275 -182.803296) (xy 237.596851 -182.821326)
			(xy 260.454646 -182.821326) (xy 260.458717 -182.765704) (xy 260.470843 -182.711267) (xy 260.490766 -182.659176)
			(xy 260.518062 -182.610541) (xy 260.552148 -182.566398) (xy 260.592297 -182.527689) (xy 260.637655 -182.495238)
			(xy 260.687255 -182.469737) (xy 260.740039 -182.45173) (xy 260.794882 -182.4416) (xy 260.850616 -182.439563)
			(xy 260.906053 -182.445663) (xy 260.96001 -182.459769) (xy 261.011339 -182.481581) (xy 261.058945 -182.510635)
			(xy 261.101813 -182.54631) (xy 261.13903 -182.587847) (xy 261.169803 -182.63436) (xy 261.193475 -182.684857)
			(xy 261.209543 -182.738264) (xy 261.217663 -182.79344) (xy 261.218172 -182.821326) (xy 261.217663 -182.849212)
			(xy 261.209543 -182.904388) (xy 261.193475 -182.957795) (xy 261.169803 -183.008292) (xy 261.13903 -183.054805)
			(xy 261.101813 -183.096342) (xy 261.058945 -183.132017) (xy 261.011339 -183.161071) (xy 260.96001 -183.182883)
			(xy 260.906053 -183.196989) (xy 260.850616 -183.203089) (xy 260.794882 -183.201052) (xy 260.740039 -183.190922)
			(xy 260.687255 -183.172915) (xy 260.637655 -183.147414) (xy 260.592297 -183.114963) (xy 260.552148 -183.076254)
			(xy 260.518062 -183.032111) (xy 260.490766 -182.983476) (xy 260.470843 -182.931385) (xy 260.458717 -182.876948)
			(xy 260.454646 -182.821326) (xy 237.596851 -182.821326) (xy 237.586207 -182.856703) (xy 237.562535 -182.9072)
			(xy 237.531762 -182.953713) (xy 237.494545 -182.99525) (xy 237.451677 -183.030925) (xy 237.404071 -183.059979)
			(xy 237.352742 -183.081791) (xy 237.298785 -183.095897) (xy 237.243348 -183.101997) (xy 237.187614 -183.09996)
			(xy 237.132771 -183.08983) (xy 237.079987 -183.071823) (xy 237.030387 -183.046322) (xy 236.985029 -183.013871)
			(xy 236.94488 -182.975162) (xy 236.910794 -182.931019) (xy 236.883498 -182.882384) (xy 236.863575 -182.830293)
			(xy 236.851449 -182.775856) (xy 236.847378 -182.720234) (xy 190.803115 -182.720234) (xy 190.580294 -183.932576)
			(xy 207.46796 -183.932576) (xy 207.472031 -183.876954) (xy 207.484157 -183.822517) (xy 207.50408 -183.770426)
			(xy 207.531376 -183.721791) (xy 207.565462 -183.677648) (xy 207.605611 -183.638939) (xy 207.650969 -183.606488)
			(xy 207.700569 -183.580987) (xy 207.753353 -183.56298) (xy 207.808196 -183.55285) (xy 207.86393 -183.550813)
			(xy 207.919367 -183.556913) (xy 207.924213 -183.55818) (xy 217.546426 -183.55818) (xy 217.550497 -183.502558)
			(xy 217.562623 -183.448121) (xy 217.582546 -183.39603) (xy 217.609842 -183.347395) (xy 217.643928 -183.303252)
			(xy 217.684077 -183.264543) (xy 217.729435 -183.232092) (xy 217.779035 -183.206591) (xy 217.831819 -183.188584)
			(xy 217.886662 -183.178454) (xy 217.942396 -183.176417) (xy 217.997833 -183.182517) (xy 218.05179 -183.196623)
			(xy 218.103119 -183.218435) (xy 218.150725 -183.247489) (xy 218.193593 -183.283164) (xy 218.23081 -183.324701)
			(xy 218.261583 -183.371214) (xy 218.276596 -183.40324) (xy 225.557332 -183.40324) (xy 225.561403 -183.347618)
			(xy 225.573529 -183.293181) (xy 225.593452 -183.24109) (xy 225.620748 -183.192455) (xy 225.654834 -183.148312)
			(xy 225.694983 -183.109603) (xy 225.740341 -183.077152) (xy 225.789941 -183.051651) (xy 225.842725 -183.033644)
			(xy 225.897568 -183.023514) (xy 225.953302 -183.021477) (xy 226.008739 -183.027577) (xy 226.062696 -183.041683)
			(xy 226.114025 -183.063495) (xy 226.161631 -183.092549) (xy 226.204499 -183.128224) (xy 226.241716 -183.169761)
			(xy 226.272489 -183.216274) (xy 226.296161 -183.266771) (xy 226.30798 -183.306056) (xy 230.971235 -183.306056)
			(xy 230.971235 -183.251544) (xy 230.978994 -183.197586) (xy 230.994353 -183.145282) (xy 231.017 -183.095696)
			(xy 231.046473 -183.049838) (xy 231.082174 -183.008642) (xy 231.123374 -182.972947) (xy 231.169235 -182.943478)
			(xy 231.218823 -182.920837) (xy 231.271129 -182.905484) (xy 231.325088 -182.897732) (xy 231.352344 -182.897272)
			(xy 231.378761 -182.897761) (xy 231.43109 -182.905044) (xy 231.481913 -182.919478) (xy 231.530259 -182.940788)
			(xy 231.575201 -182.968565) (xy 231.61588 -183.002278) (xy 231.63403 -183.021478) (xy 231.643343 -183.031183)
			(xy 231.666024 -183.045634) (xy 231.691691 -183.053665) (xy 231.718563 -183.05472) (xy 231.74478 -183.048726)
			(xy 231.768525 -183.036098) (xy 231.788151 -183.017711) (xy 231.795574 -183.006492) (xy 231.810627 -182.983228)
			(xy 231.846314 -182.940843) (xy 231.887756 -182.904065) (xy 231.934082 -182.873667) (xy 231.984316 -182.850289)
			(xy 232.037404 -182.834421) (xy 232.092228 -182.826398) (xy 232.119932 -182.825898) (xy 232.147182 -182.826374)
			(xy 232.201127 -182.834134) (xy 232.253419 -182.849492) (xy 232.302993 -182.872136) (xy 232.34884 -182.901603)
			(xy 232.390027 -182.937295) (xy 232.425716 -182.978486) (xy 232.45518 -183.024335) (xy 232.477819 -183.073911)
			(xy 232.493172 -183.126204) (xy 232.500928 -183.18015) (xy 232.500928 -183.23465) (xy 232.493172 -183.288596)
			(xy 232.477819 -183.340889) (xy 232.45518 -183.390465) (xy 232.425716 -183.436314) (xy 232.390027 -183.477505)
			(xy 232.34884 -183.513197) (xy 232.302993 -183.542664) (xy 232.253419 -183.565308) (xy 232.201127 -183.580666)
			(xy 232.147182 -183.588426) (xy 232.119932 -183.588914) (xy 232.093514 -183.588446) (xy 232.041184 -183.581159)
			(xy 231.99036 -183.566721) (xy 231.942015 -183.545407) (xy 231.897073 -183.517626) (xy 231.856395 -183.483909)
			(xy 231.838246 -183.464708) (xy 231.828866 -183.455069) (xy 231.806205 -183.440601) (xy 231.780552 -183.432554)
			(xy 231.753688 -183.431486) (xy 231.727477 -183.43747) (xy 231.703738 -183.450092) (xy 231.68412 -183.468476)
			(xy 231.676702 -183.479694) (xy 231.661695 -183.502989) (xy 231.625997 -183.545369) (xy 231.584545 -183.582142)
			(xy 231.538212 -183.612535) (xy 231.487971 -183.635908) (xy 231.434878 -183.651771) (xy 231.38005 -183.65979)
			(xy 231.352344 -183.660288) (xy 231.325088 -183.659868) (xy 231.271129 -183.652116) (xy 231.218823 -183.636763)
			(xy 231.169235 -183.614122) (xy 231.123374 -183.584653) (xy 231.082174 -183.548958) (xy 231.046473 -183.507762)
			(xy 231.017 -183.461904) (xy 230.994353 -183.412318) (xy 230.978994 -183.360014) (xy 230.971235 -183.306056)
			(xy 226.30798 -183.306056) (xy 226.312229 -183.320178) (xy 226.320349 -183.375354) (xy 226.320858 -183.40324)
			(xy 226.320349 -183.431126) (xy 226.312229 -183.486302) (xy 226.296161 -183.539709) (xy 226.272489 -183.590206)
			(xy 226.241716 -183.636719) (xy 226.204499 -183.678256) (xy 226.161631 -183.713931) (xy 226.114025 -183.742985)
			(xy 226.062696 -183.764797) (xy 226.008739 -183.778903) (xy 225.953302 -183.785003) (xy 225.897568 -183.782966)
			(xy 225.842725 -183.772836) (xy 225.789941 -183.754829) (xy 225.740341 -183.729328) (xy 225.694983 -183.696877)
			(xy 225.654834 -183.658168) (xy 225.620748 -183.614025) (xy 225.593452 -183.56539) (xy 225.573529 -183.513299)
			(xy 225.561403 -183.458862) (xy 225.557332 -183.40324) (xy 218.276596 -183.40324) (xy 218.285255 -183.421711)
			(xy 218.301323 -183.475118) (xy 218.309443 -183.530294) (xy 218.309952 -183.55818) (xy 218.309443 -183.586066)
			(xy 218.301323 -183.641242) (xy 218.285255 -183.694649) (xy 218.261583 -183.745146) (xy 218.23081 -183.791659)
			(xy 218.193593 -183.833196) (xy 218.180084 -183.844438) (xy 235.066076 -183.844438) (xy 235.070147 -183.788816)
			(xy 235.082273 -183.734379) (xy 235.102196 -183.682288) (xy 235.129492 -183.633653) (xy 235.163578 -183.58951)
			(xy 235.203727 -183.550801) (xy 235.249085 -183.51835) (xy 235.298685 -183.492849) (xy 235.351469 -183.474842)
			(xy 235.406312 -183.464712) (xy 235.462046 -183.462675) (xy 235.517483 -183.468775) (xy 235.57144 -183.482881)
			(xy 235.622769 -183.504693) (xy 235.670375 -183.533747) (xy 235.713243 -183.569422) (xy 235.75046 -183.610959)
			(xy 235.781233 -183.657472) (xy 235.804905 -183.707969) (xy 235.820973 -183.761376) (xy 235.829093 -183.816552)
			(xy 235.829602 -183.844438) (xy 235.829093 -183.872324) (xy 235.820973 -183.9275) (xy 235.804905 -183.980907)
			(xy 235.781233 -184.031404) (xy 235.75046 -184.077917) (xy 235.713243 -184.119454) (xy 235.670375 -184.155129)
			(xy 235.622769 -184.184183) (xy 235.57144 -184.205995) (xy 235.517483 -184.220101) (xy 235.462046 -184.226201)
			(xy 235.406312 -184.224164) (xy 235.351469 -184.214034) (xy 235.298685 -184.196027) (xy 235.249085 -184.170526)
			(xy 235.203727 -184.138075) (xy 235.163578 -184.099366) (xy 235.129492 -184.055223) (xy 235.102196 -184.006588)
			(xy 235.082273 -183.954497) (xy 235.070147 -183.90006) (xy 235.066076 -183.844438) (xy 218.180084 -183.844438)
			(xy 218.150725 -183.868871) (xy 218.103119 -183.897925) (xy 218.05179 -183.919737) (xy 217.997833 -183.933843)
			(xy 217.942396 -183.939943) (xy 217.886662 -183.937906) (xy 217.831819 -183.927776) (xy 217.779035 -183.909769)
			(xy 217.729435 -183.884268) (xy 217.684077 -183.851817) (xy 217.643928 -183.813108) (xy 217.609842 -183.768965)
			(xy 217.582546 -183.72033) (xy 217.562623 -183.668239) (xy 217.550497 -183.613802) (xy 217.546426 -183.55818)
			(xy 207.924213 -183.55818) (xy 207.973324 -183.571019) (xy 208.024653 -183.592831) (xy 208.072259 -183.621885)
			(xy 208.115127 -183.65756) (xy 208.152344 -183.699097) (xy 208.183117 -183.74561) (xy 208.206789 -183.796107)
			(xy 208.222857 -183.849514) (xy 208.230977 -183.90469) (xy 208.231486 -183.932576) (xy 208.230977 -183.960462)
			(xy 208.222857 -184.015638) (xy 208.206789 -184.069045) (xy 208.183117 -184.119542) (xy 208.152344 -184.166055)
			(xy 208.115127 -184.207592) (xy 208.072259 -184.243267) (xy 208.024653 -184.272321) (xy 207.973324 -184.294133)
			(xy 207.919367 -184.308239) (xy 207.86393 -184.314339) (xy 207.808196 -184.312302) (xy 207.753353 -184.302172)
			(xy 207.700569 -184.284165) (xy 207.650969 -184.258664) (xy 207.605611 -184.226213) (xy 207.565462 -184.187504)
			(xy 207.531376 -184.143361) (xy 207.50408 -184.094726) (xy 207.484157 -184.042635) (xy 207.472031 -183.988198)
			(xy 207.46796 -183.932576) (xy 190.580294 -183.932576) (xy 190.435413 -184.720857) (xy 208.300715 -184.720857)
			(xy 208.300715 -184.666343) (xy 208.308474 -184.612384) (xy 208.323833 -184.560078) (xy 208.34648 -184.510491)
			(xy 208.375953 -184.464632) (xy 208.411654 -184.423434) (xy 208.452854 -184.387736) (xy 208.498716 -184.358266)
			(xy 208.548305 -184.335623) (xy 208.600611 -184.320268) (xy 208.654571 -184.312513) (xy 208.681828 -184.312052)
			(xy 208.709343 -184.312556) (xy 208.763802 -184.320465) (xy 208.816561 -184.336113) (xy 208.866525 -184.359177)
			(xy 208.889854 -184.373774) (xy 208.899506 -184.37987) (xy 208.921858 -184.382918) (xy 209.018886 -184.352184)
			(xy 209.035396 -184.33669) (xy 209.039714 -184.326022) (xy 209.050628 -184.29972) (xy 209.079229 -184.250476)
			(xy 209.114833 -184.206033) (xy 209.15665 -184.167377) (xy 209.203748 -184.135367) (xy 209.255083 -184.110716)
			(xy 209.309511 -184.093971) (xy 209.365825 -184.085504) (xy 209.394298 -184.084976) (xy 209.42155 -184.085471)
			(xy 209.475499 -184.093228) (xy 209.527795 -184.108583) (xy 209.577373 -184.131224) (xy 209.623224 -184.160691)
			(xy 209.664415 -184.196383) (xy 209.698176 -184.235344) (xy 242.889784 -184.235344) (xy 242.893855 -184.179722)
			(xy 242.905981 -184.125285) (xy 242.925904 -184.073194) (xy 242.9532 -184.024559) (xy 242.987286 -183.980416)
			(xy 243.027435 -183.941707) (xy 243.072793 -183.909256) (xy 243.122393 -183.883755) (xy 243.175177 -183.865748)
			(xy 243.23002 -183.855618) (xy 243.285754 -183.853581) (xy 243.341191 -183.859681) (xy 243.395148 -183.873787)
			(xy 243.446477 -183.895599) (xy 243.494083 -183.924653) (xy 243.536951 -183.960328) (xy 243.574168 -184.001865)
			(xy 243.604941 -184.048378) (xy 243.628613 -184.098875) (xy 243.644681 -184.152282) (xy 243.646476 -184.164478)
			(xy 244.441218 -184.164478) (xy 244.441719 -184.136325) (xy 244.449971 -184.080627) (xy 244.466324 -184.026748)
			(xy 244.490421 -183.975859) (xy 244.521738 -183.929066) (xy 244.559595 -183.887386) (xy 244.603169 -183.851725)
			(xy 244.651512 -183.822859) (xy 244.703575 -183.801414) (xy 244.730778 -183.794146) (xy 244.74381 -183.790438)
			(xy 244.767417 -183.777159) (xy 244.786701 -183.75814) (xy 244.800306 -183.734719) (xy 244.807273 -183.708545)
			(xy 244.807113 -183.681461) (xy 244.799837 -183.655371) (xy 244.793262 -183.643524) (xy 244.780436 -183.621266)
			(xy 244.760219 -183.574041) (xy 244.746523 -183.52453) (xy 244.739596 -183.473629) (xy 244.73916 -183.447944)
			(xy 244.73916 -183.447436) (xy 244.739646 -183.420185) (xy 244.747402 -183.366237) (xy 244.762757 -183.313942)
			(xy 244.785399 -183.264365) (xy 244.814865 -183.218515) (xy 244.850556 -183.177324) (xy 244.891747 -183.141633)
			(xy 244.937597 -183.112167) (xy 244.987174 -183.089525) (xy 245.039469 -183.07417) (xy 245.093417 -183.066414)
			(xy 245.147919 -183.066414) (xy 245.201867 -183.07417) (xy 245.254162 -183.089525) (xy 245.303739 -183.112167)
			(xy 245.349589 -183.141633) (xy 245.39078 -183.177324) (xy 245.426471 -183.218515) (xy 245.455937 -183.264365)
			(xy 245.478579 -183.313942) (xy 245.493934 -183.366237) (xy 245.50169 -183.420185) (xy 245.502176 -183.447436)
			(xy 245.501692 -183.47559) (xy 245.494303 -183.525451) (xy 245.640591 -183.525451) (xy 245.640591 -183.470949)
			(xy 245.648348 -183.417003) (xy 245.663703 -183.36471) (xy 245.686343 -183.315134) (xy 245.715809 -183.269285)
			(xy 245.7515 -183.228096) (xy 245.79269 -183.192406) (xy 245.838539 -183.16294) (xy 245.888115 -183.1403)
			(xy 245.940409 -183.124946) (xy 245.994355 -183.117191) (xy 246.021606 -183.116728) (xy 246.047005 -183.117125)
			(xy 246.097355 -183.123868) (xy 246.146364 -183.137233) (xy 246.193166 -183.156984) (xy 246.236933 -183.182771)
			(xy 246.27689 -183.214139) (xy 246.29491 -183.232044) (xy 246.30126 -183.238648) (xy 246.318024 -183.246522)
			(xy 246.403114 -183.25338) (xy 246.42064 -183.248554) (xy 246.428006 -183.242966) (xy 246.452759 -183.225404)
			(xy 246.506672 -183.197538) (xy 246.564312 -183.178543) (xy 246.62423 -183.168899) (xy 246.654574 -183.16829)
			(xy 246.681863 -183.168741) (xy 246.735885 -183.176517) (xy 246.788246 -183.191913) (xy 246.837879 -183.214616)
			(xy 246.861076 -183.228996) (xy 246.869756 -183.234066) (xy 246.88953 -183.237602) (xy 246.89943 -183.235854)
			(xy 246.979694 -183.218328) (xy 246.996204 -183.206898) (xy 247.001538 -183.198516) (xy 247.01666 -183.175784)
			(xy 247.052362 -183.134479) (xy 247.093585 -183.098683) (xy 247.139489 -183.069126) (xy 247.189135 -183.046412)
			(xy 247.241512 -183.031004) (xy 247.29555 -183.023217) (xy 247.322848 -183.022748) (xy 247.350094 -183.023325)
			(xy 247.40403 -183.031087) (xy 247.456313 -183.046444) (xy 247.505878 -183.069085) (xy 247.551717 -183.098549)
			(xy 247.592897 -183.134237) (xy 247.628579 -183.175421) (xy 247.658038 -183.221264) (xy 247.680673 -183.270832)
			(xy 247.696024 -183.323117) (xy 247.703778 -183.377054) (xy 247.703778 -183.431546) (xy 247.696024 -183.485483)
			(xy 247.691981 -183.499252) (xy 256.04724 -183.499252) (xy 256.047633 -183.471997) (xy 256.055398 -183.418044)
			(xy 256.070761 -183.365744) (xy 256.093411 -183.316164) (xy 256.122887 -183.270311) (xy 256.158588 -183.22912)
			(xy 256.199788 -183.19343) (xy 256.245648 -183.163965) (xy 256.295235 -183.141328) (xy 256.347538 -183.125977)
			(xy 256.401493 -183.118226) (xy 256.428748 -183.117744) (xy 256.457052 -183.118254) (xy 256.51304 -183.126599)
			(xy 256.56718 -183.14313) (xy 256.618281 -183.167481) (xy 256.665221 -183.199119) (xy 256.706969 -183.237349)
			(xy 256.742607 -183.281329) (xy 256.757424 -183.30545) (xy 256.764282 -183.317134) (xy 256.78765 -183.330596)
			(xy 256.88925 -183.330088) (xy 256.898084 -183.329645) (xy 256.914666 -183.32353) (xy 256.928187 -183.312149)
			(xy 256.932938 -183.304688) (xy 256.933192 -183.304688) (xy 256.933192 -183.304434) (xy 256.947832 -183.279804)
			(xy 256.983393 -183.234877) (xy 257.025277 -183.195779) (xy 257.072541 -183.16339) (xy 257.12412 -183.138439)
			(xy 257.178853 -183.121489) (xy 257.235505 -183.112921) (xy 257.264154 -183.11241) (xy 257.291407 -183.112898)
			(xy 257.345358 -183.120649) (xy 257.397656 -183.136) (xy 257.447237 -183.158639) (xy 257.493091 -183.188104)
			(xy 257.534285 -183.223795) (xy 257.569979 -183.264986) (xy 257.599448 -183.310838) (xy 257.62209 -183.360418)
			(xy 257.637445 -183.412715) (xy 257.6452 -183.466666) (xy 257.645662 -183.493918) (xy 257.6449 -183.518048)
			(xy 257.644698 -183.528098) (xy 257.651248 -183.547087) (xy 257.6576 -183.554878) (xy 257.71221 -183.6166)
			(xy 257.730244 -183.625236) (xy 257.740404 -183.625744) (xy 257.76923 -183.627884) (xy 257.825782 -183.639849)
			(xy 257.879882 -183.660204) (xy 257.930295 -183.688483) (xy 257.975869 -183.72404) (xy 258.01556 -183.766061)
			(xy 258.048462 -183.813586) (xy 258.073823 -183.865529) (xy 258.091062 -183.920701) (xy 258.099785 -183.977843)
			(xy 258.100322 -184.006744) (xy 258.099836 -184.033995) (xy 258.09208 -184.087943) (xy 258.076725 -184.140238)
			(xy 258.054083 -184.189815) (xy 258.024617 -184.235665) (xy 257.988926 -184.276856) (xy 257.947735 -184.312547)
			(xy 257.901885 -184.342013) (xy 257.852308 -184.364655) (xy 257.800013 -184.38001) (xy 257.746065 -184.387766)
			(xy 257.691563 -184.387766) (xy 257.637615 -184.38001) (xy 257.58532 -184.364655) (xy 257.535743 -184.342013)
			(xy 257.489893 -184.312547) (xy 257.448702 -184.276856) (xy 257.413011 -184.235665) (xy 257.383545 -184.189815)
			(xy 257.360903 -184.140238) (xy 257.345548 -184.087943) (xy 257.337792 -184.033995) (xy 257.337306 -184.006744)
			(xy 257.337427 -183.994324) (xy 257.339079 -183.96954) (xy 257.340608 -183.957214) (xy 257.341583 -183.946312)
			(xy 257.335251 -183.925379) (xy 257.328416 -183.916828) (xy 257.306826 -183.892698) (xy 257.299155 -183.884756)
			(xy 257.279 -183.875798) (xy 257.267964 -183.875426) (xy 257.264154 -183.875426) (xy 257.261614 -183.875426)
			(xy 257.226562 -183.919368) (xy 257.220227 -183.928193) (xy 257.214952 -183.949243) (xy 257.216402 -183.960008)
			(xy 257.219253 -183.976753) (xy 257.222303 -184.010587) (xy 257.222498 -184.027572) (xy 257.222498 -184.027826)
			(xy 257.222012 -184.055077) (xy 257.214256 -184.109025) (xy 257.198901 -184.16132) (xy 257.176259 -184.210897)
			(xy 257.146793 -184.256747) (xy 257.111102 -184.297938) (xy 257.069911 -184.333629) (xy 257.024061 -184.363095)
			(xy 256.974484 -184.385737) (xy 256.922189 -184.401092) (xy 256.868241 -184.408848) (xy 256.813739 -184.408848)
			(xy 256.759791 -184.401092) (xy 256.707496 -184.385737) (xy 256.657919 -184.363095) (xy 256.612069 -184.333629)
			(xy 256.570878 -184.297938) (xy 256.535187 -184.256747) (xy 256.505721 -184.210897) (xy 256.483079 -184.16132)
			(xy 256.467724 -184.109025) (xy 256.459968 -184.055077) (xy 256.459482 -184.027826) (xy 256.459482 -184.027318)
			(xy 256.459549 -184.017521) (xy 256.460564 -183.997953) (xy 256.461514 -183.988202) (xy 256.462148 -183.978367)
			(xy 256.45679 -183.959419) (xy 256.4511 -183.951372) (xy 256.401824 -183.888126) (xy 256.384552 -183.87822)
			(xy 256.3749 -183.87695) (xy 256.347967 -183.872622) (xy 256.295613 -183.857305) (xy 256.245974 -183.834688)
			(xy 256.200061 -183.805233) (xy 256.158811 -183.76954) (xy 256.123064 -183.728336) (xy 256.09355 -183.682462)
			(xy 256.070869 -183.632852) (xy 256.055483 -183.580518) (xy 256.047708 -183.526526) (xy 256.04724 -183.499252)
			(xy 247.691981 -183.499252) (xy 247.680673 -183.537768) (xy 247.658038 -183.587336) (xy 247.628579 -183.633179)
			(xy 247.592897 -183.674363) (xy 247.551717 -183.710051) (xy 247.505878 -183.739515) (xy 247.456313 -183.762156)
			(xy 247.40403 -183.777513) (xy 247.350094 -183.785275) (xy 247.322848 -183.785764) (xy 247.295559 -183.785309)
			(xy 247.241537 -183.777536) (xy 247.189175 -183.762141) (xy 247.139543 -183.739439) (xy 247.116346 -183.725058)
			(xy 247.107661 -183.719997) (xy 247.087891 -183.716457) (xy 247.077992 -183.7182) (xy 246.997728 -183.735726)
			(xy 246.981218 -183.747156) (xy 246.975884 -183.755538) (xy 246.960732 -183.778249) (xy 246.925037 -183.819557)
			(xy 246.88382 -183.855356) (xy 246.837921 -183.884916) (xy 246.788279 -183.907633) (xy 246.735906 -183.923045)
			(xy 246.681871 -183.930835) (xy 246.654574 -183.931306) (xy 246.629175 -183.930911) (xy 246.578825 -183.924167)
			(xy 246.529817 -183.910801) (xy 246.483015 -183.891049) (xy 246.439248 -183.865262) (xy 246.399291 -183.833894)
			(xy 246.38127 -183.81599) (xy 246.37492 -183.809386) (xy 246.358156 -183.801512) (xy 246.273066 -183.794654)
			(xy 246.25554 -183.79948) (xy 246.248174 -183.805068) (xy 246.22343 -183.822643) (xy 246.169513 -183.850505)
			(xy 246.111871 -183.869496) (xy 246.051951 -183.879136) (xy 246.021606 -183.879744) (xy 245.994355 -183.879209)
			(xy 245.940409 -183.871454) (xy 245.888115 -183.8561) (xy 245.838539 -183.83346) (xy 245.79269 -183.803994)
			(xy 245.7515 -183.768304) (xy 245.715809 -183.727115) (xy 245.686343 -183.681266) (xy 245.663703 -183.63169)
			(xy 245.648348 -183.579397) (xy 245.640591 -183.525451) (xy 245.494303 -183.525451) (xy 245.493438 -183.531289)
			(xy 245.477083 -183.585168) (xy 245.452984 -183.636058) (xy 245.421664 -183.682851) (xy 245.383805 -183.724531)
			(xy 245.34023 -183.760191) (xy 245.291884 -183.789057) (xy 245.23982 -183.8105) (xy 245.212616 -183.817768)
			(xy 245.199577 -183.821453) (xy 245.175968 -183.834736) (xy 245.156683 -183.85376) (xy 245.143079 -183.877184)
			(xy 245.136113 -183.903362) (xy 245.136275 -183.93045) (xy 245.143554 -183.956542) (xy 245.150132 -183.96839)
			(xy 245.162963 -183.990645) (xy 245.183179 -184.037871) (xy 245.196874 -184.087383) (xy 245.203799 -184.138285)
			(xy 245.204234 -184.16397) (xy 245.204234 -184.164478) (xy 245.203748 -184.191729) (xy 245.195992 -184.245677)
			(xy 245.180637 -184.297972) (xy 245.157995 -184.347549) (xy 245.128529 -184.393399) (xy 245.092838 -184.43459)
			(xy 245.051647 -184.470281) (xy 245.005797 -184.499747) (xy 244.95622 -184.522389) (xy 244.903925 -184.537744)
			(xy 244.849977 -184.5455) (xy 244.795475 -184.5455) (xy 244.741527 -184.537744) (xy 244.689232 -184.522389)
			(xy 244.639655 -184.499747) (xy 244.593805 -184.470281) (xy 244.552614 -184.43459) (xy 244.516923 -184.393399)
			(xy 244.487457 -184.347549) (xy 244.464815 -184.297972) (xy 244.44946 -184.245677) (xy 244.441704 -184.191729)
			(xy 244.441218 -184.164478) (xy 243.646476 -184.164478) (xy 243.652801 -184.207458) (xy 243.65331 -184.235344)
			(xy 243.652801 -184.26323) (xy 243.644681 -184.318406) (xy 243.628613 -184.371813) (xy 243.604941 -184.42231)
			(xy 243.574168 -184.468823) (xy 243.536951 -184.51036) (xy 243.494083 -184.546035) (xy 243.446477 -184.575089)
			(xy 243.395148 -184.596901) (xy 243.341191 -184.611007) (xy 243.285754 -184.617107) (xy 243.23002 -184.61507)
			(xy 243.175177 -184.60494) (xy 243.122393 -184.586933) (xy 243.072793 -184.561432) (xy 243.027435 -184.528981)
			(xy 242.987286 -184.490272) (xy 242.9532 -184.446129) (xy 242.925904 -184.397494) (xy 242.905981 -184.345403)
			(xy 242.893855 -184.290966) (xy 242.889784 -184.235344) (xy 209.698176 -184.235344) (xy 209.700108 -184.237574)
			(xy 209.729575 -184.283425) (xy 209.752217 -184.333004) (xy 209.767572 -184.385299) (xy 209.775329 -184.439248)
			(xy 209.775329 -184.493752) (xy 209.767572 -184.547701) (xy 209.752217 -184.599996) (xy 209.729575 -184.649575)
			(xy 209.700108 -184.695426) (xy 209.664415 -184.736617) (xy 209.623234 -184.7723) (xy 237.368586 -184.7723)
			(xy 237.372657 -184.716678) (xy 237.384783 -184.662241) (xy 237.404706 -184.61015) (xy 237.432002 -184.561515)
			(xy 237.466088 -184.517372) (xy 237.506237 -184.478663) (xy 237.551595 -184.446212) (xy 237.601195 -184.420711)
			(xy 237.653979 -184.402704) (xy 237.708822 -184.392574) (xy 237.764556 -184.390537) (xy 237.819993 -184.396637)
			(xy 237.87395 -184.410743) (xy 237.925279 -184.432555) (xy 237.972885 -184.461609) (xy 238.015753 -184.497284)
			(xy 238.05297 -184.538821) (xy 238.083743 -184.585334) (xy 238.107415 -184.635831) (xy 238.123483 -184.689238)
			(xy 238.131603 -184.744414) (xy 238.132112 -184.7723) (xy 238.131603 -184.800186) (xy 238.123483 -184.855362)
			(xy 238.107415 -184.908769) (xy 238.083743 -184.959266) (xy 238.05297 -185.005779) (xy 238.015753 -185.047316)
			(xy 237.972885 -185.082991) (xy 237.925279 -185.112045) (xy 237.87395 -185.133857) (xy 237.819993 -185.147963)
			(xy 237.764556 -185.154063) (xy 237.708822 -185.152026) (xy 237.653979 -185.141896) (xy 237.601195 -185.123889)
			(xy 237.551595 -185.098388) (xy 237.506237 -185.065937) (xy 237.466088 -185.027228) (xy 237.432002 -184.983085)
			(xy 237.404706 -184.93445) (xy 237.384783 -184.882359) (xy 237.372657 -184.827922) (xy 237.368586 -184.7723)
			(xy 209.623234 -184.7723) (xy 209.623224 -184.772309) (xy 209.577373 -184.801776) (xy 209.527795 -184.824417)
			(xy 209.475499 -184.839772) (xy 209.42155 -184.847529) (xy 209.394298 -184.847992) (xy 209.366782 -184.847516)
			(xy 209.312322 -184.839598) (xy 209.259563 -184.823941) (xy 209.2096 -184.80087) (xy 209.186272 -184.78627)
			(xy 209.17662 -184.780174) (xy 209.154268 -184.777126) (xy 209.05724 -184.80786) (xy 209.04073 -184.823354)
			(xy 209.036412 -184.834022) (xy 209.025447 -184.860302) (xy 208.996855 -184.909546) (xy 208.96126 -184.953992)
			(xy 208.919451 -184.99265) (xy 208.87236 -185.024663) (xy 208.821032 -185.049318) (xy 208.766608 -185.066067)
			(xy 208.710299 -185.074538) (xy 208.681828 -185.075068) (xy 208.654571 -185.074687) (xy 208.600611 -185.066932)
			(xy 208.548305 -185.051577) (xy 208.498716 -185.028934) (xy 208.452854 -184.999464) (xy 208.411654 -184.963766)
			(xy 208.375953 -184.922568) (xy 208.34648 -184.876709) (xy 208.323833 -184.827122) (xy 208.308474 -184.774816)
			(xy 208.300715 -184.720857) (xy 190.435413 -184.720857) (xy 190.272462 -185.607452) (xy 206.34909 -185.607452)
			(xy 206.353161 -185.55183) (xy 206.365287 -185.497393) (xy 206.38521 -185.445302) (xy 206.412506 -185.396667)
			(xy 206.446592 -185.352524) (xy 206.486741 -185.313815) (xy 206.532099 -185.281364) (xy 206.581699 -185.255863)
			(xy 206.634483 -185.237856) (xy 206.689326 -185.227726) (xy 206.74506 -185.225689) (xy 206.800497 -185.231789)
			(xy 206.854454 -185.245895) (xy 206.905783 -185.267707) (xy 206.953389 -185.296761) (xy 206.996257 -185.332436)
			(xy 207.024191 -185.363612) (xy 224.074226 -185.363612) (xy 224.078297 -185.30799) (xy 224.090423 -185.253553)
			(xy 224.110346 -185.201462) (xy 224.137642 -185.152827) (xy 224.171728 -185.108684) (xy 224.211877 -185.069975)
			(xy 224.257235 -185.037524) (xy 224.306835 -185.012023) (xy 224.359619 -184.994016) (xy 224.414462 -184.983886)
			(xy 224.470196 -184.981849) (xy 224.525633 -184.987949) (xy 224.57959 -185.002055) (xy 224.630919 -185.023867)
			(xy 224.678525 -185.052921) (xy 224.721393 -185.088596) (xy 224.75861 -185.130133) (xy 224.789383 -185.176646)
			(xy 224.813055 -185.227143) (xy 224.829123 -185.28055) (xy 224.837243 -185.335726) (xy 224.837752 -185.363612)
			(xy 224.837243 -185.391498) (xy 224.829123 -185.446674) (xy 224.828666 -185.448194) (xy 241.210336 -185.448194)
			(xy 241.214407 -185.392572) (xy 241.226533 -185.338135) (xy 241.246456 -185.286044) (xy 241.273752 -185.237409)
			(xy 241.307838 -185.193266) (xy 241.347987 -185.154557) (xy 241.393345 -185.122106) (xy 241.442945 -185.096605)
			(xy 241.495729 -185.078598) (xy 241.550572 -185.068468) (xy 241.606306 -185.066431) (xy 241.661743 -185.072531)
			(xy 241.7157 -185.086637) (xy 241.767029 -185.108449) (xy 241.814635 -185.137503) (xy 241.857503 -185.173178)
			(xy 241.89472 -185.214715) (xy 241.925493 -185.261228) (xy 241.949165 -185.311725) (xy 241.965233 -185.365132)
			(xy 241.970429 -185.400442) (xy 246.211088 -185.400442) (xy 246.215159 -185.34482) (xy 246.227285 -185.290383)
			(xy 246.247208 -185.238292) (xy 246.274504 -185.189657) (xy 246.30859 -185.145514) (xy 246.348739 -185.106805)
			(xy 246.394097 -185.074354) (xy 246.443697 -185.048853) (xy 246.496481 -185.030846) (xy 246.551324 -185.020716)
			(xy 246.607058 -185.018679) (xy 246.662495 -185.024779) (xy 246.716452 -185.038885) (xy 246.767781 -185.060697)
			(xy 246.815387 -185.089751) (xy 246.858255 -185.125426) (xy 246.895472 -185.166963) (xy 246.926245 -185.213476)
			(xy 246.949917 -185.263973) (xy 246.965985 -185.31738) (xy 246.974105 -185.372556) (xy 246.974614 -185.400442)
			(xy 246.974105 -185.428328) (xy 246.965985 -185.483504) (xy 246.949917 -185.536911) (xy 246.926245 -185.587408)
			(xy 246.908279 -185.614564) (xy 248.11939 -185.614564) (xy 248.123461 -185.558942) (xy 248.135587 -185.504505)
			(xy 248.15551 -185.452414) (xy 248.182806 -185.403779) (xy 248.216892 -185.359636) (xy 248.257041 -185.320927)
			(xy 248.302399 -185.288476) (xy 248.351999 -185.262975) (xy 248.404783 -185.244968) (xy 248.459626 -185.234838)
			(xy 248.51536 -185.232801) (xy 248.570797 -185.238901) (xy 248.624754 -185.253007) (xy 248.676083 -185.274819)
			(xy 248.723689 -185.303873) (xy 248.766557 -185.339548) (xy 248.803774 -185.381085) (xy 248.834547 -185.427598)
			(xy 248.858219 -185.478095) (xy 248.874287 -185.531502) (xy 248.882407 -185.586678) (xy 248.882916 -185.614564)
			(xy 248.882407 -185.64245) (xy 248.874287 -185.697626) (xy 248.858219 -185.751033) (xy 248.834547 -185.80153)
			(xy 248.803774 -185.848043) (xy 248.800408 -185.8518) (xy 262.050782 -185.8518) (xy 262.054853 -185.796178)
			(xy 262.066979 -185.741741) (xy 262.086902 -185.68965) (xy 262.114198 -185.641015) (xy 262.148284 -185.596872)
			(xy 262.188433 -185.558163) (xy 262.233791 -185.525712) (xy 262.283391 -185.500211) (xy 262.336175 -185.482204)
			(xy 262.391018 -185.472074) (xy 262.446752 -185.470037) (xy 262.502189 -185.476137) (xy 262.556146 -185.490243)
			(xy 262.607475 -185.512055) (xy 262.655081 -185.541109) (xy 262.697949 -185.576784) (xy 262.735166 -185.618321)
			(xy 262.765939 -185.664834) (xy 262.789611 -185.715331) (xy 262.805679 -185.768738) (xy 262.813799 -185.823914)
			(xy 262.814308 -185.8518) (xy 262.813799 -185.879686) (xy 262.805679 -185.934862) (xy 262.789611 -185.988269)
			(xy 262.765939 -186.038766) (xy 262.735166 -186.085279) (xy 262.697949 -186.126816) (xy 262.655081 -186.162491)
			(xy 262.607475 -186.191545) (xy 262.556146 -186.213357) (xy 262.502189 -186.227463) (xy 262.446752 -186.233563)
			(xy 262.391018 -186.231526) (xy 262.336175 -186.221396) (xy 262.283391 -186.203389) (xy 262.233791 -186.177888)
			(xy 262.188433 -186.145437) (xy 262.148284 -186.106728) (xy 262.114198 -186.062585) (xy 262.086902 -186.01395)
			(xy 262.066979 -185.961859) (xy 262.054853 -185.907422) (xy 262.050782 -185.8518) (xy 248.800408 -185.8518)
			(xy 248.766557 -185.88958) (xy 248.723689 -185.925255) (xy 248.676083 -185.954309) (xy 248.624754 -185.976121)
			(xy 248.570797 -185.990227) (xy 248.51536 -185.996327) (xy 248.459626 -185.99429) (xy 248.404783 -185.98416)
			(xy 248.351999 -185.966153) (xy 248.302399 -185.940652) (xy 248.257041 -185.908201) (xy 248.216892 -185.869492)
			(xy 248.182806 -185.825349) (xy 248.15551 -185.776714) (xy 248.135587 -185.724623) (xy 248.123461 -185.670186)
			(xy 248.11939 -185.614564) (xy 246.908279 -185.614564) (xy 246.895472 -185.633921) (xy 246.858255 -185.675458)
			(xy 246.815387 -185.711133) (xy 246.767781 -185.740187) (xy 246.716452 -185.761999) (xy 246.662495 -185.776105)
			(xy 246.607058 -185.782205) (xy 246.551324 -185.780168) (xy 246.496481 -185.770038) (xy 246.443697 -185.752031)
			(xy 246.394097 -185.72653) (xy 246.348739 -185.694079) (xy 246.30859 -185.65537) (xy 246.274504 -185.611227)
			(xy 246.247208 -185.562592) (xy 246.227285 -185.510501) (xy 246.215159 -185.456064) (xy 246.211088 -185.400442)
			(xy 241.970429 -185.400442) (xy 241.973353 -185.420308) (xy 241.973862 -185.448194) (xy 241.973353 -185.47608)
			(xy 241.965233 -185.531256) (xy 241.949165 -185.584663) (xy 241.925493 -185.63516) (xy 241.89472 -185.681673)
			(xy 241.857503 -185.72321) (xy 241.814635 -185.758885) (xy 241.767029 -185.787939) (xy 241.7157 -185.809751)
			(xy 241.661743 -185.823857) (xy 241.606306 -185.829957) (xy 241.550572 -185.82792) (xy 241.495729 -185.81779)
			(xy 241.442945 -185.799783) (xy 241.393345 -185.774282) (xy 241.347987 -185.741831) (xy 241.307838 -185.703122)
			(xy 241.273752 -185.658979) (xy 241.246456 -185.610344) (xy 241.226533 -185.558253) (xy 241.214407 -185.503816)
			(xy 241.210336 -185.448194) (xy 224.828666 -185.448194) (xy 224.813055 -185.500081) (xy 224.789383 -185.550578)
			(xy 224.75861 -185.597091) (xy 224.721393 -185.638628) (xy 224.678525 -185.674303) (xy 224.630919 -185.703357)
			(xy 224.57959 -185.725169) (xy 224.525633 -185.739275) (xy 224.470196 -185.745375) (xy 224.414462 -185.743338)
			(xy 224.359619 -185.733208) (xy 224.306835 -185.715201) (xy 224.257235 -185.6897) (xy 224.211877 -185.657249)
			(xy 224.171728 -185.61854) (xy 224.137642 -185.574397) (xy 224.110346 -185.525762) (xy 224.090423 -185.473671)
			(xy 224.078297 -185.419234) (xy 224.074226 -185.363612) (xy 207.024191 -185.363612) (xy 207.033474 -185.373973)
			(xy 207.064247 -185.420486) (xy 207.087919 -185.470983) (xy 207.103987 -185.52439) (xy 207.112107 -185.579566)
			(xy 207.112616 -185.607452) (xy 207.112107 -185.635338) (xy 207.103987 -185.690514) (xy 207.087919 -185.743921)
			(xy 207.064247 -185.794418) (xy 207.033474 -185.840931) (xy 206.996257 -185.882468) (xy 206.953389 -185.918143)
			(xy 206.905783 -185.947197) (xy 206.854454 -185.969009) (xy 206.800497 -185.983115) (xy 206.74506 -185.989215)
			(xy 206.689326 -185.987178) (xy 206.634483 -185.977048) (xy 206.581699 -185.959041) (xy 206.532099 -185.93354)
			(xy 206.486741 -185.901089) (xy 206.446592 -185.86238) (xy 206.412506 -185.818237) (xy 206.38521 -185.769602)
			(xy 206.365287 -185.717511) (xy 206.353161 -185.663074) (xy 206.34909 -185.607452) (xy 190.272462 -185.607452)
			(xy 190.11187 -186.481212) (xy 242.429282 -186.481212) (xy 242.433353 -186.42559) (xy 242.445479 -186.371153)
			(xy 242.465402 -186.319062) (xy 242.492698 -186.270427) (xy 242.526784 -186.226284) (xy 242.566933 -186.187575)
			(xy 242.612291 -186.155124) (xy 242.661891 -186.129623) (xy 242.714675 -186.111616) (xy 242.769518 -186.101486)
			(xy 242.825252 -186.099449) (xy 242.880689 -186.105549) (xy 242.934646 -186.119655) (xy 242.985975 -186.141467)
			(xy 243.033581 -186.170521) (xy 243.076449 -186.206196) (xy 243.113666 -186.247733) (xy 243.144439 -186.294246)
			(xy 243.168111 -186.344743) (xy 243.184179 -186.39815) (xy 243.192299 -186.453326) (xy 243.192808 -186.481212)
			(xy 243.445282 -186.481212) (xy 243.449353 -186.42559) (xy 243.461479 -186.371153) (xy 243.481402 -186.319062)
			(xy 243.508698 -186.270427) (xy 243.542784 -186.226284) (xy 243.582933 -186.187575) (xy 243.628291 -186.155124)
			(xy 243.677891 -186.129623) (xy 243.730675 -186.111616) (xy 243.785518 -186.101486) (xy 243.841252 -186.099449)
			(xy 243.896689 -186.105549) (xy 243.950646 -186.119655) (xy 244.001975 -186.141467) (xy 244.049581 -186.170521)
			(xy 244.092449 -186.206196) (xy 244.129666 -186.247733) (xy 244.160439 -186.294246) (xy 244.184111 -186.344743)
			(xy 244.200179 -186.39815) (xy 244.208299 -186.453326) (xy 244.208808 -186.481212) (xy 244.461282 -186.481212)
			(xy 244.465353 -186.42559) (xy 244.477479 -186.371153) (xy 244.497402 -186.319062) (xy 244.524698 -186.270427)
			(xy 244.558784 -186.226284) (xy 244.598933 -186.187575) (xy 244.644291 -186.155124) (xy 244.693891 -186.129623)
			(xy 244.746675 -186.111616) (xy 244.801518 -186.101486) (xy 244.857252 -186.099449) (xy 244.912689 -186.105549)
			(xy 244.966646 -186.119655) (xy 245.017975 -186.141467) (xy 245.065581 -186.170521) (xy 245.108449 -186.206196)
			(xy 245.145666 -186.247733) (xy 245.176439 -186.294246) (xy 245.200111 -186.344743) (xy 245.216179 -186.39815)
			(xy 245.224299 -186.453326) (xy 245.224808 -186.481212) (xy 245.224299 -186.509098) (xy 245.216179 -186.564274)
			(xy 245.200111 -186.617681) (xy 245.176439 -186.668178) (xy 245.145666 -186.714691) (xy 245.108449 -186.756228)
			(xy 245.065581 -186.791903) (xy 245.017975 -186.820957) (xy 244.966646 -186.842769) (xy 244.912689 -186.856875)
			(xy 244.857252 -186.862975) (xy 244.801518 -186.860938) (xy 244.746675 -186.850808) (xy 244.693891 -186.832801)
			(xy 244.644291 -186.8073) (xy 244.598933 -186.774849) (xy 244.558784 -186.73614) (xy 244.524698 -186.691997)
			(xy 244.497402 -186.643362) (xy 244.477479 -186.591271) (xy 244.465353 -186.536834) (xy 244.461282 -186.481212)
			(xy 244.208808 -186.481212) (xy 244.208299 -186.509098) (xy 244.200179 -186.564274) (xy 244.184111 -186.617681)
			(xy 244.160439 -186.668178) (xy 244.129666 -186.714691) (xy 244.092449 -186.756228) (xy 244.049581 -186.791903)
			(xy 244.001975 -186.820957) (xy 243.950646 -186.842769) (xy 243.896689 -186.856875) (xy 243.841252 -186.862975)
			(xy 243.785518 -186.860938) (xy 243.730675 -186.850808) (xy 243.677891 -186.832801) (xy 243.628291 -186.8073)
			(xy 243.582933 -186.774849) (xy 243.542784 -186.73614) (xy 243.508698 -186.691997) (xy 243.481402 -186.643362)
			(xy 243.461479 -186.591271) (xy 243.449353 -186.536834) (xy 243.445282 -186.481212) (xy 243.192808 -186.481212)
			(xy 243.192299 -186.509098) (xy 243.184179 -186.564274) (xy 243.168111 -186.617681) (xy 243.144439 -186.668178)
			(xy 243.113666 -186.714691) (xy 243.076449 -186.756228) (xy 243.033581 -186.791903) (xy 242.985975 -186.820957)
			(xy 242.934646 -186.842769) (xy 242.880689 -186.856875) (xy 242.825252 -186.862975) (xy 242.769518 -186.860938)
			(xy 242.714675 -186.850808) (xy 242.661891 -186.832801) (xy 242.612291 -186.8073) (xy 242.566933 -186.774849)
			(xy 242.526784 -186.73614) (xy 242.492698 -186.691997) (xy 242.465402 -186.643362) (xy 242.445479 -186.591271)
			(xy 242.433353 -186.536834) (xy 242.429282 -186.481212) (xy 190.11187 -186.481212) (xy 189.794375 -188.208666)
			(xy 206.292194 -188.208666) (xy 206.296265 -188.153044) (xy 206.308391 -188.098607) (xy 206.328314 -188.046516)
			(xy 206.35561 -187.997881) (xy 206.389696 -187.953738) (xy 206.429845 -187.915029) (xy 206.475203 -187.882578)
			(xy 206.524803 -187.857077) (xy 206.577587 -187.83907) (xy 206.63243 -187.82894) (xy 206.688164 -187.826903)
			(xy 206.743601 -187.833003) (xy 206.797558 -187.847109) (xy 206.844451 -187.867036) (xy 207.844134 -187.867036)
			(xy 207.848205 -187.811414) (xy 207.860331 -187.756977) (xy 207.880254 -187.704886) (xy 207.90755 -187.656251)
			(xy 207.941636 -187.612108) (xy 207.981785 -187.573399) (xy 208.027143 -187.540948) (xy 208.076743 -187.515447)
			(xy 208.129527 -187.49744) (xy 208.18437 -187.48731) (xy 208.240104 -187.485273) (xy 208.295541 -187.491373)
			(xy 208.349498 -187.505479) (xy 208.400827 -187.527291) (xy 208.448433 -187.556345) (xy 208.491301 -187.59202)
			(xy 208.528518 -187.633557) (xy 208.534435 -187.6425) (xy 210.560918 -187.6425) (xy 210.564989 -187.586878)
			(xy 210.577115 -187.532441) (xy 210.597038 -187.48035) (xy 210.624334 -187.431715) (xy 210.65842 -187.387572)
			(xy 210.698569 -187.348863) (xy 210.743927 -187.316412) (xy 210.793527 -187.290911) (xy 210.846311 -187.272904)
			(xy 210.901154 -187.262774) (xy 210.956888 -187.260737) (xy 211.012325 -187.266837) (xy 211.066282 -187.280943)
			(xy 211.117611 -187.302755) (xy 211.165217 -187.331809) (xy 211.208085 -187.367484) (xy 211.245302 -187.409021)
			(xy 211.276075 -187.455534) (xy 211.299747 -187.506031) (xy 211.315815 -187.559438) (xy 211.323935 -187.614614)
			(xy 211.324444 -187.6425) (xy 211.324439 -187.642754) (xy 212.143084 -187.642754) (xy 212.147155 -187.587132)
			(xy 212.159281 -187.532695) (xy 212.179204 -187.480604) (xy 212.2065 -187.431969) (xy 212.240586 -187.387826)
			(xy 212.280735 -187.349117) (xy 212.326093 -187.316666) (xy 212.375693 -187.291165) (xy 212.428477 -187.273158)
			(xy 212.48332 -187.263028) (xy 212.539054 -187.260991) (xy 212.594491 -187.267091) (xy 212.648448 -187.281197)
			(xy 212.699777 -187.303009) (xy 212.747383 -187.332063) (xy 212.790251 -187.367738) (xy 212.827468 -187.409275)
			(xy 212.858241 -187.455788) (xy 212.881913 -187.506285) (xy 212.897981 -187.559692) (xy 212.906101 -187.614868)
			(xy 212.906605 -187.6425) (xy 214.624918 -187.6425) (xy 214.628989 -187.586878) (xy 214.641115 -187.532441)
			(xy 214.661038 -187.48035) (xy 214.688334 -187.431715) (xy 214.72242 -187.387572) (xy 214.762569 -187.348863)
			(xy 214.807927 -187.316412) (xy 214.857527 -187.290911) (xy 214.910311 -187.272904) (xy 214.965154 -187.262774)
			(xy 215.020888 -187.260737) (xy 215.076325 -187.266837) (xy 215.130282 -187.280943) (xy 215.181611 -187.302755)
			(xy 215.229217 -187.331809) (xy 215.272085 -187.367484) (xy 215.309302 -187.409021) (xy 215.340075 -187.455534)
			(xy 215.363747 -187.506031) (xy 215.379815 -187.559438) (xy 215.387665 -187.612782) (xy 216.656918 -187.612782)
			(xy 216.660989 -187.55716) (xy 216.673115 -187.502723) (xy 216.693038 -187.450632) (xy 216.720334 -187.401997)
			(xy 216.75442 -187.357854) (xy 216.794569 -187.319145) (xy 216.839927 -187.286694) (xy 216.889527 -187.261193)
			(xy 216.942311 -187.243186) (xy 216.997154 -187.233056) (xy 217.052888 -187.231019) (xy 217.108325 -187.237119)
			(xy 217.162282 -187.251225) (xy 217.213611 -187.273037) (xy 217.261217 -187.302091) (xy 217.304085 -187.337766)
			(xy 217.341302 -187.379303) (xy 217.372075 -187.425816) (xy 217.395747 -187.476313) (xy 217.411815 -187.52972)
			(xy 217.419935 -187.584896) (xy 217.420444 -187.612782) (xy 217.419935 -187.640668) (xy 217.411815 -187.695844)
			(xy 217.395747 -187.749251) (xy 217.372075 -187.799748) (xy 217.341302 -187.846261) (xy 217.304085 -187.887798)
			(xy 217.261217 -187.923473) (xy 217.213611 -187.952527) (xy 217.162282 -187.974339) (xy 217.108325 -187.988445)
			(xy 217.052888 -187.994545) (xy 216.997154 -187.992508) (xy 216.942311 -187.982378) (xy 216.889527 -187.964371)
			(xy 216.839927 -187.93887) (xy 216.794569 -187.906419) (xy 216.75442 -187.86771) (xy 216.720334 -187.823567)
			(xy 216.693038 -187.774932) (xy 216.673115 -187.722841) (xy 216.660989 -187.668404) (xy 216.656918 -187.612782)
			(xy 215.387665 -187.612782) (xy 215.387935 -187.614614) (xy 215.388444 -187.6425) (xy 215.387935 -187.670386)
			(xy 215.379815 -187.725562) (xy 215.363747 -187.778969) (xy 215.340075 -187.829466) (xy 215.309302 -187.875979)
			(xy 215.272085 -187.917516) (xy 215.229217 -187.953191) (xy 215.181611 -187.982245) (xy 215.130282 -188.004057)
			(xy 215.076325 -188.018163) (xy 215.020888 -188.024263) (xy 214.965154 -188.022226) (xy 214.910311 -188.012096)
			(xy 214.857527 -187.994089) (xy 214.807927 -187.968588) (xy 214.762569 -187.936137) (xy 214.72242 -187.897428)
			(xy 214.688334 -187.853285) (xy 214.661038 -187.80465) (xy 214.641115 -187.752559) (xy 214.628989 -187.698122)
			(xy 214.624918 -187.6425) (xy 212.906605 -187.6425) (xy 212.90661 -187.642754) (xy 212.906101 -187.67064)
			(xy 212.897981 -187.725816) (xy 212.881913 -187.779223) (xy 212.858241 -187.82972) (xy 212.827468 -187.876233)
			(xy 212.790251 -187.91777) (xy 212.747383 -187.953445) (xy 212.699777 -187.982499) (xy 212.648448 -188.004311)
			(xy 212.594491 -188.018417) (xy 212.539054 -188.024517) (xy 212.48332 -188.02248) (xy 212.428477 -188.01235)
			(xy 212.375693 -187.994343) (xy 212.326093 -187.968842) (xy 212.280735 -187.936391) (xy 212.240586 -187.897682)
			(xy 212.2065 -187.853539) (xy 212.179204 -187.804904) (xy 212.159281 -187.752813) (xy 212.147155 -187.698376)
			(xy 212.143084 -187.642754) (xy 211.324439 -187.642754) (xy 211.323935 -187.670386) (xy 211.315815 -187.725562)
			(xy 211.299747 -187.778969) (xy 211.276075 -187.829466) (xy 211.245302 -187.875979) (xy 211.208085 -187.917516)
			(xy 211.165217 -187.953191) (xy 211.117611 -187.982245) (xy 211.066282 -188.004057) (xy 211.012325 -188.018163)
			(xy 210.956888 -188.024263) (xy 210.901154 -188.022226) (xy 210.846311 -188.012096) (xy 210.793527 -187.994089)
			(xy 210.743927 -187.968588) (xy 210.698569 -187.936137) (xy 210.65842 -187.897428) (xy 210.624334 -187.853285)
			(xy 210.597038 -187.80465) (xy 210.577115 -187.752559) (xy 210.564989 -187.698122) (xy 210.560918 -187.6425)
			(xy 208.534435 -187.6425) (xy 208.559291 -187.68007) (xy 208.582963 -187.730567) (xy 208.599031 -187.783974)
			(xy 208.607151 -187.83915) (xy 208.60766 -187.867036) (xy 208.607151 -187.894922) (xy 208.599031 -187.950098)
			(xy 208.582963 -188.003505) (xy 208.559291 -188.054002) (xy 208.528518 -188.100515) (xy 208.491301 -188.142052)
			(xy 208.448433 -188.177727) (xy 208.400827 -188.206781) (xy 208.349498 -188.228593) (xy 208.295541 -188.242699)
			(xy 208.240104 -188.248799) (xy 208.18437 -188.246762) (xy 208.129527 -188.236632) (xy 208.076743 -188.218625)
			(xy 208.027143 -188.193124) (xy 207.981785 -188.160673) (xy 207.941636 -188.121964) (xy 207.90755 -188.077821)
			(xy 207.880254 -188.029186) (xy 207.860331 -187.977095) (xy 207.848205 -187.922658) (xy 207.844134 -187.867036)
			(xy 206.844451 -187.867036) (xy 206.848887 -187.868921) (xy 206.896493 -187.897975) (xy 206.939361 -187.93365)
			(xy 206.976578 -187.975187) (xy 207.007351 -188.0217) (xy 207.031023 -188.072197) (xy 207.047091 -188.125604)
			(xy 207.055211 -188.18078) (xy 207.05572 -188.208666) (xy 207.055211 -188.236552) (xy 207.047091 -188.291728)
			(xy 207.031023 -188.345135) (xy 207.007351 -188.395632) (xy 206.976578 -188.442145) (xy 206.939361 -188.483682)
			(xy 206.908394 -188.509453) (xy 221.989079 -188.509453) (xy 221.989079 -188.454947) (xy 221.996837 -188.400996)
			(xy 222.012194 -188.348698) (xy 222.034838 -188.299118) (xy 222.064308 -188.253266) (xy 222.100004 -188.212075)
			(xy 222.141199 -188.176383) (xy 222.187055 -188.146918) (xy 222.236637 -188.124279) (xy 222.288937 -188.108928)
			(xy 222.342889 -188.101176) (xy 222.370142 -188.100716) (xy 222.397431 -188.101183) (xy 222.451454 -188.10894)
			(xy 222.50382 -188.12432) (xy 222.553458 -188.147007) (xy 222.599355 -188.176539) (xy 222.640574 -188.212311)
			(xy 222.676273 -188.253594) (xy 222.705722 -188.299545) (xy 222.72832 -188.349224) (xy 222.73641 -188.37529)
			(xy 222.74022 -188.388244) (xy 222.759778 -188.407294) (xy 222.85833 -188.431424) (xy 222.867061 -188.433204)
			(xy 222.884762 -188.43131) (xy 222.900719 -188.423418) (xy 222.907098 -188.4172) (xy 222.925124 -188.399002)
			(xy 222.965252 -188.367166) (xy 223.009278 -188.340984) (xy 223.056412 -188.320927) (xy 223.105804 -188.307356)
			(xy 223.156568 -188.300514) (xy 223.18218 -188.300106) (xy 223.209433 -188.300574) (xy 223.263384 -188.308329)
			(xy 223.315683 -188.323683) (xy 223.365264 -188.346324) (xy 223.411118 -188.375791) (xy 223.452311 -188.411484)
			(xy 223.488005 -188.452677) (xy 223.517473 -188.498531) (xy 223.540115 -188.548111) (xy 223.55547 -188.60041)
			(xy 223.563226 -188.654361) (xy 223.563688 -188.681614) (xy 223.563611 -188.692049) (xy 223.562469 -188.712889)
			(xy 223.561402 -188.72327) (xy 223.560686 -188.734024) (xy 223.567305 -188.754518) (xy 223.581729 -188.770511)
			(xy 223.601433 -188.779204) (xy 223.622969 -188.779075) (xy 223.642568 -188.770148) (xy 223.650048 -188.762386)
			(xy 223.663887 -188.747143) (xy 223.694305 -188.719396) (xy 223.710754 -188.707014) (xy 223.718628 -188.701172)
			(xy 223.728788 -188.684916) (xy 223.74479 -188.596016) (xy 223.740726 -188.57722) (xy 223.735392 -188.569092)
			(xy 223.735392 -188.568584) (xy 223.720307 -188.54501) (xy 223.69642 -188.494399) (xy 223.680174 -188.440844)
			(xy 223.671918 -188.385492) (xy 223.671384 -188.35751) (xy 223.671865 -188.330258) (xy 223.67962 -188.276308)
			(xy 223.694974 -188.224011) (xy 223.717615 -188.174431) (xy 223.747081 -188.128578) (xy 223.782773 -188.087386)
			(xy 223.823964 -188.051692) (xy 223.869815 -188.022224) (xy 223.919394 -187.999581) (xy 223.97169 -187.984224)
			(xy 224.02564 -187.976466) (xy 224.052892 -187.976002) (xy 224.053146 -187.976002) (xy 224.078307 -187.976425)
			(xy 224.12819 -187.983065) (xy 224.176769 -187.996197) (xy 224.223203 -188.015594) (xy 224.266689 -188.040921)
			(xy 224.286826 -188.056012) (xy 224.29597 -188.063124) (xy 224.318322 -188.068204) (xy 224.417636 -188.044582)
			(xy 224.435416 -188.030612) (xy 224.440496 -188.020452) (xy 224.440496 -188.019944) (xy 224.452496 -187.996074)
			(xy 224.482285 -187.95172) (xy 224.517969 -187.911954) (xy 224.558852 -187.877556) (xy 224.604133 -187.849197)
			(xy 224.652927 -187.827431) (xy 224.704281 -187.812685) (xy 224.757189 -187.805246) (xy 224.783904 -187.804806)
			(xy 224.811156 -187.805264) (xy 224.865105 -187.813021) (xy 224.917402 -187.828377) (xy 224.96698 -187.85102)
			(xy 225.012832 -187.880487) (xy 225.054023 -187.91618) (xy 225.089715 -187.957372) (xy 225.119182 -188.003223)
			(xy 225.141824 -188.052802) (xy 225.15718 -188.105099) (xy 225.164936 -188.159048) (xy 225.164936 -188.213552)
			(xy 225.15718 -188.267501) (xy 225.141824 -188.319798) (xy 225.119182 -188.369377) (xy 225.089715 -188.415228)
			(xy 225.054023 -188.45642) (xy 225.012832 -188.492113) (xy 224.96698 -188.52158) (xy 224.917402 -188.544223)
			(xy 224.865105 -188.559579) (xy 224.811156 -188.567336) (xy 224.783904 -188.567822) (xy 224.78365 -188.567822)
			(xy 224.758488 -188.567417) (xy 224.708604 -188.560775) (xy 224.660024 -188.54764) (xy 224.61359 -188.528238)
			(xy 224.570106 -188.502906) (xy 224.54997 -188.487812) (xy 224.540826 -188.4807) (xy 224.518474 -188.47562)
			(xy 224.41916 -188.499242) (xy 224.40138 -188.513212) (xy 224.3963 -188.523372) (xy 224.3963 -188.52388)
			(xy 224.382166 -188.551592) (xy 224.346303 -188.602417) (xy 224.302686 -188.646767) (xy 224.277936 -188.665612)
			(xy 224.270062 -188.671454) (xy 224.259902 -188.68771) (xy 224.2439 -188.77661) (xy 224.247964 -188.795406)
			(xy 224.253044 -188.803534) (xy 224.253552 -188.804042) (xy 224.271078 -188.832998) (xy 224.276412 -188.842904)
			(xy 224.294192 -188.856112) (xy 224.391728 -188.876686) (xy 224.413064 -188.872114) (xy 224.4217 -188.865256)
			(xy 224.422208 -188.865256) (xy 224.442197 -188.85043) (xy 224.485314 -188.825575) (xy 224.531302 -188.80655)
			(xy 224.579376 -188.793678) (xy 224.628718 -188.787181) (xy 224.653602 -188.78677) (xy 224.680852 -188.7873)
			(xy 224.734796 -188.795057) (xy 224.787087 -188.810411) (xy 224.836661 -188.833051) (xy 224.882509 -188.862516)
			(xy 224.923696 -188.898205) (xy 224.959386 -188.939393) (xy 224.98885 -188.98524) (xy 225.004118 -189.018672)
			(xy 242.843048 -189.018672) (xy 242.847119 -188.96305) (xy 242.859245 -188.908613) (xy 242.879168 -188.856522)
			(xy 242.906464 -188.807887) (xy 242.94055 -188.763744) (xy 242.980699 -188.725035) (xy 243.026057 -188.692584)
			(xy 243.075657 -188.667083) (xy 243.128441 -188.649076) (xy 243.183284 -188.638946) (xy 243.239018 -188.636909)
			(xy 243.294455 -188.643009) (xy 243.348412 -188.657115) (xy 243.399741 -188.678927) (xy 243.447347 -188.707981)
			(xy 243.490215 -188.743656) (xy 243.527432 -188.785193) (xy 243.558205 -188.831706) (xy 243.581877 -188.882203)
			(xy 243.597945 -188.93561) (xy 243.606065 -188.990786) (xy 243.606574 -189.018672) (xy 243.606065 -189.046558)
			(xy 243.597945 -189.101734) (xy 243.581877 -189.155141) (xy 243.558205 -189.205638) (xy 243.527432 -189.252151)
			(xy 243.506542 -189.275466) (xy 249.014486 -189.275466) (xy 249.018557 -189.219844) (xy 249.030683 -189.165407)
			(xy 249.050606 -189.113316) (xy 249.077902 -189.064681) (xy 249.111988 -189.020538) (xy 249.152137 -188.981829)
			(xy 249.197495 -188.949378) (xy 249.247095 -188.923877) (xy 249.299879 -188.90587) (xy 249.354722 -188.89574)
			(xy 249.410456 -188.893703) (xy 249.465893 -188.899803) (xy 249.51985 -188.913909) (xy 249.571179 -188.935721)
			(xy 249.618785 -188.964775) (xy 249.661653 -189.00045) (xy 249.69887 -189.041987) (xy 249.729643 -189.0885)
			(xy 249.753315 -189.138997) (xy 249.769383 -189.192404) (xy 249.777503 -189.24758) (xy 249.778012 -189.275466)
			(xy 249.777503 -189.303352) (xy 249.769383 -189.358528) (xy 249.753315 -189.411935) (xy 249.743823 -189.432184)
			(xy 250.433076 -189.432184) (xy 250.437147 -189.376562) (xy 250.449273 -189.322125) (xy 250.469196 -189.270034)
			(xy 250.496492 -189.221399) (xy 250.530578 -189.177256) (xy 250.570727 -189.138547) (xy 250.616085 -189.106096)
			(xy 250.665685 -189.080595) (xy 250.718469 -189.062588) (xy 250.773312 -189.052458) (xy 250.829046 -189.050421)
			(xy 250.884483 -189.056521) (xy 250.93844 -189.070627) (xy 250.989769 -189.092439) (xy 251.037375 -189.121493)
			(xy 251.080243 -189.157168) (xy 251.11746 -189.198705) (xy 251.148233 -189.245218) (xy 251.171905 -189.295715)
			(xy 251.187973 -189.349122) (xy 251.196093 -189.404298) (xy 251.196602 -189.432184) (xy 251.196093 -189.46007)
			(xy 251.187973 -189.515246) (xy 251.171905 -189.568653) (xy 251.148233 -189.61915) (xy 251.11746 -189.665663)
			(xy 251.080243 -189.7072) (xy 251.037375 -189.742875) (xy 250.989769 -189.771929) (xy 250.93844 -189.793741)
			(xy 250.884483 -189.807847) (xy 250.829046 -189.813947) (xy 250.773312 -189.81191) (xy 250.718469 -189.80178)
			(xy 250.665685 -189.783773) (xy 250.616085 -189.758272) (xy 250.570727 -189.725821) (xy 250.530578 -189.687112)
			(xy 250.496492 -189.642969) (xy 250.469196 -189.594334) (xy 250.449273 -189.542243) (xy 250.437147 -189.487806)
			(xy 250.433076 -189.432184) (xy 249.743823 -189.432184) (xy 249.729643 -189.462432) (xy 249.69887 -189.508945)
			(xy 249.661653 -189.550482) (xy 249.618785 -189.586157) (xy 249.571179 -189.615211) (xy 249.51985 -189.637023)
			(xy 249.465893 -189.651129) (xy 249.410456 -189.657229) (xy 249.354722 -189.655192) (xy 249.299879 -189.645062)
			(xy 249.247095 -189.627055) (xy 249.197495 -189.601554) (xy 249.152137 -189.569103) (xy 249.111988 -189.530394)
			(xy 249.077902 -189.486251) (xy 249.050606 -189.437616) (xy 249.030683 -189.385525) (xy 249.018557 -189.331088)
			(xy 249.014486 -189.275466) (xy 243.506542 -189.275466) (xy 243.490215 -189.293688) (xy 243.447347 -189.329363)
			(xy 243.399741 -189.358417) (xy 243.348412 -189.380229) (xy 243.294455 -189.394335) (xy 243.239018 -189.400435)
			(xy 243.183284 -189.398398) (xy 243.128441 -189.388268) (xy 243.075657 -189.370261) (xy 243.026057 -189.34476)
			(xy 242.980699 -189.312309) (xy 242.94055 -189.2736) (xy 242.906464 -189.229457) (xy 242.879168 -189.180822)
			(xy 242.859245 -189.128731) (xy 242.847119 -189.074294) (xy 242.843048 -189.018672) (xy 225.004118 -189.018672)
			(xy 225.01149 -189.034815) (xy 225.026844 -189.087106) (xy 225.0346 -189.14105) (xy 225.0346 -189.19555)
			(xy 225.026844 -189.249494) (xy 225.01149 -189.301785) (xy 224.98885 -189.35136) (xy 224.959386 -189.397207)
			(xy 224.923696 -189.438395) (xy 224.882509 -189.474084) (xy 224.836661 -189.503549) (xy 224.787087 -189.526189)
			(xy 224.734796 -189.541543) (xy 224.680852 -189.5493) (xy 224.653602 -189.549786) (xy 224.624337 -189.549276)
			(xy 224.566491 -189.540349) (xy 224.510688 -189.52269) (xy 224.458238 -189.496713) (xy 224.410373 -189.463028)
			(xy 224.368215 -189.422426) (xy 224.332755 -189.37586) (xy 224.318322 -189.350396) (xy 224.312988 -189.34049)
			(xy 224.295208 -189.327282) (xy 224.197672 -189.306708) (xy 224.176336 -189.31128) (xy 224.1677 -189.318138)
			(xy 224.167192 -189.318138) (xy 224.147202 -189.332963) (xy 224.104086 -189.357818) (xy 224.058098 -189.376844)
			(xy 224.010024 -189.389715) (xy 223.960682 -189.396213) (xy 223.935798 -189.396624) (xy 223.908351 -189.39619)
			(xy 223.854021 -189.388335) (xy 223.801378 -189.372774) (xy 223.75151 -189.349827) (xy 223.705446 -189.31997)
			(xy 223.664137 -189.283817) (xy 223.628438 -189.242117) (xy 223.599084 -189.19573) (xy 223.576682 -189.145614)
			(xy 223.561696 -189.092805) (xy 223.557592 -189.065662) (xy 223.557592 -189.065408) (xy 223.556073 -189.056859)
			(xy 223.548092 -189.041449) (xy 223.535429 -189.029583) (xy 223.52762 -189.025784) (xy 223.43618 -188.985398)
			(xy 223.410018 -188.987684) (xy 223.399096 -188.995304) (xy 223.375062 -189.011292) (xy 223.323191 -189.036615)
			(xy 223.268099 -189.053839) (xy 223.211041 -189.062571) (xy 223.18218 -189.063122) (xy 223.15489 -189.062698)
			(xy 223.100867 -189.05493) (xy 223.048501 -189.039542) (xy 222.998864 -189.016848) (xy 222.952968 -188.987311)
			(xy 222.91175 -188.951534) (xy 222.876052 -188.910248) (xy 222.846603 -188.864295) (xy 222.824003 -188.814615)
			(xy 222.815912 -188.788548) (xy 222.812102 -188.775594) (xy 222.792544 -188.756544) (xy 222.693992 -188.732414)
			(xy 222.685272 -188.730561) (xy 222.667558 -188.732481) (xy 222.651599 -188.740404) (xy 222.645224 -188.746638)
			(xy 222.627176 -188.764814) (xy 222.587054 -188.796654) (xy 222.543033 -188.822841) (xy 222.495904 -188.842902)
			(xy 222.446514 -188.856477) (xy 222.395753 -188.863322) (xy 222.370142 -188.863732) (xy 222.342889 -188.863224)
			(xy 222.288937 -188.855472) (xy 222.236637 -188.840121) (xy 222.187055 -188.817482) (xy 222.141199 -188.788017)
			(xy 222.100004 -188.752325) (xy 222.064308 -188.711134) (xy 222.034838 -188.665282) (xy 222.012194 -188.615702)
			(xy 221.996837 -188.563404) (xy 221.989079 -188.509453) (xy 206.908394 -188.509453) (xy 206.896493 -188.519357)
			(xy 206.848887 -188.548411) (xy 206.797558 -188.570223) (xy 206.743601 -188.584329) (xy 206.688164 -188.590429)
			(xy 206.63243 -188.588392) (xy 206.577587 -188.578262) (xy 206.524803 -188.560255) (xy 206.475203 -188.534754)
			(xy 206.429845 -188.502303) (xy 206.389696 -188.463594) (xy 206.35561 -188.419451) (xy 206.328314 -188.370816)
			(xy 206.308391 -188.318725) (xy 206.296265 -188.264288) (xy 206.292194 -188.208666) (xy 189.794375 -188.208666)
			(xy 189.629208 -189.107318) (xy 217.854528 -189.107318) (xy 217.858599 -189.051696) (xy 217.870725 -188.997259)
			(xy 217.890648 -188.945168) (xy 217.917944 -188.896533) (xy 217.95203 -188.85239) (xy 217.992179 -188.813681)
			(xy 218.037537 -188.78123) (xy 218.087137 -188.755729) (xy 218.139921 -188.737722) (xy 218.194764 -188.727592)
			(xy 218.250498 -188.725555) (xy 218.305935 -188.731655) (xy 218.359892 -188.745761) (xy 218.411221 -188.767573)
			(xy 218.458827 -188.796627) (xy 218.501695 -188.832302) (xy 218.538912 -188.873839) (xy 218.569685 -188.920352)
			(xy 218.593357 -188.970849) (xy 218.609425 -189.024256) (xy 218.617545 -189.079432) (xy 218.618054 -189.107318)
			(xy 218.617545 -189.135204) (xy 218.609425 -189.19038) (xy 218.593357 -189.243787) (xy 218.569685 -189.294284)
			(xy 218.538912 -189.340797) (xy 218.501695 -189.382334) (xy 218.458827 -189.418009) (xy 218.411221 -189.447063)
			(xy 218.359892 -189.468875) (xy 218.305935 -189.482981) (xy 218.250498 -189.489081) (xy 218.194764 -189.487044)
			(xy 218.139921 -189.476914) (xy 218.087137 -189.458907) (xy 218.037537 -189.433406) (xy 217.992179 -189.400955)
			(xy 217.95203 -189.362246) (xy 217.917944 -189.318103) (xy 217.890648 -189.269468) (xy 217.870725 -189.217377)
			(xy 217.858599 -189.16294) (xy 217.854528 -189.107318) (xy 189.629208 -189.107318) (xy 189.520015 -189.701424)
			(xy 206.285844 -189.701424) (xy 206.289915 -189.645802) (xy 206.302041 -189.591365) (xy 206.321964 -189.539274)
			(xy 206.34926 -189.490639) (xy 206.383346 -189.446496) (xy 206.423495 -189.407787) (xy 206.468853 -189.375336)
			(xy 206.518453 -189.349835) (xy 206.571237 -189.331828) (xy 206.62608 -189.321698) (xy 206.681814 -189.319661)
			(xy 206.737251 -189.325761) (xy 206.791208 -189.339867) (xy 206.842537 -189.361679) (xy 206.890143 -189.390733)
			(xy 206.933011 -189.426408) (xy 206.970228 -189.467945) (xy 207.001001 -189.514458) (xy 207.024673 -189.564955)
			(xy 207.040741 -189.618362) (xy 207.048861 -189.673538) (xy 207.04937 -189.701424) (xy 207.048861 -189.72931)
			(xy 207.042835 -189.770258) (xy 209.545428 -189.770258) (xy 209.545914 -189.743007) (xy 209.55367 -189.689059)
			(xy 209.569025 -189.636764) (xy 209.591667 -189.587187) (xy 209.621133 -189.541337) (xy 209.656824 -189.500146)
			(xy 209.698015 -189.464455) (xy 209.743865 -189.434989) (xy 209.793442 -189.412347) (xy 209.845737 -189.396992)
			(xy 209.899685 -189.389236) (xy 209.954187 -189.389236) (xy 210.008135 -189.396992) (xy 210.06043 -189.412347)
			(xy 210.110007 -189.434989) (xy 210.155857 -189.464455) (xy 210.197048 -189.500146) (xy 210.232739 -189.541337)
			(xy 210.262205 -189.587187) (xy 210.284847 -189.636764) (xy 210.292273 -189.662054) (xy 212.592918 -189.662054)
			(xy 212.596989 -189.606432) (xy 212.609115 -189.551995) (xy 212.629038 -189.499904) (xy 212.656334 -189.451269)
			(xy 212.69042 -189.407126) (xy 212.730569 -189.368417) (xy 212.775927 -189.335966) (xy 212.825527 -189.310465)
			(xy 212.878311 -189.292458) (xy 212.933154 -189.282328) (xy 212.988888 -189.280291) (xy 213.044325 -189.286391)
			(xy 213.098282 -189.300497) (xy 213.149611 -189.322309) (xy 213.197217 -189.351363) (xy 213.240085 -189.387038)
			(xy 213.277302 -189.428575) (xy 213.308075 -189.475088) (xy 213.331747 -189.525585) (xy 213.347815 -189.578992)
			(xy 213.355935 -189.634168) (xy 213.356444 -189.662054) (xy 216.656918 -189.662054) (xy 216.660989 -189.606432)
			(xy 216.673115 -189.551995) (xy 216.693038 -189.499904) (xy 216.720334 -189.451269) (xy 216.75442 -189.407126)
			(xy 216.794569 -189.368417) (xy 216.839927 -189.335966) (xy 216.889527 -189.310465) (xy 216.942311 -189.292458)
			(xy 216.997154 -189.282328) (xy 217.052888 -189.280291) (xy 217.108325 -189.286391) (xy 217.162282 -189.300497)
			(xy 217.213611 -189.322309) (xy 217.261217 -189.351363) (xy 217.304085 -189.387038) (xy 217.341302 -189.428575)
			(xy 217.372075 -189.475088) (xy 217.395747 -189.525585) (xy 217.411815 -189.578992) (xy 217.419935 -189.634168)
			(xy 217.420444 -189.662054) (xy 217.419935 -189.68994) (xy 217.411815 -189.745116) (xy 217.395747 -189.798523)
			(xy 217.390779 -189.80912) (xy 246.874282 -189.80912) (xy 246.878353 -189.753498) (xy 246.890479 -189.699061)
			(xy 246.910402 -189.64697) (xy 246.937698 -189.598335) (xy 246.971784 -189.554192) (xy 247.011933 -189.515483)
			(xy 247.057291 -189.483032) (xy 247.106891 -189.457531) (xy 247.159675 -189.439524) (xy 247.214518 -189.429394)
			(xy 247.270252 -189.427357) (xy 247.325689 -189.433457) (xy 247.379646 -189.447563) (xy 247.430975 -189.469375)
			(xy 247.478581 -189.498429) (xy 247.521449 -189.534104) (xy 247.558666 -189.575641) (xy 247.589439 -189.622154)
			(xy 247.613111 -189.672651) (xy 247.629179 -189.726058) (xy 247.637299 -189.781234) (xy 247.637808 -189.80912)
			(xy 247.637299 -189.837006) (xy 247.629179 -189.892182) (xy 247.613111 -189.945589) (xy 247.589439 -189.996086)
			(xy 247.558666 -190.042599) (xy 247.521449 -190.084136) (xy 247.478581 -190.119811) (xy 247.430975 -190.148865)
			(xy 247.379646 -190.170677) (xy 247.325689 -190.184783) (xy 247.270252 -190.190883) (xy 247.214518 -190.188846)
			(xy 247.159675 -190.178716) (xy 247.106891 -190.160709) (xy 247.057291 -190.135208) (xy 247.011933 -190.102757)
			(xy 246.971784 -190.064048) (xy 246.937698 -190.019905) (xy 246.910402 -189.97127) (xy 246.890479 -189.919179)
			(xy 246.878353 -189.864742) (xy 246.874282 -189.80912) (xy 217.390779 -189.80912) (xy 217.372075 -189.84902)
			(xy 217.341302 -189.895533) (xy 217.304085 -189.93707) (xy 217.261217 -189.972745) (xy 217.213611 -190.001799)
			(xy 217.162282 -190.023611) (xy 217.108325 -190.037717) (xy 217.052888 -190.043817) (xy 216.997154 -190.04178)
			(xy 216.942311 -190.03165) (xy 216.889527 -190.013643) (xy 216.839927 -189.988142) (xy 216.794569 -189.955691)
			(xy 216.75442 -189.916982) (xy 216.720334 -189.872839) (xy 216.693038 -189.824204) (xy 216.673115 -189.772113)
			(xy 216.660989 -189.717676) (xy 216.656918 -189.662054) (xy 213.356444 -189.662054) (xy 213.355935 -189.68994)
			(xy 213.347815 -189.745116) (xy 213.331747 -189.798523) (xy 213.308075 -189.84902) (xy 213.277302 -189.895533)
			(xy 213.240085 -189.93707) (xy 213.197217 -189.972745) (xy 213.149611 -190.001799) (xy 213.098282 -190.023611)
			(xy 213.044325 -190.037717) (xy 212.988888 -190.043817) (xy 212.933154 -190.04178) (xy 212.878311 -190.03165)
			(xy 212.825527 -190.013643) (xy 212.775927 -189.988142) (xy 212.730569 -189.955691) (xy 212.69042 -189.916982)
			(xy 212.656334 -189.872839) (xy 212.629038 -189.824204) (xy 212.609115 -189.772113) (xy 212.596989 -189.717676)
			(xy 212.592918 -189.662054) (xy 210.292273 -189.662054) (xy 210.300202 -189.689059) (xy 210.307958 -189.743007)
			(xy 210.308444 -189.770258) (xy 210.308444 -189.770512) (xy 210.307938 -189.7986) (xy 210.299678 -189.854166)
			(xy 210.283369 -189.907922) (xy 210.259362 -189.95871) (xy 210.244182 -189.982348) (xy 210.236955 -189.993771)
			(xy 210.228304 -190.019373) (xy 210.226688 -190.046349) (xy 210.232221 -190.072801) (xy 210.244513 -190.096868)
			(xy 210.2627 -190.116856) (xy 210.285503 -190.13136) (xy 210.298284 -190.135764) (xy 210.323855 -190.144172)
			(xy 210.372506 -190.167208) (xy 210.417433 -190.196857) (xy 210.448282 -190.224156) (xy 221.65005 -190.224156)
			(xy 221.654121 -190.168534) (xy 221.666247 -190.114097) (xy 221.68617 -190.062006) (xy 221.713466 -190.013371)
			(xy 221.747552 -189.969228) (xy 221.787701 -189.930519) (xy 221.833059 -189.898068) (xy 221.882659 -189.872567)
			(xy 221.935443 -189.85456) (xy 221.990286 -189.84443) (xy 222.04602 -189.842393) (xy 222.101457 -189.848493)
			(xy 222.155414 -189.862599) (xy 222.206743 -189.884411) (xy 222.254349 -189.913465) (xy 222.297217 -189.94914)
			(xy 222.334434 -189.990677) (xy 222.365207 -190.03719) (xy 222.388879 -190.087687) (xy 222.404947 -190.141094)
			(xy 222.413067 -190.19627) (xy 222.413576 -190.224156) (xy 222.413067 -190.252042) (xy 222.408424 -190.283592)
			(xy 223.43186 -190.283592) (xy 223.435931 -190.22797) (xy 223.448057 -190.173533) (xy 223.46798 -190.121442)
			(xy 223.495276 -190.072807) (xy 223.529362 -190.028664) (xy 223.569511 -189.989955) (xy 223.614869 -189.957504)
			(xy 223.664469 -189.932003) (xy 223.717253 -189.913996) (xy 223.772096 -189.903866) (xy 223.82783 -189.901829)
			(xy 223.883267 -189.907929) (xy 223.937224 -189.922035) (xy 223.988553 -189.943847) (xy 224.036159 -189.972901)
			(xy 224.079027 -190.008576) (xy 224.116244 -190.050113) (xy 224.147017 -190.096626) (xy 224.170689 -190.147123)
			(xy 224.186757 -190.20053) (xy 224.194877 -190.255706) (xy 224.195386 -190.283592) (xy 224.194877 -190.311478)
			(xy 224.186757 -190.366654) (xy 224.170689 -190.420061) (xy 224.147017 -190.470558) (xy 224.116244 -190.517071)
			(xy 224.079027 -190.558608) (xy 224.036159 -190.594283) (xy 223.988553 -190.623337) (xy 223.937224 -190.645149)
			(xy 223.883267 -190.659255) (xy 223.82783 -190.665355) (xy 223.772096 -190.663318) (xy 223.717253 -190.653188)
			(xy 223.664469 -190.635181) (xy 223.614869 -190.60968) (xy 223.569511 -190.577229) (xy 223.529362 -190.53852)
			(xy 223.495276 -190.494377) (xy 223.46798 -190.445742) (xy 223.448057 -190.393651) (xy 223.435931 -190.339214)
			(xy 223.43186 -190.283592) (xy 222.408424 -190.283592) (xy 222.404947 -190.307218) (xy 222.388879 -190.360625)
			(xy 222.365207 -190.411122) (xy 222.334434 -190.457635) (xy 222.297217 -190.499172) (xy 222.254349 -190.534847)
			(xy 222.206743 -190.563901) (xy 222.155414 -190.585713) (xy 222.101457 -190.599819) (xy 222.04602 -190.605919)
			(xy 221.990286 -190.603882) (xy 221.935443 -190.593752) (xy 221.882659 -190.575745) (xy 221.833059 -190.550244)
			(xy 221.787701 -190.517793) (xy 221.747552 -190.479084) (xy 221.713466 -190.434941) (xy 221.68617 -190.386306)
			(xy 221.666247 -190.334215) (xy 221.654121 -190.279778) (xy 221.65005 -190.224156) (xy 210.448282 -190.224156)
			(xy 210.457744 -190.232529) (xy 210.492638 -190.273517) (xy 210.52142 -190.319004) (xy 210.543519 -190.368087)
			(xy 210.558496 -190.41979) (xy 210.566052 -190.473086) (xy 210.566508 -190.5) (xy 210.566022 -190.527251)
			(xy 210.558266 -190.581199) (xy 210.542911 -190.633494) (xy 210.520269 -190.683071) (xy 210.51174 -190.696342)
			(xy 257.043426 -190.696342) (xy 257.047497 -190.64072) (xy 257.059623 -190.586283) (xy 257.079546 -190.534192)
			(xy 257.106842 -190.485557) (xy 257.140928 -190.441414) (xy 257.181077 -190.402705) (xy 257.226435 -190.370254)
			(xy 257.276035 -190.344753) (xy 257.328819 -190.326746) (xy 257.383662 -190.316616) (xy 257.439396 -190.314579)
			(xy 257.494833 -190.320679) (xy 257.54879 -190.334785) (xy 257.600119 -190.356597) (xy 257.647725 -190.385651)
			(xy 257.690593 -190.421326) (xy 257.72781 -190.462863) (xy 257.758583 -190.509376) (xy 257.782255 -190.559873)
			(xy 257.798323 -190.61328) (xy 257.806443 -190.668456) (xy 257.806952 -190.696342) (xy 257.806443 -190.724228)
			(xy 257.798323 -190.779404) (xy 257.782255 -190.832811) (xy 257.758583 -190.883308) (xy 257.749187 -190.89751)
			(xy 258.193792 -190.89751) (xy 258.197863 -190.841888) (xy 258.209989 -190.787451) (xy 258.229912 -190.73536)
			(xy 258.257208 -190.686725) (xy 258.291294 -190.642582) (xy 258.331443 -190.603873) (xy 258.376801 -190.571422)
			(xy 258.426401 -190.545921) (xy 258.479185 -190.527914) (xy 258.534028 -190.517784) (xy 258.589762 -190.515747)
			(xy 258.645199 -190.521847) (xy 258.699156 -190.535953) (xy 258.750485 -190.557765) (xy 258.798091 -190.586819)
			(xy 258.840959 -190.622494) (xy 258.878176 -190.664031) (xy 258.908949 -190.710544) (xy 258.932621 -190.761041)
			(xy 258.948689 -190.814448) (xy 258.956809 -190.869624) (xy 258.957318 -190.89751) (xy 258.956809 -190.925396)
			(xy 258.948689 -190.980572) (xy 258.932621 -191.033979) (xy 258.908949 -191.084476) (xy 258.878176 -191.130989)
			(xy 258.840959 -191.172526) (xy 258.798091 -191.208201) (xy 258.750485 -191.237255) (xy 258.699156 -191.259067)
			(xy 258.645199 -191.273173) (xy 258.589762 -191.279273) (xy 258.534028 -191.277236) (xy 258.479185 -191.267106)
			(xy 258.426401 -191.249099) (xy 258.376801 -191.223598) (xy 258.331443 -191.191147) (xy 258.291294 -191.152438)
			(xy 258.257208 -191.108295) (xy 258.229912 -191.05966) (xy 258.209989 -191.007569) (xy 258.197863 -190.953132)
			(xy 258.193792 -190.89751) (xy 257.749187 -190.89751) (xy 257.72781 -190.929821) (xy 257.690593 -190.971358)
			(xy 257.647725 -191.007033) (xy 257.600119 -191.036087) (xy 257.54879 -191.057899) (xy 257.494833 -191.072005)
			(xy 257.439396 -191.078105) (xy 257.383662 -191.076068) (xy 257.328819 -191.065938) (xy 257.276035 -191.047931)
			(xy 257.226435 -191.02243) (xy 257.181077 -190.989979) (xy 257.140928 -190.95127) (xy 257.106842 -190.907127)
			(xy 257.079546 -190.858492) (xy 257.059623 -190.806401) (xy 257.047497 -190.751964) (xy 257.043426 -190.696342)
			(xy 210.51174 -190.696342) (xy 210.490803 -190.728921) (xy 210.455112 -190.770112) (xy 210.413921 -190.805803)
			(xy 210.368071 -190.835269) (xy 210.318494 -190.857911) (xy 210.266199 -190.873266) (xy 210.212251 -190.881022)
			(xy 210.157749 -190.881022) (xy 210.103801 -190.873266) (xy 210.051506 -190.857911) (xy 210.001929 -190.835269)
			(xy 209.956079 -190.805803) (xy 209.914888 -190.770112) (xy 209.879197 -190.728921) (xy 209.849731 -190.683071)
			(xy 209.827089 -190.633494) (xy 209.811734 -190.581199) (xy 209.803978 -190.527251) (xy 209.803492 -190.5)
			(xy 209.803492 -190.499746) (xy 209.80402 -190.471659) (xy 209.812272 -190.416094) (xy 209.828574 -190.362337)
			(xy 209.852576 -190.311548) (xy 209.867754 -190.28791) (xy 209.874891 -190.276436) (xy 209.883546 -190.250851)
			(xy 209.88517 -190.223891) (xy 209.87965 -190.197452) (xy 209.867375 -190.173393) (xy 209.849207 -190.153408)
			(xy 209.826424 -190.138902) (xy 209.813652 -190.134494) (xy 209.788086 -190.126073) (xy 209.739439 -190.103035)
			(xy 209.694516 -190.073385) (xy 209.654207 -190.037713) (xy 209.619315 -189.996727) (xy 209.590532 -189.951243)
			(xy 209.568431 -189.902163) (xy 209.55345 -189.850464) (xy 209.545888 -189.797171) (xy 209.545428 -189.770258)
			(xy 207.042835 -189.770258) (xy 207.040741 -189.784486) (xy 207.024673 -189.837893) (xy 207.001001 -189.88839)
			(xy 206.970228 -189.934903) (xy 206.933011 -189.97644) (xy 206.890143 -190.012115) (xy 206.842537 -190.041169)
			(xy 206.791208 -190.062981) (xy 206.737251 -190.077087) (xy 206.681814 -190.083187) (xy 206.62608 -190.08115)
			(xy 206.571237 -190.07102) (xy 206.518453 -190.053013) (xy 206.468853 -190.027512) (xy 206.423495 -189.995061)
			(xy 206.383346 -189.956352) (xy 206.34926 -189.912209) (xy 206.321964 -189.863574) (xy 206.302041 -189.811483)
			(xy 206.289915 -189.757046) (xy 206.285844 -189.701424) (xy 189.520015 -189.701424) (xy 189.266663 -191.079882)
			(xy 208.444336 -191.079882) (xy 208.448407 -191.02426) (xy 208.460533 -190.969823) (xy 208.480456 -190.917732)
			(xy 208.507752 -190.869097) (xy 208.541838 -190.824954) (xy 208.581987 -190.786245) (xy 208.627345 -190.753794)
			(xy 208.676945 -190.728293) (xy 208.729729 -190.710286) (xy 208.784572 -190.700156) (xy 208.840306 -190.698119)
			(xy 208.895743 -190.704219) (xy 208.9497 -190.718325) (xy 209.001029 -190.740137) (xy 209.048635 -190.769191)
			(xy 209.091503 -190.804866) (xy 209.12872 -190.846403) (xy 209.159493 -190.892916) (xy 209.183165 -190.943413)
			(xy 209.199233 -190.99682) (xy 209.207353 -191.051996) (xy 209.207862 -191.079882) (xy 209.207353 -191.107768)
			(xy 209.199233 -191.162944) (xy 209.183165 -191.216351) (xy 209.159493 -191.266848) (xy 209.12872 -191.313361)
			(xy 209.116933 -191.326516) (xy 218.932504 -191.326516) (xy 218.936575 -191.270894) (xy 218.948701 -191.216457)
			(xy 218.968624 -191.164366) (xy 218.99592 -191.115731) (xy 219.030006 -191.071588) (xy 219.070155 -191.032879)
			(xy 219.115513 -191.000428) (xy 219.165113 -190.974927) (xy 219.217897 -190.95692) (xy 219.27274 -190.94679)
			(xy 219.328474 -190.944753) (xy 219.383911 -190.950853) (xy 219.437868 -190.964959) (xy 219.489197 -190.986771)
			(xy 219.536803 -191.015825) (xy 219.579671 -191.0515) (xy 219.616888 -191.093037) (xy 219.647661 -191.13955)
			(xy 219.66839 -191.183768) (xy 221.544894 -191.183768) (xy 221.548965 -191.128146) (xy 221.561091 -191.073709)
			(xy 221.581014 -191.021618) (xy 221.60831 -190.972983) (xy 221.642396 -190.92884) (xy 221.682545 -190.890131)
			(xy 221.727903 -190.85768) (xy 221.777503 -190.832179) (xy 221.830287 -190.814172) (xy 221.88513 -190.804042)
			(xy 221.940864 -190.802005) (xy 221.996301 -190.808105) (xy 222.050258 -190.822211) (xy 222.101587 -190.844023)
			(xy 222.149193 -190.873077) (xy 222.192061 -190.908752) (xy 222.229278 -190.950289) (xy 222.260051 -190.996802)
			(xy 222.283723 -191.047299) (xy 222.299791 -191.100706) (xy 222.307911 -191.155882) (xy 222.30842 -191.183768)
			(xy 222.307911 -191.211654) (xy 222.299791 -191.26683) (xy 222.283723 -191.320237) (xy 222.260051 -191.370734)
			(xy 222.229278 -191.417247) (xy 222.229098 -191.417448) (xy 223.106232 -191.417448) (xy 223.110303 -191.361826)
			(xy 223.122429 -191.307389) (xy 223.142352 -191.255298) (xy 223.169648 -191.206663) (xy 223.203734 -191.16252)
			(xy 223.243883 -191.123811) (xy 223.289241 -191.09136) (xy 223.338841 -191.065859) (xy 223.391625 -191.047852)
			(xy 223.446468 -191.037722) (xy 223.502202 -191.035685) (xy 223.557639 -191.041785) (xy 223.611596 -191.055891)
			(xy 223.662925 -191.077703) (xy 223.710531 -191.106757) (xy 223.753399 -191.142432) (xy 223.790616 -191.183969)
			(xy 223.821389 -191.230482) (xy 223.845061 -191.280979) (xy 223.861129 -191.334386) (xy 223.869249 -191.389562)
			(xy 223.869758 -191.417448) (xy 223.869249 -191.445334) (xy 223.861129 -191.50051) (xy 223.845061 -191.553917)
			(xy 223.821389 -191.604414) (xy 223.790616 -191.650927) (xy 223.787235 -191.6547) (xy 260.878564 -191.6547)
			(xy 260.882652 -191.56889) (xy 260.894878 -191.483857) (xy 260.915131 -191.400372) (xy 260.943228 -191.319189)
			(xy 260.978915 -191.241045) (xy 261.021869 -191.166647) (xy 261.071699 -191.096669) (xy 261.127956 -191.031745)
			(xy 261.19013 -190.972462) (xy 261.257657 -190.919357) (xy 261.329926 -190.872911) (xy 261.406284 -190.833546)
			(xy 261.486037 -190.801617) (xy 261.568464 -190.777413) (xy 261.652818 -190.761154) (xy 261.738336 -190.752987)
			(xy 261.78129 -190.752476) (xy 261.823257 -190.752953) (xy 261.906829 -190.760748) (xy 261.989316 -190.776271)
			(xy 262.070004 -190.799389) (xy 262.148197 -190.8299) (xy 262.223218 -190.867543) (xy 262.294418 -190.91199)
			(xy 262.361182 -190.962858) (xy 262.422933 -191.019708) (xy 262.479137 -191.082047) (xy 262.529308 -191.149336)
			(xy 262.573012 -191.220995) (xy 262.609872 -191.296403) (xy 262.639569 -191.374909) (xy 262.661845 -191.455834)
			(xy 262.67651 -191.538477) (xy 262.68045 -191.580262) (xy 262.681466 -191.593724) (xy 262.696706 -191.616076)
			(xy 262.799322 -191.66586) (xy 262.826246 -191.664082) (xy 262.837422 -191.656716) (xy 262.860872 -191.641879)
			(xy 262.911162 -191.618424) (xy 262.964321 -191.60251) (xy 263.019227 -191.594473) (xy 263.046972 -191.593978)
			(xy 263.047226 -191.593978) (xy 263.076379 -191.594536) (xy 263.134006 -191.603412) (xy 263.189611 -191.620953)
			(xy 263.2419 -191.64675) (xy 263.289655 -191.680203) (xy 263.331763 -191.720533) (xy 263.367245 -191.7668)
			(xy 263.381744 -191.792098) (xy 263.386824 -191.801496) (xy 263.403842 -191.81445) (xy 263.497314 -191.83731)
			(xy 263.518396 -191.8335) (xy 263.527286 -191.827658) (xy 263.550926 -191.812478) (xy 263.601706 -191.788451)
			(xy 263.655463 -191.772139) (xy 263.711033 -191.763895) (xy 263.739122 -191.763396) (xy 263.739376 -191.763396)
			(xy 263.76663 -191.76385) (xy 263.820584 -191.771604) (xy 263.872886 -191.786958) (xy 263.922469 -191.809599)
			(xy 263.968326 -191.839067) (xy 264.009522 -191.874761) (xy 264.045218 -191.915955) (xy 264.074689 -191.96181)
			(xy 264.097333 -192.011392) (xy 264.112691 -192.063692) (xy 264.120449 -192.117646) (xy 264.120449 -192.172154)
			(xy 264.112691 -192.226108) (xy 264.097333 -192.278408) (xy 264.074689 -192.32799) (xy 264.045218 -192.373845)
			(xy 264.009522 -192.415039) (xy 263.968326 -192.450733) (xy 263.922469 -192.480201) (xy 263.872886 -192.502842)
			(xy 263.820584 -192.518196) (xy 263.76663 -192.52595) (xy 263.739376 -192.526412) (xy 263.710223 -192.525857)
			(xy 263.652596 -192.516982) (xy 263.59699 -192.499441) (xy 263.544701 -192.473643) (xy 263.496946 -192.440189)
			(xy 263.454838 -192.399859) (xy 263.419356 -192.353591) (xy 263.404858 -192.328292) (xy 263.399778 -192.318894)
			(xy 263.38276 -192.30594) (xy 263.289288 -192.28308) (xy 263.268206 -192.28689) (xy 263.259316 -192.292732)
			(xy 263.235675 -192.30791) (xy 263.184895 -192.331938) (xy 263.131138 -192.348251) (xy 263.075569 -192.356495)
			(xy 263.04748 -192.356994) (xy 263.047226 -192.356994) (xy 263.017819 -192.356399) (xy 262.959702 -192.34737)
			(xy 262.903657 -192.329536) (xy 262.85101 -192.30332) (xy 262.803004 -192.269341) (xy 262.760777 -192.228403)
			(xy 262.725325 -192.181474) (xy 262.71093 -192.155826) (xy 262.704834 -192.144142) (xy 262.681974 -192.129664)
			(xy 262.581136 -192.125346) (xy 262.572422 -192.125342) (xy 262.555791 -192.13051) (xy 262.541827 -192.140915)
			(xy 262.536686 -192.147952) (xy 262.536432 -192.147952) (xy 262.536432 -192.14846) (xy 262.513764 -192.182237)
			(xy 262.463287 -192.246035) (xy 262.407273 -192.30503) (xy 262.346176 -192.358743) (xy 262.280491 -192.406739)
			(xy 262.210754 -192.448628) (xy 262.137529 -192.48407) (xy 262.06141 -192.512776) (xy 261.983017 -192.534515)
			(xy 261.902986 -192.549109) (xy 261.821966 -192.556439) (xy 261.78129 -192.556892) (xy 261.738336 -192.556413)
			(xy 261.652818 -192.548246) (xy 261.568464 -192.531987) (xy 261.486037 -192.507783) (xy 261.406284 -192.475854)
			(xy 261.329926 -192.436489) (xy 261.257657 -192.390043) (xy 261.19013 -192.336938) (xy 261.127956 -192.277655)
			(xy 261.071699 -192.212731) (xy 261.021869 -192.142753) (xy 260.978915 -192.068355) (xy 260.943228 -191.990211)
			(xy 260.915131 -191.909028) (xy 260.894878 -191.825543) (xy 260.882652 -191.74051) (xy 260.878564 -191.6547)
			(xy 223.787235 -191.6547) (xy 223.753399 -191.692464) (xy 223.710531 -191.728139) (xy 223.662925 -191.757193)
			(xy 223.611596 -191.779005) (xy 223.557639 -191.793111) (xy 223.502202 -191.799211) (xy 223.446468 -191.797174)
			(xy 223.391625 -191.787044) (xy 223.338841 -191.769037) (xy 223.289241 -191.743536) (xy 223.243883 -191.711085)
			(xy 223.203734 -191.672376) (xy 223.169648 -191.628233) (xy 223.142352 -191.579598) (xy 223.122429 -191.527507)
			(xy 223.110303 -191.47307) (xy 223.106232 -191.417448) (xy 222.229098 -191.417448) (xy 222.192061 -191.458784)
			(xy 222.149193 -191.494459) (xy 222.101587 -191.523513) (xy 222.050258 -191.545325) (xy 221.996301 -191.559431)
			(xy 221.940864 -191.565531) (xy 221.88513 -191.563494) (xy 221.830287 -191.553364) (xy 221.777503 -191.535357)
			(xy 221.727903 -191.509856) (xy 221.682545 -191.477405) (xy 221.642396 -191.438696) (xy 221.60831 -191.394553)
			(xy 221.581014 -191.345918) (xy 221.561091 -191.293827) (xy 221.548965 -191.23939) (xy 221.544894 -191.183768)
			(xy 219.66839 -191.183768) (xy 219.671333 -191.190047) (xy 219.687401 -191.243454) (xy 219.695521 -191.29863)
			(xy 219.69603 -191.326516) (xy 219.695521 -191.354402) (xy 219.687401 -191.409578) (xy 219.671333 -191.462985)
			(xy 219.647661 -191.513482) (xy 219.616888 -191.559995) (xy 219.579671 -191.601532) (xy 219.536803 -191.637207)
			(xy 219.489197 -191.666261) (xy 219.437868 -191.688073) (xy 219.383911 -191.702179) (xy 219.328474 -191.708279)
			(xy 219.27274 -191.706242) (xy 219.217897 -191.696112) (xy 219.165113 -191.678105) (xy 219.115513 -191.652604)
			(xy 219.070155 -191.620153) (xy 219.030006 -191.581444) (xy 218.99592 -191.537301) (xy 218.968624 -191.488666)
			(xy 218.948701 -191.436575) (xy 218.936575 -191.382138) (xy 218.932504 -191.326516) (xy 209.116933 -191.326516)
			(xy 209.091503 -191.354898) (xy 209.048635 -191.390573) (xy 209.001029 -191.419627) (xy 208.9497 -191.441439)
			(xy 208.895743 -191.455545) (xy 208.840306 -191.461645) (xy 208.784572 -191.459608) (xy 208.729729 -191.449478)
			(xy 208.676945 -191.431471) (xy 208.627345 -191.40597) (xy 208.581987 -191.373519) (xy 208.541838 -191.33481)
			(xy 208.507752 -191.290667) (xy 208.480456 -191.242032) (xy 208.460533 -191.189941) (xy 208.448407 -191.135504)
			(xy 208.444336 -191.079882) (xy 189.266663 -191.079882) (xy 189.054532 -192.234058) (xy 207.228692 -192.234058)
			(xy 207.232763 -192.178436) (xy 207.244889 -192.123999) (xy 207.264812 -192.071908) (xy 207.292108 -192.023273)
			(xy 207.326194 -191.97913) (xy 207.366343 -191.940421) (xy 207.411701 -191.90797) (xy 207.461301 -191.882469)
			(xy 207.514085 -191.864462) (xy 207.568928 -191.854332) (xy 207.624662 -191.852295) (xy 207.680099 -191.858395)
			(xy 207.734056 -191.872501) (xy 207.785385 -191.894313) (xy 207.832991 -191.923367) (xy 207.875859 -191.959042)
			(xy 207.913076 -192.000579) (xy 207.928571 -192.024) (xy 209.040982 -192.024) (xy 209.045053 -191.968378)
			(xy 209.057179 -191.913941) (xy 209.077102 -191.86185) (xy 209.104398 -191.813215) (xy 209.138484 -191.769072)
			(xy 209.178633 -191.730363) (xy 209.223991 -191.697912) (xy 209.273591 -191.672411) (xy 209.326375 -191.654404)
			(xy 209.381218 -191.644274) (xy 209.436952 -191.642237) (xy 209.492389 -191.648337) (xy 209.546346 -191.662443)
			(xy 209.597675 -191.684255) (xy 209.645281 -191.713309) (xy 209.688149 -191.748984) (xy 209.725366 -191.790521)
			(xy 209.756139 -191.837034) (xy 209.779811 -191.887531) (xy 209.795879 -191.940938) (xy 209.803999 -191.996114)
			(xy 209.804508 -192.024) (xy 217.803982 -192.024) (xy 217.808053 -191.968378) (xy 217.820179 -191.913941)
			(xy 217.840102 -191.86185) (xy 217.867398 -191.813215) (xy 217.901484 -191.769072) (xy 217.941633 -191.730363)
			(xy 217.986991 -191.697912) (xy 218.036591 -191.672411) (xy 218.089375 -191.654404) (xy 218.144218 -191.644274)
			(xy 218.199952 -191.642237) (xy 218.255389 -191.648337) (xy 218.309346 -191.662443) (xy 218.360675 -191.684255)
			(xy 218.408281 -191.713309) (xy 218.451149 -191.748984) (xy 218.488366 -191.790521) (xy 218.519139 -191.837034)
			(xy 218.542811 -191.887531) (xy 218.558879 -191.940938) (xy 218.566999 -191.996114) (xy 218.567508 -192.024)
			(xy 218.566999 -192.051886) (xy 218.558879 -192.107062) (xy 218.542811 -192.160469) (xy 218.519139 -192.210966)
			(xy 218.488366 -192.257479) (xy 218.451149 -192.299016) (xy 218.408281 -192.334691) (xy 218.370904 -192.357502)
			(xy 220.6023 -192.357502) (xy 220.606371 -192.30188) (xy 220.618497 -192.247443) (xy 220.63842 -192.195352)
			(xy 220.665716 -192.146717) (xy 220.699802 -192.102574) (xy 220.739951 -192.063865) (xy 220.785309 -192.031414)
			(xy 220.834909 -192.005913) (xy 220.887693 -191.987906) (xy 220.942536 -191.977776) (xy 220.99827 -191.975739)
			(xy 221.053707 -191.981839) (xy 221.107664 -191.995945) (xy 221.158993 -192.017757) (xy 221.206599 -192.046811)
			(xy 221.249467 -192.082486) (xy 221.286684 -192.124023) (xy 221.317457 -192.170536) (xy 221.341129 -192.221033)
			(xy 221.357197 -192.27444) (xy 221.364038 -192.320926) (xy 254.316736 -192.320926) (xy 254.320807 -192.265304)
			(xy 254.332933 -192.210867) (xy 254.352856 -192.158776) (xy 254.380152 -192.110141) (xy 254.414238 -192.065998)
			(xy 254.454387 -192.027289) (xy 254.499745 -191.994838) (xy 254.549345 -191.969337) (xy 254.602129 -191.95133)
			(xy 254.656972 -191.9412) (xy 254.712706 -191.939163) (xy 254.768143 -191.945263) (xy 254.8221 -191.959369)
			(xy 254.873429 -191.981181) (xy 254.921035 -192.010235) (xy 254.963903 -192.04591) (xy 255.00112 -192.087447)
			(xy 255.031893 -192.13396) (xy 255.055565 -192.184457) (xy 255.06277 -192.208404) (xy 256.958336 -192.208404)
			(xy 256.962407 -192.152782) (xy 256.974533 -192.098345) (xy 256.994456 -192.046254) (xy 257.021752 -191.997619)
			(xy 257.055838 -191.953476) (xy 257.095987 -191.914767) (xy 257.141345 -191.882316) (xy 257.190945 -191.856815)
			(xy 257.243729 -191.838808) (xy 257.298572 -191.828678) (xy 257.354306 -191.826641) (xy 257.409743 -191.832741)
			(xy 257.4637 -191.846847) (xy 257.515029 -191.868659) (xy 257.562635 -191.897713) (xy 257.605503 -191.933388)
			(xy 257.64272 -191.974925) (xy 257.673493 -192.021438) (xy 257.697165 -192.071935) (xy 257.713233 -192.125342)
			(xy 257.716448 -192.14719) (xy 259.887718 -192.14719) (xy 259.891789 -192.091568) (xy 259.903915 -192.037131)
			(xy 259.923838 -191.98504) (xy 259.951134 -191.936405) (xy 259.98522 -191.892262) (xy 260.025369 -191.853553)
			(xy 260.070727 -191.821102) (xy 260.120327 -191.795601) (xy 260.173111 -191.777594) (xy 260.227954 -191.767464)
			(xy 260.283688 -191.765427) (xy 260.339125 -191.771527) (xy 260.393082 -191.785633) (xy 260.444411 -191.807445)
			(xy 260.492017 -191.836499) (xy 260.534885 -191.872174) (xy 260.572102 -191.913711) (xy 260.602875 -191.960224)
			(xy 260.626547 -192.010721) (xy 260.642615 -192.064128) (xy 260.650735 -192.119304) (xy 260.651244 -192.14719)
			(xy 260.650735 -192.175076) (xy 260.642615 -192.230252) (xy 260.626547 -192.283659) (xy 260.602875 -192.334156)
			(xy 260.572102 -192.380669) (xy 260.534885 -192.422206) (xy 260.492017 -192.457881) (xy 260.444411 -192.486935)
			(xy 260.393082 -192.508747) (xy 260.339125 -192.522853) (xy 260.283688 -192.528953) (xy 260.227954 -192.526916)
			(xy 260.173111 -192.516786) (xy 260.120327 -192.498779) (xy 260.070727 -192.473278) (xy 260.025369 -192.440827)
			(xy 259.98522 -192.402118) (xy 259.951134 -192.357975) (xy 259.923838 -192.30934) (xy 259.903915 -192.257249)
			(xy 259.891789 -192.202812) (xy 259.887718 -192.14719) (xy 257.716448 -192.14719) (xy 257.721353 -192.180518)
			(xy 257.721862 -192.208404) (xy 257.721353 -192.23629) (xy 257.713233 -192.291466) (xy 257.697165 -192.344873)
			(xy 257.673493 -192.39537) (xy 257.64272 -192.441883) (xy 257.605503 -192.48342) (xy 257.562635 -192.519095)
			(xy 257.515029 -192.548149) (xy 257.4637 -192.569961) (xy 257.409743 -192.584067) (xy 257.354306 -192.590167)
			(xy 257.298572 -192.58813) (xy 257.243729 -192.578) (xy 257.190945 -192.559993) (xy 257.141345 -192.534492)
			(xy 257.095987 -192.502041) (xy 257.055838 -192.463332) (xy 257.021752 -192.419189) (xy 256.994456 -192.370554)
			(xy 256.974533 -192.318463) (xy 256.962407 -192.264026) (xy 256.958336 -192.208404) (xy 255.06277 -192.208404)
			(xy 255.071633 -192.237864) (xy 255.079753 -192.29304) (xy 255.080262 -192.320926) (xy 255.079753 -192.348812)
			(xy 255.071633 -192.403988) (xy 255.055565 -192.457395) (xy 255.031893 -192.507892) (xy 255.00112 -192.554405)
			(xy 254.963903 -192.595942) (xy 254.921035 -192.631617) (xy 254.873429 -192.660671) (xy 254.8221 -192.682483)
			(xy 254.768143 -192.696589) (xy 254.712706 -192.702689) (xy 254.656972 -192.700652) (xy 254.602129 -192.690522)
			(xy 254.549345 -192.672515) (xy 254.499745 -192.647014) (xy 254.454387 -192.614563) (xy 254.414238 -192.575854)
			(xy 254.380152 -192.531711) (xy 254.352856 -192.483076) (xy 254.332933 -192.430985) (xy 254.320807 -192.376548)
			(xy 254.316736 -192.320926) (xy 221.364038 -192.320926) (xy 221.365317 -192.329616) (xy 221.365826 -192.357502)
			(xy 221.365317 -192.385388) (xy 221.357197 -192.440564) (xy 221.341129 -192.493971) (xy 221.317457 -192.544468)
			(xy 221.286684 -192.590981) (xy 221.249467 -192.632518) (xy 221.206599 -192.668193) (xy 221.158993 -192.697247)
			(xy 221.107664 -192.719059) (xy 221.053707 -192.733165) (xy 220.99827 -192.739265) (xy 220.942536 -192.737228)
			(xy 220.887693 -192.727098) (xy 220.834909 -192.709091) (xy 220.785309 -192.68359) (xy 220.739951 -192.651139)
			(xy 220.699802 -192.61243) (xy 220.665716 -192.568287) (xy 220.63842 -192.519652) (xy 220.618497 -192.467561)
			(xy 220.606371 -192.413124) (xy 220.6023 -192.357502) (xy 218.370904 -192.357502) (xy 218.360675 -192.363745)
			(xy 218.309346 -192.385557) (xy 218.255389 -192.399663) (xy 218.199952 -192.405763) (xy 218.144218 -192.403726)
			(xy 218.089375 -192.393596) (xy 218.036591 -192.375589) (xy 217.986991 -192.350088) (xy 217.941633 -192.317637)
			(xy 217.901484 -192.278928) (xy 217.867398 -192.234785) (xy 217.840102 -192.18615) (xy 217.820179 -192.134059)
			(xy 217.808053 -192.079622) (xy 217.803982 -192.024) (xy 209.804508 -192.024) (xy 209.803999 -192.051886)
			(xy 209.795879 -192.107062) (xy 209.779811 -192.160469) (xy 209.756139 -192.210966) (xy 209.725366 -192.257479)
			(xy 209.688149 -192.299016) (xy 209.645281 -192.334691) (xy 209.597675 -192.363745) (xy 209.546346 -192.385557)
			(xy 209.492389 -192.399663) (xy 209.436952 -192.405763) (xy 209.381218 -192.403726) (xy 209.326375 -192.393596)
			(xy 209.273591 -192.375589) (xy 209.223991 -192.350088) (xy 209.178633 -192.317637) (xy 209.138484 -192.278928)
			(xy 209.104398 -192.234785) (xy 209.077102 -192.18615) (xy 209.057179 -192.134059) (xy 209.045053 -192.079622)
			(xy 209.040982 -192.024) (xy 207.928571 -192.024) (xy 207.943849 -192.047092) (xy 207.967521 -192.097589)
			(xy 207.983589 -192.150996) (xy 207.991709 -192.206172) (xy 207.992218 -192.234058) (xy 207.991709 -192.261944)
			(xy 207.983589 -192.31712) (xy 207.967521 -192.370527) (xy 207.943849 -192.421024) (xy 207.913076 -192.467537)
			(xy 207.875859 -192.509074) (xy 207.832991 -192.544749) (xy 207.785385 -192.573803) (xy 207.734056 -192.595615)
			(xy 207.680099 -192.609721) (xy 207.624662 -192.615821) (xy 207.568928 -192.613784) (xy 207.514085 -192.603654)
			(xy 207.461301 -192.585647) (xy 207.411701 -192.560146) (xy 207.366343 -192.527695) (xy 207.326194 -192.488986)
			(xy 207.292108 -192.444843) (xy 207.264812 -192.396208) (xy 207.244889 -192.344117) (xy 207.232763 -192.28968)
			(xy 207.228692 -192.234058) (xy 189.054532 -192.234058) (xy 188.97643 -192.659) (xy 215.390982 -192.659)
			(xy 215.395053 -192.603378) (xy 215.407179 -192.548941) (xy 215.427102 -192.49685) (xy 215.454398 -192.448215)
			(xy 215.488484 -192.404072) (xy 215.528633 -192.365363) (xy 215.573991 -192.332912) (xy 215.623591 -192.307411)
			(xy 215.676375 -192.289404) (xy 215.731218 -192.279274) (xy 215.786952 -192.277237) (xy 215.842389 -192.283337)
			(xy 215.896346 -192.297443) (xy 215.947675 -192.319255) (xy 215.995281 -192.348309) (xy 216.038149 -192.383984)
			(xy 216.075366 -192.425521) (xy 216.106139 -192.472034) (xy 216.129811 -192.522531) (xy 216.145879 -192.575938)
			(xy 216.153999 -192.631114) (xy 216.154508 -192.659) (xy 216.153999 -192.686886) (xy 216.145879 -192.742062)
			(xy 216.129811 -192.795469) (xy 216.106139 -192.845966) (xy 216.075366 -192.892479) (xy 216.038149 -192.934016)
			(xy 215.995281 -192.969691) (xy 215.947675 -192.998745) (xy 215.896346 -193.020557) (xy 215.842389 -193.034663)
			(xy 215.793886 -193.04) (xy 217.803982 -193.04) (xy 217.808053 -192.984378) (xy 217.820179 -192.929941)
			(xy 217.840102 -192.87785) (xy 217.867398 -192.829215) (xy 217.901484 -192.785072) (xy 217.941633 -192.746363)
			(xy 217.986991 -192.713912) (xy 218.036591 -192.688411) (xy 218.089375 -192.670404) (xy 218.144218 -192.660274)
			(xy 218.199952 -192.658237) (xy 218.255389 -192.664337) (xy 218.309346 -192.678443) (xy 218.360675 -192.700255)
			(xy 218.408281 -192.729309) (xy 218.451149 -192.764984) (xy 218.488366 -192.806521) (xy 218.519139 -192.853034)
			(xy 218.542811 -192.903531) (xy 218.558879 -192.956938) (xy 218.566999 -193.012114) (xy 218.567508 -193.04)
			(xy 218.566999 -193.067886) (xy 218.558879 -193.123062) (xy 218.542811 -193.176469) (xy 218.519139 -193.226966)
			(xy 218.488366 -193.273479) (xy 218.451149 -193.315016) (xy 218.408281 -193.350691) (xy 218.393379 -193.359786)
			(xy 220.426532 -193.359786) (xy 220.430603 -193.304164) (xy 220.442729 -193.249727) (xy 220.462652 -193.197636)
			(xy 220.489948 -193.149001) (xy 220.524034 -193.104858) (xy 220.564183 -193.066149) (xy 220.609541 -193.033698)
			(xy 220.659141 -193.008197) (xy 220.711925 -192.99019) (xy 220.766768 -192.98006) (xy 220.822502 -192.978023)
			(xy 220.877939 -192.984123) (xy 220.931896 -192.998229) (xy 220.943523 -193.00317) (xy 224.004884 -193.00317)
			(xy 224.008955 -192.947548) (xy 224.021081 -192.893111) (xy 224.041004 -192.84102) (xy 224.0683 -192.792385)
			(xy 224.102386 -192.748242) (xy 224.142535 -192.709533) (xy 224.187893 -192.677082) (xy 224.237493 -192.651581)
			(xy 224.290277 -192.633574) (xy 224.34512 -192.623444) (xy 224.400854 -192.621407) (xy 224.456291 -192.627507)
			(xy 224.510248 -192.641613) (xy 224.561577 -192.663425) (xy 224.609183 -192.692479) (xy 224.652051 -192.728154)
			(xy 224.689268 -192.769691) (xy 224.720041 -192.816204) (xy 224.743713 -192.866701) (xy 224.759781 -192.920108)
			(xy 224.767901 -192.975284) (xy 224.76841 -193.00317) (xy 224.767901 -193.031056) (xy 224.759781 -193.086232)
			(xy 224.743713 -193.139639) (xy 224.720041 -193.190136) (xy 224.689268 -193.236649) (xy 224.652051 -193.278186)
			(xy 224.609183 -193.313861) (xy 224.561577 -193.342915) (xy 224.510248 -193.364727) (xy 224.456291 -193.378833)
			(xy 224.400854 -193.384933) (xy 224.34512 -193.382896) (xy 224.290277 -193.372766) (xy 224.237493 -193.354759)
			(xy 224.187893 -193.329258) (xy 224.142535 -193.296807) (xy 224.102386 -193.258098) (xy 224.0683 -193.213955)
			(xy 224.041004 -193.16532) (xy 224.021081 -193.113229) (xy 224.008955 -193.058792) (xy 224.004884 -193.00317)
			(xy 220.943523 -193.00317) (xy 220.983225 -193.020041) (xy 221.030831 -193.049095) (xy 221.073699 -193.08477)
			(xy 221.110916 -193.126307) (xy 221.141689 -193.17282) (xy 221.165361 -193.223317) (xy 221.181429 -193.276724)
			(xy 221.189549 -193.3319) (xy 221.190058 -193.359786) (xy 221.189549 -193.387672) (xy 221.181429 -193.442848)
			(xy 221.165361 -193.496255) (xy 221.141689 -193.546752) (xy 221.110916 -193.593265) (xy 221.073699 -193.634802)
			(xy 221.030831 -193.670477) (xy 220.983225 -193.699531) (xy 220.931896 -193.721343) (xy 220.877939 -193.735449)
			(xy 220.822502 -193.741549) (xy 220.766768 -193.739512) (xy 220.711925 -193.729382) (xy 220.659141 -193.711375)
			(xy 220.609541 -193.685874) (xy 220.564183 -193.653423) (xy 220.524034 -193.614714) (xy 220.489948 -193.570571)
			(xy 220.462652 -193.521936) (xy 220.442729 -193.469845) (xy 220.430603 -193.415408) (xy 220.426532 -193.359786)
			(xy 218.393379 -193.359786) (xy 218.360675 -193.379745) (xy 218.309346 -193.401557) (xy 218.255389 -193.415663)
			(xy 218.199952 -193.421763) (xy 218.144218 -193.419726) (xy 218.089375 -193.409596) (xy 218.036591 -193.391589)
			(xy 217.986991 -193.366088) (xy 217.941633 -193.333637) (xy 217.901484 -193.294928) (xy 217.867398 -193.250785)
			(xy 217.840102 -193.20215) (xy 217.820179 -193.150059) (xy 217.808053 -193.095622) (xy 217.803982 -193.04)
			(xy 215.793886 -193.04) (xy 215.786952 -193.040763) (xy 215.731218 -193.038726) (xy 215.676375 -193.028596)
			(xy 215.623591 -193.010589) (xy 215.573991 -192.985088) (xy 215.528633 -192.952637) (xy 215.488484 -192.913928)
			(xy 215.454398 -192.869785) (xy 215.427102 -192.82115) (xy 215.407179 -192.769059) (xy 215.395053 -192.714622)
			(xy 215.390982 -192.659) (xy 188.97643 -192.659) (xy 188.813038 -193.548) (xy 206.281272 -193.548)
			(xy 206.285343 -193.492378) (xy 206.297469 -193.437941) (xy 206.317392 -193.38585) (xy 206.344688 -193.337215)
			(xy 206.378774 -193.293072) (xy 206.418923 -193.254363) (xy 206.464281 -193.221912) (xy 206.513881 -193.196411)
			(xy 206.566665 -193.178404) (xy 206.621508 -193.168274) (xy 206.677242 -193.166237) (xy 206.684176 -193.167)
			(xy 209.040982 -193.167) (xy 209.045053 -193.111378) (xy 209.057179 -193.056941) (xy 209.077102 -193.00485)
			(xy 209.104398 -192.956215) (xy 209.138484 -192.912072) (xy 209.178633 -192.873363) (xy 209.223991 -192.840912)
			(xy 209.273591 -192.815411) (xy 209.326375 -192.797404) (xy 209.381218 -192.787274) (xy 209.436952 -192.785237)
			(xy 209.492389 -192.791337) (xy 209.546346 -192.805443) (xy 209.597675 -192.827255) (xy 209.645281 -192.856309)
			(xy 209.688149 -192.891984) (xy 209.725366 -192.933521) (xy 209.756139 -192.980034) (xy 209.779811 -193.030531)
			(xy 209.795879 -193.083938) (xy 209.803999 -193.139114) (xy 209.804508 -193.167) (xy 209.803999 -193.194886)
			(xy 209.795879 -193.250062) (xy 209.779811 -193.303469) (xy 209.756139 -193.353966) (xy 209.725366 -193.400479)
			(xy 209.688149 -193.442016) (xy 209.645281 -193.477691) (xy 209.597675 -193.506745) (xy 209.546346 -193.528557)
			(xy 209.492389 -193.542663) (xy 209.436952 -193.548763) (xy 209.381218 -193.546726) (xy 209.326375 -193.536596)
			(xy 209.273591 -193.518589) (xy 209.223991 -193.493088) (xy 209.178633 -193.460637) (xy 209.138484 -193.421928)
			(xy 209.104398 -193.377785) (xy 209.077102 -193.32915) (xy 209.057179 -193.277059) (xy 209.045053 -193.222622)
			(xy 209.040982 -193.167) (xy 206.684176 -193.167) (xy 206.732679 -193.172337) (xy 206.786636 -193.186443)
			(xy 206.837965 -193.208255) (xy 206.885571 -193.237309) (xy 206.928439 -193.272984) (xy 206.965656 -193.314521)
			(xy 206.996429 -193.361034) (xy 207.020101 -193.411531) (xy 207.036169 -193.464938) (xy 207.044289 -193.520114)
			(xy 207.044798 -193.548) (xy 207.044289 -193.575886) (xy 207.036169 -193.631062) (xy 207.020101 -193.684469)
			(xy 206.996429 -193.734966) (xy 206.965656 -193.781479) (xy 206.928439 -193.823016) (xy 206.885571 -193.858691)
			(xy 206.837965 -193.887745) (xy 206.786636 -193.909557) (xy 206.732679 -193.923663) (xy 206.677242 -193.929763)
			(xy 206.621508 -193.927726) (xy 206.566665 -193.917596) (xy 206.513881 -193.899589) (xy 206.464281 -193.874088)
			(xy 206.418923 -193.841637) (xy 206.378774 -193.802928) (xy 206.344688 -193.758785) (xy 206.317392 -193.71015)
			(xy 206.297469 -193.658059) (xy 206.285343 -193.603622) (xy 206.281272 -193.548) (xy 188.813038 -193.548)
			(xy 188.786008 -193.695066) (xy 188.785754 -193.700908) (xy 188.792866 -193.72707) (xy 188.79439 -193.730118)
			(xy 188.80698 -193.752215) (xy 188.826829 -193.799039) (xy 188.840266 -193.848089) (xy 188.84705 -193.898492)
			(xy 188.847476 -193.92392) (xy 188.84695 -193.952699) (xy 188.8383 -194.009605) (xy 188.821199 -194.064564)
			(xy 188.798322 -194.111626) (xy 207.284318 -194.111626) (xy 207.288389 -194.056004) (xy 207.300515 -194.001567)
			(xy 207.320438 -193.949476) (xy 207.347734 -193.900841) (xy 207.38182 -193.856698) (xy 207.421969 -193.817989)
			(xy 207.467327 -193.785538) (xy 207.516927 -193.760037) (xy 207.569711 -193.74203) (xy 207.624554 -193.7319)
			(xy 207.680288 -193.729863) (xy 207.735725 -193.735963) (xy 207.789682 -193.750069) (xy 207.841011 -193.771881)
			(xy 207.888617 -193.800935) (xy 207.931485 -193.83661) (xy 207.968702 -193.878147) (xy 207.999475 -193.92466)
			(xy 208.00151 -193.929) (xy 215.390982 -193.929) (xy 215.395053 -193.873378) (xy 215.407179 -193.818941)
			(xy 215.427102 -193.76685) (xy 215.454398 -193.718215) (xy 215.488484 -193.674072) (xy 215.528633 -193.635363)
			(xy 215.573991 -193.602912) (xy 215.623591 -193.577411) (xy 215.676375 -193.559404) (xy 215.731218 -193.549274)
			(xy 215.786952 -193.547237) (xy 215.842389 -193.553337) (xy 215.896346 -193.567443) (xy 215.947675 -193.589255)
			(xy 215.995281 -193.618309) (xy 216.038149 -193.653984) (xy 216.075366 -193.695521) (xy 216.106139 -193.742034)
			(xy 216.129811 -193.792531) (xy 216.145879 -193.845938) (xy 216.153999 -193.901114) (xy 216.154508 -193.929)
			(xy 216.153999 -193.956886) (xy 216.145879 -194.012062) (xy 216.13266 -194.056) (xy 217.803982 -194.056)
			(xy 217.808053 -194.000378) (xy 217.820179 -193.945941) (xy 217.840102 -193.89385) (xy 217.867398 -193.845215)
			(xy 217.901484 -193.801072) (xy 217.941633 -193.762363) (xy 217.986991 -193.729912) (xy 218.036591 -193.704411)
			(xy 218.089375 -193.686404) (xy 218.144218 -193.676274) (xy 218.199952 -193.674237) (xy 218.255389 -193.680337)
			(xy 218.309346 -193.694443) (xy 218.360675 -193.716255) (xy 218.408281 -193.745309) (xy 218.451149 -193.780984)
			(xy 218.475669 -193.80835) (xy 241.89258 -193.80835) (xy 241.896651 -193.752728) (xy 241.908777 -193.698291)
			(xy 241.9287 -193.6462) (xy 241.955996 -193.597565) (xy 241.990082 -193.553422) (xy 242.030231 -193.514713)
			(xy 242.075589 -193.482262) (xy 242.125189 -193.456761) (xy 242.177973 -193.438754) (xy 242.232816 -193.428624)
			(xy 242.28855 -193.426587) (xy 242.343987 -193.432687) (xy 242.397944 -193.446793) (xy 242.449273 -193.468605)
			(xy 242.496879 -193.497659) (xy 242.539747 -193.533334) (xy 242.576964 -193.574871) (xy 242.607737 -193.621384)
			(xy 242.631409 -193.671881) (xy 242.647477 -193.725288) (xy 242.655597 -193.780464) (xy 242.656106 -193.80835)
			(xy 242.655597 -193.836236) (xy 242.647477 -193.891412) (xy 242.631409 -193.944819) (xy 242.630847 -193.946018)
			(xy 244.977664 -193.946018) (xy 244.981735 -193.890396) (xy 244.993861 -193.835959) (xy 245.013784 -193.783868)
			(xy 245.04108 -193.735233) (xy 245.075166 -193.69109) (xy 245.115315 -193.652381) (xy 245.160673 -193.61993)
			(xy 245.210273 -193.594429) (xy 245.263057 -193.576422) (xy 245.3179 -193.566292) (xy 245.373634 -193.564255)
			(xy 245.429071 -193.570355) (xy 245.483028 -193.584461) (xy 245.534357 -193.606273) (xy 245.581963 -193.635327)
			(xy 245.624831 -193.671002) (xy 245.662048 -193.712539) (xy 245.692821 -193.759052) (xy 245.716493 -193.809549)
			(xy 245.732561 -193.862956) (xy 245.740681 -193.918132) (xy 245.74119 -193.946018) (xy 245.740681 -193.973904)
			(xy 245.732561 -194.02908) (xy 245.716493 -194.082487) (xy 245.711883 -194.092322) (xy 250.664216 -194.092322)
			(xy 250.668287 -194.0367) (xy 250.680413 -193.982263) (xy 250.700336 -193.930172) (xy 250.727632 -193.881537)
			(xy 250.761718 -193.837394) (xy 250.801867 -193.798685) (xy 250.847225 -193.766234) (xy 250.896825 -193.740733)
			(xy 250.949609 -193.722726) (xy 251.004452 -193.712596) (xy 251.060186 -193.710559) (xy 251.115623 -193.716659)
			(xy 251.16958 -193.730765) (xy 251.220909 -193.752577) (xy 251.268515 -193.781631) (xy 251.311383 -193.817306)
			(xy 251.3486 -193.858843) (xy 251.379373 -193.905356) (xy 251.403045 -193.955853) (xy 251.419113 -194.00926)
			(xy 251.427233 -194.064436) (xy 251.427742 -194.092322) (xy 251.427233 -194.120208) (xy 251.419113 -194.175384)
			(xy 251.411778 -194.199764) (xy 253.615442 -194.199764) (xy 253.619513 -194.144142) (xy 253.631639 -194.089705)
			(xy 253.651562 -194.037614) (xy 253.678858 -193.988979) (xy 253.712944 -193.944836) (xy 253.753093 -193.906127)
			(xy 253.798451 -193.873676) (xy 253.848051 -193.848175) (xy 253.900835 -193.830168) (xy 253.955678 -193.820038)
			(xy 254.011412 -193.818001) (xy 254.066849 -193.824101) (xy 254.120806 -193.838207) (xy 254.172135 -193.860019)
			(xy 254.219741 -193.889073) (xy 254.262609 -193.924748) (xy 254.299826 -193.966285) (xy 254.330599 -194.012798)
			(xy 254.354271 -194.063295) (xy 254.370339 -194.116702) (xy 254.378459 -194.171878) (xy 254.378968 -194.199764)
			(xy 254.378459 -194.22765) (xy 254.370339 -194.282826) (xy 254.354271 -194.336233) (xy 254.330599 -194.38673)
			(xy 254.299826 -194.433243) (xy 254.262609 -194.47478) (xy 254.219741 -194.510455) (xy 254.174041 -194.538346)
			(xy 254.631442 -194.538346) (xy 254.635513 -194.482724) (xy 254.647639 -194.428287) (xy 254.667562 -194.376196)
			(xy 254.694858 -194.327561) (xy 254.728944 -194.283418) (xy 254.769093 -194.244709) (xy 254.814451 -194.212258)
			(xy 254.864051 -194.186757) (xy 254.916835 -194.16875) (xy 254.971678 -194.15862) (xy 255.027412 -194.156583)
			(xy 255.082849 -194.162683) (xy 255.136806 -194.176789) (xy 255.188135 -194.198601) (xy 255.235741 -194.227655)
			(xy 255.278609 -194.26333) (xy 255.315826 -194.304867) (xy 255.346599 -194.35138) (xy 255.370271 -194.401877)
			(xy 255.386339 -194.455284) (xy 255.394459 -194.51046) (xy 255.394968 -194.538346) (xy 255.647442 -194.538346)
			(xy 255.651513 -194.482724) (xy 255.663639 -194.428287) (xy 255.683562 -194.376196) (xy 255.710858 -194.327561)
			(xy 255.744944 -194.283418) (xy 255.785093 -194.244709) (xy 255.830451 -194.212258) (xy 255.880051 -194.186757)
			(xy 255.932835 -194.16875) (xy 255.987678 -194.15862) (xy 256.043412 -194.156583) (xy 256.098849 -194.162683)
			(xy 256.152806 -194.176789) (xy 256.204135 -194.198601) (xy 256.251741 -194.227655) (xy 256.294609 -194.26333)
			(xy 256.331826 -194.304867) (xy 256.362599 -194.35138) (xy 256.386271 -194.401877) (xy 256.402339 -194.455284)
			(xy 256.410459 -194.51046) (xy 256.410968 -194.538346) (xy 256.410459 -194.566232) (xy 256.402339 -194.621408)
			(xy 256.386271 -194.674815) (xy 256.362599 -194.725312) (xy 256.331826 -194.771825) (xy 256.294609 -194.813362)
			(xy 256.251741 -194.849037) (xy 256.204135 -194.878091) (xy 256.152806 -194.899903) (xy 256.098849 -194.914009)
			(xy 256.043412 -194.920109) (xy 255.987678 -194.918072) (xy 255.932835 -194.907942) (xy 255.880051 -194.889935)
			(xy 255.830451 -194.864434) (xy 255.785093 -194.831983) (xy 255.744944 -194.793274) (xy 255.710858 -194.749131)
			(xy 255.683562 -194.700496) (xy 255.663639 -194.648405) (xy 255.651513 -194.593968) (xy 255.647442 -194.538346)
			(xy 255.394968 -194.538346) (xy 255.394459 -194.566232) (xy 255.386339 -194.621408) (xy 255.370271 -194.674815)
			(xy 255.346599 -194.725312) (xy 255.315826 -194.771825) (xy 255.278609 -194.813362) (xy 255.235741 -194.849037)
			(xy 255.188135 -194.878091) (xy 255.136806 -194.899903) (xy 255.082849 -194.914009) (xy 255.027412 -194.920109)
			(xy 254.971678 -194.918072) (xy 254.916835 -194.907942) (xy 254.864051 -194.889935) (xy 254.814451 -194.864434)
			(xy 254.769093 -194.831983) (xy 254.728944 -194.793274) (xy 254.694858 -194.749131) (xy 254.667562 -194.700496)
			(xy 254.647639 -194.648405) (xy 254.635513 -194.593968) (xy 254.631442 -194.538346) (xy 254.174041 -194.538346)
			(xy 254.172135 -194.539509) (xy 254.120806 -194.561321) (xy 254.066849 -194.575427) (xy 254.011412 -194.581527)
			(xy 253.955678 -194.57949) (xy 253.900835 -194.56936) (xy 253.848051 -194.551353) (xy 253.798451 -194.525852)
			(xy 253.753093 -194.493401) (xy 253.712944 -194.454692) (xy 253.678858 -194.410549) (xy 253.651562 -194.361914)
			(xy 253.631639 -194.309823) (xy 253.619513 -194.255386) (xy 253.615442 -194.199764) (xy 251.411778 -194.199764)
			(xy 251.403045 -194.228791) (xy 251.379373 -194.279288) (xy 251.3486 -194.325801) (xy 251.311383 -194.367338)
			(xy 251.268515 -194.403013) (xy 251.220909 -194.432067) (xy 251.16958 -194.453879) (xy 251.115623 -194.467985)
			(xy 251.060186 -194.474085) (xy 251.004452 -194.472048) (xy 250.949609 -194.461918) (xy 250.896825 -194.443911)
			(xy 250.847225 -194.41841) (xy 250.801867 -194.385959) (xy 250.761718 -194.34725) (xy 250.727632 -194.303107)
			(xy 250.700336 -194.254472) (xy 250.680413 -194.202381) (xy 250.668287 -194.147944) (xy 250.664216 -194.092322)
			(xy 245.711883 -194.092322) (xy 245.692821 -194.132984) (xy 245.662048 -194.179497) (xy 245.624831 -194.221034)
			(xy 245.581963 -194.256709) (xy 245.534357 -194.285763) (xy 245.483028 -194.307575) (xy 245.429071 -194.321681)
			(xy 245.373634 -194.327781) (xy 245.3179 -194.325744) (xy 245.263057 -194.315614) (xy 245.210273 -194.297607)
			(xy 245.160673 -194.272106) (xy 245.115315 -194.239655) (xy 245.075166 -194.200946) (xy 245.04108 -194.156803)
			(xy 245.013784 -194.108168) (xy 244.993861 -194.056077) (xy 244.981735 -194.00164) (xy 244.977664 -193.946018)
			(xy 242.630847 -193.946018) (xy 242.607737 -193.995316) (xy 242.576964 -194.041829) (xy 242.539747 -194.083366)
			(xy 242.496879 -194.119041) (xy 242.449273 -194.148095) (xy 242.397944 -194.169907) (xy 242.343987 -194.184013)
			(xy 242.28855 -194.190113) (xy 242.232816 -194.188076) (xy 242.177973 -194.177946) (xy 242.125189 -194.159939)
			(xy 242.075589 -194.134438) (xy 242.030231 -194.101987) (xy 241.990082 -194.063278) (xy 241.955996 -194.019135)
			(xy 241.9287 -193.9705) (xy 241.908777 -193.918409) (xy 241.896651 -193.863972) (xy 241.89258 -193.80835)
			(xy 218.475669 -193.80835) (xy 218.488366 -193.822521) (xy 218.519139 -193.869034) (xy 218.542811 -193.919531)
			(xy 218.558879 -193.972938) (xy 218.566999 -194.028114) (xy 218.567508 -194.056) (xy 218.566999 -194.083886)
			(xy 218.558879 -194.139062) (xy 218.542811 -194.192469) (xy 218.519139 -194.242966) (xy 218.488366 -194.289479)
			(xy 218.451149 -194.331016) (xy 218.408281 -194.366691) (xy 218.360675 -194.395745) (xy 218.309346 -194.417557)
			(xy 218.255389 -194.431663) (xy 218.199952 -194.437763) (xy 218.144218 -194.435726) (xy 218.089375 -194.425596)
			(xy 218.036591 -194.407589) (xy 217.986991 -194.382088) (xy 217.941633 -194.349637) (xy 217.901484 -194.310928)
			(xy 217.867398 -194.266785) (xy 217.840102 -194.21815) (xy 217.820179 -194.166059) (xy 217.808053 -194.111622)
			(xy 217.803982 -194.056) (xy 216.13266 -194.056) (xy 216.129811 -194.065469) (xy 216.106139 -194.115966)
			(xy 216.075366 -194.162479) (xy 216.038149 -194.204016) (xy 215.995281 -194.239691) (xy 215.947675 -194.268745)
			(xy 215.896346 -194.290557) (xy 215.842389 -194.304663) (xy 215.786952 -194.310763) (xy 215.731218 -194.308726)
			(xy 215.676375 -194.298596) (xy 215.623591 -194.280589) (xy 215.573991 -194.255088) (xy 215.528633 -194.222637)
			(xy 215.488484 -194.183928) (xy 215.454398 -194.139785) (xy 215.427102 -194.09115) (xy 215.407179 -194.039059)
			(xy 215.395053 -193.984622) (xy 215.390982 -193.929) (xy 208.00151 -193.929) (xy 208.023147 -193.975157)
			(xy 208.039215 -194.028564) (xy 208.047335 -194.08374) (xy 208.047844 -194.111626) (xy 208.047335 -194.139512)
			(xy 208.039215 -194.194688) (xy 208.023147 -194.248095) (xy 207.999475 -194.298592) (xy 207.968702 -194.345105)
			(xy 207.931485 -194.386642) (xy 207.888617 -194.422317) (xy 207.841011 -194.451371) (xy 207.789682 -194.473183)
			(xy 207.735725 -194.487289) (xy 207.680288 -194.493389) (xy 207.624554 -194.491352) (xy 207.569711 -194.481222)
			(xy 207.516927 -194.463215) (xy 207.467327 -194.437714) (xy 207.421969 -194.405263) (xy 207.38182 -194.366554)
			(xy 207.347734 -194.322411) (xy 207.320438 -194.273776) (xy 207.300515 -194.221685) (xy 207.288389 -194.167248)
			(xy 207.284318 -194.111626) (xy 188.798322 -194.111626) (xy 188.796035 -194.116331) (xy 188.763379 -194.16373)
			(xy 188.723973 -194.205685) (xy 188.70168 -194.223894) (xy 188.701426 -194.224148) (xy 188.694919 -194.229703)
			(xy 188.685697 -194.244103) (xy 188.683392 -194.252342) (xy 188.621162 -194.591686) (xy 188.620455 -194.595496)
			(xy 223.931986 -194.595496) (xy 223.936057 -194.539874) (xy 223.948183 -194.485437) (xy 223.968106 -194.433346)
			(xy 223.995402 -194.384711) (xy 224.029488 -194.340568) (xy 224.069637 -194.301859) (xy 224.114995 -194.269408)
			(xy 224.164595 -194.243907) (xy 224.217379 -194.2259) (xy 224.272222 -194.21577) (xy 224.327956 -194.213733)
			(xy 224.383393 -194.219833) (xy 224.43735 -194.233939) (xy 224.488679 -194.255751) (xy 224.536285 -194.284805)
			(xy 224.579153 -194.32048) (xy 224.61637 -194.362017) (xy 224.647143 -194.40853) (xy 224.670815 -194.459027)
			(xy 224.675421 -194.474338) (xy 249.499626 -194.474338) (xy 249.503697 -194.418716) (xy 249.515823 -194.364279)
			(xy 249.535746 -194.312188) (xy 249.563042 -194.263553) (xy 249.597128 -194.21941) (xy 249.637277 -194.180701)
			(xy 249.682635 -194.14825) (xy 249.732235 -194.122749) (xy 249.785019 -194.104742) (xy 249.839862 -194.094612)
			(xy 249.895596 -194.092575) (xy 249.951033 -194.098675) (xy 250.00499 -194.112781) (xy 250.056319 -194.134593)
			(xy 250.103925 -194.163647) (xy 250.146793 -194.199322) (xy 250.18401 -194.240859) (xy 250.214783 -194.287372)
			(xy 250.238455 -194.337869) (xy 250.254523 -194.391276) (xy 250.262643 -194.446452) (xy 250.263152 -194.474338)
			(xy 250.262643 -194.502224) (xy 250.254523 -194.5574) (xy 250.238455 -194.610807) (xy 250.214783 -194.661304)
			(xy 250.18401 -194.707817) (xy 250.146793 -194.749354) (xy 250.103925 -194.785029) (xy 250.056319 -194.814083)
			(xy 250.00499 -194.835895) (xy 249.951033 -194.850001) (xy 249.895596 -194.856101) (xy 249.839862 -194.854064)
			(xy 249.785019 -194.843934) (xy 249.732235 -194.825927) (xy 249.682635 -194.800426) (xy 249.637277 -194.767975)
			(xy 249.597128 -194.729266) (xy 249.563042 -194.685123) (xy 249.535746 -194.636488) (xy 249.515823 -194.584397)
			(xy 249.503697 -194.52996) (xy 249.499626 -194.474338) (xy 224.675421 -194.474338) (xy 224.686883 -194.512434)
			(xy 224.695003 -194.56761) (xy 224.695512 -194.595496) (xy 224.695003 -194.623382) (xy 224.686883 -194.678558)
			(xy 224.670815 -194.731965) (xy 224.647143 -194.782462) (xy 224.61637 -194.828975) (xy 224.579153 -194.870512)
			(xy 224.536285 -194.906187) (xy 224.488679 -194.935241) (xy 224.43735 -194.957053) (xy 224.383393 -194.971159)
			(xy 224.327956 -194.977259) (xy 224.272222 -194.975222) (xy 224.217379 -194.965092) (xy 224.164595 -194.947085)
			(xy 224.114995 -194.921584) (xy 224.069637 -194.889133) (xy 224.029488 -194.850424) (xy 223.995402 -194.806281)
			(xy 223.968106 -194.757646) (xy 223.948183 -194.705555) (xy 223.936057 -194.651118) (xy 223.931986 -194.595496)
			(xy 188.620455 -194.595496) (xy 188.608716 -194.658742) (xy 188.60008 -194.705732) (xy 188.598958 -194.713979)
			(xy 188.60143 -194.730427) (xy 188.604906 -194.73799) (xy 188.608716 -194.74561) (xy 188.620908 -194.757294)
			(xy 188.628782 -194.76085) (xy 188.653153 -194.772697) (xy 188.698571 -194.802252) (xy 188.739352 -194.837935)
			(xy 188.774673 -194.879029) (xy 188.803826 -194.924706) (xy 188.826224 -194.974049) (xy 188.841416 -195.026063)
			(xy 188.849096 -195.079704) (xy 188.849508 -195.106798) (xy 188.849037 -195.134153) (xy 188.84122 -195.188303)
			(xy 188.825746 -195.240779) (xy 188.802933 -195.290507) (xy 188.780008 -195.326) (xy 210.457032 -195.326)
			(xy 210.461103 -195.270378) (xy 210.473229 -195.215941) (xy 210.493152 -195.16385) (xy 210.520448 -195.115215)
			(xy 210.554534 -195.071072) (xy 210.594683 -195.032363) (xy 210.640041 -194.999912) (xy 210.689641 -194.974411)
			(xy 210.742425 -194.956404) (xy 210.797268 -194.946274) (xy 210.853002 -194.944237) (xy 210.908439 -194.950337)
			(xy 210.962396 -194.964443) (xy 211.013725 -194.986255) (xy 211.061331 -195.015309) (xy 211.104199 -195.050984)
			(xy 211.141416 -195.092521) (xy 211.172189 -195.139034) (xy 211.195861 -195.189531) (xy 211.211929 -195.242938)
			(xy 211.220049 -195.298114) (xy 211.220558 -195.326) (xy 211.220049 -195.353886) (xy 211.211929 -195.409062)
			(xy 211.197105 -195.458334) (xy 213.653876 -195.458334) (xy 213.657947 -195.402712) (xy 213.670073 -195.348275)
			(xy 213.689996 -195.296184) (xy 213.717292 -195.247549) (xy 213.751378 -195.203406) (xy 213.791527 -195.164697)
			(xy 213.836885 -195.132246) (xy 213.886485 -195.106745) (xy 213.939269 -195.088738) (xy 213.994112 -195.078608)
			(xy 214.049846 -195.076571) (xy 214.105283 -195.082671) (xy 214.15924 -195.096777) (xy 214.210569 -195.118589)
			(xy 214.258175 -195.147643) (xy 214.301043 -195.183318) (xy 214.33826 -195.224855) (xy 214.369033 -195.271368)
			(xy 214.392705 -195.321865) (xy 214.408773 -195.375272) (xy 214.416893 -195.430448) (xy 214.417402 -195.458334)
			(xy 214.416893 -195.48622) (xy 214.408773 -195.541396) (xy 214.392705 -195.594803) (xy 214.369033 -195.6453)
			(xy 214.33826 -195.691813) (xy 214.324653 -195.707) (xy 218.419932 -195.707) (xy 218.424003 -195.651378)
			(xy 218.436129 -195.596941) (xy 218.456052 -195.54485) (xy 218.483348 -195.496215) (xy 218.517434 -195.452072)
			(xy 218.557583 -195.413363) (xy 218.602941 -195.380912) (xy 218.652541 -195.355411) (xy 218.705325 -195.337404)
			(xy 218.760168 -195.327274) (xy 218.815902 -195.325237) (xy 218.871339 -195.331337) (xy 218.925296 -195.345443)
			(xy 218.976625 -195.367255) (xy 219.024231 -195.396309) (xy 219.067099 -195.431984) (xy 219.104316 -195.473521)
			(xy 219.135089 -195.520034) (xy 219.158761 -195.570531) (xy 219.174829 -195.623938) (xy 219.179577 -195.6562)
			(xy 242.4463 -195.6562) (xy 242.450371 -195.600578) (xy 242.462497 -195.546141) (xy 242.48242 -195.49405)
			(xy 242.509716 -195.445415) (xy 242.543802 -195.401272) (xy 242.583951 -195.362563) (xy 242.629309 -195.330112)
			(xy 242.678909 -195.304611) (xy 242.731693 -195.286604) (xy 242.786536 -195.276474) (xy 242.84227 -195.274437)
			(xy 242.897707 -195.280537) (xy 242.951664 -195.294643) (xy 243.002993 -195.316455) (xy 243.050599 -195.345509)
			(xy 243.093467 -195.381184) (xy 243.130684 -195.422721) (xy 243.161457 -195.469234) (xy 243.185129 -195.519731)
			(xy 243.201197 -195.573138) (xy 243.209317 -195.628314) (xy 243.209826 -195.6562) (xy 243.209317 -195.684086)
			(xy 243.201197 -195.739262) (xy 243.185129 -195.792669) (xy 243.161457 -195.843166) (xy 243.130684 -195.889679)
			(xy 243.093467 -195.931216) (xy 243.050599 -195.966891) (xy 243.002993 -195.995945) (xy 242.951664 -196.017757)
			(xy 242.897707 -196.031863) (xy 242.84227 -196.037963) (xy 242.786536 -196.035926) (xy 242.731693 -196.025796)
			(xy 242.678909 -196.007789) (xy 242.629309 -195.982288) (xy 242.583951 -195.949837) (xy 242.543802 -195.911128)
			(xy 242.509716 -195.866985) (xy 242.48242 -195.81835) (xy 242.462497 -195.766259) (xy 242.450371 -195.711822)
			(xy 242.4463 -195.6562) (xy 219.179577 -195.6562) (xy 219.182949 -195.679114) (xy 219.183458 -195.707)
			(xy 219.182949 -195.734886) (xy 219.174829 -195.790062) (xy 219.158761 -195.843469) (xy 219.135089 -195.893966)
			(xy 219.104316 -195.940479) (xy 219.067099 -195.982016) (xy 219.024231 -196.017691) (xy 218.976625 -196.046745)
			(xy 218.925296 -196.068557) (xy 218.871339 -196.082663) (xy 218.815902 -196.088763) (xy 218.760168 -196.086726)
			(xy 218.705325 -196.076596) (xy 218.652541 -196.058589) (xy 218.602941 -196.033088) (xy 218.557583 -196.000637)
			(xy 218.517434 -195.961928) (xy 218.483348 -195.917785) (xy 218.456052 -195.86915) (xy 218.436129 -195.817059)
			(xy 218.424003 -195.762622) (xy 218.419932 -195.707) (xy 214.324653 -195.707) (xy 214.301043 -195.73335)
			(xy 214.258175 -195.769025) (xy 214.210569 -195.798079) (xy 214.15924 -195.819891) (xy 214.105283 -195.833997)
			(xy 214.049846 -195.840097) (xy 213.994112 -195.83806) (xy 213.939269 -195.82793) (xy 213.886485 -195.809923)
			(xy 213.836885 -195.784422) (xy 213.791527 -195.751971) (xy 213.751378 -195.713262) (xy 213.717292 -195.669119)
			(xy 213.689996 -195.620484) (xy 213.670073 -195.568393) (xy 213.657947 -195.513956) (xy 213.653876 -195.458334)
			(xy 211.197105 -195.458334) (xy 211.195861 -195.462469) (xy 211.172189 -195.512966) (xy 211.141416 -195.559479)
			(xy 211.104199 -195.601016) (xy 211.061331 -195.636691) (xy 211.013725 -195.665745) (xy 210.962396 -195.687557)
			(xy 210.908439 -195.701663) (xy 210.853002 -195.707763) (xy 210.797268 -195.705726) (xy 210.742425 -195.695596)
			(xy 210.689641 -195.677589) (xy 210.640041 -195.652088) (xy 210.594683 -195.619637) (xy 210.554534 -195.580928)
			(xy 210.520448 -195.536785) (xy 210.493152 -195.48815) (xy 210.473229 -195.436059) (xy 210.461103 -195.381622)
			(xy 210.457032 -195.326) (xy 188.780008 -195.326) (xy 188.773249 -195.336464) (xy 188.737302 -195.377708)
			(xy 188.695832 -195.413394) (xy 188.649688 -195.442787) (xy 188.599817 -195.465286) (xy 188.573664 -195.47332)
			(xy 188.573156 -195.47332) (xy 188.561472 -195.476876) (xy 188.552582 -195.485258) (xy 188.548215 -195.489635)
			(xy 188.541549 -195.500044) (xy 188.539374 -195.505832) (xy 188.52007 -195.562728) (xy 188.52007 -195.563236)
			(xy 188.512196 -195.587112) (xy 188.50957 -195.598) (xy 188.512868 -195.620129) (xy 188.518546 -195.629784)
			(xy 188.52007 -195.631816) (xy 188.534143 -195.651364) (xy 188.557789 -195.693328) (xy 188.575975 -195.737931)
			(xy 188.582554 -195.761102) (xy 188.585348 -195.771262) (xy 188.591698 -195.779136) (xy 188.594926 -195.783181)
			(xy 188.602733 -195.789972) (xy 188.607192 -195.792598) (xy 188.671962 -195.827904) (xy 188.676662 -195.830323)
			(xy 188.686777 -195.833391) (xy 188.692028 -195.834) (xy 188.702442 -195.834762) (xy 188.712348 -195.83146)
			(xy 188.741082 -195.822677) (xy 188.800417 -195.813242) (xy 188.830458 -195.812664) (xy 188.832744 -195.812664)
			(xy 188.859901 -195.813289) (xy 188.913629 -195.82128) (xy 188.96568 -195.836812) (xy 189.015003 -195.859568)
			(xy 189.060599 -195.889089) (xy 189.101548 -195.924779) (xy 189.137021 -195.965916) (xy 189.166301 -196.011668)
			(xy 189.188797 -196.06111) (xy 189.202538 -196.108066) (xy 214.501982 -196.108066) (xy 214.506053 -196.052444)
			(xy 214.518179 -195.998007) (xy 214.538102 -195.945916) (xy 214.565398 -195.897281) (xy 214.599484 -195.853138)
			(xy 214.639633 -195.814429) (xy 214.684991 -195.781978) (xy 214.734591 -195.756477) (xy 214.787375 -195.73847)
			(xy 214.842218 -195.72834) (xy 214.897952 -195.726303) (xy 214.953389 -195.732403) (xy 215.007346 -195.746509)
			(xy 215.058675 -195.768321) (xy 215.106281 -195.797375) (xy 215.149149 -195.83305) (xy 215.186366 -195.874587)
			(xy 215.217139 -195.9211) (xy 215.240811 -195.971597) (xy 215.256879 -196.025004) (xy 215.264999 -196.08018)
			(xy 215.265508 -196.108066) (xy 215.264999 -196.135952) (xy 215.256879 -196.191128) (xy 215.240811 -196.244535)
			(xy 215.217139 -196.295032) (xy 215.186366 -196.341545) (xy 215.149149 -196.383082) (xy 215.106281 -196.418757)
			(xy 215.058675 -196.447811) (xy 215.007346 -196.469623) (xy 214.953389 -196.483729) (xy 214.897952 -196.489829)
			(xy 214.842218 -196.487792) (xy 214.787375 -196.477662) (xy 214.734591 -196.459655) (xy 214.684991 -196.434154)
			(xy 214.639633 -196.401703) (xy 214.599484 -196.362994) (xy 214.565398 -196.318851) (xy 214.538102 -196.270216)
			(xy 214.518179 -196.218125) (xy 214.506053 -196.163688) (xy 214.501982 -196.108066) (xy 189.202538 -196.108066)
			(xy 189.204053 -196.113243) (xy 189.21176 -196.167012) (xy 189.21222 -196.194172) (xy 189.211759 -196.221427)
			(xy 189.204005 -196.275381) (xy 189.188652 -196.327683) (xy 189.166011 -196.377268) (xy 189.136544 -196.423125)
			(xy 189.100851 -196.464322) (xy 189.059657 -196.50002) (xy 189.013803 -196.529492) (xy 188.964221 -196.552138)
			(xy 188.91192 -196.567497) (xy 188.857966 -196.575256) (xy 188.830712 -196.57568) (xy 188.804343 -196.575235)
			(xy 188.752107 -196.56797) (xy 188.701371 -196.553577) (xy 188.653101 -196.532331) (xy 188.60822 -196.504636)
			(xy 188.567582 -196.471022) (xy 188.531964 -196.432129) (xy 188.502044 -196.388699) (xy 188.478393 -196.341561)
			(xy 188.461463 -196.291614) (xy 188.456062 -196.2658) (xy 188.454792 -196.260212) (xy 188.451611 -196.251228)
			(xy 188.439739 -196.236339) (xy 188.431678 -196.231256) (xy 188.401706 -196.215) (xy 188.392338 -196.210462)
			(xy 188.371633 -196.208509) (xy 188.361574 -196.21119) (xy 188.34989 -196.215762) (xy 188.349382 -196.21627)
			(xy 188.347096 -196.217032) (xy 188.343794 -196.218302) (xy 188.33305 -196.224132) (xy 188.318197 -196.243499)
			(xy 188.315346 -196.255386) (xy 188.25272 -196.596) (xy 209.040982 -196.596) (xy 209.045053 -196.540378)
			(xy 209.057179 -196.485941) (xy 209.077102 -196.43385) (xy 209.104398 -196.385215) (xy 209.138484 -196.341072)
			(xy 209.178633 -196.302363) (xy 209.223991 -196.269912) (xy 209.273591 -196.244411) (xy 209.326375 -196.226404)
			(xy 209.381218 -196.216274) (xy 209.436952 -196.214237) (xy 209.492389 -196.220337) (xy 209.546346 -196.234443)
			(xy 209.597675 -196.256255) (xy 209.645281 -196.285309) (xy 209.688149 -196.320984) (xy 209.725366 -196.362521)
			(xy 209.756139 -196.409034) (xy 209.779811 -196.459531) (xy 209.795879 -196.512938) (xy 209.803999 -196.568114)
			(xy 209.804508 -196.596) (xy 217.803982 -196.596) (xy 217.808053 -196.540378) (xy 217.820179 -196.485941)
			(xy 217.840102 -196.43385) (xy 217.867398 -196.385215) (xy 217.901484 -196.341072) (xy 217.941633 -196.302363)
			(xy 217.986991 -196.269912) (xy 218.036591 -196.244411) (xy 218.089375 -196.226404) (xy 218.144218 -196.216274)
			(xy 218.199952 -196.214237) (xy 218.255389 -196.220337) (xy 218.309346 -196.234443) (xy 218.360675 -196.256255)
			(xy 218.408281 -196.285309) (xy 218.451149 -196.320984) (xy 218.488366 -196.362521) (xy 218.519139 -196.409034)
			(xy 218.542811 -196.459531) (xy 218.558879 -196.512938) (xy 218.566999 -196.568114) (xy 218.567508 -196.596)
			(xy 219.835982 -196.596) (xy 219.840053 -196.540378) (xy 219.852179 -196.485941) (xy 219.872102 -196.43385)
			(xy 219.899398 -196.385215) (xy 219.933484 -196.341072) (xy 219.973633 -196.302363) (xy 220.018991 -196.269912)
			(xy 220.068591 -196.244411) (xy 220.121375 -196.226404) (xy 220.176218 -196.216274) (xy 220.231952 -196.214237)
			(xy 220.287389 -196.220337) (xy 220.341346 -196.234443) (xy 220.392675 -196.256255) (xy 220.440281 -196.285309)
			(xy 220.483149 -196.320984) (xy 220.520366 -196.362521) (xy 220.551139 -196.409034) (xy 220.574811 -196.459531)
			(xy 220.590879 -196.512938) (xy 220.598999 -196.568114) (xy 220.599508 -196.596) (xy 220.599485 -196.59727)
			(xy 250.567442 -196.59727) (xy 250.571513 -196.541648) (xy 250.583639 -196.487211) (xy 250.603562 -196.43512)
			(xy 250.630858 -196.386485) (xy 250.664944 -196.342342) (xy 250.705093 -196.303633) (xy 250.750451 -196.271182)
			(xy 250.800051 -196.245681) (xy 250.852835 -196.227674) (xy 250.907678 -196.217544) (xy 250.963412 -196.215507)
			(xy 251.018849 -196.221607) (xy 251.072806 -196.235713) (xy 251.124135 -196.257525) (xy 251.171741 -196.286579)
			(xy 251.214609 -196.322254) (xy 251.251826 -196.363791) (xy 251.282599 -196.410304) (xy 251.306271 -196.460801)
			(xy 251.322339 -196.514208) (xy 251.330459 -196.569384) (xy 251.330968 -196.59727) (xy 251.330459 -196.625156)
			(xy 251.322339 -196.680332) (xy 251.306271 -196.733739) (xy 251.290944 -196.766434) (xy 253.615442 -196.766434)
			(xy 253.619513 -196.710812) (xy 253.631639 -196.656375) (xy 253.651562 -196.604284) (xy 253.678858 -196.555649)
			(xy 253.712944 -196.511506) (xy 253.753093 -196.472797) (xy 253.798451 -196.440346) (xy 253.848051 -196.414845)
			(xy 253.900835 -196.396838) (xy 253.955678 -196.386708) (xy 254.011412 -196.384671) (xy 254.066849 -196.390771)
			(xy 254.120806 -196.404877) (xy 254.172135 -196.426689) (xy 254.219741 -196.455743) (xy 254.262609 -196.491418)
			(xy 254.299826 -196.532955) (xy 254.330599 -196.579468) (xy 254.354271 -196.629965) (xy 254.370339 -196.683372)
			(xy 254.37789 -196.734684) (xy 260.878586 -196.734684) (xy 260.882552 -196.650153) (xy 260.894417 -196.566366)
			(xy 260.914075 -196.484057) (xy 260.941355 -196.403951) (xy 260.976016 -196.326752) (xy 261.017754 -196.253137)
			(xy 261.066201 -196.183754) (xy 261.120933 -196.119213) (xy 261.181469 -196.060081) (xy 261.247275 -196.006877)
			(xy 261.317775 -195.960069) (xy 261.392347 -195.920068) (xy 261.470338 -195.887226) (xy 261.551062 -195.861832)
			(xy 261.633809 -195.844109) (xy 261.717851 -195.834211) (xy 261.802452 -195.832228) (xy 261.886866 -195.838175)
			(xy 261.970353 -195.852) (xy 262.052178 -195.873583) (xy 262.131622 -195.902733) (xy 262.207988 -195.939194)
			(xy 262.280604 -195.982646) (xy 262.348832 -196.032707) (xy 262.412072 -196.088937) (xy 262.469769 -196.150842)
			(xy 262.521416 -196.217878) (xy 262.566558 -196.289455) (xy 262.6048 -196.364945) (xy 262.635804 -196.443684)
			(xy 262.659299 -196.524981) (xy 262.675078 -196.60812) (xy 262.683002 -196.692372) (xy 262.683498 -196.734684)
			(xy 262.683002 -196.776996) (xy 262.675078 -196.861248) (xy 262.659299 -196.944387) (xy 262.635804 -197.025684)
			(xy 262.6048 -197.104423) (xy 262.566558 -197.179913) (xy 262.521416 -197.25149) (xy 262.48828 -197.2945)
			(xy 263.442194 -197.2945) (xy 263.446265 -197.238878) (xy 263.458391 -197.184441) (xy 263.478314 -197.13235)
			(xy 263.50561 -197.083715) (xy 263.539696 -197.039572) (xy 263.579845 -197.000863) (xy 263.625203 -196.968412)
			(xy 263.674803 -196.942911) (xy 263.727587 -196.924904) (xy 263.78243 -196.914774) (xy 263.838164 -196.912737)
			(xy 263.893601 -196.918837) (xy 263.947558 -196.932943) (xy 263.998887 -196.954755) (xy 264.046493 -196.983809)
			(xy 264.089361 -197.019484) (xy 264.126578 -197.061021) (xy 264.157351 -197.107534) (xy 264.181023 -197.158031)
			(xy 264.197091 -197.211438) (xy 264.205211 -197.266614) (xy 264.20572 -197.2945) (xy 264.205211 -197.322386)
			(xy 264.197091 -197.377562) (xy 264.181023 -197.430969) (xy 264.157351 -197.481466) (xy 264.126578 -197.527979)
			(xy 264.089361 -197.569516) (xy 264.046493 -197.605191) (xy 263.998887 -197.634245) (xy 263.947558 -197.656057)
			(xy 263.893601 -197.670163) (xy 263.838164 -197.676263) (xy 263.78243 -197.674226) (xy 263.727587 -197.664096)
			(xy 263.674803 -197.646089) (xy 263.625203 -197.620588) (xy 263.579845 -197.588137) (xy 263.539696 -197.549428)
			(xy 263.50561 -197.505285) (xy 263.478314 -197.45665) (xy 263.458391 -197.404559) (xy 263.446265 -197.350122)
			(xy 263.442194 -197.2945) (xy 262.48828 -197.2945) (xy 262.469769 -197.318526) (xy 262.412072 -197.380431)
			(xy 262.348832 -197.436661) (xy 262.280604 -197.486722) (xy 262.207988 -197.530174) (xy 262.131622 -197.566635)
			(xy 262.052178 -197.595785) (xy 261.970353 -197.617368) (xy 261.886866 -197.631193) (xy 261.802452 -197.63714)
			(xy 261.717851 -197.635157) (xy 261.633809 -197.625259) (xy 261.551062 -197.607536) (xy 261.470338 -197.582142)
			(xy 261.392347 -197.5493) (xy 261.317775 -197.509299) (xy 261.247275 -197.462491) (xy 261.181469 -197.409287)
			(xy 261.120933 -197.350155) (xy 261.066201 -197.285614) (xy 261.017754 -197.216231) (xy 260.976016 -197.142616)
			(xy 260.941355 -197.065417) (xy 260.914075 -196.985311) (xy 260.894417 -196.903002) (xy 260.882552 -196.819215)
			(xy 260.878586 -196.734684) (xy 254.37789 -196.734684) (xy 254.378459 -196.738548) (xy 254.378968 -196.766434)
			(xy 254.378459 -196.79432) (xy 254.370339 -196.849496) (xy 254.354271 -196.902903) (xy 254.330599 -196.9534)
			(xy 254.299826 -196.999913) (xy 254.262609 -197.04145) (xy 254.219741 -197.077125) (xy 254.172135 -197.106179)
			(xy 254.120806 -197.127991) (xy 254.066849 -197.142097) (xy 254.011412 -197.148197) (xy 253.955678 -197.14616)
			(xy 253.900835 -197.13603) (xy 253.848051 -197.118023) (xy 253.798451 -197.092522) (xy 253.753093 -197.060071)
			(xy 253.712944 -197.021362) (xy 253.678858 -196.977219) (xy 253.651562 -196.928584) (xy 253.631639 -196.876493)
			(xy 253.619513 -196.822056) (xy 253.615442 -196.766434) (xy 251.290944 -196.766434) (xy 251.282599 -196.784236)
			(xy 251.251826 -196.830749) (xy 251.214609 -196.872286) (xy 251.171741 -196.907961) (xy 251.124135 -196.937015)
			(xy 251.072806 -196.958827) (xy 251.018849 -196.972933) (xy 250.963412 -196.979033) (xy 250.907678 -196.976996)
			(xy 250.852835 -196.966866) (xy 250.800051 -196.948859) (xy 250.750451 -196.923358) (xy 250.705093 -196.890907)
			(xy 250.664944 -196.852198) (xy 250.630858 -196.808055) (xy 250.603562 -196.75942) (xy 250.583639 -196.707329)
			(xy 250.571513 -196.652892) (xy 250.567442 -196.59727) (xy 220.599485 -196.59727) (xy 220.598999 -196.623886)
			(xy 220.590879 -196.679062) (xy 220.574811 -196.732469) (xy 220.551139 -196.782966) (xy 220.520366 -196.829479)
			(xy 220.483149 -196.871016) (xy 220.440281 -196.906691) (xy 220.392675 -196.935745) (xy 220.341346 -196.957557)
			(xy 220.287389 -196.971663) (xy 220.231952 -196.977763) (xy 220.176218 -196.975726) (xy 220.121375 -196.965596)
			(xy 220.068591 -196.947589) (xy 220.018991 -196.922088) (xy 219.973633 -196.889637) (xy 219.933484 -196.850928)
			(xy 219.899398 -196.806785) (xy 219.872102 -196.75815) (xy 219.852179 -196.706059) (xy 219.840053 -196.651622)
			(xy 219.835982 -196.596) (xy 218.567508 -196.596) (xy 218.566999 -196.623886) (xy 218.558879 -196.679062)
			(xy 218.542811 -196.732469) (xy 218.519139 -196.782966) (xy 218.488366 -196.829479) (xy 218.451149 -196.871016)
			(xy 218.408281 -196.906691) (xy 218.360675 -196.935745) (xy 218.309346 -196.957557) (xy 218.255389 -196.971663)
			(xy 218.199952 -196.977763) (xy 218.144218 -196.975726) (xy 218.089375 -196.965596) (xy 218.036591 -196.947589)
			(xy 217.986991 -196.922088) (xy 217.941633 -196.889637) (xy 217.901484 -196.850928) (xy 217.867398 -196.806785)
			(xy 217.840102 -196.75815) (xy 217.820179 -196.706059) (xy 217.808053 -196.651622) (xy 217.803982 -196.596)
			(xy 209.804508 -196.596) (xy 209.803999 -196.623886) (xy 209.795879 -196.679062) (xy 209.779811 -196.732469)
			(xy 209.756139 -196.782966) (xy 209.725366 -196.829479) (xy 209.688149 -196.871016) (xy 209.645281 -196.906691)
			(xy 209.597675 -196.935745) (xy 209.546346 -196.957557) (xy 209.492389 -196.971663) (xy 209.436952 -196.977763)
			(xy 209.381218 -196.975726) (xy 209.326375 -196.965596) (xy 209.273591 -196.947589) (xy 209.223991 -196.922088)
			(xy 209.178633 -196.889637) (xy 209.138484 -196.850928) (xy 209.104398 -196.806785) (xy 209.077102 -196.75815)
			(xy 209.057179 -196.706059) (xy 209.045053 -196.651622) (xy 209.040982 -196.596) (xy 188.25272 -196.596)
			(xy 188.244734 -196.639434) (xy 188.243405 -196.648272) (xy 188.246322 -196.665893) (xy 188.255146 -196.681421)
			(xy 188.261752 -196.68744) (xy 188.289184 -196.710808) (xy 188.289438 -196.711062) (xy 188.292232 -196.713348)
			(xy 188.297073 -196.716853) (xy 188.307982 -196.721728) (xy 188.313822 -196.723) (xy 188.320172 -196.724016)
			(xy 188.33338 -196.723) (xy 188.339984 -196.720714) (xy 188.370462 -196.710771) (xy 188.433662 -196.700047)
			(xy 188.465714 -196.699378) (xy 188.466222 -196.699378) (xy 188.493473 -196.699865) (xy 188.547421 -196.707625)
			(xy 188.599715 -196.722982) (xy 188.649291 -196.745625) (xy 188.69514 -196.775093) (xy 188.736329 -196.810786)
			(xy 188.77202 -196.851977) (xy 188.801485 -196.897828) (xy 188.824125 -196.947406) (xy 188.83948 -196.999701)
			(xy 188.847236 -197.053649) (xy 188.847236 -197.108151) (xy 188.83948 -197.162099) (xy 188.824125 -197.214394)
			(xy 188.816542 -197.231) (xy 215.390982 -197.231) (xy 215.395053 -197.175378) (xy 215.407179 -197.120941)
			(xy 215.427102 -197.06885) (xy 215.454398 -197.020215) (xy 215.488484 -196.976072) (xy 215.528633 -196.937363)
			(xy 215.573991 -196.904912) (xy 215.623591 -196.879411) (xy 215.676375 -196.861404) (xy 215.731218 -196.851274)
			(xy 215.786952 -196.849237) (xy 215.842389 -196.855337) (xy 215.896346 -196.869443) (xy 215.947675 -196.891255)
			(xy 215.995281 -196.920309) (xy 216.038149 -196.955984) (xy 216.075366 -196.997521) (xy 216.106139 -197.044034)
			(xy 216.129811 -197.094531) (xy 216.145879 -197.147938) (xy 216.153692 -197.201028) (xy 245.01424 -197.201028)
			(xy 245.018311 -197.145406) (xy 245.030437 -197.090969) (xy 245.05036 -197.038878) (xy 245.077656 -196.990243)
			(xy 245.111742 -196.9461) (xy 245.151891 -196.907391) (xy 245.197249 -196.87494) (xy 245.246849 -196.849439)
			(xy 245.299633 -196.831432) (xy 245.354476 -196.821302) (xy 245.41021 -196.819265) (xy 245.465647 -196.825365)
			(xy 245.519604 -196.839471) (xy 245.570933 -196.861283) (xy 245.618539 -196.890337) (xy 245.661407 -196.926012)
			(xy 245.698624 -196.967549) (xy 245.729397 -197.014062) (xy 245.753069 -197.064559) (xy 245.769137 -197.117966)
			(xy 245.777257 -197.173142) (xy 245.777766 -197.201028) (xy 245.777257 -197.228914) (xy 245.769137 -197.28409)
			(xy 245.753069 -197.337497) (xy 245.729397 -197.387994) (xy 245.698624 -197.434507) (xy 245.661407 -197.476044)
			(xy 245.633859 -197.49897) (xy 249.64466 -197.49897) (xy 249.648731 -197.443348) (xy 249.660857 -197.388911)
			(xy 249.68078 -197.33682) (xy 249.708076 -197.288185) (xy 249.742162 -197.244042) (xy 249.782311 -197.205333)
			(xy 249.827669 -197.172882) (xy 249.877269 -197.147381) (xy 249.930053 -197.129374) (xy 249.984896 -197.119244)
			(xy 250.04063 -197.117207) (xy 250.096067 -197.123307) (xy 250.150024 -197.137413) (xy 250.201353 -197.159225)
			(xy 250.248959 -197.188279) (xy 250.291827 -197.223954) (xy 250.329044 -197.265491) (xy 250.344539 -197.288912)
			(xy 256.842512 -197.288912) (xy 256.846583 -197.23329) (xy 256.858709 -197.178853) (xy 256.878632 -197.126762)
			(xy 256.905928 -197.078127) (xy 256.940014 -197.033984) (xy 256.980163 -196.995275) (xy 257.025521 -196.962824)
			(xy 257.075121 -196.937323) (xy 257.127905 -196.919316) (xy 257.182748 -196.909186) (xy 257.238482 -196.907149)
			(xy 257.293919 -196.913249) (xy 257.347876 -196.927355) (xy 257.399205 -196.949167) (xy 257.446811 -196.978221)
			(xy 257.489679 -197.013896) (xy 257.526896 -197.055433) (xy 257.557669 -197.101946) (xy 257.581341 -197.152443)
			(xy 257.597409 -197.20585) (xy 257.605529 -197.261026) (xy 257.606038 -197.288912) (xy 257.605529 -197.316798)
			(xy 257.597409 -197.371974) (xy 257.581341 -197.425381) (xy 257.557669 -197.475878) (xy 257.526896 -197.522391)
			(xy 257.489679 -197.563928) (xy 257.446811 -197.599603) (xy 257.399205 -197.628657) (xy 257.347876 -197.650469)
			(xy 257.293919 -197.664575) (xy 257.238482 -197.670675) (xy 257.182748 -197.668638) (xy 257.127905 -197.658508)
			(xy 257.075121 -197.640501) (xy 257.025521 -197.615) (xy 256.980163 -197.582549) (xy 256.940014 -197.54384)
			(xy 256.905928 -197.499697) (xy 256.878632 -197.451062) (xy 256.858709 -197.398971) (xy 256.846583 -197.344534)
			(xy 256.842512 -197.288912) (xy 250.344539 -197.288912) (xy 250.359817 -197.312004) (xy 250.383489 -197.362501)
			(xy 250.399557 -197.415908) (xy 250.407677 -197.471084) (xy 250.408186 -197.49897) (xy 250.407677 -197.526856)
			(xy 250.399557 -197.582032) (xy 250.383489 -197.635439) (xy 250.359817 -197.685936) (xy 250.329044 -197.732449)
			(xy 250.293589 -197.77202) (xy 251.255528 -197.77202) (xy 251.259599 -197.716398) (xy 251.271725 -197.661961)
			(xy 251.291648 -197.60987) (xy 251.318944 -197.561235) (xy 251.35303 -197.517092) (xy 251.393179 -197.478383)
			(xy 251.438537 -197.445932) (xy 251.488137 -197.420431) (xy 251.540921 -197.402424) (xy 251.595764 -197.392294)
			(xy 251.651498 -197.390257) (xy 251.706935 -197.396357) (xy 251.760892 -197.410463) (xy 251.812221 -197.432275)
			(xy 251.859827 -197.461329) (xy 251.902695 -197.497004) (xy 251.939912 -197.538541) (xy 251.970685 -197.585054)
			(xy 251.994357 -197.635551) (xy 252.010425 -197.688958) (xy 252.018545 -197.744134) (xy 252.019054 -197.77202)
			(xy 252.018545 -197.799906) (xy 252.015061 -197.823582) (xy 252.868936 -197.823582) (xy 252.873007 -197.76796)
			(xy 252.885133 -197.713523) (xy 252.905056 -197.661432) (xy 252.932352 -197.612797) (xy 252.966438 -197.568654)
			(xy 253.006587 -197.529945) (xy 253.051945 -197.497494) (xy 253.101545 -197.471993) (xy 253.154329 -197.453986)
			(xy 253.209172 -197.443856) (xy 253.264906 -197.441819) (xy 253.320343 -197.447919) (xy 253.3743 -197.462025)
			(xy 253.425629 -197.483837) (xy 253.473235 -197.512891) (xy 253.516103 -197.548566) (xy 253.55332 -197.590103)
			(xy 253.584093 -197.636616) (xy 253.607765 -197.687113) (xy 253.623833 -197.74052) (xy 253.631953 -197.795696)
			(xy 253.632462 -197.823582) (xy 253.631953 -197.851468) (xy 253.626039 -197.891654) (xy 258.104638 -197.891654)
			(xy 258.108709 -197.836032) (xy 258.120835 -197.781595) (xy 258.140758 -197.729504) (xy 258.168054 -197.680869)
			(xy 258.20214 -197.636726) (xy 258.242289 -197.598017) (xy 258.287647 -197.565566) (xy 258.337247 -197.540065)
			(xy 258.390031 -197.522058) (xy 258.444874 -197.511928) (xy 258.500608 -197.509891) (xy 258.556045 -197.515991)
			(xy 258.610002 -197.530097) (xy 258.661331 -197.551909) (xy 258.708937 -197.580963) (xy 258.751805 -197.616638)
			(xy 258.789022 -197.658175) (xy 258.819795 -197.704688) (xy 258.843467 -197.755185) (xy 258.859535 -197.808592)
			(xy 258.867655 -197.863768) (xy 258.868164 -197.891654) (xy 258.867655 -197.91954) (xy 258.859535 -197.974716)
			(xy 258.843467 -198.028123) (xy 258.819795 -198.07862) (xy 258.789022 -198.125133) (xy 258.751805 -198.16667)
			(xy 258.708937 -198.202345) (xy 258.661331 -198.231399) (xy 258.610002 -198.253211) (xy 258.556045 -198.267317)
			(xy 258.500608 -198.273417) (xy 258.444874 -198.27138) (xy 258.390031 -198.26125) (xy 258.337247 -198.243243)
			(xy 258.287647 -198.217742) (xy 258.242289 -198.185291) (xy 258.20214 -198.146582) (xy 258.168054 -198.102439)
			(xy 258.140758 -198.053804) (xy 258.120835 -198.001713) (xy 258.108709 -197.947276) (xy 258.104638 -197.891654)
			(xy 253.626039 -197.891654) (xy 253.623833 -197.906644) (xy 253.607765 -197.960051) (xy 253.584093 -198.010548)
			(xy 253.55332 -198.057061) (xy 253.516103 -198.098598) (xy 253.473235 -198.134273) (xy 253.425629 -198.163327)
			(xy 253.3743 -198.185139) (xy 253.320343 -198.199245) (xy 253.264906 -198.205345) (xy 253.209172 -198.203308)
			(xy 253.154329 -198.193178) (xy 253.101545 -198.175171) (xy 253.051945 -198.14967) (xy 253.006587 -198.117219)
			(xy 252.966438 -198.07851) (xy 252.932352 -198.034367) (xy 252.905056 -197.985732) (xy 252.885133 -197.933641)
			(xy 252.873007 -197.879204) (xy 252.868936 -197.823582) (xy 252.015061 -197.823582) (xy 252.010425 -197.855082)
			(xy 251.994357 -197.908489) (xy 251.970685 -197.958986) (xy 251.939912 -198.005499) (xy 251.902695 -198.047036)
			(xy 251.859827 -198.082711) (xy 251.812221 -198.111765) (xy 251.760892 -198.133577) (xy 251.706935 -198.147683)
			(xy 251.651498 -198.153783) (xy 251.595764 -198.151746) (xy 251.540921 -198.141616) (xy 251.488137 -198.123609)
			(xy 251.438537 -198.098108) (xy 251.393179 -198.065657) (xy 251.35303 -198.026948) (xy 251.318944 -197.982805)
			(xy 251.291648 -197.93417) (xy 251.271725 -197.882079) (xy 251.259599 -197.827642) (xy 251.255528 -197.77202)
			(xy 250.293589 -197.77202) (xy 250.291827 -197.773986) (xy 250.248959 -197.809661) (xy 250.201353 -197.838715)
			(xy 250.150024 -197.860527) (xy 250.096067 -197.874633) (xy 250.04063 -197.880733) (xy 249.984896 -197.878696)
			(xy 249.930053 -197.868566) (xy 249.877269 -197.850559) (xy 249.827669 -197.825058) (xy 249.782311 -197.792607)
			(xy 249.742162 -197.753898) (xy 249.708076 -197.709755) (xy 249.68078 -197.66112) (xy 249.660857 -197.609029)
			(xy 249.648731 -197.554592) (xy 249.64466 -197.49897) (xy 245.633859 -197.49897) (xy 245.618539 -197.511719)
			(xy 245.570933 -197.540773) (xy 245.519604 -197.562585) (xy 245.465647 -197.576691) (xy 245.41021 -197.582791)
			(xy 245.354476 -197.580754) (xy 245.299633 -197.570624) (xy 245.246849 -197.552617) (xy 245.197249 -197.527116)
			(xy 245.151891 -197.494665) (xy 245.111742 -197.455956) (xy 245.077656 -197.411813) (xy 245.05036 -197.363178)
			(xy 245.030437 -197.311087) (xy 245.018311 -197.25665) (xy 245.01424 -197.201028) (xy 216.153692 -197.201028)
			(xy 216.153999 -197.203114) (xy 216.154508 -197.231) (xy 216.153999 -197.258886) (xy 216.145879 -197.314062)
			(xy 216.129811 -197.367469) (xy 216.106139 -197.417966) (xy 216.075366 -197.464479) (xy 216.038149 -197.506016)
			(xy 215.995281 -197.541691) (xy 215.947675 -197.570745) (xy 215.896346 -197.592557) (xy 215.842389 -197.606663)
			(xy 215.786952 -197.612763) (xy 215.731218 -197.610726) (xy 215.676375 -197.600596) (xy 215.623591 -197.582589)
			(xy 215.573991 -197.557088) (xy 215.528633 -197.524637) (xy 215.488484 -197.485928) (xy 215.454398 -197.441785)
			(xy 215.427102 -197.39315) (xy 215.407179 -197.341059) (xy 215.395053 -197.286622) (xy 215.390982 -197.231)
			(xy 188.816542 -197.231) (xy 188.801485 -197.263972) (xy 188.77202 -197.309823) (xy 188.736329 -197.351014)
			(xy 188.69514 -197.386707) (xy 188.649291 -197.416175) (xy 188.599715 -197.438818) (xy 188.547421 -197.454175)
			(xy 188.493473 -197.461935) (xy 188.466222 -197.462394) (xy 188.465714 -197.462394) (xy 188.439012 -197.461953)
			(xy 188.386128 -197.454511) (xy 188.334802 -197.439756) (xy 188.28604 -197.417979) (xy 188.240796 -197.389605)
			(xy 188.220096 -197.372732) (xy 188.219588 -197.372478) (xy 188.214455 -197.368391) (xy 188.202624 -197.362729)
			(xy 188.19622 -197.361302) (xy 188.190124 -197.360286) (xy 188.176916 -197.361302) (xy 188.13526 -197.376034)
			(xy 188.132974 -197.376796) (xy 188.125195 -197.380337) (xy 188.112396 -197.39165) (xy 188.10402 -197.406538)
			(xy 188.10224 -197.414896) (xy 188.04267 -197.739) (xy 209.040982 -197.739) (xy 209.045053 -197.683378)
			(xy 209.057179 -197.628941) (xy 209.077102 -197.57685) (xy 209.104398 -197.528215) (xy 209.138484 -197.484072)
			(xy 209.178633 -197.445363) (xy 209.223991 -197.412912) (xy 209.273591 -197.387411) (xy 209.326375 -197.369404)
			(xy 209.381218 -197.359274) (xy 209.436952 -197.357237) (xy 209.492389 -197.363337) (xy 209.546346 -197.377443)
			(xy 209.597675 -197.399255) (xy 209.645281 -197.428309) (xy 209.688149 -197.463984) (xy 209.725366 -197.505521)
			(xy 209.756139 -197.552034) (xy 209.779811 -197.602531) (xy 209.795879 -197.655938) (xy 209.803999 -197.711114)
			(xy 209.804508 -197.739) (xy 209.803999 -197.766886) (xy 209.795879 -197.822062) (xy 209.779811 -197.875469)
			(xy 209.756139 -197.925966) (xy 209.725366 -197.972479) (xy 209.688149 -198.014016) (xy 209.645281 -198.049691)
			(xy 209.597675 -198.078745) (xy 209.546346 -198.100557) (xy 209.492389 -198.114663) (xy 209.436952 -198.120763)
			(xy 209.381218 -198.118726) (xy 209.326375 -198.108596) (xy 209.273591 -198.090589) (xy 209.223991 -198.065088)
			(xy 209.178633 -198.032637) (xy 209.138484 -197.993928) (xy 209.104398 -197.949785) (xy 209.077102 -197.90115)
			(xy 209.057179 -197.849059) (xy 209.045053 -197.794622) (xy 209.040982 -197.739) (xy 188.04267 -197.739)
			(xy 187.855929 -198.755) (xy 209.040982 -198.755) (xy 209.045053 -198.699378) (xy 209.057179 -198.644941)
			(xy 209.077102 -198.59285) (xy 209.104398 -198.544215) (xy 209.138484 -198.500072) (xy 209.178633 -198.461363)
			(xy 209.223991 -198.428912) (xy 209.273591 -198.403411) (xy 209.326375 -198.385404) (xy 209.381218 -198.375274)
			(xy 209.436952 -198.373237) (xy 209.492389 -198.379337) (xy 209.546346 -198.393443) (xy 209.597675 -198.415255)
			(xy 209.645281 -198.444309) (xy 209.688149 -198.479984) (xy 209.706979 -198.501) (xy 215.390982 -198.501)
			(xy 215.395053 -198.445378) (xy 215.407179 -198.390941) (xy 215.427102 -198.33885) (xy 215.454398 -198.290215)
			(xy 215.488484 -198.246072) (xy 215.528633 -198.207363) (xy 215.573991 -198.174912) (xy 215.623591 -198.149411)
			(xy 215.676375 -198.131404) (xy 215.731218 -198.121274) (xy 215.786952 -198.119237) (xy 215.842389 -198.125337)
			(xy 215.896346 -198.139443) (xy 215.947675 -198.161255) (xy 215.995281 -198.190309) (xy 216.038149 -198.225984)
			(xy 216.075366 -198.267521) (xy 216.106139 -198.314034) (xy 216.129811 -198.364531) (xy 216.13266 -198.374)
			(xy 217.804492 -198.374) (xy 217.804975 -198.345081) (xy 217.813707 -198.287907) (xy 217.830969 -198.232706)
			(xy 217.856367 -198.180744) (xy 217.889319 -198.133211) (xy 217.929068 -198.091197) (xy 217.951558 -198.07301)
			(xy 217.96036 -198.065399) (xy 217.970544 -198.044501) (xy 217.971116 -198.032878) (xy 217.971116 -197.953122)
			(xy 217.970544 -197.941494) (xy 217.960378 -197.920585) (xy 217.951558 -197.91299) (xy 217.929061 -197.894815)
			(xy 217.889329 -197.852791) (xy 217.856392 -197.805252) (xy 217.831007 -197.753288) (xy 217.813753 -197.698088)
			(xy 217.805026 -197.640917) (xy 217.804492 -197.612) (xy 217.804978 -197.584749) (xy 217.812734 -197.530801)
			(xy 217.828089 -197.478506) (xy 217.850731 -197.428929) (xy 217.880197 -197.383079) (xy 217.915888 -197.341888)
			(xy 217.957079 -197.306197) (xy 218.002929 -197.276731) (xy 218.052506 -197.254089) (xy 218.104801 -197.238734)
			(xy 218.158749 -197.230978) (xy 218.213251 -197.230978) (xy 218.267199 -197.238734) (xy 218.319494 -197.254089)
			(xy 218.369071 -197.276731) (xy 218.414921 -197.306197) (xy 218.456112 -197.341888) (xy 218.491803 -197.383079)
			(xy 218.521269 -197.428929) (xy 218.543911 -197.478506) (xy 218.559266 -197.530801) (xy 218.567022 -197.584749)
			(xy 218.567508 -197.612) (xy 218.567025 -197.640919) (xy 218.558293 -197.698093) (xy 218.541031 -197.753294)
			(xy 218.515633 -197.805256) (xy 218.482681 -197.852789) (xy 218.442932 -197.894803) (xy 218.420442 -197.91299)
			(xy 218.41164 -197.920601) (xy 218.401456 -197.941499) (xy 218.400884 -197.953122) (xy 218.400884 -198.032878)
			(xy 218.401456 -198.044506) (xy 218.411622 -198.065415) (xy 218.420442 -198.07301) (xy 218.442939 -198.091185)
			(xy 218.470182 -198.12) (xy 220.597982 -198.12) (xy 220.602053 -198.064378) (xy 220.614179 -198.009941)
			(xy 220.634102 -197.95785) (xy 220.661398 -197.909215) (xy 220.695484 -197.865072) (xy 220.735633 -197.826363)
			(xy 220.780991 -197.793912) (xy 220.830591 -197.768411) (xy 220.883375 -197.750404) (xy 220.938218 -197.740274)
			(xy 220.993952 -197.738237) (xy 221.049389 -197.744337) (xy 221.103346 -197.758443) (xy 221.154675 -197.780255)
			(xy 221.202281 -197.809309) (xy 221.245149 -197.844984) (xy 221.282366 -197.886521) (xy 221.313139 -197.933034)
			(xy 221.336811 -197.983531) (xy 221.352879 -198.036938) (xy 221.3543 -198.046594) (xy 241.095528 -198.046594)
			(xy 241.099599 -197.990972) (xy 241.111725 -197.936535) (xy 241.131648 -197.884444) (xy 241.158944 -197.835809)
			(xy 241.19303 -197.791666) (xy 241.233179 -197.752957) (xy 241.278537 -197.720506) (xy 241.328137 -197.695005)
			(xy 241.380921 -197.676998) (xy 241.435764 -197.666868) (xy 241.491498 -197.664831) (xy 241.546935 -197.670931)
			(xy 241.600892 -197.685037) (xy 241.652221 -197.706849) (xy 241.699827 -197.735903) (xy 241.742695 -197.771578)
			(xy 241.779912 -197.813115) (xy 241.810685 -197.859628) (xy 241.834357 -197.910125) (xy 241.850425 -197.963532)
			(xy 241.858545 -198.018708) (xy 241.859054 -198.046594) (xy 241.858545 -198.07448) (xy 241.850425 -198.129656)
			(xy 241.834357 -198.183063) (xy 241.810685 -198.23356) (xy 241.779912 -198.280073) (xy 241.742695 -198.32161)
			(xy 241.740784 -198.3232) (xy 242.822982 -198.3232) (xy 242.827053 -198.267578) (xy 242.839179 -198.213141)
			(xy 242.859102 -198.16105) (xy 242.886398 -198.112415) (xy 242.920484 -198.068272) (xy 242.960633 -198.029563)
			(xy 243.005991 -197.997112) (xy 243.055591 -197.971611) (xy 243.108375 -197.953604) (xy 243.163218 -197.943474)
			(xy 243.218952 -197.941437) (xy 243.274389 -197.947537) (xy 243.328346 -197.961643) (xy 243.379675 -197.983455)
			(xy 243.427281 -198.012509) (xy 243.470149 -198.048184) (xy 243.507366 -198.089721) (xy 243.538139 -198.136234)
			(xy 243.561811 -198.186731) (xy 243.577879 -198.240138) (xy 243.585999 -198.295314) (xy 243.586508 -198.3232)
			(xy 243.585999 -198.351086) (xy 243.577879 -198.406262) (xy 243.561811 -198.459669) (xy 243.538139 -198.510166)
			(xy 243.507366 -198.556679) (xy 243.470149 -198.598216) (xy 243.427281 -198.633891) (xy 243.379675 -198.662945)
			(xy 243.328346 -198.684757) (xy 243.274389 -198.698863) (xy 243.218952 -198.704963) (xy 243.163218 -198.702926)
			(xy 243.108375 -198.692796) (xy 243.055591 -198.674789) (xy 243.005991 -198.649288) (xy 242.960633 -198.616837)
			(xy 242.920484 -198.578128) (xy 242.886398 -198.533985) (xy 242.859102 -198.48535) (xy 242.839179 -198.433259)
			(xy 242.827053 -198.378822) (xy 242.822982 -198.3232) (xy 241.740784 -198.3232) (xy 241.699827 -198.357285)
			(xy 241.652221 -198.386339) (xy 241.600892 -198.408151) (xy 241.546935 -198.422257) (xy 241.491498 -198.428357)
			(xy 241.435764 -198.42632) (xy 241.380921 -198.41619) (xy 241.328137 -198.398183) (xy 241.278537 -198.372682)
			(xy 241.233179 -198.340231) (xy 241.19303 -198.301522) (xy 241.158944 -198.257379) (xy 241.131648 -198.208744)
			(xy 241.111725 -198.156653) (xy 241.099599 -198.102216) (xy 241.095528 -198.046594) (xy 221.3543 -198.046594)
			(xy 221.360999 -198.092114) (xy 221.361508 -198.12) (xy 221.360999 -198.147886) (xy 221.352879 -198.203062)
			(xy 221.336811 -198.256469) (xy 221.313139 -198.306966) (xy 221.282366 -198.353479) (xy 221.245149 -198.395016)
			(xy 221.202281 -198.430691) (xy 221.154675 -198.459745) (xy 221.103346 -198.481557) (xy 221.049389 -198.495663)
			(xy 220.993952 -198.501763) (xy 220.938218 -198.499726) (xy 220.883375 -198.489596) (xy 220.830591 -198.471589)
			(xy 220.780991 -198.446088) (xy 220.735633 -198.413637) (xy 220.695484 -198.374928) (xy 220.661398 -198.330785)
			(xy 220.634102 -198.28215) (xy 220.614179 -198.230059) (xy 220.602053 -198.175622) (xy 220.597982 -198.12)
			(xy 218.470182 -198.12) (xy 218.482671 -198.133209) (xy 218.515608 -198.180748) (xy 218.540993 -198.232712)
			(xy 218.558247 -198.287912) (xy 218.566974 -198.345083) (xy 218.567508 -198.374) (xy 218.567022 -198.401251)
			(xy 218.559266 -198.455199) (xy 218.543911 -198.507494) (xy 218.521269 -198.557071) (xy 218.491803 -198.602921)
			(xy 218.456112 -198.644112) (xy 218.414921 -198.679803) (xy 218.369071 -198.709269) (xy 218.319494 -198.731911)
			(xy 218.267199 -198.747266) (xy 218.213251 -198.755022) (xy 218.158749 -198.755022) (xy 218.104801 -198.747266)
			(xy 218.052506 -198.731911) (xy 218.002929 -198.709269) (xy 217.957079 -198.679803) (xy 217.915888 -198.644112)
			(xy 217.880197 -198.602921) (xy 217.850731 -198.557071) (xy 217.828089 -198.507494) (xy 217.812734 -198.455199)
			(xy 217.804978 -198.401251) (xy 217.804492 -198.374) (xy 216.13266 -198.374) (xy 216.145879 -198.417938)
			(xy 216.153999 -198.473114) (xy 216.154508 -198.501) (xy 216.153999 -198.528886) (xy 216.145879 -198.584062)
			(xy 216.129811 -198.637469) (xy 216.106139 -198.687966) (xy 216.075366 -198.734479) (xy 216.038149 -198.776016)
			(xy 215.995281 -198.811691) (xy 215.947675 -198.840745) (xy 215.896346 -198.862557) (xy 215.842389 -198.876663)
			(xy 215.786952 -198.882763) (xy 215.731218 -198.880726) (xy 215.676375 -198.870596) (xy 215.623591 -198.852589)
			(xy 215.573991 -198.827088) (xy 215.528633 -198.794637) (xy 215.488484 -198.755928) (xy 215.454398 -198.711785)
			(xy 215.427102 -198.66315) (xy 215.407179 -198.611059) (xy 215.395053 -198.556622) (xy 215.390982 -198.501)
			(xy 209.706979 -198.501) (xy 209.725366 -198.521521) (xy 209.756139 -198.568034) (xy 209.779811 -198.618531)
			(xy 209.795879 -198.671938) (xy 209.803999 -198.727114) (xy 209.804508 -198.755) (xy 209.803999 -198.782886)
			(xy 209.795879 -198.838062) (xy 209.779811 -198.891469) (xy 209.756139 -198.941966) (xy 209.725366 -198.988479)
			(xy 209.688149 -199.030016) (xy 209.645281 -199.065691) (xy 209.597675 -199.094745) (xy 209.546346 -199.116557)
			(xy 209.492389 -199.130663) (xy 209.436952 -199.136763) (xy 209.381218 -199.134726) (xy 209.326375 -199.124596)
			(xy 209.273591 -199.106589) (xy 209.223991 -199.081088) (xy 209.178633 -199.048637) (xy 209.138484 -199.009928)
			(xy 209.104398 -198.965785) (xy 209.077102 -198.91715) (xy 209.057179 -198.865059) (xy 209.045053 -198.810622)
			(xy 209.040982 -198.755) (xy 187.855929 -198.755) (xy 187.752335 -199.318626) (xy 223.10928 -199.318626)
			(xy 223.113351 -199.263004) (xy 223.125477 -199.208567) (xy 223.1454 -199.156476) (xy 223.172696 -199.107841)
			(xy 223.206782 -199.063698) (xy 223.246931 -199.024989) (xy 223.292289 -198.992538) (xy 223.341889 -198.967037)
			(xy 223.394673 -198.94903) (xy 223.449516 -198.9389) (xy 223.50525 -198.936863) (xy 223.560687 -198.942963)
			(xy 223.614644 -198.957069) (xy 223.665973 -198.978881) (xy 223.713579 -199.007935) (xy 223.756447 -199.04361)
			(xy 223.793664 -199.085147) (xy 223.824437 -199.13166) (xy 223.848109 -199.182157) (xy 223.864177 -199.235564)
			(xy 223.868626 -199.265794) (xy 226.196142 -199.265794) (xy 226.200213 -199.210172) (xy 226.212339 -199.155735)
			(xy 226.232262 -199.103644) (xy 226.259558 -199.055009) (xy 226.293644 -199.010866) (xy 226.333793 -198.972157)
			(xy 226.379151 -198.939706) (xy 226.428751 -198.914205) (xy 226.481535 -198.896198) (xy 226.536378 -198.886068)
			(xy 226.592112 -198.884031) (xy 226.647549 -198.890131) (xy 226.701506 -198.904237) (xy 226.752835 -198.926049)
			(xy 226.800441 -198.955103) (xy 226.843309 -198.990778) (xy 226.880526 -199.032315) (xy 226.911299 -199.078828)
			(xy 226.934971 -199.129325) (xy 226.951039 -199.182732) (xy 226.959159 -199.237908) (xy 226.959668 -199.265794)
			(xy 226.959159 -199.29368) (xy 226.951039 -199.348856) (xy 226.949283 -199.354694) (xy 242.207286 -199.354694)
			(xy 242.211357 -199.299072) (xy 242.223483 -199.244635) (xy 242.243406 -199.192544) (xy 242.270702 -199.143909)
			(xy 242.304788 -199.099766) (xy 242.344937 -199.061057) (xy 242.390295 -199.028606) (xy 242.439895 -199.003105)
			(xy 242.492679 -198.985098) (xy 242.547522 -198.974968) (xy 242.603256 -198.972931) (xy 242.658693 -198.979031)
			(xy 242.71265 -198.993137) (xy 242.763979 -199.014949) (xy 242.811585 -199.044003) (xy 242.854453 -199.079678)
			(xy 242.89167 -199.121215) (xy 242.922443 -199.167728) (xy 242.946115 -199.218225) (xy 242.962183 -199.271632)
			(xy 242.970303 -199.326808) (xy 242.970812 -199.354694) (xy 242.970303 -199.38258) (xy 242.962183 -199.437756)
			(xy 242.946115 -199.491163) (xy 242.922443 -199.54166) (xy 242.89167 -199.588173) (xy 242.857808 -199.625966)
			(xy 257.001008 -199.625966) (xy 257.005079 -199.570344) (xy 257.017205 -199.515907) (xy 257.037128 -199.463816)
			(xy 257.064424 -199.415181) (xy 257.09851 -199.371038) (xy 257.138659 -199.332329) (xy 257.184017 -199.299878)
			(xy 257.233617 -199.274377) (xy 257.286401 -199.25637) (xy 257.341244 -199.24624) (xy 257.396978 -199.244203)
			(xy 257.452415 -199.250303) (xy 257.506372 -199.264409) (xy 257.530552 -199.274684) (xy 260.878586 -199.274684)
			(xy 260.882552 -199.190153) (xy 260.894417 -199.106366) (xy 260.914075 -199.024057) (xy 260.941355 -198.943951)
			(xy 260.976016 -198.866752) (xy 261.017754 -198.793137) (xy 261.066201 -198.723754) (xy 261.120933 -198.659213)
			(xy 261.181469 -198.600081) (xy 261.247275 -198.546877) (xy 261.317775 -198.500069) (xy 261.392347 -198.460068)
			(xy 261.470338 -198.427226) (xy 261.551062 -198.401832) (xy 261.633809 -198.384109) (xy 261.717851 -198.374211)
			(xy 261.802452 -198.372228) (xy 261.886866 -198.378175) (xy 261.970353 -198.392) (xy 262.052178 -198.413583)
			(xy 262.131622 -198.442733) (xy 262.207988 -198.479194) (xy 262.280604 -198.522646) (xy 262.348832 -198.572707)
			(xy 262.412072 -198.628937) (xy 262.449313 -198.668894) (xy 264.544046 -198.668894) (xy 264.548117 -198.613272)
			(xy 264.560243 -198.558835) (xy 264.580166 -198.506744) (xy 264.607462 -198.458109) (xy 264.641548 -198.413966)
			(xy 264.681697 -198.375257) (xy 264.727055 -198.342806) (xy 264.776655 -198.317305) (xy 264.829439 -198.299298)
			(xy 264.884282 -198.289168) (xy 264.940016 -198.287131) (xy 264.995453 -198.293231) (xy 265.04941 -198.307337)
			(xy 265.100739 -198.329149) (xy 265.148345 -198.358203) (xy 265.191213 -198.393878) (xy 265.22843 -198.435415)
			(xy 265.259203 -198.481928) (xy 265.282875 -198.532425) (xy 265.298943 -198.585832) (xy 265.307063 -198.641008)
			(xy 265.307572 -198.668894) (xy 265.307063 -198.69678) (xy 265.298943 -198.751956) (xy 265.282875 -198.805363)
			(xy 265.259203 -198.85586) (xy 265.22843 -198.902373) (xy 265.191213 -198.94391) (xy 265.148345 -198.979585)
			(xy 265.100739 -199.008639) (xy 265.04941 -199.030451) (xy 264.995453 -199.044557) (xy 264.940016 -199.050657)
			(xy 264.884282 -199.04862) (xy 264.829439 -199.03849) (xy 264.776655 -199.020483) (xy 264.727055 -198.994982)
			(xy 264.681697 -198.962531) (xy 264.641548 -198.923822) (xy 264.607462 -198.879679) (xy 264.580166 -198.831044)
			(xy 264.560243 -198.778953) (xy 264.548117 -198.724516) (xy 264.544046 -198.668894) (xy 262.449313 -198.668894)
			(xy 262.469769 -198.690842) (xy 262.521416 -198.757878) (xy 262.566558 -198.829455) (xy 262.6048 -198.904945)
			(xy 262.635804 -198.983684) (xy 262.659299 -199.064981) (xy 262.675078 -199.14812) (xy 262.683002 -199.232372)
			(xy 262.683498 -199.274684) (xy 262.683002 -199.316996) (xy 262.675078 -199.401248) (xy 262.659299 -199.484387)
			(xy 262.635804 -199.565684) (xy 262.6048 -199.644423) (xy 262.566558 -199.719913) (xy 262.521416 -199.79149)
			(xy 262.469769 -199.858526) (xy 262.412072 -199.920431) (xy 262.348832 -199.976661) (xy 262.280604 -200.026722)
			(xy 262.207988 -200.070174) (xy 262.131622 -200.106635) (xy 262.052178 -200.135785) (xy 261.970353 -200.157368)
			(xy 261.886866 -200.171193) (xy 261.802452 -200.17714) (xy 261.717851 -200.175157) (xy 261.633809 -200.165259)
			(xy 261.551062 -200.147536) (xy 261.470338 -200.122142) (xy 261.392347 -200.0893) (xy 261.317775 -200.049299)
			(xy 261.247275 -200.002491) (xy 261.181469 -199.949287) (xy 261.120933 -199.890155) (xy 261.066201 -199.825614)
			(xy 261.017754 -199.756231) (xy 260.976016 -199.682616) (xy 260.941355 -199.605417) (xy 260.914075 -199.525311)
			(xy 260.894417 -199.443002) (xy 260.882552 -199.359215) (xy 260.878586 -199.274684) (xy 257.530552 -199.274684)
			(xy 257.557701 -199.286221) (xy 257.605307 -199.315275) (xy 257.648175 -199.35095) (xy 257.685392 -199.392487)
			(xy 257.716165 -199.439) (xy 257.739837 -199.489497) (xy 257.755905 -199.542904) (xy 257.764025 -199.59808)
			(xy 257.764534 -199.625966) (xy 257.764025 -199.653852) (xy 257.755905 -199.709028) (xy 257.739837 -199.762435)
			(xy 257.716165 -199.812932) (xy 257.685392 -199.859445) (xy 257.648175 -199.900982) (xy 257.605307 -199.936657)
			(xy 257.557701 -199.965711) (xy 257.506372 -199.987523) (xy 257.452415 -200.001629) (xy 257.396978 -200.007729)
			(xy 257.341244 -200.005692) (xy 257.286401 -199.995562) (xy 257.233617 -199.977555) (xy 257.184017 -199.952054)
			(xy 257.138659 -199.919603) (xy 257.09851 -199.880894) (xy 257.064424 -199.836751) (xy 257.037128 -199.788116)
			(xy 257.017205 -199.736025) (xy 257.005079 -199.681588) (xy 257.001008 -199.625966) (xy 242.857808 -199.625966)
			(xy 242.854453 -199.62971) (xy 242.811585 -199.665385) (xy 242.763979 -199.694439) (xy 242.71265 -199.716251)
			(xy 242.658693 -199.730357) (xy 242.603256 -199.736457) (xy 242.547522 -199.73442) (xy 242.492679 -199.72429)
			(xy 242.439895 -199.706283) (xy 242.390295 -199.680782) (xy 242.344937 -199.648331) (xy 242.304788 -199.609622)
			(xy 242.270702 -199.565479) (xy 242.243406 -199.516844) (xy 242.223483 -199.464753) (xy 242.211357 -199.410316)
			(xy 242.207286 -199.354694) (xy 226.949283 -199.354694) (xy 226.934971 -199.402263) (xy 226.911299 -199.45276)
			(xy 226.880526 -199.499273) (xy 226.843309 -199.54081) (xy 226.800441 -199.576485) (xy 226.752835 -199.605539)
			(xy 226.701506 -199.627351) (xy 226.647549 -199.641457) (xy 226.592112 -199.647557) (xy 226.536378 -199.64552)
			(xy 226.481535 -199.63539) (xy 226.428751 -199.617383) (xy 226.379151 -199.591882) (xy 226.333793 -199.559431)
			(xy 226.293644 -199.520722) (xy 226.259558 -199.476579) (xy 226.232262 -199.427944) (xy 226.212339 -199.375853)
			(xy 226.200213 -199.321416) (xy 226.196142 -199.265794) (xy 223.868626 -199.265794) (xy 223.872297 -199.29074)
			(xy 223.872806 -199.318626) (xy 223.872297 -199.346512) (xy 223.864177 -199.401688) (xy 223.848109 -199.455095)
			(xy 223.824437 -199.505592) (xy 223.793664 -199.552105) (xy 223.756447 -199.593642) (xy 223.713579 -199.629317)
			(xy 223.665973 -199.658371) (xy 223.614644 -199.680183) (xy 223.560687 -199.694289) (xy 223.50525 -199.700389)
			(xy 223.449516 -199.698352) (xy 223.394673 -199.688222) (xy 223.341889 -199.670215) (xy 223.292289 -199.644714)
			(xy 223.246931 -199.612263) (xy 223.206782 -199.573554) (xy 223.172696 -199.529411) (xy 223.1454 -199.480776)
			(xy 223.125477 -199.428685) (xy 223.113351 -199.374248) (xy 223.10928 -199.318626) (xy 187.752335 -199.318626)
			(xy 187.645846 -199.898) (xy 210.457032 -199.898) (xy 210.461103 -199.842378) (xy 210.473229 -199.787941)
			(xy 210.493152 -199.73585) (xy 210.520448 -199.687215) (xy 210.554534 -199.643072) (xy 210.594683 -199.604363)
			(xy 210.640041 -199.571912) (xy 210.689641 -199.546411) (xy 210.742425 -199.528404) (xy 210.797268 -199.518274)
			(xy 210.853002 -199.516237) (xy 210.908439 -199.522337) (xy 210.962396 -199.536443) (xy 211.013725 -199.558255)
			(xy 211.061331 -199.587309) (xy 211.104199 -199.622984) (xy 211.141416 -199.664521) (xy 211.172189 -199.711034)
			(xy 211.184344 -199.736964) (xy 240.148362 -199.736964) (xy 240.152433 -199.681342) (xy 240.164559 -199.626905)
			(xy 240.184482 -199.574814) (xy 240.211778 -199.526179) (xy 240.245864 -199.482036) (xy 240.286013 -199.443327)
			(xy 240.331371 -199.410876) (xy 240.380971 -199.385375) (xy 240.433755 -199.367368) (xy 240.488598 -199.357238)
			(xy 240.544332 -199.355201) (xy 240.599769 -199.361301) (xy 240.653726 -199.375407) (xy 240.705055 -199.397219)
			(xy 240.752661 -199.426273) (xy 240.795529 -199.461948) (xy 240.832746 -199.503485) (xy 240.863519 -199.549998)
			(xy 240.887191 -199.600495) (xy 240.903259 -199.653902) (xy 240.911379 -199.709078) (xy 240.911888 -199.736964)
			(xy 240.911379 -199.76485) (xy 240.903259 -199.820026) (xy 240.887191 -199.873433) (xy 240.863519 -199.92393)
			(xy 240.832746 -199.970443) (xy 240.795529 -200.01198) (xy 240.752661 -200.047655) (xy 240.705055 -200.076709)
			(xy 240.653726 -200.098521) (xy 240.599769 -200.112627) (xy 240.544332 -200.118727) (xy 240.488598 -200.11669)
			(xy 240.433755 -200.10656) (xy 240.380971 -200.088553) (xy 240.331371 -200.063052) (xy 240.286013 -200.030601)
			(xy 240.245864 -199.991892) (xy 240.211778 -199.947749) (xy 240.184482 -199.899114) (xy 240.164559 -199.847023)
			(xy 240.152433 -199.792586) (xy 240.148362 -199.736964) (xy 211.184344 -199.736964) (xy 211.195861 -199.761531)
			(xy 211.211929 -199.814938) (xy 211.220049 -199.870114) (xy 211.220558 -199.898) (xy 211.220049 -199.925886)
			(xy 211.211929 -199.981062) (xy 211.195861 -200.034469) (xy 211.172189 -200.084966) (xy 211.141416 -200.131479)
			(xy 211.104199 -200.173016) (xy 211.061331 -200.208691) (xy 211.013725 -200.237745) (xy 210.962396 -200.259557)
			(xy 210.908439 -200.273663) (xy 210.853002 -200.279763) (xy 210.797268 -200.277726) (xy 210.742425 -200.267596)
			(xy 210.689641 -200.249589) (xy 210.640041 -200.224088) (xy 210.594683 -200.191637) (xy 210.554534 -200.152928)
			(xy 210.520448 -200.108785) (xy 210.493152 -200.06015) (xy 210.473229 -200.008059) (xy 210.461103 -199.953622)
			(xy 210.457032 -199.898) (xy 187.645846 -199.898) (xy 187.511066 -200.631298) (xy 216.35161 -200.631298)
			(xy 216.355681 -200.575676) (xy 216.367807 -200.521239) (xy 216.38773 -200.469148) (xy 216.415026 -200.420513)
			(xy 216.449112 -200.37637) (xy 216.489261 -200.337661) (xy 216.534619 -200.30521) (xy 216.584219 -200.279709)
			(xy 216.637003 -200.261702) (xy 216.691846 -200.251572) (xy 216.74758 -200.249535) (xy 216.803017 -200.255635)
			(xy 216.856974 -200.269741) (xy 216.908303 -200.291553) (xy 216.955909 -200.320607) (xy 216.998777 -200.356282)
			(xy 217.035994 -200.397819) (xy 217.066767 -200.444332) (xy 217.090439 -200.494829) (xy 217.093135 -200.50379)
			(xy 217.45702 -200.50379) (xy 217.457506 -200.476539) (xy 217.465262 -200.422591) (xy 217.480617 -200.370296)
			(xy 217.503259 -200.320719) (xy 217.532725 -200.274869) (xy 217.568416 -200.233678) (xy 217.609607 -200.197987)
			(xy 217.655457 -200.168521) (xy 217.705034 -200.145879) (xy 217.757329 -200.130524) (xy 217.811277 -200.122768)
			(xy 217.865779 -200.122768) (xy 217.919727 -200.130524) (xy 217.972022 -200.145879) (xy 218.021599 -200.168521)
			(xy 218.067449 -200.197987) (xy 218.10864 -200.233678) (xy 218.144331 -200.274869) (xy 218.146986 -200.279)
			(xy 218.419932 -200.279) (xy 218.424003 -200.223378) (xy 218.436129 -200.168941) (xy 218.456052 -200.11685)
			(xy 218.483348 -200.068215) (xy 218.517434 -200.024072) (xy 218.557583 -199.985363) (xy 218.602941 -199.952912)
			(xy 218.652541 -199.927411) (xy 218.705325 -199.909404) (xy 218.760168 -199.899274) (xy 218.815902 -199.897237)
			(xy 218.871339 -199.903337) (xy 218.925296 -199.917443) (xy 218.976625 -199.939255) (xy 219.024231 -199.968309)
			(xy 219.067099 -200.003984) (xy 219.104316 -200.045521) (xy 219.135089 -200.092034) (xy 219.158761 -200.142531)
			(xy 219.17376 -200.192386) (xy 225.617784 -200.192386) (xy 225.621855 -200.136764) (xy 225.633981 -200.082327)
			(xy 225.653904 -200.030236) (xy 225.6812 -199.981601) (xy 225.715286 -199.937458) (xy 225.755435 -199.898749)
			(xy 225.800793 -199.866298) (xy 225.850393 -199.840797) (xy 225.903177 -199.82279) (xy 225.95802 -199.81266)
			(xy 226.013754 -199.810623) (xy 226.069191 -199.816723) (xy 226.123148 -199.830829) (xy 226.174477 -199.852641)
			(xy 226.222083 -199.881695) (xy 226.264951 -199.91737) (xy 226.302168 -199.958907) (xy 226.332941 -200.00542)
			(xy 226.356613 -200.055917) (xy 226.372681 -200.109324) (xy 226.380801 -200.1645) (xy 226.38131 -200.192386)
			(xy 226.380801 -200.220272) (xy 226.372681 -200.275448) (xy 226.356613 -200.328855) (xy 226.332941 -200.379352)
			(xy 226.302168 -200.425865) (xy 226.264951 -200.467402) (xy 226.251442 -200.478644) (xy 239.057686 -200.478644)
			(xy 239.061757 -200.423022) (xy 239.073883 -200.368585) (xy 239.093806 -200.316494) (xy 239.121102 -200.267859)
			(xy 239.155188 -200.223716) (xy 239.195337 -200.185007) (xy 239.240695 -200.152556) (xy 239.290295 -200.127055)
			(xy 239.343079 -200.109048) (xy 239.397922 -200.098918) (xy 239.453656 -200.096881) (xy 239.509093 -200.102981)
			(xy 239.56305 -200.117087) (xy 239.614379 -200.138899) (xy 239.661985 -200.167953) (xy 239.704853 -200.203628)
			(xy 239.74207 -200.245165) (xy 239.772843 -200.291678) (xy 239.796515 -200.342175) (xy 239.812583 -200.395582)
			(xy 239.820703 -200.450758) (xy 239.821212 -200.478644) (xy 239.820864 -200.497694) (xy 241.038632 -200.497694)
			(xy 241.042703 -200.442072) (xy 241.054829 -200.387635) (xy 241.074752 -200.335544) (xy 241.102048 -200.286909)
			(xy 241.136134 -200.242766) (xy 241.176283 -200.204057) (xy 241.221641 -200.171606) (xy 241.271241 -200.146105)
			(xy 241.324025 -200.128098) (xy 241.378868 -200.117968) (xy 241.434602 -200.115931) (xy 241.490039 -200.122031)
			(xy 241.543996 -200.136137) (xy 241.595325 -200.157949) (xy 241.642931 -200.187003) (xy 241.685799 -200.222678)
			(xy 241.723016 -200.264215) (xy 241.753789 -200.310728) (xy 241.777461 -200.361225) (xy 241.789709 -200.401936)
			(xy 242.245132 -200.401936) (xy 242.249203 -200.346314) (xy 242.261329 -200.291877) (xy 242.281252 -200.239786)
			(xy 242.308548 -200.191151) (xy 242.342634 -200.147008) (xy 242.382783 -200.108299) (xy 242.428141 -200.075848)
			(xy 242.477741 -200.050347) (xy 242.530525 -200.03234) (xy 242.585368 -200.02221) (xy 242.641102 -200.020173)
			(xy 242.661886 -200.02246) (xy 250.416058 -200.02246) (xy 250.420129 -199.966838) (xy 250.432255 -199.912401)
			(xy 250.452178 -199.86031) (xy 250.479474 -199.811675) (xy 250.51356 -199.767532) (xy 250.553709 -199.728823)
			(xy 250.599067 -199.696372) (xy 250.648667 -199.670871) (xy 250.701451 -199.652864) (xy 250.756294 -199.642734)
			(xy 250.812028 -199.640697) (xy 250.867465 -199.646797) (xy 250.921422 -199.660903) (xy 250.972751 -199.682715)
			(xy 251.020357 -199.711769) (xy 251.063225 -199.747444) (xy 251.100442 -199.788981) (xy 251.131215 -199.835494)
			(xy 251.154887 -199.885991) (xy 251.170955 -199.939398) (xy 251.179075 -199.994574) (xy 251.179584 -200.02246)
			(xy 251.179075 -200.050346) (xy 251.170955 -200.105522) (xy 251.154887 -200.158929) (xy 251.131215 -200.209426)
			(xy 251.100442 -200.255939) (xy 251.063225 -200.297476) (xy 251.020357 -200.333151) (xy 250.972751 -200.362205)
			(xy 250.921422 -200.384017) (xy 250.867465 -200.398123) (xy 250.812028 -200.404223) (xy 250.756294 -200.402186)
			(xy 250.701451 -200.392056) (xy 250.648667 -200.374049) (xy 250.599067 -200.348548) (xy 250.553709 -200.316097)
			(xy 250.51356 -200.277388) (xy 250.479474 -200.233245) (xy 250.452178 -200.18461) (xy 250.432255 -200.132519)
			(xy 250.420129 -200.078082) (xy 250.416058 -200.02246) (xy 242.661886 -200.02246) (xy 242.696539 -200.026273)
			(xy 242.750496 -200.040379) (xy 242.801825 -200.062191) (xy 242.849431 -200.091245) (xy 242.892299 -200.12692)
			(xy 242.929516 -200.168457) (xy 242.960289 -200.21497) (xy 242.983961 -200.265467) (xy 243.000029 -200.318874)
			(xy 243.008149 -200.37405) (xy 243.008658 -200.401936) (xy 243.008149 -200.429822) (xy 243.000029 -200.484998)
			(xy 242.983961 -200.538405) (xy 242.960289 -200.588902) (xy 242.943667 -200.614026) (xy 247.569226 -200.614026)
			(xy 247.573297 -200.558404) (xy 247.585423 -200.503967) (xy 247.605346 -200.451876) (xy 247.632642 -200.403241)
			(xy 247.666728 -200.359098) (xy 247.706877 -200.320389) (xy 247.752235 -200.287938) (xy 247.801835 -200.262437)
			(xy 247.854619 -200.24443) (xy 247.909462 -200.2343) (xy 247.965196 -200.232263) (xy 248.020633 -200.238363)
			(xy 248.07459 -200.252469) (xy 248.125919 -200.274281) (xy 248.173525 -200.303335) (xy 248.216393 -200.33901)
			(xy 248.25361 -200.380547) (xy 248.284383 -200.42706) (xy 248.308055 -200.477557) (xy 248.324123 -200.530964)
			(xy 248.332243 -200.58614) (xy 248.332752 -200.614026) (xy 248.332243 -200.641912) (xy 248.324123 -200.697088)
			(xy 248.308055 -200.750495) (xy 248.284383 -200.800992) (xy 248.25361 -200.847505) (xy 248.216393 -200.889042)
			(xy 248.173525 -200.924717) (xy 248.125919 -200.953771) (xy 248.07459 -200.975583) (xy 248.020633 -200.989689)
			(xy 247.965196 -200.995789) (xy 247.909462 -200.993752) (xy 247.854619 -200.983622) (xy 247.801835 -200.965615)
			(xy 247.752235 -200.940114) (xy 247.706877 -200.907663) (xy 247.666728 -200.868954) (xy 247.632642 -200.824811)
			(xy 247.605346 -200.776176) (xy 247.585423 -200.724085) (xy 247.573297 -200.669648) (xy 247.569226 -200.614026)
			(xy 242.943667 -200.614026) (xy 242.929516 -200.635415) (xy 242.892299 -200.676952) (xy 242.849431 -200.712627)
			(xy 242.801825 -200.741681) (xy 242.750496 -200.763493) (xy 242.696539 -200.777599) (xy 242.641102 -200.783699)
			(xy 242.585368 -200.781662) (xy 242.530525 -200.771532) (xy 242.477741 -200.753525) (xy 242.428141 -200.728024)
			(xy 242.382783 -200.695573) (xy 242.342634 -200.656864) (xy 242.308548 -200.612721) (xy 242.281252 -200.564086)
			(xy 242.261329 -200.511995) (xy 242.249203 -200.457558) (xy 242.245132 -200.401936) (xy 241.789709 -200.401936)
			(xy 241.793529 -200.414632) (xy 241.801649 -200.469808) (xy 241.802158 -200.497694) (xy 241.801649 -200.52558)
			(xy 241.793529 -200.580756) (xy 241.777461 -200.634163) (xy 241.753789 -200.68466) (xy 241.723016 -200.731173)
			(xy 241.685799 -200.77271) (xy 241.642931 -200.808385) (xy 241.595325 -200.837439) (xy 241.543996 -200.859251)
			(xy 241.490039 -200.873357) (xy 241.434602 -200.879457) (xy 241.378868 -200.87742) (xy 241.324025 -200.86729)
			(xy 241.271241 -200.849283) (xy 241.221641 -200.823782) (xy 241.176283 -200.791331) (xy 241.136134 -200.752622)
			(xy 241.102048 -200.708479) (xy 241.074752 -200.659844) (xy 241.054829 -200.607753) (xy 241.042703 -200.553316)
			(xy 241.038632 -200.497694) (xy 239.820864 -200.497694) (xy 239.820703 -200.50653) (xy 239.812583 -200.561706)
			(xy 239.796515 -200.615113) (xy 239.772843 -200.66561) (xy 239.74207 -200.712123) (xy 239.704853 -200.75366)
			(xy 239.661985 -200.789335) (xy 239.614379 -200.818389) (xy 239.56305 -200.840201) (xy 239.509093 -200.854307)
			(xy 239.453656 -200.860407) (xy 239.397922 -200.85837) (xy 239.343079 -200.84824) (xy 239.290295 -200.830233)
			(xy 239.240695 -200.804732) (xy 239.195337 -200.772281) (xy 239.155188 -200.733572) (xy 239.121102 -200.689429)
			(xy 239.093806 -200.640794) (xy 239.073883 -200.588703) (xy 239.061757 -200.534266) (xy 239.057686 -200.478644)
			(xy 226.251442 -200.478644) (xy 226.222083 -200.503077) (xy 226.174477 -200.532131) (xy 226.123148 -200.553943)
			(xy 226.069191 -200.568049) (xy 226.013754 -200.574149) (xy 225.95802 -200.572112) (xy 225.903177 -200.561982)
			(xy 225.850393 -200.543975) (xy 225.800793 -200.518474) (xy 225.755435 -200.486023) (xy 225.715286 -200.447314)
			(xy 225.6812 -200.403171) (xy 225.653904 -200.354536) (xy 225.633981 -200.302445) (xy 225.621855 -200.248008)
			(xy 225.617784 -200.192386) (xy 219.17376 -200.192386) (xy 219.174829 -200.195938) (xy 219.182949 -200.251114)
			(xy 219.183458 -200.279) (xy 219.182949 -200.306886) (xy 219.174829 -200.362062) (xy 219.158761 -200.415469)
			(xy 219.135089 -200.465966) (xy 219.104316 -200.512479) (xy 219.067099 -200.554016) (xy 219.024231 -200.589691)
			(xy 218.976625 -200.618745) (xy 218.925296 -200.640557) (xy 218.871339 -200.654663) (xy 218.815902 -200.660763)
			(xy 218.760168 -200.658726) (xy 218.705325 -200.648596) (xy 218.652541 -200.630589) (xy 218.602941 -200.605088)
			(xy 218.557583 -200.572637) (xy 218.517434 -200.533928) (xy 218.483348 -200.489785) (xy 218.456052 -200.44115)
			(xy 218.436129 -200.389059) (xy 218.424003 -200.334622) (xy 218.419932 -200.279) (xy 218.146986 -200.279)
			(xy 218.173797 -200.320719) (xy 218.196439 -200.370296) (xy 218.211794 -200.422591) (xy 218.21955 -200.476539)
			(xy 218.220036 -200.50379) (xy 218.219614 -200.529607) (xy 218.21265 -200.580769) (xy 218.198848 -200.630524)
			(xy 218.189048 -200.654412) (xy 218.184918 -200.6651) (xy 218.185714 -200.687977) (xy 218.190572 -200.698354)
			(xy 218.227148 -200.76795) (xy 218.232936 -200.777674) (xy 218.250996 -200.791258) (xy 218.261946 -200.794112)
			(xy 218.2622 -200.794112) (xy 218.290532 -200.800533) (xy 218.345031 -200.820636) (xy 218.395853 -200.848767)
			(xy 218.441824 -200.884275) (xy 218.481883 -200.926341) (xy 218.515104 -200.973991) (xy 218.54072 -201.026126)
			(xy 218.558138 -201.081541) (xy 218.566957 -201.138956) (xy 218.567508 -201.168) (xy 219.835982 -201.168)
			(xy 219.840053 -201.112378) (xy 219.852179 -201.057941) (xy 219.872102 -201.00585) (xy 219.899398 -200.957215)
			(xy 219.933484 -200.913072) (xy 219.973633 -200.874363) (xy 220.018991 -200.841912) (xy 220.068591 -200.816411)
			(xy 220.121375 -200.798404) (xy 220.176218 -200.788274) (xy 220.231952 -200.786237) (xy 220.287389 -200.792337)
			(xy 220.341346 -200.806443) (xy 220.392675 -200.828255) (xy 220.440281 -200.857309) (xy 220.483149 -200.892984)
			(xy 220.520366 -200.934521) (xy 220.551139 -200.981034) (xy 220.574811 -201.031531) (xy 220.590879 -201.084938)
			(xy 220.598999 -201.140114) (xy 220.599508 -201.168) (xy 220.598999 -201.195886) (xy 220.590879 -201.251062)
			(xy 220.574811 -201.304469) (xy 220.551139 -201.354966) (xy 220.531828 -201.384154) (xy 223.148142 -201.384154)
			(xy 223.152213 -201.328532) (xy 223.164339 -201.274095) (xy 223.184262 -201.222004) (xy 223.211558 -201.173369)
			(xy 223.245644 -201.129226) (xy 223.285793 -201.090517) (xy 223.331151 -201.058066) (xy 223.380751 -201.032565)
			(xy 223.433535 -201.014558) (xy 223.488378 -201.004428) (xy 223.544112 -201.002391) (xy 223.599549 -201.008491)
			(xy 223.653506 -201.022597) (xy 223.704835 -201.044409) (xy 223.752441 -201.073463) (xy 223.795309 -201.109138)
			(xy 223.832526 -201.150675) (xy 223.863299 -201.197188) (xy 223.886971 -201.247685) (xy 223.903039 -201.301092)
			(xy 223.911159 -201.356268) (xy 223.911668 -201.384154) (xy 225.555046 -201.384154) (xy 225.559117 -201.328532)
			(xy 225.571243 -201.274095) (xy 225.591166 -201.222004) (xy 225.618462 -201.173369) (xy 225.652548 -201.129226)
			(xy 225.692697 -201.090517) (xy 225.738055 -201.058066) (xy 225.787655 -201.032565) (xy 225.840439 -201.014558)
			(xy 225.895282 -201.004428) (xy 225.951016 -201.002391) (xy 226.006453 -201.008491) (xy 226.06041 -201.022597)
			(xy 226.111739 -201.044409) (xy 226.159345 -201.073463) (xy 226.202213 -201.109138) (xy 226.23943 -201.150675)
			(xy 226.270203 -201.197188) (xy 226.290932 -201.241406) (xy 227.89718 -201.241406) (xy 227.901251 -201.185784)
			(xy 227.913377 -201.131347) (xy 227.9333 -201.079256) (xy 227.960596 -201.030621) (xy 227.994682 -200.986478)
			(xy 228.034831 -200.947769) (xy 228.080189 -200.915318) (xy 228.129789 -200.889817) (xy 228.182573 -200.87181)
			(xy 228.237416 -200.86168) (xy 228.29315 -200.859643) (xy 228.348587 -200.865743) (xy 228.402544 -200.879849)
			(xy 228.453873 -200.901661) (xy 228.501479 -200.930715) (xy 228.544347 -200.96639) (xy 228.581564 -201.007927)
			(xy 228.612337 -201.05444) (xy 228.636009 -201.104937) (xy 228.652077 -201.158344) (xy 228.660197 -201.21352)
			(xy 228.660706 -201.241406) (xy 228.660197 -201.269292) (xy 228.652077 -201.324468) (xy 228.636009 -201.377875)
			(xy 228.618539 -201.415142) (xy 255.40284 -201.415142) (xy 255.406911 -201.35952) (xy 255.419037 -201.305083)
			(xy 255.43896 -201.252992) (xy 255.466256 -201.204357) (xy 255.500342 -201.160214) (xy 255.540491 -201.121505)
			(xy 255.585849 -201.089054) (xy 255.635449 -201.063553) (xy 255.688233 -201.045546) (xy 255.743076 -201.035416)
			(xy 255.79881 -201.033379) (xy 255.854247 -201.039479) (xy 255.908204 -201.053585) (xy 255.959533 -201.075397)
			(xy 256.007139 -201.104451) (xy 256.050007 -201.140126) (xy 256.087224 -201.181663) (xy 256.117997 -201.228176)
			(xy 256.141669 -201.278673) (xy 256.157737 -201.33208) (xy 256.165857 -201.387256) (xy 256.166366 -201.415142)
			(xy 256.165857 -201.443028) (xy 256.157737 -201.498204) (xy 256.141669 -201.551611) (xy 256.123842 -201.58964)
			(xy 257.190238 -201.58964) (xy 257.194309 -201.534018) (xy 257.206435 -201.479581) (xy 257.226358 -201.42749)
			(xy 257.253654 -201.378855) (xy 257.28774 -201.334712) (xy 257.327889 -201.296003) (xy 257.373247 -201.263552)
			(xy 257.422847 -201.238051) (xy 257.475631 -201.220044) (xy 257.530474 -201.209914) (xy 257.586208 -201.207877)
			(xy 257.641645 -201.213977) (xy 257.695602 -201.228083) (xy 257.746931 -201.249895) (xy 257.794537 -201.278949)
			(xy 257.837405 -201.314624) (xy 257.874622 -201.356161) (xy 257.905395 -201.402674) (xy 257.929067 -201.453171)
			(xy 257.945135 -201.506578) (xy 257.953255 -201.561754) (xy 257.953764 -201.58964) (xy 257.953255 -201.617526)
			(xy 257.945135 -201.672702) (xy 257.929067 -201.726109) (xy 257.905395 -201.776606) (xy 257.880203 -201.814684)
			(xy 260.878586 -201.814684) (xy 260.882552 -201.730153) (xy 260.894417 -201.646366) (xy 260.914075 -201.564057)
			(xy 260.941355 -201.483951) (xy 260.976016 -201.406752) (xy 261.017754 -201.333137) (xy 261.066201 -201.263754)
			(xy 261.120933 -201.199213) (xy 261.181469 -201.140081) (xy 261.247275 -201.086877) (xy 261.317775 -201.040069)
			(xy 261.392347 -201.000068) (xy 261.470338 -200.967226) (xy 261.551062 -200.941832) (xy 261.633809 -200.924109)
			(xy 261.717851 -200.914211) (xy 261.802452 -200.912228) (xy 261.886866 -200.918175) (xy 261.970353 -200.932)
			(xy 262.052178 -200.953583) (xy 262.131622 -200.982733) (xy 262.207988 -201.019194) (xy 262.280604 -201.062646)
			(xy 262.348832 -201.112707) (xy 262.412072 -201.168937) (xy 262.469769 -201.230842) (xy 262.521416 -201.297878)
			(xy 262.558367 -201.356468) (xy 265.319254 -201.356468) (xy 265.323325 -201.300846) (xy 265.335451 -201.246409)
			(xy 265.355374 -201.194318) (xy 265.38267 -201.145683) (xy 265.416756 -201.10154) (xy 265.456905 -201.062831)
			(xy 265.502263 -201.03038) (xy 265.551863 -201.004879) (xy 265.604647 -200.986872) (xy 265.65949 -200.976742)
			(xy 265.715224 -200.974705) (xy 265.770661 -200.980805) (xy 265.824618 -200.994911) (xy 265.875947 -201.016723)
			(xy 265.923553 -201.045777) (xy 265.966421 -201.081452) (xy 266.003638 -201.122989) (xy 266.034411 -201.169502)
			(xy 266.058083 -201.219999) (xy 266.074151 -201.273406) (xy 266.082271 -201.328582) (xy 266.08278 -201.356468)
			(xy 266.082271 -201.384354) (xy 266.074151 -201.43953) (xy 266.058083 -201.492937) (xy 266.034411 -201.543434)
			(xy 266.003638 -201.589947) (xy 265.966421 -201.631484) (xy 265.923553 -201.667159) (xy 265.875947 -201.696213)
			(xy 265.824618 -201.718025) (xy 265.770661 -201.732131) (xy 265.715224 -201.738231) (xy 265.65949 -201.736194)
			(xy 265.604647 -201.726064) (xy 265.551863 -201.708057) (xy 265.502263 -201.682556) (xy 265.456905 -201.650105)
			(xy 265.416756 -201.611396) (xy 265.38267 -201.567253) (xy 265.355374 -201.518618) (xy 265.335451 -201.466527)
			(xy 265.323325 -201.41209) (xy 265.319254 -201.356468) (xy 262.558367 -201.356468) (xy 262.566558 -201.369455)
			(xy 262.6048 -201.444945) (xy 262.635804 -201.523684) (xy 262.659299 -201.604981) (xy 262.675078 -201.68812)
			(xy 262.683002 -201.772372) (xy 262.683498 -201.814684) (xy 262.683002 -201.856996) (xy 262.675078 -201.941248)
			(xy 262.659299 -202.024387) (xy 262.635804 -202.105684) (xy 262.6048 -202.184423) (xy 262.566558 -202.259913)
			(xy 262.525208 -202.325478) (xy 265.538202 -202.325478) (xy 265.542273 -202.269856) (xy 265.554399 -202.215419)
			(xy 265.574322 -202.163328) (xy 265.601618 -202.114693) (xy 265.635704 -202.07055) (xy 265.675853 -202.031841)
			(xy 265.721211 -201.99939) (xy 265.770811 -201.973889) (xy 265.823595 -201.955882) (xy 265.878438 -201.945752)
			(xy 265.934172 -201.943715) (xy 265.989609 -201.949815) (xy 266.043566 -201.963921) (xy 266.094895 -201.985733)
			(xy 266.142501 -202.014787) (xy 266.185369 -202.050462) (xy 266.222586 -202.091999) (xy 266.253359 -202.138512)
			(xy 266.277031 -202.189009) (xy 266.293099 -202.242416) (xy 266.301219 -202.297592) (xy 266.301728 -202.325478)
			(xy 266.301219 -202.353364) (xy 266.293099 -202.40854) (xy 266.277031 -202.461947) (xy 266.253359 -202.512444)
			(xy 266.222586 -202.558957) (xy 266.185369 -202.600494) (xy 266.142501 -202.636169) (xy 266.094895 -202.665223)
			(xy 266.043566 -202.687035) (xy 265.989609 -202.701141) (xy 265.934172 -202.707241) (xy 265.878438 -202.705204)
			(xy 265.823595 -202.695074) (xy 265.770811 -202.677067) (xy 265.721211 -202.651566) (xy 265.675853 -202.619115)
			(xy 265.635704 -202.580406) (xy 265.601618 -202.536263) (xy 265.574322 -202.487628) (xy 265.554399 -202.435537)
			(xy 265.542273 -202.3811) (xy 265.538202 -202.325478) (xy 262.525208 -202.325478) (xy 262.521416 -202.33149)
			(xy 262.469769 -202.398526) (xy 262.412072 -202.460431) (xy 262.348832 -202.516661) (xy 262.280604 -202.566722)
			(xy 262.207988 -202.610174) (xy 262.131622 -202.646635) (xy 262.052178 -202.675785) (xy 261.970353 -202.697368)
			(xy 261.886866 -202.711193) (xy 261.802452 -202.71714) (xy 261.717851 -202.715157) (xy 261.633809 -202.705259)
			(xy 261.551062 -202.687536) (xy 261.470338 -202.662142) (xy 261.392347 -202.6293) (xy 261.317775 -202.589299)
			(xy 261.247275 -202.542491) (xy 261.181469 -202.489287) (xy 261.120933 -202.430155) (xy 261.066201 -202.365614)
			(xy 261.017754 -202.296231) (xy 260.976016 -202.222616) (xy 260.941355 -202.145417) (xy 260.914075 -202.065311)
			(xy 260.894417 -201.983002) (xy 260.882552 -201.899215) (xy 260.878586 -201.814684) (xy 257.880203 -201.814684)
			(xy 257.874622 -201.823119) (xy 257.837405 -201.864656) (xy 257.794537 -201.900331) (xy 257.746931 -201.929385)
			(xy 257.695602 -201.951197) (xy 257.641645 -201.965303) (xy 257.586208 -201.971403) (xy 257.530474 -201.969366)
			(xy 257.475631 -201.959236) (xy 257.422847 -201.941229) (xy 257.373247 -201.915728) (xy 257.327889 -201.883277)
			(xy 257.28774 -201.844568) (xy 257.253654 -201.800425) (xy 257.226358 -201.75179) (xy 257.206435 -201.699699)
			(xy 257.194309 -201.645262) (xy 257.190238 -201.58964) (xy 256.123842 -201.58964) (xy 256.117997 -201.602108)
			(xy 256.087224 -201.648621) (xy 256.050007 -201.690158) (xy 256.007139 -201.725833) (xy 255.959533 -201.754887)
			(xy 255.908204 -201.776699) (xy 255.854247 -201.790805) (xy 255.79881 -201.796905) (xy 255.743076 -201.794868)
			(xy 255.688233 -201.784738) (xy 255.635449 -201.766731) (xy 255.585849 -201.74123) (xy 255.540491 -201.708779)
			(xy 255.500342 -201.67007) (xy 255.466256 -201.625927) (xy 255.43896 -201.577292) (xy 255.419037 -201.525201)
			(xy 255.406911 -201.470764) (xy 255.40284 -201.415142) (xy 228.618539 -201.415142) (xy 228.612337 -201.428372)
			(xy 228.581564 -201.474885) (xy 228.544347 -201.516422) (xy 228.501479 -201.552097) (xy 228.453873 -201.581151)
			(xy 228.402544 -201.602963) (xy 228.348587 -201.617069) (xy 228.29315 -201.623169) (xy 228.237416 -201.621132)
			(xy 228.182573 -201.611002) (xy 228.129789 -201.592995) (xy 228.080189 -201.567494) (xy 228.034831 -201.535043)
			(xy 227.994682 -201.496334) (xy 227.960596 -201.452191) (xy 227.9333 -201.403556) (xy 227.913377 -201.351465)
			(xy 227.901251 -201.297028) (xy 227.89718 -201.241406) (xy 226.290932 -201.241406) (xy 226.293875 -201.247685)
			(xy 226.309943 -201.301092) (xy 226.318063 -201.356268) (xy 226.318572 -201.384154) (xy 226.318063 -201.41204)
			(xy 226.309943 -201.467216) (xy 226.293875 -201.520623) (xy 226.270203 -201.57112) (xy 226.23943 -201.617633)
			(xy 226.202213 -201.65917) (xy 226.159345 -201.694845) (xy 226.111739 -201.723899) (xy 226.06041 -201.745711)
			(xy 226.006453 -201.759817) (xy 225.951016 -201.765917) (xy 225.895282 -201.76388) (xy 225.840439 -201.75375)
			(xy 225.787655 -201.735743) (xy 225.738055 -201.710242) (xy 225.692697 -201.677791) (xy 225.652548 -201.639082)
			(xy 225.618462 -201.594939) (xy 225.591166 -201.546304) (xy 225.571243 -201.494213) (xy 225.559117 -201.439776)
			(xy 225.555046 -201.384154) (xy 223.911668 -201.384154) (xy 223.911159 -201.41204) (xy 223.903039 -201.467216)
			(xy 223.886971 -201.520623) (xy 223.863299 -201.57112) (xy 223.832526 -201.617633) (xy 223.795309 -201.65917)
			(xy 223.752441 -201.694845) (xy 223.704835 -201.723899) (xy 223.653506 -201.745711) (xy 223.599549 -201.759817)
			(xy 223.544112 -201.765917) (xy 223.488378 -201.76388) (xy 223.433535 -201.75375) (xy 223.380751 -201.735743)
			(xy 223.331151 -201.710242) (xy 223.285793 -201.677791) (xy 223.245644 -201.639082) (xy 223.211558 -201.594939)
			(xy 223.184262 -201.546304) (xy 223.164339 -201.494213) (xy 223.152213 -201.439776) (xy 223.148142 -201.384154)
			(xy 220.531828 -201.384154) (xy 220.520366 -201.401479) (xy 220.483149 -201.443016) (xy 220.440281 -201.478691)
			(xy 220.392675 -201.507745) (xy 220.341346 -201.529557) (xy 220.287389 -201.543663) (xy 220.231952 -201.549763)
			(xy 220.176218 -201.547726) (xy 220.121375 -201.537596) (xy 220.068591 -201.519589) (xy 220.018991 -201.494088)
			(xy 219.973633 -201.461637) (xy 219.933484 -201.422928) (xy 219.899398 -201.378785) (xy 219.872102 -201.33015)
			(xy 219.852179 -201.278059) (xy 219.840053 -201.223622) (xy 219.835982 -201.168) (xy 218.567508 -201.168)
			(xy 218.567022 -201.195251) (xy 218.559266 -201.249199) (xy 218.543911 -201.301494) (xy 218.521269 -201.351071)
			(xy 218.491803 -201.396921) (xy 218.456112 -201.438112) (xy 218.414921 -201.473803) (xy 218.369071 -201.503269)
			(xy 218.319494 -201.525911) (xy 218.267199 -201.541266) (xy 218.213251 -201.549022) (xy 218.158749 -201.549022)
			(xy 218.104801 -201.541266) (xy 218.052506 -201.525911) (xy 218.002929 -201.503269) (xy 217.957079 -201.473803)
			(xy 217.915888 -201.438112) (xy 217.880197 -201.396921) (xy 217.850731 -201.351071) (xy 217.828089 -201.301494)
			(xy 217.812734 -201.249199) (xy 217.804978 -201.195251) (xy 217.804492 -201.168) (xy 217.804908 -201.142183)
			(xy 217.811874 -201.091021) (xy 217.825678 -201.041266) (xy 217.83548 -201.017378) (xy 217.839622 -201.006693)
			(xy 217.838821 -200.983812) (xy 217.833956 -200.973436) (xy 217.79738 -200.90384) (xy 217.791599 -200.89411)
			(xy 217.773535 -200.880525) (xy 217.762582 -200.877678) (xy 217.762328 -200.877678) (xy 217.733981 -200.871317)
			(xy 217.679483 -200.851203) (xy 217.628662 -200.823063) (xy 217.582692 -200.787546) (xy 217.542635 -200.745473)
			(xy 217.509416 -200.697816) (xy 217.483803 -200.645675) (xy 217.466387 -200.590255) (xy 217.457571 -200.532836)
			(xy 217.45702 -200.50379) (xy 217.093135 -200.50379) (xy 217.106507 -200.548236) (xy 217.114627 -200.603412)
			(xy 217.115136 -200.631298) (xy 217.114627 -200.659184) (xy 217.106507 -200.71436) (xy 217.090439 -200.767767)
			(xy 217.066767 -200.818264) (xy 217.035994 -200.864777) (xy 216.998777 -200.906314) (xy 216.955909 -200.941989)
			(xy 216.908303 -200.971043) (xy 216.856974 -200.992855) (xy 216.803017 -201.006961) (xy 216.74758 -201.013061)
			(xy 216.691846 -201.011024) (xy 216.637003 -201.000894) (xy 216.584219 -200.982887) (xy 216.534619 -200.957386)
			(xy 216.489261 -200.924935) (xy 216.449112 -200.886226) (xy 216.415026 -200.842083) (xy 216.38773 -200.793448)
			(xy 216.367807 -200.741357) (xy 216.355681 -200.68692) (xy 216.35161 -200.631298) (xy 187.511066 -200.631298)
			(xy 187.397714 -201.24801) (xy 209.00085 -201.24801) (xy 209.004921 -201.192388) (xy 209.017047 -201.137951)
			(xy 209.03697 -201.08586) (xy 209.064266 -201.037225) (xy 209.098352 -200.993082) (xy 209.138501 -200.954373)
			(xy 209.183859 -200.921922) (xy 209.233459 -200.896421) (xy 209.286243 -200.878414) (xy 209.341086 -200.868284)
			(xy 209.39682 -200.866247) (xy 209.452257 -200.872347) (xy 209.506214 -200.886453) (xy 209.557543 -200.908265)
			(xy 209.605149 -200.937319) (xy 209.648017 -200.972994) (xy 209.685234 -201.014531) (xy 209.716007 -201.061044)
			(xy 209.739679 -201.111541) (xy 209.755747 -201.164948) (xy 209.763867 -201.220124) (xy 209.764376 -201.24801)
			(xy 209.763867 -201.275896) (xy 209.755747 -201.331072) (xy 209.739679 -201.384479) (xy 209.716007 -201.434976)
			(xy 209.685234 -201.481489) (xy 209.648017 -201.523026) (xy 209.605149 -201.558701) (xy 209.557543 -201.587755)
			(xy 209.506214 -201.609567) (xy 209.452257 -201.623673) (xy 209.39682 -201.629773) (xy 209.341086 -201.627736)
			(xy 209.286243 -201.617606) (xy 209.233459 -201.599599) (xy 209.183859 -201.574098) (xy 209.138501 -201.541647)
			(xy 209.098352 -201.502938) (xy 209.064266 -201.458795) (xy 209.03697 -201.41016) (xy 209.017047 -201.358069)
			(xy 209.004921 -201.303632) (xy 209.00085 -201.24801) (xy 187.397714 -201.24801) (xy 187.295707 -201.803)
			(xy 215.390982 -201.803) (xy 215.395053 -201.747378) (xy 215.407179 -201.692941) (xy 215.427102 -201.64085)
			(xy 215.454398 -201.592215) (xy 215.488484 -201.548072) (xy 215.528633 -201.509363) (xy 215.573991 -201.476912)
			(xy 215.623591 -201.451411) (xy 215.676375 -201.433404) (xy 215.731218 -201.423274) (xy 215.786952 -201.421237)
			(xy 215.842389 -201.427337) (xy 215.896346 -201.441443) (xy 215.947675 -201.463255) (xy 215.995281 -201.492309)
			(xy 216.038149 -201.527984) (xy 216.075366 -201.569521) (xy 216.106139 -201.616034) (xy 216.129811 -201.666531)
			(xy 216.145879 -201.719938) (xy 216.153999 -201.775114) (xy 216.154508 -201.803) (xy 216.153999 -201.830886)
			(xy 216.145879 -201.886062) (xy 216.129811 -201.939469) (xy 216.106139 -201.989966) (xy 216.075366 -202.036479)
			(xy 216.038149 -202.078016) (xy 215.995281 -202.113691) (xy 215.947675 -202.142745) (xy 215.896346 -202.164557)
			(xy 215.842389 -202.178663) (xy 215.793886 -202.184) (xy 217.803982 -202.184) (xy 217.808053 -202.128378)
			(xy 217.820179 -202.073941) (xy 217.840102 -202.02185) (xy 217.867398 -201.973215) (xy 217.901484 -201.929072)
			(xy 217.941633 -201.890363) (xy 217.986991 -201.857912) (xy 218.036591 -201.832411) (xy 218.089375 -201.814404)
			(xy 218.144218 -201.804274) (xy 218.199952 -201.802237) (xy 218.255389 -201.808337) (xy 218.309346 -201.822443)
			(xy 218.360675 -201.844255) (xy 218.408281 -201.873309) (xy 218.451149 -201.908984) (xy 218.488366 -201.950521)
			(xy 218.519139 -201.997034) (xy 218.542811 -202.047531) (xy 218.558879 -202.100938) (xy 218.559116 -202.10255)
			(xy 230.216966 -202.10255) (xy 230.216966 -202.04805) (xy 230.224722 -201.994103) (xy 230.240075 -201.94181)
			(xy 230.262715 -201.892233) (xy 230.292178 -201.846383) (xy 230.327867 -201.805193) (xy 230.369054 -201.7695)
			(xy 230.414902 -201.740032) (xy 230.464476 -201.717388) (xy 230.516768 -201.702029) (xy 230.570714 -201.694268)
			(xy 230.597964 -201.69378) (xy 230.624245 -201.694245) (xy 230.676311 -201.701457) (xy 230.726894 -201.715748)
			(xy 230.775036 -201.736848) (xy 230.819825 -201.764358) (xy 230.860413 -201.797756) (xy 230.896032 -201.83641)
			(xy 230.926007 -201.879589) (xy 230.94977 -201.926473) (xy 230.966871 -201.976176) (xy 230.97236 -202.001882)
			(xy 230.974447 -202.010635) (xy 230.983838 -202.025973) (xy 230.997956 -202.037113) (xy 231.006396 -202.040236)
			(xy 231.104186 -202.071986) (xy 231.13111 -202.066144) (xy 231.14127 -202.056492) (xy 231.162567 -202.037401)
			(xy 231.209799 -202.005147) (xy 231.261315 -201.980304) (xy 231.315962 -201.963426) (xy 231.372515 -201.954893)
			(xy 231.401112 -201.954384) (xy 231.428879 -201.954885) (xy 231.483826 -201.962938) (xy 231.537026 -201.978873)
			(xy 231.587352 -202.002352) (xy 231.633743 -202.03288) (xy 231.675218 -202.069811) (xy 231.7109 -202.112365)
			(xy 231.740036 -202.159642) (xy 231.762009 -202.210645) (xy 231.769666 -202.23734) (xy 231.77233 -202.2458)
			(xy 231.782508 -202.26031) (xy 231.797023 -202.27048) (xy 231.80548 -202.273154) (xy 231.890316 -202.296268)
			(xy 231.898971 -202.298295) (xy 231.916677 -202.296803) (xy 231.932801 -202.28934) (xy 231.939338 -202.283314)
			(xy 231.960903 -202.262844) (xy 232.009179 -202.228143) (xy 232.062256 -202.201354) (xy 232.118847 -202.183126)
			(xy 232.177581 -202.1739) (xy 232.207308 -202.173332) (xy 232.234562 -202.173738) (xy 232.288514 -202.181497)
			(xy 232.340814 -202.196854) (xy 232.341033 -202.196954) (xy 240.818668 -202.196954) (xy 240.822739 -202.141332)
			(xy 240.834865 -202.086895) (xy 240.854788 -202.034804) (xy 240.882084 -201.986169) (xy 240.91617 -201.942026)
			(xy 240.956319 -201.903317) (xy 241.001677 -201.870866) (xy 241.051277 -201.845365) (xy 241.104061 -201.827358)
			(xy 241.158904 -201.817228) (xy 241.214638 -201.815191) (xy 241.270075 -201.821291) (xy 241.324032 -201.835397)
			(xy 241.375361 -201.857209) (xy 241.422967 -201.886263) (xy 241.465835 -201.921938) (xy 241.503052 -201.963475)
			(xy 241.533825 -202.009988) (xy 241.557497 -202.060485) (xy 241.573565 -202.113892) (xy 241.581685 -202.169068)
			(xy 241.582194 -202.196954) (xy 241.581685 -202.22484) (xy 241.573565 -202.280016) (xy 241.557497 -202.333423)
			(xy 241.533825 -202.38392) (xy 241.503052 -202.430433) (xy 241.465835 -202.47197) (xy 241.422967 -202.507645)
			(xy 241.375361 -202.536699) (xy 241.324032 -202.558511) (xy 241.270075 -202.572617) (xy 241.214638 -202.578717)
			(xy 241.158904 -202.57668) (xy 241.104061 -202.56655) (xy 241.051277 -202.548543) (xy 241.001677 -202.523042)
			(xy 240.956319 -202.490591) (xy 240.91617 -202.451882) (xy 240.882084 -202.407739) (xy 240.854788 -202.359104)
			(xy 240.834865 -202.307013) (xy 240.822739 -202.252576) (xy 240.818668 -202.196954) (xy 232.341033 -202.196954)
			(xy 232.390395 -202.219498) (xy 232.436249 -202.248968) (xy 232.477443 -202.284663) (xy 232.513137 -202.325857)
			(xy 232.542606 -202.371712) (xy 232.565249 -202.421294) (xy 232.580605 -202.473594) (xy 232.588362 -202.527546)
			(xy 232.588362 -202.582054) (xy 232.580605 -202.636006) (xy 232.565249 -202.688306) (xy 232.542606 -202.737888)
			(xy 232.513137 -202.783743) (xy 232.477443 -202.824937) (xy 232.436249 -202.860632) (xy 232.390395 -202.890102)
			(xy 232.340814 -202.912746) (xy 232.288514 -202.928103) (xy 232.234562 -202.935862) (xy 232.207308 -202.936348)
			(xy 232.179543 -202.935806) (xy 232.124598 -202.927756) (xy 232.071401 -202.911826) (xy 232.021076 -202.888351)
			(xy 231.974686 -202.857829) (xy 231.933211 -202.820903) (xy 231.897527 -202.778355) (xy 231.868389 -202.731082)
			(xy 231.846413 -202.680085) (xy 231.838754 -202.653392) (xy 231.836061 -202.644943) (xy 231.825897 -202.630431)
			(xy 231.811393 -202.620256) (xy 231.80294 -202.617578) (xy 231.718104 -202.594464) (xy 231.709447 -202.592444)
			(xy 231.691742 -202.59393) (xy 231.675618 -202.601392) (xy 231.669082 -202.607418) (xy 231.647514 -202.627884)
			(xy 231.599238 -202.662584) (xy 231.546162 -202.689374) (xy 231.489572 -202.707603) (xy 231.430839 -202.71683)
			(xy 231.401112 -202.7174) (xy 231.374829 -202.716973) (xy 231.322761 -202.709758) (xy 231.272177 -202.695463)
			(xy 231.224034 -202.674358) (xy 231.179244 -202.646844) (xy 231.138656 -202.613442) (xy 231.103037 -202.574783)
			(xy 231.073064 -202.531601) (xy 231.049303 -202.484712) (xy 231.032204 -202.435005) (xy 231.026716 -202.409298)
			(xy 231.024596 -202.400556) (xy 231.015214 -202.385222) (xy 231.001112 -202.374075) (xy 230.99268 -202.370944)
			(xy 230.89489 -202.339194) (xy 230.867966 -202.345036) (xy 230.857806 -202.354688) (xy 230.836516 -202.373788)
			(xy 230.789283 -202.40604) (xy 230.737765 -202.430883) (xy 230.683116 -202.447758) (xy 230.626561 -202.456289)
			(xy 230.597964 -202.456796) (xy 230.570714 -202.456332) (xy 230.516768 -202.448571) (xy 230.464476 -202.433212)
			(xy 230.414902 -202.410568) (xy 230.369054 -202.3811) (xy 230.327867 -202.345407) (xy 230.292178 -202.304217)
			(xy 230.262715 -202.258367) (xy 230.240075 -202.20879) (xy 230.224722 -202.156497) (xy 230.216966 -202.10255)
			(xy 218.559116 -202.10255) (xy 218.566999 -202.156114) (xy 218.567508 -202.184) (xy 218.566999 -202.211886)
			(xy 218.558879 -202.267062) (xy 218.542811 -202.320469) (xy 218.519139 -202.370966) (xy 218.488366 -202.417479)
			(xy 218.451149 -202.459016) (xy 218.408281 -202.494691) (xy 218.360675 -202.523745) (xy 218.314398 -202.54341)
			(xy 222.22409 -202.54341) (xy 222.228161 -202.487788) (xy 222.240287 -202.433351) (xy 222.26021 -202.38126)
			(xy 222.287506 -202.332625) (xy 222.321592 -202.288482) (xy 222.361741 -202.249773) (xy 222.407099 -202.217322)
			(xy 222.456699 -202.191821) (xy 222.509483 -202.173814) (xy 222.564326 -202.163684) (xy 222.62006 -202.161647)
			(xy 222.675497 -202.167747) (xy 222.729454 -202.181853) (xy 222.780783 -202.203665) (xy 222.828389 -202.232719)
			(xy 222.871257 -202.268394) (xy 222.908474 -202.309931) (xy 222.939247 -202.356444) (xy 222.962919 -202.406941)
			(xy 222.978987 -202.460348) (xy 222.987107 -202.515524) (xy 222.987616 -202.54341) (xy 222.987107 -202.571296)
			(xy 222.978987 -202.626472) (xy 222.962919 -202.679879) (xy 222.939247 -202.730376) (xy 222.908474 -202.776889)
			(xy 222.871257 -202.818426) (xy 222.828389 -202.854101) (xy 222.780783 -202.883155) (xy 222.729454 -202.904967)
			(xy 222.675497 -202.919073) (xy 222.62006 -202.925173) (xy 222.564326 -202.923136) (xy 222.509483 -202.913006)
			(xy 222.456699 -202.894999) (xy 222.407099 -202.869498) (xy 222.361741 -202.837047) (xy 222.321592 -202.798338)
			(xy 222.287506 -202.754195) (xy 222.26021 -202.70556) (xy 222.240287 -202.653469) (xy 222.228161 -202.599032)
			(xy 222.22409 -202.54341) (xy 218.314398 -202.54341) (xy 218.309346 -202.545557) (xy 218.255389 -202.559663)
			(xy 218.199952 -202.565763) (xy 218.144218 -202.563726) (xy 218.089375 -202.553596) (xy 218.036591 -202.535589)
			(xy 217.986991 -202.510088) (xy 217.941633 -202.477637) (xy 217.901484 -202.438928) (xy 217.867398 -202.394785)
			(xy 217.840102 -202.34615) (xy 217.820179 -202.294059) (xy 217.808053 -202.239622) (xy 217.803982 -202.184)
			(xy 215.793886 -202.184) (xy 215.786952 -202.184763) (xy 215.731218 -202.182726) (xy 215.676375 -202.172596)
			(xy 215.623591 -202.154589) (xy 215.573991 -202.129088) (xy 215.528633 -202.096637) (xy 215.488484 -202.057928)
			(xy 215.454398 -202.013785) (xy 215.427102 -201.96515) (xy 215.407179 -201.913059) (xy 215.395053 -201.858622)
			(xy 215.390982 -201.803) (xy 187.295707 -201.803) (xy 187.178994 -202.438) (xy 207.389982 -202.438)
			(xy 207.394053 -202.382378) (xy 207.406179 -202.327941) (xy 207.426102 -202.27585) (xy 207.453398 -202.227215)
			(xy 207.487484 -202.183072) (xy 207.527633 -202.144363) (xy 207.572991 -202.111912) (xy 207.622591 -202.086411)
			(xy 207.675375 -202.068404) (xy 207.730218 -202.058274) (xy 207.785952 -202.056237) (xy 207.841389 -202.062337)
			(xy 207.895346 -202.076443) (xy 207.946675 -202.098255) (xy 207.994281 -202.127309) (xy 208.037149 -202.162984)
			(xy 208.074366 -202.204521) (xy 208.105139 -202.251034) (xy 208.128811 -202.301531) (xy 208.13166 -202.311)
			(xy 209.040982 -202.311) (xy 209.045053 -202.255378) (xy 209.057179 -202.200941) (xy 209.077102 -202.14885)
			(xy 209.104398 -202.100215) (xy 209.138484 -202.056072) (xy 209.178633 -202.017363) (xy 209.223991 -201.984912)
			(xy 209.273591 -201.959411) (xy 209.326375 -201.941404) (xy 209.381218 -201.931274) (xy 209.436952 -201.929237)
			(xy 209.492389 -201.935337) (xy 209.546346 -201.949443) (xy 209.597675 -201.971255) (xy 209.645281 -202.000309)
			(xy 209.688149 -202.035984) (xy 209.725366 -202.077521) (xy 209.756139 -202.124034) (xy 209.779811 -202.174531)
			(xy 209.795879 -202.227938) (xy 209.803999 -202.283114) (xy 209.804508 -202.311) (xy 209.803999 -202.338886)
			(xy 209.795879 -202.394062) (xy 209.779811 -202.447469) (xy 209.756139 -202.497966) (xy 209.725366 -202.544479)
			(xy 209.688149 -202.586016) (xy 209.645281 -202.621691) (xy 209.597675 -202.650745) (xy 209.546346 -202.672557)
			(xy 209.492389 -202.686663) (xy 209.436952 -202.692763) (xy 209.381218 -202.690726) (xy 209.326375 -202.680596)
			(xy 209.273591 -202.662589) (xy 209.223991 -202.637088) (xy 209.178633 -202.604637) (xy 209.138484 -202.565928)
			(xy 209.104398 -202.521785) (xy 209.077102 -202.47315) (xy 209.057179 -202.421059) (xy 209.045053 -202.366622)
			(xy 209.040982 -202.311) (xy 208.13166 -202.311) (xy 208.144879 -202.354938) (xy 208.152999 -202.410114)
			(xy 208.153508 -202.438) (xy 208.152999 -202.465886) (xy 208.144879 -202.521062) (xy 208.128811 -202.574469)
			(xy 208.105139 -202.624966) (xy 208.074366 -202.671479) (xy 208.037149 -202.713016) (xy 207.994281 -202.748691)
			(xy 207.946675 -202.777745) (xy 207.895346 -202.799557) (xy 207.841389 -202.813663) (xy 207.785952 -202.819763)
			(xy 207.730218 -202.817726) (xy 207.675375 -202.807596) (xy 207.622591 -202.789589) (xy 207.572991 -202.764088)
			(xy 207.527633 -202.731637) (xy 207.487484 -202.692928) (xy 207.453398 -202.648785) (xy 207.426102 -202.60015)
			(xy 207.406179 -202.548059) (xy 207.394053 -202.493622) (xy 207.389982 -202.438) (xy 187.178994 -202.438)
			(xy 187.015596 -203.327) (xy 209.040982 -203.327) (xy 209.045053 -203.271378) (xy 209.057179 -203.216941)
			(xy 209.077102 -203.16485) (xy 209.104398 -203.116215) (xy 209.138484 -203.072072) (xy 209.178633 -203.033363)
			(xy 209.223991 -203.000912) (xy 209.273591 -202.975411) (xy 209.326375 -202.957404) (xy 209.381218 -202.947274)
			(xy 209.436952 -202.945237) (xy 209.492389 -202.951337) (xy 209.546346 -202.965443) (xy 209.597675 -202.987255)
			(xy 209.645281 -203.016309) (xy 209.688149 -203.051984) (xy 209.706979 -203.073) (xy 215.390982 -203.073)
			(xy 215.395053 -203.017378) (xy 215.407179 -202.962941) (xy 215.427102 -202.91085) (xy 215.454398 -202.862215)
			(xy 215.488484 -202.818072) (xy 215.528633 -202.779363) (xy 215.573991 -202.746912) (xy 215.623591 -202.721411)
			(xy 215.676375 -202.703404) (xy 215.731218 -202.693274) (xy 215.786952 -202.691237) (xy 215.842389 -202.697337)
			(xy 215.896346 -202.711443) (xy 215.947675 -202.733255) (xy 215.995281 -202.762309) (xy 216.038149 -202.797984)
			(xy 216.075366 -202.839521) (xy 216.106139 -202.886034) (xy 216.129811 -202.936531) (xy 216.145879 -202.989938)
			(xy 216.153999 -203.045114) (xy 216.154508 -203.073) (xy 216.153999 -203.100886) (xy 216.145879 -203.156062)
			(xy 216.13266 -203.2) (xy 217.803982 -203.2) (xy 217.808053 -203.144378) (xy 217.820179 -203.089941)
			(xy 217.840102 -203.03785) (xy 217.867398 -202.989215) (xy 217.901484 -202.945072) (xy 217.941633 -202.906363)
			(xy 217.986991 -202.873912) (xy 218.036591 -202.848411) (xy 218.089375 -202.830404) (xy 218.144218 -202.820274)
			(xy 218.199952 -202.818237) (xy 218.255389 -202.824337) (xy 218.309346 -202.838443) (xy 218.360675 -202.860255)
			(xy 218.408281 -202.889309) (xy 218.451149 -202.924984) (xy 218.488366 -202.966521) (xy 218.519139 -203.013034)
			(xy 218.542811 -203.063531) (xy 218.558879 -203.116938) (xy 218.566999 -203.172114) (xy 218.567508 -203.2)
			(xy 218.566999 -203.227886) (xy 218.558879 -203.283062) (xy 218.542811 -203.336469) (xy 218.519139 -203.386966)
			(xy 218.488366 -203.433479) (xy 218.462697 -203.462128) (xy 220.606872 -203.462128) (xy 220.610943 -203.406506)
			(xy 220.623069 -203.352069) (xy 220.642992 -203.299978) (xy 220.670288 -203.251343) (xy 220.704374 -203.2072)
			(xy 220.744523 -203.168491) (xy 220.789881 -203.13604) (xy 220.839481 -203.110539) (xy 220.892265 -203.092532)
			(xy 220.947108 -203.082402) (xy 221.002842 -203.080365) (xy 221.058279 -203.086465) (xy 221.112236 -203.100571)
			(xy 221.163565 -203.122383) (xy 221.211171 -203.151437) (xy 221.254039 -203.187112) (xy 221.291256 -203.228649)
			(xy 221.322029 -203.275162) (xy 221.345701 -203.325659) (xy 221.361769 -203.379066) (xy 221.363302 -203.389484)
			(xy 221.848932 -203.389484) (xy 221.853003 -203.333862) (xy 221.865129 -203.279425) (xy 221.885052 -203.227334)
			(xy 221.912348 -203.178699) (xy 221.946434 -203.134556) (xy 221.986583 -203.095847) (xy 222.031941 -203.063396)
			(xy 222.081541 -203.037895) (xy 222.134325 -203.019888) (xy 222.189168 -203.009758) (xy 222.244902 -203.007721)
			(xy 222.300339 -203.013821) (xy 222.354296 -203.027927) (xy 222.405625 -203.049739) (xy 222.453231 -203.078793)
			(xy 222.496099 -203.114468) (xy 222.533316 -203.156005) (xy 222.564089 -203.202518) (xy 222.587761 -203.253015)
			(xy 222.603829 -203.306422) (xy 222.611949 -203.361598) (xy 222.612458 -203.389484) (xy 222.612138 -203.40701)
			(xy 224.133156 -203.40701) (xy 224.133613 -203.379022) (xy 224.141779 -203.323647) (xy 224.157951 -203.270059)
			(xy 224.181783 -203.219411) (xy 224.212763 -203.172791) (xy 224.250224 -203.1312) (xy 224.293363 -203.095531)
			(xy 224.317052 -203.08062) (xy 224.329285 -203.072719) (xy 224.348953 -203.051256) (xy 224.361766 -203.025116)
			(xy 224.366682 -202.996422) (xy 224.363302 -202.967507) (xy 224.351901 -202.940721) (xy 224.333405 -202.91824)
			(xy 224.321624 -202.909678) (xy 224.299973 -202.894372) (xy 224.260715 -202.858733) (xy 224.226773 -202.818)
			(xy 224.198799 -202.772958) (xy 224.177335 -202.724475) (xy 224.162793 -202.673486) (xy 224.155453 -202.620975)
			(xy 224.155 -202.594464) (xy 224.155486 -202.567213) (xy 224.163242 -202.513265) (xy 224.178597 -202.46097)
			(xy 224.201239 -202.411393) (xy 224.230705 -202.365543) (xy 224.266396 -202.324352) (xy 224.307587 -202.288661)
			(xy 224.353437 -202.259195) (xy 224.403014 -202.236553) (xy 224.455309 -202.221198) (xy 224.509257 -202.213442)
			(xy 224.563759 -202.213442) (xy 224.617707 -202.221198) (xy 224.670002 -202.236553) (xy 224.719579 -202.259195)
			(xy 224.765429 -202.288661) (xy 224.80662 -202.324352) (xy 224.842311 -202.365543) (xy 224.871777 -202.411393)
			(xy 224.894419 -202.46097) (xy 224.909774 -202.513265) (xy 224.91753 -202.567213) (xy 224.918016 -202.594464)
			(xy 224.917504 -202.622449) (xy 224.909344 -202.677821) (xy 224.893178 -202.731406) (xy 224.869354 -202.782052)
			(xy 224.838384 -202.828673) (xy 224.800933 -202.870266) (xy 224.757805 -202.90594) (xy 224.73412 -202.920854)
			(xy 224.721913 -202.92879) (xy 224.702251 -202.950247) (xy 224.689441 -202.97638) (xy 224.684524 -203.005064)
			(xy 224.687898 -203.033971) (xy 224.69929 -203.060752) (xy 224.717774 -203.083232) (xy 224.729548 -203.091796)
			(xy 224.751203 -203.107095) (xy 224.790458 -203.142738) (xy 224.824398 -203.183474) (xy 224.852369 -203.228517)
			(xy 224.873833 -203.277) (xy 224.888376 -203.327988) (xy 224.895718 -203.380499) (xy 224.896172 -203.40701)
			(xy 225.148646 -203.40701) (xy 225.152717 -203.351388) (xy 225.164843 -203.296951) (xy 225.184766 -203.24486)
			(xy 225.212062 -203.196225) (xy 225.246148 -203.152082) (xy 225.286297 -203.113373) (xy 225.331655 -203.080922)
			(xy 225.381255 -203.055421) (xy 225.434039 -203.037414) (xy 225.488882 -203.027284) (xy 225.544616 -203.025247)
			(xy 225.600053 -203.031347) (xy 225.65401 -203.045453) (xy 225.705339 -203.067265) (xy 225.752945 -203.096319)
			(xy 225.756972 -203.09967) (xy 226.164646 -203.09967) (xy 226.168717 -203.044048) (xy 226.180843 -202.989611)
			(xy 226.200766 -202.93752) (xy 226.228062 -202.888885) (xy 226.262148 -202.844742) (xy 226.302297 -202.806033)
			(xy 226.347655 -202.773582) (xy 226.397255 -202.748081) (xy 226.450039 -202.730074) (xy 226.504882 -202.719944)
			(xy 226.560616 -202.717907) (xy 226.616053 -202.724007) (xy 226.67001 -202.738113) (xy 226.721339 -202.759925)
			(xy 226.768945 -202.788979) (xy 226.811813 -202.824654) (xy 226.84903 -202.866191) (xy 226.879803 -202.912704)
			(xy 226.903475 -202.963201) (xy 226.919543 -203.016608) (xy 226.927663 -203.071784) (xy 226.928172 -203.09967)
			(xy 226.927663 -203.127556) (xy 226.919543 -203.182732) (xy 226.903475 -203.236139) (xy 226.879803 -203.286636)
			(xy 226.84903 -203.333149) (xy 226.818126 -203.36764) (xy 227.158548 -203.36764) (xy 227.162619 -203.312018)
			(xy 227.174745 -203.257581) (xy 227.194668 -203.20549) (xy 227.221964 -203.156855) (xy 227.25605 -203.112712)
			(xy 227.296199 -203.074003) (xy 227.341557 -203.041552) (xy 227.391157 -203.016051) (xy 227.443941 -202.998044)
			(xy 227.498784 -202.987914) (xy 227.554518 -202.985877) (xy 227.609955 -202.991977) (xy 227.663912 -203.006083)
			(xy 227.715241 -203.027895) (xy 227.762847 -203.056949) (xy 227.805715 -203.092624) (xy 227.842932 -203.134161)
			(xy 227.873705 -203.180674) (xy 227.897377 -203.231171) (xy 227.913445 -203.284578) (xy 227.921565 -203.339754)
			(xy 227.922074 -203.36764) (xy 227.921666 -203.389992) (xy 228.888796 -203.389992) (xy 228.892867 -203.33437)
			(xy 228.904993 -203.279933) (xy 228.924916 -203.227842) (xy 228.952212 -203.179207) (xy 228.986298 -203.135064)
			(xy 229.026447 -203.096355) (xy 229.071805 -203.063904) (xy 229.121405 -203.038403) (xy 229.174189 -203.020396)
			(xy 229.229032 -203.010266) (xy 229.284766 -203.008229) (xy 229.340203 -203.014329) (xy 229.39416 -203.028435)
			(xy 229.445489 -203.050247) (xy 229.493095 -203.079301) (xy 229.535963 -203.114976) (xy 229.57318 -203.156513)
			(xy 229.603953 -203.203026) (xy 229.627625 -203.253523) (xy 229.643693 -203.30693) (xy 229.651813 -203.362106)
			(xy 229.652322 -203.389992) (xy 229.652039 -203.405486) (xy 233.8959 -203.405486) (xy 233.896402 -203.37819)
			(xy 233.904198 -203.324159) (xy 233.919615 -203.271789) (xy 233.942338 -203.222152) (xy 233.971903 -203.176259)
			(xy 234.007706 -203.135048) (xy 234.049018 -203.099361) (xy 234.094993 -203.069925) (xy 234.144694 -203.047341)
			(xy 234.197106 -203.032071) (xy 234.224068 -203.027788) (xy 234.238969 -203.025097) (xy 234.266403 -203.01233)
			(xy 234.288889 -202.992081) (xy 234.304449 -202.966129) (xy 234.311716 -202.936756) (xy 234.310052 -202.906542)
			(xy 234.305348 -202.892152) (xy 234.294456 -202.860421) (xy 234.282706 -202.794375) (xy 234.28198 -202.760834)
			(xy 234.282466 -202.733583) (xy 234.290222 -202.679635) (xy 234.305577 -202.62734) (xy 234.328219 -202.577763)
			(xy 234.357685 -202.531913) (xy 234.393376 -202.490722) (xy 234.434567 -202.455031) (xy 234.480417 -202.425565)
			(xy 234.529994 -202.402923) (xy 234.582289 -202.387568) (xy 234.636237 -202.379812) (xy 234.690739 -202.379812)
			(xy 234.744687 -202.387568) (xy 234.796982 -202.402923) (xy 234.846559 -202.425565) (xy 234.892409 -202.455031)
			(xy 234.9336 -202.490722) (xy 234.969291 -202.531913) (xy 234.998757 -202.577763) (xy 235.021399 -202.62734)
			(xy 235.036754 -202.679635) (xy 235.04451 -202.733583) (xy 235.044996 -202.760834) (xy 235.04488 -202.767438)
			(xy 236.651036 -202.767438) (xy 236.655107 -202.711816) (xy 236.667233 -202.657379) (xy 236.687156 -202.605288)
			(xy 236.714452 -202.556653) (xy 236.748538 -202.51251) (xy 236.788687 -202.473801) (xy 236.834045 -202.44135)
			(xy 236.883645 -202.415849) (xy 236.936429 -202.397842) (xy 236.991272 -202.387712) (xy 237.047006 -202.385675)
			(xy 237.102443 -202.391775) (xy 237.1564 -202.405881) (xy 237.207729 -202.427693) (xy 237.255335 -202.456747)
			(xy 237.298203 -202.492422) (xy 237.33542 -202.533959) (xy 237.366193 -202.580472) (xy 237.389865 -202.630969)
			(xy 237.405933 -202.684376) (xy 237.414053 -202.739552) (xy 237.414562 -202.767438) (xy 237.414053 -202.795324)
			(xy 237.408588 -202.832462) (xy 242.81968 -202.832462) (xy 242.823751 -202.77684) (xy 242.835877 -202.722403)
			(xy 242.8558 -202.670312) (xy 242.883096 -202.621677) (xy 242.917182 -202.577534) (xy 242.957331 -202.538825)
			(xy 243.002689 -202.506374) (xy 243.052289 -202.480873) (xy 243.105073 -202.462866) (xy 243.159916 -202.452736)
			(xy 243.21565 -202.450699) (xy 243.271087 -202.456799) (xy 243.325044 -202.470905) (xy 243.376373 -202.492717)
			(xy 243.423979 -202.521771) (xy 243.466847 -202.557446) (xy 243.504064 -202.598983) (xy 243.534837 -202.645496)
			(xy 243.558509 -202.695993) (xy 243.574577 -202.7494) (xy 243.582697 -202.804576) (xy 243.583206 -202.832462)
			(xy 243.582697 -202.860348) (xy 243.574577 -202.915524) (xy 243.558509 -202.968931) (xy 243.534837 -203.019428)
			(xy 243.504064 -203.065941) (xy 243.466847 -203.107478) (xy 243.423979 -203.143153) (xy 243.376373 -203.172207)
			(xy 243.325044 -203.194019) (xy 243.271087 -203.208125) (xy 243.21565 -203.214225) (xy 243.159916 -203.212188)
			(xy 243.105073 -203.202058) (xy 243.052289 -203.184051) (xy 243.002689 -203.15855) (xy 242.957331 -203.126099)
			(xy 242.917182 -203.08739) (xy 242.883096 -203.043247) (xy 242.8558 -202.994612) (xy 242.835877 -202.942521)
			(xy 242.823751 -202.888084) (xy 242.81968 -202.832462) (xy 237.408588 -202.832462) (xy 237.405933 -202.8505)
			(xy 237.389865 -202.903907) (xy 237.366193 -202.954404) (xy 237.33542 -203.000917) (xy 237.298203 -203.042454)
			(xy 237.255335 -203.078129) (xy 237.207729 -203.107183) (xy 237.1564 -203.128995) (xy 237.102443 -203.143101)
			(xy 237.047006 -203.149201) (xy 236.991272 -203.147164) (xy 236.936429 -203.137034) (xy 236.883645 -203.119027)
			(xy 236.834045 -203.093526) (xy 236.788687 -203.061075) (xy 236.748538 -203.022366) (xy 236.714452 -202.978223)
			(xy 236.687156 -202.929588) (xy 236.667233 -202.877497) (xy 236.655107 -202.82306) (xy 236.651036 -202.767438)
			(xy 235.04488 -202.767438) (xy 235.044515 -202.78813) (xy 235.036716 -202.842163) (xy 235.021297 -202.894533)
			(xy 234.998571 -202.944171) (xy 234.969004 -202.990064) (xy 234.933198 -203.031274) (xy 234.891885 -203.066962)
			(xy 234.845907 -203.096397) (xy 234.796204 -203.11898) (xy 234.74379 -203.134249) (xy 234.716828 -203.138532)
			(xy 234.701921 -203.141195) (xy 234.674483 -203.153966) (xy 234.651996 -203.174221) (xy 234.636436 -203.200179)
			(xy 234.629172 -203.229558) (xy 234.630841 -203.259776) (xy 234.635548 -203.274168) (xy 234.646445 -203.305898)
			(xy 234.658192 -203.371945) (xy 234.658916 -203.405486) (xy 234.658463 -203.430886) (xy 235.308646 -203.430886)
			(xy 235.312717 -203.375264) (xy 235.324843 -203.320827) (xy 235.344766 -203.268736) (xy 235.372062 -203.220101)
			(xy 235.406148 -203.175958) (xy 235.446297 -203.137249) (xy 235.491655 -203.104798) (xy 235.541255 -203.079297)
			(xy 235.594039 -203.06129) (xy 235.648882 -203.05116) (xy 235.704616 -203.049123) (xy 235.760053 -203.055223)
			(xy 235.81401 -203.069329) (xy 235.865339 -203.091141) (xy 235.912945 -203.120195) (xy 235.955813 -203.15587)
			(xy 235.99303 -203.197407) (xy 236.023803 -203.24392) (xy 236.047475 -203.294417) (xy 236.063543 -203.347824)
			(xy 236.071663 -203.403) (xy 236.072172 -203.430886) (xy 236.071663 -203.458772) (xy 236.063543 -203.513948)
			(xy 236.047475 -203.567355) (xy 236.023803 -203.617852) (xy 235.99303 -203.664365) (xy 235.955813 -203.705902)
			(xy 235.912945 -203.741577) (xy 235.865339 -203.770631) (xy 235.81401 -203.792443) (xy 235.760053 -203.806549)
			(xy 235.704616 -203.812649) (xy 235.648882 -203.810612) (xy 235.594039 -203.800482) (xy 235.541255 -203.782475)
			(xy 235.491655 -203.756974) (xy 235.446297 -203.724523) (xy 235.406148 -203.685814) (xy 235.372062 -203.641671)
			(xy 235.344766 -203.593036) (xy 235.324843 -203.540945) (xy 235.312717 -203.486508) (xy 235.308646 -203.430886)
			(xy 234.658463 -203.430886) (xy 234.65843 -203.432737) (xy 234.650674 -203.486685) (xy 234.635319 -203.53898)
			(xy 234.612677 -203.588557) (xy 234.583211 -203.634407) (xy 234.54752 -203.675598) (xy 234.506329 -203.711289)
			(xy 234.460479 -203.740755) (xy 234.410902 -203.763397) (xy 234.358607 -203.778752) (xy 234.304659 -203.786508)
			(xy 234.250157 -203.786508) (xy 234.196209 -203.778752) (xy 234.143914 -203.763397) (xy 234.094337 -203.740755)
			(xy 234.048487 -203.711289) (xy 234.007296 -203.675598) (xy 233.971605 -203.634407) (xy 233.942139 -203.588557)
			(xy 233.919497 -203.53898) (xy 233.904142 -203.486685) (xy 233.896386 -203.432737) (xy 233.8959 -203.405486)
			(xy 229.652039 -203.405486) (xy 229.651813 -203.417878) (xy 229.643693 -203.473054) (xy 229.627625 -203.526461)
			(xy 229.603953 -203.576958) (xy 229.57318 -203.623471) (xy 229.535963 -203.665008) (xy 229.493095 -203.700683)
			(xy 229.445489 -203.729737) (xy 229.39416 -203.751549) (xy 229.340203 -203.765655) (xy 229.284766 -203.771755)
			(xy 229.229032 -203.769718) (xy 229.174189 -203.759588) (xy 229.121405 -203.741581) (xy 229.071805 -203.71608)
			(xy 229.026447 -203.683629) (xy 228.986298 -203.64492) (xy 228.952212 -203.600777) (xy 228.924916 -203.552142)
			(xy 228.904993 -203.500051) (xy 228.892867 -203.445614) (xy 228.888796 -203.389992) (xy 227.921666 -203.389992)
			(xy 227.921565 -203.395526) (xy 227.913445 -203.450702) (xy 227.897377 -203.504109) (xy 227.873705 -203.554606)
			(xy 227.842932 -203.601119) (xy 227.805715 -203.642656) (xy 227.762847 -203.678331) (xy 227.715241 -203.707385)
			(xy 227.663912 -203.729197) (xy 227.609955 -203.743303) (xy 227.554518 -203.749403) (xy 227.498784 -203.747366)
			(xy 227.443941 -203.737236) (xy 227.391157 -203.719229) (xy 227.341557 -203.693728) (xy 227.296199 -203.661277)
			(xy 227.25605 -203.622568) (xy 227.221964 -203.578425) (xy 227.194668 -203.52979) (xy 227.174745 -203.477699)
			(xy 227.162619 -203.423262) (xy 227.158548 -203.36764) (xy 226.818126 -203.36764) (xy 226.811813 -203.374686)
			(xy 226.768945 -203.410361) (xy 226.721339 -203.439415) (xy 226.67001 -203.461227) (xy 226.616053 -203.475333)
			(xy 226.560616 -203.481433) (xy 226.504882 -203.479396) (xy 226.450039 -203.469266) (xy 226.397255 -203.451259)
			(xy 226.347655 -203.425758) (xy 226.302297 -203.393307) (xy 226.262148 -203.354598) (xy 226.228062 -203.310455)
			(xy 226.200766 -203.26182) (xy 226.180843 -203.209729) (xy 226.168717 -203.155292) (xy 226.164646 -203.09967)
			(xy 225.756972 -203.09967) (xy 225.795813 -203.131994) (xy 225.83303 -203.173531) (xy 225.863803 -203.220044)
			(xy 225.887475 -203.270541) (xy 225.903543 -203.323948) (xy 225.911663 -203.379124) (xy 225.912172 -203.40701)
			(xy 225.911663 -203.434896) (xy 225.903543 -203.490072) (xy 225.887475 -203.543479) (xy 225.863803 -203.593976)
			(xy 225.83303 -203.640489) (xy 225.795813 -203.682026) (xy 225.752945 -203.717701) (xy 225.705339 -203.746755)
			(xy 225.65401 -203.768567) (xy 225.600053 -203.782673) (xy 225.544616 -203.788773) (xy 225.488882 -203.786736)
			(xy 225.434039 -203.776606) (xy 225.381255 -203.758599) (xy 225.331655 -203.733098) (xy 225.286297 -203.700647)
			(xy 225.246148 -203.661938) (xy 225.212062 -203.617795) (xy 225.184766 -203.56916) (xy 225.164843 -203.517069)
			(xy 225.152717 -203.462632) (xy 225.148646 -203.40701) (xy 224.896172 -203.40701) (xy 224.895686 -203.434261)
			(xy 224.88793 -203.488209) (xy 224.872575 -203.540504) (xy 224.849933 -203.590081) (xy 224.820467 -203.635931)
			(xy 224.784776 -203.677122) (xy 224.743585 -203.712813) (xy 224.697735 -203.742279) (xy 224.648158 -203.764921)
			(xy 224.595863 -203.780276) (xy 224.541915 -203.788032) (xy 224.487413 -203.788032) (xy 224.433465 -203.780276)
			(xy 224.38117 -203.764921) (xy 224.331593 -203.742279) (xy 224.285743 -203.712813) (xy 224.244552 -203.677122)
			(xy 224.208861 -203.635931) (xy 224.179395 -203.590081) (xy 224.156753 -203.540504) (xy 224.141398 -203.488209)
			(xy 224.133642 -203.434261) (xy 224.133156 -203.40701) (xy 222.612138 -203.40701) (xy 222.611949 -203.41737)
			(xy 222.603829 -203.472546) (xy 222.587761 -203.525953) (xy 222.564089 -203.57645) (xy 222.533316 -203.622963)
			(xy 222.496099 -203.6645) (xy 222.453231 -203.700175) (xy 222.405625 -203.729229) (xy 222.354296 -203.751041)
			(xy 222.300339 -203.765147) (xy 222.244902 -203.771247) (xy 222.189168 -203.76921) (xy 222.134325 -203.75908)
			(xy 222.081541 -203.741073) (xy 222.031941 -203.715572) (xy 221.986583 -203.683121) (xy 221.946434 -203.644412)
			(xy 221.912348 -203.600269) (xy 221.885052 -203.551634) (xy 221.865129 -203.499543) (xy 221.853003 -203.445106)
			(xy 221.848932 -203.389484) (xy 221.363302 -203.389484) (xy 221.369889 -203.434242) (xy 221.370398 -203.462128)
			(xy 221.369889 -203.490014) (xy 221.361769 -203.54519) (xy 221.345701 -203.598597) (xy 221.322029 -203.649094)
			(xy 221.291256 -203.695607) (xy 221.254039 -203.737144) (xy 221.211171 -203.772819) (xy 221.163565 -203.801873)
			(xy 221.112236 -203.823685) (xy 221.058279 -203.837791) (xy 221.002842 -203.843891) (xy 220.947108 -203.841854)
			(xy 220.892265 -203.831724) (xy 220.839481 -203.813717) (xy 220.789881 -203.788216) (xy 220.744523 -203.755765)
			(xy 220.704374 -203.717056) (xy 220.670288 -203.672913) (xy 220.642992 -203.624278) (xy 220.623069 -203.572187)
			(xy 220.610943 -203.51775) (xy 220.606872 -203.462128) (xy 218.462697 -203.462128) (xy 218.451149 -203.475016)
			(xy 218.408281 -203.510691) (xy 218.360675 -203.539745) (xy 218.309346 -203.561557) (xy 218.255389 -203.575663)
			(xy 218.199952 -203.581763) (xy 218.144218 -203.579726) (xy 218.089375 -203.569596) (xy 218.036591 -203.551589)
			(xy 217.986991 -203.526088) (xy 217.941633 -203.493637) (xy 217.901484 -203.454928) (xy 217.867398 -203.410785)
			(xy 217.840102 -203.36215) (xy 217.820179 -203.310059) (xy 217.808053 -203.255622) (xy 217.803982 -203.2)
			(xy 216.13266 -203.2) (xy 216.129811 -203.209469) (xy 216.106139 -203.259966) (xy 216.075366 -203.306479)
			(xy 216.038149 -203.348016) (xy 215.995281 -203.383691) (xy 215.947675 -203.412745) (xy 215.896346 -203.434557)
			(xy 215.842389 -203.448663) (xy 215.786952 -203.454763) (xy 215.731218 -203.452726) (xy 215.676375 -203.442596)
			(xy 215.623591 -203.424589) (xy 215.573991 -203.399088) (xy 215.528633 -203.366637) (xy 215.488484 -203.327928)
			(xy 215.454398 -203.283785) (xy 215.427102 -203.23515) (xy 215.407179 -203.183059) (xy 215.395053 -203.128622)
			(xy 215.390982 -203.073) (xy 209.706979 -203.073) (xy 209.725366 -203.093521) (xy 209.756139 -203.140034)
			(xy 209.779811 -203.190531) (xy 209.795879 -203.243938) (xy 209.803999 -203.299114) (xy 209.804508 -203.327)
			(xy 209.803999 -203.354886) (xy 209.795879 -203.410062) (xy 209.779811 -203.463469) (xy 209.756139 -203.513966)
			(xy 209.725366 -203.560479) (xy 209.688149 -203.602016) (xy 209.645281 -203.637691) (xy 209.597675 -203.666745)
			(xy 209.546346 -203.688557) (xy 209.492389 -203.702663) (xy 209.436952 -203.708763) (xy 209.381218 -203.706726)
			(xy 209.326375 -203.696596) (xy 209.273591 -203.678589) (xy 209.223991 -203.653088) (xy 209.178633 -203.620637)
			(xy 209.138484 -203.581928) (xy 209.104398 -203.537785) (xy 209.077102 -203.48915) (xy 209.057179 -203.437059)
			(xy 209.045053 -203.382622) (xy 209.040982 -203.327) (xy 187.015596 -203.327) (xy 186.899724 -203.957428)
			(xy 245.37924 -203.957428) (xy 245.379733 -203.929238) (xy 245.388047 -203.873475) (xy 245.40447 -203.81954)
			(xy 245.428645 -203.768605) (xy 245.460045 -203.721779) (xy 245.497989 -203.680078) (xy 245.541652 -203.64441)
			(xy 245.590085 -203.615548) (xy 245.615968 -203.604368) (xy 245.6294 -203.598255) (xy 245.652318 -203.579686)
			(xy 245.668978 -203.555345) (xy 245.677992 -203.527259) (xy 245.678609 -203.497769) (xy 245.670777 -203.469331)
			(xy 245.655149 -203.444315) (xy 245.644416 -203.434188) (xy 245.624357 -203.415989) (xy 245.589093 -203.37488)
			(xy 245.559993 -203.3292) (xy 245.537643 -203.279866) (xy 245.52249 -203.227867) (xy 245.514839 -203.174249)
			(xy 245.514368 -203.147168) (xy 245.514854 -203.119917) (xy 245.52261 -203.065969) (xy 245.537965 -203.013674)
			(xy 245.560607 -202.964097) (xy 245.590073 -202.918247) (xy 245.625764 -202.877056) (xy 245.666955 -202.841365)
			(xy 245.712805 -202.811899) (xy 245.762382 -202.789257) (xy 245.814677 -202.773902) (xy 245.868625 -202.766146)
			(xy 245.923127 -202.766146) (xy 245.977075 -202.773902) (xy 246.02937 -202.789257) (xy 246.078947 -202.811899)
			(xy 246.086044 -202.81646) (xy 258.208016 -202.81646) (xy 258.212087 -202.760838) (xy 258.224213 -202.706401)
			(xy 258.244136 -202.65431) (xy 258.271432 -202.605675) (xy 258.305518 -202.561532) (xy 258.345667 -202.522823)
			(xy 258.391025 -202.490372) (xy 258.440625 -202.464871) (xy 258.493409 -202.446864) (xy 258.548252 -202.436734)
			(xy 258.603986 -202.434697) (xy 258.659423 -202.440797) (xy 258.71338 -202.454903) (xy 258.764709 -202.476715)
			(xy 258.812315 -202.505769) (xy 258.855183 -202.541444) (xy 258.8924 -202.582981) (xy 258.923173 -202.629494)
			(xy 258.946845 -202.679991) (xy 258.962913 -202.733398) (xy 258.971033 -202.788574) (xy 258.971542 -202.81646)
			(xy 258.971033 -202.844346) (xy 258.962913 -202.899522) (xy 258.946845 -202.952929) (xy 258.923173 -203.003426)
			(xy 258.8924 -203.049939) (xy 258.855183 -203.091476) (xy 258.812315 -203.127151) (xy 258.764709 -203.156205)
			(xy 258.71338 -203.178017) (xy 258.659423 -203.192123) (xy 258.603986 -203.198223) (xy 258.548252 -203.196186)
			(xy 258.493409 -203.186056) (xy 258.440625 -203.168049) (xy 258.391025 -203.142548) (xy 258.345667 -203.110097)
			(xy 258.305518 -203.071388) (xy 258.271432 -203.027245) (xy 258.244136 -202.97861) (xy 258.224213 -202.926519)
			(xy 258.212087 -202.872082) (xy 258.208016 -202.81646) (xy 246.086044 -202.81646) (xy 246.124797 -202.841365)
			(xy 246.165988 -202.877056) (xy 246.201679 -202.918247) (xy 246.231145 -202.964097) (xy 246.253787 -203.013674)
			(xy 246.269142 -203.065969) (xy 246.276898 -203.119917) (xy 246.277384 -203.147168) (xy 246.276873 -203.175357)
			(xy 246.26856 -203.231119) (xy 246.252138 -203.285053) (xy 246.227966 -203.335986) (xy 246.196568 -203.382812)
			(xy 246.158627 -203.424513) (xy 246.114967 -203.460183) (xy 246.066538 -203.489046) (xy 246.040656 -203.500228)
			(xy 246.027228 -203.506351) (xy 246.004306 -203.524916) (xy 245.987643 -203.549255) (xy 245.978627 -203.57734)
			(xy 245.97801 -203.60683) (xy 245.985843 -203.635267) (xy 246.001474 -203.660282) (xy 246.012208 -203.670408)
			(xy 246.03227 -203.688604) (xy 246.067533 -203.729714) (xy 246.096631 -203.775395) (xy 246.118981 -203.82473)
			(xy 246.134134 -203.876729) (xy 246.141785 -203.930347) (xy 246.142256 -203.957428) (xy 246.14177 -203.984679)
			(xy 246.134014 -204.038627) (xy 246.122654 -204.077316) (xy 256.335528 -204.077316) (xy 256.339599 -204.021694)
			(xy 256.351725 -203.967257) (xy 256.371648 -203.915166) (xy 256.398944 -203.866531) (xy 256.43303 -203.822388)
			(xy 256.473179 -203.783679) (xy 256.518537 -203.751228) (xy 256.568137 -203.725727) (xy 256.620921 -203.70772)
			(xy 256.675764 -203.69759) (xy 256.731498 -203.695553) (xy 256.786935 -203.701653) (xy 256.840892 -203.715759)
			(xy 256.892221 -203.737571) (xy 256.939827 -203.766625) (xy 256.982695 -203.8023) (xy 257.019912 -203.843837)
			(xy 257.050685 -203.89035) (xy 257.074357 -203.940847) (xy 257.090425 -203.994254) (xy 257.098545 -204.04943)
			(xy 257.099054 -204.077316) (xy 257.098545 -204.105202) (xy 257.090425 -204.160378) (xy 257.074357 -204.213785)
			(xy 257.050685 -204.264282) (xy 257.019912 -204.310795) (xy 256.982695 -204.352332) (xy 256.979869 -204.354684)
			(xy 260.878586 -204.354684) (xy 260.882552 -204.270153) (xy 260.894417 -204.186366) (xy 260.914075 -204.104057)
			(xy 260.941355 -204.023951) (xy 260.976016 -203.946752) (xy 261.017754 -203.873137) (xy 261.066201 -203.803754)
			(xy 261.120933 -203.739213) (xy 261.181469 -203.680081) (xy 261.247275 -203.626877) (xy 261.317775 -203.580069)
			(xy 261.392347 -203.540068) (xy 261.470338 -203.507226) (xy 261.551062 -203.481832) (xy 261.633809 -203.464109)
			(xy 261.717851 -203.454211) (xy 261.802452 -203.452228) (xy 261.886866 -203.458175) (xy 261.970353 -203.472)
			(xy 262.052178 -203.493583) (xy 262.131622 -203.522733) (xy 262.207988 -203.559194) (xy 262.220234 -203.566522)
			(xy 264.391138 -203.566522) (xy 264.395209 -203.5109) (xy 264.407335 -203.456463) (xy 264.427258 -203.404372)
			(xy 264.454554 -203.355737) (xy 264.48864 -203.311594) (xy 264.528789 -203.272885) (xy 264.574147 -203.240434)
			(xy 264.623747 -203.214933) (xy 264.676531 -203.196926) (xy 264.731374 -203.186796) (xy 264.787108 -203.184759)
			(xy 264.842545 -203.190859) (xy 264.896502 -203.204965) (xy 264.947831 -203.226777) (xy 264.995437 -203.255831)
			(xy 265.038305 -203.291506) (xy 265.075522 -203.333043) (xy 265.106295 -203.379556) (xy 265.129967 -203.430053)
			(xy 265.146035 -203.48346) (xy 265.154155 -203.538636) (xy 265.154664 -203.566522) (xy 265.154155 -203.594408)
			(xy 265.146035 -203.649584) (xy 265.129967 -203.702991) (xy 265.106295 -203.753488) (xy 265.075522 -203.800001)
			(xy 265.038305 -203.841538) (xy 264.995437 -203.877213) (xy 264.947831 -203.906267) (xy 264.896502 -203.928079)
			(xy 264.842545 -203.942185) (xy 264.787108 -203.948285) (xy 264.731374 -203.946248) (xy 264.676531 -203.936118)
			(xy 264.623747 -203.918111) (xy 264.574147 -203.89261) (xy 264.528789 -203.860159) (xy 264.48864 -203.82145)
			(xy 264.454554 -203.777307) (xy 264.427258 -203.728672) (xy 264.407335 -203.676581) (xy 264.395209 -203.622144)
			(xy 264.391138 -203.566522) (xy 262.220234 -203.566522) (xy 262.280604 -203.602646) (xy 262.348832 -203.652707)
			(xy 262.412072 -203.708937) (xy 262.469769 -203.770842) (xy 262.521416 -203.837878) (xy 262.566558 -203.909455)
			(xy 262.6048 -203.984945) (xy 262.635804 -204.063684) (xy 262.659299 -204.144981) (xy 262.675078 -204.22812)
			(xy 262.683002 -204.312372) (xy 262.683498 -204.354684) (xy 262.683002 -204.396996) (xy 262.675078 -204.481248)
			(xy 262.659299 -204.564387) (xy 262.635804 -204.645684) (xy 262.6048 -204.724423) (xy 262.566558 -204.799913)
			(xy 262.521416 -204.87149) (xy 262.469769 -204.938526) (xy 262.412072 -205.000431) (xy 262.348832 -205.056661)
			(xy 262.280604 -205.106722) (xy 262.207988 -205.150174) (xy 262.131622 -205.186635) (xy 262.052178 -205.215785)
			(xy 261.970353 -205.237368) (xy 261.886866 -205.251193) (xy 261.802452 -205.25714) (xy 261.717851 -205.255157)
			(xy 261.633809 -205.245259) (xy 261.551062 -205.227536) (xy 261.470338 -205.202142) (xy 261.392347 -205.1693)
			(xy 261.317775 -205.129299) (xy 261.247275 -205.082491) (xy 261.181469 -205.029287) (xy 261.120933 -204.970155)
			(xy 261.066201 -204.905614) (xy 261.017754 -204.836231) (xy 260.976016 -204.762616) (xy 260.941355 -204.685417)
			(xy 260.914075 -204.605311) (xy 260.894417 -204.523002) (xy 260.882552 -204.439215) (xy 260.878586 -204.354684)
			(xy 256.979869 -204.354684) (xy 256.939827 -204.388007) (xy 256.892221 -204.417061) (xy 256.840892 -204.438873)
			(xy 256.786935 -204.452979) (xy 256.731498 -204.459079) (xy 256.675764 -204.457042) (xy 256.620921 -204.446912)
			(xy 256.568137 -204.428905) (xy 256.518537 -204.403404) (xy 256.473179 -204.370953) (xy 256.43303 -204.332244)
			(xy 256.398944 -204.288101) (xy 256.371648 -204.239466) (xy 256.351725 -204.187375) (xy 256.339599 -204.132938)
			(xy 256.335528 -204.077316) (xy 246.122654 -204.077316) (xy 246.118659 -204.090922) (xy 246.096017 -204.140499)
			(xy 246.066551 -204.186349) (xy 246.03086 -204.22754) (xy 245.989669 -204.263231) (xy 245.943819 -204.292697)
			(xy 245.894242 -204.315339) (xy 245.841947 -204.330694) (xy 245.787999 -204.33845) (xy 245.733497 -204.33845)
			(xy 245.679549 -204.330694) (xy 245.627254 -204.315339) (xy 245.577677 -204.292697) (xy 245.531827 -204.263231)
			(xy 245.490636 -204.22754) (xy 245.454945 -204.186349) (xy 245.425479 -204.140499) (xy 245.402837 -204.090922)
			(xy 245.387482 -204.038627) (xy 245.379726 -203.984679) (xy 245.37924 -203.957428) (xy 186.899724 -203.957428)
			(xy 186.805513 -204.47) (xy 206.119982 -204.47) (xy 206.124053 -204.414378) (xy 206.136179 -204.359941)
			(xy 206.156102 -204.30785) (xy 206.183398 -204.259215) (xy 206.217484 -204.215072) (xy 206.257633 -204.176363)
			(xy 206.302991 -204.143912) (xy 206.352591 -204.118411) (xy 206.405375 -204.100404) (xy 206.460218 -204.090274)
			(xy 206.515952 -204.088237) (xy 206.571389 -204.094337) (xy 206.625346 -204.108443) (xy 206.676675 -204.130255)
			(xy 206.724281 -204.159309) (xy 206.767149 -204.194984) (xy 206.804366 -204.236521) (xy 206.835139 -204.283034)
			(xy 206.858811 -204.333531) (xy 206.874879 -204.386938) (xy 206.882999 -204.442114) (xy 206.883508 -204.47)
			(xy 210.457032 -204.47) (xy 210.461103 -204.414378) (xy 210.473229 -204.359941) (xy 210.493152 -204.30785)
			(xy 210.520448 -204.259215) (xy 210.554534 -204.215072) (xy 210.594683 -204.176363) (xy 210.640041 -204.143912)
			(xy 210.689641 -204.118411) (xy 210.742425 -204.100404) (xy 210.797268 -204.090274) (xy 210.853002 -204.088237)
			(xy 210.908439 -204.094337) (xy 210.962396 -204.108443) (xy 211.013725 -204.130255) (xy 211.061331 -204.159309)
			(xy 211.104199 -204.194984) (xy 211.141416 -204.236521) (xy 211.172189 -204.283034) (xy 211.195861 -204.333531)
			(xy 211.211929 -204.386938) (xy 211.220049 -204.442114) (xy 211.220558 -204.47) (xy 211.220049 -204.497886)
			(xy 211.211929 -204.553062) (xy 211.195861 -204.606469) (xy 211.172189 -204.656966) (xy 211.141416 -204.703479)
			(xy 211.104199 -204.745016) (xy 211.061331 -204.780691) (xy 211.013725 -204.809745) (xy 210.962396 -204.831557)
			(xy 210.908439 -204.845663) (xy 210.853002 -204.851763) (xy 210.797268 -204.849726) (xy 210.742425 -204.839596)
			(xy 210.689641 -204.821589) (xy 210.640041 -204.796088) (xy 210.594683 -204.763637) (xy 210.554534 -204.724928)
			(xy 210.520448 -204.680785) (xy 210.493152 -204.63215) (xy 210.473229 -204.580059) (xy 210.461103 -204.525622)
			(xy 210.457032 -204.47) (xy 206.883508 -204.47) (xy 206.882999 -204.497886) (xy 206.874879 -204.553062)
			(xy 206.858811 -204.606469) (xy 206.835139 -204.656966) (xy 206.804366 -204.703479) (xy 206.767149 -204.745016)
			(xy 206.724281 -204.780691) (xy 206.676675 -204.809745) (xy 206.625346 -204.831557) (xy 206.571389 -204.845663)
			(xy 206.515952 -204.851763) (xy 206.460218 -204.849726) (xy 206.405375 -204.839596) (xy 206.352591 -204.821589)
			(xy 206.302991 -204.796088) (xy 206.257633 -204.763637) (xy 206.217484 -204.724928) (xy 206.183398 -204.680785)
			(xy 206.156102 -204.63215) (xy 206.136179 -204.580059) (xy 206.124053 -204.525622) (xy 206.119982 -204.47)
			(xy 186.805513 -204.47) (xy 186.36107 -206.88808) (xy 186.360308 -206.897478) (xy 186.380882 -206.934562)
			(xy 186.389264 -206.943706) (xy 186.39409 -206.946754) (xy 186.417194 -206.962803) (xy 186.458863 -207.000594)
			(xy 186.494532 -207.044092) (xy 186.523429 -207.092355) (xy 186.544928 -207.144338) (xy 186.558563 -207.198914)
			(xy 186.564038 -207.2549) (xy 186.561235 -207.311083) (xy 186.550214 -207.366246) (xy 186.531214 -207.419194)
			(xy 186.504648 -207.468778) (xy 186.47109 -207.513926) (xy 186.431268 -207.553657) (xy 186.386044 -207.587113)
			(xy 186.336399 -207.613566) (xy 186.283409 -207.632445) (xy 186.255914 -207.638396) (xy 186.25566 -207.638396)
			(xy 186.246258 -207.64062) (xy 186.229996 -207.65102) (xy 186.218764 -207.666719) (xy 186.216036 -207.675988)
			(xy 185.885836 -209.474054) (xy 185.763408 -210.140042) (xy 185.762646 -210.149186) (xy 185.785252 -210.183476)
			(xy 185.789279 -210.189192) (xy 185.799847 -210.19834) (xy 185.80608 -210.20151) (xy 185.829275 -210.212891)
			(xy 185.872636 -210.240983) (xy 185.911813 -210.274666) (xy 185.92927 -210.293712) (xy 185.932845 -210.297629)
			(xy 185.941292 -210.304038) (xy 185.946034 -210.306412) (xy 185.955432 -210.31073) (xy 186.031632 -210.312)
			(xy 186.036907 -210.311996) (xy 186.047276 -210.310068) (xy 186.052206 -210.30819) (xy 186.078368 -210.297014)
			(xy 186.085226 -210.290156) (xy 186.106833 -210.269421) (xy 186.155307 -210.234262) (xy 186.208677 -210.207105)
			(xy 186.265634 -210.188617) (xy 186.324779 -210.179252) (xy 186.35472 -210.17865) (xy 186.381973 -210.179137)
			(xy 186.435925 -210.186897) (xy 186.488223 -210.202255) (xy 186.537803 -210.2249) (xy 186.583656 -210.25437)
			(xy 186.624848 -210.290066) (xy 186.660542 -210.33126) (xy 186.690009 -210.377115) (xy 186.712652 -210.426696)
			(xy 186.728007 -210.478995) (xy 186.735764 -210.532947) (xy 186.735764 -210.587453) (xy 186.728007 -210.641405)
			(xy 186.712652 -210.693704) (xy 186.690009 -210.743285) (xy 186.660542 -210.78914) (xy 186.624848 -210.830334)
			(xy 186.583656 -210.86603) (xy 186.537803 -210.8955) (xy 186.488223 -210.918145) (xy 186.435925 -210.933503)
			(xy 186.381973 -210.941263) (xy 186.35472 -210.941666) (xy 186.354466 -210.941666) (xy 186.327568 -210.941209)
			(xy 186.274305 -210.933654) (xy 186.222634 -210.918685) (xy 186.17358 -210.8966) (xy 186.128119 -210.867837)
			(xy 186.087154 -210.832968) (xy 186.06897 -210.813142) (xy 186.06539 -210.809231) (xy 186.056937 -210.802836)
			(xy 186.052206 -210.800442) (xy 186.042808 -210.796124) (xy 185.966608 -210.794854) (xy 185.961332 -210.794854)
			(xy 185.950959 -210.796773) (xy 185.946034 -210.798664) (xy 185.919872 -210.80984) (xy 185.913014 -210.816698)
			(xy 185.892547 -210.83638) (xy 185.846854 -210.870088) (xy 185.796676 -210.896662) (xy 185.743117 -210.915517)
			(xy 185.687358 -210.926237) (xy 185.659014 -210.92795) (xy 185.650434 -210.928619) (xy 185.634454 -210.934975)
			(xy 185.627772 -210.940396) (xy 185.621497 -210.946291) (xy 185.612928 -210.961213) (xy 185.611008 -210.969606)
			(xy 184.523184 -216.88806) (xy 185.727084 -216.88806) (xy 185.731155 -216.832438) (xy 185.743281 -216.778001)
			(xy 185.763204 -216.72591) (xy 185.7905 -216.677275) (xy 185.824586 -216.633132) (xy 185.864735 -216.594423)
			(xy 185.910093 -216.561972) (xy 185.959693 -216.536471) (xy 186.012477 -216.518464) (xy 186.06732 -216.508334)
			(xy 186.123054 -216.506297) (xy 186.178491 -216.512397) (xy 186.232448 -216.526503) (xy 186.283777 -216.548315)
			(xy 186.331383 -216.577369) (xy 186.374251 -216.613044) (xy 186.411468 -216.654581) (xy 186.442241 -216.701094)
			(xy 186.465913 -216.751591) (xy 186.481981 -216.804998) (xy 186.490101 -216.860174) (xy 186.49061 -216.88806)
			(xy 186.490101 -216.915946) (xy 186.481981 -216.971122) (xy 186.465913 -217.024529) (xy 186.442241 -217.075026)
			(xy 186.411468 -217.121539) (xy 186.374251 -217.163076) (xy 186.331383 -217.198751) (xy 186.283777 -217.227805)
			(xy 186.232448 -217.249617) (xy 186.178491 -217.263723) (xy 186.123054 -217.269823) (xy 186.06732 -217.267786)
			(xy 186.012477 -217.257656) (xy 185.959693 -217.239649) (xy 185.910093 -217.214148) (xy 185.864735 -217.181697)
			(xy 185.824586 -217.142988) (xy 185.7905 -217.098845) (xy 185.763204 -217.05021) (xy 185.743281 -216.998119)
			(xy 185.731155 -216.943682) (xy 185.727084 -216.88806) (xy 184.523184 -216.88806) (xy 184.038773 -219.523564)
			(xy 186.561982 -219.523564) (xy 186.566053 -219.467942) (xy 186.578179 -219.413505) (xy 186.598102 -219.361414)
			(xy 186.625398 -219.312779) (xy 186.659484 -219.268636) (xy 186.699633 -219.229927) (xy 186.744991 -219.197476)
			(xy 186.794591 -219.171975) (xy 186.847375 -219.153968) (xy 186.902218 -219.143838) (xy 186.957952 -219.141801)
			(xy 187.013389 -219.147901) (xy 187.067346 -219.162007) (xy 187.118675 -219.183819) (xy 187.166281 -219.212873)
			(xy 187.209149 -219.248548) (xy 187.246366 -219.290085) (xy 187.277139 -219.336598) (xy 187.300811 -219.387095)
			(xy 187.316879 -219.440502) (xy 187.324999 -219.495678) (xy 187.325508 -219.523564) (xy 187.324999 -219.55145)
			(xy 187.316879 -219.606626) (xy 187.300811 -219.660033) (xy 187.277139 -219.71053) (xy 187.246366 -219.757043)
			(xy 187.209149 -219.79858) (xy 187.166281 -219.834255) (xy 187.118675 -219.863309) (xy 187.067346 -219.885121)
			(xy 187.013389 -219.899227) (xy 186.957952 -219.905327) (xy 186.902218 -219.90329) (xy 186.847375 -219.89316)
			(xy 186.794591 -219.875153) (xy 186.744991 -219.849652) (xy 186.699633 -219.817201) (xy 186.659484 -219.778492)
			(xy 186.625398 -219.734349) (xy 186.598102 -219.685714) (xy 186.578179 -219.633623) (xy 186.566053 -219.579186)
			(xy 186.561982 -219.523564) (xy 184.038773 -219.523564) (xy 183.848248 -220.560138) (xy 183.847486 -220.569282)
			(xy 183.847486 -220.643704) (xy 183.851804 -220.658182) (xy 183.856122 -220.664278) (xy 183.871654 -220.688099)
			(xy 183.896244 -220.739373) (xy 183.912941 -220.793731) (xy 183.921376 -220.849967) (xy 183.921908 -220.8784)
			(xy 183.921426 -220.90562) (xy 183.913695 -220.95951) (xy 183.89839 -221.011755) (xy 183.87582 -221.061297)
			(xy 183.846444 -221.107132) (xy 183.810857 -221.148331) (xy 183.76978 -221.184059) (xy 183.747156 -221.199202)
			(xy 183.738266 -221.20479) (xy 183.732424 -221.213172) (xy 183.729593 -221.217601) (xy 183.725619 -221.22733)
			(xy 183.72455 -221.232476) (xy 183.141112 -224.40773) (xy 182.993677 -225.209862) (xy 184.70575 -225.209862)
			(xy 184.709821 -225.15424) (xy 184.721947 -225.099803) (xy 184.74187 -225.047712) (xy 184.769166 -224.999077)
			(xy 184.803252 -224.954934) (xy 184.843401 -224.916225) (xy 184.888759 -224.883774) (xy 184.938359 -224.858273)
			(xy 184.991143 -224.840266) (xy 185.045986 -224.830136) (xy 185.10172 -224.828099) (xy 185.157157 -224.834199)
			(xy 185.211114 -224.848305) (xy 185.262443 -224.870117) (xy 185.310049 -224.899171) (xy 185.352917 -224.934846)
			(xy 185.390134 -224.976383) (xy 185.420907 -225.022896) (xy 185.444579 -225.073393) (xy 185.460647 -225.1268)
			(xy 185.468767 -225.181976) (xy 185.469276 -225.209862) (xy 185.468767 -225.237748) (xy 185.460647 -225.292924)
			(xy 185.444579 -225.346331) (xy 185.420907 -225.396828) (xy 185.390134 -225.443341) (xy 185.352917 -225.484878)
			(xy 185.310049 -225.520553) (xy 185.262443 -225.549607) (xy 185.211114 -225.571419) (xy 185.157157 -225.585525)
			(xy 185.10172 -225.591625) (xy 185.045986 -225.589588) (xy 184.991143 -225.579458) (xy 184.938359 -225.561451)
			(xy 184.888759 -225.53595) (xy 184.843401 -225.503499) (xy 184.803252 -225.46479) (xy 184.769166 -225.420647)
			(xy 184.74187 -225.372012) (xy 184.721947 -225.319921) (xy 184.709821 -225.265484) (xy 184.70575 -225.209862)
			(xy 182.993677 -225.209862) (xy 182.690685 -226.858322) (xy 183.69356 -226.858322) (xy 183.697631 -226.8027)
			(xy 183.709757 -226.748263) (xy 183.72968 -226.696172) (xy 183.756976 -226.647537) (xy 183.791062 -226.603394)
			(xy 183.831211 -226.564685) (xy 183.876569 -226.532234) (xy 183.926169 -226.506733) (xy 183.978953 -226.488726)
			(xy 184.033796 -226.478596) (xy 184.08953 -226.476559) (xy 184.144967 -226.482659) (xy 184.17216 -226.489768)
			(xy 184.657744 -226.489768) (xy 184.661815 -226.434146) (xy 184.673941 -226.379709) (xy 184.693864 -226.327618)
			(xy 184.72116 -226.278983) (xy 184.755246 -226.23484) (xy 184.795395 -226.196131) (xy 184.840753 -226.16368)
			(xy 184.890353 -226.138179) (xy 184.943137 -226.120172) (xy 184.99798 -226.110042) (xy 185.053714 -226.108005)
			(xy 185.109151 -226.114105) (xy 185.163108 -226.128211) (xy 185.214437 -226.150023) (xy 185.262043 -226.179077)
			(xy 185.286214 -226.199192) (xy 186.67679 -226.199192) (xy 186.680861 -226.14357) (xy 186.692987 -226.089133)
			(xy 186.71291 -226.037042) (xy 186.740206 -225.988407) (xy 186.774292 -225.944264) (xy 186.814441 -225.905555)
			(xy 186.859799 -225.873104) (xy 186.909399 -225.847603) (xy 186.962183 -225.829596) (xy 187.017026 -225.819466)
			(xy 187.07276 -225.817429) (xy 187.128197 -225.823529) (xy 187.182154 -225.837635) (xy 187.233483 -225.859447)
			(xy 187.281089 -225.888501) (xy 187.323957 -225.924176) (xy 187.361174 -225.965713) (xy 187.391947 -226.012226)
			(xy 187.415619 -226.062723) (xy 187.431687 -226.11613) (xy 187.439807 -226.171306) (xy 187.440316 -226.199192)
			(xy 187.439807 -226.227078) (xy 187.431687 -226.282254) (xy 187.415619 -226.335661) (xy 187.391947 -226.386158)
			(xy 187.361174 -226.432671) (xy 187.323957 -226.474208) (xy 187.281089 -226.509883) (xy 187.233483 -226.538937)
			(xy 187.182154 -226.560749) (xy 187.128197 -226.574855) (xy 187.07276 -226.580955) (xy 187.017026 -226.578918)
			(xy 186.962183 -226.568788) (xy 186.909399 -226.550781) (xy 186.859799 -226.52528) (xy 186.814441 -226.492829)
			(xy 186.774292 -226.45412) (xy 186.740206 -226.409977) (xy 186.71291 -226.361342) (xy 186.692987 -226.309251)
			(xy 186.680861 -226.254814) (xy 186.67679 -226.199192) (xy 185.286214 -226.199192) (xy 185.304911 -226.214752)
			(xy 185.342128 -226.256289) (xy 185.372901 -226.302802) (xy 185.396573 -226.353299) (xy 185.412641 -226.406706)
			(xy 185.420761 -226.461882) (xy 185.42127 -226.489768) (xy 185.420761 -226.517654) (xy 185.412641 -226.57283)
			(xy 185.396573 -226.626237) (xy 185.372901 -226.676734) (xy 185.342128 -226.723247) (xy 185.304911 -226.764784)
			(xy 185.262043 -226.800459) (xy 185.214437 -226.829513) (xy 185.163108 -226.851325) (xy 185.109151 -226.865431)
			(xy 185.053714 -226.871531) (xy 184.99798 -226.869494) (xy 184.943137 -226.859364) (xy 184.890353 -226.841357)
			(xy 184.840753 -226.815856) (xy 184.795395 -226.783405) (xy 184.755246 -226.744696) (xy 184.72116 -226.700553)
			(xy 184.693864 -226.651918) (xy 184.673941 -226.599827) (xy 184.661815 -226.54539) (xy 184.657744 -226.489768)
			(xy 184.17216 -226.489768) (xy 184.198924 -226.496765) (xy 184.250253 -226.518577) (xy 184.297859 -226.547631)
			(xy 184.340727 -226.583306) (xy 184.377944 -226.624843) (xy 184.408717 -226.671356) (xy 184.432389 -226.721853)
			(xy 184.448457 -226.77526) (xy 184.456577 -226.830436) (xy 184.457086 -226.858322) (xy 184.456577 -226.886208)
			(xy 184.448457 -226.941384) (xy 184.432389 -226.994791) (xy 184.408717 -227.045288) (xy 184.377944 -227.091801)
			(xy 184.340727 -227.133338) (xy 184.297859 -227.169013) (xy 184.250253 -227.198067) (xy 184.198924 -227.219879)
			(xy 184.144967 -227.233985) (xy 184.08953 -227.240085) (xy 184.033796 -227.238048) (xy 183.978953 -227.227918)
			(xy 183.926169 -227.209911) (xy 183.876569 -227.18441) (xy 183.831211 -227.151959) (xy 183.791062 -227.11325)
			(xy 183.756976 -227.069107) (xy 183.72968 -227.020472) (xy 183.709757 -226.968381) (xy 183.697631 -226.913944)
			(xy 183.69356 -226.858322) (xy 182.690685 -226.858322) (xy 182.141798 -229.8446) (xy 182.411876 -229.8446)
			(xy 182.415947 -229.788978) (xy 182.428073 -229.734541) (xy 182.447996 -229.68245) (xy 182.475292 -229.633815)
			(xy 182.509378 -229.589672) (xy 182.549527 -229.550963) (xy 182.594885 -229.518512) (xy 182.644485 -229.493011)
			(xy 182.697269 -229.475004) (xy 182.752112 -229.464874) (xy 182.807846 -229.462837) (xy 182.863283 -229.468937)
			(xy 182.91724 -229.483043) (xy 182.968569 -229.504855) (xy 183.016175 -229.533909) (xy 183.059043 -229.569584)
			(xy 183.09626 -229.611121) (xy 183.127033 -229.657634) (xy 183.150705 -229.708131) (xy 183.166773 -229.761538)
			(xy 183.174893 -229.816714) (xy 183.175402 -229.8446) (xy 183.174893 -229.872486) (xy 183.166773 -229.927662)
			(xy 183.150705 -229.981069) (xy 183.127033 -230.031566) (xy 183.09626 -230.078079) (xy 183.059043 -230.119616)
			(xy 183.016175 -230.155291) (xy 182.968569 -230.184345) (xy 182.91724 -230.206157) (xy 182.863283 -230.220263)
			(xy 182.807846 -230.226363) (xy 182.752112 -230.224326) (xy 182.697269 -230.214196) (xy 182.644485 -230.196189)
			(xy 182.594885 -230.170688) (xy 182.549527 -230.138237) (xy 182.509378 -230.099528) (xy 182.475292 -230.055385)
			(xy 182.447996 -230.00675) (xy 182.428073 -229.954659) (xy 182.415947 -229.900222) (xy 182.411876 -229.8446)
			(xy 182.141798 -229.8446) (xy 181.105603 -235.48213) (xy 183.206388 -235.48213) (xy 183.210459 -235.426508)
			(xy 183.222585 -235.372071) (xy 183.242508 -235.31998) (xy 183.269804 -235.271345) (xy 183.30389 -235.227202)
			(xy 183.344039 -235.188493) (xy 183.389397 -235.156042) (xy 183.438997 -235.130541) (xy 183.491781 -235.112534)
			(xy 183.546624 -235.102404) (xy 183.602358 -235.100367) (xy 183.657795 -235.106467) (xy 183.711752 -235.120573)
			(xy 183.763081 -235.142385) (xy 183.810687 -235.171439) (xy 183.853555 -235.207114) (xy 183.890772 -235.248651)
			(xy 183.921545 -235.295164) (xy 183.945217 -235.345661) (xy 183.961285 -235.399068) (xy 183.969405 -235.454244)
			(xy 183.969914 -235.48213) (xy 183.969405 -235.510016) (xy 183.961285 -235.565192) (xy 183.945217 -235.618599)
			(xy 183.921545 -235.669096) (xy 183.890772 -235.715609) (xy 183.853555 -235.757146) (xy 183.810687 -235.792821)
			(xy 183.763081 -235.821875) (xy 183.711752 -235.843687) (xy 183.657795 -235.857793) (xy 183.602358 -235.863893)
			(xy 183.546624 -235.861856) (xy 183.491781 -235.851726) (xy 183.438997 -235.833719) (xy 183.389397 -235.808218)
			(xy 183.344039 -235.775767) (xy 183.30389 -235.737058) (xy 183.269804 -235.692915) (xy 183.242508 -235.64428)
			(xy 183.222585 -235.592189) (xy 183.210459 -235.537752) (xy 183.206388 -235.48213) (xy 181.105603 -235.48213)
			(xy 180.889213 -236.65942) (xy 182.566816 -236.65942) (xy 182.570887 -236.603798) (xy 182.583013 -236.549361)
			(xy 182.602936 -236.49727) (xy 182.630232 -236.448635) (xy 182.664318 -236.404492) (xy 182.704467 -236.365783)
			(xy 182.749825 -236.333332) (xy 182.799425 -236.307831) (xy 182.852209 -236.289824) (xy 182.907052 -236.279694)
			(xy 182.962786 -236.277657) (xy 183.018223 -236.283757) (xy 183.07218 -236.297863) (xy 183.123509 -236.319675)
			(xy 183.171115 -236.348729) (xy 183.213983 -236.384404) (xy 183.2512 -236.425941) (xy 183.281973 -236.472454)
			(xy 183.305645 -236.522951) (xy 183.321713 -236.576358) (xy 183.329833 -236.631534) (xy 183.330342 -236.65942)
			(xy 183.329833 -236.687306) (xy 183.321713 -236.742482) (xy 183.305645 -236.795889) (xy 183.281973 -236.846386)
			(xy 183.2512 -236.892899) (xy 183.213983 -236.934436) (xy 183.171115 -236.970111) (xy 183.123509 -236.999165)
			(xy 183.07218 -237.020977) (xy 183.018223 -237.035083) (xy 182.962786 -237.041183) (xy 182.907052 -237.039146)
			(xy 182.852209 -237.029016) (xy 182.799425 -237.011009) (xy 182.749825 -236.985508) (xy 182.704467 -236.953057)
			(xy 182.664318 -236.914348) (xy 182.630232 -236.870205) (xy 182.602936 -236.82157) (xy 182.583013 -236.769479)
			(xy 182.570887 -236.715042) (xy 182.566816 -236.65942) (xy 180.889213 -236.65942) (xy 180.381396 -239.422251)
			(xy 183.108578 -239.422251) (xy 183.108578 -239.367749) (xy 183.116334 -239.313801) (xy 183.131689 -239.261506)
			(xy 183.154331 -239.211929) (xy 183.183797 -239.166079) (xy 183.219488 -239.124888) (xy 183.260679 -239.089197)
			(xy 183.306529 -239.059731) (xy 183.356106 -239.037089) (xy 183.408401 -239.021734) (xy 183.462349 -239.013978)
			(xy 183.4896 -239.013492) (xy 183.515775 -239.013916) (xy 183.567631 -239.021092) (xy 183.618017 -239.035297)
			(xy 183.665986 -239.056263) (xy 183.710635 -239.083595) (xy 183.731154 -239.099852) (xy 183.739771 -239.106192)
			(xy 183.760385 -239.11183) (xy 183.771032 -239.110774) (xy 183.85663 -239.097566) (xy 183.87441 -239.086136)
			(xy 183.880506 -239.076992) (xy 183.895682 -239.054692) (xy 183.93136 -239.014235) (xy 183.972383 -238.97921)
			(xy 184.017932 -238.950314) (xy 184.067098 -238.928125) (xy 184.118901 -238.913085) (xy 184.172305 -238.905495)
			(xy 184.199276 -238.905034) (xy 184.226533 -238.905411) (xy 184.280493 -238.913166) (xy 184.332799 -238.928522)
			(xy 184.382388 -238.951166) (xy 184.428249 -238.980636) (xy 184.469449 -239.016334) (xy 184.505149 -239.057532)
			(xy 184.534623 -239.103391) (xy 184.55727 -239.152978) (xy 184.572629 -239.205284) (xy 184.580387 -239.259243)
			(xy 184.580387 -239.313757) (xy 184.572629 -239.367716) (xy 184.55727 -239.420022) (xy 184.547585 -239.441228)
			(xy 185.623706 -239.441228) (xy 185.627777 -239.385606) (xy 185.639903 -239.331169) (xy 185.659826 -239.279078)
			(xy 185.687122 -239.230443) (xy 185.721208 -239.1863) (xy 185.761357 -239.147591) (xy 185.806715 -239.11514)
			(xy 185.856315 -239.089639) (xy 185.909099 -239.071632) (xy 185.963942 -239.061502) (xy 186.019676 -239.059465)
			(xy 186.075113 -239.065565) (xy 186.12907 -239.079671) (xy 186.180399 -239.101483) (xy 186.228005 -239.130537)
			(xy 186.270873 -239.166212) (xy 186.30809 -239.207749) (xy 186.338863 -239.254262) (xy 186.362535 -239.304759)
			(xy 186.378603 -239.358166) (xy 186.386723 -239.413342) (xy 186.387232 -239.441228) (xy 186.386723 -239.469114)
			(xy 186.378603 -239.52429) (xy 186.362535 -239.577697) (xy 186.338863 -239.628194) (xy 186.30809 -239.674707)
			(xy 186.270873 -239.716244) (xy 186.228005 -239.751919) (xy 186.180399 -239.780973) (xy 186.12907 -239.802785)
			(xy 186.075113 -239.816891) (xy 186.019676 -239.822991) (xy 185.963942 -239.820954) (xy 185.909099 -239.810824)
			(xy 185.856315 -239.792817) (xy 185.806715 -239.767316) (xy 185.761357 -239.734865) (xy 185.721208 -239.696156)
			(xy 185.687122 -239.652013) (xy 185.659826 -239.603378) (xy 185.639903 -239.551287) (xy 185.627777 -239.49685)
			(xy 185.623706 -239.441228) (xy 184.547585 -239.441228) (xy 184.534623 -239.469609) (xy 184.505149 -239.515468)
			(xy 184.469449 -239.556666) (xy 184.428249 -239.592364) (xy 184.382388 -239.621834) (xy 184.332799 -239.644478)
			(xy 184.280493 -239.659834) (xy 184.226533 -239.667589) (xy 184.199276 -239.66805) (xy 184.173102 -239.667596)
			(xy 184.121247 -239.660429) (xy 184.07086 -239.646232) (xy 184.022891 -239.625272) (xy 183.978241 -239.597945)
			(xy 183.957722 -239.58169) (xy 183.94911 -239.575341) (xy 183.928492 -239.569707) (xy 183.917844 -239.570768)
			(xy 183.832246 -239.583976) (xy 183.814466 -239.595406) (xy 183.80837 -239.60455) (xy 183.793158 -239.626824)
			(xy 183.757485 -239.667279) (xy 183.716467 -239.702305) (xy 183.670924 -239.731203) (xy 183.621764 -239.753397)
			(xy 183.569968 -239.768443) (xy 183.516569 -239.776042) (xy 183.4896 -239.776508) (xy 183.462349 -239.776022)
			(xy 183.408401 -239.768266) (xy 183.356106 -239.752911) (xy 183.306529 -239.730269) (xy 183.260679 -239.700803)
			(xy 183.219488 -239.665112) (xy 183.183797 -239.623921) (xy 183.154331 -239.578071) (xy 183.131689 -239.528494)
			(xy 183.116334 -239.476199) (xy 183.108578 -239.422251) (xy 180.381396 -239.422251) (xy 180.114179 -240.876074)
			(xy 184.744866 -240.876074) (xy 184.748937 -240.820452) (xy 184.761063 -240.766015) (xy 184.780986 -240.713924)
			(xy 184.808282 -240.665289) (xy 184.842368 -240.621146) (xy 184.882517 -240.582437) (xy 184.927875 -240.549986)
			(xy 184.977475 -240.524485) (xy 185.030259 -240.506478) (xy 185.085102 -240.496348) (xy 185.140836 -240.494311)
			(xy 185.196273 -240.500411) (xy 185.25023 -240.514517) (xy 185.301559 -240.536329) (xy 185.349165 -240.565383)
			(xy 185.392033 -240.601058) (xy 185.42925 -240.642595) (xy 185.460023 -240.689108) (xy 185.483695 -240.739605)
			(xy 185.499763 -240.793012) (xy 185.507883 -240.848188) (xy 185.508392 -240.876074) (xy 185.507883 -240.90396)
			(xy 185.499763 -240.959136) (xy 185.483695 -241.012543) (xy 185.460023 -241.06304) (xy 185.42925 -241.109553)
			(xy 185.392033 -241.15109) (xy 185.349165 -241.186765) (xy 185.301559 -241.215819) (xy 185.25023 -241.237631)
			(xy 185.196273 -241.251737) (xy 185.140836 -241.257837) (xy 185.085102 -241.2558) (xy 185.030259 -241.24567)
			(xy 184.977475 -241.227663) (xy 184.927875 -241.202162) (xy 184.882517 -241.169711) (xy 184.842368 -241.131002)
			(xy 184.808282 -241.086859) (xy 184.780986 -241.038224) (xy 184.761063 -240.986133) (xy 184.748937 -240.931696)
			(xy 184.744866 -240.876074) (xy 180.114179 -240.876074) (xy 180.027577 -241.347244) (xy 186.002674 -241.347244)
			(xy 186.006745 -241.291622) (xy 186.018871 -241.237185) (xy 186.038794 -241.185094) (xy 186.06609 -241.136459)
			(xy 186.100176 -241.092316) (xy 186.140325 -241.053607) (xy 186.185683 -241.021156) (xy 186.235283 -240.995655)
			(xy 186.288067 -240.977648) (xy 186.34291 -240.967518) (xy 186.398644 -240.965481) (xy 186.454081 -240.971581)
			(xy 186.508038 -240.985687) (xy 186.559367 -241.007499) (xy 186.606973 -241.036553) (xy 186.649841 -241.072228)
			(xy 186.687058 -241.113765) (xy 186.717831 -241.160278) (xy 186.741503 -241.210775) (xy 186.757571 -241.264182)
			(xy 186.765691 -241.319358) (xy 186.7662 -241.347244) (xy 186.765691 -241.37513) (xy 186.757571 -241.430306)
			(xy 186.741503 -241.483713) (xy 186.717831 -241.53421) (xy 186.687058 -241.580723) (xy 186.649841 -241.62226)
			(xy 186.606973 -241.657935) (xy 186.559367 -241.686989) (xy 186.508038 -241.708801) (xy 186.454081 -241.722907)
			(xy 186.398644 -241.729007) (xy 186.34291 -241.72697) (xy 186.288067 -241.71684) (xy 186.235283 -241.698833)
			(xy 186.185683 -241.673332) (xy 186.140325 -241.640881) (xy 186.100176 -241.602172) (xy 186.06609 -241.558029)
			(xy 186.038794 -241.509394) (xy 186.018871 -241.457303) (xy 186.006745 -241.402866) (xy 186.002674 -241.347244)
			(xy 180.027577 -241.347244) (xy 179.600867 -243.668804) (xy 184.305446 -243.668804) (xy 184.309517 -243.613182)
			(xy 184.321643 -243.558745) (xy 184.341566 -243.506654) (xy 184.368862 -243.458019) (xy 184.402948 -243.413876)
			(xy 184.443097 -243.375167) (xy 184.488455 -243.342716) (xy 184.538055 -243.317215) (xy 184.590839 -243.299208)
			(xy 184.645682 -243.289078) (xy 184.701416 -243.287041) (xy 184.756853 -243.293141) (xy 184.81081 -243.307247)
			(xy 184.862139 -243.329059) (xy 184.909745 -243.358113) (xy 184.952613 -243.393788) (xy 184.98983 -243.435325)
			(xy 185.020603 -243.481838) (xy 185.044275 -243.532335) (xy 185.060343 -243.585742) (xy 185.068463 -243.640918)
			(xy 185.068972 -243.668804) (xy 185.068463 -243.69669) (xy 185.060343 -243.751866) (xy 185.044275 -243.805273)
			(xy 185.020603 -243.85577) (xy 184.98983 -243.902283) (xy 184.952613 -243.94382) (xy 184.909745 -243.979495)
			(xy 184.862139 -244.008549) (xy 184.81081 -244.030361) (xy 184.756853 -244.044467) (xy 184.701416 -244.050567)
			(xy 184.645682 -244.04853) (xy 184.590839 -244.0384) (xy 184.538055 -244.020393) (xy 184.488455 -243.994892)
			(xy 184.443097 -243.962441) (xy 184.402948 -243.923732) (xy 184.368862 -243.879589) (xy 184.341566 -243.830954)
			(xy 184.321643 -243.778863) (xy 184.309517 -243.724426) (xy 184.305446 -243.668804) (xy 179.600867 -243.668804)
			(xy 179.208938 -245.801134) (xy 178.241064 -251.066808) (xy 188.18936 -251.066808) (xy 188.193431 -251.011186)
			(xy 188.205557 -250.956749) (xy 188.22548 -250.904658) (xy 188.252776 -250.856023) (xy 188.286862 -250.81188)
			(xy 188.327011 -250.773171) (xy 188.372369 -250.74072) (xy 188.421969 -250.715219) (xy 188.474753 -250.697212)
			(xy 188.529596 -250.687082) (xy 188.58533 -250.685045) (xy 188.640767 -250.691145) (xy 188.694724 -250.705251)
			(xy 188.746053 -250.727063) (xy 188.793659 -250.756117) (xy 188.836527 -250.791792) (xy 188.873744 -250.833329)
			(xy 188.904517 -250.879842) (xy 188.928189 -250.930339) (xy 188.944257 -250.983746) (xy 188.952377 -251.038922)
			(xy 188.952886 -251.066808) (xy 188.952377 -251.094694) (xy 188.944257 -251.14987) (xy 188.928189 -251.203277)
			(xy 188.904517 -251.253774) (xy 188.873744 -251.300287) (xy 188.836527 -251.341824) (xy 188.793659 -251.377499)
			(xy 188.746053 -251.406553) (xy 188.694724 -251.428365) (xy 188.640767 -251.442471) (xy 188.58533 -251.448571)
			(xy 188.529596 -251.446534) (xy 188.474753 -251.436404) (xy 188.421969 -251.418397) (xy 188.372369 -251.392896)
			(xy 188.327011 -251.360445) (xy 188.286862 -251.321736) (xy 188.252776 -251.277593) (xy 188.22548 -251.228958)
			(xy 188.205557 -251.176867) (xy 188.193431 -251.12243) (xy 188.18936 -251.066808) (xy 178.241064 -251.066808)
			(xy 178.02733 -252.22962) (xy 178.025876 -252.240714) (xy 178.031527 -252.262336) (xy 178.038252 -252.271276)
			(xy 178.045807 -252.279489) (xy 178.06597 -252.288988) (xy 178.077114 -252.289564) (xy 194.954906 -252.289564)
			(xy 194.963034 -252.288802) (xy 194.963542 -252.288802) (xy 194.97106 -252.2872) (xy 194.984746 -252.280222)
			(xy 194.990466 -252.275086) (xy 196.123052 -251.1425) (xy 196.128243 -251.13682) (xy 196.13522 -251.123114)
			(xy 196.136768 -251.115576) (xy 196.136768 -251.115068) (xy 196.13753 -251.10694) (xy 196.13753 -208.74482)
			(xy 196.137968 -208.734757) (xy 196.145707 -208.716176) (xy 196.152516 -208.708752) (xy 199.987408 -204.87386)
			(xy 199.99482 -204.867176) (xy 200.013253 -204.859579) (xy 200.033191 -204.859579) (xy 200.051624 -204.867176)
			(xy 200.059036 -204.87386) (xy 200.280524 -205.095348) (xy 200.286025 -205.100332) (xy 200.299192 -205.10717)
			(xy 200.306432 -205.10881) (xy 200.316084 -205.109826) (xy 200.647046 -205.109826) (xy 200.653056 -205.109659)
			(xy 200.664739 -205.106838) (xy 200.67016 -205.104238) (xy 200.673637 -205.102403) (xy 200.680024 -205.097817)
			(xy 200.68286 -205.095094) (xy 200.693528 -205.084426) (xy 200.700927 -205.077581) (xy 200.719525 -205.069853)
			(xy 200.729596 -205.06944) (xy 218.33332 -205.06944) (xy 218.344879 -205.068829) (xy 218.365647 -205.058654)
			(xy 218.373198 -205.049882) (xy 218.422474 -204.98689) (xy 218.424974 -204.983516) (xy 218.428927 -204.976109)
			(xy 218.430348 -204.972158) (xy 218.432349 -204.965684) (xy 218.433255 -204.952169) (xy 218.432126 -204.945488)
			(xy 218.426623 -204.922256) (xy 218.42077 -204.874873) (xy 218.420442 -204.851) (xy 218.420928 -204.823749)
			(xy 218.428684 -204.769801) (xy 218.444039 -204.717506) (xy 218.466681 -204.667929) (xy 218.496147 -204.622079)
			(xy 218.531838 -204.580888) (xy 218.573029 -204.545197) (xy 218.618879 -204.515731) (xy 218.668456 -204.493089)
			(xy 218.720751 -204.477734) (xy 218.774699 -204.469978) (xy 218.829201 -204.469978) (xy 218.883149 -204.477734)
			(xy 218.935444 -204.493089) (xy 218.95997 -204.50429) (xy 250.041916 -204.50429) (xy 250.045987 -204.448668)
			(xy 250.058113 -204.394231) (xy 250.078036 -204.34214) (xy 250.105332 -204.293505) (xy 250.139418 -204.249362)
			(xy 250.179567 -204.210653) (xy 250.224925 -204.178202) (xy 250.274525 -204.152701) (xy 250.327309 -204.134694)
			(xy 250.382152 -204.124564) (xy 250.437886 -204.122527) (xy 250.493323 -204.128627) (xy 250.54728 -204.142733)
			(xy 250.598609 -204.164545) (xy 250.646215 -204.193599) (xy 250.689083 -204.229274) (xy 250.7263 -204.270811)
			(xy 250.757073 -204.317324) (xy 250.780745 -204.367821) (xy 250.796813 -204.421228) (xy 250.804933 -204.476404)
			(xy 250.805442 -204.50429) (xy 250.804933 -204.532176) (xy 250.796813 -204.587352) (xy 250.780745 -204.640759)
			(xy 250.757073 -204.691256) (xy 250.7263 -204.737769) (xy 250.689083 -204.779306) (xy 250.646215 -204.814981)
			(xy 250.598609 -204.844035) (xy 250.54728 -204.865847) (xy 250.493323 -204.879953) (xy 250.437886 -204.886053)
			(xy 250.382152 -204.884016) (xy 250.327309 -204.873886) (xy 250.274525 -204.855879) (xy 250.224925 -204.830378)
			(xy 250.179567 -204.797927) (xy 250.139418 -204.759218) (xy 250.105332 -204.715075) (xy 250.078036 -204.66644)
			(xy 250.058113 -204.614349) (xy 250.045987 -204.559912) (xy 250.041916 -204.50429) (xy 218.95997 -204.50429)
			(xy 218.985021 -204.515731) (xy 219.030871 -204.545197) (xy 219.072062 -204.580888) (xy 219.107753 -204.622079)
			(xy 219.137219 -204.667929) (xy 219.159861 -204.717506) (xy 219.175216 -204.769801) (xy 219.182972 -204.823749)
			(xy 219.183458 -204.851) (xy 219.183133 -204.874872) (xy 219.17727 -204.922254) (xy 219.171774 -204.945488)
			(xy 219.170625 -204.952169) (xy 219.171528 -204.965688) (xy 219.173552 -204.972158) (xy 219.174983 -204.976104)
			(xy 219.178943 -204.983505) (xy 219.181426 -204.98689) (xy 219.230702 -205.049882) (xy 219.238242 -205.05867)
			(xy 219.259015 -205.068845) (xy 219.27058 -205.06944) (xy 236.19079 -205.06944) (xy 236.20086 -205.069863)
			(xy 236.219463 -205.077579) (xy 236.226858 -205.084426) (xy 236.237526 -205.095094) (xy 236.240379 -205.097797)
			(xy 236.24676 -205.102385) (xy 236.250226 -205.104238) (xy 236.255652 -205.106826) (xy 236.267332 -205.109657)
			(xy 236.27334 -205.109826) (xy 238.157258 -205.109826) (xy 238.162775 -205.109657) (xy 238.173539 -205.107218)
			(xy 238.178594 -205.105) (xy 238.178848 -205.105) (xy 238.204563 -205.093314) (xy 238.258578 -205.076804)
			(xy 238.314437 -205.068441) (xy 238.342678 -205.067916) (xy 238.370961 -205.068428) (xy 238.426909 -205.076775)
			(xy 238.481011 -205.093291) (xy 238.506762 -205.105) (xy 238.516922 -205.109826) (xy 239.136428 -205.109826)
			(xy 239.149128 -205.108048) (xy 239.149636 -205.108048) (xy 239.173462 -205.102188) (xy 239.22213 -205.095939)
			(xy 239.246664 -205.095602) (xy 239.271195 -205.095984) (xy 239.319859 -205.102225) (xy 239.343692 -205.108048)
			(xy 239.350042 -205.109826) (xy 239.898428 -205.109826) (xy 239.911128 -205.108048) (xy 239.911636 -205.108048)
			(xy 239.935462 -205.102188) (xy 239.98413 -205.095939) (xy 240.008664 -205.095602) (xy 240.033195 -205.095984)
			(xy 240.081859 -205.102225) (xy 240.105692 -205.108048) (xy 240.112042 -205.109826) (xy 241.35969 -205.109826)
			(xy 241.366579 -205.109566) (xy 241.379846 -205.105842) (xy 241.385852 -205.10246) (xy 241.412268 -205.086712)
			(xy 241.421412 -205.07706) (xy 241.42446 -205.071726) (xy 241.439208 -205.047275) (xy 241.474828 -205.002648)
			(xy 241.516699 -204.963825) (xy 241.563886 -204.931673) (xy 241.615337 -204.90691) (xy 241.669902 -204.890087)
			(xy 241.726364 -204.881581) (xy 241.783464 -204.881581) (xy 241.839926 -204.890087) (xy 241.894491 -204.90691)
			(xy 241.945942 -204.931673) (xy 241.993129 -204.963825) (xy 242.035 -205.002648) (xy 242.07062 -205.047275)
			(xy 242.085368 -205.071726) (xy 242.088416 -205.07706) (xy 242.09756 -205.086712) (xy 242.123976 -205.10246)
			(xy 242.129972 -205.10587) (xy 242.143244 -205.10961) (xy 242.150138 -205.109826) (xy 244.451632 -205.109826)
			(xy 244.4603 -205.109521) (xy 244.476661 -205.103805) (xy 244.483636 -205.09865) (xy 244.49024 -205.093316)
			(xy 244.499384 -205.078584) (xy 244.501162 -205.069948) (xy 244.507497 -205.043498) (xy 244.526648 -204.992593)
			(xy 244.552833 -204.944923) (xy 244.585521 -204.901454) (xy 244.62405 -204.863066) (xy 244.667638 -204.830538)
			(xy 244.715404 -204.804528) (xy 244.766379 -204.785564) (xy 244.81953 -204.77403) (xy 244.87378 -204.770159)
			(xy 244.92803 -204.77403) (xy 244.981181 -204.785564) (xy 245.032156 -204.804528) (xy 245.079922 -204.830538)
			(xy 245.12351 -204.863066) (xy 245.162039 -204.901454) (xy 245.194727 -204.944923) (xy 245.220912 -204.992593)
			(xy 245.240063 -205.043498) (xy 245.246398 -205.069948) (xy 245.248598 -205.078295) (xy 245.25769 -205.092956)
			(xy 245.264178 -205.09865) (xy 245.270782 -205.103984) (xy 245.287038 -205.109826) (xy 257.584448 -205.109826)
			(xy 257.593708 -205.109478) (xy 257.611041 -205.102972) (xy 257.61823 -205.097126) (xy 257.625088 -205.09103)
			(xy 257.63347 -205.075028) (xy 257.63474 -205.065376) (xy 257.638718 -205.038112) (xy 257.653503 -204.985035)
			(xy 257.675771 -204.934637) (xy 257.705057 -204.887968) (xy 257.740754 -204.845997) (xy 257.782118 -204.8096)
			(xy 257.828288 -204.779532) (xy 257.878304 -204.75642) (xy 257.931125 -204.740744) (xy 257.985651 -204.732831)
			(xy 258.0132 -204.732382) (xy 258.040452 -204.732868) (xy 258.0944 -204.740624) (xy 258.146695 -204.755979)
			(xy 258.196273 -204.77862) (xy 258.242124 -204.808086) (xy 258.283315 -204.843778) (xy 258.319008 -204.884968)
			(xy 258.348475 -204.930818) (xy 258.371117 -204.980396) (xy 258.386474 -205.03269) (xy 258.394232 -205.086639)
			(xy 258.394708 -205.11389) (xy 258.394708 -205.114398) (xy 258.394308 -205.138686) (xy 258.388104 -205.186865)
			(xy 258.375835 -205.233867) (xy 258.357698 -205.278931) (xy 258.346194 -205.300326) (xy 258.3434 -205.305406)
			(xy 258.339825 -205.315362) (xy 258.340212 -205.336488) (xy 258.344162 -205.3463) (xy 258.346139 -205.350285)
			(xy 258.351239 -205.357572) (xy 258.354322 -205.360778) (xy 259.888228 -206.894684) (xy 260.878586 -206.894684)
			(xy 260.882552 -206.810153) (xy 260.894417 -206.726366) (xy 260.914075 -206.644057) (xy 260.941355 -206.563951)
			(xy 260.976016 -206.486752) (xy 261.017754 -206.413137) (xy 261.066201 -206.343754) (xy 261.120933 -206.279213)
			(xy 261.181469 -206.220081) (xy 261.247275 -206.166877) (xy 261.317775 -206.120069) (xy 261.392347 -206.080068)
			(xy 261.470338 -206.047226) (xy 261.551062 -206.021832) (xy 261.633809 -206.004109) (xy 261.717851 -205.994211)
			(xy 261.802452 -205.992228) (xy 261.886866 -205.998175) (xy 261.970353 -206.012) (xy 262.052178 -206.033583)
			(xy 262.131622 -206.062733) (xy 262.207988 -206.099194) (xy 262.280604 -206.142646) (xy 262.348832 -206.192707)
			(xy 262.412072 -206.248937) (xy 262.469769 -206.310842) (xy 262.487888 -206.33436) (xy 263.587736 -206.33436)
			(xy 263.591807 -206.278738) (xy 263.603933 -206.224301) (xy 263.623856 -206.17221) (xy 263.651152 -206.123575)
			(xy 263.685238 -206.079432) (xy 263.725387 -206.040723) (xy 263.770745 -206.008272) (xy 263.820345 -205.982771)
			(xy 263.873129 -205.964764) (xy 263.927972 -205.954634) (xy 263.983706 -205.952597) (xy 264.039143 -205.958697)
			(xy 264.0931 -205.972803) (xy 264.144429 -205.994615) (xy 264.192035 -206.023669) (xy 264.234903 -206.059344)
			(xy 264.27212 -206.100881) (xy 264.302893 -206.147394) (xy 264.326565 -206.197891) (xy 264.342633 -206.251298)
			(xy 264.350753 -206.306474) (xy 264.351262 -206.33436) (xy 264.350753 -206.362246) (xy 264.342633 -206.417422)
			(xy 264.326565 -206.470829) (xy 264.302893 -206.521326) (xy 264.27212 -206.567839) (xy 264.234903 -206.609376)
			(xy 264.192035 -206.645051) (xy 264.144429 -206.674105) (xy 264.0931 -206.695917) (xy 264.039143 -206.710023)
			(xy 263.983706 -206.716123) (xy 263.927972 -206.714086) (xy 263.873129 -206.703956) (xy 263.820345 -206.685949)
			(xy 263.770745 -206.660448) (xy 263.725387 -206.627997) (xy 263.685238 -206.589288) (xy 263.651152 -206.545145)
			(xy 263.623856 -206.49651) (xy 263.603933 -206.444419) (xy 263.591807 -206.389982) (xy 263.587736 -206.33436)
			(xy 262.487888 -206.33436) (xy 262.521416 -206.377878) (xy 262.566558 -206.449455) (xy 262.6048 -206.524945)
			(xy 262.635804 -206.603684) (xy 262.659299 -206.684981) (xy 262.675078 -206.76812) (xy 262.683002 -206.852372)
			(xy 262.683498 -206.894684) (xy 262.683002 -206.936996) (xy 262.675078 -207.021248) (xy 262.659299 -207.104387)
			(xy 262.635804 -207.185684) (xy 262.6048 -207.264423) (xy 262.566558 -207.339913) (xy 262.521416 -207.41149)
			(xy 262.469769 -207.478526) (xy 262.412072 -207.540431) (xy 262.348832 -207.596661) (xy 262.280604 -207.646722)
			(xy 262.207988 -207.690174) (xy 262.131622 -207.726635) (xy 262.052178 -207.755785) (xy 261.970353 -207.777368)
			(xy 261.886866 -207.791193) (xy 261.802452 -207.79714) (xy 261.717851 -207.795157) (xy 261.633809 -207.785259)
			(xy 261.551062 -207.767536) (xy 261.470338 -207.742142) (xy 261.392347 -207.7093) (xy 261.317775 -207.669299)
			(xy 261.247275 -207.622491) (xy 261.181469 -207.569287) (xy 261.120933 -207.510155) (xy 261.066201 -207.445614)
			(xy 261.017754 -207.376231) (xy 260.976016 -207.302616) (xy 260.941355 -207.225417) (xy 260.914075 -207.145311)
			(xy 260.894417 -207.063002) (xy 260.882552 -206.979215) (xy 260.878586 -206.894684) (xy 259.888228 -206.894684)
			(xy 261.144766 -208.151222) (xy 261.151613 -208.15862) (xy 261.159345 -208.177218) (xy 261.159752 -208.18729)
			(xy 261.159752 -208.402174) (xy 261.159935 -208.407977) (xy 261.162623 -208.419269) (xy 261.165086 -208.424526)
			(xy 261.167372 -208.428844) (xy 261.170411 -208.433461) (xy 261.178104 -208.441393) (xy 261.182612 -208.444592)
			(xy 261.183882 -208.445354) (xy 261.257542 -208.49082) (xy 261.261606 -208.493106) (xy 261.271648 -208.497434)
			(xy 261.293485 -208.498091) (xy 261.30377 -208.494376) (xy 261.306818 -208.492852) (xy 261.351034 -208.471213)
			(xy 261.442699 -208.435305) (xy 261.537312 -208.408095) (xy 261.634048 -208.389819) (xy 261.732066 -208.380635)
			(xy 261.78129 -208.380076) (xy 261.827315 -208.380563) (xy 261.919014 -208.388585) (xy 262.009666 -208.404569)
			(xy 262.098579 -208.428392) (xy 262.185078 -208.459874) (xy 262.268503 -208.498776) (xy 262.348221 -208.5448)
			(xy 262.423624 -208.597597) (xy 262.494139 -208.656765) (xy 262.559228 -208.721854) (xy 262.618397 -208.792368)
			(xy 262.671195 -208.86777) (xy 262.71722 -208.947488) (xy 262.756122 -209.030913) (xy 262.773655 -209.079084)
			(xy 266.711682 -209.079084) (xy 266.715753 -209.023462) (xy 266.727879 -208.969025) (xy 266.747802 -208.916934)
			(xy 266.775098 -208.868299) (xy 266.809184 -208.824156) (xy 266.849333 -208.785447) (xy 266.894691 -208.752996)
			(xy 266.944291 -208.727495) (xy 266.997075 -208.709488) (xy 267.051918 -208.699358) (xy 267.107652 -208.697321)
			(xy 267.163089 -208.703421) (xy 267.217046 -208.717527) (xy 267.268375 -208.739339) (xy 267.315981 -208.768393)
			(xy 267.358849 -208.804068) (xy 267.396066 -208.845605) (xy 267.426839 -208.892118) (xy 267.450511 -208.942615)
			(xy 267.466579 -208.996022) (xy 267.474699 -209.051198) (xy 267.475208 -209.079084) (xy 267.474699 -209.10697)
			(xy 267.466579 -209.162146) (xy 267.450511 -209.215553) (xy 267.426839 -209.26605) (xy 267.396066 -209.312563)
			(xy 267.358849 -209.3541) (xy 267.315981 -209.389775) (xy 267.268375 -209.418829) (xy 267.217046 -209.440641)
			(xy 267.163089 -209.454747) (xy 267.107652 -209.460847) (xy 267.051918 -209.45881) (xy 266.997075 -209.44868)
			(xy 266.944291 -209.430673) (xy 266.894691 -209.405172) (xy 266.849333 -209.372721) (xy 266.809184 -209.334012)
			(xy 266.775098 -209.289869) (xy 266.747802 -209.241234) (xy 266.727879 -209.189143) (xy 266.715753 -209.134706)
			(xy 266.711682 -209.079084) (xy 262.773655 -209.079084) (xy 262.787605 -209.117411) (xy 262.811429 -209.206324)
			(xy 262.827414 -209.296976) (xy 262.835436 -209.388675) (xy 262.835436 -209.480725) (xy 262.827414 -209.572424)
			(xy 262.811429 -209.663076) (xy 262.787605 -209.751989) (xy 262.756122 -209.838487) (xy 262.71722 -209.921912)
			(xy 262.671195 -210.00163) (xy 262.618397 -210.077032) (xy 262.559228 -210.147546) (xy 262.494139 -210.212635)
			(xy 262.423624 -210.271803) (xy 262.348221 -210.3246) (xy 262.268503 -210.370624) (xy 262.185078 -210.409526)
			(xy 262.098579 -210.441008) (xy 262.009666 -210.464831) (xy 261.919014 -210.480815) (xy 261.827315 -210.488837)
			(xy 261.78129 -210.489292) (xy 261.732067 -210.488723) (xy 261.634048 -210.479545) (xy 261.537313 -210.46127)
			(xy 261.442701 -210.434058) (xy 261.351039 -210.398145) (xy 261.306818 -210.376516) (xy 261.30377 -210.374992)
			(xy 261.293496 -210.37122) (xy 261.271642 -210.371891) (xy 261.261606 -210.376262) (xy 261.257542 -210.378548)
			(xy 261.183882 -210.424014) (xy 261.182612 -210.424776) (xy 261.178071 -210.427934) (xy 261.170384 -210.435884)
			(xy 261.167372 -210.440524) (xy 261.165086 -210.444842) (xy 261.162647 -210.450108) (xy 261.159957 -210.461394)
			(xy 261.159752 -210.467194) (xy 261.159752 -211.0232) (xy 264.647932 -211.0232) (xy 264.652003 -210.967578)
			(xy 264.664129 -210.913141) (xy 264.684052 -210.86105) (xy 264.711348 -210.812415) (xy 264.745434 -210.768272)
			(xy 264.785583 -210.729563) (xy 264.830941 -210.697112) (xy 264.880541 -210.671611) (xy 264.933325 -210.653604)
			(xy 264.988168 -210.643474) (xy 265.043902 -210.641437) (xy 265.099339 -210.647537) (xy 265.153296 -210.661643)
			(xy 265.204625 -210.683455) (xy 265.252231 -210.712509) (xy 265.295099 -210.748184) (xy 265.332316 -210.789721)
			(xy 265.363089 -210.836234) (xy 265.386761 -210.886731) (xy 265.402829 -210.940138) (xy 265.410949 -210.995314)
			(xy 265.411458 -211.0232) (xy 265.410949 -211.051086) (xy 265.402829 -211.106262) (xy 265.386761 -211.159669)
			(xy 265.363089 -211.210166) (xy 265.332316 -211.256679) (xy 265.295099 -211.298216) (xy 265.252231 -211.333891)
			(xy 265.204625 -211.362945) (xy 265.153296 -211.384757) (xy 265.099339 -211.398863) (xy 265.043902 -211.404963)
			(xy 264.988168 -211.402926) (xy 264.933325 -211.392796) (xy 264.880541 -211.374789) (xy 264.830941 -211.349288)
			(xy 264.785583 -211.316837) (xy 264.745434 -211.278128) (xy 264.711348 -211.233985) (xy 264.684052 -211.18535)
			(xy 264.664129 -211.133259) (xy 264.652003 -211.078822) (xy 264.647932 -211.0232) (xy 261.159752 -211.0232)
			(xy 261.159752 -211.607908) (xy 265.889738 -211.607908) (xy 265.893809 -211.552286) (xy 265.905935 -211.497849)
			(xy 265.925858 -211.445758) (xy 265.953154 -211.397123) (xy 265.98724 -211.35298) (xy 266.027389 -211.314271)
			(xy 266.072747 -211.28182) (xy 266.122347 -211.256319) (xy 266.175131 -211.238312) (xy 266.229974 -211.228182)
			(xy 266.285708 -211.226145) (xy 266.341145 -211.232245) (xy 266.395102 -211.246351) (xy 266.446431 -211.268163)
			(xy 266.494037 -211.297217) (xy 266.536905 -211.332892) (xy 266.574122 -211.374429) (xy 266.604895 -211.420942)
			(xy 266.628567 -211.471439) (xy 266.644635 -211.524846) (xy 266.645122 -211.528152) (xy 267.17955 -211.528152)
			(xy 267.183621 -211.47253) (xy 267.195747 -211.418093) (xy 267.21567 -211.366002) (xy 267.242966 -211.317367)
			(xy 267.277052 -211.273224) (xy 267.317201 -211.234515) (xy 267.362559 -211.202064) (xy 267.412159 -211.176563)
			(xy 267.464943 -211.158556) (xy 267.519786 -211.148426) (xy 267.57552 -211.146389) (xy 267.630957 -211.152489)
			(xy 267.684914 -211.166595) (xy 267.736243 -211.188407) (xy 267.783849 -211.217461) (xy 267.826717 -211.253136)
			(xy 267.863934 -211.294673) (xy 267.894707 -211.341186) (xy 267.918379 -211.391683) (xy 267.934447 -211.44509)
			(xy 267.942567 -211.500266) (xy 267.943076 -211.528152) (xy 267.942567 -211.556038) (xy 267.934447 -211.611214)
			(xy 267.918379 -211.664621) (xy 267.894707 -211.715118) (xy 267.863934 -211.761631) (xy 267.826717 -211.803168)
			(xy 267.783849 -211.838843) (xy 267.736243 -211.867897) (xy 267.684914 -211.889709) (xy 267.630957 -211.903815)
			(xy 267.57552 -211.909915) (xy 267.519786 -211.907878) (xy 267.464943 -211.897748) (xy 267.412159 -211.879741)
			(xy 267.362559 -211.85424) (xy 267.317201 -211.821789) (xy 267.277052 -211.78308) (xy 267.242966 -211.738937)
			(xy 267.21567 -211.690302) (xy 267.195747 -211.638211) (xy 267.183621 -211.583774) (xy 267.17955 -211.528152)
			(xy 266.645122 -211.528152) (xy 266.652755 -211.580022) (xy 266.653264 -211.607908) (xy 266.652755 -211.635794)
			(xy 266.644635 -211.69097) (xy 266.628567 -211.744377) (xy 266.604895 -211.794874) (xy 266.574122 -211.841387)
			(xy 266.536905 -211.882924) (xy 266.494037 -211.918599) (xy 266.446431 -211.947653) (xy 266.395102 -211.969465)
			(xy 266.341145 -211.983571) (xy 266.285708 -211.989671) (xy 266.229974 -211.987634) (xy 266.175131 -211.977504)
			(xy 266.122347 -211.959497) (xy 266.072747 -211.933996) (xy 266.027389 -211.901545) (xy 265.98724 -211.862836)
			(xy 265.953154 -211.818693) (xy 265.925858 -211.770058) (xy 265.905935 -211.717967) (xy 265.893809 -211.66353)
			(xy 265.889738 -211.607908) (xy 261.159752 -211.607908) (xy 261.159752 -212.467444) (xy 263.14984 -212.467444)
			(xy 263.153911 -212.411822) (xy 263.166037 -212.357385) (xy 263.18596 -212.305294) (xy 263.213256 -212.256659)
			(xy 263.247342 -212.212516) (xy 263.287491 -212.173807) (xy 263.332849 -212.141356) (xy 263.382449 -212.115855)
			(xy 263.435233 -212.097848) (xy 263.490076 -212.087718) (xy 263.54581 -212.085681) (xy 263.601247 -212.091781)
			(xy 263.655204 -212.105887) (xy 263.706533 -212.127699) (xy 263.754139 -212.156753) (xy 263.797007 -212.192428)
			(xy 263.834224 -212.233965) (xy 263.864997 -212.280478) (xy 263.888669 -212.330975) (xy 263.904737 -212.384382)
			(xy 263.912857 -212.439558) (xy 263.913366 -212.467444) (xy 263.912857 -212.49533) (xy 263.904737 -212.550506)
			(xy 263.888669 -212.603913) (xy 263.864997 -212.65441) (xy 263.834224 -212.700923) (xy 263.797007 -212.74246)
			(xy 263.754139 -212.778135) (xy 263.706533 -212.807189) (xy 263.655204 -212.829001) (xy 263.601247 -212.843107)
			(xy 263.54581 -212.849207) (xy 263.490076 -212.84717) (xy 263.435233 -212.83704) (xy 263.382449 -212.819033)
			(xy 263.332849 -212.793532) (xy 263.287491 -212.761081) (xy 263.247342 -212.722372) (xy 263.213256 -212.678229)
			(xy 263.18596 -212.629594) (xy 263.166037 -212.577503) (xy 263.153911 -212.523066) (xy 263.14984 -212.467444)
			(xy 261.159752 -212.467444) (xy 261.159752 -213.700106) (xy 263.98728 -213.700106) (xy 263.98766 -213.674323)
			(xy 263.994606 -213.623227) (xy 264.008372 -213.573533) (xy 264.028706 -213.526145) (xy 264.055239 -213.48193)
			(xy 264.087487 -213.441691) (xy 264.124861 -213.406164) (xy 264.145522 -213.390734) (xy 264.154017 -213.384061)
			(xy 264.164794 -213.365358) (xy 264.16635 -213.354666) (xy 264.174732 -213.267798) (xy 264.167874 -213.247224)
			(xy 264.160254 -213.239096) (xy 264.141101 -213.217806) (xy 264.108777 -213.170536) (xy 264.083876 -213.118966)
			(xy 264.066959 -213.064256) (xy 264.058404 -213.007633) (xy 264.057892 -212.979) (xy 264.058378 -212.951749)
			(xy 264.066134 -212.897801) (xy 264.081489 -212.845506) (xy 264.104131 -212.795929) (xy 264.133597 -212.750079)
			(xy 264.169288 -212.708888) (xy 264.210479 -212.673197) (xy 264.256329 -212.643731) (xy 264.305906 -212.621089)
			(xy 264.358201 -212.605734) (xy 264.412149 -212.597978) (xy 264.4394 -212.597492) (xy 264.471589 -212.5982)
			(xy 264.535047 -212.609045) (xy 264.565638 -212.619082) (xy 264.565892 -212.619082) (xy 264.577978 -212.622519)
			(xy 264.602752 -212.618534) (xy 264.613136 -212.611462) (xy 264.6807 -212.559646) (xy 264.690365 -212.551366)
			(xy 264.700766 -212.528174) (xy 264.700512 -212.51545) (xy 264.699496 -212.487002) (xy 264.699976 -212.459751)
			(xy 264.707732 -212.405803) (xy 264.723087 -212.353508) (xy 264.745728 -212.30393) (xy 264.775194 -212.258079)
			(xy 264.810885 -212.216889) (xy 264.852076 -212.181197) (xy 264.897926 -212.15173) (xy 264.947503 -212.129088)
			(xy 264.999798 -212.113733) (xy 265.053746 -212.105976) (xy 265.108249 -212.105976) (xy 265.162197 -212.113732)
			(xy 265.214492 -212.129087) (xy 265.264069 -212.151727) (xy 265.30992 -212.181193) (xy 265.351111 -212.216885)
			(xy 265.386803 -212.258075) (xy 265.41627 -212.303925) (xy 265.438911 -212.353503) (xy 265.454267 -212.405797)
			(xy 265.462024 -212.459745) (xy 265.462024 -212.514248) (xy 265.454268 -212.568196) (xy 265.438914 -212.620491)
			(xy 265.416273 -212.670069) (xy 265.386807 -212.71592) (xy 265.351116 -212.75711) (xy 265.309926 -212.792803)
			(xy 265.299626 -212.799422) (xy 266.408914 -212.799422) (xy 266.412985 -212.7438) (xy 266.425111 -212.689363)
			(xy 266.445034 -212.637272) (xy 266.47233 -212.588637) (xy 266.506416 -212.544494) (xy 266.546565 -212.505785)
			(xy 266.591923 -212.473334) (xy 266.641523 -212.447833) (xy 266.694307 -212.429826) (xy 266.74915 -212.419696)
			(xy 266.804884 -212.417659) (xy 266.860321 -212.423759) (xy 266.914278 -212.437865) (xy 266.965607 -212.459677)
			(xy 267.013213 -212.488731) (xy 267.056081 -212.524406) (xy 267.093298 -212.565943) (xy 267.124071 -212.612456)
			(xy 267.147743 -212.662953) (xy 267.163811 -212.71636) (xy 267.171931 -212.771536) (xy 267.172092 -212.780372)
			(xy 267.311884 -212.780372) (xy 267.315955 -212.72475) (xy 267.328081 -212.670313) (xy 267.348004 -212.618222)
			(xy 267.3753 -212.569587) (xy 267.409386 -212.525444) (xy 267.449535 -212.486735) (xy 267.494893 -212.454284)
			(xy 267.544493 -212.428783) (xy 267.597277 -212.410776) (xy 267.65212 -212.400646) (xy 267.707854 -212.398609)
			(xy 267.763291 -212.404709) (xy 267.817248 -212.418815) (xy 267.868577 -212.440627) (xy 267.916183 -212.469681)
			(xy 267.959051 -212.505356) (xy 267.996268 -212.546893) (xy 268.027041 -212.593406) (xy 268.050713 -212.643903)
			(xy 268.066781 -212.69731) (xy 268.074901 -212.752486) (xy 268.07541 -212.780372) (xy 268.074901 -212.808258)
			(xy 268.066781 -212.863434) (xy 268.050713 -212.916841) (xy 268.027041 -212.967338) (xy 267.996268 -213.013851)
			(xy 267.959051 -213.055388) (xy 267.916183 -213.091063) (xy 267.868577 -213.120117) (xy 267.817248 -213.141929)
			(xy 267.763291 -213.156035) (xy 267.707854 -213.162135) (xy 267.65212 -213.160098) (xy 267.597277 -213.149968)
			(xy 267.544493 -213.131961) (xy 267.494893 -213.10646) (xy 267.449535 -213.074009) (xy 267.409386 -213.0353)
			(xy 267.3753 -212.991157) (xy 267.348004 -212.942522) (xy 267.328081 -212.890431) (xy 267.315955 -212.835994)
			(xy 267.311884 -212.780372) (xy 267.172092 -212.780372) (xy 267.17244 -212.799422) (xy 267.171931 -212.827308)
			(xy 267.163811 -212.882484) (xy 267.147743 -212.935891) (xy 267.124071 -212.986388) (xy 267.093298 -213.032901)
			(xy 267.056081 -213.074438) (xy 267.013213 -213.110113) (xy 266.965607 -213.139167) (xy 266.914278 -213.160979)
			(xy 266.860321 -213.175085) (xy 266.804884 -213.181185) (xy 266.74915 -213.179148) (xy 266.694307 -213.169018)
			(xy 266.641523 -213.151011) (xy 266.591923 -213.12551) (xy 266.546565 -213.093059) (xy 266.506416 -213.05435)
			(xy 266.47233 -213.010207) (xy 266.445034 -212.961572) (xy 266.425111 -212.909481) (xy 266.412985 -212.855044)
			(xy 266.408914 -212.799422) (xy 265.299626 -212.799422) (xy 265.264075 -212.822269) (xy 265.214498 -212.844911)
			(xy 265.162203 -212.860267) (xy 265.108255 -212.868024) (xy 265.081004 -212.86851) (xy 265.048815 -212.867805)
			(xy 264.985357 -212.856959) (xy 264.954766 -212.84692) (xy 264.954512 -212.84692) (xy 264.942426 -212.843486)
			(xy 264.917652 -212.847468) (xy 264.907268 -212.85454) (xy 264.839704 -212.906356) (xy 264.830038 -212.914636)
			(xy 264.819637 -212.937828) (xy 264.819892 -212.950552) (xy 264.820908 -212.979) (xy 264.820496 -213.004781)
			(xy 264.813551 -213.055875) (xy 264.799788 -213.105567) (xy 264.779458 -213.152953) (xy 264.752931 -213.197168)
			(xy 264.72069 -213.237409) (xy 264.683323 -213.27294) (xy 264.662666 -213.288372) (xy 264.654166 -213.29504)
			(xy 264.643392 -213.313747) (xy 264.641838 -213.32444) (xy 264.633456 -213.411308) (xy 264.640314 -213.431882)
			(xy 264.647934 -213.44001) (xy 264.667088 -213.461299) (xy 264.699413 -213.50857) (xy 264.724313 -213.560139)
			(xy 264.74123 -213.614849) (xy 264.749428 -213.669118) (xy 265.313412 -213.669118) (xy 265.317483 -213.613496)
			(xy 265.329609 -213.559059) (xy 265.349532 -213.506968) (xy 265.376828 -213.458333) (xy 265.410914 -213.41419)
			(xy 265.451063 -213.375481) (xy 265.496421 -213.34303) (xy 265.546021 -213.317529) (xy 265.598805 -213.299522)
			(xy 265.653648 -213.289392) (xy 265.709382 -213.287355) (xy 265.764819 -213.293455) (xy 265.818776 -213.307561)
			(xy 265.870105 -213.329373) (xy 265.917711 -213.358427) (xy 265.960579 -213.394102) (xy 265.997796 -213.435639)
			(xy 266.028569 -213.482152) (xy 266.052241 -213.532649) (xy 266.068309 -213.586056) (xy 266.076429 -213.641232)
			(xy 266.076938 -213.669118) (xy 266.076519 -213.692051) (xy 266.953978 -213.692051) (xy 266.953978 -213.637549)
			(xy 266.961734 -213.583601) (xy 266.977089 -213.531306) (xy 266.999731 -213.481729) (xy 267.029197 -213.435879)
			(xy 267.064888 -213.394688) (xy 267.106079 -213.358997) (xy 267.151929 -213.329531) (xy 267.201506 -213.306889)
			(xy 267.253801 -213.291534) (xy 267.307749 -213.283778) (xy 267.335 -213.283292) (xy 267.364053 -213.283833)
			(xy 267.421489 -213.292632) (xy 267.476926 -213.31004) (xy 267.529081 -213.335657) (xy 267.576747 -213.368888)
			(xy 267.61882 -213.408964) (xy 267.637006 -213.431628) (xy 267.646374 -213.442846) (xy 267.670074 -213.459923)
			(xy 267.697638 -213.46959) (xy 267.726812 -213.471057) (xy 267.755208 -213.464204) (xy 267.7805 -213.44959)
			(xy 267.80062 -213.428413) (xy 267.807694 -213.415626) (xy 267.820022 -213.39245) (xy 267.850021 -213.349374)
			(xy 267.885639 -213.310814) (xy 267.926205 -213.277499) (xy 267.970953 -213.250057) (xy 268.01904 -213.229005)
			(xy 268.069558 -213.214742) (xy 268.121554 -213.207535) (xy 268.1478 -213.207092) (xy 268.175051 -213.207578)
			(xy 268.228999 -213.215334) (xy 268.281294 -213.230689) (xy 268.330871 -213.253331) (xy 268.376721 -213.282797)
			(xy 268.417912 -213.318488) (xy 268.453603 -213.359679) (xy 268.483069 -213.405529) (xy 268.505711 -213.455106)
			(xy 268.521066 -213.507401) (xy 268.528822 -213.561349) (xy 268.528822 -213.615851) (xy 268.521066 -213.669799)
			(xy 268.505711 -213.722094) (xy 268.483069 -213.771671) (xy 268.453603 -213.817521) (xy 268.417912 -213.858712)
			(xy 268.376721 -213.894403) (xy 268.330871 -213.923869) (xy 268.281294 -213.946511) (xy 268.228999 -213.961866)
			(xy 268.175051 -213.969622) (xy 268.1478 -213.970108) (xy 268.118747 -213.969567) (xy 268.061311 -213.960768)
			(xy 268.005874 -213.94336) (xy 267.953719 -213.917743) (xy 267.906053 -213.884512) (xy 267.86398 -213.844436)
			(xy 267.845794 -213.821772) (xy 267.836426 -213.810554) (xy 267.812726 -213.793477) (xy 267.785162 -213.78381)
			(xy 267.755988 -213.782343) (xy 267.727592 -213.789196) (xy 267.7023 -213.80381) (xy 267.68218 -213.824987)
			(xy 267.675106 -213.837774) (xy 267.662778 -213.86095) (xy 267.632779 -213.904026) (xy 267.597161 -213.942586)
			(xy 267.556595 -213.975901) (xy 267.511847 -214.003343) (xy 267.46376 -214.024395) (xy 267.413242 -214.038658)
			(xy 267.361246 -214.045865) (xy 267.335 -214.046308) (xy 267.307749 -214.045822) (xy 267.253801 -214.038066)
			(xy 267.201506 -214.022711) (xy 267.151929 -214.000069) (xy 267.106079 -213.970603) (xy 267.064888 -213.934912)
			(xy 267.029197 -213.893721) (xy 266.999731 -213.847871) (xy 266.977089 -213.798294) (xy 266.961734 -213.745999)
			(xy 266.953978 -213.692051) (xy 266.076519 -213.692051) (xy 266.076429 -213.697004) (xy 266.068309 -213.75218)
			(xy 266.052241 -213.805587) (xy 266.028569 -213.856084) (xy 265.997796 -213.902597) (xy 265.960579 -213.944134)
			(xy 265.917711 -213.979809) (xy 265.870105 -214.008863) (xy 265.818776 -214.030675) (xy 265.764819 -214.044781)
			(xy 265.709382 -214.050881) (xy 265.653648 -214.048844) (xy 265.598805 -214.038714) (xy 265.546021 -214.020707)
			(xy 265.496421 -213.995206) (xy 265.451063 -213.962755) (xy 265.410914 -213.924046) (xy 265.376828 -213.879903)
			(xy 265.349532 -213.831268) (xy 265.329609 -213.779177) (xy 265.317483 -213.72474) (xy 265.313412 -213.669118)
			(xy 264.749428 -213.669118) (xy 264.749784 -213.671473) (xy 264.750296 -213.700106) (xy 264.74981 -213.727357)
			(xy 264.742054 -213.781305) (xy 264.726699 -213.8336) (xy 264.704057 -213.883177) (xy 264.674591 -213.929027)
			(xy 264.6389 -213.970218) (xy 264.597709 -214.005909) (xy 264.551859 -214.035375) (xy 264.502282 -214.058017)
			(xy 264.449987 -214.073372) (xy 264.396039 -214.081128) (xy 264.341537 -214.081128) (xy 264.287589 -214.073372)
			(xy 264.235294 -214.058017) (xy 264.185717 -214.035375) (xy 264.139867 -214.005909) (xy 264.098676 -213.970218)
			(xy 264.062985 -213.929027) (xy 264.033519 -213.883177) (xy 264.010877 -213.8336) (xy 263.995522 -213.781305)
			(xy 263.987766 -213.727357) (xy 263.98728 -213.700106) (xy 261.159752 -213.700106) (xy 261.159752 -215.969342)
			(xy 261.698484 -215.969342) (xy 261.702555 -215.91372) (xy 261.714681 -215.859283) (xy 261.734604 -215.807192)
			(xy 261.7619 -215.758557) (xy 261.795986 -215.714414) (xy 261.836135 -215.675705) (xy 261.881493 -215.643254)
			(xy 261.931093 -215.617753) (xy 261.983877 -215.599746) (xy 262.03872 -215.589616) (xy 262.094454 -215.587579)
			(xy 262.149891 -215.593679) (xy 262.203848 -215.607785) (xy 262.255177 -215.629597) (xy 262.302783 -215.658651)
			(xy 262.345651 -215.694326) (xy 262.382868 -215.735863) (xy 262.413641 -215.782376) (xy 262.437313 -215.832873)
			(xy 262.453381 -215.88628) (xy 262.461501 -215.941456) (xy 262.46201 -215.969342) (xy 262.461501 -215.997228)
			(xy 262.453381 -216.052404) (xy 262.437313 -216.105811) (xy 262.413641 -216.156308) (xy 262.382868 -216.202821)
			(xy 262.345651 -216.244358) (xy 262.302783 -216.280033) (xy 262.255177 -216.309087) (xy 262.203848 -216.330899)
			(xy 262.149891 -216.345005) (xy 262.094454 -216.351105) (xy 262.03872 -216.349068) (xy 261.983877 -216.338938)
			(xy 261.931093 -216.320931) (xy 261.881493 -216.29543) (xy 261.836135 -216.262979) (xy 261.795986 -216.22427)
			(xy 261.7619 -216.180127) (xy 261.734604 -216.131492) (xy 261.714681 -216.079401) (xy 261.702555 -216.024964)
			(xy 261.698484 -215.969342) (xy 261.159752 -215.969342) (xy 261.159752 -217.432382) (xy 266.08608 -217.432382)
			(xy 266.090151 -217.37676) (xy 266.102277 -217.322323) (xy 266.1222 -217.270232) (xy 266.149496 -217.221597)
			(xy 266.183582 -217.177454) (xy 266.223731 -217.138745) (xy 266.269089 -217.106294) (xy 266.318689 -217.080793)
			(xy 266.371473 -217.062786) (xy 266.426316 -217.052656) (xy 266.48205 -217.050619) (xy 266.537487 -217.056719)
			(xy 266.591444 -217.070825) (xy 266.642773 -217.092637) (xy 266.690379 -217.121691) (xy 266.733247 -217.157366)
			(xy 266.770464 -217.198903) (xy 266.801237 -217.245416) (xy 266.822085 -217.289888) (xy 267.310868 -217.289888)
			(xy 267.314939 -217.234266) (xy 267.327065 -217.179829) (xy 267.346988 -217.127738) (xy 267.374284 -217.079103)
			(xy 267.40837 -217.03496) (xy 267.448519 -216.996251) (xy 267.493877 -216.9638) (xy 267.543477 -216.938299)
			(xy 267.596261 -216.920292) (xy 267.651104 -216.910162) (xy 267.706838 -216.908125) (xy 267.762275 -216.914225)
			(xy 267.816232 -216.928331) (xy 267.867561 -216.950143) (xy 267.915167 -216.979197) (xy 267.958035 -217.014872)
			(xy 267.995252 -217.056409) (xy 268.026025 -217.102922) (xy 268.049697 -217.153419) (xy 268.065765 -217.206826)
			(xy 268.073885 -217.262002) (xy 268.074394 -217.289888) (xy 268.073885 -217.317774) (xy 268.065765 -217.37295)
			(xy 268.049697 -217.426357) (xy 268.026025 -217.476854) (xy 267.995252 -217.523367) (xy 267.958035 -217.564904)
			(xy 267.915167 -217.600579) (xy 267.867561 -217.629633) (xy 267.816232 -217.651445) (xy 267.762275 -217.665551)
			(xy 267.706838 -217.671651) (xy 267.651104 -217.669614) (xy 267.596261 -217.659484) (xy 267.543477 -217.641477)
			(xy 267.493877 -217.615976) (xy 267.448519 -217.583525) (xy 267.40837 -217.544816) (xy 267.374284 -217.500673)
			(xy 267.346988 -217.452038) (xy 267.327065 -217.399947) (xy 267.314939 -217.34551) (xy 267.310868 -217.289888)
			(xy 266.822085 -217.289888) (xy 266.824909 -217.295913) (xy 266.840977 -217.34932) (xy 266.849097 -217.404496)
			(xy 266.849606 -217.432382) (xy 266.849097 -217.460268) (xy 266.840977 -217.515444) (xy 266.824909 -217.568851)
			(xy 266.801237 -217.619348) (xy 266.770464 -217.665861) (xy 266.733247 -217.707398) (xy 266.690379 -217.743073)
			(xy 266.642773 -217.772127) (xy 266.591444 -217.793939) (xy 266.537487 -217.808045) (xy 266.48205 -217.814145)
			(xy 266.426316 -217.812108) (xy 266.371473 -217.801978) (xy 266.318689 -217.783971) (xy 266.269089 -217.75847)
			(xy 266.223731 -217.726019) (xy 266.183582 -217.68731) (xy 266.149496 -217.643167) (xy 266.1222 -217.594532)
			(xy 266.102277 -217.542441) (xy 266.090151 -217.488004) (xy 266.08608 -217.432382) (xy 261.159752 -217.432382)
			(xy 261.159752 -218.74734) (xy 264.893042 -218.74734) (xy 264.897113 -218.691718) (xy 264.909239 -218.637281)
			(xy 264.929162 -218.58519) (xy 264.956458 -218.536555) (xy 264.990544 -218.492412) (xy 265.030693 -218.453703)
			(xy 265.076051 -218.421252) (xy 265.125651 -218.395751) (xy 265.178435 -218.377744) (xy 265.233278 -218.367614)
			(xy 265.289012 -218.365577) (xy 265.344449 -218.371677) (xy 265.398406 -218.385783) (xy 265.449735 -218.407595)
			(xy 265.497341 -218.436649) (xy 265.540209 -218.472324) (xy 265.577426 -218.513861) (xy 265.608199 -218.560374)
			(xy 265.631871 -218.610871) (xy 265.647939 -218.664278) (xy 265.656059 -218.719454) (xy 265.656568 -218.74734)
			(xy 265.656059 -218.775226) (xy 265.647939 -218.830402) (xy 265.631871 -218.883809) (xy 265.608199 -218.934306)
			(xy 265.577426 -218.980819) (xy 265.540209 -219.022356) (xy 265.497341 -219.058031) (xy 265.449735 -219.087085)
			(xy 265.398406 -219.108897) (xy 265.344449 -219.123003) (xy 265.289012 -219.129103) (xy 265.233278 -219.127066)
			(xy 265.178435 -219.116936) (xy 265.125651 -219.098929) (xy 265.076051 -219.073428) (xy 265.030693 -219.040977)
			(xy 264.990544 -219.002268) (xy 264.956458 -218.958125) (xy 264.929162 -218.90949) (xy 264.909239 -218.857399)
			(xy 264.897113 -218.802962) (xy 264.893042 -218.74734) (xy 261.159752 -218.74734) (xy 261.159752 -219.176649)
			(xy 262.556 -219.176649) (xy 262.556 -219.122151) (xy 262.563756 -219.068207) (xy 262.57911 -219.015916)
			(xy 262.601749 -218.966343) (xy 262.631212 -218.920495) (xy 262.666901 -218.879308) (xy 262.708087 -218.843618)
			(xy 262.753934 -218.814154) (xy 262.803507 -218.791513) (xy 262.855797 -218.776158) (xy 262.909741 -218.768401)
			(xy 262.93699 -218.767914) (xy 262.964289 -218.7684) (xy 263.01833 -218.776171) (xy 263.070711 -218.791568)
			(xy 263.120361 -218.814279) (xy 263.166264 -218.843837) (xy 263.18718 -218.861386) (xy 263.194369 -218.867232)
			(xy 263.211702 -218.873739) (xy 263.220962 -218.874086) (xy 263.296908 -218.873832) (xy 263.313926 -218.867482)
			(xy 263.320784 -218.861386) (xy 263.34175 -218.843678) (xy 263.387781 -218.813799) (xy 263.437621 -218.790831)
			(xy 263.490241 -218.77525) (xy 263.544551 -218.767377) (xy 263.57199 -218.766898) (xy 263.599244 -218.767349)
			(xy 263.653197 -218.775105) (xy 263.705496 -218.79046) (xy 263.755079 -218.813102) (xy 263.800934 -218.84257)
			(xy 263.842128 -218.878265) (xy 263.877824 -218.919458) (xy 263.907293 -218.965313) (xy 263.929936 -219.014894)
			(xy 263.945293 -219.067194) (xy 263.953051 -219.121146) (xy 263.953051 -219.175654) (xy 263.945293 -219.229606)
			(xy 263.929936 -219.281906) (xy 263.907293 -219.331487) (xy 263.877824 -219.377342) (xy 263.842128 -219.418535)
			(xy 263.800934 -219.45423) (xy 263.755079 -219.483698) (xy 263.705496 -219.50634) (xy 263.653197 -219.521695)
			(xy 263.599244 -219.529451) (xy 263.57199 -219.529914) (xy 263.544691 -219.529432) (xy 263.49065 -219.52166)
			(xy 263.438269 -219.506261) (xy 263.38862 -219.48355) (xy 263.342716 -219.453991) (xy 263.3218 -219.436442)
			(xy 263.314593 -219.430622) (xy 263.297273 -219.424102) (xy 263.288018 -219.423742) (xy 263.212072 -219.423996)
			(xy 263.195054 -219.430346) (xy 263.188196 -219.436442) (xy 263.167242 -219.454164) (xy 263.121207 -219.48404)
			(xy 263.071364 -219.507005) (xy 263.018742 -219.522583) (xy 262.96443 -219.530452) (xy 262.93699 -219.53093)
			(xy 262.909741 -219.530399) (xy 262.855797 -219.522642) (xy 262.803507 -219.507287) (xy 262.753934 -219.484646)
			(xy 262.708087 -219.455182) (xy 262.666901 -219.419492) (xy 262.631212 -219.378305) (xy 262.601749 -219.332457)
			(xy 262.57911 -219.282884) (xy 262.563756 -219.230593) (xy 262.556 -219.176649) (xy 261.159752 -219.176649)
			(xy 261.159752 -221.577408) (xy 265.124182 -221.577408) (xy 265.128253 -221.521786) (xy 265.140379 -221.467349)
			(xy 265.160302 -221.415258) (xy 265.187598 -221.366623) (xy 265.221684 -221.32248) (xy 265.261833 -221.283771)
			(xy 265.307191 -221.25132) (xy 265.356791 -221.225819) (xy 265.409575 -221.207812) (xy 265.464418 -221.197682)
			(xy 265.520152 -221.195645) (xy 265.575589 -221.201745) (xy 265.629546 -221.215851) (xy 265.680875 -221.237663)
			(xy 265.728481 -221.266717) (xy 265.771349 -221.302392) (xy 265.808566 -221.343929) (xy 265.839339 -221.390442)
			(xy 265.863011 -221.440939) (xy 265.879079 -221.494346) (xy 265.887199 -221.549522) (xy 265.887708 -221.577408)
			(xy 265.887199 -221.605294) (xy 265.879079 -221.66047) (xy 265.863011 -221.713877) (xy 265.839339 -221.764374)
			(xy 265.808566 -221.810887) (xy 265.771349 -221.852424) (xy 265.728481 -221.888099) (xy 265.680875 -221.917153)
			(xy 265.629546 -221.938965) (xy 265.575589 -221.953071) (xy 265.520152 -221.959171) (xy 265.464418 -221.957134)
			(xy 265.409575 -221.947004) (xy 265.356791 -221.928997) (xy 265.307191 -221.903496) (xy 265.261833 -221.871045)
			(xy 265.221684 -221.832336) (xy 265.187598 -221.788193) (xy 265.160302 -221.739558) (xy 265.140379 -221.687467)
			(xy 265.128253 -221.63303) (xy 265.124182 -221.577408) (xy 261.159752 -221.577408) (xy 261.159752 -222.323152)
			(xy 263.362184 -222.323152) (xy 263.366255 -222.26753) (xy 263.378381 -222.213093) (xy 263.398304 -222.161002)
			(xy 263.4256 -222.112367) (xy 263.459686 -222.068224) (xy 263.499835 -222.029515) (xy 263.545193 -221.997064)
			(xy 263.594793 -221.971563) (xy 263.647577 -221.953556) (xy 263.70242 -221.943426) (xy 263.758154 -221.941389)
			(xy 263.813591 -221.947489) (xy 263.867548 -221.961595) (xy 263.918877 -221.983407) (xy 263.966483 -222.012461)
			(xy 264.009351 -222.048136) (xy 264.046568 -222.089673) (xy 264.077341 -222.136186) (xy 264.101013 -222.186683)
			(xy 264.117081 -222.24009) (xy 264.125201 -222.295266) (xy 264.12571 -222.323152) (xy 264.125201 -222.351038)
			(xy 264.117081 -222.406214) (xy 264.101013 -222.459621) (xy 264.077341 -222.510118) (xy 264.046568 -222.556631)
			(xy 264.009351 -222.598168) (xy 263.966483 -222.633843) (xy 263.918877 -222.662897) (xy 263.867548 -222.684709)
			(xy 263.813591 -222.698815) (xy 263.758154 -222.704915) (xy 263.70242 -222.702878) (xy 263.647577 -222.692748)
			(xy 263.594793 -222.674741) (xy 263.545193 -222.64924) (xy 263.499835 -222.616789) (xy 263.459686 -222.57808)
			(xy 263.4256 -222.533937) (xy 263.398304 -222.485302) (xy 263.378381 -222.433211) (xy 263.366255 -222.378774)
			(xy 263.362184 -222.323152) (xy 261.159752 -222.323152) (xy 261.159752 -222.942658) (xy 261.159752 -222.942912)
			(xy 261.160439 -222.954742) (xy 261.171133 -222.975855) (xy 261.190127 -222.989975) (xy 261.201662 -222.992696)
			(xy 261.228796 -222.996788) (xy 261.281592 -223.011745) (xy 261.331701 -223.034109) (xy 261.378091 -223.063419)
			(xy 261.419805 -223.099071) (xy 261.455982 -223.140329) (xy 261.485878 -223.186344) (xy 261.508875 -223.236166)
			(xy 261.5245 -223.288768) (xy 261.53243 -223.343065) (xy 261.532436 -223.347534) (xy 267.562582 -223.347534)
			(xy 267.566653 -223.291912) (xy 267.578779 -223.237475) (xy 267.598702 -223.185384) (xy 267.625998 -223.136749)
			(xy 267.660084 -223.092606) (xy 267.700233 -223.053897) (xy 267.745591 -223.021446) (xy 267.795191 -222.995945)
			(xy 267.847975 -222.977938) (xy 267.902818 -222.967808) (xy 267.958552 -222.965771) (xy 268.013989 -222.971871)
			(xy 268.067946 -222.985977) (xy 268.119275 -223.007789) (xy 268.166881 -223.036843) (xy 268.209749 -223.072518)
			(xy 268.246966 -223.114055) (xy 268.277739 -223.160568) (xy 268.301411 -223.211065) (xy 268.317479 -223.264472)
			(xy 268.325599 -223.319648) (xy 268.326108 -223.347534) (xy 268.325599 -223.37542) (xy 268.317479 -223.430596)
			(xy 268.301411 -223.484003) (xy 268.277739 -223.5345) (xy 268.246966 -223.581013) (xy 268.209749 -223.62255)
			(xy 268.166881 -223.658225) (xy 268.119275 -223.687279) (xy 268.067946 -223.709091) (xy 268.013989 -223.723197)
			(xy 267.958552 -223.729297) (xy 267.902818 -223.72726) (xy 267.847975 -223.71713) (xy 267.795191 -223.699123)
			(xy 267.745591 -223.673622) (xy 267.700233 -223.641171) (xy 267.660084 -223.602462) (xy 267.625998 -223.558319)
			(xy 267.598702 -223.509684) (xy 267.578779 -223.457593) (xy 267.566653 -223.403156) (xy 267.562582 -223.347534)
			(xy 261.532436 -223.347534) (xy 261.532501 -223.397938) (xy 261.524713 -223.452256) (xy 261.509226 -223.504899)
			(xy 261.486359 -223.554781) (xy 261.456584 -223.600873) (xy 261.438898 -223.621854) (xy 261.433056 -223.628458)
			(xy 261.42315 -223.653604) (xy 261.421606 -223.657952) (xy 261.419944 -223.667025) (xy 261.419848 -223.671638)
			(xy 261.419594 -223.692466) (xy 261.419631 -223.696928) (xy 261.42104 -223.705738) (xy 261.422388 -223.709992)
			(xy 261.42823 -223.721422) (xy 261.43458 -223.729042) (xy 261.61492 -223.909382) (xy 261.621762 -223.916781)
			(xy 261.629479 -223.93538) (xy 261.629906 -223.94545) (xy 261.629906 -225.097086) (xy 263.196068 -225.097086)
			(xy 263.200139 -225.041464) (xy 263.212265 -224.987027) (xy 263.232188 -224.934936) (xy 263.259484 -224.886301)
			(xy 263.29357 -224.842158) (xy 263.333719 -224.803449) (xy 263.379077 -224.770998) (xy 263.428677 -224.745497)
			(xy 263.481461 -224.72749) (xy 263.536304 -224.71736) (xy 263.592038 -224.715323) (xy 263.647475 -224.721423)
			(xy 263.701432 -224.735529) (xy 263.752761 -224.757341) (xy 263.800367 -224.786395) (xy 263.843235 -224.82207)
			(xy 263.880452 -224.863607) (xy 263.911225 -224.91012) (xy 263.934897 -224.960617) (xy 263.950965 -225.014024)
			(xy 263.959085 -225.0692) (xy 263.959594 -225.097086) (xy 263.959085 -225.124972) (xy 263.950965 -225.180148)
			(xy 263.934897 -225.233555) (xy 263.911225 -225.284052) (xy 263.880452 -225.330565) (xy 263.843235 -225.372102)
			(xy 263.800367 -225.407777) (xy 263.752761 -225.436831) (xy 263.701432 -225.458643) (xy 263.698957 -225.45929)
			(xy 268.389352 -225.45929) (xy 268.393423 -225.403668) (xy 268.405549 -225.349231) (xy 268.425472 -225.29714)
			(xy 268.452768 -225.248505) (xy 268.486854 -225.204362) (xy 268.527003 -225.165653) (xy 268.572361 -225.133202)
			(xy 268.621961 -225.107701) (xy 268.674745 -225.089694) (xy 268.729588 -225.079564) (xy 268.785322 -225.077527)
			(xy 268.840759 -225.083627) (xy 268.894716 -225.097733) (xy 268.946045 -225.119545) (xy 268.993651 -225.148599)
			(xy 269.036519 -225.184274) (xy 269.073736 -225.225811) (xy 269.104509 -225.272324) (xy 269.128181 -225.322821)
			(xy 269.144249 -225.376228) (xy 269.152369 -225.431404) (xy 269.152878 -225.45929) (xy 269.152369 -225.487176)
			(xy 269.144249 -225.542352) (xy 269.128181 -225.595759) (xy 269.104509 -225.646256) (xy 269.073736 -225.692769)
			(xy 269.036519 -225.734306) (xy 268.993651 -225.769981) (xy 268.946045 -225.799035) (xy 268.894716 -225.820847)
			(xy 268.840759 -225.834953) (xy 268.785322 -225.841053) (xy 268.729588 -225.839016) (xy 268.674745 -225.828886)
			(xy 268.621961 -225.810879) (xy 268.572361 -225.785378) (xy 268.527003 -225.752927) (xy 268.486854 -225.714218)
			(xy 268.452768 -225.670075) (xy 268.425472 -225.62144) (xy 268.405549 -225.569349) (xy 268.393423 -225.514912)
			(xy 268.389352 -225.45929) (xy 263.698957 -225.45929) (xy 263.647475 -225.472749) (xy 263.592038 -225.478849)
			(xy 263.536304 -225.476812) (xy 263.481461 -225.466682) (xy 263.428677 -225.448675) (xy 263.379077 -225.423174)
			(xy 263.333719 -225.390723) (xy 263.29357 -225.352014) (xy 263.259484 -225.307871) (xy 263.232188 -225.259236)
			(xy 263.212265 -225.207145) (xy 263.200139 -225.152708) (xy 263.196068 -225.097086) (xy 261.629906 -225.097086)
			(xy 261.629906 -226.3394) (xy 266.392912 -226.3394) (xy 266.396983 -226.283778) (xy 266.409109 -226.229341)
			(xy 266.429032 -226.17725) (xy 266.456328 -226.128615) (xy 266.490414 -226.084472) (xy 266.530563 -226.045763)
			(xy 266.575921 -226.013312) (xy 266.625521 -225.987811) (xy 266.678305 -225.969804) (xy 266.733148 -225.959674)
			(xy 266.788882 -225.957637) (xy 266.844319 -225.963737) (xy 266.898276 -225.977843) (xy 266.949605 -225.999655)
			(xy 266.997211 -226.028709) (xy 267.040079 -226.064384) (xy 267.077296 -226.105921) (xy 267.108069 -226.152434)
			(xy 267.131741 -226.202931) (xy 267.147809 -226.256338) (xy 267.155929 -226.311514) (xy 267.156438 -226.3394)
			(xy 267.155929 -226.367286) (xy 267.147809 -226.422462) (xy 267.131741 -226.475869) (xy 267.108069 -226.526366)
			(xy 267.077296 -226.572879) (xy 267.040079 -226.614416) (xy 266.997211 -226.650091) (xy 266.949605 -226.679145)
			(xy 266.898276 -226.700957) (xy 266.844319 -226.715063) (xy 266.788882 -226.721163) (xy 266.733148 -226.719126)
			(xy 266.678305 -226.708996) (xy 266.625521 -226.690989) (xy 266.575921 -226.665488) (xy 266.530563 -226.633037)
			(xy 266.490414 -226.594328) (xy 266.456328 -226.550185) (xy 266.429032 -226.50155) (xy 266.409109 -226.449459)
			(xy 266.396983 -226.395022) (xy 266.392912 -226.3394) (xy 261.629906 -226.3394) (xy 261.629906 -229.25151)
			(xy 263.272522 -229.25151) (xy 263.276593 -229.195888) (xy 263.288719 -229.141451) (xy 263.308642 -229.08936)
			(xy 263.335938 -229.040725) (xy 263.370024 -228.996582) (xy 263.410173 -228.957873) (xy 263.455531 -228.925422)
			(xy 263.505131 -228.899921) (xy 263.557915 -228.881914) (xy 263.612758 -228.871784) (xy 263.668492 -228.869747)
			(xy 263.723929 -228.875847) (xy 263.777886 -228.889953) (xy 263.829215 -228.911765) (xy 263.876821 -228.940819)
			(xy 263.919689 -228.976494) (xy 263.956906 -229.018031) (xy 263.987679 -229.064544) (xy 264.011351 -229.115041)
			(xy 264.027419 -229.168448) (xy 264.035539 -229.223624) (xy 264.036048 -229.25151) (xy 264.035539 -229.279396)
			(xy 264.027419 -229.334572) (xy 264.011351 -229.387979) (xy 263.987679 -229.438476) (xy 263.956906 -229.484989)
			(xy 263.919689 -229.526526) (xy 263.876821 -229.562201) (xy 263.829215 -229.591255) (xy 263.777886 -229.613067)
			(xy 263.723929 -229.627173) (xy 263.668492 -229.633273) (xy 263.612758 -229.631236) (xy 263.557915 -229.621106)
			(xy 263.505131 -229.603099) (xy 263.455531 -229.577598) (xy 263.410173 -229.545147) (xy 263.370024 -229.506438)
			(xy 263.335938 -229.462295) (xy 263.308642 -229.41366) (xy 263.288719 -229.361569) (xy 263.276593 -229.307132)
			(xy 263.272522 -229.25151) (xy 261.629906 -229.25151) (xy 261.629906 -232.703116) (xy 261.630163 -232.710527)
			(xy 261.634432 -232.724721) (xy 261.638288 -232.731056) (xy 261.646416 -232.743502) (xy 261.653782 -232.74655)
			(xy 261.660894 -232.749598) (xy 261.686282 -232.761009) (xy 261.733731 -232.790107) (xy 261.776449 -232.82579)
			(xy 261.813529 -232.867301) (xy 261.844185 -232.91376) (xy 261.867765 -232.964179) (xy 261.883769 -233.017489)
			(xy 261.891858 -233.072559) (xy 261.891859 -233.128219) (xy 261.883774 -233.18329) (xy 261.867773 -233.236601)
			(xy 261.844196 -233.287021) (xy 261.813543 -233.333481) (xy 261.776465 -233.374994) (xy 261.733749 -233.41068)
			(xy 261.686302 -233.439781) (xy 261.660894 -233.451146) (xy 261.653782 -233.454194) (xy 261.646416 -233.457242)
			(xy 261.638288 -233.469688) (xy 261.63442 -233.476017) (xy 261.630151 -233.490215) (xy 261.629906 -233.497628)
			(xy 261.629906 -234.816142) (xy 261.629476 -234.826209) (xy 261.621751 -234.844803) (xy 261.61492 -234.85221)
			(xy 261.593076 -234.874054) (xy 261.586381 -234.881464) (xy 261.578765 -234.899903) (xy 261.578756 -234.919852)
			(xy 261.586356 -234.938298) (xy 261.593076 -234.945682) (xy 263.648444 -237.00105) (xy 263.654121 -237.006248)
			(xy 263.667825 -237.01324) (xy 263.675368 -237.014766) (xy 263.675876 -237.014766) (xy 263.684004 -237.015528)
			(xy 269.02537 -237.015528) (xy 269.033752 -237.014766) (xy 269.042354 -237.012957) (xy 269.05769 -237.004393)
			(xy 269.063724 -236.998002) (xy 269.067788 -236.99343) (xy 269.11173 -236.907578) (xy 269.11173 -236.907324)
			(xy 269.115401 -236.899318) (xy 269.117626 -236.88186) (xy 269.113818 -236.864677) (xy 269.109444 -236.857032)
			(xy 269.107666 -236.854492) (xy 269.090677 -236.829968) (xy 269.063722 -236.77675) (xy 269.045382 -236.719984)
			(xy 269.036105 -236.661054) (xy 269.03553 -236.631226) (xy 269.035992 -236.603973) (xy 269.043746 -236.550021)
			(xy 269.0591 -236.497722) (xy 269.081741 -236.448141) (xy 269.111209 -236.402288) (xy 269.146904 -236.361095)
			(xy 269.188097 -236.325402) (xy 269.233952 -236.295936) (xy 269.283534 -236.273296) (xy 269.335833 -236.257943)
			(xy 269.389785 -236.250191) (xy 269.417038 -236.249718) (xy 269.417292 -236.249718) (xy 269.444545 -236.250181)
			(xy 269.498495 -236.257937) (xy 269.550792 -236.273293) (xy 269.600372 -236.295935) (xy 269.646224 -236.325403)
			(xy 269.687416 -236.361097) (xy 269.723108 -236.40229) (xy 269.752574 -236.448144) (xy 269.775214 -236.497725)
			(xy 269.790567 -236.550023) (xy 269.79832 -236.603973) (xy 269.7988 -236.631226) (xy 269.798218 -236.661096)
			(xy 269.788897 -236.720103) (xy 269.770488 -236.776935) (xy 269.743442 -236.830201) (xy 269.72641 -236.854746)
			(xy 269.724378 -236.857794) (xy 269.720143 -236.865253) (xy 269.716454 -236.881994) (xy 269.718542 -236.899009)
			(xy 269.722092 -236.906816) (xy 269.724124 -236.911134) (xy 269.764764 -236.990128) (xy 269.768828 -236.996478)
			(xy 269.770098 -236.997748) (xy 269.770606 -236.998256) (xy 269.776615 -237.004543) (xy 269.791813 -237.012974)
			(xy 269.800324 -237.014766) (xy 269.808706 -237.015528) (xy 270.363696 -237.015528) (xy 270.373204 -237.014798)
			(xy 270.390692 -237.007228) (xy 270.397732 -237.000796) (xy 270.429482 -236.964728) (xy 270.450564 -236.940598)
			(xy 270.453992 -236.936476) (xy 270.459232 -236.927125) (xy 270.460978 -236.922056) (xy 270.464026 -236.911896)
			(xy 270.462502 -236.90072) (xy 270.460964 -236.888331) (xy 270.459309 -236.863419) (xy 270.4592 -236.850936)
			(xy 270.459704 -236.823085) (xy 270.467802 -236.767974) (xy 270.48383 -236.714628) (xy 270.507447 -236.66418)
			(xy 270.538152 -236.617704) (xy 270.57529 -236.57619) (xy 270.618072 -236.540518) (xy 270.641572 -236.525562)
			(xy 270.643858 -236.524038) (xy 270.660622 -236.507274) (xy 270.66367 -236.502448) (xy 270.678716 -236.479337)
			(xy 270.714408 -236.4373) (xy 270.755779 -236.400837) (xy 270.801968 -236.370709) (xy 270.852012 -236.347543)
			(xy 270.904869 -236.331821) (xy 270.959439 -236.323871) (xy 270.987012 -236.323378) (xy 271.014205 -236.32386)
			(xy 271.068041 -236.331586) (xy 271.120234 -236.346878) (xy 271.169726 -236.369426) (xy 271.215514 -236.398775)
			(xy 271.256671 -236.434329) (xy 271.292361 -236.475366) (xy 271.321863 -236.521057) (xy 271.344576 -236.570474)
			(xy 271.360042 -236.622615) (xy 271.367947 -236.676424) (xy 271.36852 -236.703616) (xy 271.36852 -236.705394)
			(xy 271.368434 -236.716341) (xy 271.367161 -236.738198) (xy 271.36598 -236.749082) (xy 271.365726 -236.754924)
			(xy 271.36598 -236.760766) (xy 271.37487 -236.78388) (xy 271.382484 -236.793545) (xy 271.404245 -236.804945)
			(xy 271.416526 -236.805724) (xy 271.441418 -236.796326) (xy 271.444799 -236.795023) (xy 271.451176 -236.791583)
			(xy 271.454118 -236.789468) (xy 271.466781 -236.779006) (xy 271.493618 -236.760059) (xy 271.507712 -236.751622)
			(xy 271.507966 -236.751368) (xy 271.514038 -236.747573) (xy 271.523962 -236.73726) (xy 271.527524 -236.731048)
			(xy 271.530826 -236.724698) (xy 271.533366 -236.710728) (xy 262.80872 -138.330432) (xy 262.807378 -138.314458)
			(xy 262.8056 -138.282448) (xy 262.805164 -138.266424) (xy 262.291068 -117.09527) (xy 262.291068 -117.092984)
			(xy 262.29056 -117.07114) (xy 262.29056 -117.070632) (xy 262.292084 -117.017292) (xy 262.890254 -105.917746)
			(xy 262.9662 -104.50957) (xy 262.96743 -104.489058) (xy 262.971366 -104.448151) (xy 262.974074 -104.427782)
			(xy 265.030204 -89.408) (xy 265.31316 -87.340948) (xy 265.31316 -87.34044) (xy 265.382756 -86.77783)
			(xy 265.382847 -86.767944) (xy 265.376432 -86.749265) (xy 265.36345 -86.73438) (xy 265.354816 -86.72957)
			(xy 265.335766 -86.719918) (xy 265.269218 -86.68639) (xy 265.262082 -86.683067) (xy 265.246564 -86.68047)
			(xy 265.238738 -86.68131) (xy 265.23188 -86.682326) (xy 265.218164 -86.68893) (xy 265.211814 -86.695026)
			(xy 265.190404 -86.714613) (xy 265.142767 -86.747742) (xy 265.090663 -86.773277) (xy 265.035294 -86.790631)
			(xy 264.977936 -86.799404) (xy 264.948924 -86.799928) (xy 264.94867 -86.799928) (xy 264.92142 -86.79944)
			(xy 264.867474 -86.79168) (xy 264.815182 -86.776323) (xy 264.765607 -86.75368) (xy 264.719759 -86.724213)
			(xy 264.678571 -86.688522) (xy 264.642881 -86.647333) (xy 264.613415 -86.601484) (xy 264.590774 -86.551909)
			(xy 264.575418 -86.499616) (xy 264.567659 -86.44567) (xy 264.567162 -86.41842) (xy 264.567624 -86.39157)
			(xy 264.575161 -86.338402) (xy 264.590075 -86.286815) (xy 264.612071 -86.237827) (xy 264.640716 -86.192405)
			(xy 264.675444 -86.151445) (xy 264.715569 -86.115757) (xy 264.7603 -86.086045) (xy 264.808753 -86.062895)
			(xy 264.859973 -86.046763) (xy 264.912948 -86.037969) (xy 264.93978 -86.036912) (xy 264.947146 -86.036658)
			(xy 264.948924 -86.036658) (xy 264.976356 -86.037128) (xy 265.030655 -86.044975) (xy 265.08327 -86.060519)
			(xy 265.133117 -86.083439) (xy 265.179166 -86.113261) (xy 265.22047 -86.149373) (xy 265.256175 -86.191027)
			(xy 265.27125 -86.21395) (xy 265.275822 -86.221316) (xy 265.28776 -86.231222) (xy 265.294364 -86.234016)
			(xy 265.301618 -86.236662) (xy 265.316997 -86.237956) (xy 265.32459 -86.236556) (xy 265.406886 -86.218268)
			(xy 265.419586 -86.215474) (xy 265.427773 -86.213074) (xy 265.442021 -86.203708) (xy 265.452415 -86.190192)
			(xy 265.4554 -86.1822) (xy 265.457686 -86.172294) (xy 265.501374 -85.819488) (xy 266.476988 -77.9272)
			(xy 266.476861 -77.922653) (xy 266.475196 -77.913711) (xy 266.473686 -77.90942) (xy 266.461748 -77.881988)
			(xy 266.454636 -77.87513) (xy 266.436469 -77.857075) (xy 266.40464 -77.816947) (xy 266.37846 -77.772924)
			(xy 266.358397 -77.725798) (xy 266.344812 -77.676414) (xy 266.337947 -77.625657) (xy 266.337542 -77.600048)
			(xy 266.338002 -77.573193) (xy 266.345536 -77.520015) (xy 266.360446 -77.468417) (xy 266.38244 -77.419417)
			(xy 266.411083 -77.373983) (xy 266.44581 -77.333011) (xy 266.465558 -77.314806) (xy 266.471908 -77.308202)
			(xy 266.478512 -77.297788) (xy 266.482576 -77.289152) (xy 266.483592 -77.258926) (xy 266.485624 -77.20076)
			(xy 266.48537 -77.198728) (xy 266.48156 -77.183234) (xy 266.478004 -77.174598) (xy 266.470638 -77.166724)
			(xy 266.470384 -77.166724) (xy 266.449806 -77.14513) (xy 266.414938 -77.096737) (xy 266.388024 -77.043508)
			(xy 266.36972 -76.98674) (xy 266.360472 -76.927815) (xy 266.359894 -76.897992) (xy 266.360148 -76.88453)
			(xy 266.360402 -76.87691) (xy 266.362382 -76.849609) (xy 266.373186 -76.795948) (xy 266.391556 -76.744385)
			(xy 266.417115 -76.695981) (xy 266.449336 -76.651732) (xy 266.468098 -76.6318) (xy 266.468352 -76.6318)
			(xy 266.492012 -76.608472) (xy 266.54592 -76.569638) (xy 266.57554 -76.554584) (xy 266.581601 -76.551402)
			(xy 266.591896 -76.542386) (xy 266.59586 -76.536804) (xy 266.59967 -76.531216) (xy 266.603734 -76.518516)
			(xy 266.67333 -75.203558) (xy 266.720066 -74.319638) (xy 266.875006 -71.391018) (xy 266.875134 -71.386108)
			(xy 266.87372 -71.376389) (xy 266.872212 -71.371714) (xy 266.869164 -71.362824) (xy 266.863068 -71.355458)
			(xy 266.862814 -71.355204) (xy 266.84623 -71.334541) (xy 266.818324 -71.289502) (xy 266.796916 -71.241037)
			(xy 266.782415 -71.190077) (xy 266.7751 -71.137602) (xy 266.774676 -71.11111) (xy 266.774676 -71.109586)
			(xy 266.774676 -71.095108) (xy 266.775946 -71.078852) (xy 266.777978 -71.060056) (xy 266.778232 -71.059294)
			(xy 266.782088 -71.034236) (xy 266.795567 -70.985362) (xy 266.815396 -70.938702) (xy 266.841225 -70.895076)
			(xy 266.872601 -70.855253) (xy 266.8905 -70.837298) (xy 266.890754 -70.837044) (xy 266.897133 -70.830099)
			(xy 266.904826 -70.812901) (xy 266.90574 -70.803516) (xy 267.337032 -62.641988) (xy 267.337032 -62.6364)
			(xy 267.245338 -61.013848) (xy 267.244128 -61.001494) (xy 267.231486 -60.980164) (xy 267.221208 -60.973208)
			(xy 267.21816 -60.971684) (xy 267.195321 -60.959253) (xy 267.152932 -60.929138) (xy 267.115022 -60.893548)
			(xy 267.082292 -60.853143) (xy 267.05535 -60.80867) (xy 267.034692 -60.760951) (xy 267.020701 -60.710871)
			(xy 267.013637 -60.659355) (xy 267.013182 -60.633356) (xy 267.014706 -60.600336) (xy 267.015976 -60.588652)
			(xy 267.019637 -60.561555) (xy 267.033715 -60.508719) (xy 267.055195 -60.458436) (xy 267.083638 -60.411737)
			(xy 267.118458 -60.369579) (xy 267.158943 -60.332826) (xy 267.18133 -60.317126) (xy 267.186539 -60.313364)
			(xy 267.195028 -60.303723) (xy 267.198094 -60.298076) (xy 267.201396 -60.29198) (xy 267.203936 -60.279026)
			(xy 267.116306 -58.729626) (xy 267.115286 -58.721895) (xy 267.109213 -58.707542) (xy 267.104368 -58.701432)
			(xy 267.104114 -58.701178) (xy 267.086347 -58.680216) (xy 267.056395 -58.634147) (xy 267.03337 -58.584254)
			(xy 267.017748 -58.531572) (xy 267.009855 -58.477193) (xy 267.009372 -58.449718) (xy 267.009906 -58.420752)
			(xy 267.018648 -58.363484) (xy 267.035934 -58.308191) (xy 267.061368 -58.256141) (xy 267.077444 -58.23204)
			(xy 267.078714 -58.230262) (xy 267.082635 -58.223428) (xy 267.086521 -58.208167) (xy 267.086334 -58.20029)
			(xy 267.030962 -57.217056) (xy 266.957556 -55.917846) (xy 266.885674 -54.644798) (xy 266.884207 -54.635125)
			(xy 266.875019 -54.617873) (xy 266.86003 -54.605328) (xy 266.850876 -54.601872) (xy 266.850622 -54.601872)
			(xy 266.825376 -54.593242) (xy 266.777391 -54.569918) (xy 266.733123 -54.540137) (xy 266.693436 -54.504479)
			(xy 266.659102 -54.463641) (xy 266.630793 -54.418418) (xy 266.609059 -54.369692) (xy 266.594325 -54.318413)
			(xy 266.586878 -54.265582) (xy 266.586462 -54.238906) (xy 266.586936 -54.211575) (xy 266.594741 -54.157474)
			(xy 266.61018 -54.105038) (xy 266.632936 -54.055339) (xy 266.662546 -54.009391) (xy 266.698402 -53.968134)
			(xy 266.739775 -53.93241) (xy 266.785817 -53.902948) (xy 266.81049 -53.89118) (xy 266.810744 -53.89118)
			(xy 266.817674 -53.887727) (xy 266.829189 -53.877389) (xy 266.83335 -53.87086) (xy 266.83716 -53.864764)
			(xy 266.840716 -53.850032) (xy 266.743942 -52.13731) (xy 266.719558 -51.70551) (xy 266.718159 -51.692974)
			(xy 266.704976 -51.671505) (xy 266.694412 -51.664616) (xy 266.693142 -51.663854) (xy 266.687679 -51.660875)
			(xy 266.675729 -51.657418) (xy 266.66952 -51.656996) (xy 266.657074 -51.656488) (xy 266.64539 -51.66233)
			(xy 266.619024 -51.674741) (xy 266.56346 -51.692291) (xy 266.505869 -51.701165) (xy 266.476734 -51.7017)
			(xy 266.472162 -51.7017) (xy 266.445047 -51.700916) (xy 266.391439 -51.692627) (xy 266.339545 -51.676832)
			(xy 266.290409 -51.653851) (xy 266.245021 -51.624144) (xy 266.204296 -51.588312) (xy 266.169054 -51.547075)
			(xy 266.154154 -51.524408) (xy 266.152884 -51.522122) (xy 266.152376 -51.521614) (xy 266.15136 -51.520344)
			(xy 266.150852 -51.519582) (xy 266.14628 -51.513994) (xy 266.13977 -51.507519) (xy 266.123363 -51.499307)
			(xy 266.114276 -51.497992) (xy 266.074652 -51.493928) (xy 266.074144 -51.493928) (xy 266.050522 -51.491388)
			(xy 266.050014 -51.491388) (xy 266.034266 -51.489864) (xy 266.022632 -51.489267) (xy 266.000803 -51.497336)
			(xy 265.992356 -51.505358) (xy 265.992102 -51.505612) (xy 265.974007 -51.524179) (xy 265.933671 -51.556748)
			(xy 265.889297 -51.583559) (xy 265.841704 -51.604117) (xy 265.791766 -51.618045) (xy 265.740402 -51.625086)
			(xy 265.71448 -51.6255) (xy 265.68723 -51.625013) (xy 265.633285 -51.617254) (xy 265.580993 -51.601897)
			(xy 265.531419 -51.579255) (xy 265.485571 -51.549788) (xy 265.444384 -51.514096) (xy 265.408696 -51.472906)
			(xy 265.379232 -51.427057) (xy 265.356593 -51.377481) (xy 265.34124 -51.325188) (xy 265.333485 -51.271242)
			(xy 265.332972 -51.243992) (xy 265.333397 -51.218481) (xy 265.340193 -51.167914) (xy 265.353663 -51.118702)
			(xy 265.373567 -51.071723) (xy 265.39955 -51.027813) (xy 265.415014 -51.007518) (xy 265.417554 -51.00447)
			(xy 265.41857 -51.002946) (xy 265.421872 -50.996342) (xy 265.424218 -50.99112) (xy 265.426786 -50.979966)
			(xy 265.426952 -50.974244) (xy 265.426952 -50.94224) (xy 265.438128 -50.94224) (xy 265.438128 -50.89144)
			(xy 265.437792 -50.882837) (xy 265.432075 -50.86661) (xy 265.426952 -50.85969) (xy 265.425682 -50.858166)
			(xy 265.408287 -50.83729) (xy 265.378967 -50.79154) (xy 265.356438 -50.742093) (xy 265.341155 -50.689947)
			(xy 265.333429 -50.636161) (xy 265.332972 -50.608992) (xy 265.333458 -50.581741) (xy 265.341216 -50.527793)
			(xy 265.356571 -50.475498) (xy 265.379213 -50.42592) (xy 265.408679 -50.380069) (xy 265.44437 -50.338878)
			(xy 265.48556 -50.303186) (xy 265.53141 -50.273718) (xy 265.580986 -50.251075) (xy 265.633281 -50.235718)
			(xy 265.687229 -50.227959) (xy 265.71448 -50.227484) (xy 265.742519 -50.227985) (xy 265.79799 -50.236208)
			(xy 265.85166 -50.252465) (xy 265.902371 -50.276404) (xy 265.949031 -50.307511) (xy 265.990632 -50.345115)
			(xy 266.008866 -50.366422) (xy 266.00912 -50.366676) (xy 266.015978 -50.374804) (xy 266.0396 -50.386488)
			(xy 266.04595 -50.389536) (xy 266.050841 -50.391615) (xy 266.061213 -50.39392) (xy 266.066524 -50.394108)
			(xy 266.124182 -50.394108) (xy 266.134596 -50.393092) (xy 266.14628 -50.389028) (xy 266.165584 -50.379376)
			(xy 266.169766 -50.377218) (xy 266.177306 -50.37159) (xy 266.18057 -50.3682) (xy 266.182094 -50.366168)
			(xy 266.201485 -50.343557) (xy 266.246064 -50.304055) (xy 266.29624 -50.271961) (xy 266.350795 -50.248056)
			(xy 266.379452 -50.23993) (xy 266.382246 -50.239168) (xy 266.389866 -50.237136) (xy 266.39393 -50.234088)
			(xy 266.398248 -50.230532) (xy 266.40028 -50.229008) (xy 266.405868 -50.223166) (xy 266.411456 -50.21453)
			(xy 266.420854 -50.197004) (xy 266.425256 -50.187512) (xy 266.42682 -50.166667) (xy 266.423902 -50.156618)
			(xy 266.356338 -49.961292) (xy 266.346432 -49.93259) (xy 266.328906 -49.88179) (xy 266.324815 -49.872635)
			(xy 266.310845 -49.858273) (xy 266.292436 -49.850364) (xy 266.282424 -49.849786) (xy 266.24788 -49.849786)
			(xy 266.243268 -49.849887) (xy 266.234194 -49.851548) (xy 266.229846 -49.853088) (xy 266.221718 -49.856136)
			(xy 266.214606 -49.862232) (xy 266.193674 -49.879873) (xy 266.147707 -49.909597) (xy 266.09796 -49.932439)
			(xy 266.045457 -49.947929) (xy 265.991278 -49.955748) (xy 265.963908 -49.956212) (xy 265.938396 -49.955788)
			(xy 265.887827 -49.948995) (xy 265.838613 -49.935529) (xy 265.79163 -49.91563) (xy 265.747714 -49.889653)
			(xy 265.727434 -49.87417) (xy 265.724386 -49.87163) (xy 265.722862 -49.870614) (xy 265.716258 -49.867312)
			(xy 265.711036 -49.864965) (xy 265.699882 -49.862395) (xy 265.69416 -49.862232) (xy 265.662156 -49.862232)
			(xy 265.662156 -49.851056) (xy 265.611356 -49.851056) (xy 265.602752 -49.851388) (xy 265.58652 -49.8571)
			(xy 265.579606 -49.862232) (xy 265.578082 -49.863502) (xy 265.557204 -49.880893) (xy 265.511453 -49.910204)
			(xy 265.462005 -49.932723) (xy 265.40986 -49.947995) (xy 265.356076 -49.95571) (xy 265.328908 -49.956212)
			(xy 265.303396 -49.955788) (xy 265.252827 -49.948995) (xy 265.203613 -49.935529) (xy 265.15663 -49.91563)
			(xy 265.112714 -49.889653) (xy 265.092434 -49.87417) (xy 265.089386 -49.87163) (xy 265.087862 -49.870614)
			(xy 265.081258 -49.867312) (xy 265.076036 -49.864965) (xy 265.064882 -49.862395) (xy 265.05916 -49.862232)
			(xy 265.027156 -49.862232) (xy 265.027156 -49.851056) (xy 264.976356 -49.851056) (xy 264.967752 -49.851388)
			(xy 264.95152 -49.8571) (xy 264.944606 -49.862232) (xy 264.943082 -49.863502) (xy 264.922204 -49.880893)
			(xy 264.876453 -49.910204) (xy 264.827005 -49.932723) (xy 264.77486 -49.947995) (xy 264.721076 -49.95571)
			(xy 264.693908 -49.956212) (xy 264.666654 -49.955749) (xy 264.612702 -49.947993) (xy 264.560403 -49.932638)
			(xy 264.510821 -49.909995) (xy 264.464967 -49.880527) (xy 264.423772 -49.844833) (xy 264.388078 -49.80364)
			(xy 264.358609 -49.757786) (xy 264.335965 -49.708205) (xy 264.320609 -49.655906) (xy 264.312851 -49.601954)
			(xy 264.312851 -49.547446) (xy 264.320609 -49.493494) (xy 264.335965 -49.441195) (xy 264.358609 -49.391614)
			(xy 264.388078 -49.34576) (xy 264.423772 -49.304567) (xy 264.464967 -49.268873) (xy 264.510821 -49.239405)
			(xy 264.560403 -49.216762) (xy 264.612702 -49.201407) (xy 264.666654 -49.193651) (xy 264.693908 -49.193196)
			(xy 264.719419 -49.193621) (xy 264.769987 -49.200416) (xy 264.8192 -49.213884) (xy 264.866182 -49.233785)
			(xy 264.910095 -49.259764) (xy 264.930382 -49.275238) (xy 264.93343 -49.277778) (xy 264.934954 -49.278794)
			(xy 264.941558 -49.282096) (xy 264.946781 -49.284441) (xy 264.957934 -49.287007) (xy 264.963656 -49.287176)
			(xy 264.99566 -49.287176) (xy 264.99566 -49.298352) (xy 265.04646 -49.298352) (xy 265.055063 -49.298017)
			(xy 265.071292 -49.292302) (xy 265.07821 -49.287176) (xy 265.079734 -49.285906) (xy 265.10061 -49.26851)
			(xy 265.146359 -49.239188) (xy 265.195806 -49.216658) (xy 265.247952 -49.201374) (xy 265.301739 -49.193648)
			(xy 265.328908 -49.193196) (xy 265.354419 -49.193621) (xy 265.404987 -49.200416) (xy 265.4542 -49.213884)
			(xy 265.501182 -49.233785) (xy 265.545095 -49.259764) (xy 265.565382 -49.275238) (xy 265.56843 -49.277778)
			(xy 265.569954 -49.278794) (xy 265.576558 -49.282096) (xy 265.581781 -49.284441) (xy 265.592934 -49.287007)
			(xy 265.598656 -49.287176) (xy 265.63066 -49.287176) (xy 265.63066 -49.298352) (xy 265.68146 -49.298352)
			(xy 265.690063 -49.298017) (xy 265.706292 -49.292302) (xy 265.71321 -49.287176) (xy 265.714734 -49.285906)
			(xy 265.7221 -49.279302) (xy 265.723116 -49.278794) (xy 265.724386 -49.277778) (xy 265.724894 -49.27727)
			(xy 265.746992 -49.26076) (xy 265.747246 -49.260506) (xy 265.747754 -49.260252) (xy 265.762486 -49.250346)
			(xy 265.762994 -49.250346) (xy 265.77925 -49.240694) (xy 265.784141 -49.23781) (xy 265.79261 -49.230251)
			(xy 265.796014 -49.225708) (xy 265.79957 -49.221136) (xy 265.803888 -49.210468) (xy 265.817604 -49.123854)
			(xy 265.818352 -49.113296) (xy 265.812183 -49.093077) (xy 265.805666 -49.084738) (xy 260.067044 -42.828718)
			(xy 260.06277 -42.824917) (xy 260.052893 -42.819155) (xy 260.047486 -42.817288) (xy 260.040374 -42.81551)
			(xy 260.034514 -42.814711) (xy 260.022716 -42.81549) (xy 260.017006 -42.817034) (xy 260.016244 -42.817288)
			(xy 259.928614 -42.845482) (xy 259.919334 -42.848918) (xy 259.904155 -42.861585) (xy 259.89915 -42.87012)
			(xy 259.897341 -42.873796) (xy 259.894784 -42.88158) (xy 259.89407 -42.885614) (xy 259.893816 -42.887646)
			(xy 259.889949 -42.915019) (xy 259.87534 -42.968336) (xy 259.853189 -43.018985) (xy 259.823959 -43.065907)
			(xy 259.788262 -43.108118) (xy 259.746847 -43.144735) (xy 259.700579 -43.174991) (xy 259.65043 -43.198251)
			(xy 259.597448 -43.214029) (xy 259.542743 -43.221994) (xy 259.515102 -43.222418) (xy 259.487848 -43.221955)
			(xy 259.433896 -43.214198) (xy 259.381596 -43.198842) (xy 259.332014 -43.176199) (xy 259.28616 -43.14673)
			(xy 259.244966 -43.111036) (xy 259.209271 -43.069842) (xy 259.179802 -43.023987) (xy 259.157159 -42.974406)
			(xy 259.141802 -42.922106) (xy 259.134045 -42.868154) (xy 259.134045 -42.813646) (xy 259.141802 -42.759694)
			(xy 259.157159 -42.707394) (xy 259.179802 -42.657813) (xy 259.209271 -42.611958) (xy 259.244966 -42.570764)
			(xy 259.28616 -42.53507) (xy 259.332014 -42.505601) (xy 259.381596 -42.482958) (xy 259.433896 -42.467602)
			(xy 259.487848 -42.459845) (xy 259.515102 -42.459402) (xy 259.522722 -42.459402) (xy 259.535137 -42.45878)
			(xy 259.557099 -42.447193) (xy 259.564632 -42.437304) (xy 259.56641 -42.434256) (xy 259.57022 -42.427906)
			(xy 259.606034 -42.365168) (xy 259.606034 -42.36466) (xy 259.610606 -42.356278) (xy 259.613748 -42.350342)
			(xy 259.617089 -42.337339) (xy 259.61721 -42.330624) (xy 259.616956 -42.316908) (xy 259.60959 -42.30497)
			(xy 259.590032 -42.271696) (xy 259.589524 -42.27068) (xy 259.58927 -42.270426) (xy 259.026152 -41.331388)
			(xy 259.018786 -41.322498) (xy 259.018532 -41.322244) (xy 259.013198 -41.317164) (xy 259.006086 -41.313354)
			(xy 259.005324 -41.3131) (xy 258.981901 -41.300902) (xy 258.938362 -41.271012) (xy 258.899367 -41.235397)
			(xy 258.865662 -41.19474) (xy 258.837893 -41.149819) (xy 258.816591 -41.101494) (xy 258.802165 -41.050692)
			(xy 258.794891 -40.998384) (xy 258.794504 -40.971978) (xy 258.794504 -40.960548) (xy 258.794758 -40.953182)
			(xy 258.79298 -40.946324) (xy 258.792048 -40.942662) (xy 258.789246 -40.935646) (xy 258.787392 -40.932354)
			(xy 258.780534 -40.921178) (xy 258.45389 -40.37711) (xy 258.453636 -40.376602) (xy 258.452366 -40.37457)
			(xy 258.450334 -40.371268) (xy 258.444219 -40.3626) (xy 258.426637 -40.350773) (xy 258.416298 -40.348408)
			(xy 258.41579 -40.348408) (xy 258.389362 -40.343589) (xy 258.338105 -40.327507) (xy 258.289611 -40.304393)
			(xy 258.24484 -40.274704) (xy 258.204677 -40.239027) (xy 258.169916 -40.198069) (xy 258.141245 -40.152639)
			(xy 258.119231 -40.103637) (xy 258.104309 -40.05203) (xy 258.096776 -39.99884) (xy 258.096258 -39.97198)
			(xy 258.096258 -39.971726) (xy 258.096842 -39.941422) (xy 258.106413 -39.881575) (xy 258.115308 -39.8526)
			(xy 258.116578 -39.849044) (xy 258.118102 -39.840662) (xy 258.119197 -39.831777) (xy 258.115823 -39.814209)
			(xy 258.111498 -39.806372) (xy 258.111498 -39.806118) (xy 257.589528 -38.93566) (xy 257.584715 -38.928377)
			(xy 257.571224 -38.91732) (xy 257.554814 -38.911401) (xy 257.546094 -38.911022) (xy 257.544316 -38.911022)
			(xy 257.503422 -38.911784) (xy 257.4965 -38.912152) (xy 257.483232 -38.91614) (xy 257.47726 -38.919658)
			(xy 257.471418 -38.923214) (xy 257.46202 -38.933374) (xy 257.458972 -38.939724) (xy 257.445462 -38.965571)
			(xy 257.412389 -39.013608) (xy 257.37301 -39.056627) (xy 257.328077 -39.093808) (xy 257.278448 -39.124439)
			(xy 257.22507 -39.147938) (xy 257.168962 -39.163854) (xy 257.111197 -39.171885) (xy 257.082036 -39.172388)
			(xy 257.053171 -39.171911) (xy 256.995982 -39.164033) (xy 256.940401 -39.148433) (xy 256.887464 -39.125401)
			(xy 256.838162 -39.095368) (xy 256.793414 -39.058895) (xy 256.754056 -39.016662) (xy 256.720822 -38.969459)
			(xy 256.707132 -38.944042) (xy 256.705608 -38.940994) (xy 256.698949 -38.931092) (xy 256.678802 -38.918366)
			(xy 256.667 -38.91661) (xy 256.65811 -38.916102) (xy 256.629662 -38.914324) (xy 256.618822 -38.914113)
			(xy 256.598552 -38.921746) (xy 256.590546 -38.929056) (xy 256.586736 -38.932866) (xy 256.584958 -38.935152)
			(xy 256.584196 -38.936168) (xy 256.566198 -38.958591) (xy 256.524599 -38.998283) (xy 256.477515 -39.031282)
			(xy 256.426012 -39.056842) (xy 256.371257 -39.074384) (xy 256.314489 -39.083511) (xy 256.285746 -39.08425)
			(xy 256.281936 -39.08425) (xy 256.254678 -39.08379) (xy 256.200718 -39.076036) (xy 256.14841 -39.060681)
			(xy 256.098819 -39.038038) (xy 256.052957 -39.008568) (xy 256.011755 -38.97287) (xy 255.976054 -38.931672)
			(xy 255.946579 -38.885812) (xy 255.923931 -38.836224) (xy 255.908572 -38.783918) (xy 255.900813 -38.729958)
			(xy 255.900813 -38.675442) (xy 255.908572 -38.621482) (xy 255.923931 -38.569176) (xy 255.946579 -38.519588)
			(xy 255.976054 -38.473728) (xy 256.011755 -38.43253) (xy 256.052957 -38.396832) (xy 256.098819 -38.367362)
			(xy 256.14841 -38.344719) (xy 256.200718 -38.329364) (xy 256.254678 -38.32161) (xy 256.281936 -38.321234)
			(xy 256.309422 -38.321707) (xy 256.363828 -38.329579) (xy 256.416544 -38.345168) (xy 256.46648 -38.368154)
			(xy 256.512605 -38.398061) (xy 256.553967 -38.434271) (xy 256.58971 -38.476037) (xy 256.60477 -38.499034)
			(xy 256.60477 -38.499288) (xy 256.60731 -38.503352) (xy 256.608072 -38.504368) (xy 256.61239 -38.508432)
			(xy 256.620772 -38.515036) (xy 256.640076 -38.526974) (xy 256.643412 -38.528968) (xy 256.650555 -38.53203)
			(xy 256.6543 -38.53307) (xy 256.663698 -38.534594) (xy 256.663952 -38.534594) (xy 256.688336 -38.536118)
			(xy 256.694895 -38.53631) (xy 256.707758 -38.533742) (xy 256.713736 -38.531038) (xy 256.719578 -38.528244)
			(xy 256.729484 -38.519608) (xy 256.733294 -38.513766) (xy 256.750195 -38.489793) (xy 256.789567 -38.446317)
			(xy 256.834583 -38.408717) (xy 256.884376 -38.377717) (xy 256.937984 -38.353917) (xy 256.994373 -38.337775)
			(xy 257.052455 -38.329603) (xy 257.081782 -38.329108) (xy 257.08229 -38.329108) (xy 257.094736 -38.329362)
			(xy 257.104896 -38.328346) (xy 257.109722 -38.327076) (xy 257.118165 -38.324069) (xy 257.132359 -38.313144)
			(xy 257.137408 -38.30574) (xy 257.137662 -38.305232) (xy 257.138424 -38.303708) (xy 257.138932 -38.302946)
			(xy 257.145536 -38.291262) (xy 257.145536 -38.290754) (xy 257.15341 -38.27653) (xy 257.157474 -38.265862)
			(xy 257.158998 -38.253416) (xy 257.158998 -38.231318) (xy 257.158768 -38.224945) (xy 257.155557 -38.212609)
			(xy 257.152648 -38.206934) (xy 256.898648 -37.783262) (xy 256.6289 -37.333428) (xy 256.626614 -37.329872)
			(xy 256.538476 -37.219636) (xy 256.510336 -37.183653) (xy 256.460025 -37.107403) (xy 256.416909 -37.026865)
			(xy 256.381351 -36.942717) (xy 256.367026 -36.899342) (xy 256.365248 -36.893754) (xy 256.325878 -36.827968)
			(xy 256.286508 -36.76269) (xy 256.278888 -36.756594) (xy 256.253811 -36.736639) (xy 256.210078 -36.689799)
			(xy 256.174799 -36.636302) (xy 256.161286 -36.607242) (xy 256.157476 -36.598352) (xy 255.736598 -36.177474)
			(xy 255.726438 -36.1696) (xy 255.721104 -36.166552) (xy 255.715008 -36.164774) (xy 255.679194 -36.153344)
			(xy 255.670812 -36.15055) (xy 255.66243 -36.15055) (xy 255.657874 -36.150748) (xy 255.648933 -36.15254)
			(xy 255.64465 -36.154106) (xy 255.624584 -36.16198) (xy 255.61798 -36.167568) (xy 255.597179 -36.18461)
			(xy 255.551695 -36.213297) (xy 255.502635 -36.235319) (xy 255.450972 -36.250238) (xy 255.397726 -36.257761)
			(xy 255.370838 -36.258246) (xy 255.344022 -36.257787) (xy 255.290918 -36.250272) (xy 255.23939 -36.235398)
			(xy 255.19045 -36.213457) (xy 255.145063 -36.184883) (xy 255.104122 -36.150237) (xy 255.068434 -36.110202)
			(xy 255.038701 -36.065566) (xy 255.015508 -36.017208) (xy 254.999311 -35.966079) (xy 254.990431 -35.913187)
			(xy 254.98933 -35.88639) (xy 254.98933 -35.875976) (xy 254.989827 -35.847555) (xy 254.998213 -35.791335)
			(xy 255.014854 -35.736984) (xy 255.026668 -35.71113) (xy 255.029462 -35.705542) (xy 255.031748 -35.695128)
			(xy 255.031748 -35.672522) (xy 255.031252 -35.66308) (xy 255.024335 -35.645501) (xy 255.018286 -35.638232)
			(xy 254.982726 -35.602672) (xy 254.952702 -35.572019) (xy 254.89749 -35.506331) (xy 254.848179 -35.436105)
			(xy 254.826262 -35.399218) (xy 254.821436 -35.390582) (xy 254.798068 -35.372802) (xy 254.793982 -35.369808)
			(xy 254.784894 -35.365339) (xy 254.780034 -35.363912) (xy 254.748792 -35.355784) (xy 254.748284 -35.355784)
			(xy 254.728218 -35.350958) (xy 254.717804 -35.349688) (xy 254.690118 -35.357816) (xy 254.684022 -35.361626)
			(xy 254.643911 -35.386576) (xy 254.559834 -35.429653) (xy 254.472062 -35.46459) (xy 254.38138 -35.491073)
			(xy 254.2886 -35.508864) (xy 254.194555 -35.517806) (xy 254.14732 -35.518344) (xy 254.134366 -35.518344)
			(xy 254.07493 -35.515804) (xy 254.031841 -35.512196) (xy 253.946464 -35.498457) (xy 253.862598 -35.477377)
			(xy 253.780872 -35.449113) (xy 253.701902 -35.413877) (xy 253.626279 -35.371935) (xy 253.554572 -35.323602)
			(xy 253.487321 -35.269241) (xy 253.42503 -35.20926) (xy 253.368167 -35.14411) (xy 253.31716 -35.07428)
			(xy 253.294388 -35.037522) (xy 253.291848 -35.033712) (xy 253.281434 -35.021774) (xy 253.27991 -35.020504)
			(xy 253.257288 -35.002317) (xy 253.217289 -34.960258) (xy 253.184121 -34.912627) (xy 253.15855 -34.860521)
			(xy 253.141164 -34.805144) (xy 253.132366 -34.747773) (xy 253.131828 -34.718752) (xy 253.131828 -34.718498)
			(xy 253.132292 -34.689997) (xy 253.14071 -34.633623) (xy 253.148592 -34.60623) (xy 253.150116 -34.599118)
			(xy 253.151894 -34.588196) (xy 253.151894 -34.58464) (xy 253.15164 -34.581846) (xy 253.151132 -34.567622)
			(xy 253.151132 -34.566606) (xy 253.150116 -34.520886) (xy 253.150551 -34.478299) (xy 253.157792 -34.393435)
			(xy 253.172244 -34.309497) (xy 253.193804 -34.227098) (xy 253.222314 -34.146839) (xy 253.239524 -34.107882)
			(xy 253.242705 -34.098749) (xy 253.2427 -34.079425) (xy 253.239524 -34.07029) (xy 253.222316 -34.031333)
			(xy 253.193824 -33.951069) (xy 253.172274 -33.86867) (xy 253.157823 -33.784734) (xy 253.150576 -33.699872)
			(xy 253.150116 -33.657286) (xy 253.151894 -33.595818) (xy 253.152656 -33.583626) (xy 253.150624 -33.578038)
			(xy 253.145798 -33.56864) (xy 253.13767 -33.55721) (xy 253.107698 -33.525206) (xy 253.103988 -33.52156)
			(xy 253.095416 -33.515671) (xy 253.09068 -33.513522) (xy 253.080774 -33.509204) (xy 253.078742 -33.509204)
			(xy 253.070106 -33.509458) (xy 253.053088 -33.509712) (xy 252.557534 -33.509712) (xy 252.514278 -33.509249)
			(xy 252.428091 -33.501752) (xy 252.342879 -33.486812) (xy 252.259283 -33.464541) (xy 252.218444 -33.450276)
			(xy 252.214143 -33.448831) (xy 252.205201 -33.447303) (xy 252.200664 -33.447228) (xy 252.167644 -33.459928)
			(xy 252.160786 -33.46577) (xy 252.126791 -33.494747) (xy 252.054475 -33.547194) (xy 251.977759 -33.592965)
			(xy 251.897257 -33.631692) (xy 251.813615 -33.663065) (xy 251.727502 -33.686833) (xy 251.639609 -33.702806)
			(xy 251.55064 -33.710854) (xy 251.505974 -33.711388) (xy 251.505974 -33.711642) (xy 251.505212 -33.711642)
			(xy 251.458732 -33.711108) (xy 251.366174 -33.702456) (xy 251.274824 -33.685225) (xy 251.185474 -33.659567)
			(xy 251.098901 -33.625703) (xy 251.015856 -33.583927) (xy 250.93706 -33.534602) (xy 250.863198 -33.478157)
			(xy 250.79491 -33.415082) (xy 250.73279 -33.345924) (xy 250.677377 -33.271283) (xy 250.652788 -33.231836)
			(xy 250.650248 -33.227772) (xy 250.637802 -33.214056) (xy 250.6345 -33.211516) (xy 250.612297 -33.193284)
			(xy 250.573091 -33.151292) (xy 250.540608 -33.103907) (xy 250.51558 -33.052195) (xy 250.49857 -32.997322)
			(xy 250.489961 -32.940521) (xy 250.489466 -32.911796) (xy 250.49099 -32.879284) (xy 250.49226 -32.867092)
			(xy 250.494467 -32.849945) (xy 250.501594 -32.816111) (xy 250.506484 -32.799528) (xy 250.508008 -32.792416)
			(xy 250.509786 -32.781494) (xy 250.509786 -32.777938) (xy 250.509532 -32.775144) (xy 250.509024 -32.76092)
			(xy 250.509024 -32.759904) (xy 250.508008 -32.714184) (xy 250.508443 -32.671598) (xy 250.515685 -32.586733)
			(xy 250.530139 -32.502796) (xy 250.5517 -32.420398) (xy 250.580212 -32.34014) (xy 250.597416 -32.30118)
			(xy 250.600596 -32.292047) (xy 250.600591 -32.272724) (xy 250.597416 -32.263588) (xy 250.580208 -32.224631)
			(xy 250.551716 -32.144367) (xy 250.530167 -32.061968) (xy 250.515716 -31.978032) (xy 250.508469 -31.89317)
			(xy 250.508008 -31.850584) (xy 250.509024 -31.804864) (xy 250.509024 -31.803848) (xy 250.509532 -31.789624)
			(xy 250.509786 -31.78683) (xy 250.509786 -31.783274) (xy 250.508008 -31.772352) (xy 250.506484 -31.76524)
			(xy 250.497848 -31.731712) (xy 250.49226 -31.697676) (xy 250.49099 -31.685484) (xy 250.489466 -31.652972)
			(xy 250.490012 -31.62392) (xy 250.498822 -31.566486) (xy 250.516234 -31.511052) (xy 250.541847 -31.458896)
			(xy 250.575067 -31.411225) (xy 250.615129 -31.369138) (xy 250.637802 -31.350966) (xy 250.641467 -31.348008)
			(xy 250.647733 -31.340978) (xy 250.650248 -31.336996) (xy 250.651264 -31.335218) (xy 250.652788 -31.332932)
			(xy 250.677364 -31.293481) (xy 250.732787 -31.21886) (xy 250.794916 -31.149722) (xy 250.86321 -31.086667)
			(xy 250.937078 -31.030243) (xy 251.015876 -30.98094) (xy 251.098922 -30.939185) (xy 251.185494 -30.905342)
			(xy 251.274841 -30.879704) (xy 251.366186 -30.862495) (xy 251.458736 -30.853862) (xy 251.505212 -30.85338)
			(xy 251.505466 -30.85338) (xy 251.547916 -30.85382) (xy 251.632509 -30.861037) (xy 251.716182 -30.875421)
			(xy 251.798328 -30.896869) (xy 251.878354 -30.925224) (xy 251.955678 -30.960282) (xy 252.02974 -31.001788)
			(xy 252.100005 -31.049442) (xy 252.165963 -31.102898) (xy 252.196854 -31.132018) (xy 252.203597 -31.137279)
			(xy 252.219563 -31.143383) (xy 252.228096 -31.143956) (xy 253.07671 -31.143956) (xy 253.08306 -31.143448)
			(xy 253.091553 -31.142069) (xy 253.106963 -31.134439) (xy 253.118971 -31.122129) (xy 253.122938 -31.114492)
			(xy 253.13259 -31.091124) (xy 253.133352 -31.083504) (xy 253.133606 -31.081218) (xy 253.133606 -31.080456)
			(xy 253.135889 -31.060694) (xy 253.144034 -31.021753) (xy 253.149862 -31.002732) (xy 253.151115 -30.998273)
			(xy 253.152134 -30.989069) (xy 253.151894 -30.984444) (xy 253.151894 -30.983936) (xy 253.151008 -30.96814)
			(xy 253.150118 -30.936511) (xy 253.150116 -30.92069) (xy 253.150551 -30.878103) (xy 253.157791 -30.793239)
			(xy 253.172244 -30.709301) (xy 253.193803 -30.626902) (xy 253.222312 -30.546642) (xy 253.239524 -30.507686)
			(xy 253.242705 -30.498553) (xy 253.242702 -30.479229) (xy 253.239524 -30.470094) (xy 253.222316 -30.431137)
			(xy 253.193823 -30.350874) (xy 253.172273 -30.268474) (xy 253.157822 -30.184538) (xy 253.150574 -30.099676)
			(xy 253.150116 -30.05709) (xy 253.151894 -29.996384) (xy 253.152148 -29.99232) (xy 253.152656 -29.983684)
			(xy 253.151132 -29.97962) (xy 253.14402 -29.966666) (xy 253.137924 -29.95803) (xy 253.128526 -29.947108)
			(xy 253.11989 -29.942536) (xy 253.096014 -29.929836) (xy 253.086362 -29.928566) (xy 253.059622 -29.925387)
			(xy 253.006507 -29.916491) (xy 252.98019 -29.910786) (xy 252.974602 -29.909516) (xy 252.88494 -29.909516)
			(xy 252.843575 -29.909096) (xy 252.761128 -29.902239) (xy 252.679535 -29.888568) (xy 252.599356 -29.868178)
			(xy 252.521144 -29.841208) (xy 252.483112 -29.824934) (xy 252.47346 -29.820616) (xy 252.229874 -29.820616)
			(xy 252.224996 -29.82071) (xy 252.215405 -29.822493) (xy 252.210824 -29.824172) (xy 252.202188 -29.827728)
			(xy 252.194822 -29.83484) (xy 252.163949 -29.863776) (xy 252.098084 -29.916903) (xy 252.027953 -29.964257)
			(xy 251.954061 -30.005497) (xy 251.876939 -30.040325) (xy 251.797143 -30.068492) (xy 251.715247 -30.089795)
			(xy 251.63184 -30.10408) (xy 251.547523 -30.111244) (xy 251.505212 -30.1117) (xy 251.458683 -30.11115)
			(xy 251.366033 -30.102456) (xy 251.274594 -30.085171) (xy 251.185163 -30.059444) (xy 251.098517 -30.0255)
			(xy 251.01541 -29.983633) (xy 250.936563 -29.934207) (xy 250.862662 -29.877653) (xy 250.794349 -29.814462)
			(xy 250.732219 -29.745182) (xy 250.676812 -29.670418) (xy 250.65228 -29.630878) (xy 250.64974 -29.627068)
			(xy 250.639326 -29.61513) (xy 250.637802 -29.61386) (xy 250.615183 -29.595672) (xy 250.57519 -29.553611)
			(xy 250.542028 -29.505979) (xy 250.516463 -29.453873) (xy 250.499084 -29.398497) (xy 250.490293 -29.341128)
			(xy 250.48972 -29.312108) (xy 250.48972 -29.311854) (xy 250.490187 -29.283354) (xy 250.498612 -29.226981)
			(xy 250.506484 -29.199586) (xy 250.508008 -29.192474) (xy 250.509786 -29.181552) (xy 250.509786 -29.177996)
			(xy 250.509532 -29.175202) (xy 250.509024 -29.160978) (xy 250.509024 -29.159962) (xy 250.508008 -29.114242)
			(xy 250.508441 -29.071655) (xy 250.515677 -28.986789) (xy 250.530127 -28.90285) (xy 250.551684 -28.82045)
			(xy 250.580192 -28.740189) (xy 250.597416 -28.701238) (xy 250.600608 -28.692105) (xy 250.600622 -28.672773)
			(xy 250.597416 -28.663646) (xy 250.580206 -28.62469) (xy 250.55171 -28.544426) (xy 250.530155 -28.462027)
			(xy 250.515699 -28.378091) (xy 250.508448 -28.293228) (xy 250.508008 -28.250642) (xy 250.509024 -28.204922)
			(xy 250.509024 -28.203906) (xy 250.509532 -28.189682) (xy 250.509786 -28.186888) (xy 250.509786 -28.183332)
			(xy 250.508008 -28.17241) (xy 250.506484 -28.165298) (xy 250.497848 -28.13177) (xy 250.49226 -28.097734)
			(xy 250.49099 -28.085542) (xy 250.489466 -28.05303) (xy 250.489982 -28.024323) (xy 250.498578 -27.967557)
			(xy 250.51558 -27.912719) (xy 250.540604 -27.861047) (xy 250.573087 -27.813706) (xy 250.612295 -27.771765)
			(xy 250.6345 -27.753564) (xy 250.640342 -27.747976) (xy 250.650248 -27.737054) (xy 250.652788 -27.732736)
			(xy 250.677375 -27.693296) (xy 250.732816 -27.618697) (xy 250.794957 -27.549578) (xy 250.863258 -27.48654)
			(xy 250.937126 -27.430128) (xy 251.015922 -27.380833) (xy 251.098962 -27.339081) (xy 251.185526 -27.305235)
			(xy 251.274863 -27.279588) (xy 251.366198 -27.262363) (xy 251.458739 -27.253709) (xy 251.505212 -27.253184)
			(xy 251.552225 -27.253741) (xy 251.645831 -27.262618) (xy 251.738186 -27.280265) (xy 251.828471 -27.306524)
			(xy 251.915884 -27.341162) (xy 251.99965 -27.383873) (xy 252.079025 -27.434276) (xy 252.153304 -27.491925)
			(xy 252.187964 -27.523694) (xy 252.193298 -27.528774) (xy 252.194568 -27.530044) (xy 252.194822 -27.530298)
			(xy 252.220222 -27.540458) (xy 252.224789 -27.542211) (xy 252.234382 -27.544126) (xy 252.239272 -27.544268)
			(xy 254.330454 -27.544268) (xy 254.373444 -27.544755) (xy 254.459101 -27.552223) (xy 254.543798 -27.56703)
			(xy 254.626907 -27.589067) (xy 254.667512 -27.603196) (xy 254.709422 -27.619452) (xy 256.052066 -28.173426)
			(xy 256.058322 -28.175783) (xy 256.071582 -28.177456) (xy 256.078228 -28.176728) (xy 256.091182 -28.17495)
			(xy 256.102104 -28.166568) (xy 256.12217 -28.151651) (xy 256.165462 -28.126634) (xy 256.21165 -28.107484)
			(xy 256.259943 -28.094529) (xy 256.309514 -28.087989) (xy 256.334514 -28.087574) (xy 256.361754 -28.08806)
			(xy 256.415678 -28.095811) (xy 256.467952 -28.111155) (xy 256.517512 -28.133778) (xy 256.525854 -28.139136)
			(xy 260.597902 -28.139136) (xy 260.601973 -28.083514) (xy 260.614099 -28.029077) (xy 260.634022 -27.976986)
			(xy 260.661318 -27.928351) (xy 260.695404 -27.884208) (xy 260.735553 -27.845499) (xy 260.780911 -27.813048)
			(xy 260.830511 -27.787547) (xy 260.883295 -27.76954) (xy 260.938138 -27.75941) (xy 260.993872 -27.757373)
			(xy 261.049309 -27.763473) (xy 261.103266 -27.777579) (xy 261.154595 -27.799391) (xy 261.202201 -27.828445)
			(xy 261.245069 -27.86412) (xy 261.282286 -27.905657) (xy 261.313059 -27.95217) (xy 261.336731 -28.002667)
			(xy 261.352799 -28.056074) (xy 261.360919 -28.11125) (xy 261.361428 -28.139136) (xy 261.867902 -28.139136)
			(xy 261.871973 -28.083514) (xy 261.884099 -28.029077) (xy 261.904022 -27.976986) (xy 261.931318 -27.928351)
			(xy 261.965404 -27.884208) (xy 262.005553 -27.845499) (xy 262.050911 -27.813048) (xy 262.100511 -27.787547)
			(xy 262.153295 -27.76954) (xy 262.208138 -27.75941) (xy 262.263872 -27.757373) (xy 262.319309 -27.763473)
			(xy 262.373266 -27.777579) (xy 262.424595 -27.799391) (xy 262.472201 -27.828445) (xy 262.515069 -27.86412)
			(xy 262.552286 -27.905657) (xy 262.583059 -27.95217) (xy 262.606731 -28.002667) (xy 262.622799 -28.056074)
			(xy 262.630919 -28.11125) (xy 262.631428 -28.139136) (xy 262.630919 -28.167022) (xy 262.622799 -28.222198)
			(xy 262.606731 -28.275605) (xy 262.583059 -28.326102) (xy 262.552286 -28.372615) (xy 262.515069 -28.414152)
			(xy 262.472201 -28.449827) (xy 262.424595 -28.478881) (xy 262.373266 -28.500693) (xy 262.319309 -28.514799)
			(xy 262.263872 -28.520899) (xy 262.208138 -28.518862) (xy 262.153295 -28.508732) (xy 262.100511 -28.490725)
			(xy 262.050911 -28.465224) (xy 262.005553 -28.432773) (xy 261.965404 -28.394064) (xy 261.931318 -28.349921)
			(xy 261.904022 -28.301286) (xy 261.884099 -28.249195) (xy 261.871973 -28.194758) (xy 261.867902 -28.139136)
			(xy 261.361428 -28.139136) (xy 261.360919 -28.167022) (xy 261.352799 -28.222198) (xy 261.336731 -28.275605)
			(xy 261.313059 -28.326102) (xy 261.282286 -28.372615) (xy 261.245069 -28.414152) (xy 261.202201 -28.449827)
			(xy 261.154595 -28.478881) (xy 261.103266 -28.500693) (xy 261.049309 -28.514799) (xy 260.993872 -28.520899)
			(xy 260.938138 -28.518862) (xy 260.883295 -28.508732) (xy 260.830511 -28.490725) (xy 260.780911 -28.465224)
			(xy 260.735553 -28.432773) (xy 260.695404 -28.394064) (xy 260.661318 -28.349921) (xy 260.634022 -28.301286)
			(xy 260.614099 -28.249195) (xy 260.601973 -28.194758) (xy 260.597902 -28.139136) (xy 256.525854 -28.139136)
			(xy 256.56335 -28.163221) (xy 256.604533 -28.198884) (xy 256.640225 -28.240044) (xy 256.669698 -28.285861)
			(xy 256.692355 -28.335406) (xy 256.707734 -28.387669) (xy 256.715522 -28.441589) (xy 256.716022 -28.468828)
			(xy 256.716022 -28.469336) (xy 256.715514 -28.486608) (xy 256.746383 -28.511194) (xy 256.804559 -28.564527)
			(xy 256.85833 -28.6223) (xy 256.883154 -28.652978) (xy 257.255204 -29.12237) (xy 266.80668 -29.12237)
			(xy 266.80668 -28.25877) (xy 266.80717 -28.228786) (xy 266.814998 -28.16933) (xy 266.830519 -28.111405)
			(xy 266.853468 -28.056001) (xy 266.883452 -28.004067) (xy 266.919958 -27.956491) (xy 266.962363 -27.914086)
			(xy 267.009939 -27.87758) (xy 267.061873 -27.847596) (xy 267.117277 -27.824647) (xy 267.175202 -27.809126)
			(xy 267.234658 -27.801298) (xy 267.294626 -27.801298) (xy 267.354082 -27.809126) (xy 267.412007 -27.824647)
			(xy 267.467411 -27.847596) (xy 267.519345 -27.87758) (xy 267.566921 -27.914086) (xy 267.609326 -27.956491)
			(xy 267.645832 -28.004067) (xy 267.675816 -28.056001) (xy 267.698765 -28.111405) (xy 267.714286 -28.16933)
			(xy 267.722114 -28.228786) (xy 267.722604 -28.25877) (xy 267.722604 -29.12237) (xy 267.722114 -29.152354)
			(xy 267.714286 -29.21181) (xy 267.698765 -29.269735) (xy 267.675816 -29.325139) (xy 267.645832 -29.377073)
			(xy 267.609326 -29.424649) (xy 267.566921 -29.467054) (xy 267.519345 -29.50356) (xy 267.467411 -29.533544)
			(xy 267.412007 -29.556493) (xy 267.354082 -29.572014) (xy 267.294626 -29.579842) (xy 267.234658 -29.579842)
			(xy 267.175202 -29.572014) (xy 267.117277 -29.556493) (xy 267.061873 -29.533544) (xy 267.009939 -29.50356)
			(xy 266.962363 -29.467054) (xy 266.919958 -29.424649) (xy 266.883452 -29.377073) (xy 266.853468 -29.325139)
			(xy 266.830519 -29.269735) (xy 266.814998 -29.21181) (xy 266.80717 -29.152354) (xy 266.80668 -29.12237)
			(xy 257.255204 -29.12237) (xy 257.401568 -29.307028) (xy 257.4671 -29.389578) (xy 257.474541 -29.396986)
			(xy 257.4937 -29.405515) (xy 257.504184 -29.406088) (xy 257.511042 -29.40558) (xy 257.512312 -29.405326)
			(xy 257.523385 -29.404123) (xy 257.545624 -29.402852) (xy 257.556762 -29.402786) (xy 257.557524 -29.402786)
			(xy 257.584774 -29.403273) (xy 257.63872 -29.411033) (xy 257.691012 -29.42639) (xy 257.740587 -29.449032)
			(xy 257.786434 -29.478499) (xy 257.827622 -29.514191) (xy 257.863312 -29.55538) (xy 257.892776 -29.601229)
			(xy 257.915416 -29.650805) (xy 257.930771 -29.703098) (xy 257.938528 -29.757044) (xy 257.939032 -29.784294)
			(xy 257.939032 -29.784802) (xy 257.938302 -29.817938) (xy 257.926809 -29.883206) (xy 257.916172 -29.914596)
			(xy 257.915664 -29.916374) (xy 257.912616 -29.933646) (xy 257.912904 -29.942228) (xy 257.918484 -29.958455)
			(xy 257.923538 -29.965396) (xy 258.249731 -30.376876) (xy 259.08889 -30.376876) (xy 259.089429 -30.347959)
			(xy 259.098149 -30.290788) (xy 259.1154 -30.235588) (xy 259.140788 -30.183625) (xy 259.17373 -30.136091)
			(xy 259.213471 -30.094075) (xy 259.235956 -30.075886) (xy 259.244769 -30.068285) (xy 259.254947 -30.047379)
			(xy 259.255514 -30.035754) (xy 259.255514 -29.955998) (xy 259.254957 -29.944369) (xy 259.24478 -29.923459)
			(xy 259.235956 -29.915866) (xy 259.213447 -29.897705) (xy 259.173715 -29.855678) (xy 259.140781 -29.808136)
			(xy 259.115397 -29.756169) (xy 259.098146 -29.700967) (xy 259.089422 -29.643794) (xy 259.08889 -29.614876)
			(xy 259.089376 -29.587625) (xy 259.097132 -29.533677) (xy 259.112487 -29.481382) (xy 259.135129 -29.431805)
			(xy 259.164595 -29.385955) (xy 259.200286 -29.344764) (xy 259.241477 -29.309073) (xy 259.287327 -29.279607)
			(xy 259.336904 -29.256965) (xy 259.389199 -29.24161) (xy 259.443147 -29.233854) (xy 259.497649 -29.233854)
			(xy 259.551597 -29.24161) (xy 259.603892 -29.256965) (xy 259.653469 -29.279607) (xy 259.699319 -29.309073)
			(xy 259.74051 -29.344764) (xy 259.776201 -29.385955) (xy 259.805667 -29.431805) (xy 259.828309 -29.481382)
			(xy 259.843664 -29.533677) (xy 259.85142 -29.587625) (xy 259.851906 -29.614876) (xy 259.851406 -29.643794)
			(xy 259.842678 -29.700968) (xy 259.825419 -29.756168) (xy 259.800024 -29.808131) (xy 259.767076 -29.855664)
			(xy 259.727329 -29.897678) (xy 259.70484 -29.915866) (xy 259.696048 -29.923487) (xy 259.685858 -29.944378)
			(xy 259.685282 -29.955998) (xy 259.685282 -30.035754) (xy 259.685811 -30.047387) (xy 259.696008 -30.068296)
			(xy 259.70484 -30.075886) (xy 259.727325 -30.094075) (xy 259.767058 -30.136096) (xy 259.799996 -30.183632)
			(xy 259.825384 -30.235593) (xy 259.84264 -30.290791) (xy 259.85137 -30.34796) (xy 259.851906 -30.376876)
			(xy 262.129016 -30.376876) (xy 262.129583 -30.347961) (xy 262.138301 -30.290792) (xy 262.155549 -30.235593)
			(xy 262.180931 -30.183631) (xy 262.213867 -30.136096) (xy 262.2536 -30.094077) (xy 262.276082 -30.075886)
			(xy 262.284899 -30.068289) (xy 262.295074 -30.04738) (xy 262.29564 -30.035754) (xy 262.29564 -29.955998)
			(xy 262.295109 -29.944365) (xy 262.284917 -29.923454) (xy 262.276082 -29.915866) (xy 262.253578 -29.897699)
			(xy 262.213845 -29.855673) (xy 262.180909 -29.808134) (xy 262.155524 -29.756168) (xy 262.138272 -29.700966)
			(xy 262.129548 -29.643793) (xy 262.129016 -29.614876) (xy 262.129502 -29.587625) (xy 262.137258 -29.533677)
			(xy 262.152613 -29.481382) (xy 262.175255 -29.431805) (xy 262.204721 -29.385955) (xy 262.240412 -29.344764)
			(xy 262.281603 -29.309073) (xy 262.327453 -29.279607) (xy 262.37703 -29.256965) (xy 262.429325 -29.24161)
			(xy 262.483273 -29.233854) (xy 262.537775 -29.233854) (xy 262.591723 -29.24161) (xy 262.644018 -29.256965)
			(xy 262.693595 -29.279607) (xy 262.739445 -29.309073) (xy 262.780636 -29.344764) (xy 262.816327 -29.385955)
			(xy 262.845793 -29.431805) (xy 262.868435 -29.481382) (xy 262.88379 -29.533677) (xy 262.891546 -29.587625)
			(xy 262.892032 -29.614876) (xy 262.891522 -29.643794) (xy 262.882795 -29.700966) (xy 262.865537 -29.756166)
			(xy 262.840144 -29.808129) (xy 262.807198 -29.855662) (xy 262.767453 -29.897677) (xy 262.744966 -29.915866)
			(xy 262.736179 -29.923492) (xy 262.725985 -29.944379) (xy 262.725408 -29.955998) (xy 262.725408 -30.035754)
			(xy 262.725927 -30.047388) (xy 262.73613 -30.068298) (xy 262.744966 -30.075886) (xy 262.767436 -30.094094)
			(xy 262.807173 -30.136109) (xy 262.840115 -30.18364) (xy 262.865506 -30.235598) (xy 262.882765 -30.290793)
			(xy 262.891496 -30.347961) (xy 262.892032 -30.376876) (xy 262.891546 -30.404127) (xy 262.88379 -30.458075)
			(xy 262.868435 -30.51037) (xy 262.845793 -30.559947) (xy 262.816327 -30.605797) (xy 262.780636 -30.646988)
			(xy 262.739445 -30.682679) (xy 262.693595 -30.712145) (xy 262.644018 -30.734787) (xy 262.591723 -30.750142)
			(xy 262.537775 -30.757898) (xy 262.483273 -30.757898) (xy 262.429325 -30.750142) (xy 262.37703 -30.734787)
			(xy 262.327453 -30.712145) (xy 262.281603 -30.682679) (xy 262.240412 -30.646988) (xy 262.204721 -30.605797)
			(xy 262.175255 -30.559947) (xy 262.152613 -30.51037) (xy 262.137258 -30.458075) (xy 262.129502 -30.404127)
			(xy 262.129016 -30.376876) (xy 259.851906 -30.376876) (xy 259.85142 -30.404127) (xy 259.843664 -30.458075)
			(xy 259.828309 -30.51037) (xy 259.805667 -30.559947) (xy 259.776201 -30.605797) (xy 259.74051 -30.646988)
			(xy 259.699319 -30.682679) (xy 259.653469 -30.712145) (xy 259.603892 -30.734787) (xy 259.551597 -30.750142)
			(xy 259.497649 -30.757898) (xy 259.443147 -30.757898) (xy 259.389199 -30.750142) (xy 259.336904 -30.734787)
			(xy 259.287327 -30.712145) (xy 259.241477 -30.682679) (xy 259.200286 -30.646988) (xy 259.164595 -30.605797)
			(xy 259.135129 -30.559947) (xy 259.112487 -30.51037) (xy 259.097132 -30.458075) (xy 259.089376 -30.404127)
			(xy 259.08889 -30.376876) (xy 258.249731 -30.376876) (xy 258.388866 -30.55239) (xy 258.682347 -30.922468)
			(xy 264.95248 -30.922468) (xy 264.95248 -30.058868) (xy 264.95297 -30.028884) (xy 264.960798 -29.969428)
			(xy 264.976319 -29.911503) (xy 264.999268 -29.856099) (xy 265.029252 -29.804165) (xy 265.065758 -29.756589)
			(xy 265.108163 -29.714184) (xy 265.155739 -29.677678) (xy 265.207673 -29.647694) (xy 265.263077 -29.624745)
			(xy 265.321002 -29.609224) (xy 265.380458 -29.601396) (xy 265.440426 -29.601396) (xy 265.499882 -29.609224)
			(xy 265.557807 -29.624745) (xy 265.613211 -29.647694) (xy 265.665145 -29.677678) (xy 265.712721 -29.714184)
			(xy 265.755126 -29.756589) (xy 265.791632 -29.804165) (xy 265.821616 -29.856099) (xy 265.844565 -29.911503)
			(xy 265.860086 -29.969428) (xy 265.867914 -30.028884) (xy 265.868404 -30.058868) (xy 265.868404 -30.922468)
			(xy 265.867914 -30.952452) (xy 265.860086 -31.011908) (xy 265.844565 -31.069833) (xy 265.821616 -31.125237)
			(xy 265.791632 -31.177171) (xy 265.755126 -31.224747) (xy 265.712721 -31.267152) (xy 265.665145 -31.303658)
			(xy 265.613211 -31.333642) (xy 265.557807 -31.356591) (xy 265.499882 -31.372112) (xy 265.440426 -31.37994)
			(xy 265.380458 -31.37994) (xy 265.321002 -31.372112) (xy 265.263077 -31.356591) (xy 265.207673 -31.333642)
			(xy 265.155739 -31.303658) (xy 265.108163 -31.267152) (xy 265.065758 -31.224747) (xy 265.029252 -31.177171)
			(xy 264.999268 -31.125237) (xy 264.976319 -31.069833) (xy 264.960798 -31.011908) (xy 264.95297 -30.952452)
			(xy 264.95248 -30.922468) (xy 258.682347 -30.922468) (xy 258.741164 -30.996636) (xy 258.743958 -30.999938)
			(xy 258.77901 -31.03499) (xy 259.110988 -31.367222) (xy 259.119291 -31.374483) (xy 259.140102 -31.381715)
			(xy 259.15112 -31.381192) (xy 259.181854 -31.378398) (xy 259.182362 -31.378398) (xy 259.19176 -31.377382)
			(xy 259.196501 -31.377025) (xy 259.205966 -31.377918) (xy 259.210556 -31.37916) (xy 259.212842 -31.379668)
			(xy 259.23367 -31.384748) (xy 259.2451 -31.382462) (xy 259.265166 -31.353252) (xy 259.280469 -31.331564)
			(xy 259.316117 -31.292236) (xy 259.356874 -31.258233) (xy 259.401953 -31.23021) (xy 259.450483 -31.208709)
			(xy 259.501525 -31.194147) (xy 259.554094 -31.186804) (xy 259.580634 -31.186374) (xy 259.607884 -31.186862)
			(xy 259.661829 -31.194622) (xy 259.714121 -31.20998) (xy 259.763695 -31.232623) (xy 259.809542 -31.26209)
			(xy 259.85073 -31.297781) (xy 259.88642 -31.33897) (xy 259.915885 -31.384819) (xy 259.938525 -31.434394)
			(xy 259.953881 -31.486687) (xy 259.961639 -31.540632) (xy 259.962142 -31.567882) (xy 259.961594 -31.596997)
			(xy 259.952749 -31.654551) (xy 259.935261 -31.710093) (xy 259.930744 -31.719266) (xy 260.48538 -31.719266)
			(xy 260.489451 -31.663644) (xy 260.501577 -31.609207) (xy 260.5215 -31.557116) (xy 260.548796 -31.508481)
			(xy 260.582882 -31.464338) (xy 260.623031 -31.425629) (xy 260.668389 -31.393178) (xy 260.717989 -31.367677)
			(xy 260.770773 -31.34967) (xy 260.825616 -31.33954) (xy 260.88135 -31.337503) (xy 260.936787 -31.343603)
			(xy 260.990744 -31.357709) (xy 261.042073 -31.379521) (xy 261.089679 -31.408575) (xy 261.132547 -31.44425)
			(xy 261.169764 -31.485787) (xy 261.200537 -31.5323) (xy 261.224209 -31.582797) (xy 261.240277 -31.636204)
			(xy 261.244427 -31.664402) (xy 261.760968 -31.664402) (xy 261.765039 -31.60878) (xy 261.777165 -31.554343)
			(xy 261.797088 -31.502252) (xy 261.824384 -31.453617) (xy 261.85847 -31.409474) (xy 261.898619 -31.370765)
			(xy 261.943977 -31.338314) (xy 261.993577 -31.312813) (xy 262.046361 -31.294806) (xy 262.101204 -31.284676)
			(xy 262.156938 -31.282639) (xy 262.212375 -31.288739) (xy 262.266332 -31.302845) (xy 262.317661 -31.324657)
			(xy 262.365267 -31.353711) (xy 262.408135 -31.389386) (xy 262.445352 -31.430923) (xy 262.476125 -31.477436)
			(xy 262.499797 -31.527933) (xy 262.515865 -31.58134) (xy 262.523985 -31.636516) (xy 262.524494 -31.664402)
			(xy 262.523985 -31.692288) (xy 262.515865 -31.747464) (xy 262.506925 -31.777178) (xy 263.026142 -31.777178)
			(xy 263.030213 -31.721556) (xy 263.042339 -31.667119) (xy 263.062262 -31.615028) (xy 263.089558 -31.566393)
			(xy 263.123644 -31.52225) (xy 263.163793 -31.483541) (xy 263.209151 -31.45109) (xy 263.258751 -31.425589)
			(xy 263.311535 -31.407582) (xy 263.366378 -31.397452) (xy 263.422112 -31.395415) (xy 263.477549 -31.401515)
			(xy 263.531506 -31.415621) (xy 263.582835 -31.437433) (xy 263.630441 -31.466487) (xy 263.673309 -31.502162)
			(xy 263.710526 -31.543699) (xy 263.741299 -31.590212) (xy 263.764971 -31.640709) (xy 263.781039 -31.694116)
			(xy 263.789159 -31.749292) (xy 263.789668 -31.777178) (xy 263.789159 -31.805064) (xy 263.781039 -31.86024)
			(xy 263.764971 -31.913647) (xy 263.741299 -31.964144) (xy 263.710526 -32.010657) (xy 263.673309 -32.052194)
			(xy 263.630441 -32.087869) (xy 263.582835 -32.116923) (xy 263.531506 -32.138735) (xy 263.477549 -32.152841)
			(xy 263.422112 -32.158941) (xy 263.366378 -32.156904) (xy 263.311535 -32.146774) (xy 263.258751 -32.128767)
			(xy 263.209151 -32.103266) (xy 263.163793 -32.070815) (xy 263.123644 -32.032106) (xy 263.089558 -31.987963)
			(xy 263.062262 -31.939328) (xy 263.042339 -31.887237) (xy 263.030213 -31.8328) (xy 263.026142 -31.777178)
			(xy 262.506925 -31.777178) (xy 262.499797 -31.800871) (xy 262.476125 -31.851368) (xy 262.445352 -31.897881)
			(xy 262.408135 -31.939418) (xy 262.365267 -31.975093) (xy 262.317661 -32.004147) (xy 262.266332 -32.025959)
			(xy 262.212375 -32.040065) (xy 262.156938 -32.046165) (xy 262.101204 -32.044128) (xy 262.046361 -32.033998)
			(xy 261.993577 -32.015991) (xy 261.943977 -31.99049) (xy 261.898619 -31.958039) (xy 261.85847 -31.91933)
			(xy 261.824384 -31.875187) (xy 261.797088 -31.826552) (xy 261.777165 -31.774461) (xy 261.765039 -31.720024)
			(xy 261.760968 -31.664402) (xy 261.244427 -31.664402) (xy 261.248397 -31.69138) (xy 261.248906 -31.719266)
			(xy 261.248397 -31.747152) (xy 261.240277 -31.802328) (xy 261.224209 -31.855735) (xy 261.200537 -31.906232)
			(xy 261.169764 -31.952745) (xy 261.132547 -31.994282) (xy 261.089679 -32.029957) (xy 261.042073 -32.059011)
			(xy 260.990744 -32.080823) (xy 260.936787 -32.094929) (xy 260.88135 -32.101029) (xy 260.825616 -32.098992)
			(xy 260.770773 -32.088862) (xy 260.717989 -32.070855) (xy 260.668389 -32.045354) (xy 260.623031 -32.012903)
			(xy 260.582882 -31.974194) (xy 260.548796 -31.930051) (xy 260.5215 -31.881416) (xy 260.501577 -31.829325)
			(xy 260.489451 -31.774888) (xy 260.48538 -31.719266) (xy 259.930744 -31.719266) (xy 259.909537 -31.762332)
			(xy 259.876173 -31.810056) (xy 259.835946 -31.852156) (xy 259.789788 -31.887655) (xy 259.76453 -31.902146)
			(xy 259.755894 -31.906972) (xy 259.736336 -31.930848) (xy 259.733951 -31.934057) (xy 259.730123 -31.941076)
			(xy 259.728716 -31.944818) (xy 259.719318 -31.97733) (xy 259.719318 -31.977584) (xy 259.717286 -31.983172)
			(xy 259.709666 -32.001968) (xy 259.706125 -32.012999) (xy 259.708367 -32.036032) (xy 259.713984 -32.046164)
			(xy 259.9563 -32.440626) (xy 260.129465 -32.722312) (xy 266.80668 -32.722312) (xy 266.80668 -31.858712)
			(xy 266.80717 -31.828728) (xy 266.814998 -31.769272) (xy 266.830519 -31.711347) (xy 266.853468 -31.655943)
			(xy 266.883452 -31.604009) (xy 266.919958 -31.556433) (xy 266.962363 -31.514028) (xy 267.009939 -31.477522)
			(xy 267.061873 -31.447538) (xy 267.117277 -31.424589) (xy 267.175202 -31.409068) (xy 267.234658 -31.40124)
			(xy 267.294626 -31.40124) (xy 267.354082 -31.409068) (xy 267.412007 -31.424589) (xy 267.467411 -31.447538)
			(xy 267.519345 -31.477522) (xy 267.566921 -31.514028) (xy 267.609326 -31.556433) (xy 267.645832 -31.604009)
			(xy 267.675816 -31.655943) (xy 267.698765 -31.711347) (xy 267.714286 -31.769272) (xy 267.722114 -31.828728)
			(xy 267.722604 -31.858712) (xy 267.722604 -32.722312) (xy 267.722114 -32.752296) (xy 267.714286 -32.811752)
			(xy 267.698765 -32.869677) (xy 267.675816 -32.925081) (xy 267.645832 -32.977015) (xy 267.609326 -33.024591)
			(xy 267.566921 -33.066996) (xy 267.519345 -33.103502) (xy 267.467411 -33.133486) (xy 267.412007 -33.156435)
			(xy 267.354082 -33.171956) (xy 267.294626 -33.179784) (xy 267.234658 -33.179784) (xy 267.175202 -33.171956)
			(xy 267.117277 -33.156435) (xy 267.061873 -33.133486) (xy 267.009939 -33.103502) (xy 266.962363 -33.066996)
			(xy 266.919958 -33.024591) (xy 266.883452 -32.977015) (xy 266.853468 -32.925081) (xy 266.830519 -32.869677)
			(xy 266.814998 -32.811752) (xy 266.80717 -32.752296) (xy 266.80668 -32.722312) (xy 260.129465 -32.722312)
			(xy 260.199886 -32.836866) (xy 260.202934 -32.841438) (xy 260.208776 -32.849058) (xy 260.214364 -32.855916)
			(xy 260.219707 -32.862134) (xy 260.23344 -32.87107) (xy 260.241288 -32.873442) (xy 260.244082 -32.87395)
			(xy 260.272544 -32.880193) (xy 260.327284 -32.900153) (xy 260.378353 -32.928205) (xy 260.424563 -32.963695)
			(xy 260.464839 -33.005799) (xy 260.498246 -33.053537) (xy 260.524005 -33.105799) (xy 260.541519 -33.161371)
			(xy 260.550379 -33.218959) (xy 260.550914 -33.248092) (xy 260.55066 -33.260792) (xy 260.55066 -33.261046)
			(xy 260.550832 -33.269412) (xy 260.555883 -33.285353) (xy 260.560566 -33.292288) (xy 261.462266 -34.430208)
			(xy 261.535353 -34.52241) (xy 264.95248 -34.52241) (xy 264.95248 -33.65881) (xy 264.95297 -33.628826)
			(xy 264.960798 -33.56937) (xy 264.976319 -33.511445) (xy 264.999268 -33.456041) (xy 265.029252 -33.404107)
			(xy 265.065758 -33.356531) (xy 265.108163 -33.314126) (xy 265.155739 -33.27762) (xy 265.207673 -33.247636)
			(xy 265.263077 -33.224687) (xy 265.321002 -33.209166) (xy 265.380458 -33.201338) (xy 265.440426 -33.201338)
			(xy 265.499882 -33.209166) (xy 265.557807 -33.224687) (xy 265.613211 -33.247636) (xy 265.665145 -33.27762)
			(xy 265.712721 -33.314126) (xy 265.755126 -33.356531) (xy 265.791632 -33.404107) (xy 265.821616 -33.456041)
			(xy 265.844565 -33.511445) (xy 265.860086 -33.56937) (xy 265.867914 -33.628826) (xy 265.868404 -33.65881)
			(xy 265.868404 -34.52241) (xy 265.867914 -34.552394) (xy 265.860086 -34.61185) (xy 265.844565 -34.669775)
			(xy 265.821616 -34.725179) (xy 265.791632 -34.777113) (xy 265.755126 -34.824689) (xy 265.712721 -34.867094)
			(xy 265.665145 -34.9036) (xy 265.613211 -34.933584) (xy 265.557807 -34.956533) (xy 265.499882 -34.972054)
			(xy 265.440426 -34.979882) (xy 265.380458 -34.979882) (xy 265.321002 -34.972054) (xy 265.263077 -34.956533)
			(xy 265.207673 -34.933584) (xy 265.155739 -34.9036) (xy 265.108163 -34.867094) (xy 265.065758 -34.824689)
			(xy 265.029252 -34.777113) (xy 264.999268 -34.725179) (xy 264.976319 -34.669775) (xy 264.960798 -34.61185)
			(xy 264.95297 -34.552394) (xy 264.95248 -34.52241) (xy 261.535353 -34.52241) (xy 261.984744 -35.089338)
			(xy 261.991147 -35.096737) (xy 262.008133 -35.106411) (xy 262.017764 -35.108134) (xy 262.022336 -35.108388)
			(xy 262.025638 -35.108642) (xy 262.108442 -35.102292) (xy 262.112252 -35.102038) (xy 262.124414 -35.100425)
			(xy 262.145262 -35.087564) (xy 262.15213 -35.0774) (xy 262.152638 -35.076638) (xy 262.152638 -35.076384)
			(xy 262.167288 -35.051651) (xy 262.20286 -35.006497) (xy 262.244805 -34.967191) (xy 262.292172 -34.934625)
			(xy 262.34389 -34.909534) (xy 262.398787 -34.892488) (xy 262.455621 -34.883872) (xy 262.484362 -34.883344)
			(xy 262.511616 -34.883827) (xy 262.565571 -34.891579) (xy 262.617873 -34.90693) (xy 262.667458 -34.929569)
			(xy 262.713316 -34.959033) (xy 262.754515 -34.994724) (xy 262.790215 -35.035915) (xy 262.81969 -35.081767)
			(xy 262.84234 -35.131347) (xy 262.857703 -35.183645) (xy 262.865467 -35.237598) (xy 262.86587 -35.264852)
			(xy 262.865412 -35.29146) (xy 262.858024 -35.34416) (xy 262.843384 -35.395322) (xy 262.821778 -35.443953)
			(xy 262.793624 -35.489111) (xy 262.759467 -35.529918) (xy 262.719972 -35.565583) (xy 262.675904 -35.595414)
			(xy 262.628119 -35.618832) (xy 262.60298 -35.627564) (xy 262.591804 -35.63112) (xy 262.567166 -35.65525)
			(xy 262.562846 -35.659702) (xy 262.556299 -35.670236) (xy 262.554212 -35.676078) (xy 262.532368 -35.744658)
			(xy 262.529419 -35.755866) (xy 262.53285 -35.778761) (xy 262.538972 -35.7886) (xy 262.933977 -36.286948)
			(xy 263.400284 -36.286948) (xy 263.404355 -36.231326) (xy 263.416481 -36.176889) (xy 263.436404 -36.124798)
			(xy 263.4637 -36.076163) (xy 263.497786 -36.03202) (xy 263.537935 -35.993311) (xy 263.583293 -35.96086)
			(xy 263.632893 -35.935359) (xy 263.685677 -35.917352) (xy 263.74052 -35.907222) (xy 263.796254 -35.905185)
			(xy 263.851691 -35.911285) (xy 263.905648 -35.925391) (xy 263.956977 -35.947203) (xy 264.004583 -35.976257)
			(xy 264.047451 -36.011932) (xy 264.084668 -36.053469) (xy 264.115441 -36.099982) (xy 264.139113 -36.150479)
			(xy 264.155181 -36.203886) (xy 264.163301 -36.259062) (xy 264.16381 -36.286948) (xy 264.163301 -36.314834)
			(xy 264.155181 -36.37001) (xy 264.139113 -36.423417) (xy 264.115441 -36.473914) (xy 264.087896 -36.515548)
			(xy 265.214098 -36.515548) (xy 265.218169 -36.459926) (xy 265.230295 -36.405489) (xy 265.250218 -36.353398)
			(xy 265.277514 -36.304763) (xy 265.3116 -36.26062) (xy 265.351749 -36.221911) (xy 265.397107 -36.18946)
			(xy 265.446707 -36.163959) (xy 265.499491 -36.145952) (xy 265.554334 -36.135822) (xy 265.610068 -36.133785)
			(xy 265.665505 -36.139885) (xy 265.719462 -36.153991) (xy 265.770791 -36.175803) (xy 265.818397 -36.204857)
			(xy 265.861265 -36.240532) (xy 265.898482 -36.282069) (xy 265.929255 -36.328582) (xy 265.952927 -36.379079)
			(xy 265.968995 -36.432486) (xy 265.977115 -36.487662) (xy 265.977624 -36.515548) (xy 265.977115 -36.543434)
			(xy 265.968995 -36.59861) (xy 265.968538 -36.60013) (xy 270.198603 -36.60013) (xy 270.202607 -36.512245)
			(xy 270.214587 -36.425088) (xy 270.234442 -36.339381) (xy 270.262009 -36.255836) (xy 270.297059 -36.175143)
			(xy 270.339301 -36.097971) (xy 270.388386 -36.024961) (xy 270.443907 -35.956717) (xy 270.505404 -35.893804)
			(xy 270.572366 -35.836744) (xy 270.64424 -35.78601) (xy 270.72043 -35.742022) (xy 270.800304 -35.705144)
			(xy 270.883201 -35.675683) (xy 270.968433 -35.653881) (xy 271.055295 -35.639921) (xy 271.143066 -35.633917)
			(xy 271.23102 -35.63592) (xy 271.318427 -35.645912) (xy 271.404563 -35.663812) (xy 271.488715 -35.68947)
			(xy 271.570185 -35.722674) (xy 271.648298 -35.763148) (xy 271.722406 -35.810559) (xy 271.791897 -35.864512)
			(xy 271.804988 -35.876738) (xy 276.917148 -35.876738) (xy 276.921219 -35.821116) (xy 276.933345 -35.766679)
			(xy 276.953268 -35.714588) (xy 276.980564 -35.665953) (xy 277.01465 -35.62181) (xy 277.054799 -35.583101)
			(xy 277.100157 -35.55065) (xy 277.149757 -35.525149) (xy 277.202541 -35.507142) (xy 277.257384 -35.497012)
			(xy 277.313118 -35.494975) (xy 277.368555 -35.501075) (xy 277.422512 -35.515181) (xy 277.473841 -35.536993)
			(xy 277.521447 -35.566047) (xy 277.564315 -35.601722) (xy 277.601532 -35.643259) (xy 277.632305 -35.689772)
			(xy 277.655977 -35.740269) (xy 277.672045 -35.793676) (xy 277.680165 -35.848852) (xy 277.680674 -35.876738)
			(xy 277.680165 -35.904624) (xy 277.672045 -35.9598) (xy 277.655977 -36.013207) (xy 277.632305 -36.063704)
			(xy 277.601532 -36.110217) (xy 277.564315 -36.151754) (xy 277.521447 -36.187429) (xy 277.473841 -36.216483)
			(xy 277.422512 -36.238295) (xy 277.368555 -36.252401) (xy 277.313118 -36.258501) (xy 277.257384 -36.256464)
			(xy 277.202541 -36.246334) (xy 277.149757 -36.228327) (xy 277.100157 -36.202826) (xy 277.054799 -36.170375)
			(xy 277.01465 -36.131666) (xy 276.980564 -36.087523) (xy 276.953268 -36.038888) (xy 276.933345 -35.986797)
			(xy 276.921219 -35.93236) (xy 276.917148 -35.876738) (xy 271.804988 -35.876738) (xy 271.856193 -35.92456)
			(xy 271.914762 -35.990207) (xy 271.967119 -36.060907) (xy 272.012831 -36.136076) (xy 272.051517 -36.21509)
			(xy 272.082858 -36.297295) (xy 272.106593 -36.382009) (xy 272.122527 -36.46853) (xy 272.12631 -36.50996)
			(xy 278.813766 -36.50996) (xy 278.817837 -36.454338) (xy 278.829963 -36.399901) (xy 278.849886 -36.34781)
			(xy 278.877182 -36.299175) (xy 278.911268 -36.255032) (xy 278.951417 -36.216323) (xy 278.996775 -36.183872)
			(xy 279.046375 -36.158371) (xy 279.099159 -36.140364) (xy 279.154002 -36.130234) (xy 279.209736 -36.128197)
			(xy 279.265173 -36.134297) (xy 279.31913 -36.148403) (xy 279.370459 -36.170215) (xy 279.418065 -36.199269)
			(xy 279.460933 -36.234944) (xy 279.49815 -36.276481) (xy 279.528923 -36.322994) (xy 279.552595 -36.373491)
			(xy 279.568663 -36.426898) (xy 279.576783 -36.482074) (xy 279.577292 -36.50996) (xy 279.576783 -36.537846)
			(xy 279.568663 -36.593022) (xy 279.552595 -36.646429) (xy 279.528923 -36.696926) (xy 279.49815 -36.743439)
			(xy 279.460933 -36.784976) (xy 279.418065 -36.820651) (xy 279.370459 -36.849705) (xy 279.31913 -36.871517)
			(xy 279.265173 -36.885623) (xy 279.209736 -36.891723) (xy 279.154002 -36.889686) (xy 279.099159 -36.879556)
			(xy 279.046375 -36.861549) (xy 278.996775 -36.836048) (xy 278.951417 -36.803597) (xy 278.911268 -36.764888)
			(xy 278.877182 -36.720745) (xy 278.849886 -36.67211) (xy 278.829963 -36.620019) (xy 278.817837 -36.565582)
			(xy 278.813766 -36.50996) (xy 272.12631 -36.50996) (xy 272.130527 -36.556142) (xy 272.131028 -36.60013)
			(xy 272.130527 -36.644118) (xy 272.122527 -36.73173) (xy 272.106593 -36.818251) (xy 272.082858 -36.902965)
			(xy 272.051517 -36.98517) (xy 272.012831 -37.064184) (xy 271.967119 -37.139353) (xy 271.914762 -37.210053)
			(xy 271.856193 -37.2757) (xy 271.791897 -37.335748) (xy 271.722406 -37.389701) (xy 271.648298 -37.437112)
			(xy 271.574867 -37.47516) (xy 275.95906 -37.47516) (xy 275.963131 -37.419538) (xy 275.975257 -37.365101)
			(xy 275.99518 -37.31301) (xy 276.022476 -37.264375) (xy 276.056562 -37.220232) (xy 276.096711 -37.181523)
			(xy 276.142069 -37.149072) (xy 276.191669 -37.123571) (xy 276.244453 -37.105564) (xy 276.299296 -37.095434)
			(xy 276.35503 -37.093397) (xy 276.410467 -37.099497) (xy 276.464424 -37.113603) (xy 276.515753 -37.135415)
			(xy 276.563359 -37.164469) (xy 276.606227 -37.200144) (xy 276.643444 -37.241681) (xy 276.674217 -37.288194)
			(xy 276.697889 -37.338691) (xy 276.713957 -37.392098) (xy 276.722077 -37.447274) (xy 276.722586 -37.47516)
			(xy 276.722077 -37.503046) (xy 276.713957 -37.558222) (xy 276.697889 -37.611629) (xy 276.674217 -37.662126)
			(xy 276.674064 -37.662358) (xy 278.148286 -37.662358) (xy 278.152357 -37.606736) (xy 278.164483 -37.552299)
			(xy 278.184406 -37.500208) (xy 278.211702 -37.451573) (xy 278.245788 -37.40743) (xy 278.285937 -37.368721)
			(xy 278.331295 -37.33627) (xy 278.380895 -37.310769) (xy 278.433679 -37.292762) (xy 278.488522 -37.282632)
			(xy 278.544256 -37.280595) (xy 278.599693 -37.286695) (xy 278.65365 -37.300801) (xy 278.704979 -37.322613)
			(xy 278.752585 -37.351667) (xy 278.795453 -37.387342) (xy 278.83267 -37.428879) (xy 278.863443 -37.475392)
			(xy 278.887115 -37.525889) (xy 278.903183 -37.579296) (xy 278.911303 -37.634472) (xy 278.911812 -37.662358)
			(xy 278.911303 -37.690244) (xy 278.903183 -37.74542) (xy 278.887115 -37.798827) (xy 278.863443 -37.849324)
			(xy 278.83267 -37.895837) (xy 278.795453 -37.937374) (xy 278.752585 -37.973049) (xy 278.704979 -38.002103)
			(xy 278.65365 -38.023915) (xy 278.599693 -38.038021) (xy 278.544256 -38.044121) (xy 278.488522 -38.042084)
			(xy 278.433679 -38.031954) (xy 278.380895 -38.013947) (xy 278.331295 -37.988446) (xy 278.285937 -37.955995)
			(xy 278.245788 -37.917286) (xy 278.211702 -37.873143) (xy 278.184406 -37.824508) (xy 278.164483 -37.772417)
			(xy 278.152357 -37.71798) (xy 278.148286 -37.662358) (xy 276.674064 -37.662358) (xy 276.643444 -37.708639)
			(xy 276.606227 -37.750176) (xy 276.563359 -37.785851) (xy 276.515753 -37.814905) (xy 276.464424 -37.836717)
			(xy 276.410467 -37.850823) (xy 276.35503 -37.856923) (xy 276.299296 -37.854886) (xy 276.244453 -37.844756)
			(xy 276.191669 -37.826749) (xy 276.142069 -37.801248) (xy 276.096711 -37.768797) (xy 276.056562 -37.730088)
			(xy 276.022476 -37.685945) (xy 275.99518 -37.63731) (xy 275.975257 -37.585219) (xy 275.963131 -37.530782)
			(xy 275.95906 -37.47516) (xy 271.574867 -37.47516) (xy 271.570185 -37.477586) (xy 271.488715 -37.51079)
			(xy 271.404563 -37.536448) (xy 271.318427 -37.554348) (xy 271.23102 -37.56434) (xy 271.143066 -37.566343)
			(xy 271.055295 -37.560339) (xy 270.968433 -37.546379) (xy 270.883201 -37.524577) (xy 270.800304 -37.495116)
			(xy 270.72043 -37.458238) (xy 270.64424 -37.41425) (xy 270.572366 -37.363516) (xy 270.505404 -37.306456)
			(xy 270.443907 -37.243543) (xy 270.388386 -37.175299) (xy 270.339301 -37.102289) (xy 270.297059 -37.025117)
			(xy 270.262009 -36.944424) (xy 270.234442 -36.860879) (xy 270.214587 -36.775172) (xy 270.202607 -36.688015)
			(xy 270.198603 -36.60013) (xy 265.968538 -36.60013) (xy 265.952927 -36.652017) (xy 265.929255 -36.702514)
			(xy 265.898482 -36.749027) (xy 265.861265 -36.790564) (xy 265.818397 -36.826239) (xy 265.770791 -36.855293)
			(xy 265.719462 -36.877105) (xy 265.665505 -36.891211) (xy 265.610068 -36.897311) (xy 265.554334 -36.895274)
			(xy 265.499491 -36.885144) (xy 265.446707 -36.867137) (xy 265.397107 -36.841636) (xy 265.351749 -36.809185)
			(xy 265.3116 -36.770476) (xy 265.277514 -36.726333) (xy 265.250218 -36.677698) (xy 265.230295 -36.625607)
			(xy 265.218169 -36.57117) (xy 265.214098 -36.515548) (xy 264.087896 -36.515548) (xy 264.084668 -36.520427)
			(xy 264.047451 -36.561964) (xy 264.004583 -36.597639) (xy 263.956977 -36.626693) (xy 263.905648 -36.648505)
			(xy 263.851691 -36.662611) (xy 263.796254 -36.668711) (xy 263.74052 -36.666674) (xy 263.685677 -36.656544)
			(xy 263.632893 -36.638537) (xy 263.583293 -36.613036) (xy 263.537935 -36.580585) (xy 263.497786 -36.541876)
			(xy 263.4637 -36.497733) (xy 263.436404 -36.449098) (xy 263.416481 -36.397007) (xy 263.404355 -36.34257)
			(xy 263.400284 -36.286948) (xy 262.933977 -36.286948) (xy 263.828276 -37.415216) (xy 263.835494 -37.422541)
			(xy 263.854116 -37.431222) (xy 263.87465 -37.431922) (xy 263.88441 -37.428678) (xy 263.887204 -37.427408)
			(xy 263.912257 -37.416424) (xy 263.96472 -37.400936) (xy 264.018857 -37.393097) (xy 264.046208 -37.39261)
			(xy 264.046716 -37.39261) (xy 264.073968 -37.393074) (xy 264.127916 -37.400833) (xy 264.180211 -37.416191)
			(xy 264.229788 -37.438835) (xy 264.275638 -37.468303) (xy 264.316827 -37.503997) (xy 264.352517 -37.54519)
			(xy 264.381982 -37.591042) (xy 264.404621 -37.640621) (xy 264.419974 -37.692917) (xy 264.427728 -37.746866)
			(xy 264.428224 -37.774118) (xy 264.427817 -37.799339) (xy 264.421173 -37.849343) (xy 264.408002 -37.898036)
			(xy 264.388534 -37.944571) (xy 264.363109 -37.988137) (xy 264.34796 -38.008306) (xy 264.347706 -38.00856)
			(xy 264.342698 -38.015514) (xy 264.337233 -38.031744) (xy 264.337038 -38.04031) (xy 264.337038 -38.048184)
			(xy 264.342626 -38.063932) (xy 266.882609 -41.268755) (xy 274.043827 -41.268755) (xy 274.043827 -41.214245)
			(xy 274.051585 -41.16029) (xy 274.066942 -41.107988) (xy 274.089586 -41.058404) (xy 274.119057 -41.012547)
			(xy 274.154753 -40.971352) (xy 274.195949 -40.935655) (xy 274.241806 -40.906185) (xy 274.29139 -40.883541)
			(xy 274.343692 -40.868184) (xy 274.397647 -40.860427) (xy 274.424902 -40.859964) (xy 274.45364 -40.860496)
			(xy 274.510467 -40.869118) (xy 274.565357 -40.886167) (xy 274.617069 -40.911256) (xy 274.664432 -40.943819)
			(xy 274.68576 -40.963088) (xy 274.692618 -40.969692) (xy 274.710652 -40.976804) (xy 274.799552 -40.976804)
			(xy 274.817586 -40.969692) (xy 274.824444 -40.963088) (xy 274.845778 -40.943825) (xy 274.893137 -40.911255)
			(xy 274.944847 -40.886161) (xy 274.999736 -40.869108) (xy 275.056563 -40.860485) (xy 275.085302 -40.859964)
			(xy 275.112551 -40.860506) (xy 275.166495 -40.868263) (xy 275.218785 -40.883617) (xy 275.268358 -40.906256)
			(xy 275.314205 -40.93572) (xy 275.355392 -40.971409) (xy 275.391081 -41.012596) (xy 275.420545 -41.058443)
			(xy 275.443184 -41.108017) (xy 275.458538 -41.160307) (xy 275.466294 -41.214251) (xy 275.466294 -41.268749)
			(xy 275.458538 -41.322693) (xy 275.443184 -41.374983) (xy 275.420545 -41.424557) (xy 275.391081 -41.470404)
			(xy 275.355392 -41.511591) (xy 275.314205 -41.54728) (xy 275.268358 -41.576744) (xy 275.218785 -41.599383)
			(xy 275.166495 -41.614737) (xy 275.112551 -41.622494) (xy 275.085302 -41.62298) (xy 275.056564 -41.622434)
			(xy 274.999739 -41.613813) (xy 274.944849 -41.596767) (xy 274.893137 -41.571681) (xy 274.845773 -41.539123)
			(xy 274.824444 -41.519856) (xy 274.817586 -41.513252) (xy 274.799552 -41.50614) (xy 274.710652 -41.50614)
			(xy 274.692618 -41.513252) (xy 274.68576 -41.519856) (xy 274.664431 -41.539125) (xy 274.61707 -41.571692)
			(xy 274.565359 -41.596785) (xy 274.510468 -41.613836) (xy 274.453641 -41.622459) (xy 274.424902 -41.62298)
			(xy 274.397647 -41.622573) (xy 274.343692 -41.614816) (xy 274.29139 -41.599459) (xy 274.241806 -41.576815)
			(xy 274.195949 -41.547345) (xy 274.154753 -41.511648) (xy 274.119057 -41.470453) (xy 274.089586 -41.424596)
			(xy 274.066942 -41.375012) (xy 274.051585 -41.32271) (xy 274.043827 -41.268755) (xy 266.882609 -41.268755)
			(xy 268.496611 -43.305222) (xy 276.507194 -43.305222) (xy 276.507674 -43.277852) (xy 276.515489 -43.223674)
			(xy 276.530975 -43.171171) (xy 276.553813 -43.121424) (xy 276.583534 -43.075456) (xy 276.601174 -43.054524)
			(xy 276.601428 -43.05427) (xy 276.606995 -43.04717) (xy 276.613252 -43.030263) (xy 276.61362 -43.02125)
			(xy 276.61362 -42.954194) (xy 276.613261 -42.945177) (xy 276.607014 -42.928261) (xy 276.601428 -42.921174)
			(xy 276.601174 -42.921174) (xy 276.601174 -42.92092) (xy 276.583527 -42.899995) (xy 276.553817 -42.85402)
			(xy 276.530983 -42.80427) (xy 276.515494 -42.751768) (xy 276.507667 -42.697592) (xy 276.507194 -42.670222)
			(xy 276.507733 -42.641484) (xy 276.516352 -42.584657) (xy 276.533399 -42.529767) (xy 276.558487 -42.478055)
			(xy 276.591049 -42.430691) (xy 276.610318 -42.409364) (xy 276.616922 -42.402506) (xy 276.624034 -42.384472)
			(xy 276.624034 -42.295572) (xy 276.616922 -42.277538) (xy 276.610318 -42.27068) (xy 276.591069 -42.249334)
			(xy 276.558504 -42.201975) (xy 276.533411 -42.150266) (xy 276.51636 -42.095378) (xy 276.507736 -42.038554)
			(xy 276.507733 -41.981078) (xy 276.516353 -41.924253) (xy 276.5334 -41.869364) (xy 276.558488 -41.817653)
			(xy 276.591049 -41.770291) (xy 276.610318 -41.748964) (xy 276.616922 -41.742106) (xy 276.624034 -41.724072)
			(xy 276.624034 -41.635172) (xy 276.616922 -41.617138) (xy 276.610318 -41.61028) (xy 276.591054 -41.588947)
			(xy 276.558488 -41.541586) (xy 276.533394 -41.489876) (xy 276.516342 -41.434987) (xy 276.507717 -41.378161)
			(xy 276.507194 -41.349422) (xy 276.50768 -41.322171) (xy 276.515436 -41.268223) (xy 276.530791 -41.215928)
			(xy 276.553433 -41.166351) (xy 276.582899 -41.120501) (xy 276.61859 -41.07931) (xy 276.659781 -41.043619)
			(xy 276.705631 -41.014153) (xy 276.755208 -40.991511) (xy 276.807503 -40.976156) (xy 276.861451 -40.9684)
			(xy 276.915953 -40.9684) (xy 276.969901 -40.976156) (xy 277.022196 -40.991511) (xy 277.071773 -41.014153)
			(xy 277.117623 -41.043619) (xy 277.158814 -41.07931) (xy 277.194505 -41.120501) (xy 277.223971 -41.166351)
			(xy 277.246613 -41.215928) (xy 277.261968 -41.268223) (xy 277.269724 -41.322171) (xy 277.27021 -41.349422)
			(xy 277.269697 -41.378161) (xy 277.261071 -41.434989) (xy 277.244019 -41.48988) (xy 277.218925 -41.541591)
			(xy 277.186358 -41.588953) (xy 277.167086 -41.61028) (xy 277.160482 -41.617138) (xy 277.15337 -41.635172)
			(xy 277.15337 -41.724072) (xy 277.160482 -41.742106) (xy 277.167086 -41.748964) (xy 277.186378 -41.770272)
			(xy 277.218942 -41.817638) (xy 277.244032 -41.869353) (xy 277.261079 -41.924246) (xy 277.2697 -41.981076)
			(xy 277.269697 -42.038556) (xy 277.261072 -42.095385) (xy 277.24402 -42.150277) (xy 277.218926 -42.20199)
			(xy 277.186358 -42.249353) (xy 277.167086 -42.27068) (xy 277.160482 -42.277538) (xy 277.15337 -42.295572)
			(xy 277.15337 -42.384472) (xy 277.160482 -42.402506) (xy 277.167086 -42.409364) (xy 277.186371 -42.430679)
			(xy 277.218935 -42.478044) (xy 277.244024 -42.529759) (xy 277.261071 -42.584653) (xy 277.269691 -42.641482)
			(xy 277.27021 -42.670222) (xy 277.269754 -42.697593) (xy 277.261934 -42.751772) (xy 277.246442 -42.804275)
			(xy 277.225887 -42.849038) (xy 279.091896 -42.849038) (xy 279.095967 -42.793416) (xy 279.108093 -42.738979)
			(xy 279.128016 -42.686888) (xy 279.155312 -42.638253) (xy 279.189398 -42.59411) (xy 279.229547 -42.555401)
			(xy 279.274905 -42.52295) (xy 279.324505 -42.497449) (xy 279.377289 -42.479442) (xy 279.432132 -42.469312)
			(xy 279.487866 -42.467275) (xy 279.543303 -42.473375) (xy 279.59726 -42.487481) (xy 279.648589 -42.509293)
			(xy 279.696195 -42.538347) (xy 279.739063 -42.574022) (xy 279.77628 -42.615559) (xy 279.807053 -42.662072)
			(xy 279.830725 -42.712569) (xy 279.846793 -42.765976) (xy 279.854913 -42.821152) (xy 279.855422 -42.849038)
			(xy 279.854913 -42.876924) (xy 279.846793 -42.9321) (xy 279.830725 -42.985507) (xy 279.807053 -43.036004)
			(xy 279.77628 -43.082517) (xy 279.739063 -43.124054) (xy 279.696195 -43.159729) (xy 279.648589 -43.188783)
			(xy 279.59726 -43.210595) (xy 279.543303 -43.224701) (xy 279.487866 -43.230801) (xy 279.432132 -43.228764)
			(xy 279.377289 -43.218634) (xy 279.324505 -43.200627) (xy 279.274905 -43.175126) (xy 279.229547 -43.142675)
			(xy 279.189398 -43.103966) (xy 279.155312 -43.059823) (xy 279.128016 -43.011188) (xy 279.108093 -42.959097)
			(xy 279.095967 -42.90466) (xy 279.091896 -42.849038) (xy 277.225887 -42.849038) (xy 277.223598 -42.854022)
			(xy 277.193872 -42.899988) (xy 277.17623 -42.92092) (xy 277.175976 -42.921174) (xy 277.170392 -42.928262)
			(xy 277.164144 -42.945178) (xy 277.163784 -42.954194) (xy 277.163784 -43.02125) (xy 277.164168 -43.030264)
			(xy 277.170397 -43.047181) (xy 277.175976 -43.05427) (xy 277.17623 -43.05427) (xy 277.17623 -43.054524)
			(xy 277.193852 -43.07547) (xy 277.223565 -43.121439) (xy 277.246404 -43.171184) (xy 277.261899 -43.223681)
			(xy 277.269733 -43.277854) (xy 277.27021 -43.305222) (xy 277.269724 -43.332473) (xy 277.261968 -43.386421)
			(xy 277.246613 -43.438716) (xy 277.223971 -43.488293) (xy 277.194505 -43.534143) (xy 277.158814 -43.575334)
			(xy 277.117623 -43.611025) (xy 277.071773 -43.640491) (xy 277.022196 -43.663133) (xy 276.969901 -43.678488)
			(xy 276.915953 -43.686244) (xy 276.861451 -43.686244) (xy 276.807503 -43.678488) (xy 276.755208 -43.663133)
			(xy 276.705631 -43.640491) (xy 276.659781 -43.611025) (xy 276.61859 -43.575334) (xy 276.582899 -43.534143)
			(xy 276.553433 -43.488293) (xy 276.530791 -43.438716) (xy 276.515436 -43.386421) (xy 276.50768 -43.332473)
			(xy 276.507194 -43.305222) (xy 268.496611 -43.305222) (xy 268.83823 -43.73626) (xy 278.412954 -43.73626)
			(xy 278.417025 -43.680638) (xy 278.429151 -43.626201) (xy 278.449074 -43.57411) (xy 278.47637 -43.525475)
			(xy 278.510456 -43.481332) (xy 278.550605 -43.442623) (xy 278.595963 -43.410172) (xy 278.645563 -43.384671)
			(xy 278.698347 -43.366664) (xy 278.75319 -43.356534) (xy 278.808924 -43.354497) (xy 278.864361 -43.360597)
			(xy 278.918318 -43.374703) (xy 278.969647 -43.396515) (xy 279.017253 -43.425569) (xy 279.060121 -43.461244)
			(xy 279.097338 -43.502781) (xy 279.128111 -43.549294) (xy 279.136337 -43.566842) (xy 281.533344 -43.566842)
			(xy 281.537415 -43.51122) (xy 281.549541 -43.456783) (xy 281.569464 -43.404692) (xy 281.59676 -43.356057)
			(xy 281.630846 -43.311914) (xy 281.670995 -43.273205) (xy 281.716353 -43.240754) (xy 281.765953 -43.215253)
			(xy 281.818737 -43.197246) (xy 281.87358 -43.187116) (xy 281.929314 -43.185079) (xy 281.984751 -43.191179)
			(xy 282.038708 -43.205285) (xy 282.090037 -43.227097) (xy 282.137643 -43.256151) (xy 282.180511 -43.291826)
			(xy 282.217728 -43.333363) (xy 282.248501 -43.379876) (xy 282.272173 -43.430373) (xy 282.288241 -43.48378)
			(xy 282.296361 -43.538956) (xy 282.29687 -43.566842) (xy 282.296361 -43.594728) (xy 282.288241 -43.649904)
			(xy 282.272173 -43.703311) (xy 282.248501 -43.753808) (xy 282.217728 -43.800321) (xy 282.180511 -43.841858)
			(xy 282.162424 -43.85691) (xy 282.919676 -43.85691) (xy 282.923747 -43.801288) (xy 282.935873 -43.746851)
			(xy 282.955796 -43.69476) (xy 282.983092 -43.646125) (xy 283.017178 -43.601982) (xy 283.057327 -43.563273)
			(xy 283.102685 -43.530822) (xy 283.152285 -43.505321) (xy 283.205069 -43.487314) (xy 283.259912 -43.477184)
			(xy 283.315646 -43.475147) (xy 283.371083 -43.481247) (xy 283.42504 -43.495353) (xy 283.476369 -43.517165)
			(xy 283.523975 -43.546219) (xy 283.566843 -43.581894) (xy 283.60406 -43.623431) (xy 283.634833 -43.669944)
			(xy 283.658505 -43.720441) (xy 283.674573 -43.773848) (xy 283.682693 -43.829024) (xy 283.683202 -43.85691)
			(xy 283.682693 -43.884796) (xy 283.674573 -43.939972) (xy 283.658505 -43.993379) (xy 283.634833 -44.043876)
			(xy 283.60406 -44.090389) (xy 283.566843 -44.131926) (xy 283.523975 -44.167601) (xy 283.476369 -44.196655)
			(xy 283.42504 -44.218467) (xy 283.371083 -44.232573) (xy 283.315646 -44.238673) (xy 283.259912 -44.236636)
			(xy 283.205069 -44.226506) (xy 283.152285 -44.208499) (xy 283.102685 -44.182998) (xy 283.057327 -44.150547)
			(xy 283.017178 -44.111838) (xy 282.983092 -44.067695) (xy 282.955796 -44.01906) (xy 282.935873 -43.966969)
			(xy 282.923747 -43.912532) (xy 282.919676 -43.85691) (xy 282.162424 -43.85691) (xy 282.137643 -43.877533)
			(xy 282.090037 -43.906587) (xy 282.038708 -43.928399) (xy 281.984751 -43.942505) (xy 281.929314 -43.948605)
			(xy 281.87358 -43.946568) (xy 281.818737 -43.936438) (xy 281.765953 -43.918431) (xy 281.716353 -43.89293)
			(xy 281.670995 -43.860479) (xy 281.630846 -43.82177) (xy 281.59676 -43.777627) (xy 281.569464 -43.728992)
			(xy 281.549541 -43.676901) (xy 281.537415 -43.622464) (xy 281.533344 -43.566842) (xy 279.136337 -43.566842)
			(xy 279.151783 -43.599791) (xy 279.167851 -43.653198) (xy 279.175971 -43.708374) (xy 279.17648 -43.73626)
			(xy 279.175971 -43.764146) (xy 279.167851 -43.819322) (xy 279.151783 -43.872729) (xy 279.128111 -43.923226)
			(xy 279.097338 -43.969739) (xy 279.060121 -44.011276) (xy 279.017253 -44.046951) (xy 278.969647 -44.076005)
			(xy 278.918318 -44.097817) (xy 278.864361 -44.111923) (xy 278.808924 -44.118023) (xy 278.75319 -44.115986)
			(xy 278.698347 -44.105856) (xy 278.645563 -44.087849) (xy 278.595963 -44.062348) (xy 278.550605 -44.029897)
			(xy 278.510456 -43.991188) (xy 278.47637 -43.947045) (xy 278.449074 -43.89841) (xy 278.429151 -43.846319)
			(xy 278.417025 -43.791882) (xy 278.412954 -43.73626) (xy 268.83823 -43.73626) (xy 268.909292 -43.825922)
			(xy 268.935661 -43.859889) (xy 268.983102 -43.931616) (xy 269.004034 -43.969178) (xy 269.62684 -45.114464)
			(xy 278.26538 -45.114464) (xy 278.269451 -45.058842) (xy 278.281577 -45.004405) (xy 278.3015 -44.952314)
			(xy 278.328796 -44.903679) (xy 278.362882 -44.859536) (xy 278.403031 -44.820827) (xy 278.448389 -44.788376)
			(xy 278.497989 -44.762875) (xy 278.550773 -44.744868) (xy 278.605616 -44.734738) (xy 278.66135 -44.732701)
			(xy 278.716787 -44.738801) (xy 278.770744 -44.752907) (xy 278.822073 -44.774719) (xy 278.869679 -44.803773)
			(xy 278.912547 -44.839448) (xy 278.942529 -44.87291) (xy 285.133032 -44.87291) (xy 285.137103 -44.817288)
			(xy 285.149229 -44.762851) (xy 285.169152 -44.71076) (xy 285.196448 -44.662125) (xy 285.230534 -44.617982)
			(xy 285.270683 -44.579273) (xy 285.316041 -44.546822) (xy 285.365641 -44.521321) (xy 285.418425 -44.503314)
			(xy 285.473268 -44.493184) (xy 285.529002 -44.491147) (xy 285.584439 -44.497247) (xy 285.638396 -44.511353)
			(xy 285.689725 -44.533165) (xy 285.737331 -44.562219) (xy 285.780199 -44.597894) (xy 285.817416 -44.639431)
			(xy 285.848189 -44.685944) (xy 285.871861 -44.736441) (xy 285.887929 -44.789848) (xy 285.896049 -44.845024)
			(xy 285.896558 -44.87291) (xy 285.896049 -44.900796) (xy 285.887929 -44.955972) (xy 285.871861 -45.009379)
			(xy 285.848189 -45.059876) (xy 285.817416 -45.106389) (xy 285.780199 -45.147926) (xy 285.737331 -45.183601)
			(xy 285.689725 -45.212655) (xy 285.638396 -45.234467) (xy 285.584439 -45.248573) (xy 285.529002 -45.254673)
			(xy 285.473268 -45.252636) (xy 285.418425 -45.242506) (xy 285.365641 -45.224499) (xy 285.316041 -45.198998)
			(xy 285.270683 -45.166547) (xy 285.230534 -45.127838) (xy 285.196448 -45.083695) (xy 285.169152 -45.03506)
			(xy 285.149229 -44.982969) (xy 285.137103 -44.928532) (xy 285.133032 -44.87291) (xy 278.942529 -44.87291)
			(xy 278.949764 -44.880985) (xy 278.980537 -44.927498) (xy 279.004209 -44.977995) (xy 279.020277 -45.031402)
			(xy 279.028397 -45.086578) (xy 279.028906 -45.114464) (xy 279.028397 -45.14235) (xy 279.020277 -45.197526)
			(xy 279.004209 -45.250933) (xy 278.980537 -45.30143) (xy 278.949764 -45.347943) (xy 278.944122 -45.35424)
			(xy 282.903674 -45.35424) (xy 282.907745 -45.298618) (xy 282.919871 -45.244181) (xy 282.939794 -45.19209)
			(xy 282.96709 -45.143455) (xy 283.001176 -45.099312) (xy 283.041325 -45.060603) (xy 283.086683 -45.028152)
			(xy 283.136283 -45.002651) (xy 283.189067 -44.984644) (xy 283.24391 -44.974514) (xy 283.299644 -44.972477)
			(xy 283.355081 -44.978577) (xy 283.409038 -44.992683) (xy 283.460367 -45.014495) (xy 283.507973 -45.043549)
			(xy 283.550841 -45.079224) (xy 283.588058 -45.120761) (xy 283.618831 -45.167274) (xy 283.642503 -45.217771)
			(xy 283.658571 -45.271178) (xy 283.666691 -45.326354) (xy 283.6672 -45.35424) (xy 283.666691 -45.382126)
			(xy 283.658571 -45.437302) (xy 283.642503 -45.490709) (xy 283.618831 -45.541206) (xy 283.588058 -45.587719)
			(xy 283.550841 -45.629256) (xy 283.507973 -45.664931) (xy 283.460367 -45.693985) (xy 283.409038 -45.715797)
			(xy 283.355081 -45.729903) (xy 283.299644 -45.736003) (xy 283.24391 -45.733966) (xy 283.189067 -45.723836)
			(xy 283.136283 -45.705829) (xy 283.086683 -45.680328) (xy 283.041325 -45.647877) (xy 283.001176 -45.609168)
			(xy 282.96709 -45.565025) (xy 282.939794 -45.51639) (xy 282.919871 -45.464299) (xy 282.907745 -45.409862)
			(xy 282.903674 -45.35424) (xy 278.944122 -45.35424) (xy 278.912547 -45.38948) (xy 278.869679 -45.425155)
			(xy 278.822073 -45.454209) (xy 278.770744 -45.476021) (xy 278.716787 -45.490127) (xy 278.66135 -45.496227)
			(xy 278.605616 -45.49419) (xy 278.550773 -45.48406) (xy 278.497989 -45.466053) (xy 278.448389 -45.440552)
			(xy 278.403031 -45.408101) (xy 278.362882 -45.369392) (xy 278.328796 -45.325249) (xy 278.3015 -45.276614)
			(xy 278.281577 -45.224523) (xy 278.269451 -45.170086) (xy 278.26538 -45.114464) (xy 269.62684 -45.114464)
			(xy 269.92961 -45.671232) (xy 269.932912 -45.676058) (xy 270.305523 -46.082204) (xy 276.252432 -46.082204)
			(xy 276.252859 -46.054949) (xy 276.260617 -46.000995) (xy 276.275974 -45.948694) (xy 276.298619 -45.899111)
			(xy 276.32809 -45.853256) (xy 276.363788 -45.812063) (xy 276.404985 -45.776369) (xy 276.450843 -45.746902)
			(xy 276.500428 -45.724262) (xy 276.55273 -45.708909) (xy 276.606685 -45.701157) (xy 276.63394 -45.700696)
			(xy 276.660844 -45.701128) (xy 276.714115 -45.708705) (xy 276.765794 -45.72369) (xy 276.814856 -45.745785)
			(xy 276.860328 -45.774552) (xy 276.901308 -45.809421) (xy 276.936985 -45.8497) (xy 276.952202 -45.871892)
			(xy 276.959314 -45.882814) (xy 276.982174 -45.894752) (xy 277.094442 -45.89272) (xy 277.116794 -45.879766)
			(xy 277.123652 -45.86859) (xy 277.138552 -45.844974) (xy 277.174234 -45.802022) (xy 277.215796 -45.76473)
			(xy 277.26235 -45.733895) (xy 277.312901 -45.710174) (xy 277.36637 -45.694074) (xy 277.421614 -45.68594)
			(xy 277.449534 -45.685456) (xy 277.476528 -45.685897) (xy 277.529977 -45.693508) (xy 277.581821 -45.708573)
			(xy 277.631025 -45.730791) (xy 277.676608 -45.75972) (xy 277.697438 -45.776896) (xy 277.705566 -45.784008)
			(xy 277.72614 -45.790104) (xy 277.811484 -45.779182) (xy 277.822029 -45.77741) (xy 277.840312 -45.766354)
			(xy 277.84679 -45.757846) (xy 277.862156 -45.736625) (xy 277.897741 -45.698172) (xy 277.938256 -45.664953)
			(xy 277.982937 -45.637593) (xy 278.030943 -45.616608) (xy 278.08137 -45.602392) (xy 278.133268 -45.595215)
			(xy 278.159464 -45.594778) (xy 278.186718 -45.595267) (xy 278.24067 -45.603019) (xy 278.292971 -45.618372)
			(xy 278.342553 -45.641011) (xy 278.388409 -45.670477) (xy 278.429605 -45.70617) (xy 278.465301 -45.747362)
			(xy 278.494771 -45.793215) (xy 278.517416 -45.842796) (xy 278.532773 -45.895094) (xy 278.540531 -45.949047)
			(xy 278.540531 -46.003553) (xy 278.532773 -46.057506) (xy 278.517416 -46.109804) (xy 278.494771 -46.159385)
			(xy 278.465301 -46.205238) (xy 278.429605 -46.24643) (xy 278.388409 -46.282123) (xy 278.342553 -46.311589)
			(xy 278.292971 -46.334228) (xy 278.24067 -46.349581) (xy 278.186718 -46.357333) (xy 278.159464 -46.357794)
			(xy 278.132471 -46.357342) (xy 278.079022 -46.349732) (xy 278.027179 -46.334669) (xy 277.977975 -46.312453)
			(xy 277.932391 -46.283528) (xy 277.91156 -46.266354) (xy 277.903432 -46.259242) (xy 277.882858 -46.253146)
			(xy 277.797514 -46.264068) (xy 277.786973 -46.265857) (xy 277.76869 -46.276902) (xy 277.762208 -46.285404)
			(xy 277.744591 -46.309701) (xy 277.702998 -46.352963) (xy 277.679404 -46.37151) (xy 277.67153 -46.377352)
			(xy 277.661116 -46.394878) (xy 277.647908 -46.485302) (xy 277.652734 -46.504606) (xy 277.658576 -46.51248)
			(xy 277.658576 -46.512734) (xy 277.676079 -46.537478) (xy 277.703882 -46.591331) (xy 277.722818 -46.648903)
			(xy 277.730021 -46.693836) (xy 282.876244 -46.693836) (xy 282.87673 -46.666585) (xy 282.884486 -46.612637)
			(xy 282.899841 -46.560342) (xy 282.922483 -46.510765) (xy 282.951949 -46.464915) (xy 282.98764 -46.423724)
			(xy 283.028831 -46.388033) (xy 283.074681 -46.358567) (xy 283.124258 -46.335925) (xy 283.176553 -46.32057)
			(xy 283.230501 -46.312814) (xy 283.285003 -46.312814) (xy 283.338951 -46.32057) (xy 283.391246 -46.335925)
			(xy 283.440823 -46.358567) (xy 283.486673 -46.388033) (xy 283.527864 -46.423724) (xy 283.563555 -46.464915)
			(xy 283.593021 -46.510765) (xy 283.615663 -46.560342) (xy 283.631018 -46.612637) (xy 283.638774 -46.666585)
			(xy 283.63926 -46.693836) (xy 283.638793 -46.720264) (xy 283.631483 -46.772612) (xy 283.617008 -46.823447)
			(xy 283.595646 -46.871793) (xy 283.58211 -46.894496) (xy 283.581856 -46.89475) (xy 283.576519 -46.904768)
			(xy 283.574262 -46.927318) (xy 283.577538 -46.938184) (xy 283.6037 -47.01286) (xy 283.608062 -47.023387)
			(xy 283.624166 -47.039471) (xy 283.634688 -47.043848) (xy 283.634942 -47.043848) (xy 283.65945 -47.05292)
			(xy 283.705902 -47.076862) (xy 283.748655 -47.106917) (xy 283.786907 -47.142524) (xy 283.819943 -47.183017)
			(xy 283.847147 -47.227638) (xy 283.868009 -47.275553) (xy 283.882139 -47.325866) (xy 283.889273 -47.377636)
			(xy 283.889704 -47.403766) (xy 283.889218 -47.431017) (xy 283.887695 -47.441612) (xy 285.161734 -47.441612)
			(xy 285.165805 -47.38599) (xy 285.177931 -47.331553) (xy 285.197854 -47.279462) (xy 285.22515 -47.230827)
			(xy 285.259236 -47.186684) (xy 285.299385 -47.147975) (xy 285.344743 -47.115524) (xy 285.394343 -47.090023)
			(xy 285.447127 -47.072016) (xy 285.50197 -47.061886) (xy 285.557704 -47.059849) (xy 285.613141 -47.065949)
			(xy 285.667098 -47.080055) (xy 285.718427 -47.101867) (xy 285.766033 -47.130921) (xy 285.808901 -47.166596)
			(xy 285.846118 -47.208133) (xy 285.876891 -47.254646) (xy 285.900563 -47.305143) (xy 285.916631 -47.35855)
			(xy 285.924751 -47.413726) (xy 285.92526 -47.441612) (xy 285.924751 -47.469498) (xy 285.916631 -47.524674)
			(xy 285.900563 -47.578081) (xy 285.876891 -47.628578) (xy 285.846118 -47.675091) (xy 285.808901 -47.716628)
			(xy 285.766033 -47.752303) (xy 285.718427 -47.781357) (xy 285.667098 -47.803169) (xy 285.613141 -47.817275)
			(xy 285.557704 -47.823375) (xy 285.50197 -47.821338) (xy 285.447127 -47.811208) (xy 285.394343 -47.793201)
			(xy 285.344743 -47.7677) (xy 285.299385 -47.735249) (xy 285.259236 -47.69654) (xy 285.22515 -47.652397)
			(xy 285.197854 -47.603762) (xy 285.177931 -47.551671) (xy 285.165805 -47.497234) (xy 285.161734 -47.441612)
			(xy 283.887695 -47.441612) (xy 283.881462 -47.484965) (xy 283.866107 -47.53726) (xy 283.843465 -47.586837)
			(xy 283.813999 -47.632687) (xy 283.778308 -47.673878) (xy 283.737117 -47.709569) (xy 283.691267 -47.739035)
			(xy 283.64169 -47.761677) (xy 283.589395 -47.777032) (xy 283.535447 -47.784788) (xy 283.480945 -47.784788)
			(xy 283.426997 -47.777032) (xy 283.374702 -47.761677) (xy 283.325125 -47.739035) (xy 283.279275 -47.709569)
			(xy 283.238084 -47.673878) (xy 283.202393 -47.632687) (xy 283.172927 -47.586837) (xy 283.150285 -47.53726)
			(xy 283.13493 -47.484965) (xy 283.127174 -47.431017) (xy 283.126688 -47.403766) (xy 283.127163 -47.377339)
			(xy 283.134472 -47.324991) (xy 283.148945 -47.274156) (xy 283.170304 -47.225809) (xy 283.183838 -47.203106)
			(xy 283.184092 -47.202852) (xy 283.189427 -47.192834) (xy 283.191684 -47.170284) (xy 283.18841 -47.159418)
			(xy 283.162248 -47.084742) (xy 283.157863 -47.074227) (xy 283.141775 -47.058138) (xy 283.13126 -47.053754)
			(xy 283.131006 -47.053754) (xy 283.106488 -47.04471) (xy 283.060036 -47.020762) (xy 283.017286 -46.990701)
			(xy 282.979036 -46.95509) (xy 282.946001 -46.914594) (xy 282.918799 -46.869971) (xy 282.897938 -46.822053)
			(xy 282.883809 -46.771739) (xy 282.876675 -46.719967) (xy 282.876244 -46.693836) (xy 277.730021 -46.693836)
			(xy 277.732411 -46.708745) (xy 277.732998 -46.739048) (xy 277.732567 -46.766301) (xy 277.724803 -46.820251)
			(xy 277.709442 -46.872547) (xy 277.686794 -46.922126) (xy 277.657322 -46.967976) (xy 277.621625 -47.009166)
			(xy 277.58043 -47.044857) (xy 277.534575 -47.074322) (xy 277.484993 -47.096962) (xy 277.432694 -47.112316)
			(xy 277.378743 -47.120071) (xy 277.35149 -47.120556) (xy 277.325456 -47.120107) (xy 277.273874 -47.11302)
			(xy 277.223732 -47.09899) (xy 277.175961 -47.07828) (xy 277.131446 -47.051272) (xy 277.110952 -47.035212)
			(xy 277.103187 -47.029483) (xy 277.084783 -47.023735) (xy 277.075138 -47.024036) (xy 276.995382 -47.030386)
			(xy 276.977602 -47.039022) (xy 276.971252 -47.046388) (xy 276.953068 -47.066031) (xy 276.912161 -47.100553)
			(xy 276.866833 -47.129023) (xy 276.817972 -47.150881) (xy 276.766536 -47.165699) (xy 276.713536 -47.173186)
			(xy 276.686772 -47.173642) (xy 276.659522 -47.173148) (xy 276.605576 -47.165389) (xy 276.553283 -47.150032)
			(xy 276.503708 -47.12739) (xy 276.45786 -47.097924) (xy 276.416671 -47.062234) (xy 276.38098 -47.021045)
			(xy 276.351513 -46.975197) (xy 276.32887 -46.925622) (xy 276.313512 -46.87333) (xy 276.305752 -46.819384)
			(xy 276.305264 -46.792134) (xy 276.305798 -46.76336) (xy 276.314448 -46.706467) (xy 276.331543 -46.651517)
			(xy 276.356694 -46.599757) (xy 276.389331 -46.55236) (xy 276.408642 -46.531022) (xy 276.416008 -46.523148)
			(xy 276.42312 -46.503336) (xy 276.415754 -46.40707) (xy 276.405848 -46.388274) (xy 276.397466 -46.38167)
			(xy 276.375291 -46.363434) (xy 276.336078 -46.321502) (xy 276.30359 -46.274169) (xy 276.27856 -46.222503)
			(xy 276.261552 -46.167671) (xy 276.25295 -46.110909) (xy 276.252432 -46.082204) (xy 270.305523 -46.082204)
			(xy 270.364712 -46.14672) (xy 270.391662 -46.176731) (xy 270.441142 -46.240442) (xy 270.485266 -46.307972)
			(xy 270.523742 -46.378873) (xy 270.556314 -46.452673) (xy 270.569944 -46.490636) (xy 270.914114 -47.481236)
			(xy 270.915892 -47.485554) (xy 271.014698 -47.667418) (xy 271.034769 -47.705318) (xy 271.069104 -47.783914)
			(xy 271.083278 -47.82439) (xy 271.246435 -48.30699) (xy 282.753814 -48.30699) (xy 282.757885 -48.251368)
			(xy 282.770011 -48.196931) (xy 282.789934 -48.14484) (xy 282.81723 -48.096205) (xy 282.851316 -48.052062)
			(xy 282.891465 -48.013353) (xy 282.936823 -47.980902) (xy 282.986423 -47.955401) (xy 283.039207 -47.937394)
			(xy 283.09405 -47.927264) (xy 283.149784 -47.925227) (xy 283.205221 -47.931327) (xy 283.259178 -47.945433)
			(xy 283.310507 -47.967245) (xy 283.358113 -47.996299) (xy 283.400981 -48.031974) (xy 283.438198 -48.073511)
			(xy 283.468971 -48.120024) (xy 283.492643 -48.170521) (xy 283.508711 -48.223928) (xy 283.516831 -48.279104)
			(xy 283.51734 -48.30699) (xy 283.516831 -48.334876) (xy 283.508711 -48.390052) (xy 283.492643 -48.443459)
			(xy 283.468971 -48.493956) (xy 283.438198 -48.540469) (xy 283.400981 -48.582006) (xy 283.358113 -48.617681)
			(xy 283.310507 -48.646735) (xy 283.259178 -48.668547) (xy 283.205221 -48.682653) (xy 283.149784 -48.688753)
			(xy 283.09405 -48.686716) (xy 283.039207 -48.676586) (xy 282.986423 -48.658579) (xy 282.936823 -48.633078)
			(xy 282.891465 -48.600627) (xy 282.851316 -48.561918) (xy 282.81723 -48.517775) (xy 282.789934 -48.46914)
			(xy 282.770011 -48.417049) (xy 282.757885 -48.362612) (xy 282.753814 -48.30699) (xy 271.246435 -48.30699)
			(xy 271.397226 -48.753014) (xy 279.368248 -48.753014) (xy 279.372319 -48.697392) (xy 279.384445 -48.642955)
			(xy 279.404368 -48.590864) (xy 279.431664 -48.542229) (xy 279.46575 -48.498086) (xy 279.505899 -48.459377)
			(xy 279.551257 -48.426926) (xy 279.600857 -48.401425) (xy 279.653641 -48.383418) (xy 279.708484 -48.373288)
			(xy 279.764218 -48.371251) (xy 279.819655 -48.377351) (xy 279.873612 -48.391457) (xy 279.924941 -48.413269)
			(xy 279.972547 -48.442323) (xy 280.015415 -48.477998) (xy 280.052632 -48.519535) (xy 280.083405 -48.566048)
			(xy 280.107077 -48.616545) (xy 280.123145 -48.669952) (xy 280.131265 -48.725128) (xy 280.131774 -48.753014)
			(xy 280.131265 -48.7809) (xy 280.123145 -48.836076) (xy 280.107077 -48.889483) (xy 280.105681 -48.89246)
			(xy 281.413964 -48.89246) (xy 281.418035 -48.836838) (xy 281.430161 -48.782401) (xy 281.450084 -48.73031)
			(xy 281.47738 -48.681675) (xy 281.511466 -48.637532) (xy 281.551615 -48.598823) (xy 281.596973 -48.566372)
			(xy 281.646573 -48.540871) (xy 281.699357 -48.522864) (xy 281.7542 -48.512734) (xy 281.809934 -48.510697)
			(xy 281.865371 -48.516797) (xy 281.919328 -48.530903) (xy 281.970657 -48.552715) (xy 282.018263 -48.581769)
			(xy 282.061131 -48.617444) (xy 282.098348 -48.658981) (xy 282.129121 -48.705494) (xy 282.152793 -48.755991)
			(xy 282.168861 -48.809398) (xy 282.176981 -48.864574) (xy 282.17749 -48.89246) (xy 282.176981 -48.920346)
			(xy 282.174543 -48.93691) (xy 285.133032 -48.93691) (xy 285.137103 -48.881288) (xy 285.149229 -48.826851)
			(xy 285.169152 -48.77476) (xy 285.196448 -48.726125) (xy 285.230534 -48.681982) (xy 285.270683 -48.643273)
			(xy 285.316041 -48.610822) (xy 285.365641 -48.585321) (xy 285.418425 -48.567314) (xy 285.473268 -48.557184)
			(xy 285.529002 -48.555147) (xy 285.584439 -48.561247) (xy 285.638396 -48.575353) (xy 285.689725 -48.597165)
			(xy 285.737331 -48.626219) (xy 285.780199 -48.661894) (xy 285.817416 -48.703431) (xy 285.848189 -48.749944)
			(xy 285.871861 -48.800441) (xy 285.887929 -48.853848) (xy 285.896049 -48.909024) (xy 285.896558 -48.93691)
			(xy 285.896049 -48.964796) (xy 285.887929 -49.019972) (xy 285.871861 -49.073379) (xy 285.848189 -49.123876)
			(xy 285.817416 -49.170389) (xy 285.780199 -49.211926) (xy 285.737331 -49.247601) (xy 285.689725 -49.276655)
			(xy 285.638396 -49.298467) (xy 285.584439 -49.312573) (xy 285.529002 -49.318673) (xy 285.473268 -49.316636)
			(xy 285.418425 -49.306506) (xy 285.365641 -49.288499) (xy 285.316041 -49.262998) (xy 285.270683 -49.230547)
			(xy 285.230534 -49.191838) (xy 285.196448 -49.147695) (xy 285.169152 -49.09906) (xy 285.149229 -49.046969)
			(xy 285.137103 -48.992532) (xy 285.133032 -48.93691) (xy 282.174543 -48.93691) (xy 282.168861 -48.975522)
			(xy 282.152793 -49.028929) (xy 282.129121 -49.079426) (xy 282.098348 -49.125939) (xy 282.061131 -49.167476)
			(xy 282.018263 -49.203151) (xy 281.970657 -49.232205) (xy 281.919328 -49.254017) (xy 281.865371 -49.268123)
			(xy 281.809934 -49.274223) (xy 281.7542 -49.272186) (xy 281.699357 -49.262056) (xy 281.646573 -49.244049)
			(xy 281.596973 -49.218548) (xy 281.551615 -49.186097) (xy 281.511466 -49.147388) (xy 281.47738 -49.103245)
			(xy 281.450084 -49.05461) (xy 281.430161 -49.002519) (xy 281.418035 -48.948082) (xy 281.413964 -48.89246)
			(xy 280.105681 -48.89246) (xy 280.083405 -48.93998) (xy 280.052632 -48.986493) (xy 280.015415 -49.02803)
			(xy 279.972547 -49.063705) (xy 279.924941 -49.092759) (xy 279.873612 -49.114571) (xy 279.819655 -49.128677)
			(xy 279.764218 -49.134777) (xy 279.708484 -49.13274) (xy 279.653641 -49.12261) (xy 279.600857 -49.104603)
			(xy 279.551257 -49.079102) (xy 279.505899 -49.046651) (xy 279.46575 -49.007942) (xy 279.431664 -48.963799)
			(xy 279.404368 -48.915164) (xy 279.384445 -48.863073) (xy 279.372319 -48.808636) (xy 279.368248 -48.753014)
			(xy 271.397226 -48.753014) (xy 271.802884 -49.95291) (xy 285.133032 -49.95291) (xy 285.137103 -49.897288)
			(xy 285.149229 -49.842851) (xy 285.169152 -49.79076) (xy 285.196448 -49.742125) (xy 285.230534 -49.697982)
			(xy 285.270683 -49.659273) (xy 285.316041 -49.626822) (xy 285.365641 -49.601321) (xy 285.418425 -49.583314)
			(xy 285.473268 -49.573184) (xy 285.529002 -49.571147) (xy 285.584439 -49.577247) (xy 285.638396 -49.591353)
			(xy 285.689725 -49.613165) (xy 285.737331 -49.642219) (xy 285.780199 -49.677894) (xy 285.817416 -49.719431)
			(xy 285.848189 -49.765944) (xy 285.871861 -49.816441) (xy 285.887929 -49.869848) (xy 285.896049 -49.925024)
			(xy 285.896558 -49.95291) (xy 285.896049 -49.980796) (xy 285.887929 -50.035972) (xy 285.871861 -50.089379)
			(xy 285.848189 -50.139876) (xy 285.817416 -50.186389) (xy 285.780199 -50.227926) (xy 285.737331 -50.263601)
			(xy 285.689725 -50.292655) (xy 285.638396 -50.314467) (xy 285.584439 -50.328573) (xy 285.529002 -50.334673)
			(xy 285.473268 -50.332636) (xy 285.418425 -50.322506) (xy 285.365641 -50.304499) (xy 285.316041 -50.278998)
			(xy 285.270683 -50.246547) (xy 285.230534 -50.207838) (xy 285.196448 -50.163695) (xy 285.169152 -50.11506)
			(xy 285.149229 -50.062969) (xy 285.137103 -50.008532) (xy 285.133032 -49.95291) (xy 271.802884 -49.95291)
			(xy 271.831308 -50.036984) (xy 271.845044 -50.079111) (xy 271.865871 -50.165242) (xy 271.878979 -50.252881)
			(xy 271.882108 -50.29708) (xy 271.89303 -50.480214) (xy 271.925028 -51.019456) (xy 282.949394 -51.019456)
			(xy 282.953465 -50.963834) (xy 282.965591 -50.909397) (xy 282.985514 -50.857306) (xy 283.01281 -50.808671)
			(xy 283.046896 -50.764528) (xy 283.087045 -50.725819) (xy 283.132403 -50.693368) (xy 283.182003 -50.667867)
			(xy 283.234787 -50.64986) (xy 283.28963 -50.63973) (xy 283.345364 -50.637693) (xy 283.400801 -50.643793)
			(xy 283.454758 -50.657899) (xy 283.506087 -50.679711) (xy 283.553693 -50.708765) (xy 283.596561 -50.74444)
			(xy 283.633778 -50.785977) (xy 283.664551 -50.83249) (xy 283.688223 -50.882987) (xy 283.704291 -50.936394)
			(xy 283.712411 -50.99157) (xy 283.71292 -51.019456) (xy 283.712411 -51.047342) (xy 283.704291 -51.102518)
			(xy 283.688223 -51.155925) (xy 283.664551 -51.206422) (xy 283.633778 -51.252935) (xy 283.596561 -51.294472)
			(xy 283.553693 -51.330147) (xy 283.506087 -51.359201) (xy 283.454758 -51.381013) (xy 283.400801 -51.395119)
			(xy 283.345364 -51.401219) (xy 283.28963 -51.399182) (xy 283.234787 -51.389052) (xy 283.182003 -51.371045)
			(xy 283.132403 -51.345544) (xy 283.087045 -51.313093) (xy 283.046896 -51.274384) (xy 283.01281 -51.230241)
			(xy 282.985514 -51.181606) (xy 282.965591 -51.129515) (xy 282.953465 -51.075078) (xy 282.949394 -51.019456)
			(xy 271.925028 -51.019456) (xy 271.932654 -51.14798) (xy 271.985608 -52.035456) (xy 285.14116 -52.035456)
			(xy 285.145231 -51.979834) (xy 285.157357 -51.925397) (xy 285.17728 -51.873306) (xy 285.204576 -51.824671)
			(xy 285.238662 -51.780528) (xy 285.278811 -51.741819) (xy 285.324169 -51.709368) (xy 285.373769 -51.683867)
			(xy 285.426553 -51.66586) (xy 285.481396 -51.65573) (xy 285.53713 -51.653693) (xy 285.592567 -51.659793)
			(xy 285.646524 -51.673899) (xy 285.697853 -51.695711) (xy 285.745459 -51.724765) (xy 285.788327 -51.76044)
			(xy 285.825544 -51.801977) (xy 285.856317 -51.84849) (xy 285.879989 -51.898987) (xy 285.896057 -51.952394)
			(xy 285.904177 -52.00757) (xy 285.904686 -52.035456) (xy 285.904177 -52.063342) (xy 285.896057 -52.118518)
			(xy 285.879989 -52.171925) (xy 285.856317 -52.222422) (xy 285.825544 -52.268935) (xy 285.788327 -52.310472)
			(xy 285.745459 -52.346147) (xy 285.697853 -52.375201) (xy 285.646524 -52.397013) (xy 285.592567 -52.411119)
			(xy 285.53713 -52.417219) (xy 285.481396 -52.415182) (xy 285.426553 -52.405052) (xy 285.373769 -52.387045)
			(xy 285.324169 -52.361544) (xy 285.278811 -52.329093) (xy 285.238662 -52.290384) (xy 285.204576 -52.246241)
			(xy 285.17728 -52.197606) (xy 285.157357 -52.145515) (xy 285.145231 -52.091078) (xy 285.14116 -52.035456)
			(xy 271.985608 -52.035456) (xy 272.007584 -52.403756) (xy 272.009862 -52.415114) (xy 272.02296 -52.434192)
			(xy 272.043063 -52.445655) (xy 272.054574 -52.446936) (xy 272.062702 -52.446936) (xy 272.065242 -52.446682)
			(xy 272.102072 -52.444904) (xy 272.129326 -52.445365) (xy 272.183279 -52.453119) (xy 272.23558 -52.468473)
			(xy 272.285163 -52.491114) (xy 272.331018 -52.520581) (xy 272.372213 -52.556275) (xy 272.407909 -52.597469)
			(xy 272.437378 -52.643323) (xy 272.460021 -52.692905) (xy 272.475377 -52.745205) (xy 272.483133 -52.799158)
			(xy 272.48358 -52.826412) (xy 272.483155 -52.851923) (xy 272.476359 -52.902491) (xy 272.46289 -52.951703)
			(xy 272.442988 -52.998684) (xy 272.417007 -53.042596) (xy 272.401538 -53.062886) (xy 272.398998 -53.065934)
			(xy 272.397982 -53.067458) (xy 272.39468 -53.074062) (xy 272.392337 -53.079285) (xy 272.389772 -53.090438)
			(xy 272.3896 -53.09616) (xy 272.3896 -53.128164) (xy 272.378424 -53.128164) (xy 272.378424 -53.178964)
			(xy 272.378759 -53.187567) (xy 272.384473 -53.203797) (xy 272.3896 -53.210714) (xy 272.39087 -53.212238)
			(xy 272.408262 -53.233115) (xy 272.437578 -53.278866) (xy 272.460104 -53.328314) (xy 272.475383 -53.380458)
			(xy 272.483108 -53.434244) (xy 272.48358 -53.461412) (xy 272.483155 -53.486923) (xy 272.476359 -53.537491)
			(xy 272.46289 -53.586703) (xy 272.442988 -53.633684) (xy 272.417007 -53.677596) (xy 272.401538 -53.697886)
			(xy 272.398998 -53.700934) (xy 272.397982 -53.702458) (xy 272.39468 -53.709062) (xy 272.392337 -53.714285)
			(xy 272.389772 -53.725438) (xy 272.3896 -53.73116) (xy 272.3896 -53.763164) (xy 272.378424 -53.763164)
			(xy 272.378424 -53.813964) (xy 272.378759 -53.822567) (xy 272.384473 -53.838797) (xy 272.3896 -53.845714)
			(xy 272.39087 -53.847238) (xy 272.408262 -53.868115) (xy 272.437578 -53.913866) (xy 272.460104 -53.963314)
			(xy 272.475383 -54.015458) (xy 272.483108 -54.069244) (xy 272.48358 -54.096412) (xy 272.483155 -54.121923)
			(xy 272.476359 -54.172491) (xy 272.46289 -54.221703) (xy 272.442988 -54.268684) (xy 272.417007 -54.312596)
			(xy 272.401538 -54.332886) (xy 272.398998 -54.335934) (xy 272.397982 -54.337458) (xy 272.39468 -54.344062)
			(xy 272.392337 -54.349285) (xy 272.389772 -54.360438) (xy 272.3896 -54.36616) (xy 272.3896 -54.398164)
			(xy 272.378424 -54.398164) (xy 272.378424 -54.448964) (xy 272.378759 -54.457567) (xy 272.384473 -54.473797)
			(xy 272.3896 -54.480714) (xy 272.39087 -54.482238) (xy 272.408262 -54.503115) (xy 272.437578 -54.548866)
			(xy 272.460104 -54.598314) (xy 272.475383 -54.650458) (xy 272.483108 -54.704244) (xy 272.48358 -54.731412)
			(xy 272.483115 -54.75877) (xy 272.478454 -54.791102) (xy 274.376388 -54.791102) (xy 274.376858 -54.763732)
			(xy 274.384675 -54.709553) (xy 274.400164 -54.65705) (xy 274.423004 -54.607303) (xy 274.452728 -54.561336)
			(xy 274.470368 -54.540404) (xy 274.470622 -54.54015) (xy 274.476196 -54.533055) (xy 274.48245 -54.516145)
			(xy 274.482814 -54.50713) (xy 274.482814 -54.440074) (xy 274.482466 -54.431056) (xy 274.476212 -54.41414)
			(xy 274.470622 -54.407054) (xy 274.470368 -54.407054) (xy 274.470368 -54.4068) (xy 274.452728 -54.385866)
			(xy 274.423 -54.3399) (xy 274.400152 -54.290154) (xy 274.384653 -54.237652) (xy 274.376824 -54.183472)
			(xy 274.376823 -54.128731) (xy 274.384653 -54.074551) (xy 274.400151 -54.022049) (xy 274.422998 -53.972303)
			(xy 274.452726 -53.926336) (xy 274.470368 -53.905404) (xy 274.470622 -53.90515) (xy 274.476196 -53.898055)
			(xy 274.48245 -53.881145) (xy 274.482814 -53.87213) (xy 274.482814 -53.805074) (xy 274.482466 -53.796056)
			(xy 274.476212 -53.77914) (xy 274.470622 -53.772054) (xy 274.470368 -53.772054) (xy 274.470368 -53.7718)
			(xy 274.452728 -53.750866) (xy 274.423 -53.7049) (xy 274.400152 -53.655154) (xy 274.384653 -53.602652)
			(xy 274.376824 -53.548472) (xy 274.376823 -53.493731) (xy 274.384653 -53.439551) (xy 274.400151 -53.387049)
			(xy 274.422998 -53.337303) (xy 274.452726 -53.291336) (xy 274.470368 -53.270404) (xy 274.470622 -53.27015)
			(xy 274.476196 -53.263055) (xy 274.48245 -53.246145) (xy 274.482814 -53.23713) (xy 274.482814 -53.170074)
			(xy 274.482466 -53.161056) (xy 274.476212 -53.14414) (xy 274.470622 -53.137054) (xy 274.470368 -53.137054)
			(xy 274.470368 -53.1368) (xy 274.45271 -53.115883) (xy 274.423002 -53.069905) (xy 274.400171 -53.020154)
			(xy 274.384684 -52.96765) (xy 274.37686 -52.913472) (xy 274.376388 -52.886102) (xy 274.376874 -52.858851)
			(xy 274.38463 -52.804903) (xy 274.399985 -52.752608) (xy 274.422627 -52.703031) (xy 274.452093 -52.657181)
			(xy 274.487784 -52.61599) (xy 274.528975 -52.580299) (xy 274.574825 -52.550833) (xy 274.624402 -52.528191)
			(xy 274.676697 -52.512836) (xy 274.730645 -52.50508) (xy 274.785147 -52.50508) (xy 274.839095 -52.512836)
			(xy 274.89139 -52.528191) (xy 274.93049 -52.546048) (xy 279.879596 -52.546048) (xy 279.879596 -52.491552)
			(xy 279.887351 -52.437611) (xy 279.902703 -52.385323) (xy 279.925339 -52.335751) (xy 279.9548 -52.289905)
			(xy 279.990484 -52.248718) (xy 280.031667 -52.213029) (xy 280.077509 -52.183563) (xy 280.127078 -52.16092)
			(xy 280.179364 -52.145561) (xy 280.233304 -52.1378) (xy 280.260552 -52.13731) (xy 280.287921 -52.137802)
			(xy 280.342099 -52.145613) (xy 280.394602 -52.161096) (xy 280.44435 -52.183932) (xy 280.490318 -52.213651)
			(xy 280.51125 -52.23129) (xy 280.511504 -52.231544) (xy 280.518581 -52.237144) (xy 280.535505 -52.243381)
			(xy 280.544524 -52.243736) (xy 280.61158 -52.243736) (xy 280.620595 -52.243361) (xy 280.637512 -52.237125)
			(xy 280.6446 -52.231544) (xy 280.6446 -52.23129) (xy 280.644854 -52.23129) (xy 280.665787 -52.213649)
			(xy 280.711755 -52.183925) (xy 280.761501 -52.161079) (xy 280.814003 -52.145583) (xy 280.868181 -52.137754)
			(xy 280.922923 -52.137754) (xy 280.977101 -52.145583) (xy 281.029603 -52.161079) (xy 281.079349 -52.183925)
			(xy 281.125317 -52.213649) (xy 281.14625 -52.23129) (xy 281.146504 -52.231544) (xy 281.153581 -52.237144)
			(xy 281.170505 -52.243381) (xy 281.179524 -52.243736) (xy 281.24658 -52.243736) (xy 281.255595 -52.243361)
			(xy 281.272512 -52.237125) (xy 281.2796 -52.231544) (xy 281.2796 -52.23129) (xy 281.279854 -52.23129)
			(xy 281.300791 -52.213657) (xy 281.346763 -52.183945) (xy 281.396509 -52.161108) (xy 281.449008 -52.145615)
			(xy 281.503183 -52.137785) (xy 281.530552 -52.13731) (xy 281.557808 -52.137734) (xy 281.611767 -52.145485)
			(xy 281.664073 -52.160838) (xy 281.713662 -52.183479) (xy 281.759523 -52.212947) (xy 281.800724 -52.248642)
			(xy 281.836424 -52.289838) (xy 281.865898 -52.335696) (xy 281.888545 -52.385282) (xy 281.903904 -52.437586)
			(xy 281.911663 -52.491544) (xy 281.911663 -52.546056) (xy 281.905718 -52.587398) (xy 282.955236 -52.587398)
			(xy 282.959307 -52.531776) (xy 282.971433 -52.477339) (xy 282.991356 -52.425248) (xy 283.018652 -52.376613)
			(xy 283.052738 -52.33247) (xy 283.092887 -52.293761) (xy 283.138245 -52.26131) (xy 283.187845 -52.235809)
			(xy 283.240629 -52.217802) (xy 283.295472 -52.207672) (xy 283.351206 -52.205635) (xy 283.406643 -52.211735)
			(xy 283.4606 -52.225841) (xy 283.511929 -52.247653) (xy 283.559535 -52.276707) (xy 283.602403 -52.312382)
			(xy 283.63962 -52.353919) (xy 283.670393 -52.400432) (xy 283.694065 -52.450929) (xy 283.710133 -52.504336)
			(xy 283.717729 -52.555948) (xy 290.783802 -52.555948) (xy 290.783802 -52.501452) (xy 290.791557 -52.44751)
			(xy 290.80691 -52.395221) (xy 290.829548 -52.345649) (xy 290.85901 -52.299802) (xy 290.894696 -52.258616)
			(xy 290.93588 -52.222926) (xy 290.981724 -52.193461) (xy 291.031295 -52.17082) (xy 291.083583 -52.155463)
			(xy 291.137524 -52.147704) (xy 291.164772 -52.147216) (xy 291.192142 -52.147695) (xy 291.246321 -52.155509)
			(xy 291.298824 -52.170995) (xy 291.348571 -52.193834) (xy 291.394538 -52.223556) (xy 291.41547 -52.241196)
			(xy 291.415724 -52.24145) (xy 291.422795 -52.247059) (xy 291.439724 -52.253291) (xy 291.448744 -52.253642)
			(xy 291.5158 -52.253642) (xy 291.524818 -52.253297) (xy 291.541736 -52.247043) (xy 291.54882 -52.24145)
			(xy 291.54882 -52.241196) (xy 291.549074 -52.241196) (xy 291.570005 -52.223555) (xy 291.615978 -52.193844)
			(xy 291.665726 -52.171008) (xy 291.718227 -52.155517) (xy 291.772403 -52.14769) (xy 291.799772 -52.147216)
			(xy 291.827028 -52.147629) (xy 291.880985 -52.155383) (xy 291.93329 -52.170738) (xy 291.982877 -52.19338)
			(xy 292.028736 -52.222849) (xy 292.069935 -52.258545) (xy 292.105634 -52.299741) (xy 292.135106 -52.345599)
			(xy 292.157752 -52.395184) (xy 292.173111 -52.447487) (xy 292.180869 -52.501444) (xy 292.180869 -52.555956)
			(xy 292.173111 -52.609913) (xy 292.157752 -52.662216) (xy 292.135106 -52.711801) (xy 292.105634 -52.757659)
			(xy 292.069935 -52.798855) (xy 292.028736 -52.834551) (xy 291.982877 -52.86402) (xy 291.93329 -52.886662)
			(xy 291.880985 -52.902017) (xy 291.827028 -52.909771) (xy 291.799772 -52.910232) (xy 291.7724 -52.909799)
			(xy 291.718219 -52.901976) (xy 291.665715 -52.88648) (xy 291.615969 -52.86363) (xy 291.570004 -52.833897)
			(xy 291.549074 -52.816252) (xy 291.54882 -52.815998) (xy 291.541732 -52.810413) (xy 291.524816 -52.804166)
			(xy 291.5158 -52.803806) (xy 291.448744 -52.803806) (xy 291.439729 -52.804183) (xy 291.422812 -52.810417)
			(xy 291.415724 -52.815998) (xy 291.415724 -52.816252) (xy 291.41547 -52.816252) (xy 291.394516 -52.833864)
			(xy 291.34855 -52.863582) (xy 291.298808 -52.886424) (xy 291.246312 -52.901921) (xy 291.19214 -52.909755)
			(xy 291.164772 -52.910232) (xy 291.137524 -52.909696) (xy 291.083583 -52.901937) (xy 291.031295 -52.88658)
			(xy 290.981724 -52.863939) (xy 290.93588 -52.834474) (xy 290.894696 -52.798784) (xy 290.85901 -52.757598)
			(xy 290.829548 -52.711751) (xy 290.80691 -52.662179) (xy 290.791557 -52.60989) (xy 290.783802 -52.555948)
			(xy 283.717729 -52.555948) (xy 283.718253 -52.559512) (xy 283.718762 -52.587398) (xy 283.718253 -52.615284)
			(xy 283.710133 -52.67046) (xy 283.694065 -52.723867) (xy 283.670393 -52.774364) (xy 283.63962 -52.820877)
			(xy 283.602403 -52.862414) (xy 283.559535 -52.898089) (xy 283.511929 -52.927143) (xy 283.4606 -52.948955)
			(xy 283.406643 -52.963061) (xy 283.351206 -52.969161) (xy 283.295472 -52.967124) (xy 283.240629 -52.956994)
			(xy 283.187845 -52.938987) (xy 283.138245 -52.913486) (xy 283.092887 -52.881035) (xy 283.052738 -52.842326)
			(xy 283.018652 -52.798183) (xy 282.991356 -52.749548) (xy 282.971433 -52.697457) (xy 282.959307 -52.64302)
			(xy 282.955236 -52.587398) (xy 281.905718 -52.587398) (xy 281.903904 -52.600014) (xy 281.888545 -52.652318)
			(xy 281.865898 -52.701904) (xy 281.836424 -52.747762) (xy 281.800724 -52.788958) (xy 281.759523 -52.824653)
			(xy 281.713662 -52.854121) (xy 281.664073 -52.876762) (xy 281.611767 -52.892115) (xy 281.557808 -52.899866)
			(xy 281.530552 -52.900326) (xy 281.503182 -52.899847) (xy 281.449003 -52.892035) (xy 281.396499 -52.87655)
			(xy 281.346752 -52.853711) (xy 281.300785 -52.823987) (xy 281.279854 -52.806346) (xy 281.2796 -52.806092)
			(xy 281.272518 -52.800498) (xy 281.255598 -52.794256) (xy 281.24658 -52.7939) (xy 281.179524 -52.7939)
			(xy 281.170508 -52.794268) (xy 281.153591 -52.800508) (xy 281.146504 -52.806092) (xy 281.14625 -52.806346)
			(xy 281.125317 -52.823987) (xy 281.079349 -52.853711) (xy 281.029603 -52.876557) (xy 280.977101 -52.892053)
			(xy 280.922923 -52.899882) (xy 280.868181 -52.899882) (xy 280.814003 -52.892053) (xy 280.761501 -52.876557)
			(xy 280.711755 -52.853711) (xy 280.665787 -52.823987) (xy 280.644854 -52.806346) (xy 280.6446 -52.806092)
			(xy 280.637518 -52.800498) (xy 280.620598 -52.794256) (xy 280.61158 -52.7939) (xy 280.544524 -52.7939)
			(xy 280.535508 -52.794268) (xy 280.518591 -52.800508) (xy 280.511504 -52.806092) (xy 280.511504 -52.806346)
			(xy 280.51125 -52.806346) (xy 280.490303 -52.823967) (xy 280.444335 -52.853683) (xy 280.394592 -52.876524)
			(xy 280.342094 -52.892019) (xy 280.28792 -52.89985) (xy 280.260552 -52.900326) (xy 280.233304 -52.8998)
			(xy 280.179364 -52.892039) (xy 280.127078 -52.87668) (xy 280.077509 -52.854037) (xy 280.031667 -52.824571)
			(xy 279.990484 -52.788882) (xy 279.9548 -52.747695) (xy 279.925339 -52.701849) (xy 279.902703 -52.652277)
			(xy 279.887351 -52.599989) (xy 279.879596 -52.546048) (xy 274.93049 -52.546048) (xy 274.940967 -52.550833)
			(xy 274.986817 -52.580299) (xy 275.028008 -52.61599) (xy 275.063699 -52.657181) (xy 275.093165 -52.703031)
			(xy 275.115807 -52.752608) (xy 275.131162 -52.804903) (xy 275.138918 -52.858851) (xy 275.139404 -52.886102)
			(xy 275.138938 -52.913472) (xy 275.13112 -52.967651) (xy 275.115631 -53.020154) (xy 275.092789 -53.069901)
			(xy 275.063065 -53.115868) (xy 275.045424 -53.1368) (xy 275.04517 -53.137054) (xy 275.039593 -53.144147)
			(xy 275.033342 -53.161059) (xy 275.032978 -53.170074) (xy 275.032978 -53.23713) (xy 275.033325 -53.246148)
			(xy 275.03958 -53.263064) (xy 275.04517 -53.27015) (xy 275.045424 -53.27015) (xy 275.045424 -53.270404)
			(xy 275.063069 -53.291334) (xy 275.092797 -53.337301) (xy 275.115645 -53.387048) (xy 275.131144 -53.43955)
			(xy 275.138973 -53.49373) (xy 275.138973 -53.548473) (xy 275.131143 -53.602652) (xy 275.115644 -53.655155)
			(xy 275.092796 -53.704901) (xy 275.063067 -53.750868) (xy 275.046494 -53.77053) (xy 275.410676 -53.77053)
			(xy 275.411187 -53.741612) (xy 275.419913 -53.68444) (xy 275.437171 -53.629239) (xy 275.462564 -53.577277)
			(xy 275.49551 -53.529744) (xy 275.535255 -53.487729) (xy 275.557742 -53.46954) (xy 275.566528 -53.461913)
			(xy 275.576721 -53.441027) (xy 275.5773 -53.429408) (xy 275.5773 -53.349652) (xy 275.576774 -53.338018)
			(xy 275.566576 -53.317109) (xy 275.557742 -53.30952) (xy 275.535277 -53.291307) (xy 275.495539 -53.249293)
			(xy 275.462596 -53.201763) (xy 275.437204 -53.149806) (xy 275.419945 -53.094612) (xy 275.411212 -53.037445)
			(xy 275.410676 -53.00853) (xy 275.411183 -52.981279) (xy 275.418936 -52.92733) (xy 275.434287 -52.875034)
			(xy 275.456925 -52.825455) (xy 275.486388 -52.779603) (xy 275.522077 -52.73841) (xy 275.563266 -52.702716)
			(xy 275.609115 -52.673247) (xy 275.658691 -52.650603) (xy 275.710985 -52.635245) (xy 275.764933 -52.627486)
			(xy 275.792184 -52.627022) (xy 275.818498 -52.627493) (xy 275.870627 -52.634726) (xy 275.921269 -52.649044)
			(xy 275.969469 -52.670176) (xy 276.014312 -52.697722) (xy 276.054952 -52.73116) (xy 276.073108 -52.750212)
			(xy 276.080623 -52.757621) (xy 276.099908 -52.766141) (xy 276.110446 -52.766722) (xy 276.185122 -52.766722)
			(xy 276.195667 -52.766158) (xy 276.214963 -52.757647) (xy 276.22246 -52.750212) (xy 276.240596 -52.731137)
			(xy 276.281229 -52.697681) (xy 276.326074 -52.670124) (xy 276.374279 -52.648989) (xy 276.42493 -52.634676)
			(xy 276.477067 -52.627457) (xy 276.503384 -52.627022) (xy 276.530638 -52.62747) (xy 276.584591 -52.635226)
			(xy 276.636891 -52.650581) (xy 276.686473 -52.673224) (xy 276.732328 -52.702693) (xy 276.773521 -52.738389)
			(xy 276.809215 -52.779584) (xy 276.838683 -52.825439) (xy 276.861324 -52.875022) (xy 276.876677 -52.927323)
			(xy 276.884431 -52.981276) (xy 276.884892 -53.00853) (xy 276.884407 -53.036196) (xy 276.882176 -53.051456)
			(xy 285.14116 -53.051456) (xy 285.145231 -52.995834) (xy 285.157357 -52.941397) (xy 285.17728 -52.889306)
			(xy 285.204576 -52.840671) (xy 285.238662 -52.796528) (xy 285.278811 -52.757819) (xy 285.324169 -52.725368)
			(xy 285.373769 -52.699867) (xy 285.426553 -52.68186) (xy 285.481396 -52.67173) (xy 285.53713 -52.669693)
			(xy 285.592567 -52.675793) (xy 285.646524 -52.689899) (xy 285.697853 -52.711711) (xy 285.745459 -52.740765)
			(xy 285.788327 -52.77644) (xy 285.825544 -52.817977) (xy 285.856317 -52.86449) (xy 285.879989 -52.914987)
			(xy 285.896057 -52.968394) (xy 285.904177 -53.02357) (xy 285.904686 -53.051456) (xy 285.904177 -53.079342)
			(xy 285.896057 -53.134518) (xy 285.879989 -53.187925) (xy 285.856317 -53.238422) (xy 285.825544 -53.284935)
			(xy 285.788327 -53.326472) (xy 285.745459 -53.362147) (xy 285.697853 -53.391201) (xy 285.646524 -53.413013)
			(xy 285.592567 -53.427119) (xy 285.53713 -53.433219) (xy 285.481396 -53.431182) (xy 285.426553 -53.421052)
			(xy 285.373769 -53.403045) (xy 285.324169 -53.377544) (xy 285.278811 -53.345093) (xy 285.238662 -53.306384)
			(xy 285.204576 -53.262241) (xy 285.17728 -53.213606) (xy 285.157357 -53.161515) (xy 285.145231 -53.107078)
			(xy 285.14116 -53.051456) (xy 276.882176 -53.051456) (xy 276.876403 -53.090947) (xy 276.860582 -53.143969)
			(xy 276.837275 -53.194153) (xy 276.806969 -53.240449) (xy 276.7703 -53.281886) (xy 276.728035 -53.317598)
			(xy 276.704806 -53.332634) (xy 276.695126 -53.339267) (xy 276.682681 -53.35913) (xy 276.68093 -53.370734)
			(xy 276.673056 -53.450744) (xy 276.672403 -53.462383) (xy 276.680498 -53.484222) (xy 276.68855 -53.492654)
			(xy 276.688804 -53.492908) (xy 276.707372 -53.511002) (xy 276.739952 -53.551331) (xy 276.766766 -53.595703)
			(xy 276.787321 -53.643299) (xy 276.801238 -53.693241) (xy 276.808258 -53.744608) (xy 276.808692 -53.77053)
			(xy 276.80825 -53.797783) (xy 276.800489 -53.851733) (xy 276.785129 -53.904029) (xy 276.762483 -53.953608)
			(xy 276.733013 -53.999459) (xy 276.697317 -54.040649) (xy 276.656122 -54.07634) (xy 276.610267 -54.105806)
			(xy 276.560686 -54.128445) (xy 276.508388 -54.143799) (xy 276.454437 -54.151553) (xy 276.427184 -54.152038)
			(xy 276.399813 -54.151596) (xy 276.345632 -54.143775) (xy 276.293128 -54.128281) (xy 276.243381 -54.105433)
			(xy 276.197416 -54.075703) (xy 276.176486 -54.058058) (xy 276.176232 -54.057804) (xy 276.16914 -54.052225)
			(xy 276.152227 -54.045974) (xy 276.143212 -54.045612) (xy 276.076156 -54.045612) (xy 276.067142 -54.045993)
			(xy 276.050224 -54.052224) (xy 276.043136 -54.057804) (xy 276.043136 -54.058058) (xy 276.042882 -54.058058)
			(xy 276.021924 -54.075666) (xy 275.975959 -54.105384) (xy 275.926218 -54.128226) (xy 275.873723 -54.143725)
			(xy 275.819552 -54.15156) (xy 275.792184 -54.152038) (xy 275.764934 -54.151537) (xy 275.710988 -54.143779)
			(xy 275.658695 -54.128424) (xy 275.60912 -54.105783) (xy 275.563271 -54.076318) (xy 275.522082 -54.040628)
			(xy 275.486391 -53.99944) (xy 275.456924 -53.953592) (xy 275.434281 -53.904018) (xy 275.418924 -53.851726)
			(xy 275.411164 -53.79778) (xy 275.410676 -53.77053) (xy 275.046494 -53.77053) (xy 275.045424 -53.7718)
			(xy 275.04517 -53.772054) (xy 275.039593 -53.779147) (xy 275.033342 -53.796059) (xy 275.032978 -53.805074)
			(xy 275.032978 -53.87213) (xy 275.033325 -53.881148) (xy 275.03958 -53.898064) (xy 275.04517 -53.90515)
			(xy 275.045424 -53.90515) (xy 275.045424 -53.905404) (xy 275.063069 -53.926334) (xy 275.092797 -53.972301)
			(xy 275.115645 -54.022048) (xy 275.131144 -54.07455) (xy 275.138973 -54.12873) (xy 275.138973 -54.183473)
			(xy 275.131143 -54.237652) (xy 275.115644 -54.290155) (xy 275.101851 -54.320186) (xy 277.330408 -54.320186)
			(xy 277.330864 -54.292815) (xy 277.338684 -54.238636) (xy 277.354175 -54.186132) (xy 277.377019 -54.136386)
			(xy 277.406746 -54.090419) (xy 277.424388 -54.069488) (xy 277.424642 -54.069234) (xy 277.430226 -54.062146)
			(xy 277.436473 -54.04523) (xy 277.436834 -54.036214) (xy 277.436834 -53.969158) (xy 277.436442 -53.960145)
			(xy 277.430218 -53.943228) (xy 277.424642 -53.936138) (xy 277.424388 -53.936138) (xy 277.424388 -53.935884)
			(xy 277.406773 -53.914933) (xy 277.377058 -53.868965) (xy 277.354218 -53.819222) (xy 277.338721 -53.766726)
			(xy 277.330886 -53.712554) (xy 277.330408 -53.685186) (xy 277.330894 -53.657935) (xy 277.33865 -53.603987)
			(xy 277.354005 -53.551692) (xy 277.376647 -53.502115) (xy 277.406113 -53.456265) (xy 277.441804 -53.415074)
			(xy 277.482995 -53.379383) (xy 277.528845 -53.349917) (xy 277.578422 -53.327275) (xy 277.630717 -53.31192)
			(xy 277.684665 -53.304164) (xy 277.739167 -53.304164) (xy 277.793115 -53.31192) (xy 277.84541 -53.327275)
			(xy 277.894987 -53.349917) (xy 277.940837 -53.379383) (xy 277.982028 -53.415074) (xy 278.017719 -53.456265)
			(xy 278.043612 -53.496555) (xy 290.333341 -53.496555) (xy 290.333341 -53.442045) (xy 290.341099 -53.388089)
			(xy 290.356457 -53.335787) (xy 290.379103 -53.286203) (xy 290.408575 -53.240347) (xy 290.444273 -53.199152)
			(xy 290.485471 -53.163457) (xy 290.531329 -53.133988) (xy 290.580915 -53.111347) (xy 290.633219 -53.095993)
			(xy 290.687175 -53.088239) (xy 290.71443 -53.087778) (xy 290.741802 -53.088207) (xy 290.795983 -53.096031)
			(xy 290.848487 -53.111528) (xy 290.898234 -53.134378) (xy 290.944198 -53.164112) (xy 290.965128 -53.181758)
			(xy 290.965382 -53.182012) (xy 290.972469 -53.187599) (xy 290.989385 -53.193845) (xy 290.998402 -53.194204)
			(xy 291.065458 -53.194204) (xy 291.074473 -53.193826) (xy 291.09139 -53.187593) (xy 291.098478 -53.182012)
			(xy 291.098478 -53.181758) (xy 291.098732 -53.181758) (xy 291.119673 -53.16413) (xy 291.165644 -53.134418)
			(xy 291.215389 -53.111581) (xy 291.267888 -53.096087) (xy 291.322062 -53.088254) (xy 291.34943 -53.087778)
			(xy 291.376679 -53.088294) (xy 291.430621 -53.096054) (xy 291.48291 -53.111411) (xy 291.532482 -53.134053)
			(xy 291.578327 -53.163519) (xy 291.619512 -53.199209) (xy 291.655199 -53.240397) (xy 291.684661 -53.286244)
			(xy 291.707299 -53.335818) (xy 291.722652 -53.388108) (xy 291.730408 -53.442051) (xy 291.730408 -53.496549)
			(xy 291.722652 -53.550492) (xy 291.707299 -53.602782) (xy 291.684661 -53.652356) (xy 291.655199 -53.698203)
			(xy 291.619512 -53.739391) (xy 291.578327 -53.775081) (xy 291.532482 -53.804547) (xy 291.48291 -53.827189)
			(xy 291.430621 -53.842546) (xy 291.376679 -53.850306) (xy 291.34943 -53.850794) (xy 291.32206 -53.850312)
			(xy 291.267882 -53.842498) (xy 291.215379 -53.827013) (xy 291.165632 -53.804175) (xy 291.119664 -53.774454)
			(xy 291.098732 -53.756814) (xy 291.098478 -53.75656) (xy 291.091405 -53.750953) (xy 291.074478 -53.74472)
			(xy 291.065458 -53.744368) (xy 290.998402 -53.744368) (xy 290.989386 -53.744733) (xy 290.97247 -53.750976)
			(xy 290.965382 -53.75656) (xy 290.965382 -53.756814) (xy 290.965128 -53.756814) (xy 290.944198 -53.774456)
			(xy 290.898224 -53.804167) (xy 290.848476 -53.827002) (xy 290.795975 -53.842492) (xy 290.741799 -53.85032)
			(xy 290.71443 -53.850794) (xy 290.687175 -53.850361) (xy 290.633219 -53.842607) (xy 290.580915 -53.827253)
			(xy 290.531329 -53.804612) (xy 290.485471 -53.775143) (xy 290.444273 -53.739448) (xy 290.408575 -53.698253)
			(xy 290.379103 -53.652397) (xy 290.356457 -53.602813) (xy 290.341099 -53.550511) (xy 290.333341 -53.496555)
			(xy 278.043612 -53.496555) (xy 278.047185 -53.502115) (xy 278.069827 -53.551692) (xy 278.085182 -53.603987)
			(xy 278.092938 -53.657935) (xy 278.093424 -53.685186) (xy 278.092968 -53.712557) (xy 278.085151 -53.766737)
			(xy 278.06966 -53.819241) (xy 278.046816 -53.868988) (xy 278.017087 -53.914953) (xy 277.999444 -53.935884)
			(xy 277.99919 -53.936138) (xy 277.993622 -53.943237) (xy 277.987365 -53.960144) (xy 277.986998 -53.969158)
			(xy 277.986998 -54.036214) (xy 277.987349 -54.045231) (xy 277.993601 -54.062148) (xy 277.99919 -54.069234)
			(xy 277.999444 -54.069234) (xy 277.999444 -54.069488) (xy 278.017098 -54.090408) (xy 278.046806 -54.136385)
			(xy 278.069639 -54.186135) (xy 278.085127 -54.238638) (xy 278.092952 -54.292816) (xy 278.093424 -54.320186)
			(xy 278.092938 -54.347437) (xy 278.085182 -54.401385) (xy 278.069827 -54.45368) (xy 278.047185 -54.503257)
			(xy 278.017719 -54.549107) (xy 277.982028 -54.590298) (xy 277.940837 -54.625989) (xy 277.894987 -54.655455)
			(xy 277.84541 -54.678097) (xy 277.793115 -54.693452) (xy 277.739167 -54.701208) (xy 277.684665 -54.701208)
			(xy 277.630717 -54.693452) (xy 277.578422 -54.678097) (xy 277.528845 -54.655455) (xy 277.482995 -54.625989)
			(xy 277.441804 -54.590298) (xy 277.406113 -54.549107) (xy 277.376647 -54.503257) (xy 277.354005 -54.45368)
			(xy 277.33865 -54.401385) (xy 277.330894 -54.347437) (xy 277.330408 -54.320186) (xy 275.101851 -54.320186)
			(xy 275.092796 -54.339901) (xy 275.063067 -54.385868) (xy 275.045424 -54.4068) (xy 275.04517 -54.407054)
			(xy 275.039593 -54.414147) (xy 275.033342 -54.431059) (xy 275.032978 -54.440074) (xy 275.032978 -54.50713)
			(xy 275.033325 -54.516148) (xy 275.03958 -54.533064) (xy 275.04517 -54.54015) (xy 275.045424 -54.54015)
			(xy 275.045424 -54.540404) (xy 275.063082 -54.561321) (xy 275.09279 -54.607298) (xy 275.115622 -54.65705)
			(xy 275.131109 -54.709553) (xy 275.138932 -54.763732) (xy 275.139049 -54.770528) (xy 278.27097 -54.770528)
			(xy 278.271435 -54.743158) (xy 278.279251 -54.688978) (xy 278.294739 -54.636474) (xy 278.317581 -54.586727)
			(xy 278.347308 -54.540761) (xy 278.36495 -54.51983) (xy 278.365204 -54.519576) (xy 278.370807 -54.512501)
			(xy 278.377044 -54.495575) (xy 278.377396 -54.486556) (xy 278.377396 -54.4195) (xy 278.37704 -54.410483)
			(xy 278.370792 -54.393566) (xy 278.365204 -54.38648) (xy 278.36495 -54.38648) (xy 278.36495 -54.386226)
			(xy 278.347317 -54.365289) (xy 278.317603 -54.319318) (xy 278.294765 -54.269572) (xy 278.279272 -54.217072)
			(xy 278.271444 -54.162897) (xy 278.27097 -54.135528) (xy 278.271456 -54.108277) (xy 278.279212 -54.054329)
			(xy 278.294567 -54.002034) (xy 278.317209 -53.952457) (xy 278.346675 -53.906607) (xy 278.382366 -53.865416)
			(xy 278.423557 -53.829725) (xy 278.469407 -53.800259) (xy 278.518984 -53.777617) (xy 278.571279 -53.762262)
			(xy 278.625227 -53.754506) (xy 278.679729 -53.754506) (xy 278.733677 -53.762262) (xy 278.785972 -53.777617)
			(xy 278.835549 -53.800259) (xy 278.881399 -53.829725) (xy 278.92259 -53.865416) (xy 278.958281 -53.906607)
			(xy 278.987747 -53.952457) (xy 278.992822 -53.96357) (xy 282.972 -53.96357) (xy 282.976071 -53.907948)
			(xy 282.988197 -53.853511) (xy 283.00812 -53.80142) (xy 283.035416 -53.752785) (xy 283.069502 -53.708642)
			(xy 283.109651 -53.669933) (xy 283.155009 -53.637482) (xy 283.204609 -53.611981) (xy 283.257393 -53.593974)
			(xy 283.312236 -53.583844) (xy 283.36797 -53.581807) (xy 283.423407 -53.587907) (xy 283.477364 -53.602013)
			(xy 283.528693 -53.623825) (xy 283.576299 -53.652879) (xy 283.619167 -53.688554) (xy 283.656384 -53.730091)
			(xy 283.687157 -53.776604) (xy 283.710829 -53.827101) (xy 283.726897 -53.880508) (xy 283.735017 -53.935684)
			(xy 283.735526 -53.96357) (xy 283.735017 -53.991456) (xy 283.726897 -54.046632) (xy 283.710829 -54.100039)
			(xy 283.687157 -54.150536) (xy 283.656384 -54.197049) (xy 283.619167 -54.238586) (xy 283.576299 -54.274261)
			(xy 283.528693 -54.303315) (xy 283.477364 -54.325127) (xy 283.423407 -54.339233) (xy 283.36797 -54.345333)
			(xy 283.312236 -54.343296) (xy 283.257393 -54.333166) (xy 283.204609 -54.315159) (xy 283.155009 -54.289658)
			(xy 283.109651 -54.257207) (xy 283.069502 -54.218498) (xy 283.035416 -54.174355) (xy 283.00812 -54.12572)
			(xy 282.988197 -54.073629) (xy 282.976071 -54.019192) (xy 282.972 -53.96357) (xy 278.992822 -53.96357)
			(xy 279.010389 -54.002034) (xy 279.025744 -54.054329) (xy 279.0335 -54.108277) (xy 279.033986 -54.135528)
			(xy 279.03354 -54.162899) (xy 279.025718 -54.217079) (xy 279.010224 -54.269583) (xy 278.987378 -54.319329)
			(xy 278.957649 -54.365295) (xy 278.940006 -54.386226) (xy 278.939752 -54.38648) (xy 278.934162 -54.393564)
			(xy 278.927919 -54.410483) (xy 278.92756 -54.4195) (xy 278.92756 -54.486556) (xy 278.927925 -54.495572)
			(xy 278.934166 -54.51249) (xy 278.939752 -54.519576) (xy 278.940006 -54.519576) (xy 278.940006 -54.51983)
			(xy 278.957627 -54.540777) (xy 278.987341 -54.586746) (xy 279.01018 -54.636489) (xy 279.025676 -54.688987)
			(xy 279.033509 -54.74316) (xy 279.033986 -54.770528) (xy 279.0335 -54.797779) (xy 279.025744 -54.851727)
			(xy 279.010389 -54.904022) (xy 278.987747 -54.953599) (xy 278.964961 -54.989055) (xy 288.100945 -54.989055)
			(xy 288.100945 -54.934545) (xy 288.108703 -54.880591) (xy 288.12406 -54.82829) (xy 288.146705 -54.778707)
			(xy 288.176176 -54.732851) (xy 288.211874 -54.691657) (xy 288.25307 -54.655962) (xy 288.298928 -54.626494)
			(xy 288.348512 -54.603852) (xy 288.400814 -54.588498) (xy 288.454769 -54.580743) (xy 288.482024 -54.580282)
			(xy 288.510116 -54.580758) (xy 288.565694 -54.588988) (xy 288.619464 -54.605283) (xy 288.670261 -54.629289)
			(xy 288.716988 -54.660486) (xy 288.758632 -54.698201) (xy 288.794294 -54.741616) (xy 288.809176 -54.765448)
			(xy 288.81451 -54.774338) (xy 288.831528 -54.78653) (xy 288.924746 -54.80685) (xy 288.94532 -54.802532)
			(xy 288.953956 -54.79669) (xy 288.97803 -54.780705) (xy 289.029958 -54.755359) (xy 289.085113 -54.73813)
			(xy 289.142234 -54.729409) (xy 289.171126 -54.728872) (xy 289.198377 -54.729354) (xy 289.252324 -54.737113)
			(xy 289.304617 -54.752471) (xy 289.354193 -54.775113) (xy 289.400043 -54.80458) (xy 289.441232 -54.840272)
			(xy 289.476923 -54.881462) (xy 289.50639 -54.927312) (xy 289.529032 -54.976888) (xy 289.544388 -55.029182)
			(xy 289.552147 -55.083129) (xy 289.552634 -55.11038) (xy 289.552172 -55.137751) (xy 289.544356 -55.19193)
			(xy 289.528867 -55.244434) (xy 289.506024 -55.294181) (xy 289.476297 -55.340147) (xy 289.458654 -55.361078)
			(xy 289.4584 -55.361332) (xy 289.452836 -55.368434) (xy 289.446576 -55.385339) (xy 289.446208 -55.394352)
			(xy 289.446208 -55.461408) (xy 289.446559 -55.470425) (xy 289.452811 -55.487342) (xy 289.4584 -55.494428)
			(xy 289.458654 -55.494428) (xy 289.458654 -55.494682) (xy 289.476276 -55.51563) (xy 289.506003 -55.561595)
			(xy 289.528851 -55.611338) (xy 289.544349 -55.663838) (xy 289.55218 -55.718015) (xy 289.552182 -55.772755)
			(xy 289.544356 -55.826932) (xy 289.528861 -55.879433) (xy 289.506017 -55.929179) (xy 289.476294 -55.975146)
			(xy 289.458654 -55.996078) (xy 289.4584 -55.996332) (xy 289.452836 -56.003434) (xy 289.446576 -56.020339)
			(xy 289.446208 -56.029352) (xy 289.446208 -56.096408) (xy 289.446559 -56.105425) (xy 289.452811 -56.122342)
			(xy 289.4584 -56.129428) (xy 289.458654 -56.129428) (xy 289.458654 -56.129682) (xy 289.476291 -56.150616)
			(xy 289.506005 -56.196588) (xy 289.528842 -56.246334) (xy 289.544333 -56.298835) (xy 289.552161 -56.353011)
			(xy 289.552634 -56.38038) (xy 289.552148 -56.407631) (xy 289.544392 -56.461579) (xy 289.529037 -56.513874)
			(xy 289.506395 -56.563451) (xy 289.476929 -56.609301) (xy 289.441238 -56.650492) (xy 289.400047 -56.686183)
			(xy 289.354197 -56.715649) (xy 289.30462 -56.738291) (xy 289.252325 -56.753646) (xy 289.198377 -56.761402)
			(xy 289.143875 -56.761402) (xy 289.089927 -56.753646) (xy 289.037632 -56.738291) (xy 288.988055 -56.715649)
			(xy 288.942205 -56.686183) (xy 288.901014 -56.650492) (xy 288.865323 -56.609301) (xy 288.835857 -56.563451)
			(xy 288.813215 -56.513874) (xy 288.79786 -56.461579) (xy 288.790104 -56.407631) (xy 288.789618 -56.38038)
			(xy 288.790068 -56.353009) (xy 288.797889 -56.298829) (xy 288.813382 -56.246326) (xy 288.836227 -56.196579)
			(xy 288.865955 -56.150613) (xy 288.883598 -56.129682) (xy 288.883852 -56.129428) (xy 288.889439 -56.122342)
			(xy 288.895684 -56.105425) (xy 288.896044 -56.096408) (xy 288.896044 -56.029352) (xy 288.895674 -56.020336)
			(xy 288.889437 -56.003418) (xy 288.883852 -55.996332) (xy 288.883598 -55.996332) (xy 288.883598 -55.996078)
			(xy 288.865939 -55.975161) (xy 288.836217 -55.929189) (xy 288.813375 -55.87944) (xy 288.797881 -55.826936)
			(xy 288.790055 -55.772756) (xy 288.790057 -55.718014) (xy 288.797888 -55.663834) (xy 288.813385 -55.611331)
			(xy 288.836232 -55.561584) (xy 288.865957 -55.515615) (xy 288.883598 -55.494682) (xy 288.883852 -55.494428)
			(xy 288.889439 -55.487342) (xy 288.895684 -55.470425) (xy 288.896044 -55.461408) (xy 288.896044 -55.394352)
			(xy 288.895674 -55.385336) (xy 288.889437 -55.368418) (xy 288.883852 -55.361332) (xy 288.883598 -55.360824)
			(xy 288.872654 -55.348089) (xy 288.852813 -55.320998) (xy 288.843974 -55.306722) (xy 288.83864 -55.297832)
			(xy 288.821622 -55.28564) (xy 288.728404 -55.26532) (xy 288.70783 -55.269638) (xy 288.699194 -55.27548)
			(xy 288.675132 -55.291483) (xy 288.6232 -55.316825) (xy 288.568041 -55.33405) (xy 288.510917 -55.342764)
			(xy 288.482024 -55.343298) (xy 288.454769 -55.342857) (xy 288.400814 -55.335102) (xy 288.348512 -55.319748)
			(xy 288.298928 -55.297106) (xy 288.25307 -55.267638) (xy 288.211874 -55.231943) (xy 288.176176 -55.190749)
			(xy 288.146705 -55.144893) (xy 288.12406 -55.09531) (xy 288.108703 -55.043009) (xy 288.100945 -54.989055)
			(xy 278.964961 -54.989055) (xy 278.958281 -54.999449) (xy 278.92259 -55.04064) (xy 278.881399 -55.076331)
			(xy 278.835549 -55.105797) (xy 278.785972 -55.128439) (xy 278.733677 -55.143794) (xy 278.679729 -55.15155)
			(xy 278.625227 -55.15155) (xy 278.571279 -55.143794) (xy 278.518984 -55.128439) (xy 278.469407 -55.105797)
			(xy 278.423557 -55.076331) (xy 278.382366 -55.04064) (xy 278.346675 -54.999449) (xy 278.317209 -54.953599)
			(xy 278.294567 -54.904022) (xy 278.279212 -54.851727) (xy 278.271456 -54.797779) (xy 278.27097 -54.770528)
			(xy 275.139049 -54.770528) (xy 275.139404 -54.791102) (xy 275.138918 -54.818353) (xy 275.131162 -54.872301)
			(xy 275.115807 -54.924596) (xy 275.093165 -54.974173) (xy 275.063699 -55.020023) (xy 275.028008 -55.061214)
			(xy 274.986817 -55.096905) (xy 274.940967 -55.126371) (xy 274.89139 -55.149013) (xy 274.839095 -55.164368)
			(xy 274.785147 -55.172124) (xy 274.730645 -55.172124) (xy 274.676697 -55.164368) (xy 274.624402 -55.149013)
			(xy 274.574825 -55.126371) (xy 274.528975 -55.096905) (xy 274.487784 -55.061214) (xy 274.452093 -55.020023)
			(xy 274.422627 -54.974173) (xy 274.399985 -54.924596) (xy 274.38463 -54.872301) (xy 274.376874 -54.818353)
			(xy 274.376388 -54.791102) (xy 272.478454 -54.791102) (xy 272.475308 -54.812927) (xy 272.459842 -54.865412)
			(xy 272.437033 -54.915148) (xy 272.407351 -54.961114) (xy 272.371405 -55.002366) (xy 272.329932 -55.038058)
			(xy 272.283785 -55.067457) (xy 272.233909 -55.089959) (xy 272.207736 -55.097934) (xy 272.204942 -55.098696)
			(xy 272.195262 -55.102596) (xy 272.179923 -55.116716) (xy 272.171472 -55.135774) (xy 272.170906 -55.146194)
			(xy 272.205216 -55.722266) (xy 284.033974 -55.722266) (xy 284.038045 -55.666644) (xy 284.050171 -55.612207)
			(xy 284.070094 -55.560116) (xy 284.09739 -55.511481) (xy 284.131476 -55.467338) (xy 284.171625 -55.428629)
			(xy 284.216983 -55.396178) (xy 284.266583 -55.370677) (xy 284.319367 -55.35267) (xy 284.37421 -55.34254)
			(xy 284.429944 -55.340503) (xy 284.485381 -55.346603) (xy 284.539338 -55.360709) (xy 284.590667 -55.382521)
			(xy 284.638273 -55.411575) (xy 284.649424 -55.420855) (xy 286.424545 -55.420855) (xy 286.424545 -55.366345)
			(xy 286.432303 -55.312391) (xy 286.44766 -55.26009) (xy 286.470305 -55.210507) (xy 286.499776 -55.164651)
			(xy 286.535474 -55.123457) (xy 286.57667 -55.087762) (xy 286.622528 -55.058294) (xy 286.672112 -55.035652)
			(xy 286.724414 -55.020298) (xy 286.778369 -55.012543) (xy 286.805624 -55.012082) (xy 286.831938 -55.012539)
			(xy 286.884067 -55.019777) (xy 286.93471 -55.034098) (xy 286.982908 -55.055233) (xy 287.027752 -55.08278)
			(xy 287.068391 -55.11622) (xy 287.086548 -55.135272) (xy 287.094053 -55.142693) (xy 287.113346 -55.151207)
			(xy 287.123886 -55.151782) (xy 287.198562 -55.151782) (xy 287.209112 -55.151251) (xy 287.228407 -55.142718)
			(xy 287.2359 -55.135272) (xy 287.254057 -55.116218) (xy 287.294687 -55.082762) (xy 287.339527 -55.055203)
			(xy 287.387728 -55.034065) (xy 287.438375 -55.019747) (xy 287.490508 -55.012521) (xy 287.516824 -55.012082)
			(xy 287.544073 -55.01259) (xy 287.598017 -55.020349) (xy 287.650307 -55.035706) (xy 287.69988 -55.058348)
			(xy 287.745726 -55.087814) (xy 287.786913 -55.123504) (xy 287.822601 -55.164693) (xy 287.852064 -55.210541)
			(xy 287.874703 -55.260115) (xy 287.890056 -55.312406) (xy 287.897812 -55.366351) (xy 287.897812 -55.420849)
			(xy 287.890056 -55.474794) (xy 287.874703 -55.527085) (xy 287.852064 -55.576659) (xy 287.822601 -55.622507)
			(xy 287.786913 -55.663696) (xy 287.745726 -55.699386) (xy 287.69988 -55.728852) (xy 287.650307 -55.751494)
			(xy 287.598017 -55.766851) (xy 287.544073 -55.77461) (xy 287.516824 -55.775098) (xy 287.490511 -55.774615)
			(xy 287.438383 -55.767384) (xy 287.38774 -55.753068) (xy 287.339541 -55.731938) (xy 287.294697 -55.704395)
			(xy 287.254057 -55.670958) (xy 287.2359 -55.651908) (xy 287.228379 -55.644506) (xy 287.209099 -55.635981)
			(xy 287.198562 -55.635398) (xy 287.123886 -55.635398) (xy 287.113334 -55.635907) (xy 287.094039 -55.644456)
			(xy 287.086548 -55.651908) (xy 287.068412 -55.670983) (xy 287.027778 -55.704438) (xy 286.982934 -55.731995)
			(xy 286.934729 -55.75313) (xy 286.884078 -55.767443) (xy 286.831941 -55.774662) (xy 286.805624 -55.775098)
			(xy 286.778369 -55.774657) (xy 286.724414 -55.766902) (xy 286.672112 -55.751548) (xy 286.622528 -55.728906)
			(xy 286.57667 -55.699438) (xy 286.535474 -55.663743) (xy 286.499776 -55.622549) (xy 286.470305 -55.576693)
			(xy 286.44766 -55.52711) (xy 286.432303 -55.474809) (xy 286.424545 -55.420855) (xy 284.649424 -55.420855)
			(xy 284.681141 -55.44725) (xy 284.718358 -55.488787) (xy 284.749131 -55.5353) (xy 284.772803 -55.585797)
			(xy 284.788871 -55.639204) (xy 284.796991 -55.69438) (xy 284.7975 -55.722266) (xy 284.796991 -55.750152)
			(xy 284.788871 -55.805328) (xy 284.772803 -55.858735) (xy 284.749131 -55.909232) (xy 284.718358 -55.955745)
			(xy 284.681141 -55.997282) (xy 284.638273 -56.032957) (xy 284.590667 -56.062011) (xy 284.539338 -56.083823)
			(xy 284.485381 -56.097929) (xy 284.429944 -56.104029) (xy 284.37421 -56.101992) (xy 284.319367 -56.091862)
			(xy 284.266583 -56.073855) (xy 284.216983 -56.048354) (xy 284.171625 -56.015903) (xy 284.131476 -55.977194)
			(xy 284.09739 -55.933051) (xy 284.070094 -55.884416) (xy 284.050171 -55.832325) (xy 284.038045 -55.777888)
			(xy 284.033974 -55.722266) (xy 272.205216 -55.722266) (xy 272.248376 -56.446928) (xy 272.249559 -56.455289)
			(xy 272.256688 -56.470586) (xy 272.268419 -56.482719) (xy 272.275808 -56.486806) (xy 272.298924 -56.49912)
			(xy 272.34185 -56.52913) (xy 272.380268 -56.564729) (xy 272.413456 -56.605248) (xy 272.44079 -56.649926)
			(xy 272.461756 -56.697922) (xy 272.475962 -56.748334) (xy 272.483138 -56.800216) (xy 272.48358 -56.826404)
			(xy 272.48358 -56.832754) (xy 272.483163 -56.847824) (xy 272.480239 -56.877831) (xy 272.477738 -56.892698)
			(xy 272.471644 -56.923739) (xy 272.450561 -56.983376) (xy 272.43974 -57.002934) (xy 279.763474 -57.002934)
			(xy 279.764 -56.974844) (xy 279.772222 -56.919268) (xy 279.788508 -56.8655) (xy 279.812505 -56.814703)
			(xy 279.843695 -56.767976) (xy 279.881403 -56.726329) (xy 279.924812 -56.690666) (xy 279.94864 -56.675782)
			(xy 279.95753 -56.670448) (xy 279.969722 -56.65343) (xy 279.990042 -56.560212) (xy 279.985724 -56.539638)
			(xy 279.979882 -56.531002) (xy 279.963879 -56.50694) (xy 279.938537 -56.455008) (xy 279.921313 -56.399849)
			(xy 279.912598 -56.342725) (xy 279.912064 -56.313832) (xy 279.912585 -56.286581) (xy 279.920337 -56.232634)
			(xy 279.935687 -56.180339) (xy 279.958324 -56.130761) (xy 279.987786 -56.084909) (xy 280.023474 -56.043716)
			(xy 280.064661 -56.008022) (xy 280.110508 -55.978553) (xy 280.160082 -55.955908) (xy 280.212375 -55.94055)
			(xy 280.266321 -55.932789) (xy 280.293572 -55.932324) (xy 280.320942 -55.932801) (xy 280.375121 -55.940615)
			(xy 280.427624 -55.956101) (xy 280.477371 -55.978941) (xy 280.523338 -56.008664) (xy 280.54427 -56.026304)
			(xy 280.544524 -56.026558) (xy 280.551595 -56.032168) (xy 280.568524 -56.038399) (xy 280.577544 -56.03875)
			(xy 280.6446 -56.03875) (xy 280.653618 -56.038404) (xy 280.670536 -56.03215) (xy 280.67762 -56.026558)
			(xy 280.67762 -56.026304) (xy 280.677874 -56.026304) (xy 280.698807 -56.008663) (xy 280.744775 -55.978939)
			(xy 280.794521 -55.956093) (xy 280.847023 -55.940597) (xy 280.901201 -55.932768) (xy 280.955943 -55.932768)
			(xy 281.010121 -55.940597) (xy 281.062623 -55.956093) (xy 281.112369 -55.978939) (xy 281.158337 -56.008663)
			(xy 281.17927 -56.026304) (xy 281.179524 -56.026558) (xy 281.186595 -56.032168) (xy 281.203524 -56.038399)
			(xy 281.212544 -56.03875) (xy 281.2796 -56.03875) (xy 281.288618 -56.038404) (xy 281.305536 -56.03215)
			(xy 281.31262 -56.026558) (xy 281.31262 -56.026304) (xy 281.312874 -56.026304) (xy 281.333806 -56.008664)
			(xy 281.379778 -55.978952) (xy 281.429526 -55.956116) (xy 281.482027 -55.940626) (xy 281.536203 -55.932798)
			(xy 281.563572 -55.932324) (xy 281.590828 -55.932721) (xy 281.644787 -55.940475) (xy 281.697093 -55.95583)
			(xy 281.746681 -55.978473) (xy 281.792541 -56.007943) (xy 281.833741 -56.04364) (xy 281.86944 -56.084836)
			(xy 281.898913 -56.130695) (xy 281.92156 -56.180281) (xy 281.936919 -56.232586) (xy 281.944677 -56.286544)
			(xy 281.944677 -56.297068) (xy 282.286454 -56.297068) (xy 282.290525 -56.241446) (xy 282.302651 -56.187009)
			(xy 282.322574 -56.134918) (xy 282.34987 -56.086283) (xy 282.383956 -56.04214) (xy 282.424105 -56.003431)
			(xy 282.469463 -55.97098) (xy 282.519063 -55.945479) (xy 282.571847 -55.927472) (xy 282.62669 -55.917342)
			(xy 282.682424 -55.915305) (xy 282.737861 -55.921405) (xy 282.791818 -55.935511) (xy 282.843147 -55.957323)
			(xy 282.890753 -55.986377) (xy 282.933621 -56.022052) (xy 282.970838 -56.063589) (xy 283.001611 -56.110102)
			(xy 283.025283 -56.160599) (xy 283.041351 -56.214006) (xy 283.049471 -56.269182) (xy 283.04998 -56.297068)
			(xy 283.049471 -56.324954) (xy 283.041351 -56.38013) (xy 283.025283 -56.433537) (xy 283.001611 -56.484034)
			(xy 282.970838 -56.530547) (xy 282.933621 -56.572084) (xy 282.890753 -56.607759) (xy 282.843147 -56.636813)
			(xy 282.791818 -56.658625) (xy 282.737861 -56.672731) (xy 282.682424 -56.678831) (xy 282.62669 -56.676794)
			(xy 282.571847 -56.666664) (xy 282.519063 -56.648657) (xy 282.469463 -56.623156) (xy 282.424105 -56.590705)
			(xy 282.383956 -56.551996) (xy 282.34987 -56.507853) (xy 282.322574 -56.459218) (xy 282.302651 -56.407127)
			(xy 282.290525 -56.35269) (xy 282.286454 -56.297068) (xy 281.944677 -56.297068) (xy 281.944677 -56.341056)
			(xy 281.936919 -56.395014) (xy 281.92156 -56.447319) (xy 281.898913 -56.496905) (xy 281.86944 -56.542764)
			(xy 281.833741 -56.58396) (xy 281.792541 -56.619657) (xy 281.746681 -56.649127) (xy 281.697093 -56.67177)
			(xy 281.644787 -56.687125) (xy 281.590828 -56.694879) (xy 281.563572 -56.69534) (xy 281.5362 -56.694905)
			(xy 281.482019 -56.687082) (xy 281.429515 -56.671586) (xy 281.379769 -56.648737) (xy 281.333804 -56.619005)
			(xy 281.312874 -56.60136) (xy 281.31262 -56.601106) (xy 281.305531 -56.595522) (xy 281.288616 -56.589274)
			(xy 281.2796 -56.588914) (xy 281.212544 -56.588914) (xy 281.203529 -56.589289) (xy 281.186612 -56.595524)
			(xy 281.179524 -56.601106) (xy 281.179524 -56.60136) (xy 281.17927 -56.60136) (xy 281.158337 -56.619001)
			(xy 281.112369 -56.648725) (xy 281.062623 -56.671571) (xy 281.010121 -56.687067) (xy 280.955943 -56.694896)
			(xy 280.901201 -56.694896) (xy 280.847023 -56.687067) (xy 280.794521 -56.671571) (xy 280.744775 -56.648725)
			(xy 280.698807 -56.619001) (xy 280.677874 -56.60136) (xy 280.67762 -56.601106) (xy 280.670531 -56.595522)
			(xy 280.653616 -56.589274) (xy 280.6446 -56.588914) (xy 280.577544 -56.588914) (xy 280.568529 -56.589289)
			(xy 280.551612 -56.595524) (xy 280.544524 -56.601106) (xy 280.544016 -56.60136) (xy 280.531285 -56.612308)
			(xy 280.504191 -56.632147) (xy 280.489914 -56.640984) (xy 280.481024 -56.646318) (xy 280.468832 -56.663336)
			(xy 280.448512 -56.756554) (xy 280.45283 -56.777128) (xy 280.458672 -56.785764) (xy 280.474656 -56.809838)
			(xy 280.500003 -56.861766) (xy 280.517233 -56.91692) (xy 280.525953 -56.974042) (xy 280.52649 -57.002934)
			(xy 280.526004 -57.030185) (xy 280.518248 -57.084133) (xy 280.502893 -57.136428) (xy 280.480251 -57.186005)
			(xy 280.450785 -57.231855) (xy 280.415094 -57.273046) (xy 280.373903 -57.308737) (xy 280.328053 -57.338203)
			(xy 280.278476 -57.360845) (xy 280.226181 -57.3762) (xy 280.172233 -57.383956) (xy 280.117731 -57.383956)
			(xy 280.063783 -57.3762) (xy 280.011488 -57.360845) (xy 279.961911 -57.338203) (xy 279.916061 -57.308737)
			(xy 279.87487 -57.273046) (xy 279.839179 -57.231855) (xy 279.809713 -57.186005) (xy 279.787071 -57.136428)
			(xy 279.771716 -57.084133) (xy 279.76396 -57.030185) (xy 279.763474 -57.002934) (xy 272.43974 -57.002934)
			(xy 272.419938 -57.038724) (xy 272.400776 -57.063894) (xy 272.395442 -57.070498) (xy 272.39214 -57.079642)
			(xy 272.390616 -57.085484) (xy 272.3896 -57.09539) (xy 272.3896 -57.128156) (xy 272.378424 -57.128156)
			(xy 272.378424 -57.178956) (xy 272.378758 -57.18756) (xy 272.38447 -57.203791) (xy 272.3896 -57.210706)
			(xy 272.39087 -57.21223) (xy 272.408263 -57.233107) (xy 272.437579 -57.278858) (xy 272.460106 -57.328305)
			(xy 272.475387 -57.38045) (xy 272.483112 -57.434235) (xy 272.48358 -57.461404) (xy 272.483198 -57.48528)
			(xy 288.805872 -57.48528) (xy 288.809943 -57.429658) (xy 288.822069 -57.375221) (xy 288.841992 -57.32313)
			(xy 288.869288 -57.274495) (xy 288.903374 -57.230352) (xy 288.943523 -57.191643) (xy 288.988881 -57.159192)
			(xy 289.038481 -57.133691) (xy 289.091265 -57.115684) (xy 289.146108 -57.105554) (xy 289.201842 -57.103517)
			(xy 289.257279 -57.109617) (xy 289.311236 -57.123723) (xy 289.362565 -57.145535) (xy 289.410171 -57.174589)
			(xy 289.453039 -57.210264) (xy 289.490256 -57.251801) (xy 289.521029 -57.298314) (xy 289.544701 -57.348811)
			(xy 289.560769 -57.402218) (xy 289.568889 -57.457394) (xy 289.569398 -57.48528) (xy 289.568889 -57.513166)
			(xy 289.560769 -57.568342) (xy 289.544701 -57.621749) (xy 289.521029 -57.672246) (xy 289.490256 -57.718759)
			(xy 289.453039 -57.760296) (xy 289.410171 -57.795971) (xy 289.362565 -57.825025) (xy 289.311236 -57.846837)
			(xy 289.257279 -57.860943) (xy 289.201842 -57.867043) (xy 289.146108 -57.865006) (xy 289.091265 -57.854876)
			(xy 289.038481 -57.836869) (xy 288.988881 -57.811368) (xy 288.943523 -57.778917) (xy 288.903374 -57.740208)
			(xy 288.869288 -57.696065) (xy 288.841992 -57.64743) (xy 288.822069 -57.595339) (xy 288.809943 -57.540902)
			(xy 288.805872 -57.48528) (xy 272.483198 -57.48528) (xy 272.48317 -57.487021) (xy 272.476317 -57.537795)
			(xy 272.46272 -57.587192) (xy 272.442626 -57.634321) (xy 272.416397 -57.678333) (xy 272.400776 -57.69864)
			(xy 272.400522 -57.698894) (xy 272.398998 -57.700672) (xy 272.394697 -57.7072) (xy 272.389906 -57.722071)
			(xy 272.3896 -57.729882) (xy 272.3896 -57.763156) (xy 272.378424 -57.763156) (xy 272.378424 -57.813956)
			(xy 272.378758 -57.82256) (xy 272.38447 -57.838791) (xy 272.3896 -57.845706) (xy 272.39087 -57.84723)
			(xy 272.408263 -57.868107) (xy 272.437579 -57.913858) (xy 272.460106 -57.963305) (xy 272.475387 -58.01545)
			(xy 272.483112 -58.069235) (xy 272.48358 -58.096404) (xy 272.48317 -58.122021) (xy 272.476317 -58.172795)
			(xy 272.46272 -58.222192) (xy 272.442626 -58.269321) (xy 272.416397 -58.313333) (xy 272.400776 -58.33364)
			(xy 272.400522 -58.333894) (xy 272.398998 -58.335672) (xy 272.394697 -58.3422) (xy 272.389906 -58.357071)
			(xy 272.3896 -58.364882) (xy 272.3896 -58.398156) (xy 272.378424 -58.398156) (xy 272.378424 -58.448956)
			(xy 272.378758 -58.45756) (xy 272.38447 -58.473791) (xy 272.3896 -58.480706) (xy 272.39087 -58.48223)
			(xy 272.408263 -58.503107) (xy 272.437579 -58.548858) (xy 272.460106 -58.598305) (xy 272.475387 -58.65045)
			(xy 272.479536 -58.679334) (xy 280.195274 -58.679334) (xy 280.195706 -58.653019) (xy 280.202949 -58.600889)
			(xy 280.217276 -58.550246) (xy 280.238415 -58.502047) (xy 280.265967 -58.457205) (xy 280.29941 -58.416566)
			(xy 280.318464 -58.39841) (xy 280.325858 -58.390882) (xy 280.334388 -58.371607) (xy 280.334974 -58.361072)
			(xy 280.334974 -58.286396) (xy 280.334468 -58.275843) (xy 280.325917 -58.256548) (xy 280.318464 -58.249058)
			(xy 280.299388 -58.230923) (xy 280.265934 -58.190288) (xy 280.238379 -58.145443) (xy 280.217244 -58.097239)
			(xy 280.202931 -58.046588) (xy 280.19571 -57.994451) (xy 280.195274 -57.968134) (xy 280.19576 -57.940883)
			(xy 280.203516 -57.886935) (xy 280.218871 -57.83464) (xy 280.241513 -57.785063) (xy 280.270979 -57.739213)
			(xy 280.30667 -57.698022) (xy 280.347861 -57.662331) (xy 280.393711 -57.632865) (xy 280.443288 -57.610223)
			(xy 280.495583 -57.594868) (xy 280.549531 -57.587112) (xy 280.604033 -57.587112) (xy 280.657981 -57.594868)
			(xy 280.710276 -57.610223) (xy 280.759853 -57.632865) (xy 280.805703 -57.662331) (xy 280.846894 -57.698022)
			(xy 280.882585 -57.739213) (xy 280.912051 -57.785063) (xy 280.934693 -57.83464) (xy 280.950048 -57.886935)
			(xy 280.957804 -57.940883) (xy 280.95829 -57.968134) (xy 280.957848 -57.994449) (xy 280.950609 -58.046579)
			(xy 280.943341 -58.072274) (xy 284.193486 -58.072274) (xy 284.197557 -58.016652) (xy 284.209683 -57.962215)
			(xy 284.229606 -57.910124) (xy 284.256902 -57.861489) (xy 284.290988 -57.817346) (xy 284.331137 -57.778637)
			(xy 284.376495 -57.746186) (xy 284.426095 -57.720685) (xy 284.478879 -57.702678) (xy 284.533722 -57.692548)
			(xy 284.589456 -57.690511) (xy 284.644893 -57.696611) (xy 284.69885 -57.710717) (xy 284.750179 -57.732529)
			(xy 284.797785 -57.761583) (xy 284.840653 -57.797258) (xy 284.87787 -57.838795) (xy 284.908643 -57.885308)
			(xy 284.932315 -57.935805) (xy 284.948383 -57.989212) (xy 284.956503 -58.044388) (xy 284.957012 -58.072274)
			(xy 284.956942 -58.076084) (xy 289.557966 -58.076084) (xy 289.562037 -58.020462) (xy 289.574163 -57.966025)
			(xy 289.594086 -57.913934) (xy 289.621382 -57.865299) (xy 289.655468 -57.821156) (xy 289.695617 -57.782447)
			(xy 289.740975 -57.749996) (xy 289.790575 -57.724495) (xy 289.843359 -57.706488) (xy 289.898202 -57.696358)
			(xy 289.953936 -57.694321) (xy 290.009373 -57.700421) (xy 290.06333 -57.714527) (xy 290.114659 -57.736339)
			(xy 290.162265 -57.765393) (xy 290.205133 -57.801068) (xy 290.24235 -57.842605) (xy 290.258686 -57.867296)
			(xy 291.84295 -57.867296) (xy 291.847021 -57.811674) (xy 291.859147 -57.757237) (xy 291.87907 -57.705146)
			(xy 291.906366 -57.656511) (xy 291.940452 -57.612368) (xy 291.980601 -57.573659) (xy 292.025959 -57.541208)
			(xy 292.075559 -57.515707) (xy 292.128343 -57.4977) (xy 292.183186 -57.48757) (xy 292.23892 -57.485533)
			(xy 292.294357 -57.491633) (xy 292.348314 -57.505739) (xy 292.399643 -57.527551) (xy 292.447249 -57.556605)
			(xy 292.490117 -57.59228) (xy 292.527334 -57.633817) (xy 292.558107 -57.68033) (xy 292.581779 -57.730827)
			(xy 292.597847 -57.784234) (xy 292.605967 -57.83941) (xy 292.606476 -57.867296) (xy 292.605967 -57.895182)
			(xy 292.597847 -57.950358) (xy 292.581779 -58.003765) (xy 292.558107 -58.054262) (xy 292.527334 -58.100775)
			(xy 292.490117 -58.142312) (xy 292.447249 -58.177987) (xy 292.399643 -58.207041) (xy 292.348314 -58.228853)
			(xy 292.294357 -58.242959) (xy 292.23892 -58.249059) (xy 292.183186 -58.247022) (xy 292.128343 -58.236892)
			(xy 292.075559 -58.218885) (xy 292.025959 -58.193384) (xy 291.980601 -58.160933) (xy 291.940452 -58.122224)
			(xy 291.906366 -58.078081) (xy 291.87907 -58.029446) (xy 291.859147 -57.977355) (xy 291.847021 -57.922918)
			(xy 291.84295 -57.867296) (xy 290.258686 -57.867296) (xy 290.273123 -57.889118) (xy 290.296795 -57.939615)
			(xy 290.312863 -57.993022) (xy 290.320983 -58.048198) (xy 290.321492 -58.076084) (xy 290.320983 -58.10397)
			(xy 290.312863 -58.159146) (xy 290.296795 -58.212553) (xy 290.273123 -58.26305) (xy 290.24235 -58.309563)
			(xy 290.205133 -58.3511) (xy 290.162265 -58.386775) (xy 290.114659 -58.415829) (xy 290.06333 -58.437641)
			(xy 290.009373 -58.451747) (xy 289.953936 -58.457847) (xy 289.898202 -58.45581) (xy 289.843359 -58.44568)
			(xy 289.790575 -58.427673) (xy 289.740975 -58.402172) (xy 289.695617 -58.369721) (xy 289.655468 -58.331012)
			(xy 289.621382 -58.286869) (xy 289.594086 -58.238234) (xy 289.574163 -58.186143) (xy 289.562037 -58.131706)
			(xy 289.557966 -58.076084) (xy 284.956942 -58.076084) (xy 284.956503 -58.10016) (xy 284.948383 -58.155336)
			(xy 284.932315 -58.208743) (xy 284.908643 -58.25924) (xy 284.87787 -58.305753) (xy 284.840653 -58.34729)
			(xy 284.797785 -58.382965) (xy 284.750179 -58.412019) (xy 284.69885 -58.433831) (xy 284.644893 -58.447937)
			(xy 284.589456 -58.454037) (xy 284.533722 -58.452) (xy 284.478879 -58.44187) (xy 284.426095 -58.423863)
			(xy 284.376495 -58.398362) (xy 284.331137 -58.365911) (xy 284.290988 -58.327202) (xy 284.256902 -58.283059)
			(xy 284.229606 -58.234424) (xy 284.209683 -58.182333) (xy 284.197557 -58.127896) (xy 284.193486 -58.072274)
			(xy 280.943341 -58.072274) (xy 280.936285 -58.097222) (xy 280.915148 -58.145421) (xy 280.887597 -58.190264)
			(xy 280.854154 -58.230902) (xy 280.8351 -58.249058) (xy 280.827715 -58.256593) (xy 280.819181 -58.275863)
			(xy 280.81859 -58.286396) (xy 280.81859 -58.361072) (xy 280.819124 -58.371621) (xy 280.827656 -58.390916)
			(xy 280.8351 -58.39841) (xy 280.854153 -58.416568) (xy 280.887611 -58.457197) (xy 280.91517 -58.502037)
			(xy 280.936309 -58.550237) (xy 280.939415 -58.561224) (xy 290.76218 -58.561224) (xy 290.766251 -58.505602)
			(xy 290.778377 -58.451165) (xy 290.7983 -58.399074) (xy 290.825596 -58.350439) (xy 290.859682 -58.306296)
			(xy 290.899831 -58.267587) (xy 290.945189 -58.235136) (xy 290.994789 -58.209635) (xy 291.047573 -58.191628)
			(xy 291.102416 -58.181498) (xy 291.15815 -58.179461) (xy 291.213587 -58.185561) (xy 291.267544 -58.199667)
			(xy 291.318873 -58.221479) (xy 291.366479 -58.250533) (xy 291.409347 -58.286208) (xy 291.446564 -58.327745)
			(xy 291.477337 -58.374258) (xy 291.501009 -58.424755) (xy 291.517077 -58.478162) (xy 291.525197 -58.533338)
			(xy 291.525706 -58.561224) (xy 291.525197 -58.58911) (xy 291.517077 -58.644286) (xy 291.501009 -58.697693)
			(xy 291.477337 -58.74819) (xy 291.446564 -58.794703) (xy 291.409347 -58.83624) (xy 291.366479 -58.871915)
			(xy 291.318873 -58.900969) (xy 291.267544 -58.922781) (xy 291.213587 -58.936887) (xy 291.15815 -58.942987)
			(xy 291.102416 -58.94095) (xy 291.047573 -58.93082) (xy 290.994789 -58.912813) (xy 290.945189 -58.887312)
			(xy 290.899831 -58.854861) (xy 290.859682 -58.816152) (xy 290.825596 -58.772009) (xy 290.7983 -58.723374)
			(xy 290.778377 -58.671283) (xy 290.766251 -58.616846) (xy 290.76218 -58.561224) (xy 280.939415 -58.561224)
			(xy 280.950626 -58.600884) (xy 280.957851 -58.653018) (xy 280.95829 -58.679334) (xy 280.957804 -58.706585)
			(xy 280.950048 -58.760533) (xy 280.934693 -58.812828) (xy 280.912051 -58.862405) (xy 280.882585 -58.908255)
			(xy 280.846894 -58.949446) (xy 280.805703 -58.985137) (xy 280.759853 -59.014603) (xy 280.710276 -59.037245)
			(xy 280.657981 -59.0526) (xy 280.604033 -59.060356) (xy 280.549531 -59.060356) (xy 280.495583 -59.0526)
			(xy 280.443288 -59.037245) (xy 280.393711 -59.014603) (xy 280.347861 -58.985137) (xy 280.30667 -58.949446)
			(xy 280.270979 -58.908255) (xy 280.241513 -58.862405) (xy 280.218871 -58.812828) (xy 280.203516 -58.760533)
			(xy 280.19576 -58.706585) (xy 280.195274 -58.679334) (xy 272.479536 -58.679334) (xy 272.483112 -58.704235)
			(xy 272.48358 -58.731404) (xy 272.48358 -58.731658) (xy 272.482982 -58.761844) (xy 272.473437 -58.821457)
			(xy 272.45464 -58.878829) (xy 272.42706 -58.932533) (xy 272.409666 -58.95721) (xy 272.404078 -58.96483)
			(xy 272.401792 -58.97245) (xy 272.400619 -58.97673) (xy 272.399591 -58.985542) (xy 272.39976 -58.989976)
			(xy 272.410763 -59.174634) (xy 289.293044 -59.174634) (xy 289.297115 -59.119012) (xy 289.309241 -59.064575)
			(xy 289.329164 -59.012484) (xy 289.35646 -58.963849) (xy 289.390546 -58.919706) (xy 289.430695 -58.880997)
			(xy 289.476053 -58.848546) (xy 289.525653 -58.823045) (xy 289.578437 -58.805038) (xy 289.63328 -58.794908)
			(xy 289.689014 -58.792871) (xy 289.744451 -58.798971) (xy 289.798408 -58.813077) (xy 289.849737 -58.834889)
			(xy 289.897343 -58.863943) (xy 289.940211 -58.899618) (xy 289.977428 -58.941155) (xy 290.008201 -58.987668)
			(xy 290.031873 -59.038165) (xy 290.047941 -59.091572) (xy 290.056061 -59.146748) (xy 290.05657 -59.174634)
			(xy 290.056061 -59.20252) (xy 290.047941 -59.257696) (xy 290.031873 -59.311103) (xy 290.008201 -59.3616)
			(xy 289.977428 -59.408113) (xy 289.940211 -59.44965) (xy 289.897343 -59.485325) (xy 289.849737 -59.514379)
			(xy 289.798408 -59.536191) (xy 289.744451 -59.550297) (xy 289.689014 -59.556397) (xy 289.63328 -59.55436)
			(xy 289.578437 -59.54423) (xy 289.525653 -59.526223) (xy 289.476053 -59.500722) (xy 289.430695 -59.468271)
			(xy 289.390546 -59.429562) (xy 289.35646 -59.385419) (xy 289.329164 -59.336784) (xy 289.309241 -59.284693)
			(xy 289.297115 -59.230256) (xy 289.293044 -59.174634) (xy 272.410763 -59.174634) (xy 272.461089 -60.019254)
			(xy 280.335661 -60.019254) (xy 280.335661 -59.964746) (xy 280.343419 -59.910793) (xy 280.358777 -59.858493)
			(xy 280.381422 -59.808911) (xy 280.410892 -59.763057) (xy 280.446589 -59.721864) (xy 280.487786 -59.686171)
			(xy 280.533643 -59.656704) (xy 280.583227 -59.634064) (xy 280.635528 -59.618712) (xy 280.689482 -59.610959)
			(xy 280.716736 -59.610498) (xy 280.744107 -59.610943) (xy 280.798287 -59.618766) (xy 280.85079 -59.63426)
			(xy 280.900537 -59.657107) (xy 280.946503 -59.686835) (xy 280.967434 -59.704478) (xy 280.967688 -59.704732)
			(xy 280.974771 -59.710323) (xy 280.991691 -59.716566) (xy 281.000708 -59.716924) (xy 281.067764 -59.716924)
			(xy 281.076778 -59.716545) (xy 281.093695 -59.710312) (xy 281.100784 -59.704732) (xy 281.100784 -59.704478)
			(xy 281.101038 -59.704478) (xy 281.121971 -59.686837) (xy 281.167939 -59.657113) (xy 281.217685 -59.634267)
			(xy 281.270187 -59.618771) (xy 281.324365 -59.610942) (xy 281.379107 -59.610942) (xy 281.433285 -59.618771)
			(xy 281.485787 -59.634267) (xy 281.535533 -59.657113) (xy 281.581501 -59.686837) (xy 281.602434 -59.704478)
			(xy 281.602688 -59.704732) (xy 281.609771 -59.710323) (xy 281.626691 -59.716566) (xy 281.635708 -59.716924)
			(xy 281.702764 -59.716924) (xy 281.711778 -59.716545) (xy 281.728695 -59.710312) (xy 281.735784 -59.704732)
			(xy 281.735784 -59.704478) (xy 281.736038 -59.704478) (xy 281.75698 -59.686851) (xy 281.80295 -59.657138)
			(xy 281.852695 -59.6343) (xy 281.905194 -59.618806) (xy 281.959368 -59.610974) (xy 281.986736 -59.610498)
			(xy 282.013986 -59.610974) (xy 282.067931 -59.618735) (xy 282.120222 -59.634094) (xy 282.169795 -59.656737)
			(xy 282.215642 -59.686205) (xy 282.256829 -59.721897) (xy 282.292517 -59.763087) (xy 282.32198 -59.808936)
			(xy 282.344619 -59.858512) (xy 282.359973 -59.910805) (xy 282.367728 -59.96475) (xy 282.367728 -60.01925)
			(xy 282.359973 -60.073195) (xy 282.344619 -60.125488) (xy 282.32198 -60.175064) (xy 282.292517 -60.220913)
			(xy 282.256829 -60.262103) (xy 282.215642 -60.297795) (xy 282.169795 -60.327263) (xy 282.120222 -60.349906)
			(xy 282.067931 -60.365265) (xy 282.013986 -60.373026) (xy 281.986736 -60.373514) (xy 281.959367 -60.373023)
			(xy 281.905189 -60.365211) (xy 281.852686 -60.349727) (xy 281.802939 -60.326891) (xy 281.756971 -60.297172)
			(xy 281.736038 -60.279534) (xy 281.735784 -60.27928) (xy 281.728708 -60.273678) (xy 281.711783 -60.267441)
			(xy 281.702764 -60.267088) (xy 281.635708 -60.267088) (xy 281.626692 -60.267451) (xy 281.609775 -60.273695)
			(xy 281.602688 -60.27928) (xy 281.602434 -60.279534) (xy 281.581501 -60.297175) (xy 281.535533 -60.326899)
			(xy 281.485787 -60.349745) (xy 281.433285 -60.365241) (xy 281.379107 -60.37307) (xy 281.324365 -60.37307)
			(xy 281.270187 -60.365241) (xy 281.217685 -60.349745) (xy 281.167939 -60.326899) (xy 281.121971 -60.297175)
			(xy 281.101038 -60.279534) (xy 281.100784 -60.27928) (xy 281.093708 -60.273678) (xy 281.076783 -60.267441)
			(xy 281.067764 -60.267088) (xy 281.000708 -60.267088) (xy 280.991692 -60.267451) (xy 280.974775 -60.273695)
			(xy 280.967688 -60.27928) (xy 280.967688 -60.279534) (xy 280.967434 -60.279534) (xy 280.946504 -60.297176)
			(xy 280.90053 -60.326886) (xy 280.850782 -60.349721) (xy 280.798281 -60.365212) (xy 280.744105 -60.37304)
			(xy 280.716736 -60.373514) (xy 280.689482 -60.373041) (xy 280.635528 -60.365288) (xy 280.583227 -60.349936)
			(xy 280.533643 -60.327296) (xy 280.487786 -60.297829) (xy 280.446589 -60.262136) (xy 280.410892 -60.220943)
			(xy 280.381422 -60.175089) (xy 280.358777 -60.125507) (xy 280.343419 -60.073207) (xy 280.335661 -60.019254)
			(xy 272.461089 -60.019254) (xy 272.49768 -60.633356) (xy 291.996874 -60.633356) (xy 292.000945 -60.577734)
			(xy 292.013071 -60.523297) (xy 292.032994 -60.471206) (xy 292.06029 -60.422571) (xy 292.094376 -60.378428)
			(xy 292.134525 -60.339719) (xy 292.179883 -60.307268) (xy 292.229483 -60.281767) (xy 292.282267 -60.26376)
			(xy 292.33711 -60.25363) (xy 292.392844 -60.251593) (xy 292.448281 -60.257693) (xy 292.502238 -60.271799)
			(xy 292.553567 -60.293611) (xy 292.601173 -60.322665) (xy 292.644041 -60.35834) (xy 292.681258 -60.399877)
			(xy 292.712031 -60.44639) (xy 292.735703 -60.496887) (xy 292.751771 -60.550294) (xy 292.759891 -60.60547)
			(xy 292.7604 -60.633356) (xy 292.759891 -60.661242) (xy 292.751771 -60.716418) (xy 292.735703 -60.769825)
			(xy 292.712031 -60.820322) (xy 292.681258 -60.866835) (xy 292.644041 -60.908372) (xy 292.601173 -60.944047)
			(xy 292.553567 -60.973101) (xy 292.502238 -60.994913) (xy 292.448281 -61.009019) (xy 292.392844 -61.015119)
			(xy 292.33711 -61.013082) (xy 292.282267 -61.002952) (xy 292.229483 -60.984945) (xy 292.179883 -60.959444)
			(xy 292.134525 -60.926993) (xy 292.094376 -60.888284) (xy 292.06029 -60.844141) (xy 292.032994 -60.795506)
			(xy 292.013071 -60.743415) (xy 292.000945 -60.688978) (xy 291.996874 -60.633356) (xy 272.49768 -60.633356)
			(xy 272.548593 -61.487812) (xy 290.50437 -61.487812) (xy 290.508441 -61.43219) (xy 290.520567 -61.377753)
			(xy 290.54049 -61.325662) (xy 290.567786 -61.277027) (xy 290.601872 -61.232884) (xy 290.642021 -61.194175)
			(xy 290.687379 -61.161724) (xy 290.736979 -61.136223) (xy 290.789763 -61.118216) (xy 290.844606 -61.108086)
			(xy 290.90034 -61.106049) (xy 290.955777 -61.112149) (xy 291.009734 -61.126255) (xy 291.061063 -61.148067)
			(xy 291.108669 -61.177121) (xy 291.151537 -61.212796) (xy 291.188754 -61.254333) (xy 291.219527 -61.300846)
			(xy 291.243199 -61.351343) (xy 291.259267 -61.40475) (xy 291.267387 -61.459926) (xy 291.267896 -61.487812)
			(xy 291.267387 -61.515698) (xy 291.259267 -61.570874) (xy 291.243199 -61.624281) (xy 291.219527 -61.674778)
			(xy 291.188754 -61.721291) (xy 291.151537 -61.762828) (xy 291.108669 -61.798503) (xy 291.061063 -61.827557)
			(xy 291.009734 -61.849369) (xy 290.955777 -61.863475) (xy 290.90034 -61.869575) (xy 290.844606 -61.867538)
			(xy 290.789763 -61.857408) (xy 290.736979 -61.839401) (xy 290.687379 -61.8139) (xy 290.642021 -61.781449)
			(xy 290.601872 -61.74274) (xy 290.567786 -61.698597) (xy 290.54049 -61.649962) (xy 290.520567 -61.597871)
			(xy 290.508441 -61.543434) (xy 290.50437 -61.487812) (xy 272.548593 -61.487812) (xy 272.583402 -62.072012)
			(xy 272.584776 -62.121034) (xy 288.442144 -62.121034) (xy 288.446215 -62.065412) (xy 288.458341 -62.010975)
			(xy 288.478264 -61.958884) (xy 288.50556 -61.910249) (xy 288.539646 -61.866106) (xy 288.579795 -61.827397)
			(xy 288.625153 -61.794946) (xy 288.674753 -61.769445) (xy 288.727537 -61.751438) (xy 288.78238 -61.741308)
			(xy 288.838114 -61.739271) (xy 288.893551 -61.745371) (xy 288.947508 -61.759477) (xy 288.998837 -61.781289)
			(xy 289.046443 -61.810343) (xy 289.089311 -61.846018) (xy 289.126528 -61.887555) (xy 289.157301 -61.934068)
			(xy 289.180973 -61.984565) (xy 289.197041 -62.037972) (xy 289.205161 -62.093148) (xy 289.20567 -62.121034)
			(xy 289.205161 -62.14892) (xy 289.197041 -62.204096) (xy 289.180973 -62.257503) (xy 289.157301 -62.308)
			(xy 289.126528 -62.354513) (xy 289.089311 -62.39605) (xy 289.046443 -62.431725) (xy 288.998837 -62.460779)
			(xy 288.947508 -62.482591) (xy 288.893551 -62.496697) (xy 288.838114 -62.502797) (xy 288.78238 -62.50076)
			(xy 288.727537 -62.49063) (xy 288.674753 -62.472623) (xy 288.625153 -62.447122) (xy 288.579795 -62.414671)
			(xy 288.539646 -62.375962) (xy 288.50556 -62.331819) (xy 288.478264 -62.283184) (xy 288.458341 -62.231093)
			(xy 288.446215 -62.176656) (xy 288.442144 -62.121034) (xy 272.584776 -62.121034) (xy 272.584926 -62.126368)
			(xy 272.589498 -63.024004) (xy 272.589498 -63.02502) (xy 272.590768 -63.07455) (xy 272.590768 -63.075058)
			(xy 272.590006 -63.110872) (xy 272.590006 -63.11392) (xy 272.589752 -63.114936) (xy 272.590238 -63.213548)
			(xy 280.320788 -63.213548) (xy 280.320788 -63.159052) (xy 280.328543 -63.10511) (xy 280.343895 -63.052821)
			(xy 280.366532 -63.003248) (xy 280.395993 -62.957401) (xy 280.431678 -62.916214) (xy 280.472861 -62.880523)
			(xy 280.518704 -62.851056) (xy 280.568274 -62.828413) (xy 280.620561 -62.813054) (xy 280.674502 -62.805292)
			(xy 280.70175 -62.804802) (xy 280.729119 -62.805297) (xy 280.783297 -62.813108) (xy 280.8358 -62.82859)
			(xy 280.885547 -62.851425) (xy 280.931515 -62.881144) (xy 280.952448 -62.898782) (xy 280.952702 -62.899036)
			(xy 280.959781 -62.904634) (xy 280.976704 -62.910873) (xy 280.985722 -62.911228) (xy 281.052778 -62.911228)
			(xy 281.061793 -62.910854) (xy 281.07871 -62.904618) (xy 281.085798 -62.899036) (xy 281.085798 -62.898782)
			(xy 281.086052 -62.898782) (xy 281.106985 -62.881141) (xy 281.152953 -62.851417) (xy 281.202699 -62.828571)
			(xy 281.255201 -62.813075) (xy 281.309379 -62.805246) (xy 281.364121 -62.805246) (xy 281.418299 -62.813075)
			(xy 281.470801 -62.828571) (xy 281.520547 -62.851417) (xy 281.566515 -62.881141) (xy 281.587448 -62.898782)
			(xy 281.587702 -62.899036) (xy 281.594781 -62.904634) (xy 281.611704 -62.910873) (xy 281.620722 -62.911228)
			(xy 281.687778 -62.911228) (xy 281.696793 -62.910854) (xy 281.71371 -62.904618) (xy 281.720798 -62.899036)
			(xy 281.720798 -62.898782) (xy 281.721052 -62.898782) (xy 281.741989 -62.881149) (xy 281.787961 -62.851437)
			(xy 281.837707 -62.8286) (xy 281.890206 -62.813108) (xy 281.944381 -62.805277) (xy 281.97175 -62.804802)
			(xy 281.999006 -62.805241) (xy 282.052964 -62.812993) (xy 282.105269 -62.828345) (xy 282.154857 -62.850985)
			(xy 282.200717 -62.880453) (xy 282.241917 -62.916147) (xy 282.277617 -62.957342) (xy 282.307091 -63.003199)
			(xy 282.329738 -63.052784) (xy 282.339561 -63.086234) (xy 285.587438 -63.086234) (xy 285.591509 -63.030612)
			(xy 285.603635 -62.976175) (xy 285.623558 -62.924084) (xy 285.650854 -62.875449) (xy 285.68494 -62.831306)
			(xy 285.725089 -62.792597) (xy 285.770447 -62.760146) (xy 285.820047 -62.734645) (xy 285.872831 -62.716638)
			(xy 285.927674 -62.706508) (xy 285.983408 -62.704471) (xy 286.038845 -62.710571) (xy 286.092802 -62.724677)
			(xy 286.144131 -62.746489) (xy 286.191737 -62.775543) (xy 286.234605 -62.811218) (xy 286.271822 -62.852755)
			(xy 286.302595 -62.899268) (xy 286.326267 -62.949765) (xy 286.342335 -63.003172) (xy 286.350455 -63.058348)
			(xy 286.350964 -63.086234) (xy 286.350455 -63.11412) (xy 286.342335 -63.169296) (xy 286.326267 -63.222703)
			(xy 286.302595 -63.2732) (xy 286.302442 -63.273432) (xy 287.776664 -63.273432) (xy 287.780735 -63.21781)
			(xy 287.792861 -63.163373) (xy 287.812784 -63.111282) (xy 287.84008 -63.062647) (xy 287.874166 -63.018504)
			(xy 287.914315 -62.979795) (xy 287.959673 -62.947344) (xy 288.009273 -62.921843) (xy 288.062057 -62.903836)
			(xy 288.1169 -62.893706) (xy 288.172634 -62.891669) (xy 288.228071 -62.897769) (xy 288.282028 -62.911875)
			(xy 288.333357 -62.933687) (xy 288.380963 -62.962741) (xy 288.423831 -62.998416) (xy 288.461048 -63.039953)
			(xy 288.491821 -63.086466) (xy 288.515493 -63.136963) (xy 288.531561 -63.19037) (xy 288.539681 -63.245546)
			(xy 288.54019 -63.273432) (xy 288.539681 -63.301318) (xy 288.531561 -63.356494) (xy 288.515493 -63.409901)
			(xy 288.491821 -63.460398) (xy 288.461048 -63.506911) (xy 288.423831 -63.548448) (xy 288.380963 -63.584123)
			(xy 288.333357 -63.613177) (xy 288.282028 -63.634989) (xy 288.228071 -63.649095) (xy 288.172634 -63.655195)
			(xy 288.1169 -63.653158) (xy 288.062057 -63.643028) (xy 288.009273 -63.625021) (xy 287.959673 -63.59952)
			(xy 287.914315 -63.567069) (xy 287.874166 -63.52836) (xy 287.84008 -63.484217) (xy 287.812784 -63.435582)
			(xy 287.792861 -63.383491) (xy 287.780735 -63.329054) (xy 287.776664 -63.273432) (xy 286.302442 -63.273432)
			(xy 286.271822 -63.319713) (xy 286.234605 -63.36125) (xy 286.191737 -63.396925) (xy 286.144131 -63.425979)
			(xy 286.092802 -63.447791) (xy 286.038845 -63.461897) (xy 285.983408 -63.467997) (xy 285.927674 -63.46596)
			(xy 285.872831 -63.45583) (xy 285.820047 -63.437823) (xy 285.770447 -63.412322) (xy 285.725089 -63.379871)
			(xy 285.68494 -63.341162) (xy 285.650854 -63.297019) (xy 285.623558 -63.248384) (xy 285.603635 -63.196293)
			(xy 285.591509 -63.141856) (xy 285.587438 -63.086234) (xy 282.339561 -63.086234) (xy 282.345097 -63.105087)
			(xy 282.352855 -63.159044) (xy 282.352855 -63.213556) (xy 282.345097 -63.267513) (xy 282.329738 -63.319816)
			(xy 282.307091 -63.369401) (xy 282.277617 -63.415258) (xy 282.241917 -63.456453) (xy 282.200717 -63.492147)
			(xy 282.154857 -63.521615) (xy 282.105269 -63.544255) (xy 282.052964 -63.559607) (xy 281.999006 -63.567359)
			(xy 281.97175 -63.567818) (xy 281.94438 -63.567343) (xy 281.8902 -63.55953) (xy 281.837697 -63.544044)
			(xy 281.787949 -63.521204) (xy 281.741983 -63.49148) (xy 281.721052 -63.473838) (xy 281.720798 -63.473584)
			(xy 281.713717 -63.467989) (xy 281.696796 -63.461748) (xy 281.687778 -63.461392) (xy 281.620722 -63.461392)
			(xy 281.611706 -63.461761) (xy 281.594789 -63.468) (xy 281.587702 -63.473584) (xy 281.587448 -63.473838)
			(xy 281.566515 -63.491479) (xy 281.520547 -63.521203) (xy 281.470801 -63.544049) (xy 281.418299 -63.559545)
			(xy 281.364121 -63.567374) (xy 281.309379 -63.567374) (xy 281.255201 -63.559545) (xy 281.202699 -63.544049)
			(xy 281.152953 -63.521203) (xy 281.106985 -63.491479) (xy 281.086052 -63.473838) (xy 281.085798 -63.473584)
			(xy 281.078717 -63.467989) (xy 281.061796 -63.461748) (xy 281.052778 -63.461392) (xy 280.985722 -63.461392)
			(xy 280.976706 -63.461761) (xy 280.959789 -63.468) (xy 280.952702 -63.473584) (xy 280.952702 -63.473838)
			(xy 280.952448 -63.473838) (xy 280.931514 -63.491474) (xy 280.885541 -63.521185) (xy 280.835794 -63.544021)
			(xy 280.783294 -63.559513) (xy 280.729119 -63.567343) (xy 280.70175 -63.567818) (xy 280.674502 -63.567308)
			(xy 280.620561 -63.559546) (xy 280.568274 -63.544187) (xy 280.518704 -63.521544) (xy 280.472861 -63.492077)
			(xy 280.431678 -63.456386) (xy 280.395993 -63.415199) (xy 280.366532 -63.369352) (xy 280.343895 -63.319779)
			(xy 280.328543 -63.26749) (xy 280.320788 -63.213548) (xy 272.590238 -63.213548) (xy 272.595649 -64.312292)
			(xy 291.105842 -64.312292) (xy 291.109913 -64.25667) (xy 291.122039 -64.202233) (xy 291.141962 -64.150142)
			(xy 291.169258 -64.101507) (xy 291.203344 -64.057364) (xy 291.243493 -64.018655) (xy 291.288851 -63.986204)
			(xy 291.338451 -63.960703) (xy 291.391235 -63.942696) (xy 291.446078 -63.932566) (xy 291.501812 -63.930529)
			(xy 291.557249 -63.936629) (xy 291.611206 -63.950735) (xy 291.662535 -63.972547) (xy 291.710141 -64.001601)
			(xy 291.753009 -64.037276) (xy 291.790226 -64.078813) (xy 291.820999 -64.125326) (xy 291.844671 -64.175823)
			(xy 291.860739 -64.22923) (xy 291.868859 -64.284406) (xy 291.869368 -64.312292) (xy 291.868859 -64.340178)
			(xy 291.860739 -64.395354) (xy 291.844671 -64.448761) (xy 291.820999 -64.499258) (xy 291.790226 -64.545771)
			(xy 291.753009 -64.587308) (xy 291.710141 -64.622983) (xy 291.662535 -64.652037) (xy 291.611206 -64.673849)
			(xy 291.557249 -64.687955) (xy 291.501812 -64.694055) (xy 291.446078 -64.692018) (xy 291.391235 -64.681888)
			(xy 291.338451 -64.663881) (xy 291.288851 -64.63838) (xy 291.243493 -64.605929) (xy 291.203344 -64.56722)
			(xy 291.169258 -64.523077) (xy 291.141962 -64.474442) (xy 291.122039 -64.422351) (xy 291.109913 -64.367914)
			(xy 291.105842 -64.312292) (xy 272.595649 -64.312292) (xy 272.599533 -65.100962) (xy 278.332436 -65.100962)
			(xy 278.336507 -65.04534) (xy 278.348633 -64.990903) (xy 278.368556 -64.938812) (xy 278.395852 -64.890177)
			(xy 278.429938 -64.846034) (xy 278.470087 -64.807325) (xy 278.515445 -64.774874) (xy 278.565045 -64.749373)
			(xy 278.617829 -64.731366) (xy 278.672672 -64.721236) (xy 278.728406 -64.719199) (xy 278.783843 -64.725299)
			(xy 278.8378 -64.739405) (xy 278.889129 -64.761217) (xy 278.936735 -64.790271) (xy 278.979603 -64.825946)
			(xy 279.01682 -64.867483) (xy 279.047593 -64.913996) (xy 279.071265 -64.964493) (xy 279.087333 -65.0179)
			(xy 279.095453 -65.073076) (xy 279.095962 -65.100962) (xy 279.095453 -65.128848) (xy 279.087333 -65.184024)
			(xy 279.071265 -65.237431) (xy 279.047593 -65.287928) (xy 279.01682 -65.334441) (xy 278.979603 -65.375978)
			(xy 278.936735 -65.411653) (xy 278.889129 -65.440707) (xy 278.8378 -65.462519) (xy 278.783843 -65.476625)
			(xy 278.728406 -65.482725) (xy 278.672672 -65.480688) (xy 278.617829 -65.470558) (xy 278.565045 -65.452551)
			(xy 278.515445 -65.42705) (xy 278.470087 -65.394599) (xy 278.429938 -65.35589) (xy 278.395852 -65.311747)
			(xy 278.368556 -65.263112) (xy 278.348633 -65.211021) (xy 278.336507 -65.156584) (xy 278.332436 -65.100962)
			(xy 272.599533 -65.100962) (xy 272.600674 -65.33261) (xy 272.602146 -65.344473) (xy 272.614334 -65.365004)
			(xy 272.624042 -65.37198) (xy 272.701766 -65.418208) (xy 272.707319 -65.421078) (xy 272.719397 -65.424289)
			(xy 272.725642 -65.424558) (xy 272.74393 -65.419986) (xy 272.754598 -65.415922) (xy 272.78164 -65.402733)
			(xy 272.838839 -65.384082) (xy 272.898253 -65.374619) (xy 272.928334 -65.374012) (xy 272.93189 -65.374012)
			(xy 272.958987 -65.374721) (xy 273.012578 -65.382856) (xy 273.064478 -65.398494) (xy 273.113642 -65.421321)
			(xy 273.15908 -65.450877) (xy 273.199877 -65.486567) (xy 273.235211 -65.527672) (xy 273.264372 -65.573364)
			(xy 273.286771 -65.622725) (xy 273.301959 -65.674758) (xy 273.309628 -65.728418) (xy 273.310096 -65.75552)
			(xy 273.309608 -65.78277) (xy 273.301849 -65.836715) (xy 273.286493 -65.889006) (xy 273.26385 -65.93858)
			(xy 273.234383 -65.984427) (xy 273.198691 -66.025614) (xy 273.157502 -66.061302) (xy 273.111652 -66.090765)
			(xy 273.062076 -66.113404) (xy 273.009784 -66.128756) (xy 272.955838 -66.136511) (xy 272.928588 -66.137028)
			(xy 272.927826 -66.137028) (xy 272.897595 -66.136434) (xy 272.837895 -66.126853) (xy 272.780459 -66.107958)
			(xy 272.753328 -66.09461) (xy 272.753074 -66.094356) (xy 272.75282 -66.094102) (xy 272.747037 -66.091379)
			(xy 272.734574 -66.088563) (xy 272.728182 -66.088514) (xy 272.71472 -66.089022) (xy 272.628868 -66.141346)
			(xy 272.621639 -66.146234) (xy 272.610735 -66.159842) (xy 272.60501 -66.176313) (xy 272.604738 -66.185034)
			(xy 272.6055 -66.37274) (xy 272.605754 -66.402458) (xy 272.607024 -66.685668) (xy 272.608487 -66.697337)
			(xy 272.620391 -66.717589) (xy 272.629884 -66.72453) (xy 272.632424 -66.726054) (xy 272.64487 -66.733166)
			(xy 272.697448 -66.763392) (xy 272.703326 -66.766532) (xy 272.716188 -66.770001) (xy 272.722848 -66.77025)
			(xy 272.758408 -66.77025) (xy 272.76806 -66.76517) (xy 272.795864 -66.751042) (xy 272.854927 -66.731019)
			(xy 272.916456 -66.720852) (xy 272.947638 -66.720212) (xy 272.973681 -66.720678) (xy 273.025277 -66.727806)
			(xy 273.075424 -66.741885) (xy 273.123191 -66.762653) (xy 273.167691 -66.789723) (xy 273.188176 -66.80581)
			(xy 273.189192 -66.806318) (xy 273.191986 -66.808604) (xy 273.207988 -66.814192) (xy 273.24939 -66.814192)
			(xy 273.24939 -66.826638) (xy 273.29892 -66.826638) (xy 273.303746 -66.826384) (xy 273.311156 -66.82541)
			(xy 273.324966 -66.819721) (xy 273.330924 -66.815208) (xy 273.33194 -66.814192) (xy 273.352872 -66.796553)
			(xy 273.39884 -66.766832) (xy 273.448587 -66.743995) (xy 273.50109 -66.72851) (xy 273.555268 -66.720697)
			(xy 273.582638 -66.720212) (xy 273.609886 -66.720701) (xy 273.663827 -66.728461) (xy 273.716114 -66.743819)
			(xy 273.765684 -66.766461) (xy 273.811527 -66.795927) (xy 273.852711 -66.831616) (xy 273.888396 -66.872803)
			(xy 273.917857 -66.918649) (xy 273.940494 -66.968222) (xy 273.955847 -67.02051) (xy 273.963602 -67.074452)
			(xy 273.963602 -67.128948) (xy 273.955847 -67.18289) (xy 273.940494 -67.235178) (xy 273.917857 -67.284751)
			(xy 273.888396 -67.330597) (xy 273.852711 -67.371784) (xy 273.811527 -67.407473) (xy 273.765684 -67.436939)
			(xy 273.716114 -67.459581) (xy 273.663827 -67.474939) (xy 273.609886 -67.482699) (xy 273.582638 -67.483228)
			(xy 273.556596 -67.482761) (xy 273.505 -67.47563) (xy 273.454854 -67.46155) (xy 273.407088 -67.440782)
			(xy 273.362589 -67.413712) (xy 273.3421 -67.39763) (xy 273.341084 -67.397122) (xy 273.33829 -67.394836)
			(xy 273.322288 -67.389248) (xy 273.280886 -67.389248) (xy 273.280886 -67.376802) (xy 273.231356 -67.376802)
			(xy 273.22653 -67.377056) (xy 273.219115 -67.378018) (xy 273.205287 -67.383686) (xy 273.199352 -67.388232)
			(xy 273.198336 -67.389248) (xy 273.177405 -67.406889) (xy 273.131438 -67.436611) (xy 273.08169 -67.459449)
			(xy 273.029187 -67.474933) (xy 272.975008 -67.482743) (xy 272.947638 -67.483228) (xy 272.947384 -67.483228)
			(xy 272.915766 -67.482585) (xy 272.853399 -67.472123) (xy 272.793606 -67.451536) (xy 272.76552 -67.437)
			(xy 272.761964 -67.435222) (xy 272.754396 -67.431318) (xy 272.737647 -67.428293) (xy 272.720838 -67.430958)
			(xy 272.713196 -67.434714) (xy 272.634456 -67.48145) (xy 272.627491 -67.486339) (xy 272.626156 -67.488054)
			(xy 276.979124 -67.488054) (xy 276.983195 -67.432432) (xy 276.995321 -67.377995) (xy 277.015244 -67.325904)
			(xy 277.04254 -67.277269) (xy 277.076626 -67.233126) (xy 277.116775 -67.194417) (xy 277.162133 -67.161966)
			(xy 277.211733 -67.136465) (xy 277.264517 -67.118458) (xy 277.31936 -67.108328) (xy 277.375094 -67.106291)
			(xy 277.430531 -67.112391) (xy 277.484488 -67.126497) (xy 277.535817 -67.148309) (xy 277.583423 -67.177363)
			(xy 277.626291 -67.213038) (xy 277.663508 -67.254575) (xy 277.694281 -67.301088) (xy 277.717953 -67.351585)
			(xy 277.734021 -67.404992) (xy 277.742141 -67.460168) (xy 277.74265 -67.488054) (xy 277.742141 -67.51594)
			(xy 277.738956 -67.537584) (xy 278.271222 -67.537584) (xy 278.275293 -67.481962) (xy 278.287419 -67.427525)
			(xy 278.307342 -67.375434) (xy 278.334638 -67.326799) (xy 278.368724 -67.282656) (xy 278.408873 -67.243947)
			(xy 278.454231 -67.211496) (xy 278.503831 -67.185995) (xy 278.556615 -67.167988) (xy 278.611458 -67.157858)
			(xy 278.667192 -67.155821) (xy 278.722629 -67.161921) (xy 278.776586 -67.176027) (xy 278.827915 -67.197839)
			(xy 278.875521 -67.226893) (xy 278.918389 -67.262568) (xy 278.955606 -67.304105) (xy 278.986379 -67.350618)
			(xy 279.010051 -67.401115) (xy 279.026119 -67.454522) (xy 279.034239 -67.509698) (xy 279.034748 -67.537584)
			(xy 279.034239 -67.56547) (xy 279.030194 -67.592956) (xy 279.545286 -67.592956) (xy 279.549357 -67.537334)
			(xy 279.561483 -67.482897) (xy 279.581406 -67.430806) (xy 279.608702 -67.382171) (xy 279.642788 -67.338028)
			(xy 279.682937 -67.299319) (xy 279.728295 -67.266868) (xy 279.777895 -67.241367) (xy 279.830679 -67.22336)
			(xy 279.885522 -67.21323) (xy 279.941256 -67.211193) (xy 279.996693 -67.217293) (xy 280.05065 -67.231399)
			(xy 280.101979 -67.253211) (xy 280.149585 -67.282265) (xy 280.192453 -67.31794) (xy 280.22967 -67.359477)
			(xy 280.260443 -67.40599) (xy 280.284115 -67.456487) (xy 280.300183 -67.509894) (xy 280.3083 -67.565051)
			(xy 282.646593 -67.565051) (xy 282.646593 -67.510549) (xy 282.65435 -67.456601) (xy 282.669706 -67.404306)
			(xy 282.692348 -67.354729) (xy 282.721816 -67.308879) (xy 282.757509 -67.267689) (xy 282.798701 -67.231999)
			(xy 282.844553 -67.202535) (xy 282.894132 -67.179896) (xy 282.946428 -67.164544) (xy 283.000377 -67.156791)
			(xy 283.027628 -67.15633) (xy 283.054999 -67.156772) (xy 283.10918 -67.164595) (xy 283.161683 -67.180089)
			(xy 283.21143 -67.202936) (xy 283.257395 -67.232666) (xy 283.278326 -67.25031) (xy 283.27858 -67.250564)
			(xy 283.285663 -67.256156) (xy 283.302583 -67.262398) (xy 283.3116 -67.262756) (xy 283.378656 -67.262756)
			(xy 283.387672 -67.262387) (xy 283.404589 -67.256149) (xy 283.411676 -67.250564) (xy 283.411676 -67.25031)
			(xy 283.41193 -67.25031) (xy 283.432879 -67.232692) (xy 283.478847 -67.202976) (xy 283.52859 -67.180136)
			(xy 283.581087 -67.16464) (xy 283.63526 -67.156807) (xy 283.662628 -67.15633) (xy 283.689881 -67.156742)
			(xy 283.743831 -67.164502) (xy 283.796127 -67.179861) (xy 283.845706 -67.202506) (xy 283.891557 -67.231976)
			(xy 283.932748 -67.267671) (xy 283.96844 -67.308865) (xy 283.997907 -67.354719) (xy 284.020548 -67.404299)
			(xy 284.035904 -67.456597) (xy 284.04366 -67.510547) (xy 284.04366 -67.565053) (xy 284.035904 -67.619003)
			(xy 284.020548 -67.671301) (xy 283.997907 -67.720881) (xy 283.96844 -67.766735) (xy 283.932748 -67.807929)
			(xy 283.891557 -67.843624) (xy 283.845706 -67.873094) (xy 283.796127 -67.895739) (xy 283.743831 -67.911098)
			(xy 283.689881 -67.918858) (xy 283.662628 -67.919346) (xy 283.635258 -67.918877) (xy 283.581078 -67.911062)
			(xy 283.528575 -67.895574) (xy 283.478828 -67.872733) (xy 283.432861 -67.843008) (xy 283.41193 -67.825366)
			(xy 283.411676 -67.825112) (xy 283.4046 -67.819511) (xy 283.387675 -67.813272) (xy 283.378656 -67.81292)
			(xy 283.3116 -67.81292) (xy 283.302583 -67.813273) (xy 283.285665 -67.819523) (xy 283.27858 -67.825112)
			(xy 283.27858 -67.825366) (xy 283.278326 -67.825366) (xy 283.257391 -67.843001) (xy 283.211419 -67.872715)
			(xy 283.161673 -67.895552) (xy 283.109172 -67.911044) (xy 283.054997 -67.918872) (xy 283.027628 -67.919346)
			(xy 283.000377 -67.918809) (xy 282.946428 -67.911056) (xy 282.894132 -67.895704) (xy 282.844553 -67.873065)
			(xy 282.798701 -67.843601) (xy 282.757509 -67.807911) (xy 282.721816 -67.766721) (xy 282.692348 -67.720871)
			(xy 282.669706 -67.671294) (xy 282.65435 -67.618999) (xy 282.646593 -67.565051) (xy 280.3083 -67.565051)
			(xy 280.308303 -67.56507) (xy 280.308812 -67.592956) (xy 280.308303 -67.620842) (xy 280.300183 -67.676018)
			(xy 280.284115 -67.729425) (xy 280.260443 -67.779922) (xy 280.22967 -67.826435) (xy 280.192453 -67.867972)
			(xy 280.149585 -67.903647) (xy 280.101979 -67.932701) (xy 280.05065 -67.954513) (xy 279.996693 -67.968619)
			(xy 279.941256 -67.974719) (xy 279.885522 -67.972682) (xy 279.830679 -67.962552) (xy 279.777895 -67.944545)
			(xy 279.728295 -67.919044) (xy 279.682937 -67.886593) (xy 279.642788 -67.847884) (xy 279.608702 -67.803741)
			(xy 279.581406 -67.755106) (xy 279.561483 -67.703015) (xy 279.549357 -67.648578) (xy 279.545286 -67.592956)
			(xy 279.030194 -67.592956) (xy 279.026119 -67.620646) (xy 279.010051 -67.674053) (xy 278.986379 -67.72455)
			(xy 278.955606 -67.771063) (xy 278.918389 -67.8126) (xy 278.875521 -67.848275) (xy 278.827915 -67.877329)
			(xy 278.776586 -67.899141) (xy 278.722629 -67.913247) (xy 278.667192 -67.919347) (xy 278.611458 -67.91731)
			(xy 278.556615 -67.90718) (xy 278.503831 -67.889173) (xy 278.454231 -67.863672) (xy 278.408873 -67.831221)
			(xy 278.368724 -67.792512) (xy 278.334638 -67.748369) (xy 278.307342 -67.699734) (xy 278.287419 -67.647643)
			(xy 278.275293 -67.593206) (xy 278.271222 -67.537584) (xy 277.738956 -67.537584) (xy 277.734021 -67.571116)
			(xy 277.717953 -67.624523) (xy 277.694281 -67.67502) (xy 277.663508 -67.721533) (xy 277.626291 -67.76307)
			(xy 277.583423 -67.798745) (xy 277.535817 -67.827799) (xy 277.484488 -67.849611) (xy 277.430531 -67.863717)
			(xy 277.375094 -67.869817) (xy 277.31936 -67.86778) (xy 277.264517 -67.85765) (xy 277.211733 -67.839643)
			(xy 277.162133 -67.814142) (xy 277.116775 -67.781691) (xy 277.076626 -67.742982) (xy 277.04254 -67.698839)
			(xy 277.015244 -67.650204) (xy 276.995321 -67.598113) (xy 276.983195 -67.543676) (xy 276.979124 -67.488054)
			(xy 272.626156 -67.488054) (xy 272.617045 -67.499759) (xy 272.611598 -67.51587) (xy 272.611342 -67.524376)
			(xy 272.616479 -68.586604) (xy 274.825206 -68.586604) (xy 274.825673 -68.559234) (xy 274.83349 -68.505055)
			(xy 274.848979 -68.452552) (xy 274.871821 -68.402805) (xy 274.901545 -68.356838) (xy 274.919186 -68.335906)
			(xy 274.91944 -68.335652) (xy 274.925016 -68.328558) (xy 274.931268 -68.311647) (xy 274.931632 -68.302632)
			(xy 274.931632 -68.235576) (xy 274.93128 -68.226559) (xy 274.925028 -68.209642) (xy 274.91944 -68.202556)
			(xy 274.919186 -68.202556) (xy 274.919186 -68.202302) (xy 274.901532 -68.181382) (xy 274.871823 -68.135406)
			(xy 274.84899 -68.085655) (xy 274.833503 -68.033152) (xy 274.825678 -67.978974) (xy 274.825206 -67.951604)
			(xy 274.825659 -67.924351) (xy 274.833416 -67.870399) (xy 274.848772 -67.8181) (xy 274.871415 -67.768519)
			(xy 274.900884 -67.722665) (xy 274.936579 -67.681472) (xy 274.977773 -67.645778) (xy 275.023627 -67.61631)
			(xy 275.073209 -67.593669) (xy 275.125508 -67.578314) (xy 275.179461 -67.570558) (xy 275.206714 -67.570096)
			(xy 275.233028 -67.570555) (xy 275.285157 -67.577792) (xy 275.3358 -67.592113) (xy 275.383999 -67.613247)
			(xy 275.428842 -67.640794) (xy 275.469482 -67.674234) (xy 275.487638 -67.693286) (xy 275.495145 -67.700704)
			(xy 275.514436 -67.70922) (xy 275.524976 -67.709796) (xy 275.599652 -67.709796) (xy 275.6102 -67.709256)
			(xy 275.629496 -67.700729) (xy 275.63699 -67.693286) (xy 275.655155 -67.67424) (xy 275.695783 -67.640782)
			(xy 275.740621 -67.613222) (xy 275.78882 -67.592082) (xy 275.839466 -67.577763) (xy 275.891598 -67.570536)
			(xy 275.917914 -67.570096) (xy 275.945284 -67.570555) (xy 275.999464 -67.578375) (xy 276.051967 -67.593865)
			(xy 276.101714 -67.616709) (xy 276.14768 -67.646434) (xy 276.168612 -67.664076) (xy 276.168866 -67.66433)
			(xy 276.175956 -67.669912) (xy 276.19287 -67.67616) (xy 276.201886 -67.676522) (xy 276.268942 -67.676522)
			(xy 276.277956 -67.676133) (xy 276.294873 -67.669907) (xy 276.301962 -67.66433) (xy 276.301962 -67.664076)
			(xy 276.302216 -67.664076) (xy 276.323166 -67.646459) (xy 276.369134 -67.616745) (xy 276.418877 -67.593905)
			(xy 276.471374 -67.578409) (xy 276.525546 -67.570574) (xy 276.552914 -67.570096) (xy 276.580166 -67.570565)
			(xy 276.634114 -67.578323) (xy 276.68641 -67.59368) (xy 276.735987 -67.616323) (xy 276.781838 -67.645792)
			(xy 276.823028 -67.681485) (xy 276.858719 -67.722677) (xy 276.888185 -67.768529) (xy 276.910826 -67.818107)
			(xy 276.926181 -67.870403) (xy 276.933937 -67.924352) (xy 276.934422 -67.951604) (xy 276.933977 -67.978975)
			(xy 276.926157 -68.033156) (xy 276.910664 -68.08566) (xy 276.887817 -68.135407) (xy 276.858087 -68.181372)
			(xy 276.840442 -68.202302) (xy 276.840188 -68.202556) (xy 276.834612 -68.20965) (xy 276.828359 -68.226561)
			(xy 276.827996 -68.235576) (xy 276.827996 -68.302632) (xy 276.828339 -68.31165) (xy 276.834596 -68.328567)
			(xy 276.840188 -68.335652) (xy 276.840442 -68.335652) (xy 276.840442 -68.335906) (xy 276.858104 -68.356819)
			(xy 276.887811 -68.402798) (xy 276.910642 -68.45255) (xy 276.926128 -68.505055) (xy 276.933951 -68.559234)
			(xy 276.934422 -68.586604) (xy 276.933926 -68.613855) (xy 276.926169 -68.667801) (xy 276.910814 -68.720095)
			(xy 276.894175 -68.75653) (xy 280.37028 -68.75653) (xy 280.370744 -68.729159) (xy 280.378559 -68.67498)
			(xy 280.394048 -68.622476) (xy 280.416891 -68.572729) (xy 280.446617 -68.526763) (xy 280.46426 -68.505832)
			(xy 280.464514 -68.505578) (xy 280.470117 -68.498503) (xy 280.476354 -68.481577) (xy 280.476706 -68.472558)
			(xy 280.476706 -68.405502) (xy 280.476347 -68.396485) (xy 280.470101 -68.379568) (xy 280.464514 -68.372482)
			(xy 280.46426 -68.372482) (xy 280.46426 -68.372228) (xy 280.446614 -68.351302) (xy 280.416904 -68.305327)
			(xy 280.39407 -68.255578) (xy 280.378581 -68.203076) (xy 280.370753 -68.148899) (xy 280.37028 -68.12153)
			(xy 280.370783 -68.094278) (xy 280.378536 -68.04033) (xy 280.393887 -67.988033) (xy 280.416526 -67.938454)
			(xy 280.445989 -67.892601) (xy 280.481679 -67.851409) (xy 280.522868 -67.815714) (xy 280.568717 -67.786246)
			(xy 280.618294 -67.763602) (xy 280.670588 -67.748245) (xy 280.724536 -67.740486) (xy 280.751788 -67.740022)
			(xy 280.779158 -67.74049) (xy 280.833337 -67.748306) (xy 280.885841 -67.763795) (xy 280.935588 -67.786636)
			(xy 280.981554 -67.816361) (xy 281.002486 -67.834002) (xy 281.00274 -67.834256) (xy 281.009835 -67.83983)
			(xy 281.026745 -67.846083) (xy 281.03576 -67.846448) (xy 281.102816 -67.846448) (xy 281.111835 -67.84611)
			(xy 281.128752 -67.83985) (xy 281.135836 -67.834256) (xy 281.135836 -67.834002) (xy 281.13609 -67.834002)
			(xy 281.157015 -67.816354) (xy 281.20299 -67.786644) (xy 281.252739 -67.763809) (xy 281.305241 -67.74832)
			(xy 281.359418 -67.740495) (xy 281.386788 -67.740022) (xy 281.413102 -67.74049) (xy 281.465231 -67.747724)
			(xy 281.515874 -67.762042) (xy 281.564073 -67.783175) (xy 281.608916 -67.810721) (xy 281.649556 -67.84416)
			(xy 281.667712 -67.863212) (xy 281.675226 -67.870623) (xy 281.694512 -67.879142) (xy 281.70505 -67.879722)
			(xy 281.779726 -67.879722) (xy 281.790272 -67.87916) (xy 281.809567 -67.870647) (xy 281.817064 -67.863212)
			(xy 281.835198 -67.844135) (xy 281.875832 -67.810679) (xy 281.920677 -67.783123) (xy 281.968882 -67.761988)
			(xy 282.019533 -67.747676) (xy 282.071671 -67.740457) (xy 282.097988 -67.740022) (xy 282.125242 -67.740467)
			(xy 282.179195 -67.748223) (xy 282.231495 -67.763579) (xy 282.281077 -67.786222) (xy 282.326932 -67.815692)
			(xy 282.368125 -67.851387) (xy 282.403819 -67.892583) (xy 282.433287 -67.938439) (xy 282.455928 -67.988022)
			(xy 282.471281 -68.040323) (xy 282.479035 -68.094276) (xy 282.479496 -68.12153) (xy 282.479048 -68.148901)
			(xy 282.471226 -68.203081) (xy 282.455733 -68.255584) (xy 282.432887 -68.305331) (xy 282.403159 -68.351297)
			(xy 282.385516 -68.372228) (xy 282.385262 -68.372482) (xy 282.379673 -68.379566) (xy 282.373429 -68.396485)
			(xy 282.37307 -68.405502) (xy 282.37307 -68.472558) (xy 282.373454 -68.481572) (xy 282.379683 -68.498489)
			(xy 282.385262 -68.505578) (xy 282.385516 -68.505578) (xy 282.385516 -68.505832) (xy 282.403139 -68.526777)
			(xy 282.432853 -68.572746) (xy 282.455692 -68.622491) (xy 282.471186 -68.674988) (xy 282.479019 -68.729162)
			(xy 282.479496 -68.75653) (xy 282.47905 -68.783783) (xy 282.471289 -68.837732) (xy 282.45593 -68.890029)
			(xy 282.433284 -68.939607) (xy 282.403814 -68.985457) (xy 282.368118 -69.026648) (xy 282.326924 -69.062339)
			(xy 282.28107 -69.091804) (xy 282.231489 -69.114444) (xy 282.179191 -69.129798) (xy 282.125241 -69.137553)
			(xy 282.097988 -69.138038) (xy 282.071673 -69.137598) (xy 282.019542 -69.130361) (xy 281.968898 -69.116037)
			(xy 281.920699 -69.0949) (xy 281.875856 -69.067348) (xy 281.835219 -69.033903) (xy 281.817064 -69.014848)
			(xy 281.809551 -69.007436) (xy 281.790265 -68.998916) (xy 281.779726 -68.998338) (xy 281.70505 -68.998338)
			(xy 281.6945 -68.998869) (xy 281.675204 -69.007402) (xy 281.667712 -69.014848) (xy 281.649553 -69.0339)
			(xy 281.608923 -69.067356) (xy 281.564083 -69.094914) (xy 281.515883 -69.116053) (xy 281.465237 -69.130371)
			(xy 281.413104 -69.137598) (xy 281.386788 -69.138038) (xy 281.359417 -69.137594) (xy 281.305236 -69.129773)
			(xy 281.252732 -69.11428) (xy 281.202986 -69.091433) (xy 281.15702 -69.061702) (xy 281.13609 -69.044058)
			(xy 281.135836 -69.043804) (xy 281.128743 -69.038227) (xy 281.111831 -69.031974) (xy 281.102816 -69.031612)
			(xy 281.03576 -69.031612) (xy 281.026741 -69.031947) (xy 281.009824 -69.03821) (xy 281.00274 -69.043804)
			(xy 281.00274 -69.044058) (xy 281.002486 -69.044058) (xy 280.981527 -69.061664) (xy 280.935562 -69.091382)
			(xy 280.885822 -69.114225) (xy 280.833327 -69.129724) (xy 280.779155 -69.13756) (xy 280.751788 -69.138038)
			(xy 280.724538 -69.137533) (xy 280.670592 -69.129776) (xy 280.6183 -69.114421) (xy 280.568724 -69.091781)
			(xy 280.522876 -69.062316) (xy 280.481686 -69.026626) (xy 280.445995 -68.985439) (xy 280.416528 -68.939591)
			(xy 280.393885 -68.890017) (xy 280.378528 -68.837725) (xy 280.370768 -68.78378) (xy 280.37028 -68.75653)
			(xy 276.894175 -68.75653) (xy 276.888174 -68.769671) (xy 276.858708 -68.815521) (xy 276.823018 -68.856711)
			(xy 276.781829 -68.892402) (xy 276.73598 -68.921869) (xy 276.686404 -68.944511) (xy 276.634111 -68.959867)
			(xy 276.580165 -68.967625) (xy 276.552914 -68.968112) (xy 276.525544 -68.967635) (xy 276.471366 -68.959819)
			(xy 276.418863 -68.944333) (xy 276.369116 -68.921493) (xy 276.323148 -68.891772) (xy 276.302216 -68.874132)
			(xy 276.301962 -68.873878) (xy 276.294864 -68.868309) (xy 276.277956 -68.862052) (xy 276.268942 -68.861686)
			(xy 276.201886 -68.861686) (xy 276.192869 -68.86204) (xy 276.175952 -68.86829) (xy 276.168866 -68.873878)
			(xy 276.168866 -68.874132) (xy 276.168612 -68.874132) (xy 276.14769 -68.891784) (xy 276.101714 -68.921493)
			(xy 276.051964 -68.944326) (xy 275.999461 -68.959814) (xy 275.945284 -68.967639) (xy 275.917914 -68.968112)
			(xy 275.891601 -68.967631) (xy 275.839473 -68.960399) (xy 275.78883 -68.946082) (xy 275.740631 -68.924952)
			(xy 275.695788 -68.897408) (xy 275.655147 -68.863972) (xy 275.63699 -68.844922) (xy 275.629471 -68.837517)
			(xy 275.610189 -68.828994) (xy 275.599652 -68.828412) (xy 275.524976 -68.828412) (xy 275.514429 -68.828965)
			(xy 275.495133 -68.837483) (xy 275.487638 -68.844922) (xy 275.46951 -68.864005) (xy 275.428874 -68.897459)
			(xy 275.384028 -68.925014) (xy 275.335822 -68.946147) (xy 275.285169 -68.960459) (xy 275.233032 -68.967677)
			(xy 275.206714 -68.968112) (xy 275.179462 -68.967632) (xy 275.125512 -68.959877) (xy 275.073214 -68.944523)
			(xy 275.023634 -68.921882) (xy 274.977781 -68.892416) (xy 274.936589 -68.856724) (xy 274.900895 -68.815533)
			(xy 274.871427 -68.769681) (xy 274.848784 -68.720103) (xy 274.833427 -68.667806) (xy 274.82567 -68.613856)
			(xy 274.825206 -68.586604) (xy 272.616479 -68.586604) (xy 272.630839 -71.555864) (xy 277.394414 -71.555864)
			(xy 277.398485 -71.500242) (xy 277.410611 -71.445805) (xy 277.430534 -71.393714) (xy 277.45783 -71.345079)
			(xy 277.491916 -71.300936) (xy 277.532065 -71.262227) (xy 277.577423 -71.229776) (xy 277.627023 -71.204275)
			(xy 277.679807 -71.186268) (xy 277.73465 -71.176138) (xy 277.790384 -71.174101) (xy 277.845821 -71.180201)
			(xy 277.899778 -71.194307) (xy 277.951107 -71.216119) (xy 277.998713 -71.245173) (xy 278.041581 -71.280848)
			(xy 278.078798 -71.322385) (xy 278.109571 -71.368898) (xy 278.133243 -71.419395) (xy 278.149311 -71.472802)
			(xy 278.157431 -71.527978) (xy 278.15794 -71.555864) (xy 278.157431 -71.58375) (xy 278.151592 -71.623428)
			(xy 278.903428 -71.623428) (xy 278.907499 -71.567806) (xy 278.919625 -71.513369) (xy 278.939548 -71.461278)
			(xy 278.966844 -71.412643) (xy 279.00093 -71.3685) (xy 279.041079 -71.329791) (xy 279.086437 -71.29734)
			(xy 279.136037 -71.271839) (xy 279.188821 -71.253832) (xy 279.243664 -71.243702) (xy 279.299398 -71.241665)
			(xy 279.354835 -71.247765) (xy 279.408792 -71.261871) (xy 279.460121 -71.283683) (xy 279.507727 -71.312737)
			(xy 279.550595 -71.348412) (xy 279.587812 -71.389949) (xy 279.618585 -71.436462) (xy 279.642257 -71.486959)
			(xy 279.658325 -71.540366) (xy 279.666445 -71.595542) (xy 279.666954 -71.623428) (xy 279.666445 -71.651314)
			(xy 279.658325 -71.70649) (xy 279.642257 -71.759897) (xy 279.618585 -71.810394) (xy 279.587812 -71.856907)
			(xy 279.550595 -71.898444) (xy 279.507727 -71.934119) (xy 279.460121 -71.963173) (xy 279.408792 -71.984985)
			(xy 279.354835 -71.999091) (xy 279.299398 -72.005191) (xy 279.243664 -72.003154) (xy 279.188821 -71.993024)
			(xy 279.136037 -71.975017) (xy 279.086437 -71.949516) (xy 279.041079 -71.917065) (xy 279.00093 -71.878356)
			(xy 278.966844 -71.834213) (xy 278.939548 -71.785578) (xy 278.919625 -71.733487) (xy 278.907499 -71.67905)
			(xy 278.903428 -71.623428) (xy 278.151592 -71.623428) (xy 278.149311 -71.638926) (xy 278.133243 -71.692333)
			(xy 278.109571 -71.74283) (xy 278.078798 -71.789343) (xy 278.041581 -71.83088) (xy 277.998713 -71.866555)
			(xy 277.951107 -71.895609) (xy 277.899778 -71.917421) (xy 277.845821 -71.931527) (xy 277.790384 -71.937627)
			(xy 277.73465 -71.93559) (xy 277.679807 -71.92546) (xy 277.627023 -71.907453) (xy 277.577423 -71.881952)
			(xy 277.532065 -71.849501) (xy 277.491916 -71.810792) (xy 277.45783 -71.766649) (xy 277.430534 -71.718014)
			(xy 277.410611 -71.665923) (xy 277.398485 -71.611486) (xy 277.394414 -71.555864) (xy 272.630839 -71.555864)
			(xy 272.666287 -78.885796) (xy 273.067016 -78.885796) (xy 273.071087 -78.830174) (xy 273.083213 -78.775737)
			(xy 273.103136 -78.723646) (xy 273.130432 -78.675011) (xy 273.164518 -78.630868) (xy 273.204667 -78.592159)
			(xy 273.250025 -78.559708) (xy 273.299625 -78.534207) (xy 273.352409 -78.5162) (xy 273.407252 -78.50607)
			(xy 273.462986 -78.504033) (xy 273.518423 -78.510133) (xy 273.57238 -78.524239) (xy 273.623709 -78.546051)
			(xy 273.671315 -78.575105) (xy 273.714183 -78.61078) (xy 273.7514 -78.652317) (xy 273.782173 -78.69883)
			(xy 273.805845 -78.749327) (xy 273.821913 -78.802734) (xy 273.824082 -78.81747) (xy 277.361394 -78.81747)
			(xy 277.365465 -78.761848) (xy 277.377591 -78.707411) (xy 277.397514 -78.65532) (xy 277.42481 -78.606685)
			(xy 277.458896 -78.562542) (xy 277.499045 -78.523833) (xy 277.544403 -78.491382) (xy 277.594003 -78.465881)
			(xy 277.646787 -78.447874) (xy 277.70163 -78.437744) (xy 277.757364 -78.435707) (xy 277.812801 -78.441807)
			(xy 277.866758 -78.455913) (xy 277.918087 -78.477725) (xy 277.965693 -78.506779) (xy 278.008561 -78.542454)
			(xy 278.045778 -78.583991) (xy 278.076551 -78.630504) (xy 278.100223 -78.681001) (xy 278.116291 -78.734408)
			(xy 278.124411 -78.789584) (xy 278.12492 -78.81747) (xy 278.124411 -78.845356) (xy 278.116291 -78.900532)
			(xy 278.100223 -78.953939) (xy 278.076551 -79.004436) (xy 278.045778 -79.050949) (xy 278.008561 -79.092486)
			(xy 277.965693 -79.128161) (xy 277.918087 -79.157215) (xy 277.866758 -79.179027) (xy 277.812801 -79.193133)
			(xy 277.757364 -79.199233) (xy 277.70163 -79.197196) (xy 277.646787 -79.187066) (xy 277.594003 -79.169059)
			(xy 277.544403 -79.143558) (xy 277.499045 -79.111107) (xy 277.458896 -79.072398) (xy 277.42481 -79.028255)
			(xy 277.397514 -78.97962) (xy 277.377591 -78.927529) (xy 277.365465 -78.873092) (xy 277.361394 -78.81747)
			(xy 273.824082 -78.81747) (xy 273.830033 -78.85791) (xy 273.830542 -78.885796) (xy 273.830033 -78.913682)
			(xy 273.821913 -78.968858) (xy 273.805845 -79.022265) (xy 273.782173 -79.072762) (xy 273.7514 -79.119275)
			(xy 273.714183 -79.160812) (xy 273.671315 -79.196487) (xy 273.623709 -79.225541) (xy 273.57238 -79.247353)
			(xy 273.518423 -79.261459) (xy 273.462986 -79.267559) (xy 273.407252 -79.265522) (xy 273.352409 -79.255392)
			(xy 273.299625 -79.237385) (xy 273.250025 -79.211884) (xy 273.204667 -79.179433) (xy 273.164518 -79.140724)
			(xy 273.130432 -79.096581) (xy 273.103136 -79.047946) (xy 273.083213 -78.995855) (xy 273.071087 -78.941418)
			(xy 273.067016 -78.885796) (xy 272.666287 -78.885796) (xy 272.681234 -81.976468) (xy 273.798284 -81.976468)
			(xy 273.798284 -81.112868) (xy 273.798774 -81.0829) (xy 273.806597 -81.023478) (xy 273.82211 -80.965585)
			(xy 273.845046 -80.910212) (xy 273.875013 -80.858306) (xy 273.9115 -80.810756) (xy 273.95388 -80.768376)
			(xy 274.00143 -80.731889) (xy 274.053336 -80.701922) (xy 274.108709 -80.678986) (xy 274.166602 -80.663473)
			(xy 274.226024 -80.65565) (xy 274.28596 -80.65565) (xy 274.345382 -80.663473) (xy 274.403275 -80.678986)
			(xy 274.458648 -80.701922) (xy 274.510554 -80.731889) (xy 274.558104 -80.768376) (xy 274.600484 -80.810756)
			(xy 274.636971 -80.858306) (xy 274.666938 -80.910212) (xy 274.689874 -80.965585) (xy 274.705387 -81.023478)
			(xy 274.71321 -81.0829) (xy 274.7137 -81.112868) (xy 274.7137 -81.976468) (xy 274.71321 -82.006436)
			(xy 274.705387 -82.065858) (xy 274.689874 -82.123751) (xy 274.666938 -82.179124) (xy 274.636971 -82.23103)
			(xy 274.600484 -82.27858) (xy 274.558104 -82.32096) (xy 274.510554 -82.357447) (xy 274.458648 -82.387414)
			(xy 274.403275 -82.41035) (xy 274.345382 -82.425863) (xy 274.28596 -82.433686) (xy 274.226024 -82.433686)
			(xy 274.166602 -82.425863) (xy 274.108709 -82.41035) (xy 274.053336 -82.387414) (xy 274.00143 -82.357447)
			(xy 273.95388 -82.32096) (xy 273.9115 -82.27858) (xy 273.875013 -82.23103) (xy 273.845046 -82.179124)
			(xy 273.82211 -82.123751) (xy 273.806597 -82.065858) (xy 273.798774 -82.006436) (xy 273.798284 -81.976468)
			(xy 272.681234 -81.976468) (xy 272.692183 -84.24037) (xy 273.951192 -84.24037) (xy 273.951192 -83.37677)
			(xy 273.951682 -83.346786) (xy 273.95951 -83.28733) (xy 273.975031 -83.229405) (xy 273.99798 -83.174001)
			(xy 274.027964 -83.122067) (xy 274.06447 -83.074491) (xy 274.106875 -83.032086) (xy 274.154451 -82.99558)
			(xy 274.206385 -82.965596) (xy 274.261789 -82.942647) (xy 274.319714 -82.927126) (xy 274.37917 -82.919298)
			(xy 274.439138 -82.919298) (xy 274.498594 -82.927126) (xy 274.556519 -82.942647) (xy 274.611923 -82.965596)
			(xy 274.663857 -82.99558) (xy 274.711433 -83.032086) (xy 274.753838 -83.074491) (xy 274.790344 -83.122067)
			(xy 274.820328 -83.174001) (xy 274.843277 -83.229405) (xy 274.845331 -83.23707) (xy 281.247848 -83.23707)
			(xy 281.251919 -83.181448) (xy 281.264045 -83.127011) (xy 281.283968 -83.07492) (xy 281.311264 -83.026285)
			(xy 281.34535 -82.982142) (xy 281.385499 -82.943433) (xy 281.430857 -82.910982) (xy 281.480457 -82.885481)
			(xy 281.533241 -82.867474) (xy 281.588084 -82.857344) (xy 281.643818 -82.855307) (xy 281.699255 -82.861407)
			(xy 281.753212 -82.875513) (xy 281.804541 -82.897325) (xy 281.852147 -82.926379) (xy 281.895015 -82.962054)
			(xy 281.932232 -83.003591) (xy 281.963005 -83.050104) (xy 281.986677 -83.100601) (xy 282.002745 -83.154008)
			(xy 282.010865 -83.209184) (xy 282.011374 -83.23707) (xy 282.010865 -83.264956) (xy 282.002745 -83.320132)
			(xy 281.986677 -83.373539) (xy 281.963005 -83.424036) (xy 281.932232 -83.470549) (xy 281.895015 -83.512086)
			(xy 281.852147 -83.547761) (xy 281.822262 -83.566) (xy 282.827982 -83.566) (xy 282.832053 -83.510378)
			(xy 282.844179 -83.455941) (xy 282.864102 -83.40385) (xy 282.891398 -83.355215) (xy 282.925484 -83.311072)
			(xy 282.965633 -83.272363) (xy 283.010991 -83.239912) (xy 283.060591 -83.214411) (xy 283.113375 -83.196404)
			(xy 283.168218 -83.186274) (xy 283.223952 -83.184237) (xy 283.279389 -83.190337) (xy 283.333346 -83.204443)
			(xy 283.384675 -83.226255) (xy 283.432281 -83.255309) (xy 283.475149 -83.290984) (xy 283.512366 -83.332521)
			(xy 283.543139 -83.379034) (xy 283.566811 -83.429531) (xy 283.582879 -83.482938) (xy 283.590999 -83.538114)
			(xy 283.591508 -83.566) (xy 283.590999 -83.593886) (xy 283.582879 -83.649062) (xy 283.566811 -83.702469)
			(xy 283.543139 -83.752966) (xy 283.512366 -83.799479) (xy 283.475149 -83.841016) (xy 283.432281 -83.876691)
			(xy 283.384675 -83.905745) (xy 283.333346 -83.927557) (xy 283.279389 -83.941663) (xy 283.223952 -83.947763)
			(xy 283.168218 -83.945726) (xy 283.113375 -83.935596) (xy 283.060591 -83.917589) (xy 283.010991 -83.892088)
			(xy 282.965633 -83.859637) (xy 282.925484 -83.820928) (xy 282.891398 -83.776785) (xy 282.864102 -83.72815)
			(xy 282.844179 -83.676059) (xy 282.832053 -83.621622) (xy 282.827982 -83.566) (xy 281.822262 -83.566)
			(xy 281.804541 -83.576815) (xy 281.753212 -83.598627) (xy 281.699255 -83.612733) (xy 281.643818 -83.618833)
			(xy 281.588084 -83.616796) (xy 281.533241 -83.606666) (xy 281.480457 -83.588659) (xy 281.430857 -83.563158)
			(xy 281.385499 -83.530707) (xy 281.34535 -83.491998) (xy 281.311264 -83.447855) (xy 281.283968 -83.39922)
			(xy 281.264045 -83.347129) (xy 281.251919 -83.292692) (xy 281.247848 -83.23707) (xy 274.845331 -83.23707)
			(xy 274.858798 -83.28733) (xy 274.866626 -83.346786) (xy 274.867116 -83.37677) (xy 274.867116 -84.24037)
			(xy 274.866626 -84.270354) (xy 274.858798 -84.32981) (xy 274.843277 -84.387735) (xy 274.820328 -84.443139)
			(xy 274.790344 -84.495073) (xy 274.753838 -84.542649) (xy 274.711433 -84.585054) (xy 274.663857 -84.62156)
			(xy 274.611923 -84.651544) (xy 274.556519 -84.674493) (xy 274.498594 -84.690014) (xy 274.439138 -84.697842)
			(xy 274.37917 -84.697842) (xy 274.319714 -84.690014) (xy 274.261789 -84.674493) (xy 274.206385 -84.651544)
			(xy 274.154451 -84.62156) (xy 274.106875 -84.585054) (xy 274.06447 -84.542649) (xy 274.027964 -84.495073)
			(xy 273.99798 -84.443139) (xy 273.975031 -84.387735) (xy 273.95951 -84.32981) (xy 273.951682 -84.270354)
			(xy 273.951192 -84.24037) (xy 272.692183 -84.24037) (xy 272.695064 -84.836) (xy 282.827982 -84.836)
			(xy 282.832053 -84.780378) (xy 282.844179 -84.725941) (xy 282.864102 -84.67385) (xy 282.891398 -84.625215)
			(xy 282.925484 -84.581072) (xy 282.965633 -84.542363) (xy 283.010991 -84.509912) (xy 283.060591 -84.484411)
			(xy 283.113375 -84.466404) (xy 283.168218 -84.456274) (xy 283.223952 -84.454237) (xy 283.279389 -84.460337)
			(xy 283.333346 -84.474443) (xy 283.384675 -84.496255) (xy 283.432281 -84.525309) (xy 283.475149 -84.560984)
			(xy 283.512366 -84.602521) (xy 283.543139 -84.649034) (xy 283.566811 -84.699531) (xy 283.582879 -84.752938)
			(xy 283.590999 -84.808114) (xy 283.591508 -84.836) (xy 283.590999 -84.863886) (xy 283.582879 -84.919062)
			(xy 283.566811 -84.972469) (xy 283.543139 -85.022966) (xy 283.512366 -85.069479) (xy 283.475149 -85.111016)
			(xy 283.432281 -85.146691) (xy 283.384675 -85.175745) (xy 283.333346 -85.197557) (xy 283.279389 -85.211663)
			(xy 283.223952 -85.217763) (xy 283.168218 -85.215726) (xy 283.113375 -85.205596) (xy 283.060591 -85.187589)
			(xy 283.010991 -85.162088) (xy 282.965633 -85.129637) (xy 282.925484 -85.090928) (xy 282.891398 -85.046785)
			(xy 282.864102 -84.99815) (xy 282.844179 -84.946059) (xy 282.832053 -84.891622) (xy 282.827982 -84.836)
			(xy 272.695064 -84.836) (xy 272.70338 -86.55558) (xy 274.52142 -86.55558) (xy 274.525491 -86.499958)
			(xy 274.537617 -86.445521) (xy 274.55754 -86.39343) (xy 274.584836 -86.344795) (xy 274.618922 -86.300652)
			(xy 274.659071 -86.261943) (xy 274.704429 -86.229492) (xy 274.754029 -86.203991) (xy 274.806813 -86.185984)
			(xy 274.861656 -86.175854) (xy 274.91739 -86.173817) (xy 274.972827 -86.179917) (xy 275.026784 -86.194023)
			(xy 275.078113 -86.215835) (xy 275.125719 -86.244889) (xy 275.168587 -86.280564) (xy 275.197658 -86.31301)
			(xy 275.364192 -86.31301) (xy 275.368263 -86.257388) (xy 275.380389 -86.202951) (xy 275.400312 -86.15086)
			(xy 275.427608 -86.102225) (xy 275.461694 -86.058082) (xy 275.501843 -86.019373) (xy 275.547201 -85.986922)
			(xy 275.596801 -85.961421) (xy 275.649585 -85.943414) (xy 275.704428 -85.933284) (xy 275.760162 -85.931247)
			(xy 275.815599 -85.937347) (xy 275.869556 -85.951453) (xy 275.920885 -85.973265) (xy 275.968491 -86.002319)
			(xy 276.011359 -86.037994) (xy 276.048576 -86.079531) (xy 276.079349 -86.126044) (xy 276.103021 -86.176541)
			(xy 276.119089 -86.229948) (xy 276.127209 -86.285124) (xy 276.127718 -86.31301) (xy 276.127209 -86.340896)
			(xy 276.119089 -86.396072) (xy 276.105641 -86.440772) (xy 277.126698 -86.440772) (xy 277.130769 -86.38515)
			(xy 277.142895 -86.330713) (xy 277.162818 -86.278622) (xy 277.190114 -86.229987) (xy 277.2242 -86.185844)
			(xy 277.264349 -86.147135) (xy 277.309707 -86.114684) (xy 277.359307 -86.089183) (xy 277.412091 -86.071176)
			(xy 277.466934 -86.061046) (xy 277.522668 -86.059009) (xy 277.578105 -86.065109) (xy 277.632062 -86.079215)
			(xy 277.683391 -86.101027) (xy 277.730997 -86.130081) (xy 277.773865 -86.165756) (xy 277.811082 -86.207293)
			(xy 277.841855 -86.253806) (xy 277.865527 -86.304303) (xy 277.881595 -86.35771) (xy 277.889715 -86.412886)
			(xy 277.890224 -86.440772) (xy 277.889715 -86.468658) (xy 277.887875 -86.481158) (xy 278.503886 -86.481158)
			(xy 278.507957 -86.425536) (xy 278.520083 -86.371099) (xy 278.540006 -86.319008) (xy 278.567302 -86.270373)
			(xy 278.601388 -86.22623) (xy 278.641537 -86.187521) (xy 278.686895 -86.15507) (xy 278.736495 -86.129569)
			(xy 278.789279 -86.111562) (xy 278.844122 -86.101432) (xy 278.899856 -86.099395) (xy 278.955293 -86.105495)
			(xy 278.957225 -86.106) (xy 282.827982 -86.106) (xy 282.832053 -86.050378) (xy 282.844179 -85.995941)
			(xy 282.864102 -85.94385) (xy 282.891398 -85.895215) (xy 282.925484 -85.851072) (xy 282.965633 -85.812363)
			(xy 283.010991 -85.779912) (xy 283.060591 -85.754411) (xy 283.113375 -85.736404) (xy 283.168218 -85.726274)
			(xy 283.223952 -85.724237) (xy 283.279389 -85.730337) (xy 283.333346 -85.744443) (xy 283.384675 -85.766255)
			(xy 283.432281 -85.795309) (xy 283.475149 -85.830984) (xy 283.512366 -85.872521) (xy 283.543139 -85.919034)
			(xy 283.566811 -85.969531) (xy 283.582879 -86.022938) (xy 283.590999 -86.078114) (xy 283.591508 -86.106)
			(xy 283.590999 -86.133886) (xy 283.582879 -86.189062) (xy 283.566811 -86.242469) (xy 283.543139 -86.292966)
			(xy 283.512366 -86.339479) (xy 283.475149 -86.381016) (xy 283.432281 -86.416691) (xy 283.384675 -86.445745)
			(xy 283.333346 -86.467557) (xy 283.279389 -86.481663) (xy 283.223952 -86.487763) (xy 283.168218 -86.485726)
			(xy 283.113375 -86.475596) (xy 283.060591 -86.457589) (xy 283.010991 -86.432088) (xy 282.965633 -86.399637)
			(xy 282.925484 -86.360928) (xy 282.891398 -86.316785) (xy 282.864102 -86.26815) (xy 282.844179 -86.216059)
			(xy 282.832053 -86.161622) (xy 282.827982 -86.106) (xy 278.957225 -86.106) (xy 279.00925 -86.119601)
			(xy 279.060579 -86.141413) (xy 279.108185 -86.170467) (xy 279.151053 -86.206142) (xy 279.18827 -86.247679)
			(xy 279.219043 -86.294192) (xy 279.242715 -86.344689) (xy 279.258783 -86.398096) (xy 279.266903 -86.453272)
			(xy 279.267412 -86.481158) (xy 279.267101 -86.498176) (xy 279.88971 -86.498176) (xy 279.893781 -86.442554)
			(xy 279.905907 -86.388117) (xy 279.92583 -86.336026) (xy 279.953126 -86.287391) (xy 279.987212 -86.243248)
			(xy 280.027361 -86.204539) (xy 280.072719 -86.172088) (xy 280.122319 -86.146587) (xy 280.175103 -86.12858)
			(xy 280.229946 -86.11845) (xy 280.28568 -86.116413) (xy 280.341117 -86.122513) (xy 280.395074 -86.136619)
			(xy 280.446403 -86.158431) (xy 280.494009 -86.187485) (xy 280.536877 -86.22316) (xy 280.574094 -86.264697)
			(xy 280.604867 -86.31121) (xy 280.628539 -86.361707) (xy 280.644607 -86.415114) (xy 280.652727 -86.47029)
			(xy 280.653236 -86.498176) (xy 280.652727 -86.526062) (xy 280.644607 -86.581238) (xy 280.628539 -86.634645)
			(xy 280.604867 -86.685142) (xy 280.574094 -86.731655) (xy 280.536877 -86.773192) (xy 280.494009 -86.808867)
			(xy 280.446403 -86.837921) (xy 280.395074 -86.859733) (xy 280.341117 -86.873839) (xy 280.28568 -86.879939)
			(xy 280.229946 -86.877902) (xy 280.175103 -86.867772) (xy 280.122319 -86.849765) (xy 280.072719 -86.824264)
			(xy 280.027361 -86.791813) (xy 279.987212 -86.753104) (xy 279.953126 -86.708961) (xy 279.92583 -86.660326)
			(xy 279.905907 -86.608235) (xy 279.893781 -86.553798) (xy 279.88971 -86.498176) (xy 279.267101 -86.498176)
			(xy 279.266903 -86.509044) (xy 279.258783 -86.56422) (xy 279.242715 -86.617627) (xy 279.219043 -86.668124)
			(xy 279.18827 -86.714637) (xy 279.151053 -86.756174) (xy 279.108185 -86.791849) (xy 279.060579 -86.820903)
			(xy 279.00925 -86.842715) (xy 278.955293 -86.856821) (xy 278.899856 -86.862921) (xy 278.844122 -86.860884)
			(xy 278.789279 -86.850754) (xy 278.736495 -86.832747) (xy 278.686895 -86.807246) (xy 278.641537 -86.774795)
			(xy 278.601388 -86.736086) (xy 278.567302 -86.691943) (xy 278.540006 -86.643308) (xy 278.520083 -86.591217)
			(xy 278.507957 -86.53678) (xy 278.503886 -86.481158) (xy 277.887875 -86.481158) (xy 277.881595 -86.523834)
			(xy 277.865527 -86.577241) (xy 277.841855 -86.627738) (xy 277.811082 -86.674251) (xy 277.773865 -86.715788)
			(xy 277.730997 -86.751463) (xy 277.683391 -86.780517) (xy 277.632062 -86.802329) (xy 277.578105 -86.816435)
			(xy 277.522668 -86.822535) (xy 277.466934 -86.820498) (xy 277.412091 -86.810368) (xy 277.359307 -86.792361)
			(xy 277.309707 -86.76686) (xy 277.264349 -86.734409) (xy 277.2242 -86.6957) (xy 277.190114 -86.651557)
			(xy 277.162818 -86.602922) (xy 277.142895 -86.550831) (xy 277.130769 -86.496394) (xy 277.126698 -86.440772)
			(xy 276.105641 -86.440772) (xy 276.103021 -86.449479) (xy 276.079349 -86.499976) (xy 276.048576 -86.546489)
			(xy 276.011359 -86.588026) (xy 275.968491 -86.623701) (xy 275.920885 -86.652755) (xy 275.869556 -86.674567)
			(xy 275.815599 -86.688673) (xy 275.760162 -86.694773) (xy 275.704428 -86.692736) (xy 275.649585 -86.682606)
			(xy 275.596801 -86.664599) (xy 275.547201 -86.639098) (xy 275.501843 -86.606647) (xy 275.461694 -86.567938)
			(xy 275.427608 -86.523795) (xy 275.400312 -86.47516) (xy 275.380389 -86.423069) (xy 275.368263 -86.368632)
			(xy 275.364192 -86.31301) (xy 275.197658 -86.31301) (xy 275.205804 -86.322101) (xy 275.236577 -86.368614)
			(xy 275.260249 -86.419111) (xy 275.276317 -86.472518) (xy 275.284437 -86.527694) (xy 275.284946 -86.55558)
			(xy 275.284437 -86.583466) (xy 275.276317 -86.638642) (xy 275.260249 -86.692049) (xy 275.236577 -86.742546)
			(xy 275.205804 -86.789059) (xy 275.168587 -86.830596) (xy 275.125719 -86.866271) (xy 275.078113 -86.895325)
			(xy 275.026784 -86.917137) (xy 274.972827 -86.931243) (xy 274.91739 -86.937343) (xy 274.861656 -86.935306)
			(xy 274.806813 -86.925176) (xy 274.754029 -86.907169) (xy 274.704429 -86.881668) (xy 274.659071 -86.849217)
			(xy 274.618922 -86.810508) (xy 274.584836 -86.766365) (xy 274.55754 -86.71773) (xy 274.537617 -86.665639)
			(xy 274.525491 -86.611202) (xy 274.52142 -86.55558) (xy 272.70338 -86.55558) (xy 272.712876 -88.519254)
			(xy 274.64588 -88.519254) (xy 274.649951 -88.463632) (xy 274.662077 -88.409195) (xy 274.682 -88.357104)
			(xy 274.709296 -88.308469) (xy 274.743382 -88.264326) (xy 274.783531 -88.225617) (xy 274.828889 -88.193166)
			(xy 274.878489 -88.167665) (xy 274.931273 -88.149658) (xy 274.986116 -88.139528) (xy 275.04185 -88.137491)
			(xy 275.097287 -88.143591) (xy 275.151244 -88.157697) (xy 275.202573 -88.179509) (xy 275.250179 -88.208563)
			(xy 275.293047 -88.244238) (xy 275.330264 -88.285775) (xy 275.361037 -88.332288) (xy 275.384709 -88.382785)
			(xy 275.400777 -88.436192) (xy 275.408897 -88.491368) (xy 275.409406 -88.519254) (xy 275.408897 -88.54714)
			(xy 275.400777 -88.602316) (xy 275.384709 -88.655723) (xy 275.361037 -88.70622) (xy 275.330264 -88.752733)
			(xy 275.293047 -88.79427) (xy 275.250179 -88.829945) (xy 275.202573 -88.858999) (xy 275.151244 -88.880811)
			(xy 275.097287 -88.894917) (xy 275.04185 -88.901017) (xy 274.986116 -88.89898) (xy 274.931273 -88.88885)
			(xy 274.878489 -88.870843) (xy 274.828889 -88.845342) (xy 274.783531 -88.812891) (xy 274.743382 -88.774182)
			(xy 274.709296 -88.730039) (xy 274.682 -88.681404) (xy 274.662077 -88.629313) (xy 274.649951 -88.574876)
			(xy 274.64588 -88.519254) (xy 272.712876 -88.519254) (xy 272.718862 -89.756996) (xy 277.128476 -89.756996)
			(xy 277.132547 -89.701374) (xy 277.144673 -89.646937) (xy 277.164596 -89.594846) (xy 277.191892 -89.546211)
			(xy 277.225978 -89.502068) (xy 277.266127 -89.463359) (xy 277.311485 -89.430908) (xy 277.361085 -89.405407)
			(xy 277.413869 -89.3874) (xy 277.468712 -89.37727) (xy 277.524446 -89.375233) (xy 277.579883 -89.381333)
			(xy 277.63384 -89.395439) (xy 277.685169 -89.417251) (xy 277.732775 -89.446305) (xy 277.775643 -89.48198)
			(xy 277.81286 -89.523517) (xy 277.843633 -89.57003) (xy 277.867305 -89.620527) (xy 277.883373 -89.673934)
			(xy 277.891493 -89.72911) (xy 277.892002 -89.756996) (xy 277.891863 -89.764616) (xy 278.724612 -89.764616)
			(xy 278.728683 -89.708994) (xy 278.740809 -89.654557) (xy 278.760732 -89.602466) (xy 278.788028 -89.553831)
			(xy 278.822114 -89.509688) (xy 278.862263 -89.470979) (xy 278.907621 -89.438528) (xy 278.957221 -89.413027)
			(xy 279.010005 -89.39502) (xy 279.064848 -89.38489) (xy 279.120582 -89.382853) (xy 279.176019 -89.388953)
			(xy 279.229976 -89.403059) (xy 279.281305 -89.424871) (xy 279.328911 -89.453925) (xy 279.371779 -89.4896)
			(xy 279.408996 -89.531137) (xy 279.439769 -89.57765) (xy 279.463441 -89.628147) (xy 279.479509 -89.681554)
			(xy 279.487629 -89.73673) (xy 279.488138 -89.764616) (xy 279.487674 -89.790016) (xy 280.29103 -89.790016)
			(xy 280.295101 -89.734394) (xy 280.307227 -89.679957) (xy 280.32715 -89.627866) (xy 280.354446 -89.579231)
			(xy 280.388532 -89.535088) (xy 280.428681 -89.496379) (xy 280.474039 -89.463928) (xy 280.523639 -89.438427)
			(xy 280.576423 -89.42042) (xy 280.631266 -89.41029) (xy 280.687 -89.408253) (xy 280.742437 -89.414353)
			(xy 280.796394 -89.428459) (xy 280.847723 -89.450271) (xy 280.895329 -89.479325) (xy 280.938197 -89.515)
			(xy 280.975414 -89.556537) (xy 281.006187 -89.60305) (xy 281.029859 -89.653547) (xy 281.045927 -89.706954)
			(xy 281.054047 -89.76213) (xy 281.054556 -89.790016) (xy 281.054047 -89.817902) (xy 281.045927 -89.873078)
			(xy 281.029859 -89.926485) (xy 281.006187 -89.976982) (xy 280.975414 -90.023495) (xy 280.938197 -90.065032)
			(xy 280.895329 -90.100707) (xy 280.847723 -90.129761) (xy 280.796394 -90.151573) (xy 280.742437 -90.165679)
			(xy 280.687 -90.171779) (xy 280.631266 -90.169742) (xy 280.576423 -90.159612) (xy 280.523639 -90.141605)
			(xy 280.474039 -90.116104) (xy 280.428681 -90.083653) (xy 280.388532 -90.044944) (xy 280.354446 -90.000801)
			(xy 280.32715 -89.952166) (xy 280.307227 -89.900075) (xy 280.295101 -89.845638) (xy 280.29103 -89.790016)
			(xy 279.487674 -89.790016) (xy 279.487629 -89.792502) (xy 279.479509 -89.847678) (xy 279.463441 -89.901085)
			(xy 279.439769 -89.951582) (xy 279.408996 -89.998095) (xy 279.371779 -90.039632) (xy 279.328911 -90.075307)
			(xy 279.281305 -90.104361) (xy 279.229976 -90.126173) (xy 279.176019 -90.140279) (xy 279.120582 -90.146379)
			(xy 279.064848 -90.144342) (xy 279.010005 -90.134212) (xy 278.957221 -90.116205) (xy 278.907621 -90.090704)
			(xy 278.862263 -90.058253) (xy 278.822114 -90.019544) (xy 278.788028 -89.975401) (xy 278.760732 -89.926766)
			(xy 278.740809 -89.874675) (xy 278.728683 -89.820238) (xy 278.724612 -89.764616) (xy 277.891863 -89.764616)
			(xy 277.891493 -89.784882) (xy 277.883373 -89.840058) (xy 277.867305 -89.893465) (xy 277.843633 -89.943962)
			(xy 277.81286 -89.990475) (xy 277.775643 -90.032012) (xy 277.732775 -90.067687) (xy 277.685169 -90.096741)
			(xy 277.63384 -90.118553) (xy 277.579883 -90.132659) (xy 277.524446 -90.138759) (xy 277.468712 -90.136722)
			(xy 277.413869 -90.126592) (xy 277.361085 -90.108585) (xy 277.311485 -90.083084) (xy 277.266127 -90.050633)
			(xy 277.225978 -90.011924) (xy 277.191892 -89.967781) (xy 277.164596 -89.919146) (xy 277.144673 -89.867055)
			(xy 277.132547 -89.812618) (xy 277.128476 -89.756996) (xy 272.718862 -89.756996) (xy 272.740924 -94.31909)
			(xy 277.453596 -94.31909) (xy 277.457667 -94.263468) (xy 277.469793 -94.209031) (xy 277.489716 -94.15694)
			(xy 277.517012 -94.108305) (xy 277.551098 -94.064162) (xy 277.591247 -94.025453) (xy 277.636605 -93.993002)
			(xy 277.686205 -93.967501) (xy 277.738989 -93.949494) (xy 277.793832 -93.939364) (xy 277.849566 -93.937327)
			(xy 277.905003 -93.943427) (xy 277.95896 -93.957533) (xy 278.010289 -93.979345) (xy 278.057895 -94.008399)
			(xy 278.100763 -94.044074) (xy 278.13798 -94.085611) (xy 278.168753 -94.132124) (xy 278.192425 -94.182621)
			(xy 278.208493 -94.236028) (xy 278.216613 -94.291204) (xy 278.217122 -94.31909) (xy 278.216613 -94.346976)
			(xy 278.208493 -94.402152) (xy 278.192425 -94.455559) (xy 278.168753 -94.506056) (xy 278.13798 -94.552569)
			(xy 278.100763 -94.594106) (xy 278.057895 -94.629781) (xy 278.010289 -94.658835) (xy 277.95896 -94.680647)
			(xy 277.905003 -94.694753) (xy 277.849566 -94.700853) (xy 277.793832 -94.698816) (xy 277.738989 -94.688686)
			(xy 277.686205 -94.670679) (xy 277.636605 -94.645178) (xy 277.591247 -94.612727) (xy 277.551098 -94.574018)
			(xy 277.517012 -94.529875) (xy 277.489716 -94.48124) (xy 277.469793 -94.429149) (xy 277.457667 -94.374712)
			(xy 277.453596 -94.31909) (xy 272.740924 -94.31909) (xy 272.745193 -95.20174) (xy 276.739856 -95.20174)
			(xy 276.743927 -95.146118) (xy 276.756053 -95.091681) (xy 276.775976 -95.03959) (xy 276.803272 -94.990955)
			(xy 276.837358 -94.946812) (xy 276.877507 -94.908103) (xy 276.922865 -94.875652) (xy 276.972465 -94.850151)
			(xy 277.025249 -94.832144) (xy 277.080092 -94.822014) (xy 277.135826 -94.819977) (xy 277.191263 -94.826077)
			(xy 277.24522 -94.840183) (xy 277.296549 -94.861995) (xy 277.344155 -94.891049) (xy 277.387023 -94.926724)
			(xy 277.42424 -94.968261) (xy 277.455013 -95.014774) (xy 277.478685 -95.065271) (xy 277.494753 -95.118678)
			(xy 277.502873 -95.173854) (xy 277.503382 -95.20174) (xy 277.502873 -95.229626) (xy 277.494753 -95.284802)
			(xy 277.478685 -95.338209) (xy 277.455013 -95.388706) (xy 277.42424 -95.435219) (xy 277.387023 -95.476756)
			(xy 277.344155 -95.512431) (xy 277.296549 -95.541485) (xy 277.24522 -95.563297) (xy 277.191263 -95.577403)
			(xy 277.135826 -95.583503) (xy 277.080092 -95.581466) (xy 277.025249 -95.571336) (xy 276.972465 -95.553329)
			(xy 276.922865 -95.527828) (xy 276.877507 -95.495377) (xy 276.837358 -95.456668) (xy 276.803272 -95.412525)
			(xy 276.775976 -95.36389) (xy 276.756053 -95.311799) (xy 276.743927 -95.257362) (xy 276.739856 -95.20174)
			(xy 272.745193 -95.20174) (xy 272.791428 -104.762046) (xy 272.791428 -104.763062) (xy 272.939764 -111.733838)
			(xy 272.939764 -111.756698) (xy 272.937986 -111.81588) (xy 272.833846 -113.53927) (xy 272.833846 -113.542826)
			(xy 272.942304 -135.965438) (xy 272.942304 -135.970264) (xy 272.941034 -136.023604) (xy 272.937732 -136.068054)
			(xy 272.929096 -136.154414) (xy 272.929096 -136.155938) (xy 272.93189 -136.354566) (xy 272.93189 -136.35736)
			(xy 272.932144 -136.368282) (xy 272.932144 -136.36879) (xy 272.931456 -136.420036) (xy 272.920768 -136.52197)
			(xy 272.910808 -136.572244) (xy 272.86839 -136.773666) (xy 272.867628 -136.779254) (xy 272.474182 -140.772388)
			(xy 272.473808 -140.776993) (xy 272.474568 -140.786199) (xy 272.475706 -140.790676) (xy 272.477992 -140.799566)
			(xy 272.483326 -140.807186) (xy 272.500144 -140.831636) (xy 272.526815 -140.884645) (xy 272.544964 -140.941141)
			(xy 272.554154 -140.999766) (xy 272.5547 -141.029436) (xy 272.554254 -141.055478) (xy 272.547164 -141.107076)
			(xy 272.533119 -141.15723) (xy 272.512382 -141.205007) (xy 272.485338 -141.249519) (xy 272.45249 -141.289937)
			(xy 272.433796 -141.308074) (xy 272.427192 -141.31417) (xy 272.41881 -141.330934) (xy 272.313654 -142.400782)
			(xy 272.313233 -142.407282) (xy 272.315285 -142.420141) (xy 272.317718 -142.426182) (xy 272.320258 -142.432024)
			(xy 272.327878 -142.441676) (xy 272.333212 -142.445994) (xy 272.355973 -142.464202) (xy 272.396231 -142.506351)
			(xy 272.42962 -142.554125) (xy 272.455366 -142.606416) (xy 272.472871 -142.662011) (xy 272.481729 -142.719619)
			(xy 272.48231 -142.748762) (xy 272.48185 -142.775293) (xy 272.474491 -142.827843) (xy 272.459926 -142.878868)
			(xy 272.438433 -142.927383) (xy 272.410427 -142.972453) (xy 272.376449 -143.013211) (xy 272.337153 -143.048869)
			(xy 272.293297 -143.07874) (xy 272.269712 -143.0909) (xy 272.263924 -143.093915) (xy 272.254018 -143.102405)
			(xy 272.250154 -143.107664) (xy 272.246598 -143.112998) (xy 272.242026 -143.124936) (xy 272.221198 -143.337026)
			(xy 272.036286 -145.214848) (xy 272.036032 -145.222976) (xy 273.220942 -164.701474) (xy 273.490436 -169.132758)
			(xy 273.572224 -170.478704) (xy 275.047456 -194.724782) (xy 275.09089 -195.437252) (xy 275.091863 -195.446825)
			(xy 275.099984 -195.464252) (xy 275.113962 -195.477454) (xy 275.131823 -195.48457) (xy 275.141436 -195.485004)
			(xy 275.472398 -195.46951) (xy 275.899118 -195.44919) (xy 275.908847 -195.448265) (xy 275.926571 -195.440072)
			(xy 275.939944 -195.425846) (xy 275.947026 -195.40765) (xy 275.947378 -195.397882) (xy 275.688298 -188.128656)
			(xy 274.893024 -165.810184) (xy 274.893024 -165.80866) (xy 273.717766 -147.54606) (xy 273.716242 -147.515834)
			(xy 273.716242 -147.51558) (xy 273.71548 -147.482814) (xy 273.71548 -147.482306) (xy 273.71675 -147.433538)
			(xy 273.732244 -147.121372) (xy 273.732244 -147.117308) (xy 273.723354 -146.986244) (xy 273.716242 -146.882358)
			(xy 273.715236 -146.865549) (xy 273.714221 -146.831887) (xy 273.71421 -146.815048) (xy 273.71421 -146.814794)
			(xy 273.722084 -116.429536) (xy 273.722721 -116.37772) (xy 273.733412 -116.274641) (xy 273.74342 -116.223796)
			(xy 274.021296 -114.90706) (xy 274.031661 -114.860634) (xy 274.060084 -114.769847) (xy 274.097018 -114.682177)
			(xy 274.142129 -114.598421) (xy 274.168108 -114.558572) (xy 275.71319 -112.248188) (xy 275.741897 -112.20639)
			(xy 275.806539 -112.128258) (xy 275.842222 -112.092232) (xy 276.835362 -111.11357) (xy 276.838529 -111.109827)
			(xy 276.843516 -111.101386) (xy 276.845268 -111.096806) (xy 277.638002 -108.580936) (xy 279.330912 -103.15702)
			(xy 279.330658 -103.15575) (xy 279.306274 -103.134414) (xy 279.286227 -103.116203) (xy 279.250965 -103.075095)
			(xy 279.221867 -103.029417) (xy 279.199517 -102.980085) (xy 279.184363 -102.928089) (xy 279.176709 -102.874474)
			(xy 279.176226 -102.847394) (xy 279.176728 -102.819608) (xy 279.184792 -102.764625) (xy 279.200749 -102.711394)
			(xy 279.22426 -102.661041) (xy 279.254829 -102.614632) (xy 279.291807 -102.57315) (xy 279.334413 -102.537473)
			(xy 279.381745 -102.508355) (xy 279.432801 -102.486412) (xy 279.486501 -102.47211) (xy 279.514046 -102.468426)
			(xy 279.5143 -102.468426) (xy 279.521436 -102.467306) (xy 279.534707 -102.461618) (xy 279.540462 -102.45725)
			(xy 279.546304 -102.452424) (xy 279.554432 -102.440232) (xy 279.64003 -102.165912) (xy 279.907492 -101.30917)
			(xy 279.908 -101.307138) (xy 280.374598 -99.593146) (xy 280.374598 -99.592638) (xy 280.94305 -97.406714)
			(xy 281.246834 -96.23933) (xy 281.24785 -96.232218) (xy 281.24785 -96.23171) (xy 281.24818 -96.22318)
			(xy 281.243797 -96.206692) (xy 281.234201 -96.192586) (xy 281.22753 -96.18726) (xy 281.150314 -96.129602)
			(xy 281.142714 -96.124811) (xy 281.125306 -96.120418) (xy 281.107458 -96.122368) (xy 281.09926 -96.126046)
			(xy 281.09545 -96.128332) (xy 281.074876 -96.140524) (xy 281.074368 -96.140778) (xy 281.073098 -96.14154)
			(xy 281.030877 -96.165052) (xy 280.942984 -96.205244) (xy 280.897584 -96.221804) (xy 280.852832 -96.237045)
			(xy 280.761236 -96.260479) (xy 280.667927 -96.275724) (xy 280.573636 -96.282658) (xy 280.4791 -96.281229)
			(xy 280.385061 -96.271448) (xy 280.292256 -96.25339) (xy 280.20141 -96.227197) (xy 280.113236 -96.193076)
			(xy 280.028424 -96.151292) (xy 279.947638 -96.102173) (xy 279.871512 -96.046104) (xy 279.800641 -95.983523)
			(xy 279.73558 -95.914922) (xy 279.67684 -95.840838) (xy 279.624879 -95.761849) (xy 279.580106 -95.678577)
			(xy 279.561036 -95.635318) (xy 279.543427 -95.592933) (xy 279.514685 -95.505759) (xy 279.493536 -95.416438)
			(xy 279.480136 -95.325632) (xy 279.474584 -95.23401) (xy 279.476922 -95.142249) (xy 279.481534 -95.096584)
			(xy 279.481534 -95.096076) (xy 279.483058 -95.081344) (xy 279.489218 -95.036455) (xy 279.508164 -94.947843)
			(xy 279.534551 -94.861156) (xy 279.56819 -94.777017) (xy 279.608838 -94.696031) (xy 279.656204 -94.618782)
			(xy 279.709946 -94.545824) (xy 279.769677 -94.477684) (xy 279.834969 -94.414851) (xy 279.90535 -94.357777)
			(xy 279.980315 -94.306873) (xy 280.059325 -94.262506) (xy 280.14181 -94.224994) (xy 280.227178 -94.194607)
			(xy 280.314814 -94.171565) (xy 280.404087 -94.156032) (xy 280.494355 -94.148122) (xy 280.58497 -94.147889)
			(xy 280.675277 -94.155337) (xy 280.720038 -94.162372) (xy 280.76455 -94.170361) (xy 280.852141 -94.19289)
			(xy 280.937512 -94.222748) (xy 281.020051 -94.259721) (xy 281.099167 -94.303544) (xy 281.174292 -94.353902)
			(xy 281.244888 -94.410435) (xy 281.310448 -94.472738) (xy 281.370503 -94.540363) (xy 281.424622 -94.612825)
			(xy 281.472417 -94.689607) (xy 281.513546 -94.770156) (xy 281.53106 -94.81185) (xy 281.53382 -94.817903)
			(xy 281.541933 -94.82844) (xy 281.547062 -94.832678) (xy 281.571446 -94.851728) (xy 281.580336 -94.852998)
			(xy 281.623008 -94.852744) (xy 281.676856 -94.852236) (xy 281.690064 -94.850458) (xy 281.95651 -94.14637)
			(xy 284.988254 -86.136988) (xy 284.987746 -86.12632) (xy 284.986801 -86.100315) (xy 284.991116 -86.048457)
			(xy 285.002436 -85.997666) (xy 285.020552 -85.948884) (xy 285.045127 -85.903015) (xy 285.075705 -85.860911)
			(xy 285.09341 -85.84184) (xy 285.096966 -85.83803) (xy 285.105348 -85.824822) (xy 285.10992 -85.815678)
			(xy 291.798248 -68.147184) (xy 291.799772 -68.141088) (xy 291.799772 -68.14058) (xy 292.35908 -65.09131)
			(xy 292.830758 -62.520322) (xy 292.831461 -62.51083) (xy 292.826633 -62.492432) (xy 292.82136 -62.484508)
			(xy 292.796722 -62.450472) (xy 292.796468 -62.450218) (xy 292.790537 -62.442777) (xy 292.774488 -62.432582)
			(xy 292.765226 -62.430406) (xy 292.754812 -62.428882) (xy 292.753796 -62.428628) (xy 292.749478 -62.42812)
			(xy 292.746938 -62.427612) (xy 292.742874 -62.42685) (xy 292.742366 -62.42685) (xy 292.717728 -62.421262)
			(xy 292.717474 -62.421262) (xy 292.710616 -62.419484) (xy 292.696392 -62.419992) (xy 292.690042 -62.422024)
			(xy 292.683408 -62.424345) (xy 292.671688 -62.432092) (xy 292.666928 -62.437264) (xy 292.66388 -62.44082)
			(xy 292.610032 -62.503304) (xy 292.60501 -62.510189) (xy 292.59944 -62.526284) (xy 292.59911 -62.5348)
			(xy 292.59911 -62.54877) (xy 292.601904 -62.563248) (xy 292.604444 -62.57163) (xy 292.604952 -62.573154)
			(xy 292.616053 -62.605173) (xy 292.628057 -62.671862) (xy 292.628828 -62.705742) (xy 292.62832 -62.71641)
			(xy 292.627131 -62.743158) (xy 292.618189 -62.795947) (xy 292.601955 -62.846968) (xy 292.578747 -62.895218)
			(xy 292.549023 -62.93975) (xy 292.513365 -62.979689) (xy 292.472473 -63.014251) (xy 292.427152 -63.042758)
			(xy 292.37829 -63.064649) (xy 292.326848 -63.079494) (xy 292.273836 -63.087002) (xy 292.247066 -63.087504)
			(xy 292.219817 -63.087016) (xy 292.165873 -63.079256) (xy 292.113583 -63.063898) (xy 292.064011 -63.041255)
			(xy 292.018165 -63.011788) (xy 291.976979 -62.976097) (xy 291.941292 -62.934908) (xy 291.911829 -62.88906)
			(xy 291.88919 -62.839485) (xy 291.873837 -62.787194) (xy 291.866082 -62.733249) (xy 291.866082 -62.678751)
			(xy 291.873837 -62.624806) (xy 291.88919 -62.572515) (xy 291.911829 -62.52294) (xy 291.941292 -62.477092)
			(xy 291.976979 -62.435903) (xy 292.018165 -62.400212) (xy 292.064011 -62.370745) (xy 292.113583 -62.348102)
			(xy 292.165873 -62.332744) (xy 292.219817 -62.324984) (xy 292.247066 -62.324488) (xy 292.247828 -62.324488)
			(xy 292.270397 -62.324836) (xy 292.315219 -62.330183) (xy 292.337236 -62.335156) (xy 292.340284 -62.335918)
			(xy 292.349428 -62.336934) (xy 292.36132 -62.337198) (xy 292.383308 -62.328198) (xy 292.391592 -62.319662)
			(xy 292.45052 -62.251336) (xy 292.45495 -62.245864) (xy 292.46089 -62.233106) (xy 292.462204 -62.22619)
			(xy 292.463073 -62.219231) (xy 292.461403 -62.20531) (xy 292.458902 -62.198758) (xy 292.458902 -62.198504)
			(xy 292.449575 -62.17512) (xy 292.436451 -62.126517) (xy 292.429829 -62.07661) (xy 292.429438 -62.051438)
			(xy 292.429899 -62.024185) (xy 292.437652 -61.970232) (xy 292.453005 -61.917932) (xy 292.475646 -61.86835)
			(xy 292.505113 -61.822496) (xy 292.540808 -61.781302) (xy 292.582002 -61.745609) (xy 292.627857 -61.716142)
			(xy 292.67744 -61.693502) (xy 292.72974 -61.67815) (xy 292.783693 -61.670398) (xy 292.810946 -61.66993)
			(xy 292.811708 -61.66993) (xy 292.833103 -61.67026) (xy 292.875621 -61.675101) (xy 292.896544 -61.679582)
			(xy 292.901624 -61.680852) (xy 292.910182 -61.682194) (xy 292.927315 -61.679718) (xy 292.935152 -61.676026)
			(xy 292.93947 -61.673486) (xy 292.974268 -61.650372) (xy 292.98261 -61.644305) (xy 292.994018 -61.627141)
			(xy 292.996366 -61.617098) (xy 293.12235 -60.930282) (xy 293.123112 -60.920884) (xy 293.110666 -60.887864)
			(xy 293.104824 -60.88126) (xy 293.087651 -60.860429) (xy 293.05873 -60.814845) (xy 293.03652 -60.76564)
			(xy 293.021464 -60.713796) (xy 293.013864 -60.660349) (xy 293.013384 -60.633356) (xy 293.013944 -60.604136)
			(xy 293.022859 -60.546378) (xy 293.040473 -60.490655) (xy 293.066376 -60.438268) (xy 293.099961 -60.390441)
			(xy 293.140444 -60.348293) (xy 293.186878 -60.312807) (xy 293.212266 -60.29833) (xy 293.21252 -60.298076)
			(xy 293.220494 -60.293184) (xy 293.232516 -60.278872) (xy 293.238609 -60.261202) (xy 293.238682 -60.251848)
			(xy 293.232586 -60.155328) (xy 293.215314 -59.88304) (xy 293.143178 -58.759344) (xy 293.14278 -58.754617)
			(xy 293.140479 -58.745414) (xy 293.138606 -58.741056) (xy 293.134796 -58.732928) (xy 293.127684 -58.72607)
			(xy 293.109353 -58.708024) (xy 293.077213 -58.66786) (xy 293.050758 -58.623745) (xy 293.030467 -58.576476)
			(xy 293.016707 -58.52691) (xy 293.009729 -58.475945) (xy 293.00932 -58.450226) (xy 293.00932 -58.449718)
			(xy 293.009385 -58.439858) (xy 293.010403 -58.420163) (xy 293.011352 -58.410348) (xy 293.01186 -58.405014)
			(xy 293.015345 -58.379318) (xy 293.028358 -58.329121) (xy 293.048033 -58.281143) (xy 293.07401 -58.236263)
			(xy 293.089584 -58.21553) (xy 293.094664 -58.208926) (xy 293.10584 -58.17743) (xy 293.10584 -58.174128)
			(xy 293.092632 -57.967372) (xy 293.079678 -57.76595) (xy 292.880034 -54.642004) (xy 292.878362 -54.632678)
			(xy 292.86927 -54.616074) (xy 292.854794 -54.603876) (xy 292.845998 -54.600348) (xy 292.845744 -54.600348)
			(xy 292.820409 -54.591298) (xy 292.772368 -54.567085) (xy 292.728203 -54.536367) (xy 292.688787 -54.499753)
			(xy 292.654902 -54.457967) (xy 292.62722 -54.411839) (xy 292.606287 -54.36228) (xy 292.59252 -54.310274)
			(xy 292.58895 -54.28361) (xy 292.587934 -54.274466) (xy 292.58641 -54.238906) (xy 292.58688 -54.21227)
			(xy 292.594301 -54.159516) (xy 292.608986 -54.108308) (xy 292.63065 -54.059639) (xy 292.658871 -54.014455)
			(xy 292.693101 -53.973635) (xy 292.732675 -53.937972) (xy 292.776824 -53.908158) (xy 292.800532 -53.896006)
			(xy 292.80358 -53.894482) (xy 292.811564 -53.889345) (xy 292.823433 -53.87455) (xy 292.829177 -53.856473)
			(xy 292.82898 -53.846984) (xy 292.6969 -51.781964) (xy 292.69559 -51.770822) (xy 292.684776 -51.751197)
			(xy 292.676072 -51.744118) (xy 292.64483 -51.721258) (xy 292.644322 -51.72075) (xy 292.611302 -51.697128)
			(xy 292.602132 -51.691677) (xy 292.581141 -51.688013) (xy 292.570662 -51.690016) (xy 292.570408 -51.690016)
			(xy 292.547364 -51.695486) (xy 292.500364 -51.701342) (xy 292.476682 -51.7017) (xy 292.449234 -51.701237)
			(xy 292.3949 -51.693401) (xy 292.342249 -51.677864) (xy 292.292366 -51.654946) (xy 292.24628 -51.625121)
			(xy 292.20494 -51.589003) (xy 292.169199 -51.547336) (xy 292.154102 -51.524408) (xy 292.152832 -51.522122)
			(xy 292.152324 -51.521614) (xy 292.151308 -51.520344) (xy 292.1508 -51.519582) (xy 292.146228 -51.513994)
			(xy 292.139715 -51.507525) (xy 292.123306 -51.49933) (xy 292.114224 -51.497992) (xy 292.0746 -51.493928)
			(xy 292.074092 -51.493928) (xy 292.05047 -51.491388) (xy 292.049962 -51.491388) (xy 292.034214 -51.489864)
			(xy 292.022584 -51.489279) (xy 292.000772 -51.497362) (xy 291.992304 -51.505358) (xy 291.99205 -51.505612)
			(xy 291.973954 -51.524176) (xy 291.933617 -51.55674) (xy 291.889242 -51.583545) (xy 291.841648 -51.604097)
			(xy 291.791711 -51.618018) (xy 291.740349 -51.625052) (xy 291.714428 -51.6255) (xy 291.687174 -51.625039)
			(xy 291.633221 -51.617285) (xy 291.58092 -51.601931) (xy 291.531337 -51.57929) (xy 291.485481 -51.549823)
			(xy 291.444285 -51.514129) (xy 291.408589 -51.472935) (xy 291.37912 -51.427081) (xy 291.356476 -51.377499)
			(xy 291.341119 -51.325199) (xy 291.333363 -51.271246) (xy 291.33292 -51.243992) (xy 291.333345 -51.218481)
			(xy 291.34014 -51.167913) (xy 291.353609 -51.1187) (xy 291.373511 -51.071719) (xy 291.399491 -51.027807)
			(xy 291.414962 -51.007518) (xy 291.417502 -51.00447) (xy 291.418518 -51.002946) (xy 291.42182 -50.996342)
			(xy 291.424164 -50.991119) (xy 291.426729 -50.979966) (xy 291.4269 -50.974244) (xy 291.4269 -50.94224)
			(xy 291.438076 -50.94224) (xy 291.438076 -50.89144) (xy 291.437741 -50.882836) (xy 291.432029 -50.866606)
			(xy 291.4269 -50.85969) (xy 291.42563 -50.858166) (xy 291.408237 -50.837289) (xy 291.378921 -50.791538)
			(xy 291.356395 -50.74209) (xy 291.341115 -50.689946) (xy 291.33339 -50.63616) (xy 291.33292 -50.608992)
			(xy 291.333384 -50.58174) (xy 291.341142 -50.527792) (xy 291.356499 -50.475496) (xy 291.379142 -50.425919)
			(xy 291.408611 -50.380069) (xy 291.444305 -50.33888) (xy 291.485498 -50.303189) (xy 291.531351 -50.273725)
			(xy 291.58093 -50.251086) (xy 291.633227 -50.235734) (xy 291.687176 -50.227981) (xy 291.714428 -50.227484)
			(xy 291.742468 -50.227982) (xy 291.797944 -50.236198) (xy 291.851619 -50.252449) (xy 291.902336 -50.276384)
			(xy 291.949001 -50.307488) (xy 291.990608 -50.34509) (xy 292.008814 -50.366422) (xy 292.009068 -50.366676)
			(xy 292.015926 -50.374804) (xy 292.039548 -50.386488) (xy 292.045898 -50.389536) (xy 292.05079 -50.39161)
			(xy 292.061162 -50.393906) (xy 292.066472 -50.394108) (xy 292.123876 -50.394108) (xy 292.1296 -50.393957)
			(xy 292.140756 -50.391388) (xy 292.145974 -50.389028) (xy 292.164262 -50.380138) (xy 292.174168 -50.373788)
			(xy 292.177978 -50.37074) (xy 292.181534 -50.366676) (xy 292.201938 -50.342892) (xy 292.249127 -50.301669)
			(xy 292.302407 -50.26869) (xy 292.33114 -50.256186) (xy 292.341238 -50.252051) (xy 292.361826 -50.24481)
			(xy 292.372288 -50.241708) (xy 292.382448 -50.238914) (xy 292.390576 -50.23231) (xy 292.394416 -50.228958)
			(xy 292.400819 -50.221028) (xy 292.403276 -50.216562) (xy 292.420548 -50.183288) (xy 292.424939 -50.173924)
			(xy 292.42653 -50.153326) (xy 292.423596 -50.14341) (xy 292.328854 -49.86782) (xy 292.324927 -49.858038)
			(xy 292.310656 -49.842558) (xy 292.291375 -49.834098) (xy 292.280848 -49.83353) (xy 292.275006 -49.83353)
			(xy 292.270522 -49.833668) (xy 292.261705 -49.835323) (xy 292.25748 -49.836832) (xy 292.230302 -49.848008)
			(xy 292.223444 -49.854358) (xy 292.202142 -49.873388) (xy 292.154943 -49.905557) (xy 292.103478 -49.930336)
			(xy 292.048896 -49.947173) (xy 291.992416 -49.95569) (xy 291.963856 -49.956212) (xy 291.938345 -49.955785)
			(xy 291.887779 -49.948985) (xy 291.838569 -49.935514) (xy 291.79159 -49.91561) (xy 291.74768 -49.889629)
			(xy 291.727382 -49.87417) (xy 291.724334 -49.87163) (xy 291.72281 -49.870614) (xy 291.716206 -49.867312)
			(xy 291.710983 -49.864971) (xy 291.699829 -49.862411) (xy 291.694108 -49.862232) (xy 291.662104 -49.862232)
			(xy 291.662104 -49.851056) (xy 291.611304 -49.851056) (xy 291.602703 -49.851397) (xy 291.586482 -49.857122)
			(xy 291.579554 -49.862232) (xy 291.57803 -49.863502) (xy 291.557153 -49.880895) (xy 291.511404 -49.910212)
			(xy 291.461955 -49.932738) (xy 291.40981 -49.948016) (xy 291.356025 -49.955737) (xy 291.328856 -49.956212)
			(xy 291.303345 -49.955785) (xy 291.252779 -49.948985) (xy 291.203569 -49.935514) (xy 291.15659 -49.91561)
			(xy 291.11268 -49.889629) (xy 291.092382 -49.87417) (xy 291.089334 -49.87163) (xy 291.08781 -49.870614)
			(xy 291.081206 -49.867312) (xy 291.075983 -49.864971) (xy 291.064829 -49.862411) (xy 291.059108 -49.862232)
			(xy 291.027104 -49.862232) (xy 291.027104 -49.851056) (xy 290.976304 -49.851056) (xy 290.967703 -49.851397)
			(xy 290.951482 -49.857122) (xy 290.944554 -49.862232) (xy 290.94303 -49.863502) (xy 290.922153 -49.880895)
			(xy 290.876404 -49.910212) (xy 290.826955 -49.932738) (xy 290.77481 -49.948016) (xy 290.721025 -49.955737)
			(xy 290.693856 -49.956212) (xy 290.666607 -49.955723) (xy 290.612663 -49.947962) (xy 290.560373 -49.932602)
			(xy 290.510801 -49.909959) (xy 290.464955 -49.880491) (xy 290.42377 -49.844799) (xy 290.388083 -49.803609)
			(xy 290.35862 -49.757761) (xy 290.335982 -49.708186) (xy 290.320629 -49.655894) (xy 290.312874 -49.60195)
			(xy 290.312874 -49.54745) (xy 290.320629 -49.493506) (xy 290.335982 -49.441214) (xy 290.35862 -49.391639)
			(xy 290.388083 -49.345791) (xy 290.42377 -49.304601) (xy 290.464955 -49.268909) (xy 290.510801 -49.239441)
			(xy 290.560373 -49.216798) (xy 290.612663 -49.201438) (xy 290.666607 -49.193677) (xy 290.693856 -49.193196)
			(xy 290.719366 -49.193624) (xy 290.769931 -49.200425) (xy 290.819141 -49.213898) (xy 290.866119 -49.233803)
			(xy 290.910027 -49.259786) (xy 290.93033 -49.275238) (xy 290.933378 -49.277778) (xy 290.934902 -49.278794)
			(xy 290.941506 -49.282096) (xy 290.946729 -49.284436) (xy 290.957883 -49.286992) (xy 290.963604 -49.287176)
			(xy 290.995608 -49.287176) (xy 290.995608 -49.298352) (xy 291.046408 -49.298352) (xy 291.055008 -49.298009)
			(xy 291.071227 -49.292282) (xy 291.078158 -49.287176) (xy 291.079682 -49.285906) (xy 291.100559 -49.268513)
			(xy 291.146309 -49.239197) (xy 291.195757 -49.216672) (xy 291.247902 -49.201395) (xy 291.301688 -49.193676)
			(xy 291.328856 -49.193196) (xy 291.354366 -49.193624) (xy 291.404931 -49.200425) (xy 291.454141 -49.213898)
			(xy 291.501119 -49.233803) (xy 291.545027 -49.259786) (xy 291.56533 -49.275238) (xy 291.568378 -49.277778)
			(xy 291.569902 -49.278794) (xy 291.576506 -49.282096) (xy 291.581729 -49.284436) (xy 291.592883 -49.286992)
			(xy 291.598604 -49.287176) (xy 291.630608 -49.287176) (xy 291.630608 -49.298352) (xy 291.681408 -49.298352)
			(xy 291.690008 -49.298009) (xy 291.706227 -49.292282) (xy 291.713158 -49.287176) (xy 291.714682 -49.285906)
			(xy 291.722048 -49.279302) (xy 291.723064 -49.278794) (xy 291.724334 -49.277778) (xy 291.724842 -49.27727)
			(xy 291.74694 -49.26076) (xy 291.778944 -49.240948) (xy 291.779198 -49.240948) (xy 291.779452 -49.240694)
			(xy 291.78425 -49.237838) (xy 291.792579 -49.230404) (xy 291.795962 -49.225962) (xy 291.799518 -49.221136)
			(xy 291.803836 -49.210468) (xy 291.808662 -49.18075) (xy 291.808662 -49.180242) (xy 291.812472 -49.156112)
			(xy 291.812472 -49.155604) (xy 291.813126 -49.150581) (xy 291.812622 -49.140467) (xy 291.811456 -49.135538)
			(xy 291.810694 -49.132744) (xy 291.809384 -49.128877) (xy 291.805688 -49.121598) (xy 291.803328 -49.118266)
			(xy 291.631624 -48.895508) (xy 291.62883 -48.892206) (xy 286.069278 -42.831766) (xy 286.060898 -42.82344)
			(xy 286.038922 -42.814852) (xy 286.027114 -42.815256) (xy 286.015938 -42.817542) (xy 285.965646 -42.834052)
			(xy 285.965138 -42.834052) (xy 285.951168 -42.83837) (xy 285.947024 -42.839754) (xy 285.939236 -42.843713)
			(xy 285.935674 -42.846244) (xy 285.927503 -42.853035) (xy 285.91712 -42.871543) (xy 285.915608 -42.882058)
			(xy 285.912071 -42.911429) (xy 285.897488 -42.968761) (xy 285.87467 -43.023341) (xy 285.844109 -43.073993)
			(xy 285.806464 -43.119626) (xy 285.762544 -43.159258) (xy 285.713296 -43.192034) (xy 285.659782 -43.217249)
			(xy 285.603153 -43.234359) (xy 285.544629 -43.242996) (xy 285.51505 -43.2435) (xy 285.486295 -43.242984)
			(xy 285.42937 -43.234792) (xy 285.37419 -43.218584) (xy 285.321878 -43.194688) (xy 285.273499 -43.163592)
			(xy 285.230038 -43.125927) (xy 285.192378 -43.082461) (xy 285.161288 -43.034078) (xy 285.137398 -42.981763)
			(xy 285.121197 -42.926581) (xy 285.113013 -42.869656) (xy 285.113013 -42.812144) (xy 285.121197 -42.755219)
			(xy 285.137398 -42.700037) (xy 285.161288 -42.647722) (xy 285.192378 -42.599339) (xy 285.230038 -42.555873)
			(xy 285.273499 -42.518208) (xy 285.321878 -42.487112) (xy 285.37419 -42.463216) (xy 285.42937 -42.447008)
			(xy 285.486295 -42.438816) (xy 285.51505 -42.43832) (xy 285.515304 -42.43832) (xy 285.534215 -42.438554)
			(xy 285.571869 -42.442112) (xy 285.590488 -42.445432) (xy 285.602426 -42.447718) (xy 285.62554 -42.441114)
			(xy 285.670498 -42.399712) (xy 285.662624 -42.388536) (xy 285.609284 -42.330624) (xy 285.60903 -42.330116)
			(xy 285.60649 -42.327322) (xy 285.60395 -42.324782) (xy 285.566784 -42.284225) (xy 285.500715 -42.196264)
			(xy 285.472124 -42.149268) (xy 284.963616 -41.28897) (xy 284.955234 -41.282874) (xy 284.938302 -41.270583)
			(xy 284.906983 -41.242837) (xy 284.89275 -41.227502) (xy 284.871174 -41.20263) (xy 284.836052 -41.146943)
			(xy 284.8229 -41.116758) (xy 284.822392 -41.115234) (xy 284.821376 -41.11244) (xy 284.81373 -41.092531)
			(xy 284.8024 -41.051414) (xy 284.79877 -41.030398) (xy 284.79877 -41.02989) (xy 284.796738 -41.01465)
			(xy 284.795468 -41.003728) (xy 284.417262 -40.36314) (xy 284.411919 -40.356074) (xy 284.397491 -40.34582)
			(xy 284.389068 -40.343074) (xy 284.387798 -40.34282) (xy 284.387544 -40.34282) (xy 284.383734 -40.341804)
			(xy 284.356734 -40.334442) (xy 284.305085 -40.312892) (xy 284.257141 -40.284026) (xy 284.213928 -40.248465)
			(xy 284.176376 -40.206971) (xy 284.145289 -40.160435) (xy 284.121337 -40.109856) (xy 284.105032 -40.05632)
			(xy 284.096724 -40.000977) (xy 284.096206 -39.972996) (xy 284.096206 -39.968424) (xy 284.096714 -39.95166)
			(xy 284.098038 -39.931532) (xy 284.104406 -39.891698) (xy 284.109414 -39.872158) (xy 284.112208 -39.861998)
			(xy 284.110938 -39.852092) (xy 284.110195 -39.84694) (xy 284.10687 -39.837079) (xy 284.104334 -39.832534)
			(xy 283.832554 -39.37254) (xy 283.581856 -38.947344) (xy 283.57697 -38.940358) (xy 283.563559 -38.929849)
			(xy 283.54745 -38.924301) (xy 283.53893 -38.923976) (xy 283.465778 -38.923722) (xy 283.451808 -38.9255)
			(xy 283.445966 -38.927278) (xy 283.440378 -38.930326) (xy 283.43987 -38.930326) (xy 283.416248 -38.943788)
			(xy 283.412703 -38.946286) (xy 283.406445 -38.952288) (xy 283.403802 -38.955726) (xy 283.402024 -38.958266)
			(xy 283.38687 -38.980786) (xy 283.351202 -39.021701) (xy 283.31009 -39.057141) (xy 283.264366 -39.08639)
			(xy 283.214955 -39.108857) (xy 283.162856 -39.124087) (xy 283.109124 -39.131771) (xy 283.081984 -39.132256)
			(xy 283.062872 -39.132084) (xy 283.024828 -39.12839) (xy 283.006038 -39.12489) (xy 283.000958 -39.12362)
			(xy 282.985662 -39.120134) (xy 282.955651 -39.11098) (xy 282.941014 -39.105332) (xy 282.913398 -39.09372)
			(xy 282.861878 -39.063157) (xy 282.815767 -39.024918) (xy 282.776199 -38.979942) (xy 282.759658 -38.954964)
			(xy 282.75788 -38.952424) (xy 282.75407 -38.947852) (xy 282.751549 -38.945011) (xy 282.745812 -38.940034)
			(xy 282.74264 -38.937946) (xy 282.723336 -38.926262) (xy 282.718517 -38.923501) (xy 282.708008 -38.919919)
			(xy 282.702508 -38.91915) (xy 282.700222 -38.918896) (xy 282.699968 -38.918896) (xy 282.62961 -38.914324)
			(xy 282.618766 -38.914103) (xy 282.598482 -38.921722) (xy 282.590494 -38.929056) (xy 282.586684 -38.932866)
			(xy 282.584906 -38.935152) (xy 282.584144 -38.936168) (xy 282.565933 -38.958794) (xy 282.523826 -38.998797)
			(xy 282.47615 -39.031966) (xy 282.424003 -39.057538) (xy 282.368587 -39.074922) (xy 282.311178 -39.083718)
			(xy 282.282138 -39.08425) (xy 282.281884 -39.08425) (xy 282.254631 -39.083763) (xy 282.200679 -39.076004)
			(xy 282.14838 -39.060646) (xy 282.098799 -39.038001) (xy 282.052946 -39.008531) (xy 282.011753 -38.972836)
			(xy 281.976059 -38.931641) (xy 281.946591 -38.885787) (xy 281.923949 -38.836205) (xy 281.908593 -38.783906)
			(xy 281.900836 -38.729954) (xy 281.900836 -38.675446) (xy 281.908593 -38.621494) (xy 281.923949 -38.569195)
			(xy 281.946591 -38.519613) (xy 281.976059 -38.473759) (xy 282.011753 -38.432564) (xy 282.052946 -38.396869)
			(xy 282.098799 -38.367399) (xy 282.14838 -38.344754) (xy 282.200679 -38.329396) (xy 282.254631 -38.321637)
			(xy 282.281884 -38.321234) (xy 282.309369 -38.321711) (xy 282.36377 -38.329588) (xy 282.416481 -38.345182)
			(xy 282.466412 -38.368172) (xy 282.512532 -38.398081) (xy 282.553888 -38.434293) (xy 282.589626 -38.476059)
			(xy 282.604718 -38.499034) (xy 282.604718 -38.499288) (xy 282.607258 -38.503352) (xy 282.60802 -38.504368)
			(xy 282.612084 -38.508432) (xy 282.620974 -38.515036) (xy 282.640532 -38.527228) (xy 282.645909 -38.530313)
			(xy 282.657726 -38.534046) (xy 282.6639 -38.534594) (xy 282.734766 -38.539166) (xy 282.743955 -38.539366)
			(xy 282.761527 -38.534024) (xy 282.769056 -38.528752) (xy 282.778708 -38.5191) (xy 282.779978 -38.517322)
			(xy 282.803092 -38.490144) (xy 282.813506 -38.479222) (xy 282.834374 -38.459341) (xy 282.880998 -38.425457)
			(xy 282.932189 -38.398974) (xy 282.986783 -38.380495) (xy 283.043535 -38.37044) (xy 283.072332 -38.36924)
			(xy 283.074364 -38.36924) (xy 283.082746 -38.366192) (xy 283.091636 -38.361874) (xy 283.097173 -38.358199)
			(xy 283.106308 -38.348555) (xy 283.10967 -38.342824) (xy 283.125418 -38.313868) (xy 283.150818 -38.266878)
			(xy 283.154645 -38.25901) (xy 283.157268 -38.241723) (xy 283.15392 -38.224562) (xy 283.149802 -38.21684)
			(xy 283.099002 -38.130734) (xy 282.886658 -37.77107) (xy 282.878022 -37.76472) (xy 282.844885 -37.740447)
			(xy 282.782322 -37.68721) (xy 282.724387 -37.628972) (xy 282.671478 -37.566131) (xy 282.62396 -37.499122)
			(xy 282.602686 -37.463984) (xy 282.377642 -37.083238) (xy 282.355397 -37.044638) (xy 282.317152 -36.964166)
			(xy 282.286312 -36.880576) (xy 282.263127 -36.794549) (xy 282.25496 -36.750752) (xy 282.253436 -36.744402)
			(xy 282.251422 -36.73857) (xy 282.244994 -36.728041) (xy 282.240736 -36.723574) (xy 282.224577 -36.70691)
			(xy 282.195994 -36.670336) (xy 282.172047 -36.630571) (xy 282.16225 -36.609528) (xy 282.151328 -36.58235)
			(xy 282.147518 -36.571682) (xy 281.72791 -36.145724) (xy 281.720486 -36.138773) (xy 281.701749 -36.130908)
			(xy 281.691588 -36.130484) (xy 281.677618 -36.130484) (xy 281.667657 -36.130973) (xy 281.649235 -36.138563)
			(xy 281.641804 -36.145216) (xy 281.64155 -36.14547) (xy 281.619925 -36.166448) (xy 281.57129 -36.202005)
			(xy 281.517673 -36.22948) (xy 281.460405 -36.248189) (xy 281.400909 -36.257668) (xy 281.370786 -36.258246)
			(xy 281.343052 -36.25774) (xy 281.288169 -36.249694) (xy 281.23503 -36.233787) (xy 281.184753 -36.210356)
			(xy 281.138398 -36.179892) (xy 281.096941 -36.143039) (xy 281.061255 -36.100573) (xy 281.032094 -36.053388)
			(xy 281.01007 -36.002478) (xy 280.995648 -35.948917) (xy 280.991818 -35.921442) (xy 280.990294 -35.907726)
			(xy 280.988507 -35.879671) (xy 280.992209 -35.823578) (xy 281.004107 -35.768636) (xy 281.023944 -35.716037)
			(xy 281.051289 -35.666921) (xy 281.068018 -35.644328) (xy 281.073154 -35.637093) (xy 281.078484 -35.620181)
			(xy 281.078432 -35.611308) (xy 281.077162 -35.581336) (xy 281.076412 -35.571887) (xy 281.06886 -35.554516)
			(xy 281.06243 -35.547554) (xy 281.002994 -35.488372) (xy 280.878026 -35.363404) (xy 280.844498 -35.328098)
			(xy 280.84399 -35.32759) (xy 280.843482 -35.326828) (xy 280.84018 -35.323526) (xy 280.839672 -35.32251)
			(xy 280.837894 -35.320732) (xy 280.835862 -35.318446) (xy 280.82875 -35.312096) (xy 280.821384 -35.308794)
			(xy 280.817676 -35.307228) (xy 280.80989 -35.305182) (xy 280.80589 -35.30473) (xy 280.789126 -35.302952)
			(xy 280.784258 -35.30257) (xy 280.774535 -35.303457) (xy 280.769822 -35.30473) (xy 280.760932 -35.30727)
			(xy 280.753058 -35.313112) (xy 280.715786 -35.340948) (xy 280.636951 -35.390345) (xy 280.55386 -35.432187)
			(xy 280.467233 -35.46611) (xy 280.377824 -35.49182) (xy 280.28641 -35.509094) (xy 280.193784 -35.517781)
			(xy 280.147268 -35.518344) (xy 280.147014 -35.518344) (xy 280.091486 -35.517586) (xy 279.981118 -35.505239)
			(xy 279.926796 -35.493706) (xy 279.885752 -35.483941) (xy 279.80534 -35.458388) (xy 279.727376 -35.426129)
			(xy 279.652418 -35.387395) (xy 279.581003 -35.342463) (xy 279.513641 -35.291655) (xy 279.450815 -35.235335)
			(xy 279.42159 -35.204908) (xy 279.385972 -35.166093) (xy 279.322213 -35.082223) (xy 279.294336 -35.037522)
			(xy 279.291796 -35.033712) (xy 279.281382 -35.021774) (xy 279.279858 -35.020504) (xy 279.257234 -35.002319)
			(xy 279.21723 -34.960262) (xy 279.184058 -34.912631) (xy 279.158483 -34.860525) (xy 279.141095 -34.805147)
			(xy 279.132296 -34.747774) (xy 279.131776 -34.718752) (xy 279.131776 -34.718498) (xy 279.132239 -34.689997)
			(xy 279.140657 -34.633623) (xy 279.14854 -34.60623) (xy 279.150064 -34.599118) (xy 279.151842 -34.588196)
			(xy 279.151842 -34.58464) (xy 279.151588 -34.581846) (xy 279.15108 -34.567622) (xy 279.15108 -34.566606)
			(xy 279.150064 -34.520886) (xy 279.150499 -34.4783) (xy 279.15774 -34.393435) (xy 279.172193 -34.309498)
			(xy 279.193754 -34.227099) (xy 279.222265 -34.14684) (xy 279.239472 -34.107882) (xy 279.242651 -34.098749)
			(xy 279.242646 -34.079426) (xy 279.239472 -34.07029) (xy 279.222263 -34.031334) (xy 279.19377 -33.95107)
			(xy 279.172219 -33.86867) (xy 279.157767 -33.784734) (xy 279.150519 -33.699872) (xy 279.150064 -33.657286)
			(xy 279.151842 -33.595818) (xy 279.152604 -33.583626) (xy 279.150572 -33.578038) (xy 279.145746 -33.56864)
			(xy 279.137618 -33.55721) (xy 279.108154 -33.525714) (xy 279.100707 -33.518487) (xy 279.081689 -33.510232)
			(xy 279.071324 -33.509712) (xy 278.741632 -33.509712) (xy 278.700792 -33.509294) (xy 278.619386 -33.502596)
			(xy 278.538801 -33.489258) (xy 278.459579 -33.46937) (xy 278.382249 -33.443065) (xy 278.34463 -33.427162)
			(xy 278.340058 -33.42513) (xy 278.325072 -33.421828) (xy 278.314404 -33.420812) (xy 278.229568 -33.420812)
			(xy 278.219937 -33.421282) (xy 278.202059 -33.428468) (xy 278.19477 -33.434782) (xy 278.163912 -33.463685)
			(xy 278.098084 -33.516751) (xy 278.027999 -33.564052) (xy 277.954159 -33.605248) (xy 277.877096 -33.640043)
			(xy 277.797363 -33.668187) (xy 277.715533 -33.689477) (xy 277.632194 -33.703761) (xy 277.547945 -33.710936)
			(xy 277.505668 -33.711388) (xy 277.50516 -33.711388) (xy 277.462329 -33.710933) (xy 277.376982 -33.703589)
			(xy 277.29258 -33.688952) (xy 277.209745 -33.667128) (xy 277.129087 -33.638278) (xy 277.051202 -33.602615)
			(xy 276.976663 -33.560403) (xy 276.906019 -33.511952) (xy 276.839793 -33.457619) (xy 276.778472 -33.397806)
			(xy 276.722507 -33.332952) (xy 276.672313 -33.263537) (xy 276.649942 -33.22701) (xy 276.647437 -33.22319)
			(xy 276.641303 -33.21642) (xy 276.63775 -33.213548) (xy 276.615129 -33.195361) (xy 276.575132 -33.153302)
			(xy 276.541968 -33.10567) (xy 276.516401 -33.053564) (xy 276.499022 -32.998187) (xy 276.490231 -32.940816)
			(xy 276.489668 -32.911796) (xy 276.489668 -32.911542) (xy 276.490172 -32.883107) (xy 276.498589 -32.826865)
			(xy 276.506432 -32.799528) (xy 276.507956 -32.792416) (xy 276.509734 -32.781494) (xy 276.509734 -32.777938)
			(xy 276.50948 -32.775144) (xy 276.508972 -32.76092) (xy 276.508972 -32.759904) (xy 276.507956 -32.714184)
			(xy 276.508391 -32.671598) (xy 276.515632 -32.586733) (xy 276.530086 -32.502796) (xy 276.551646 -32.420397)
			(xy 276.580157 -32.340138) (xy 276.597364 -32.30118) (xy 276.600542 -32.292047) (xy 276.600537 -32.272724)
			(xy 276.597364 -32.263588) (xy 276.580156 -32.224632) (xy 276.551662 -32.144368) (xy 276.530112 -32.061968)
			(xy 276.51566 -31.978032) (xy 276.508413 -31.89317) (xy 276.507956 -31.850584) (xy 276.508972 -31.804864)
			(xy 276.508972 -31.803848) (xy 276.50948 -31.789624) (xy 276.509734 -31.78683) (xy 276.509734 -31.783274)
			(xy 276.507956 -31.772352) (xy 276.506432 -31.76524) (xy 276.498603 -31.7379) (xy 276.490183 -31.68166)
			(xy 276.489668 -31.653226) (xy 276.489668 -31.652972) (xy 276.490213 -31.623952) (xy 276.49901 -31.566583)
			(xy 276.516397 -31.51121) (xy 276.541973 -31.459109) (xy 276.575146 -31.411484) (xy 276.615151 -31.369435)
			(xy 276.63775 -31.35122) (xy 276.641318 -31.348364) (xy 276.647452 -31.34159) (xy 276.649942 -31.337758)
			(xy 276.67236 -31.301261) (xy 276.722551 -31.231846) (xy 276.778512 -31.166993) (xy 276.839829 -31.107178)
			(xy 276.90605 -31.052844) (xy 276.976689 -31.00439) (xy 277.051223 -30.962174) (xy 277.129104 -30.926508)
			(xy 277.209757 -30.897653) (xy 277.292588 -30.875823) (xy 277.376987 -30.861178) (xy 277.46233 -30.853827)
			(xy 277.50516 -30.85338) (xy 277.505414 -30.85338) (xy 277.547865 -30.853818) (xy 277.63246 -30.861031)
			(xy 277.716135 -30.875411) (xy 277.798284 -30.896855) (xy 277.878312 -30.925207) (xy 277.955639 -30.960262)
			(xy 278.029705 -31.001766) (xy 278.099973 -31.049418) (xy 278.165934 -31.102873) (xy 278.196802 -31.132018)
			(xy 278.203547 -31.137272) (xy 278.219514 -31.143361) (xy 278.228044 -31.143956) (xy 279.076658 -31.143956)
			(xy 279.083008 -31.143448) (xy 279.091506 -31.142076) (xy 279.10693 -31.134455) (xy 279.118951 -31.122148)
			(xy 279.122886 -31.114492) (xy 279.132538 -31.091124) (xy 279.133554 -31.080964) (xy 279.133554 -31.080456)
			(xy 279.135838 -31.060694) (xy 279.143984 -31.021753) (xy 279.14981 -31.002732) (xy 279.151064 -30.998274)
			(xy 279.152084 -30.989069) (xy 279.151842 -30.984444) (xy 279.151842 -30.983936) (xy 279.150956 -30.96814)
			(xy 279.150066 -30.936511) (xy 279.150064 -30.92069) (xy 279.150499 -30.878103) (xy 279.15774 -30.793239)
			(xy 279.172193 -30.709301) (xy 279.193753 -30.626903) (xy 279.222263 -30.546643) (xy 279.239472 -30.507686)
			(xy 279.242651 -30.498553) (xy 279.242648 -30.479229) (xy 279.239472 -30.470094) (xy 279.222263 -30.431138)
			(xy 279.193769 -30.350874) (xy 279.172218 -30.268474) (xy 279.157766 -30.184538) (xy 279.150518 -30.099676)
			(xy 279.150064 -30.05709) (xy 279.150318 -30.030166) (xy 279.150318 -30.029912) (xy 279.15014 -30.020569)
			(xy 279.143895 -30.002973) (xy 279.138126 -29.995622) (xy 279.091644 -29.948124) (xy 279.084471 -29.942073)
			(xy 279.066985 -29.935296) (xy 279.057608 -29.934916) (xy 279.04567 -29.934916) (xy 278.998948 -29.934341)
			(xy 278.905928 -29.925457) (xy 278.814162 -29.907829) (xy 278.724471 -29.881612) (xy 278.637656 -29.847043)
			(xy 278.595836 -29.826204) (xy 278.590409 -29.823623) (xy 278.578729 -29.820804) (xy 278.572722 -29.820616)
			(xy 278.23922 -29.820616) (xy 278.23433 -29.820755) (xy 278.22474 -29.822679) (xy 278.22017 -29.824426)
			(xy 278.19477 -29.834586) (xy 278.194516 -29.83484) (xy 278.193246 -29.83611) (xy 278.187912 -29.84119)
			(xy 278.153349 -29.872924) (xy 278.079228 -29.930467) (xy 278.000029 -29.980794) (xy 277.916453 -30.02346)
			(xy 277.829239 -30.058088) (xy 277.739159 -30.08437) (xy 277.647008 -30.102075) (xy 277.553601 -30.111047)
			(xy 277.506684 -30.1117) (xy 277.50516 -30.1117) (xy 277.458632 -30.111148) (xy 277.365984 -30.10245)
			(xy 277.274549 -30.08516) (xy 277.185122 -30.05943) (xy 277.098479 -30.025483) (xy 277.015375 -29.983613)
			(xy 276.936532 -29.934186) (xy 276.862635 -29.877631) (xy 276.794326 -29.814438) (xy 276.7322 -29.745159)
			(xy 276.676796 -29.670394) (xy 276.652228 -29.630878) (xy 276.649688 -29.627068) (xy 276.639274 -29.61513)
			(xy 276.63775 -29.61386) (xy 276.615128 -29.595674) (xy 276.57513 -29.553615) (xy 276.541964 -29.505983)
			(xy 276.516396 -29.453877) (xy 276.499015 -29.3985) (xy 276.490222 -29.341129) (xy 276.489668 -29.312108)
			(xy 276.489668 -29.311854) (xy 276.490135 -29.283354) (xy 276.498558 -29.226981) (xy 276.506432 -29.199586)
			(xy 276.507956 -29.192474) (xy 276.509734 -29.181552) (xy 276.509734 -29.177996) (xy 276.50948 -29.175202)
			(xy 276.508972 -29.160978) (xy 276.508972 -29.159962) (xy 276.507956 -29.114242) (xy 276.508389 -29.071655)
			(xy 276.515625 -28.986789) (xy 276.530074 -28.90285) (xy 276.55163 -28.820449) (xy 276.580137 -28.740187)
			(xy 276.597364 -28.701238) (xy 276.600554 -28.692104) (xy 276.600568 -28.672773) (xy 276.597364 -28.663646)
			(xy 276.580153 -28.62469) (xy 276.551655 -28.544427) (xy 276.5301 -28.462027) (xy 276.515643 -28.378091)
			(xy 276.508391 -28.293228) (xy 276.507956 -28.250642) (xy 276.508972 -28.204922) (xy 276.508972 -28.203906)
			(xy 276.50948 -28.189682) (xy 276.509734 -28.186888) (xy 276.509734 -28.183332) (xy 276.507956 -28.17241)
			(xy 276.506432 -28.165298) (xy 276.498606 -28.137958) (xy 276.490192 -28.081717) (xy 276.489668 -28.053284)
			(xy 276.489668 -28.05303) (xy 276.490209 -28.024008) (xy 276.498998 -27.966635) (xy 276.516379 -27.911255)
			(xy 276.54195 -27.859148) (xy 276.57512 -27.811516) (xy 276.615124 -27.76946) (xy 276.63775 -27.751278)
			(xy 276.641321 -27.748424) (xy 276.647462 -27.741655) (xy 276.649942 -27.737816) (xy 276.67458 -27.6987)
			(xy 276.699679 -27.661793) (xy 276.755502 -27.592141) (xy 276.817328 -27.527759) (xy 276.884662 -27.469162)
			(xy 276.956965 -27.41682) (xy 277.033659 -27.371151) (xy 277.114128 -27.332523) (xy 277.197729 -27.301243)
			(xy 277.283791 -27.277562) (xy 277.371626 -27.261671) (xy 277.46053 -27.253696) (xy 277.50516 -27.253184)
			(xy 277.505414 -27.253184) (xy 277.552933 -27.25374) (xy 277.647538 -27.2628) (xy 277.74085 -27.280827)
			(xy 277.832023 -27.307656) (xy 277.920226 -27.343045) (xy 278.004659 -27.386671) (xy 278.04491 -27.411934)
			(xy 278.082847 -27.43696) (xy 278.154465 -27.492924) (xy 278.187912 -27.523694) (xy 278.193246 -27.528774)
			(xy 278.194516 -27.530044) (xy 278.19477 -27.530298) (xy 278.22017 -27.540458) (xy 278.224736 -27.542216)
			(xy 278.234329 -27.544141) (xy 278.23922 -27.544268) (xy 280.14041 -27.544268) (xy 280.185875 -27.544792)
			(xy 280.276422 -27.553116) (xy 280.365835 -27.569656) (xy 280.453368 -27.594276) (xy 280.49601 -27.610054)
			(xy 280.522426 -27.620722) (xy 281.888184 -28.189428) (xy 281.910455 -28.198783) (xy 281.954163 -28.219364)
			(xy 281.97556 -28.230576) (xy 281.98699 -28.235148) (xy 281.988006 -28.235402) (xy 281.99643 -28.237178)
			(xy 282.013562 -28.235606) (xy 282.021534 -28.232354) (xy 282.043378 -28.222194) (xy 282.05049 -28.21432)
			(xy 282.068655 -28.194741) (xy 282.109515 -28.160347) (xy 282.154772 -28.131988) (xy 282.203542 -28.110217)
			(xy 282.254872 -28.095461) (xy 282.307758 -28.088007) (xy 282.334462 -28.087574) (xy 282.361717 -28.088034)
			(xy 282.415673 -28.095787) (xy 282.467977 -28.111139) (xy 282.517563 -28.133779) (xy 282.5259 -28.139136)
			(xy 286.59785 -28.139136) (xy 286.601921 -28.083514) (xy 286.614047 -28.029077) (xy 286.63397 -27.976986)
			(xy 286.661266 -27.928351) (xy 286.695352 -27.884208) (xy 286.735501 -27.845499) (xy 286.780859 -27.813048)
			(xy 286.830459 -27.787547) (xy 286.883243 -27.76954) (xy 286.938086 -27.75941) (xy 286.99382 -27.757373)
			(xy 287.049257 -27.763473) (xy 287.103214 -27.777579) (xy 287.154543 -27.799391) (xy 287.202149 -27.828445)
			(xy 287.245017 -27.86412) (xy 287.282234 -27.905657) (xy 287.313007 -27.95217) (xy 287.336679 -28.002667)
			(xy 287.352747 -28.056074) (xy 287.360867 -28.11125) (xy 287.361376 -28.139136) (xy 287.86785 -28.139136)
			(xy 287.871921 -28.083514) (xy 287.884047 -28.029077) (xy 287.90397 -27.976986) (xy 287.931266 -27.928351)
			(xy 287.965352 -27.884208) (xy 288.005501 -27.845499) (xy 288.050859 -27.813048) (xy 288.100459 -27.787547)
			(xy 288.153243 -27.76954) (xy 288.208086 -27.75941) (xy 288.26382 -27.757373) (xy 288.319257 -27.763473)
			(xy 288.373214 -27.777579) (xy 288.424543 -27.799391) (xy 288.472149 -27.828445) (xy 288.515017 -27.86412)
			(xy 288.552234 -27.905657) (xy 288.583007 -27.95217) (xy 288.606679 -28.002667) (xy 288.622747 -28.056074)
			(xy 288.630867 -28.11125) (xy 288.631376 -28.139136) (xy 288.630867 -28.167022) (xy 288.622747 -28.222198)
			(xy 288.606679 -28.275605) (xy 288.583007 -28.326102) (xy 288.552234 -28.372615) (xy 288.515017 -28.414152)
			(xy 288.472149 -28.449827) (xy 288.424543 -28.478881) (xy 288.373214 -28.500693) (xy 288.319257 -28.514799)
			(xy 288.26382 -28.520899) (xy 288.208086 -28.518862) (xy 288.153243 -28.508732) (xy 288.100459 -28.490725)
			(xy 288.050859 -28.465224) (xy 288.005501 -28.432773) (xy 287.965352 -28.394064) (xy 287.931266 -28.349921)
			(xy 287.90397 -28.301286) (xy 287.884047 -28.249195) (xy 287.871921 -28.194758) (xy 287.86785 -28.139136)
			(xy 287.361376 -28.139136) (xy 287.360867 -28.167022) (xy 287.352747 -28.222198) (xy 287.336679 -28.275605)
			(xy 287.313007 -28.326102) (xy 287.282234 -28.372615) (xy 287.245017 -28.414152) (xy 287.202149 -28.449827)
			(xy 287.154543 -28.478881) (xy 287.103214 -28.500693) (xy 287.049257 -28.514799) (xy 286.99382 -28.520899)
			(xy 286.938086 -28.518862) (xy 286.883243 -28.508732) (xy 286.830459 -28.490725) (xy 286.780859 -28.465224)
			(xy 286.735501 -28.432773) (xy 286.695352 -28.394064) (xy 286.661266 -28.349921) (xy 286.63397 -28.301286)
			(xy 286.614047 -28.249195) (xy 286.601921 -28.194758) (xy 286.59785 -28.139136) (xy 282.5259 -28.139136)
			(xy 282.563422 -28.163246) (xy 282.604621 -28.19894) (xy 282.64032 -28.240133) (xy 282.669794 -28.285988)
			(xy 282.692441 -28.335571) (xy 282.707801 -28.387872) (xy 282.715562 -28.441827) (xy 282.71597 -28.469082)
			(xy 282.716224 -28.469082) (xy 282.715766 -28.495946) (xy 282.708227 -28.549143) (xy 282.693294 -28.600755)
			(xy 282.671265 -28.64976) (xy 282.642575 -28.695187) (xy 282.625546 -28.71597) (xy 282.62326 -28.71851)
			(xy 282.618886 -28.725084) (xy 282.613981 -28.740085) (xy 282.613608 -28.747974) (xy 282.613608 -28.750768)
			(xy 282.615132 -28.78201) (xy 282.615386 -28.788614) (xy 282.61564 -28.7909) (xy 282.616825 -28.799723)
			(xy 282.624352 -28.81584) (xy 282.630372 -28.822396) (xy 282.716986 -28.908502) (xy 282.93232 -29.12237)
			(xy 292.806628 -29.12237) (xy 292.806628 -28.25877) (xy 292.807118 -28.228786) (xy 292.814946 -28.16933)
			(xy 292.830467 -28.111405) (xy 292.853416 -28.056001) (xy 292.8834 -28.004067) (xy 292.919906 -27.956491)
			(xy 292.962311 -27.914086) (xy 293.009887 -27.87758) (xy 293.061821 -27.847596) (xy 293.117225 -27.824647)
			(xy 293.17515 -27.809126) (xy 293.234606 -27.801298) (xy 293.294574 -27.801298) (xy 293.35403 -27.809126)
			(xy 293.411955 -27.824647) (xy 293.467359 -27.847596) (xy 293.519293 -27.87758) (xy 293.566869 -27.914086)
			(xy 293.609274 -27.956491) (xy 293.64578 -28.004067) (xy 293.675764 -28.056001) (xy 293.698713 -28.111405)
			(xy 293.714234 -28.16933) (xy 293.722062 -28.228786) (xy 293.722552 -28.25877) (xy 293.722552 -29.12237)
			(xy 293.722062 -29.152354) (xy 293.714234 -29.21181) (xy 293.698713 -29.269735) (xy 293.675764 -29.325139)
			(xy 293.64578 -29.377073) (xy 293.609274 -29.424649) (xy 293.566869 -29.467054) (xy 293.519293 -29.50356)
			(xy 293.467359 -29.533544) (xy 293.411955 -29.556493) (xy 293.35403 -29.572014) (xy 293.294574 -29.579842)
			(xy 293.234606 -29.579842) (xy 293.17515 -29.572014) (xy 293.117225 -29.556493) (xy 293.061821 -29.533544)
			(xy 293.009887 -29.50356) (xy 292.962311 -29.467054) (xy 292.919906 -29.424649) (xy 292.8834 -29.377073)
			(xy 292.853416 -29.325139) (xy 292.830467 -29.269735) (xy 292.814946 -29.21181) (xy 292.807118 -29.152354)
			(xy 292.806628 -29.12237) (xy 282.93232 -29.12237) (xy 283.276548 -29.464254) (xy 283.282957 -29.470126)
			(xy 283.298673 -29.477524) (xy 283.307282 -29.478732) (xy 283.315918 -29.479494) (xy 283.332936 -29.475176)
			(xy 283.34081 -29.469842) (xy 283.347922 -29.465016) (xy 283.34843 -29.465016) (xy 283.357828 -29.45892)
			(xy 283.358082 -29.45892) (xy 283.358844 -29.458412) (xy 283.369512 -29.452316) (xy 283.39758 -29.437165)
			(xy 283.45753 -29.415398) (xy 283.520261 -29.403882) (xy 283.552138 -29.402786) (xy 283.564076 -29.402786)
			(xy 283.590721 -29.403689) (xy 283.643381 -29.412019) (xy 283.694368 -29.427599) (xy 283.742689 -29.450124)
			(xy 283.787405 -29.479157) (xy 283.827644 -29.514132) (xy 283.862622 -29.554367) (xy 283.891659 -29.59908)
			(xy 283.914189 -29.6474) (xy 283.929773 -29.698386) (xy 283.938108 -29.751044) (xy 283.93898 -29.77769)
			(xy 283.93898 -29.786326) (xy 283.93848 -29.810484) (xy 283.93211 -29.858381) (xy 283.92628 -29.88183)
			(xy 283.917423 -29.912914) (xy 283.890731 -29.971773) (xy 283.873194 -29.998924) (xy 283.868368 -30.005782)
			(xy 283.86278 -30.014418) (xy 283.864558 -30.032198) (xy 283.865794 -30.040892) (xy 283.873321 -30.056745)
			(xy 283.87929 -30.063186) (xy 284.194886 -30.376876) (xy 285.088838 -30.376876) (xy 285.089397 -30.34796)
			(xy 285.098115 -30.29079) (xy 285.115364 -30.235592) (xy 285.140748 -30.18363) (xy 285.173686 -30.136095)
			(xy 285.213421 -30.094077) (xy 285.235904 -30.075886) (xy 285.244708 -30.068276) (xy 285.254893 -30.047377)
			(xy 285.255462 -30.035754) (xy 285.255462 -29.955998) (xy 285.254923 -29.944366) (xy 285.244735 -29.923455)
			(xy 285.235904 -29.915866) (xy 285.213405 -29.897693) (xy 285.173671 -29.85567) (xy 285.140733 -29.808131)
			(xy 285.115348 -29.756166) (xy 285.098095 -29.700965) (xy 285.08937 -29.643793) (xy 285.088838 -29.614876)
			(xy 285.089324 -29.587625) (xy 285.09708 -29.533677) (xy 285.112435 -29.481382) (xy 285.135077 -29.431805)
			(xy 285.164543 -29.385955) (xy 285.200234 -29.344764) (xy 285.241425 -29.309073) (xy 285.287275 -29.279607)
			(xy 285.336852 -29.256965) (xy 285.389147 -29.24161) (xy 285.443095 -29.233854) (xy 285.497597 -29.233854)
			(xy 285.551545 -29.24161) (xy 285.60384 -29.256965) (xy 285.653417 -29.279607) (xy 285.699267 -29.309073)
			(xy 285.740458 -29.344764) (xy 285.776149 -29.385955) (xy 285.805615 -29.431805) (xy 285.828257 -29.481382)
			(xy 285.843612 -29.533677) (xy 285.851368 -29.587625) (xy 285.851854 -29.614876) (xy 285.851336 -29.643793)
			(xy 285.842609 -29.700965) (xy 285.825352 -29.756165) (xy 285.799961 -29.808127) (xy 285.767016 -29.855661)
			(xy 285.727274 -29.897677) (xy 285.704788 -29.915866) (xy 285.696004 -29.923496) (xy 285.685808 -29.944379)
			(xy 285.68523 -29.955998) (xy 285.68523 -30.035754) (xy 285.685742 -30.04739) (xy 285.695949 -30.068299)
			(xy 285.704788 -30.075886) (xy 285.727262 -30.094088) (xy 285.766999 -30.136105) (xy 285.799939 -30.183638)
			(xy 285.825329 -30.235597) (xy 285.842587 -30.290793) (xy 285.851318 -30.347961) (xy 285.851854 -30.376876)
			(xy 288.128964 -30.376876) (xy 288.129513 -30.34796) (xy 288.138232 -30.290789) (xy 288.155482 -30.23559)
			(xy 288.180868 -30.183627) (xy 288.213808 -30.136093) (xy 288.253546 -30.094076) (xy 288.27603 -30.075886)
			(xy 288.284839 -30.06828) (xy 288.29502 -30.047378) (xy 288.295588 -30.035754) (xy 288.295588 -29.955998)
			(xy 288.29504 -29.944367) (xy 288.284858 -29.923457) (xy 288.27603 -29.915866) (xy 288.253536 -29.897687)
			(xy 288.213801 -29.855665) (xy 288.180862 -29.808128) (xy 288.155475 -29.756165) (xy 288.138221 -29.700965)
			(xy 288.129496 -29.643793) (xy 288.128964 -29.614876) (xy 288.12945 -29.587625) (xy 288.137206 -29.533677)
			(xy 288.152561 -29.481382) (xy 288.175203 -29.431805) (xy 288.204669 -29.385955) (xy 288.24036 -29.344764)
			(xy 288.281551 -29.309073) (xy 288.327401 -29.279607) (xy 288.376978 -29.256965) (xy 288.429273 -29.24161)
			(xy 288.483221 -29.233854) (xy 288.537723 -29.233854) (xy 288.591671 -29.24161) (xy 288.643966 -29.256965)
			(xy 288.693543 -29.279607) (xy 288.739393 -29.309073) (xy 288.780584 -29.344764) (xy 288.816275 -29.385955)
			(xy 288.845741 -29.431805) (xy 288.868383 -29.481382) (xy 288.883738 -29.533677) (xy 288.891494 -29.587625)
			(xy 288.89198 -29.614876) (xy 288.891452 -29.643793) (xy 288.882726 -29.700964) (xy 288.86547 -29.756163)
			(xy 288.840081 -29.808125) (xy 288.807139 -29.855659) (xy 288.767399 -29.897676) (xy 288.744914 -29.915866)
			(xy 288.736118 -29.923483) (xy 288.725932 -29.944377) (xy 288.725356 -29.955998) (xy 288.725356 -30.035754)
			(xy 288.725859 -30.047391) (xy 288.736071 -30.068301) (xy 288.744914 -30.075886) (xy 288.767394 -30.094081)
			(xy 288.807128 -30.136101) (xy 288.840068 -30.183635) (xy 288.865456 -30.235595) (xy 288.882714 -30.290792)
			(xy 288.891444 -30.34796) (xy 288.89198 -30.376876) (xy 288.891494 -30.404127) (xy 288.883738 -30.458075)
			(xy 288.868383 -30.51037) (xy 288.845741 -30.559947) (xy 288.816275 -30.605797) (xy 288.780584 -30.646988)
			(xy 288.739393 -30.682679) (xy 288.693543 -30.712145) (xy 288.643966 -30.734787) (xy 288.591671 -30.750142)
			(xy 288.537723 -30.757898) (xy 288.483221 -30.757898) (xy 288.429273 -30.750142) (xy 288.376978 -30.734787)
			(xy 288.327401 -30.712145) (xy 288.281551 -30.682679) (xy 288.24036 -30.646988) (xy 288.204669 -30.605797)
			(xy 288.175203 -30.559947) (xy 288.152561 -30.51037) (xy 288.137206 -30.458075) (xy 288.12945 -30.404127)
			(xy 288.128964 -30.376876) (xy 285.851854 -30.376876) (xy 285.851368 -30.404127) (xy 285.843612 -30.458075)
			(xy 285.828257 -30.51037) (xy 285.805615 -30.559947) (xy 285.776149 -30.605797) (xy 285.740458 -30.646988)
			(xy 285.699267 -30.682679) (xy 285.653417 -30.712145) (xy 285.60384 -30.734787) (xy 285.551545 -30.750142)
			(xy 285.497597 -30.757898) (xy 285.443095 -30.757898) (xy 285.389147 -30.750142) (xy 285.336852 -30.734787)
			(xy 285.287275 -30.712145) (xy 285.241425 -30.682679) (xy 285.200234 -30.646988) (xy 285.164543 -30.605797)
			(xy 285.135077 -30.559947) (xy 285.112435 -30.51037) (xy 285.09708 -30.458075) (xy 285.089324 -30.404127)
			(xy 285.088838 -30.376876) (xy 284.194886 -30.376876) (xy 284.743792 -30.922468) (xy 290.952428 -30.922468)
			(xy 290.952428 -30.058868) (xy 290.952918 -30.028884) (xy 290.960746 -29.969428) (xy 290.976267 -29.911503)
			(xy 290.999216 -29.856099) (xy 291.0292 -29.804165) (xy 291.065706 -29.756589) (xy 291.108111 -29.714184)
			(xy 291.155687 -29.677678) (xy 291.207621 -29.647694) (xy 291.263025 -29.624745) (xy 291.32095 -29.609224)
			(xy 291.380406 -29.601396) (xy 291.440374 -29.601396) (xy 291.49983 -29.609224) (xy 291.557755 -29.624745)
			(xy 291.613159 -29.647694) (xy 291.665093 -29.677678) (xy 291.712669 -29.714184) (xy 291.755074 -29.756589)
			(xy 291.79158 -29.804165) (xy 291.821564 -29.856099) (xy 291.844513 -29.911503) (xy 291.860034 -29.969428)
			(xy 291.867862 -30.028884) (xy 291.868352 -30.058868) (xy 291.868352 -30.922468) (xy 291.867862 -30.952452)
			(xy 291.860034 -31.011908) (xy 291.844513 -31.069833) (xy 291.821564 -31.125237) (xy 291.79158 -31.177171)
			(xy 291.755074 -31.224747) (xy 291.712669 -31.267152) (xy 291.665093 -31.303658) (xy 291.613159 -31.333642)
			(xy 291.557755 -31.356591) (xy 291.49983 -31.372112) (xy 291.440374 -31.37994) (xy 291.380406 -31.37994)
			(xy 291.32095 -31.372112) (xy 291.263025 -31.356591) (xy 291.207621 -31.333642) (xy 291.155687 -31.303658)
			(xy 291.108111 -31.267152) (xy 291.065706 -31.224747) (xy 291.0292 -31.177171) (xy 290.999216 -31.125237)
			(xy 290.976267 -31.069833) (xy 290.960746 -31.011908) (xy 290.952918 -30.952452) (xy 290.952428 -30.922468)
			(xy 284.743792 -30.922468) (xy 284.973014 -31.150306) (xy 285.001046 -31.178678) (xy 285.052996 -31.239206)
			(xy 285.099947 -31.303689) (xy 285.121096 -31.337504) (xy 285.122874 -31.340298) (xy 285.13278 -31.3563)
			(xy 285.139871 -31.366192) (xy 285.160821 -31.378513) (xy 285.172912 -31.379922) (xy 285.219902 -31.380684)
			(xy 285.228125 -31.380043) (xy 285.243549 -31.374227) (xy 285.250128 -31.369254) (xy 285.25089 -31.368746)
			(xy 285.253938 -31.365952) (xy 285.261812 -31.358078) (xy 285.264606 -31.354014) (xy 285.264606 -31.35376)
			(xy 285.27992 -31.332042) (xy 285.315591 -31.292655) (xy 285.356376 -31.258589) (xy 285.401486 -31.230501)
			(xy 285.450052 -31.208934) (xy 285.501138 -31.194303) (xy 285.553759 -31.18689) (xy 285.580328 -31.186374)
			(xy 285.580836 -31.186374) (xy 285.616904 -31.187898) (xy 285.625286 -31.188914) (xy 285.65278 -31.192653)
			(xy 285.706363 -31.207055) (xy 285.757294 -31.229069) (xy 285.804497 -31.258231) (xy 285.846977 -31.293925)
			(xy 285.883836 -31.335398) (xy 285.914298 -31.381773) (xy 285.937717 -31.432073) (xy 285.953602 -31.485236)
			(xy 285.961615 -31.540139) (xy 285.96209 -31.567882) (xy 285.961588 -31.595679) (xy 285.953519 -31.650686)
			(xy 285.937549 -31.703937) (xy 285.930387 -31.719266) (xy 286.485328 -31.719266) (xy 286.489399 -31.663644)
			(xy 286.501525 -31.609207) (xy 286.521448 -31.557116) (xy 286.548744 -31.508481) (xy 286.58283 -31.464338)
			(xy 286.622979 -31.425629) (xy 286.668337 -31.393178) (xy 286.717937 -31.367677) (xy 286.770721 -31.34967)
			(xy 286.825564 -31.33954) (xy 286.881298 -31.337503) (xy 286.936735 -31.343603) (xy 286.990692 -31.357709)
			(xy 287.042021 -31.379521) (xy 287.089627 -31.408575) (xy 287.132495 -31.44425) (xy 287.169712 -31.485787)
			(xy 287.200485 -31.5323) (xy 287.224157 -31.582797) (xy 287.240225 -31.636204) (xy 287.244375 -31.664402)
			(xy 287.760916 -31.664402) (xy 287.764987 -31.60878) (xy 287.777113 -31.554343) (xy 287.797036 -31.502252)
			(xy 287.824332 -31.453617) (xy 287.858418 -31.409474) (xy 287.898567 -31.370765) (xy 287.943925 -31.338314)
			(xy 287.993525 -31.312813) (xy 288.046309 -31.294806) (xy 288.101152 -31.284676) (xy 288.156886 -31.282639)
			(xy 288.212323 -31.288739) (xy 288.26628 -31.302845) (xy 288.317609 -31.324657) (xy 288.365215 -31.353711)
			(xy 288.408083 -31.389386) (xy 288.4453 -31.430923) (xy 288.476073 -31.477436) (xy 288.499745 -31.527933)
			(xy 288.515813 -31.58134) (xy 288.523933 -31.636516) (xy 288.524442 -31.664402) (xy 288.523933 -31.692288)
			(xy 288.515813 -31.747464) (xy 288.506873 -31.777178) (xy 289.02609 -31.777178) (xy 289.030161 -31.721556)
			(xy 289.042287 -31.667119) (xy 289.06221 -31.615028) (xy 289.089506 -31.566393) (xy 289.123592 -31.52225)
			(xy 289.163741 -31.483541) (xy 289.209099 -31.45109) (xy 289.258699 -31.425589) (xy 289.311483 -31.407582)
			(xy 289.366326 -31.397452) (xy 289.42206 -31.395415) (xy 289.477497 -31.401515) (xy 289.531454 -31.415621)
			(xy 289.582783 -31.437433) (xy 289.630389 -31.466487) (xy 289.673257 -31.502162) (xy 289.710474 -31.543699)
			(xy 289.741247 -31.590212) (xy 289.764919 -31.640709) (xy 289.780987 -31.694116) (xy 289.789107 -31.749292)
			(xy 289.789616 -31.777178) (xy 289.789107 -31.805064) (xy 289.780987 -31.86024) (xy 289.764919 -31.913647)
			(xy 289.741247 -31.964144) (xy 289.710474 -32.010657) (xy 289.673257 -32.052194) (xy 289.630389 -32.087869)
			(xy 289.582783 -32.116923) (xy 289.531454 -32.138735) (xy 289.477497 -32.152841) (xy 289.42206 -32.158941)
			(xy 289.366326 -32.156904) (xy 289.311483 -32.146774) (xy 289.258699 -32.128767) (xy 289.209099 -32.103266)
			(xy 289.163741 -32.070815) (xy 289.123592 -32.032106) (xy 289.089506 -31.987963) (xy 289.06221 -31.939328)
			(xy 289.042287 -31.887237) (xy 289.030161 -31.8328) (xy 289.02609 -31.777178) (xy 288.506873 -31.777178)
			(xy 288.499745 -31.800871) (xy 288.476073 -31.851368) (xy 288.4453 -31.897881) (xy 288.408083 -31.939418)
			(xy 288.365215 -31.975093) (xy 288.317609 -32.004147) (xy 288.26628 -32.025959) (xy 288.212323 -32.040065)
			(xy 288.156886 -32.046165) (xy 288.101152 -32.044128) (xy 288.046309 -32.033998) (xy 287.993525 -32.015991)
			(xy 287.943925 -31.99049) (xy 287.898567 -31.958039) (xy 287.858418 -31.91933) (xy 287.824332 -31.875187)
			(xy 287.797036 -31.826552) (xy 287.777113 -31.774461) (xy 287.764987 -31.720024) (xy 287.760916 -31.664402)
			(xy 287.244375 -31.664402) (xy 287.248345 -31.69138) (xy 287.248854 -31.719266) (xy 287.248345 -31.747152)
			(xy 287.240225 -31.802328) (xy 287.224157 -31.855735) (xy 287.200485 -31.906232) (xy 287.169712 -31.952745)
			(xy 287.132495 -31.994282) (xy 287.089627 -32.029957) (xy 287.042021 -32.059011) (xy 286.990692 -32.080823)
			(xy 286.936735 -32.094929) (xy 286.881298 -32.101029) (xy 286.825564 -32.098992) (xy 286.770721 -32.088862)
			(xy 286.717937 -32.070855) (xy 286.668337 -32.045354) (xy 286.622979 -32.012903) (xy 286.58283 -31.974194)
			(xy 286.548744 -31.930051) (xy 286.521448 -31.881416) (xy 286.501525 -31.829325) (xy 286.489399 -31.774888)
			(xy 286.485328 -31.719266) (xy 285.930387 -31.719266) (xy 285.914017 -31.754306) (xy 285.883421 -31.800725)
			(xy 285.84641 -31.842209) (xy 285.803768 -31.877881) (xy 285.756399 -31.906983) (xy 285.705307 -31.9289)
			(xy 285.651573 -31.943166) (xy 285.624016 -31.94685) (xy 285.621984 -31.947104) (xy 285.610443 -31.94952)
			(xy 285.591253 -31.963172) (xy 285.585154 -31.973266) (xy 285.565342 -32.013652) (xy 285.562802 -32.018986)
			(xy 285.558898 -32.029583) (xy 285.559683 -32.052126) (xy 285.564326 -32.06242) (xy 285.967837 -32.722312)
			(xy 292.806628 -32.722312) (xy 292.806628 -31.858712) (xy 292.807118 -31.828728) (xy 292.814946 -31.769272)
			(xy 292.830467 -31.711347) (xy 292.853416 -31.655943) (xy 292.8834 -31.604009) (xy 292.919906 -31.556433)
			(xy 292.962311 -31.514028) (xy 293.009887 -31.477522) (xy 293.061821 -31.447538) (xy 293.117225 -31.424589)
			(xy 293.17515 -31.409068) (xy 293.234606 -31.40124) (xy 293.294574 -31.40124) (xy 293.35403 -31.409068)
			(xy 293.411955 -31.424589) (xy 293.467359 -31.447538) (xy 293.519293 -31.477522) (xy 293.566869 -31.514028)
			(xy 293.609274 -31.556433) (xy 293.64578 -31.604009) (xy 293.675764 -31.655943) (xy 293.698713 -31.711347)
			(xy 293.714234 -31.769272) (xy 293.722062 -31.828728) (xy 293.722552 -31.858712) (xy 293.722552 -32.722312)
			(xy 293.722062 -32.752296) (xy 293.714234 -32.811752) (xy 293.698713 -32.869677) (xy 293.675764 -32.925081)
			(xy 293.64578 -32.977015) (xy 293.609274 -33.024591) (xy 293.566869 -33.066996) (xy 293.519293 -33.103502)
			(xy 293.467359 -33.133486) (xy 293.411955 -33.156435) (xy 293.35403 -33.171956) (xy 293.294574 -33.179784)
			(xy 293.234606 -33.179784) (xy 293.17515 -33.171956) (xy 293.117225 -33.156435) (xy 293.061821 -33.133486)
			(xy 293.009887 -33.103502) (xy 292.962311 -33.066996) (xy 292.919906 -33.024591) (xy 292.8834 -32.977015)
			(xy 292.853416 -32.925081) (xy 292.830467 -32.869677) (xy 292.814946 -32.811752) (xy 292.807118 -32.752296)
			(xy 292.806628 -32.722312) (xy 285.967837 -32.722312) (xy 286.616902 -33.783778) (xy 286.619868 -33.788338)
			(xy 286.627427 -33.796159) (xy 286.631888 -33.799272) (xy 286.640016 -33.80486) (xy 286.651192 -33.806892)
			(xy 286.677833 -33.812036) (xy 286.729417 -33.828857) (xy 286.778101 -33.852811) (xy 286.822903 -33.883416)
			(xy 286.862921 -33.920055) (xy 286.89735 -33.96199) (xy 286.925495 -34.008376) (xy 286.946791 -34.05828)
			(xy 286.960807 -34.110696) (xy 286.967262 -34.164568) (xy 286.967168 -34.191702) (xy 286.96666 -34.202116)
			(xy 286.965697 -34.217806) (xy 286.961498 -34.24896) (xy 286.958278 -34.264346) (xy 286.956433 -34.275587)
			(xy 286.961564 -34.29775) (xy 286.968184 -34.307018) (xy 287.139911 -34.52241) (xy 290.952428 -34.52241)
			(xy 290.952428 -33.65881) (xy 290.952918 -33.628826) (xy 290.960746 -33.56937) (xy 290.976267 -33.511445)
			(xy 290.999216 -33.456041) (xy 291.0292 -33.404107) (xy 291.065706 -33.356531) (xy 291.108111 -33.314126)
			(xy 291.155687 -33.27762) (xy 291.207621 -33.247636) (xy 291.263025 -33.224687) (xy 291.32095 -33.209166)
			(xy 291.380406 -33.201338) (xy 291.440374 -33.201338) (xy 291.49983 -33.209166) (xy 291.557755 -33.224687)
			(xy 291.613159 -33.247636) (xy 291.665093 -33.27762) (xy 291.712669 -33.314126) (xy 291.755074 -33.356531)
			(xy 291.79158 -33.404107) (xy 291.821564 -33.456041) (xy 291.844513 -33.511445) (xy 291.860034 -33.56937)
			(xy 291.867862 -33.628826) (xy 291.868352 -33.65881) (xy 291.868352 -34.52241) (xy 291.867862 -34.552394)
			(xy 291.860034 -34.61185) (xy 291.844513 -34.669775) (xy 291.821564 -34.725179) (xy 291.79158 -34.777113)
			(xy 291.755074 -34.824689) (xy 291.712669 -34.867094) (xy 291.665093 -34.9036) (xy 291.613159 -34.933584)
			(xy 291.557755 -34.956533) (xy 291.49983 -34.972054) (xy 291.440374 -34.979882) (xy 291.380406 -34.979882)
			(xy 291.32095 -34.972054) (xy 291.263025 -34.956533) (xy 291.207621 -34.933584) (xy 291.155687 -34.9036)
			(xy 291.108111 -34.867094) (xy 291.065706 -34.824689) (xy 291.0292 -34.777113) (xy 290.999216 -34.725179)
			(xy 290.976267 -34.669775) (xy 290.960746 -34.61185) (xy 290.952918 -34.552394) (xy 290.952428 -34.52241)
			(xy 287.139911 -34.52241) (xy 287.731843 -35.264852) (xy 288.102292 -35.264852) (xy 288.106363 -35.20923)
			(xy 288.118489 -35.154793) (xy 288.138412 -35.102702) (xy 288.165708 -35.054067) (xy 288.199794 -35.009924)
			(xy 288.239943 -34.971215) (xy 288.285301 -34.938764) (xy 288.334901 -34.913263) (xy 288.387685 -34.895256)
			(xy 288.442528 -34.885126) (xy 288.498262 -34.883089) (xy 288.553699 -34.889189) (xy 288.607656 -34.903295)
			(xy 288.658985 -34.925107) (xy 288.706591 -34.954161) (xy 288.749459 -34.989836) (xy 288.786676 -35.031373)
			(xy 288.817449 -35.077886) (xy 288.841121 -35.128383) (xy 288.857189 -35.18179) (xy 288.865309 -35.236966)
			(xy 288.865818 -35.264852) (xy 288.865309 -35.292738) (xy 288.857189 -35.347914) (xy 288.841121 -35.401321)
			(xy 288.817449 -35.451818) (xy 288.786676 -35.498331) (xy 288.749459 -35.539868) (xy 288.706591 -35.575543)
			(xy 288.658985 -35.604597) (xy 288.607656 -35.626409) (xy 288.553699 -35.640515) (xy 288.498262 -35.646615)
			(xy 288.442528 -35.644578) (xy 288.387685 -35.634448) (xy 288.334901 -35.616441) (xy 288.285301 -35.59094)
			(xy 288.239943 -35.558489) (xy 288.199794 -35.51978) (xy 288.165708 -35.475637) (xy 288.138412 -35.427002)
			(xy 288.118489 -35.374911) (xy 288.106363 -35.320474) (xy 288.102292 -35.264852) (xy 287.731843 -35.264852)
			(xy 288.546737 -36.286948) (xy 289.400232 -36.286948) (xy 289.404303 -36.231326) (xy 289.416429 -36.176889)
			(xy 289.436352 -36.124798) (xy 289.463648 -36.076163) (xy 289.497734 -36.03202) (xy 289.537883 -35.993311)
			(xy 289.583241 -35.96086) (xy 289.632841 -35.935359) (xy 289.685625 -35.917352) (xy 289.740468 -35.907222)
			(xy 289.796202 -35.905185) (xy 289.851639 -35.911285) (xy 289.905596 -35.925391) (xy 289.956925 -35.947203)
			(xy 290.004531 -35.976257) (xy 290.047399 -36.011932) (xy 290.084616 -36.053469) (xy 290.115389 -36.099982)
			(xy 290.139061 -36.150479) (xy 290.155129 -36.203886) (xy 290.163249 -36.259062) (xy 290.163758 -36.286948)
			(xy 290.163249 -36.314834) (xy 290.155129 -36.37001) (xy 290.139061 -36.423417) (xy 290.115389 -36.473914)
			(xy 290.087844 -36.515548) (xy 291.214046 -36.515548) (xy 291.218117 -36.459926) (xy 291.230243 -36.405489)
			(xy 291.250166 -36.353398) (xy 291.277462 -36.304763) (xy 291.311548 -36.26062) (xy 291.351697 -36.221911)
			(xy 291.397055 -36.18946) (xy 291.446655 -36.163959) (xy 291.499439 -36.145952) (xy 291.554282 -36.135822)
			(xy 291.610016 -36.133785) (xy 291.665453 -36.139885) (xy 291.71941 -36.153991) (xy 291.770739 -36.175803)
			(xy 291.818345 -36.204857) (xy 291.861213 -36.240532) (xy 291.89843 -36.282069) (xy 291.929203 -36.328582)
			(xy 291.952875 -36.379079) (xy 291.968943 -36.432486) (xy 291.977063 -36.487662) (xy 291.977572 -36.515548)
			(xy 291.977063 -36.543434) (xy 291.968943 -36.59861) (xy 291.968486 -36.60013) (xy 296.198551 -36.60013)
			(xy 296.202555 -36.512245) (xy 296.214535 -36.425088) (xy 296.23439 -36.339381) (xy 296.261957 -36.255836)
			(xy 296.297007 -36.175143) (xy 296.339249 -36.097971) (xy 296.388334 -36.024961) (xy 296.443855 -35.956717)
			(xy 296.505352 -35.893804) (xy 296.572314 -35.836744) (xy 296.644188 -35.78601) (xy 296.720378 -35.742022)
			(xy 296.800252 -35.705144) (xy 296.883149 -35.675683) (xy 296.968381 -35.653881) (xy 297.055243 -35.639921)
			(xy 297.143014 -35.633917) (xy 297.230968 -35.63592) (xy 297.318375 -35.645912) (xy 297.404511 -35.663812)
			(xy 297.488663 -35.68947) (xy 297.570133 -35.722674) (xy 297.648246 -35.763148) (xy 297.722354 -35.810559)
			(xy 297.791845 -35.864512) (xy 297.804936 -35.876738) (xy 302.917096 -35.876738) (xy 302.921167 -35.821116)
			(xy 302.933293 -35.766679) (xy 302.953216 -35.714588) (xy 302.980512 -35.665953) (xy 303.014598 -35.62181)
			(xy 303.054747 -35.583101) (xy 303.100105 -35.55065) (xy 303.149705 -35.525149) (xy 303.202489 -35.507142)
			(xy 303.257332 -35.497012) (xy 303.313066 -35.494975) (xy 303.368503 -35.501075) (xy 303.42246 -35.515181)
			(xy 303.473789 -35.536993) (xy 303.521395 -35.566047) (xy 303.564263 -35.601722) (xy 303.60148 -35.643259)
			(xy 303.632253 -35.689772) (xy 303.655925 -35.740269) (xy 303.671993 -35.793676) (xy 303.680113 -35.848852)
			(xy 303.680622 -35.876738) (xy 303.680113 -35.904624) (xy 303.671993 -35.9598) (xy 303.655925 -36.013207)
			(xy 303.632253 -36.063704) (xy 303.60148 -36.110217) (xy 303.564263 -36.151754) (xy 303.521395 -36.187429)
			(xy 303.473789 -36.216483) (xy 303.42246 -36.238295) (xy 303.368503 -36.252401) (xy 303.313066 -36.258501)
			(xy 303.257332 -36.256464) (xy 303.202489 -36.246334) (xy 303.149705 -36.228327) (xy 303.100105 -36.202826)
			(xy 303.054747 -36.170375) (xy 303.014598 -36.131666) (xy 302.980512 -36.087523) (xy 302.953216 -36.038888)
			(xy 302.933293 -35.986797) (xy 302.921167 -35.93236) (xy 302.917096 -35.876738) (xy 297.804936 -35.876738)
			(xy 297.856141 -35.92456) (xy 297.91471 -35.990207) (xy 297.967067 -36.060907) (xy 298.012779 -36.136076)
			(xy 298.051465 -36.21509) (xy 298.082806 -36.297295) (xy 298.106541 -36.382009) (xy 298.122475 -36.46853)
			(xy 298.126258 -36.50996) (xy 304.813714 -36.50996) (xy 304.817785 -36.454338) (xy 304.829911 -36.399901)
			(xy 304.849834 -36.34781) (xy 304.87713 -36.299175) (xy 304.911216 -36.255032) (xy 304.951365 -36.216323)
			(xy 304.996723 -36.183872) (xy 305.046323 -36.158371) (xy 305.099107 -36.140364) (xy 305.15395 -36.130234)
			(xy 305.209684 -36.128197) (xy 305.265121 -36.134297) (xy 305.319078 -36.148403) (xy 305.370407 -36.170215)
			(xy 305.418013 -36.199269) (xy 305.460881 -36.234944) (xy 305.498098 -36.276481) (xy 305.528871 -36.322994)
			(xy 305.552543 -36.373491) (xy 305.568611 -36.426898) (xy 305.576731 -36.482074) (xy 305.57724 -36.50996)
			(xy 305.576731 -36.537846) (xy 305.568611 -36.593022) (xy 305.552543 -36.646429) (xy 305.528871 -36.696926)
			(xy 305.498098 -36.743439) (xy 305.460881 -36.784976) (xy 305.418013 -36.820651) (xy 305.370407 -36.849705)
			(xy 305.319078 -36.871517) (xy 305.265121 -36.885623) (xy 305.209684 -36.891723) (xy 305.15395 -36.889686)
			(xy 305.099107 -36.879556) (xy 305.046323 -36.861549) (xy 304.996723 -36.836048) (xy 304.951365 -36.803597)
			(xy 304.911216 -36.764888) (xy 304.87713 -36.720745) (xy 304.849834 -36.67211) (xy 304.829911 -36.620019)
			(xy 304.817785 -36.565582) (xy 304.813714 -36.50996) (xy 298.126258 -36.50996) (xy 298.130475 -36.556142)
			(xy 298.130976 -36.60013) (xy 298.130475 -36.644118) (xy 298.122475 -36.73173) (xy 298.106541 -36.818251)
			(xy 298.082806 -36.902965) (xy 298.051465 -36.98517) (xy 298.012779 -37.064184) (xy 297.967067 -37.139353)
			(xy 297.91471 -37.210053) (xy 297.856141 -37.2757) (xy 297.791845 -37.335748) (xy 297.722354 -37.389701)
			(xy 297.648246 -37.437112) (xy 297.574815 -37.47516) (xy 301.959008 -37.47516) (xy 301.963079 -37.419538)
			(xy 301.975205 -37.365101) (xy 301.995128 -37.31301) (xy 302.022424 -37.264375) (xy 302.05651 -37.220232)
			(xy 302.096659 -37.181523) (xy 302.142017 -37.149072) (xy 302.191617 -37.123571) (xy 302.244401 -37.105564)
			(xy 302.299244 -37.095434) (xy 302.354978 -37.093397) (xy 302.410415 -37.099497) (xy 302.464372 -37.113603)
			(xy 302.515701 -37.135415) (xy 302.563307 -37.164469) (xy 302.606175 -37.200144) (xy 302.643392 -37.241681)
			(xy 302.674165 -37.288194) (xy 302.697837 -37.338691) (xy 302.713905 -37.392098) (xy 302.722025 -37.447274)
			(xy 302.722534 -37.47516) (xy 302.722025 -37.503046) (xy 302.713905 -37.558222) (xy 302.697837 -37.611629)
			(xy 302.674165 -37.662126) (xy 302.674012 -37.662358) (xy 304.148234 -37.662358) (xy 304.152305 -37.606736)
			(xy 304.164431 -37.552299) (xy 304.184354 -37.500208) (xy 304.21165 -37.451573) (xy 304.245736 -37.40743)
			(xy 304.285885 -37.368721) (xy 304.331243 -37.33627) (xy 304.380843 -37.310769) (xy 304.433627 -37.292762)
			(xy 304.48847 -37.282632) (xy 304.544204 -37.280595) (xy 304.599641 -37.286695) (xy 304.653598 -37.300801)
			(xy 304.704927 -37.322613) (xy 304.752533 -37.351667) (xy 304.795401 -37.387342) (xy 304.832618 -37.428879)
			(xy 304.863391 -37.475392) (xy 304.887063 -37.525889) (xy 304.903131 -37.579296) (xy 304.911251 -37.634472)
			(xy 304.91176 -37.662358) (xy 304.911251 -37.690244) (xy 304.903131 -37.74542) (xy 304.887063 -37.798827)
			(xy 304.863391 -37.849324) (xy 304.832618 -37.895837) (xy 304.795401 -37.937374) (xy 304.752533 -37.973049)
			(xy 304.704927 -38.002103) (xy 304.653598 -38.023915) (xy 304.599641 -38.038021) (xy 304.544204 -38.044121)
			(xy 304.48847 -38.042084) (xy 304.433627 -38.031954) (xy 304.380843 -38.013947) (xy 304.331243 -37.988446)
			(xy 304.285885 -37.955995) (xy 304.245736 -37.917286) (xy 304.21165 -37.873143) (xy 304.184354 -37.824508)
			(xy 304.164431 -37.772417) (xy 304.152305 -37.71798) (xy 304.148234 -37.662358) (xy 302.674012 -37.662358)
			(xy 302.643392 -37.708639) (xy 302.606175 -37.750176) (xy 302.563307 -37.785851) (xy 302.515701 -37.814905)
			(xy 302.464372 -37.836717) (xy 302.410415 -37.850823) (xy 302.354978 -37.856923) (xy 302.299244 -37.854886)
			(xy 302.244401 -37.844756) (xy 302.191617 -37.826749) (xy 302.142017 -37.801248) (xy 302.096659 -37.768797)
			(xy 302.05651 -37.730088) (xy 302.022424 -37.685945) (xy 301.995128 -37.63731) (xy 301.975205 -37.585219)
			(xy 301.963079 -37.530782) (xy 301.959008 -37.47516) (xy 297.574815 -37.47516) (xy 297.570133 -37.477586)
			(xy 297.488663 -37.51079) (xy 297.404511 -37.536448) (xy 297.318375 -37.554348) (xy 297.230968 -37.56434)
			(xy 297.143014 -37.566343) (xy 297.055243 -37.560339) (xy 296.968381 -37.546379) (xy 296.883149 -37.524577)
			(xy 296.800252 -37.495116) (xy 296.720378 -37.458238) (xy 296.644188 -37.41425) (xy 296.572314 -37.363516)
			(xy 296.505352 -37.306456) (xy 296.443855 -37.243543) (xy 296.388334 -37.175299) (xy 296.339249 -37.102289)
			(xy 296.297007 -37.025117) (xy 296.261957 -36.944424) (xy 296.23439 -36.860879) (xy 296.214535 -36.775172)
			(xy 296.202555 -36.688015) (xy 296.198551 -36.60013) (xy 291.968486 -36.60013) (xy 291.952875 -36.652017)
			(xy 291.929203 -36.702514) (xy 291.89843 -36.749027) (xy 291.861213 -36.790564) (xy 291.818345 -36.826239)
			(xy 291.770739 -36.855293) (xy 291.71941 -36.877105) (xy 291.665453 -36.891211) (xy 291.610016 -36.897311)
			(xy 291.554282 -36.895274) (xy 291.499439 -36.885144) (xy 291.446655 -36.867137) (xy 291.397055 -36.841636)
			(xy 291.351697 -36.809185) (xy 291.311548 -36.770476) (xy 291.277462 -36.726333) (xy 291.250166 -36.677698)
			(xy 291.230243 -36.625607) (xy 291.218117 -36.57117) (xy 291.214046 -36.515548) (xy 290.087844 -36.515548)
			(xy 290.084616 -36.520427) (xy 290.047399 -36.561964) (xy 290.004531 -36.597639) (xy 289.956925 -36.626693)
			(xy 289.905596 -36.648505) (xy 289.851639 -36.662611) (xy 289.796202 -36.668711) (xy 289.740468 -36.666674)
			(xy 289.685625 -36.656544) (xy 289.632841 -36.638537) (xy 289.583241 -36.613036) (xy 289.537883 -36.580585)
			(xy 289.497734 -36.541876) (xy 289.463648 -36.497733) (xy 289.436352 -36.449098) (xy 289.416429 -36.397007)
			(xy 289.404303 -36.34257) (xy 289.400232 -36.286948) (xy 288.546737 -36.286948) (xy 289.437572 -37.404294)
			(xy 289.567366 -37.566854) (xy 289.575326 -37.57565) (xy 289.596906 -37.585438) (xy 289.608768 -37.58565)
			(xy 289.681158 -37.582856) (xy 289.691318 -37.582602) (xy 289.702755 -37.581442) (xy 289.722855 -37.570331)
			(xy 289.729926 -37.561266) (xy 289.745198 -37.539366) (xy 289.780885 -37.499652) (xy 289.821756 -37.465297)
			(xy 289.867015 -37.436972) (xy 289.91578 -37.415228) (xy 289.967097 -37.400491) (xy 290.019968 -37.393047)
			(xy 290.046664 -37.39261) (xy 290.073918 -37.393071) (xy 290.127872 -37.400824) (xy 290.180173 -37.416177)
			(xy 290.229757 -37.438818) (xy 290.275613 -37.468285) (xy 290.316808 -37.503979) (xy 290.352504 -37.545173)
			(xy 290.381974 -37.591028) (xy 290.404617 -37.64061) (xy 290.419972 -37.69291) (xy 290.427728 -37.746864)
			(xy 290.428172 -37.774118) (xy 290.427658 -37.802749) (xy 290.419096 -37.859368) (xy 290.402168 -37.914072)
			(xy 290.377254 -37.96563) (xy 290.344913 -38.012886) (xy 290.305872 -38.054777) (xy 290.261009 -38.090362)
			(xy 290.21133 -38.118841) (xy 290.18484 -38.129718) (xy 290.182046 -38.130734) (xy 290.172062 -38.135999)
			(xy 290.15757 -38.153266) (xy 290.154106 -38.164008) (xy 290.13277 -38.242748) (xy 290.131754 -38.246812)
			(xy 290.130289 -38.25767) (xy 290.135678 -38.278881) (xy 290.142168 -38.287706) (xy 292.5189 -41.268751)
			(xy 300.04385 -41.268751) (xy 300.04385 -41.214249) (xy 300.051605 -41.160302) (xy 300.066959 -41.108007)
			(xy 300.089598 -41.05843) (xy 300.119062 -41.012578) (xy 300.154751 -40.971386) (xy 300.195938 -40.935692)
			(xy 300.241786 -40.906222) (xy 300.29136 -40.883577) (xy 300.343653 -40.868216) (xy 300.397599 -40.860453)
			(xy 300.42485 -40.859964) (xy 300.45359 -40.860467) (xy 300.510417 -40.869096) (xy 300.565308 -40.886152)
			(xy 300.617019 -40.911247) (xy 300.664381 -40.943816) (xy 300.685708 -40.963088) (xy 300.692566 -40.969692)
			(xy 300.7106 -40.976804) (xy 300.7995 -40.976804) (xy 300.817534 -40.969692) (xy 300.824392 -40.963088)
			(xy 300.845706 -40.943802) (xy 300.893071 -40.911236) (xy 300.944785 -40.886145) (xy 300.999679 -40.869099)
			(xy 301.05651 -40.860481) (xy 301.08525 -40.859964) (xy 301.112503 -40.86048) (xy 301.166456 -40.86823)
			(xy 301.218756 -40.883581) (xy 301.268338 -40.906219) (xy 301.314194 -40.935684) (xy 301.35539 -40.971375)
			(xy 301.391086 -41.012566) (xy 301.420557 -41.058418) (xy 301.443201 -41.107998) (xy 301.458559 -41.160296)
			(xy 301.466317 -41.214247) (xy 301.466317 -41.268753) (xy 301.458559 -41.322704) (xy 301.443201 -41.375002)
			(xy 301.420557 -41.424582) (xy 301.391086 -41.470434) (xy 301.35539 -41.511625) (xy 301.314194 -41.547316)
			(xy 301.268338 -41.576781) (xy 301.218756 -41.599419) (xy 301.166456 -41.61477) (xy 301.112503 -41.62252)
			(xy 301.08525 -41.62298) (xy 301.056511 -41.622465) (xy 300.999684 -41.613837) (xy 300.944794 -41.596784)
			(xy 300.893083 -41.571691) (xy 300.84572 -41.539126) (xy 300.824392 -41.519856) (xy 300.817534 -41.513252)
			(xy 300.7995 -41.50614) (xy 300.7106 -41.50614) (xy 300.692566 -41.513252) (xy 300.685708 -41.519856)
			(xy 300.664401 -41.539149) (xy 300.617033 -41.571713) (xy 300.565317 -41.596801) (xy 300.510422 -41.613846)
			(xy 300.45359 -41.622463) (xy 300.42485 -41.62298) (xy 300.397599 -41.622547) (xy 300.343653 -41.614784)
			(xy 300.29136 -41.599423) (xy 300.241786 -41.576778) (xy 300.195938 -41.547308) (xy 300.154751 -41.511614)
			(xy 300.119062 -41.470422) (xy 300.089598 -41.42457) (xy 300.066959 -41.374993) (xy 300.051605 -41.322698)
			(xy 300.04385 -41.268751) (xy 292.5189 -41.268751) (xy 294.142541 -43.305222) (xy 302.507142 -43.305222)
			(xy 302.507611 -43.277852) (xy 302.515426 -43.223672) (xy 302.530914 -43.171169) (xy 302.553756 -43.121422)
			(xy 302.58348 -43.075455) (xy 302.601122 -43.054524) (xy 302.601376 -43.05427) (xy 302.606948 -43.047174)
			(xy 302.613202 -43.030264) (xy 302.613568 -43.02125) (xy 302.613568 -42.954194) (xy 302.613221 -42.945176)
			(xy 302.606967 -42.928259) (xy 302.601376 -42.921174) (xy 302.601122 -42.921174) (xy 302.601122 -42.92092)
			(xy 302.583482 -42.899988) (xy 302.55377 -42.854016) (xy 302.530934 -42.804268) (xy 302.515443 -42.751767)
			(xy 302.507615 -42.697591) (xy 302.507142 -42.670222) (xy 302.507695 -42.641484) (xy 302.516313 -42.584659)
			(xy 302.533357 -42.529769) (xy 302.558441 -42.478057) (xy 302.590999 -42.430693) (xy 302.610266 -42.409364)
			(xy 302.61687 -42.402506) (xy 302.623982 -42.384472) (xy 302.623982 -42.295572) (xy 302.61687 -42.277538)
			(xy 302.610266 -42.27068) (xy 302.59102 -42.249333) (xy 302.558458 -42.201972) (xy 302.53337 -42.150263)
			(xy 302.516321 -42.095376) (xy 302.507697 -42.038553) (xy 302.507695 -41.981079) (xy 302.516313 -41.924255)
			(xy 302.533358 -41.869366) (xy 302.558442 -41.817655) (xy 302.590999 -41.770292) (xy 302.610266 -41.748964)
			(xy 302.61687 -41.742106) (xy 302.623982 -41.724072) (xy 302.623982 -41.635172) (xy 302.61687 -41.617138)
			(xy 302.610266 -41.61028) (xy 302.59101 -41.58894) (xy 302.558441 -41.541582) (xy 302.533345 -41.489874)
			(xy 302.516291 -41.434986) (xy 302.507665 -41.37816) (xy 302.507142 -41.349422) (xy 302.507628 -41.322171)
			(xy 302.515384 -41.268223) (xy 302.530739 -41.215928) (xy 302.553381 -41.166351) (xy 302.582847 -41.120501)
			(xy 302.618538 -41.07931) (xy 302.659729 -41.043619) (xy 302.705579 -41.014153) (xy 302.755156 -40.991511)
			(xy 302.807451 -40.976156) (xy 302.861399 -40.9684) (xy 302.915901 -40.9684) (xy 302.969849 -40.976156)
			(xy 303.022144 -40.991511) (xy 303.071721 -41.014153) (xy 303.117571 -41.043619) (xy 303.158762 -41.07931)
			(xy 303.194453 -41.120501) (xy 303.223919 -41.166351) (xy 303.246561 -41.215928) (xy 303.261916 -41.268223)
			(xy 303.269672 -41.322171) (xy 303.270158 -41.349422) (xy 303.269632 -41.378161) (xy 303.261008 -41.434987)
			(xy 303.243957 -41.489877) (xy 303.218867 -41.541589) (xy 303.186303 -41.588952) (xy 303.167034 -41.61028)
			(xy 303.16043 -41.617138) (xy 303.153318 -41.635172) (xy 303.153318 -41.724072) (xy 303.16043 -41.742106)
			(xy 303.167034 -41.748964) (xy 303.186324 -41.770273) (xy 303.218884 -41.81764) (xy 303.24397 -41.869355)
			(xy 303.261016 -41.924248) (xy 303.269635 -41.981077) (xy 303.269633 -42.038555) (xy 303.261009 -42.095383)
			(xy 303.243958 -42.150275) (xy 303.218868 -42.201987) (xy 303.186304 -42.249352) (xy 303.167034 -42.27068)
			(xy 303.16043 -42.277538) (xy 303.153318 -42.295572) (xy 303.153318 -42.384472) (xy 303.16043 -42.402506)
			(xy 303.167034 -42.409364) (xy 303.186311 -42.430686) (xy 303.218877 -42.478049) (xy 303.243969 -42.529762)
			(xy 303.261018 -42.584654) (xy 303.269639 -42.641483) (xy 303.270158 -42.670222) (xy 303.269715 -42.697593)
			(xy 303.261893 -42.751774) (xy 303.246399 -42.804277) (xy 303.225842 -42.849038) (xy 305.091844 -42.849038)
			(xy 305.095915 -42.793416) (xy 305.108041 -42.738979) (xy 305.127964 -42.686888) (xy 305.15526 -42.638253)
			(xy 305.189346 -42.59411) (xy 305.229495 -42.555401) (xy 305.274853 -42.52295) (xy 305.324453 -42.497449)
			(xy 305.377237 -42.479442) (xy 305.43208 -42.469312) (xy 305.487814 -42.467275) (xy 305.543251 -42.473375)
			(xy 305.597208 -42.487481) (xy 305.648537 -42.509293) (xy 305.696143 -42.538347) (xy 305.739011 -42.574022)
			(xy 305.776228 -42.615559) (xy 305.807001 -42.662072) (xy 305.830673 -42.712569) (xy 305.846741 -42.765976)
			(xy 305.854861 -42.821152) (xy 305.85537 -42.849038) (xy 305.854861 -42.876924) (xy 305.846741 -42.9321)
			(xy 305.830673 -42.985507) (xy 305.807001 -43.036004) (xy 305.776228 -43.082517) (xy 305.739011 -43.124054)
			(xy 305.696143 -43.159729) (xy 305.648537 -43.188783) (xy 305.597208 -43.210595) (xy 305.543251 -43.224701)
			(xy 305.487814 -43.230801) (xy 305.43208 -43.228764) (xy 305.377237 -43.218634) (xy 305.324453 -43.200627)
			(xy 305.274853 -43.175126) (xy 305.229495 -43.142675) (xy 305.189346 -43.103966) (xy 305.15526 -43.059823)
			(xy 305.127964 -43.011188) (xy 305.108041 -42.959097) (xy 305.095915 -42.90466) (xy 305.091844 -42.849038)
			(xy 303.225842 -42.849038) (xy 303.223552 -42.854024) (xy 303.193822 -42.899989) (xy 303.176178 -42.92092)
			(xy 303.175924 -42.921174) (xy 303.170333 -42.928257) (xy 303.164091 -42.945177) (xy 303.163732 -42.954194)
			(xy 303.163732 -43.02125) (xy 303.164106 -43.030265) (xy 303.170341 -43.047183) (xy 303.175924 -43.05427)
			(xy 303.176178 -43.05427) (xy 303.176178 -43.054524) (xy 303.193792 -43.075477) (xy 303.223508 -43.121444)
			(xy 303.246349 -43.171186) (xy 303.261846 -43.223682) (xy 303.269681 -43.277854) (xy 303.270158 -43.305222)
			(xy 303.269672 -43.332473) (xy 303.261916 -43.386421) (xy 303.246561 -43.438716) (xy 303.223919 -43.488293)
			(xy 303.194453 -43.534143) (xy 303.158762 -43.575334) (xy 303.117571 -43.611025) (xy 303.071721 -43.640491)
			(xy 303.022144 -43.663133) (xy 302.969849 -43.678488) (xy 302.915901 -43.686244) (xy 302.861399 -43.686244)
			(xy 302.807451 -43.678488) (xy 302.755156 -43.663133) (xy 302.705579 -43.640491) (xy 302.659729 -43.611025)
			(xy 302.618538 -43.575334) (xy 302.582847 -43.534143) (xy 302.553381 -43.488293) (xy 302.530739 -43.438716)
			(xy 302.515384 -43.386421) (xy 302.507628 -43.332473) (xy 302.507142 -43.305222) (xy 294.142541 -43.305222)
			(xy 294.4862 -43.73626) (xy 304.412902 -43.73626) (xy 304.416973 -43.680638) (xy 304.429099 -43.626201)
			(xy 304.449022 -43.57411) (xy 304.476318 -43.525475) (xy 304.510404 -43.481332) (xy 304.550553 -43.442623)
			(xy 304.595911 -43.410172) (xy 304.645511 -43.384671) (xy 304.698295 -43.366664) (xy 304.753138 -43.356534)
			(xy 304.808872 -43.354497) (xy 304.864309 -43.360597) (xy 304.918266 -43.374703) (xy 304.969595 -43.396515)
			(xy 305.017201 -43.425569) (xy 305.060069 -43.461244) (xy 305.097286 -43.502781) (xy 305.128059 -43.549294)
			(xy 305.136285 -43.566842) (xy 307.533292 -43.566842) (xy 307.537363 -43.51122) (xy 307.549489 -43.456783)
			(xy 307.569412 -43.404692) (xy 307.596708 -43.356057) (xy 307.630794 -43.311914) (xy 307.670943 -43.273205)
			(xy 307.716301 -43.240754) (xy 307.765901 -43.215253) (xy 307.818685 -43.197246) (xy 307.873528 -43.187116)
			(xy 307.929262 -43.185079) (xy 307.984699 -43.191179) (xy 308.038656 -43.205285) (xy 308.089985 -43.227097)
			(xy 308.137591 -43.256151) (xy 308.180459 -43.291826) (xy 308.217676 -43.333363) (xy 308.248449 -43.379876)
			(xy 308.272121 -43.430373) (xy 308.288189 -43.48378) (xy 308.296309 -43.538956) (xy 308.296818 -43.566842)
			(xy 308.296309 -43.594728) (xy 308.288189 -43.649904) (xy 308.272121 -43.703311) (xy 308.248449 -43.753808)
			(xy 308.217676 -43.800321) (xy 308.180459 -43.841858) (xy 308.162372 -43.85691) (xy 308.919624 -43.85691)
			(xy 308.923695 -43.801288) (xy 308.935821 -43.746851) (xy 308.955744 -43.69476) (xy 308.98304 -43.646125)
			(xy 309.017126 -43.601982) (xy 309.057275 -43.563273) (xy 309.102633 -43.530822) (xy 309.152233 -43.505321)
			(xy 309.205017 -43.487314) (xy 309.25986 -43.477184) (xy 309.315594 -43.475147) (xy 309.371031 -43.481247)
			(xy 309.424988 -43.495353) (xy 309.476317 -43.517165) (xy 309.523923 -43.546219) (xy 309.566791 -43.581894)
			(xy 309.604008 -43.623431) (xy 309.634781 -43.669944) (xy 309.658453 -43.720441) (xy 309.674521 -43.773848)
			(xy 309.682641 -43.829024) (xy 309.68315 -43.85691) (xy 309.682641 -43.884796) (xy 309.674521 -43.939972)
			(xy 309.658453 -43.993379) (xy 309.634781 -44.043876) (xy 309.604008 -44.090389) (xy 309.566791 -44.131926)
			(xy 309.523923 -44.167601) (xy 309.476317 -44.196655) (xy 309.424988 -44.218467) (xy 309.371031 -44.232573)
			(xy 309.315594 -44.238673) (xy 309.25986 -44.236636) (xy 309.205017 -44.226506) (xy 309.152233 -44.208499)
			(xy 309.102633 -44.182998) (xy 309.057275 -44.150547) (xy 309.017126 -44.111838) (xy 308.98304 -44.067695)
			(xy 308.955744 -44.01906) (xy 308.935821 -43.966969) (xy 308.923695 -43.912532) (xy 308.919624 -43.85691)
			(xy 308.162372 -43.85691) (xy 308.137591 -43.877533) (xy 308.089985 -43.906587) (xy 308.038656 -43.928399)
			(xy 307.984699 -43.942505) (xy 307.929262 -43.948605) (xy 307.873528 -43.946568) (xy 307.818685 -43.936438)
			(xy 307.765901 -43.918431) (xy 307.716301 -43.89293) (xy 307.670943 -43.860479) (xy 307.630794 -43.82177)
			(xy 307.596708 -43.777627) (xy 307.569412 -43.728992) (xy 307.549489 -43.676901) (xy 307.537363 -43.622464)
			(xy 307.533292 -43.566842) (xy 305.136285 -43.566842) (xy 305.151731 -43.599791) (xy 305.167799 -43.653198)
			(xy 305.175919 -43.708374) (xy 305.176428 -43.73626) (xy 305.175919 -43.764146) (xy 305.167799 -43.819322)
			(xy 305.151731 -43.872729) (xy 305.128059 -43.923226) (xy 305.097286 -43.969739) (xy 305.060069 -44.011276)
			(xy 305.017201 -44.046951) (xy 304.969595 -44.076005) (xy 304.918266 -44.097817) (xy 304.864309 -44.111923)
			(xy 304.808872 -44.118023) (xy 304.753138 -44.115986) (xy 304.698295 -44.105856) (xy 304.645511 -44.087849)
			(xy 304.595911 -44.062348) (xy 304.550553 -44.029897) (xy 304.510404 -43.991188) (xy 304.476318 -43.947045)
			(xy 304.449022 -43.89841) (xy 304.429099 -43.846319) (xy 304.416973 -43.791882) (xy 304.412902 -43.73626)
			(xy 294.4862 -43.73626) (xy 295.585016 -45.114464) (xy 304.265328 -45.114464) (xy 304.269399 -45.058842)
			(xy 304.281525 -45.004405) (xy 304.301448 -44.952314) (xy 304.328744 -44.903679) (xy 304.36283 -44.859536)
			(xy 304.402979 -44.820827) (xy 304.448337 -44.788376) (xy 304.497937 -44.762875) (xy 304.550721 -44.744868)
			(xy 304.605564 -44.734738) (xy 304.661298 -44.732701) (xy 304.716735 -44.738801) (xy 304.770692 -44.752907)
			(xy 304.822021 -44.774719) (xy 304.869627 -44.803773) (xy 304.912495 -44.839448) (xy 304.942477 -44.87291)
			(xy 311.13298 -44.87291) (xy 311.137051 -44.817288) (xy 311.149177 -44.762851) (xy 311.1691 -44.71076)
			(xy 311.196396 -44.662125) (xy 311.230482 -44.617982) (xy 311.270631 -44.579273) (xy 311.315989 -44.546822)
			(xy 311.365589 -44.521321) (xy 311.418373 -44.503314) (xy 311.473216 -44.493184) (xy 311.52895 -44.491147)
			(xy 311.584387 -44.497247) (xy 311.638344 -44.511353) (xy 311.689673 -44.533165) (xy 311.737279 -44.562219)
			(xy 311.780147 -44.597894) (xy 311.817364 -44.639431) (xy 311.848137 -44.685944) (xy 311.871809 -44.736441)
			(xy 311.887877 -44.789848) (xy 311.895997 -44.845024) (xy 311.896506 -44.87291) (xy 311.895997 -44.900796)
			(xy 311.887877 -44.955972) (xy 311.871809 -45.009379) (xy 311.848137 -45.059876) (xy 311.817364 -45.106389)
			(xy 311.780147 -45.147926) (xy 311.737279 -45.183601) (xy 311.689673 -45.212655) (xy 311.638344 -45.234467)
			(xy 311.584387 -45.248573) (xy 311.52895 -45.254673) (xy 311.473216 -45.252636) (xy 311.418373 -45.242506)
			(xy 311.365589 -45.224499) (xy 311.315989 -45.198998) (xy 311.270631 -45.166547) (xy 311.230482 -45.127838)
			(xy 311.196396 -45.083695) (xy 311.1691 -45.03506) (xy 311.149177 -44.982969) (xy 311.137051 -44.928532)
			(xy 311.13298 -44.87291) (xy 304.942477 -44.87291) (xy 304.949712 -44.880985) (xy 304.980485 -44.927498)
			(xy 305.004157 -44.977995) (xy 305.020225 -45.031402) (xy 305.028345 -45.086578) (xy 305.028854 -45.114464)
			(xy 305.028345 -45.14235) (xy 305.020225 -45.197526) (xy 305.004157 -45.250933) (xy 304.980485 -45.30143)
			(xy 304.949712 -45.347943) (xy 304.94407 -45.35424) (xy 308.903622 -45.35424) (xy 308.907693 -45.298618)
			(xy 308.919819 -45.244181) (xy 308.939742 -45.19209) (xy 308.967038 -45.143455) (xy 309.001124 -45.099312)
			(xy 309.041273 -45.060603) (xy 309.086631 -45.028152) (xy 309.136231 -45.002651) (xy 309.189015 -44.984644)
			(xy 309.243858 -44.974514) (xy 309.299592 -44.972477) (xy 309.355029 -44.978577) (xy 309.408986 -44.992683)
			(xy 309.460315 -45.014495) (xy 309.507921 -45.043549) (xy 309.550789 -45.079224) (xy 309.588006 -45.120761)
			(xy 309.618779 -45.167274) (xy 309.642451 -45.217771) (xy 309.658519 -45.271178) (xy 309.666639 -45.326354)
			(xy 309.667148 -45.35424) (xy 309.666639 -45.382126) (xy 309.658519 -45.437302) (xy 309.642451 -45.490709)
			(xy 309.618779 -45.541206) (xy 309.588006 -45.587719) (xy 309.550789 -45.629256) (xy 309.507921 -45.664931)
			(xy 309.460315 -45.693985) (xy 309.408986 -45.715797) (xy 309.355029 -45.729903) (xy 309.299592 -45.736003)
			(xy 309.243858 -45.733966) (xy 309.189015 -45.723836) (xy 309.136231 -45.705829) (xy 309.086631 -45.680328)
			(xy 309.041273 -45.647877) (xy 309.001124 -45.609168) (xy 308.967038 -45.565025) (xy 308.939742 -45.51639)
			(xy 308.919819 -45.464299) (xy 308.907693 -45.409862) (xy 308.903622 -45.35424) (xy 304.94407 -45.35424)
			(xy 304.912495 -45.38948) (xy 304.869627 -45.425155) (xy 304.822021 -45.454209) (xy 304.770692 -45.476021)
			(xy 304.716735 -45.490127) (xy 304.661298 -45.496227) (xy 304.605564 -45.49419) (xy 304.550721 -45.48406)
			(xy 304.497937 -45.466053) (xy 304.448337 -45.440552) (xy 304.402979 -45.408101) (xy 304.36283 -45.369392)
			(xy 304.328744 -45.325249) (xy 304.301448 -45.276614) (xy 304.281525 -45.224523) (xy 304.269399 -45.170086)
			(xy 304.265328 -45.114464) (xy 295.585016 -45.114464) (xy 296.356577 -46.082204) (xy 302.25238 -46.082204)
			(xy 302.252881 -46.054953) (xy 302.260637 -46.001007) (xy 302.275991 -45.948713) (xy 302.298631 -45.899137)
			(xy 302.328096 -45.853287) (xy 302.363786 -45.812097) (xy 302.404974 -45.776405) (xy 302.450823 -45.746939)
			(xy 302.500398 -45.724297) (xy 302.552691 -45.708941) (xy 302.606637 -45.701183) (xy 302.633888 -45.700696)
			(xy 302.66079 -45.701167) (xy 302.71406 -45.708738) (xy 302.765738 -45.723715) (xy 302.8148 -45.745804)
			(xy 302.860272 -45.774565) (xy 302.901254 -45.809428) (xy 302.936932 -45.849703) (xy 302.95215 -45.871892)
			(xy 302.959262 -45.882814) (xy 302.982122 -45.894752) (xy 303.09439 -45.89272) (xy 303.116742 -45.879766)
			(xy 303.1236 -45.86859) (xy 303.138535 -45.844997) (xy 303.174212 -45.802046) (xy 303.215768 -45.764752)
			(xy 303.262316 -45.733914) (xy 303.312861 -45.710189) (xy 303.366324 -45.694084) (xy 303.421564 -45.685944)
			(xy 303.449482 -45.685456) (xy 303.476475 -45.685928) (xy 303.529923 -45.693531) (xy 303.581766 -45.708589)
			(xy 303.630971 -45.7308) (xy 303.676555 -45.759723) (xy 303.697386 -45.776896) (xy 303.705514 -45.784008)
			(xy 303.726088 -45.790104) (xy 303.811432 -45.779182) (xy 303.821983 -45.777433) (xy 303.840263 -45.766361)
			(xy 303.846738 -45.757846) (xy 303.862074 -45.736602) (xy 303.897664 -45.69815) (xy 303.938184 -45.664932)
			(xy 303.98287 -45.637575) (xy 304.030881 -45.616594) (xy 304.081312 -45.602384) (xy 304.133214 -45.595212)
			(xy 304.159412 -45.594778) (xy 304.186662 -45.595293) (xy 304.240606 -45.603051) (xy 304.292897 -45.618406)
			(xy 304.342471 -45.641047) (xy 304.388318 -45.670513) (xy 304.429506 -45.706203) (xy 304.465194 -45.747391)
			(xy 304.494659 -45.793239) (xy 304.517298 -45.842814) (xy 304.532652 -45.895106) (xy 304.540408 -45.94905)
			(xy 304.540408 -46.00355) (xy 304.532652 -46.057494) (xy 304.517298 -46.109786) (xy 304.494659 -46.159361)
			(xy 304.465194 -46.205209) (xy 304.429506 -46.246397) (xy 304.388318 -46.282087) (xy 304.342471 -46.311553)
			(xy 304.292897 -46.334194) (xy 304.240606 -46.349549) (xy 304.186662 -46.357307) (xy 304.159412 -46.357794)
			(xy 304.13242 -46.357314) (xy 304.078973 -46.349711) (xy 304.02713 -46.334654) (xy 303.977925 -46.312445)
			(xy 303.93234 -46.283525) (xy 303.911508 -46.266354) (xy 303.90338 -46.259242) (xy 303.882806 -46.253146)
			(xy 303.797462 -46.264068) (xy 303.786927 -46.265881) (xy 303.768641 -46.276909) (xy 303.762156 -46.285404)
			(xy 303.744546 -46.309706) (xy 303.702948 -46.352965) (xy 303.679352 -46.37151) (xy 303.671478 -46.377352)
			(xy 303.661064 -46.394878) (xy 303.647856 -46.485302) (xy 303.652682 -46.504606) (xy 303.658524 -46.51248)
			(xy 303.658524 -46.512734) (xy 303.676021 -46.537483) (xy 303.703826 -46.591333) (xy 303.722764 -46.648904)
			(xy 303.729968 -46.693836) (xy 308.876192 -46.693836) (xy 308.876678 -46.666585) (xy 308.884434 -46.612637)
			(xy 308.899789 -46.560342) (xy 308.922431 -46.510765) (xy 308.951897 -46.464915) (xy 308.987588 -46.423724)
			(xy 309.028779 -46.388033) (xy 309.074629 -46.358567) (xy 309.124206 -46.335925) (xy 309.176501 -46.32057)
			(xy 309.230449 -46.312814) (xy 309.284951 -46.312814) (xy 309.338899 -46.32057) (xy 309.391194 -46.335925)
			(xy 309.440771 -46.358567) (xy 309.486621 -46.388033) (xy 309.527812 -46.423724) (xy 309.563503 -46.464915)
			(xy 309.592969 -46.510765) (xy 309.615611 -46.560342) (xy 309.630966 -46.612637) (xy 309.638722 -46.666585)
			(xy 309.639208 -46.693836) (xy 309.638734 -46.720264) (xy 309.631425 -46.772611) (xy 309.616952 -46.823446)
			(xy 309.595593 -46.871793) (xy 309.582058 -46.894496) (xy 309.581804 -46.89475) (xy 309.576467 -46.904768)
			(xy 309.574212 -46.927318) (xy 309.577486 -46.938184) (xy 309.603648 -47.01286) (xy 309.608034 -47.023374)
			(xy 309.624121 -47.039463) (xy 309.634636 -47.043848) (xy 309.63489 -47.043848) (xy 309.659408 -47.052893)
			(xy 309.70586 -47.07684) (xy 309.74861 -47.106901) (xy 309.786861 -47.142512) (xy 309.819896 -47.183008)
			(xy 309.847098 -47.227631) (xy 309.867959 -47.275548) (xy 309.882088 -47.325863) (xy 309.889221 -47.377635)
			(xy 309.889652 -47.403766) (xy 309.889166 -47.431017) (xy 309.887643 -47.441612) (xy 311.161682 -47.441612)
			(xy 311.165753 -47.38599) (xy 311.177879 -47.331553) (xy 311.197802 -47.279462) (xy 311.225098 -47.230827)
			(xy 311.259184 -47.186684) (xy 311.299333 -47.147975) (xy 311.344691 -47.115524) (xy 311.394291 -47.090023)
			(xy 311.447075 -47.072016) (xy 311.501918 -47.061886) (xy 311.557652 -47.059849) (xy 311.613089 -47.065949)
			(xy 311.667046 -47.080055) (xy 311.718375 -47.101867) (xy 311.765981 -47.130921) (xy 311.808849 -47.166596)
			(xy 311.846066 -47.208133) (xy 311.876839 -47.254646) (xy 311.900511 -47.305143) (xy 311.916579 -47.35855)
			(xy 311.924699 -47.413726) (xy 311.925208 -47.441612) (xy 311.924699 -47.469498) (xy 311.916579 -47.524674)
			(xy 311.900511 -47.578081) (xy 311.876839 -47.628578) (xy 311.846066 -47.675091) (xy 311.808849 -47.716628)
			(xy 311.765981 -47.752303) (xy 311.718375 -47.781357) (xy 311.667046 -47.803169) (xy 311.613089 -47.817275)
			(xy 311.557652 -47.823375) (xy 311.501918 -47.821338) (xy 311.447075 -47.811208) (xy 311.394291 -47.793201)
			(xy 311.344691 -47.7677) (xy 311.299333 -47.735249) (xy 311.259184 -47.69654) (xy 311.225098 -47.652397)
			(xy 311.197802 -47.603762) (xy 311.177879 -47.551671) (xy 311.165753 -47.497234) (xy 311.161682 -47.441612)
			(xy 309.887643 -47.441612) (xy 309.88141 -47.484965) (xy 309.866055 -47.53726) (xy 309.843413 -47.586837)
			(xy 309.813947 -47.632687) (xy 309.778256 -47.673878) (xy 309.737065 -47.709569) (xy 309.691215 -47.739035)
			(xy 309.641638 -47.761677) (xy 309.589343 -47.777032) (xy 309.535395 -47.784788) (xy 309.480893 -47.784788)
			(xy 309.426945 -47.777032) (xy 309.37465 -47.761677) (xy 309.325073 -47.739035) (xy 309.279223 -47.709569)
			(xy 309.238032 -47.673878) (xy 309.202341 -47.632687) (xy 309.172875 -47.586837) (xy 309.150233 -47.53726)
			(xy 309.134878 -47.484965) (xy 309.127122 -47.431017) (xy 309.126636 -47.403766) (xy 309.127105 -47.377338)
			(xy 309.134415 -47.324991) (xy 309.148889 -47.274156) (xy 309.170251 -47.225809) (xy 309.183786 -47.203106)
			(xy 309.18404 -47.202852) (xy 309.189375 -47.192833) (xy 309.191634 -47.170284) (xy 309.188358 -47.159418)
			(xy 309.162196 -47.084742) (xy 309.157835 -47.074215) (xy 309.141731 -47.058131) (xy 309.131208 -47.053754)
			(xy 309.130954 -47.053754) (xy 309.106446 -47.044683) (xy 309.059994 -47.02074) (xy 309.017242 -46.990685)
			(xy 308.97899 -46.955078) (xy 308.945953 -46.914585) (xy 308.918749 -46.869964) (xy 308.897887 -46.822049)
			(xy 308.883757 -46.771736) (xy 308.876623 -46.719966) (xy 308.876192 -46.693836) (xy 303.729968 -46.693836)
			(xy 303.732358 -46.708745) (xy 303.732946 -46.739048) (xy 303.732467 -46.766299) (xy 303.724705 -46.820245)
			(xy 303.709346 -46.872537) (xy 303.686702 -46.922112) (xy 303.657234 -46.96796) (xy 303.621542 -47.009149)
			(xy 303.580352 -47.04484) (xy 303.534503 -47.074306) (xy 303.484928 -47.096949) (xy 303.432635 -47.112307)
			(xy 303.378689 -47.120068) (xy 303.351438 -47.120556) (xy 303.325405 -47.12008) (xy 303.273824 -47.112999)
			(xy 303.223683 -47.098976) (xy 303.175911 -47.078271) (xy 303.131395 -47.051269) (xy 303.1109 -47.035212)
			(xy 303.10315 -47.029459) (xy 303.084734 -47.023725) (xy 303.075086 -47.024036) (xy 302.99533 -47.030386)
			(xy 302.97755 -47.039022) (xy 302.9712 -47.046388) (xy 302.953042 -47.066056) (xy 302.912129 -47.100576)
			(xy 302.866796 -47.129042) (xy 302.81793 -47.150896) (xy 302.76649 -47.165709) (xy 302.713485 -47.17319)
			(xy 302.68672 -47.173642) (xy 302.659471 -47.173103) (xy 302.605527 -47.16535) (xy 302.553235 -47.149999)
			(xy 302.50366 -47.127363) (xy 302.457812 -47.097902) (xy 302.416622 -47.062216) (xy 302.38093 -47.021032)
			(xy 302.351463 -46.975187) (xy 302.328819 -46.925615) (xy 302.313461 -46.873326) (xy 302.305701 -46.819383)
			(xy 302.305212 -46.792134) (xy 302.305733 -46.76336) (xy 302.314385 -46.706465) (xy 302.331481 -46.651515)
			(xy 302.356636 -46.599755) (xy 302.389277 -46.552359) (xy 302.40859 -46.531022) (xy 302.415956 -46.523148)
			(xy 302.423068 -46.503336) (xy 302.415702 -46.40707) (xy 302.405796 -46.388274) (xy 302.397414 -46.38167)
			(xy 302.375228 -46.363447) (xy 302.336019 -46.321511) (xy 302.303533 -46.274175) (xy 302.278505 -46.222507)
			(xy 302.261499 -46.167672) (xy 302.252898 -46.110909) (xy 302.25238 -46.082204) (xy 296.356577 -46.082204)
			(xy 296.53357 -46.3042) (xy 296.55938 -46.337246) (xy 296.605983 -46.406959) (xy 296.646564 -46.480342)
			(xy 296.680836 -46.556875) (xy 296.695114 -46.5963) (xy 297.294508 -48.30699) (xy 308.753762 -48.30699)
			(xy 308.757833 -48.251368) (xy 308.769959 -48.196931) (xy 308.789882 -48.14484) (xy 308.817178 -48.096205)
			(xy 308.851264 -48.052062) (xy 308.891413 -48.013353) (xy 308.936771 -47.980902) (xy 308.986371 -47.955401)
			(xy 309.039155 -47.937394) (xy 309.093998 -47.927264) (xy 309.149732 -47.925227) (xy 309.205169 -47.931327)
			(xy 309.259126 -47.945433) (xy 309.310455 -47.967245) (xy 309.358061 -47.996299) (xy 309.400929 -48.031974)
			(xy 309.438146 -48.073511) (xy 309.468919 -48.120024) (xy 309.492591 -48.170521) (xy 309.508659 -48.223928)
			(xy 309.516779 -48.279104) (xy 309.517288 -48.30699) (xy 309.516779 -48.334876) (xy 309.508659 -48.390052)
			(xy 309.492591 -48.443459) (xy 309.468919 -48.493956) (xy 309.438146 -48.540469) (xy 309.400929 -48.582006)
			(xy 309.358061 -48.617681) (xy 309.310455 -48.646735) (xy 309.259126 -48.668547) (xy 309.205169 -48.682653)
			(xy 309.149732 -48.688753) (xy 309.093998 -48.686716) (xy 309.039155 -48.676586) (xy 308.986371 -48.658579)
			(xy 308.936771 -48.633078) (xy 308.891413 -48.600627) (xy 308.851264 -48.561918) (xy 308.817178 -48.517775)
			(xy 308.789882 -48.46914) (xy 308.769959 -48.417049) (xy 308.757833 -48.362612) (xy 308.753762 -48.30699)
			(xy 297.294508 -48.30699) (xy 297.450787 -48.753014) (xy 305.368196 -48.753014) (xy 305.372267 -48.697392)
			(xy 305.384393 -48.642955) (xy 305.404316 -48.590864) (xy 305.431612 -48.542229) (xy 305.465698 -48.498086)
			(xy 305.505847 -48.459377) (xy 305.551205 -48.426926) (xy 305.600805 -48.401425) (xy 305.653589 -48.383418)
			(xy 305.708432 -48.373288) (xy 305.764166 -48.371251) (xy 305.819603 -48.377351) (xy 305.87356 -48.391457)
			(xy 305.924889 -48.413269) (xy 305.972495 -48.442323) (xy 306.015363 -48.477998) (xy 306.05258 -48.519535)
			(xy 306.083353 -48.566048) (xy 306.107025 -48.616545) (xy 306.123093 -48.669952) (xy 306.131213 -48.725128)
			(xy 306.131722 -48.753014) (xy 306.131213 -48.7809) (xy 306.123093 -48.836076) (xy 306.120649 -48.8442)
			(xy 306.387244 -48.8442) (xy 306.391315 -48.788578) (xy 306.403441 -48.734141) (xy 306.423364 -48.68205)
			(xy 306.45066 -48.633415) (xy 306.484746 -48.589272) (xy 306.524895 -48.550563) (xy 306.570253 -48.518112)
			(xy 306.619853 -48.492611) (xy 306.672637 -48.474604) (xy 306.72748 -48.464474) (xy 306.783214 -48.462437)
			(xy 306.838651 -48.468537) (xy 306.892608 -48.482643) (xy 306.943937 -48.504455) (xy 306.991543 -48.533509)
			(xy 307.034411 -48.569184) (xy 307.071628 -48.610721) (xy 307.102401 -48.657234) (xy 307.126073 -48.707731)
			(xy 307.142141 -48.761138) (xy 307.150261 -48.816314) (xy 307.15077 -48.8442) (xy 307.150261 -48.872086)
			(xy 307.147263 -48.89246) (xy 307.413912 -48.89246) (xy 307.417983 -48.836838) (xy 307.430109 -48.782401)
			(xy 307.450032 -48.73031) (xy 307.477328 -48.681675) (xy 307.511414 -48.637532) (xy 307.551563 -48.598823)
			(xy 307.596921 -48.566372) (xy 307.646521 -48.540871) (xy 307.699305 -48.522864) (xy 307.754148 -48.512734)
			(xy 307.809882 -48.510697) (xy 307.865319 -48.516797) (xy 307.919276 -48.530903) (xy 307.970605 -48.552715)
			(xy 308.018211 -48.581769) (xy 308.061079 -48.617444) (xy 308.098296 -48.658981) (xy 308.129069 -48.705494)
			(xy 308.152741 -48.755991) (xy 308.168809 -48.809398) (xy 308.176929 -48.864574) (xy 308.177438 -48.89246)
			(xy 308.176929 -48.920346) (xy 308.174491 -48.93691) (xy 311.13298 -48.93691) (xy 311.137051 -48.881288)
			(xy 311.149177 -48.826851) (xy 311.1691 -48.77476) (xy 311.196396 -48.726125) (xy 311.230482 -48.681982)
			(xy 311.270631 -48.643273) (xy 311.315989 -48.610822) (xy 311.365589 -48.585321) (xy 311.418373 -48.567314)
			(xy 311.473216 -48.557184) (xy 311.52895 -48.555147) (xy 311.584387 -48.561247) (xy 311.638344 -48.575353)
			(xy 311.689673 -48.597165) (xy 311.737279 -48.626219) (xy 311.780147 -48.661894) (xy 311.817364 -48.703431)
			(xy 311.848137 -48.749944) (xy 311.871809 -48.800441) (xy 311.887877 -48.853848) (xy 311.895997 -48.909024)
			(xy 311.896506 -48.93691) (xy 311.895997 -48.964796) (xy 311.887877 -49.019972) (xy 311.871809 -49.073379)
			(xy 311.848137 -49.123876) (xy 311.817364 -49.170389) (xy 311.780147 -49.211926) (xy 311.737279 -49.247601)
			(xy 311.689673 -49.276655) (xy 311.638344 -49.298467) (xy 311.584387 -49.312573) (xy 311.52895 -49.318673)
			(xy 311.473216 -49.316636) (xy 311.418373 -49.306506) (xy 311.365589 -49.288499) (xy 311.315989 -49.262998)
			(xy 311.270631 -49.230547) (xy 311.230482 -49.191838) (xy 311.196396 -49.147695) (xy 311.1691 -49.09906)
			(xy 311.149177 -49.046969) (xy 311.137051 -48.992532) (xy 311.13298 -48.93691) (xy 308.174491 -48.93691)
			(xy 308.168809 -48.975522) (xy 308.152741 -49.028929) (xy 308.129069 -49.079426) (xy 308.098296 -49.125939)
			(xy 308.061079 -49.167476) (xy 308.018211 -49.203151) (xy 307.970605 -49.232205) (xy 307.919276 -49.254017)
			(xy 307.865319 -49.268123) (xy 307.809882 -49.274223) (xy 307.754148 -49.272186) (xy 307.699305 -49.262056)
			(xy 307.646521 -49.244049) (xy 307.596921 -49.218548) (xy 307.551563 -49.186097) (xy 307.511414 -49.147388)
			(xy 307.477328 -49.103245) (xy 307.450032 -49.05461) (xy 307.430109 -49.002519) (xy 307.417983 -48.948082)
			(xy 307.413912 -48.89246) (xy 307.147263 -48.89246) (xy 307.142141 -48.927262) (xy 307.126073 -48.980669)
			(xy 307.102401 -49.031166) (xy 307.071628 -49.077679) (xy 307.034411 -49.119216) (xy 306.991543 -49.154891)
			(xy 306.943937 -49.183945) (xy 306.892608 -49.205757) (xy 306.838651 -49.219863) (xy 306.783214 -49.225963)
			(xy 306.72748 -49.223926) (xy 306.672637 -49.213796) (xy 306.619853 -49.195789) (xy 306.570253 -49.170288)
			(xy 306.524895 -49.137837) (xy 306.484746 -49.099128) (xy 306.45066 -49.054985) (xy 306.423364 -49.00635)
			(xy 306.403441 -48.954259) (xy 306.391315 -48.899822) (xy 306.387244 -48.8442) (xy 306.120649 -48.8442)
			(xy 306.107025 -48.889483) (xy 306.083353 -48.93998) (xy 306.05258 -48.986493) (xy 306.015363 -49.02803)
			(xy 305.972495 -49.063705) (xy 305.924889 -49.092759) (xy 305.87356 -49.114571) (xy 305.819603 -49.128677)
			(xy 305.764166 -49.134777) (xy 305.708432 -49.13274) (xy 305.653589 -49.12261) (xy 305.600805 -49.104603)
			(xy 305.551205 -49.079102) (xy 305.505847 -49.046651) (xy 305.465698 -49.007942) (xy 305.431612 -48.963799)
			(xy 305.404316 -48.915164) (xy 305.384393 -48.863073) (xy 305.372267 -48.808636) (xy 305.368196 -48.753014)
			(xy 297.450787 -48.753014) (xy 297.721782 -49.526444) (xy 297.736396 -49.569763) (xy 297.758574 -49.658462)
			(xy 297.772548 -49.748818) (xy 297.775884 -49.794414) (xy 297.817269 -50.462434) (xy 307.026054 -50.462434)
			(xy 307.030125 -50.406812) (xy 307.042251 -50.352375) (xy 307.062174 -50.300284) (xy 307.08947 -50.251649)
			(xy 307.123556 -50.207506) (xy 307.163705 -50.168797) (xy 307.209063 -50.136346) (xy 307.258663 -50.110845)
			(xy 307.311447 -50.092838) (xy 307.36629 -50.082708) (xy 307.422024 -50.080671) (xy 307.477461 -50.086771)
			(xy 307.531418 -50.100877) (xy 307.582747 -50.122689) (xy 307.630353 -50.151743) (xy 307.673221 -50.187418)
			(xy 307.710438 -50.228955) (xy 307.741211 -50.275468) (xy 307.764883 -50.325965) (xy 307.780951 -50.379372)
			(xy 307.789071 -50.434548) (xy 307.78958 -50.462434) (xy 307.789071 -50.49032) (xy 307.780951 -50.545496)
			(xy 307.764883 -50.598903) (xy 307.741211 -50.6494) (xy 307.710438 -50.695913) (xy 307.673221 -50.73745)
			(xy 307.630353 -50.773125) (xy 307.582747 -50.802179) (xy 307.531418 -50.823991) (xy 307.477461 -50.838097)
			(xy 307.422024 -50.844197) (xy 307.36629 -50.84216) (xy 307.311447 -50.83203) (xy 307.258663 -50.814023)
			(xy 307.209063 -50.788522) (xy 307.163705 -50.756071) (xy 307.123556 -50.717362) (xy 307.08947 -50.673219)
			(xy 307.062174 -50.624584) (xy 307.042251 -50.572493) (xy 307.030125 -50.518056) (xy 307.026054 -50.462434)
			(xy 297.817269 -50.462434) (xy 297.851777 -51.019456) (xy 308.949342 -51.019456) (xy 308.953413 -50.963834)
			(xy 308.965539 -50.909397) (xy 308.985462 -50.857306) (xy 309.012758 -50.808671) (xy 309.046844 -50.764528)
			(xy 309.086993 -50.725819) (xy 309.132351 -50.693368) (xy 309.181951 -50.667867) (xy 309.234735 -50.64986)
			(xy 309.289578 -50.63973) (xy 309.345312 -50.637693) (xy 309.400749 -50.643793) (xy 309.454706 -50.657899)
			(xy 309.506035 -50.679711) (xy 309.553641 -50.708765) (xy 309.596509 -50.74444) (xy 309.633726 -50.785977)
			(xy 309.664499 -50.83249) (xy 309.688171 -50.882987) (xy 309.704239 -50.936394) (xy 309.712359 -50.99157)
			(xy 309.712868 -51.019456) (xy 309.712359 -51.047342) (xy 309.704239 -51.102518) (xy 309.688171 -51.155925)
			(xy 309.664499 -51.206422) (xy 309.633726 -51.252935) (xy 309.596509 -51.294472) (xy 309.553641 -51.330147)
			(xy 309.506035 -51.359201) (xy 309.454706 -51.381013) (xy 309.400749 -51.395119) (xy 309.345312 -51.401219)
			(xy 309.289578 -51.399182) (xy 309.234735 -51.389052) (xy 309.181951 -51.371045) (xy 309.132351 -51.345544)
			(xy 309.086993 -51.313093) (xy 309.046844 -51.274384) (xy 309.012758 -51.230241) (xy 308.985462 -51.181606)
			(xy 308.965539 -51.129515) (xy 308.953413 -51.075078) (xy 308.949342 -51.019456) (xy 297.851777 -51.019456)
			(xy 297.914719 -52.035456) (xy 311.141108 -52.035456) (xy 311.145179 -51.979834) (xy 311.157305 -51.925397)
			(xy 311.177228 -51.873306) (xy 311.204524 -51.824671) (xy 311.23861 -51.780528) (xy 311.278759 -51.741819)
			(xy 311.324117 -51.709368) (xy 311.373717 -51.683867) (xy 311.426501 -51.66586) (xy 311.481344 -51.65573)
			(xy 311.537078 -51.653693) (xy 311.592515 -51.659793) (xy 311.646472 -51.673899) (xy 311.697801 -51.695711)
			(xy 311.745407 -51.724765) (xy 311.788275 -51.76044) (xy 311.825492 -51.801977) (xy 311.856265 -51.84849)
			(xy 311.879937 -51.898987) (xy 311.896005 -51.952394) (xy 311.904125 -52.00757) (xy 311.904634 -52.035456)
			(xy 311.904125 -52.063342) (xy 311.896005 -52.118518) (xy 311.879937 -52.171925) (xy 311.856265 -52.222422)
			(xy 311.825492 -52.268935) (xy 311.788275 -52.310472) (xy 311.745407 -52.346147) (xy 311.697801 -52.375201)
			(xy 311.646472 -52.397013) (xy 311.592515 -52.411119) (xy 311.537078 -52.417219) (xy 311.481344 -52.415182)
			(xy 311.426501 -52.405052) (xy 311.373717 -52.387045) (xy 311.324117 -52.361544) (xy 311.278759 -52.329093)
			(xy 311.23861 -52.290384) (xy 311.204524 -52.246241) (xy 311.177228 -52.197606) (xy 311.157305 -52.145515)
			(xy 311.145179 -52.091078) (xy 311.141108 -52.035456) (xy 297.914719 -52.035456) (xy 297.935396 -52.369212)
			(xy 297.936509 -52.379842) (xy 297.946376 -52.39878) (xy 297.954446 -52.405788) (xy 297.997118 -52.439824)
			(xy 298.004583 -52.445287) (xy 298.022158 -52.451017) (xy 298.031408 -52.451) (xy 298.036234 -52.450492)
			(xy 298.036996 -52.450492) (xy 298.037504 -52.450238) (xy 298.037758 -52.450238) (xy 298.039028 -52.449984)
			(xy 298.054476 -52.447607) (xy 298.085629 -52.445066) (xy 298.101258 -52.444904) (xy 298.10202 -52.444904)
			(xy 298.12927 -52.445392) (xy 298.183215 -52.453151) (xy 298.235506 -52.468507) (xy 298.28508 -52.49115)
			(xy 298.330927 -52.520617) (xy 298.372114 -52.556309) (xy 298.407802 -52.597498) (xy 298.437265 -52.643348)
			(xy 298.459904 -52.692924) (xy 298.475256 -52.745216) (xy 298.483011 -52.799162) (xy 298.483528 -52.826412)
			(xy 298.483102 -52.851923) (xy 298.476306 -52.90249) (xy 298.462836 -52.951701) (xy 298.442931 -52.99868)
			(xy 298.416948 -53.04259) (xy 298.401486 -53.062886) (xy 298.398946 -53.065934) (xy 298.39793 -53.067458)
			(xy 298.394628 -53.074062) (xy 298.392283 -53.079284) (xy 298.389716 -53.090438) (xy 298.389548 -53.09616)
			(xy 298.389548 -53.128164) (xy 298.378372 -53.128164) (xy 298.378372 -53.178964) (xy 298.378708 -53.187567)
			(xy 298.384427 -53.203793) (xy 298.389548 -53.210714) (xy 298.390818 -53.212238) (xy 298.408212 -53.233114)
			(xy 298.437532 -53.278864) (xy 298.460061 -53.328312) (xy 298.475343 -53.380457) (xy 298.483068 -53.434243)
			(xy 298.483528 -53.461412) (xy 298.483102 -53.486923) (xy 298.476306 -53.53749) (xy 298.462836 -53.586701)
			(xy 298.442931 -53.63368) (xy 298.416948 -53.67759) (xy 298.401486 -53.697886) (xy 298.398946 -53.700934)
			(xy 298.39793 -53.702458) (xy 298.394628 -53.709062) (xy 298.392283 -53.714284) (xy 298.389716 -53.725438)
			(xy 298.389548 -53.73116) (xy 298.389548 -53.763164) (xy 298.378372 -53.763164) (xy 298.378372 -53.813964)
			(xy 298.378708 -53.822567) (xy 298.384427 -53.838793) (xy 298.389548 -53.845714) (xy 298.390818 -53.847238)
			(xy 298.408212 -53.868114) (xy 298.437532 -53.913864) (xy 298.460061 -53.963312) (xy 298.475343 -54.015457)
			(xy 298.483068 -54.069243) (xy 298.483528 -54.096412) (xy 298.483102 -54.121923) (xy 298.476306 -54.17249)
			(xy 298.462836 -54.221701) (xy 298.442931 -54.26868) (xy 298.416948 -54.31259) (xy 298.401486 -54.332886)
			(xy 298.398946 -54.335934) (xy 298.39793 -54.337458) (xy 298.394628 -54.344062) (xy 298.392283 -54.349284)
			(xy 298.389716 -54.360438) (xy 298.389548 -54.36616) (xy 298.389548 -54.398164) (xy 298.378372 -54.398164)
			(xy 298.378372 -54.448964) (xy 298.378708 -54.457567) (xy 298.384427 -54.473793) (xy 298.389548 -54.480714)
			(xy 298.390818 -54.482238) (xy 298.408212 -54.503114) (xy 298.437532 -54.548864) (xy 298.460061 -54.598312)
			(xy 298.475343 -54.650457) (xy 298.483068 -54.704243) (xy 298.483528 -54.731412) (xy 298.483051 -54.758856)
			(xy 298.478382 -54.791102) (xy 300.376336 -54.791102) (xy 300.376794 -54.763731) (xy 300.384613 -54.709552)
			(xy 300.400103 -54.657048) (xy 300.422947 -54.607301) (xy 300.452674 -54.561335) (xy 300.470316 -54.540404)
			(xy 300.47057 -54.54015) (xy 300.47615 -54.533059) (xy 300.482399 -54.516145) (xy 300.482762 -54.50713)
			(xy 300.482762 -54.440074) (xy 300.482426 -54.431055) (xy 300.476165 -54.414138) (xy 300.47057 -54.407054)
			(xy 300.470316 -54.407054) (xy 300.470316 -54.4068) (xy 300.452678 -54.385865) (xy 300.422954 -54.339898)
			(xy 300.400109 -54.290152) (xy 300.384613 -54.23765) (xy 300.376784 -54.183472) (xy 300.376784 -54.128731)
			(xy 300.384612 -54.074553) (xy 300.400108 -54.022051) (xy 300.422952 -53.972305) (xy 300.452676 -53.926337)
			(xy 300.470316 -53.905404) (xy 300.47057 -53.90515) (xy 300.47615 -53.898059) (xy 300.482399 -53.881145)
			(xy 300.482762 -53.87213) (xy 300.482762 -53.805074) (xy 300.482426 -53.796055) (xy 300.476165 -53.779138)
			(xy 300.47057 -53.772054) (xy 300.470316 -53.772054) (xy 300.470316 -53.7718) (xy 300.452678 -53.750865)
			(xy 300.422954 -53.704898) (xy 300.400109 -53.655152) (xy 300.384613 -53.60265) (xy 300.376784 -53.548472)
			(xy 300.376784 -53.493731) (xy 300.384612 -53.439553) (xy 300.400108 -53.387051) (xy 300.422952 -53.337305)
			(xy 300.452676 -53.291337) (xy 300.470316 -53.270404) (xy 300.47057 -53.27015) (xy 300.47615 -53.263059)
			(xy 300.482399 -53.246145) (xy 300.482762 -53.23713) (xy 300.482762 -53.170074) (xy 300.482426 -53.161055)
			(xy 300.476165 -53.144138) (xy 300.47057 -53.137054) (xy 300.470316 -53.137054) (xy 300.470316 -53.1368)
			(xy 300.452666 -53.115877) (xy 300.422955 -53.069902) (xy 300.400121 -53.020152) (xy 300.384633 -52.967649)
			(xy 300.376808 -52.913472) (xy 300.376336 -52.886102) (xy 300.376822 -52.858851) (xy 300.384578 -52.804903)
			(xy 300.399933 -52.752608) (xy 300.422575 -52.703031) (xy 300.452041 -52.657181) (xy 300.487732 -52.61599)
			(xy 300.528923 -52.580299) (xy 300.574773 -52.550833) (xy 300.62435 -52.528191) (xy 300.676645 -52.512836)
			(xy 300.730593 -52.50508) (xy 300.785095 -52.50508) (xy 300.839043 -52.512836) (xy 300.891338 -52.528191)
			(xy 300.930442 -52.54605) (xy 305.879496 -52.54605) (xy 305.879496 -52.49155) (xy 305.887252 -52.437605)
			(xy 305.902607 -52.385313) (xy 305.925247 -52.335738) (xy 305.954712 -52.28989) (xy 305.990401 -52.248701)
			(xy 306.03159 -52.213012) (xy 306.077438 -52.183547) (xy 306.127013 -52.160907) (xy 306.179305 -52.145552)
			(xy 306.23325 -52.137796) (xy 306.2605 -52.13731) (xy 306.28787 -52.137774) (xy 306.34205 -52.145592)
			(xy 306.394553 -52.161081) (xy 306.4443 -52.183924) (xy 306.490266 -52.213649) (xy 306.511198 -52.23129)
			(xy 306.511452 -52.231544) (xy 306.518544 -52.237122) (xy 306.535457 -52.243373) (xy 306.544472 -52.243736)
			(xy 306.611528 -52.243736) (xy 306.620545 -52.243385) (xy 306.637462 -52.237132) (xy 306.644548 -52.231544)
			(xy 306.644548 -52.23129) (xy 306.644802 -52.23129) (xy 306.665735 -52.213649) (xy 306.711703 -52.183925)
			(xy 306.761449 -52.161079) (xy 306.813951 -52.145583) (xy 306.868129 -52.137754) (xy 306.922871 -52.137754)
			(xy 306.977049 -52.145583) (xy 307.029551 -52.161079) (xy 307.079297 -52.183925) (xy 307.125265 -52.213649)
			(xy 307.146198 -52.23129) (xy 307.146452 -52.231544) (xy 307.153544 -52.237122) (xy 307.170457 -52.243373)
			(xy 307.179472 -52.243736) (xy 307.246528 -52.243736) (xy 307.255545 -52.243385) (xy 307.272462 -52.237132)
			(xy 307.279548 -52.231544) (xy 307.279548 -52.23129) (xy 307.279802 -52.23129) (xy 307.300721 -52.213635)
			(xy 307.346698 -52.183926) (xy 307.396448 -52.161093) (xy 307.448952 -52.145606) (xy 307.50313 -52.137782)
			(xy 307.5305 -52.13731) (xy 307.557753 -52.13776) (xy 307.611703 -52.145517) (xy 307.664 -52.160873)
			(xy 307.71358 -52.183515) (xy 307.759432 -52.212982) (xy 307.800624 -52.248676) (xy 307.836318 -52.289868)
			(xy 307.865785 -52.33572) (xy 307.888427 -52.3853) (xy 307.903783 -52.437597) (xy 307.91154 -52.491547)
			(xy 307.91154 -52.546053) (xy 307.905595 -52.587398) (xy 308.955184 -52.587398) (xy 308.959255 -52.531776)
			(xy 308.971381 -52.477339) (xy 308.991304 -52.425248) (xy 309.0186 -52.376613) (xy 309.052686 -52.33247)
			(xy 309.092835 -52.293761) (xy 309.138193 -52.26131) (xy 309.187793 -52.235809) (xy 309.240577 -52.217802)
			(xy 309.29542 -52.207672) (xy 309.351154 -52.205635) (xy 309.406591 -52.211735) (xy 309.460548 -52.225841)
			(xy 309.511877 -52.247653) (xy 309.559483 -52.276707) (xy 309.602351 -52.312382) (xy 309.639568 -52.353919)
			(xy 309.670341 -52.400432) (xy 309.694013 -52.450929) (xy 309.710081 -52.504336) (xy 309.717677 -52.555952)
			(xy 316.783679 -52.555952) (xy 316.783679 -52.501448) (xy 316.791436 -52.447499) (xy 316.806792 -52.395203)
			(xy 316.829435 -52.345624) (xy 316.858903 -52.299773) (xy 316.894597 -52.258582) (xy 316.935789 -52.222891)
			(xy 316.981642 -52.193425) (xy 317.031221 -52.170785) (xy 317.083518 -52.155432) (xy 317.137468 -52.147678)
			(xy 317.16472 -52.147216) (xy 317.192091 -52.147666) (xy 317.246271 -52.155487) (xy 317.298774 -52.17098)
			(xy 317.348521 -52.193825) (xy 317.394487 -52.223553) (xy 317.415418 -52.241196) (xy 317.415672 -52.24145)
			(xy 317.422758 -52.247037) (xy 317.439675 -52.253282) (xy 317.448692 -52.253642) (xy 317.515748 -52.253642)
			(xy 317.524764 -52.253273) (xy 317.541682 -52.247035) (xy 317.548768 -52.24145) (xy 317.548768 -52.241196)
			(xy 317.549022 -52.241196) (xy 317.569972 -52.223579) (xy 317.61594 -52.193864) (xy 317.665683 -52.171024)
			(xy 317.71818 -52.155528) (xy 317.772352 -52.147693) (xy 317.79972 -52.147216) (xy 317.826972 -52.147655)
			(xy 317.880921 -52.155415) (xy 317.933217 -52.170772) (xy 317.982794 -52.193416) (xy 318.028645 -52.222885)
			(xy 318.069836 -52.258579) (xy 318.105527 -52.299771) (xy 318.134994 -52.345623) (xy 318.157635 -52.395202)
			(xy 318.17299 -52.447499) (xy 318.180746 -52.501448) (xy 318.180746 -52.555952) (xy 318.17299 -52.609901)
			(xy 318.157635 -52.662198) (xy 318.134994 -52.711777) (xy 318.105527 -52.757629) (xy 318.069836 -52.798821)
			(xy 318.028645 -52.834515) (xy 317.982794 -52.863984) (xy 317.933217 -52.886628) (xy 317.880921 -52.901985)
			(xy 317.826972 -52.909745) (xy 317.79972 -52.910232) (xy 317.772349 -52.909771) (xy 317.718169 -52.901954)
			(xy 317.665666 -52.886465) (xy 317.615919 -52.863622) (xy 317.569953 -52.833895) (xy 317.549022 -52.816252)
			(xy 317.548768 -52.815998) (xy 317.541666 -52.810434) (xy 317.524761 -52.804174) (xy 317.515748 -52.803806)
			(xy 317.448692 -52.803806) (xy 317.439675 -52.804158) (xy 317.422758 -52.810409) (xy 317.415672 -52.815998)
			(xy 317.415672 -52.816252) (xy 317.415418 -52.816252) (xy 317.394484 -52.833889) (xy 317.348512 -52.863603)
			(xy 317.298765 -52.88644) (xy 317.246265 -52.901931) (xy 317.192089 -52.909759) (xy 317.16472 -52.910232)
			(xy 317.137468 -52.909722) (xy 317.083518 -52.901968) (xy 317.031221 -52.886615) (xy 316.981642 -52.863975)
			(xy 316.935789 -52.834509) (xy 316.894597 -52.798818) (xy 316.858903 -52.757627) (xy 316.829435 -52.711776)
			(xy 316.806792 -52.662197) (xy 316.791436 -52.609901) (xy 316.783679 -52.555952) (xy 309.717677 -52.555952)
			(xy 309.718201 -52.559512) (xy 309.71871 -52.587398) (xy 309.718201 -52.615284) (xy 309.710081 -52.67046)
			(xy 309.694013 -52.723867) (xy 309.670341 -52.774364) (xy 309.639568 -52.820877) (xy 309.602351 -52.862414)
			(xy 309.559483 -52.898089) (xy 309.511877 -52.927143) (xy 309.460548 -52.948955) (xy 309.406591 -52.963061)
			(xy 309.351154 -52.969161) (xy 309.29542 -52.967124) (xy 309.240577 -52.956994) (xy 309.187793 -52.938987)
			(xy 309.138193 -52.913486) (xy 309.092835 -52.881035) (xy 309.052686 -52.842326) (xy 309.0186 -52.798183)
			(xy 308.991304 -52.749548) (xy 308.971381 -52.697457) (xy 308.959255 -52.64302) (xy 308.955184 -52.587398)
			(xy 307.905595 -52.587398) (xy 307.903783 -52.600003) (xy 307.888427 -52.6523) (xy 307.865785 -52.70188)
			(xy 307.836318 -52.747732) (xy 307.800624 -52.788924) (xy 307.759432 -52.824618) (xy 307.71358 -52.854085)
			(xy 307.664 -52.876727) (xy 307.611703 -52.892083) (xy 307.557753 -52.89984) (xy 307.5305 -52.900326)
			(xy 307.503129 -52.899878) (xy 307.448948 -52.892059) (xy 307.396444 -52.876566) (xy 307.346698 -52.85372)
			(xy 307.300732 -52.82399) (xy 307.279802 -52.806346) (xy 307.279548 -52.806092) (xy 307.272453 -52.800518)
			(xy 307.255543 -52.794264) (xy 307.246528 -52.7939) (xy 307.179472 -52.7939) (xy 307.170454 -52.794244)
			(xy 307.153537 -52.800501) (xy 307.146452 -52.806092) (xy 307.146198 -52.806346) (xy 307.125265 -52.823987)
			(xy 307.079297 -52.853711) (xy 307.029551 -52.876557) (xy 306.977049 -52.892053) (xy 306.922871 -52.899882)
			(xy 306.868129 -52.899882) (xy 306.813951 -52.892053) (xy 306.761449 -52.876557) (xy 306.711703 -52.853711)
			(xy 306.665735 -52.823987) (xy 306.644802 -52.806346) (xy 306.644548 -52.806092) (xy 306.637453 -52.800518)
			(xy 306.620543 -52.794264) (xy 306.611528 -52.7939) (xy 306.544472 -52.7939) (xy 306.535454 -52.794244)
			(xy 306.518537 -52.800501) (xy 306.511452 -52.806092) (xy 306.511452 -52.806346) (xy 306.511198 -52.806346)
			(xy 306.490271 -52.823991) (xy 306.444297 -52.853704) (xy 306.394549 -52.87654) (xy 306.342047 -52.892029)
			(xy 306.28787 -52.899854) (xy 306.2605 -52.900326) (xy 306.23325 -52.899804) (xy 306.179305 -52.892048)
			(xy 306.127013 -52.876693) (xy 306.077438 -52.854053) (xy 306.03159 -52.824588) (xy 305.990401 -52.788899)
			(xy 305.954712 -52.74771) (xy 305.925247 -52.701862) (xy 305.902607 -52.652287) (xy 305.887252 -52.599995)
			(xy 305.879496 -52.54605) (xy 300.930442 -52.54605) (xy 300.940915 -52.550833) (xy 300.986765 -52.580299)
			(xy 301.027956 -52.61599) (xy 301.063647 -52.657181) (xy 301.093113 -52.703031) (xy 301.115755 -52.752608)
			(xy 301.13111 -52.804903) (xy 301.138866 -52.858851) (xy 301.139352 -52.886102) (xy 301.138899 -52.913473)
			(xy 301.13108 -52.967653) (xy 301.115588 -53.020157) (xy 301.092743 -53.069903) (xy 301.063015 -53.115869)
			(xy 301.045372 -53.1368) (xy 301.045118 -53.137054) (xy 301.039547 -53.144151) (xy 301.033291 -53.16106)
			(xy 301.032926 -53.170074) (xy 301.032926 -53.23713) (xy 301.033263 -53.246149) (xy 301.039524 -53.263066)
			(xy 301.045118 -53.27015) (xy 301.045372 -53.27015) (xy 301.045372 -53.270404) (xy 301.063015 -53.291335)
			(xy 301.092739 -53.337303) (xy 301.115585 -53.38705) (xy 301.131081 -53.439552) (xy 301.138909 -53.493731)
			(xy 301.138909 -53.548472) (xy 301.13108 -53.602651) (xy 301.115584 -53.655153) (xy 301.092738 -53.704899)
			(xy 301.063013 -53.750867) (xy 301.046442 -53.77053) (xy 301.410624 -53.77053) (xy 301.411155 -53.741613)
			(xy 301.41988 -53.684442) (xy 301.437135 -53.629243) (xy 301.462524 -53.577282) (xy 301.495466 -53.529747)
			(xy 301.535205 -53.48773) (xy 301.55769 -53.46954) (xy 301.566468 -53.461904) (xy 301.576668 -53.441025)
			(xy 301.577248 -53.429408) (xy 301.577248 -53.349652) (xy 301.57674 -53.338016) (xy 301.566531 -53.317105)
			(xy 301.55769 -53.30952) (xy 301.535214 -53.29132) (xy 301.495479 -53.249302) (xy 301.462539 -53.201769)
			(xy 301.43715 -53.149809) (xy 301.419892 -53.094613) (xy 301.41116 -53.037445) (xy 301.410624 -53.00853)
			(xy 301.411083 -52.981276) (xy 301.418837 -52.927324) (xy 301.434191 -52.875024) (xy 301.456832 -52.825442)
			(xy 301.4863 -52.779587) (xy 301.521994 -52.738393) (xy 301.563188 -52.702699) (xy 301.609043 -52.673231)
			(xy 301.658626 -52.65059) (xy 301.710926 -52.635237) (xy 301.764878 -52.627483) (xy 301.792132 -52.627022)
			(xy 301.818447 -52.627461) (xy 301.870577 -52.634701) (xy 301.921221 -52.649025) (xy 301.96942 -52.670163)
			(xy 302.014262 -52.697714) (xy 302.0549 -52.731158) (xy 302.073056 -52.750212) (xy 302.08059 -52.757598)
			(xy 302.099861 -52.766131) (xy 302.110394 -52.766722) (xy 302.18507 -52.766722) (xy 302.195618 -52.766183)
			(xy 302.214913 -52.757654) (xy 302.222408 -52.750212) (xy 302.240569 -52.731162) (xy 302.281197 -52.697704)
			(xy 302.326036 -52.670144) (xy 302.374236 -52.649004) (xy 302.424883 -52.634686) (xy 302.477016 -52.627461)
			(xy 302.503332 -52.627022) (xy 302.530585 -52.627448) (xy 302.584537 -52.63521) (xy 302.636835 -52.65057)
			(xy 302.686414 -52.673218) (xy 302.732266 -52.70269) (xy 302.773456 -52.738388) (xy 302.809147 -52.779584)
			(xy 302.838612 -52.825441) (xy 302.861251 -52.875024) (xy 302.876603 -52.927324) (xy 302.884356 -52.981277)
			(xy 302.88484 -53.00853) (xy 302.884379 -53.036197) (xy 302.882148 -53.051456) (xy 311.141108 -53.051456)
			(xy 311.145179 -52.995834) (xy 311.157305 -52.941397) (xy 311.177228 -52.889306) (xy 311.204524 -52.840671)
			(xy 311.23861 -52.796528) (xy 311.278759 -52.757819) (xy 311.324117 -52.725368) (xy 311.373717 -52.699867)
			(xy 311.426501 -52.68186) (xy 311.481344 -52.67173) (xy 311.537078 -52.669693) (xy 311.592515 -52.675793)
			(xy 311.646472 -52.689899) (xy 311.697801 -52.711711) (xy 311.745407 -52.740765) (xy 311.788275 -52.77644)
			(xy 311.825492 -52.817977) (xy 311.856265 -52.86449) (xy 311.879937 -52.914987) (xy 311.896005 -52.968394)
			(xy 311.904125 -53.02357) (xy 311.904634 -53.051456) (xy 311.904125 -53.079342) (xy 311.896005 -53.134518)
			(xy 311.879937 -53.187925) (xy 311.856265 -53.238422) (xy 311.825492 -53.284935) (xy 311.788275 -53.326472)
			(xy 311.745407 -53.362147) (xy 311.697801 -53.391201) (xy 311.646472 -53.413013) (xy 311.592515 -53.427119)
			(xy 311.537078 -53.433219) (xy 311.481344 -53.431182) (xy 311.426501 -53.421052) (xy 311.373717 -53.403045)
			(xy 311.324117 -53.377544) (xy 311.278759 -53.345093) (xy 311.23861 -53.306384) (xy 311.204524 -53.262241)
			(xy 311.177228 -53.213606) (xy 311.157305 -53.161515) (xy 311.145179 -53.107078) (xy 311.141108 -53.051456)
			(xy 302.882148 -53.051456) (xy 302.876374 -53.09095) (xy 302.86055 -53.143974) (xy 302.83724 -53.194159)
			(xy 302.80693 -53.240454) (xy 302.770256 -53.28189) (xy 302.727985 -53.317599) (xy 302.704754 -53.332634)
			(xy 302.695064 -53.339255) (xy 302.682626 -53.359128) (xy 302.680878 -53.370734) (xy 302.673004 -53.450744)
			(xy 302.672366 -53.462382) (xy 302.680452 -53.484219) (xy 302.688498 -53.492654) (xy 302.688752 -53.492908)
			(xy 302.70731 -53.511012) (xy 302.739893 -53.551338) (xy 302.76671 -53.595707) (xy 302.787267 -53.643301)
			(xy 302.801185 -53.693242) (xy 302.808206 -53.744608) (xy 302.80864 -53.77053) (xy 302.80815 -53.797781)
			(xy 302.80039 -53.851726) (xy 302.785033 -53.904019) (xy 302.762391 -53.953594) (xy 302.732924 -53.999443)
			(xy 302.697234 -54.040632) (xy 302.656045 -54.076323) (xy 302.610196 -54.10579) (xy 302.560621 -54.128432)
			(xy 302.508328 -54.14379) (xy 302.454383 -54.15155) (xy 302.427132 -54.152038) (xy 302.399762 -54.151568)
			(xy 302.345582 -54.143754) (xy 302.293079 -54.128266) (xy 302.243332 -54.105425) (xy 302.197365 -54.0757)
			(xy 302.176434 -54.058058) (xy 302.17618 -54.057804) (xy 302.169103 -54.052203) (xy 302.152179 -54.045965)
			(xy 302.14316 -54.045612) (xy 302.076104 -54.045612) (xy 302.067087 -54.045968) (xy 302.05017 -54.052216)
			(xy 302.043084 -54.057804) (xy 302.043084 -54.058058) (xy 302.04283 -54.058058) (xy 302.021892 -54.07569)
			(xy 301.975922 -54.105404) (xy 301.926176 -54.128242) (xy 301.873676 -54.143735) (xy 301.819501 -54.151564)
			(xy 301.792132 -54.152038) (xy 301.764881 -54.151515) (xy 301.710934 -54.143763) (xy 301.658639 -54.128413)
			(xy 301.609061 -54.105776) (xy 301.563209 -54.076314) (xy 301.522017 -54.040627) (xy 301.486323 -53.99944)
			(xy 301.456854 -53.953593) (xy 301.434209 -53.904019) (xy 301.41885 -53.851727) (xy 301.411089 -53.797781)
			(xy 301.410624 -53.77053) (xy 301.046442 -53.77053) (xy 301.045372 -53.7718) (xy 301.045118 -53.772054)
			(xy 301.039547 -53.779151) (xy 301.033291 -53.79606) (xy 301.032926 -53.805074) (xy 301.032926 -53.87213)
			(xy 301.033263 -53.881149) (xy 301.039524 -53.898066) (xy 301.045118 -53.90515) (xy 301.045372 -53.90515)
			(xy 301.045372 -53.905404) (xy 301.063015 -53.926335) (xy 301.092739 -53.972303) (xy 301.115585 -54.02205)
			(xy 301.131081 -54.074552) (xy 301.138909 -54.128731) (xy 301.138909 -54.183472) (xy 301.13108 -54.237651)
			(xy 301.115584 -54.290153) (xy 301.101791 -54.320186) (xy 303.330356 -54.320186) (xy 303.3308 -54.292815)
			(xy 303.338621 -54.238634) (xy 303.354115 -54.18613) (xy 303.376962 -54.136384) (xy 303.406692 -54.090418)
			(xy 303.424336 -54.069488) (xy 303.42459 -54.069234) (xy 303.430167 -54.062141) (xy 303.43642 -54.045229)
			(xy 303.436782 -54.036214) (xy 303.436782 -53.969158) (xy 303.436401 -53.960143) (xy 303.43017 -53.943226)
			(xy 303.42459 -53.936138) (xy 303.424336 -53.936138) (xy 303.424336 -53.935884) (xy 303.406728 -53.914926)
			(xy 303.377011 -53.868961) (xy 303.354168 -53.81922) (xy 303.33867 -53.766725) (xy 303.330834 -53.712554)
			(xy 303.330356 -53.685186) (xy 303.330842 -53.657935) (xy 303.338598 -53.603987) (xy 303.353953 -53.551692)
			(xy 303.376595 -53.502115) (xy 303.406061 -53.456265) (xy 303.441752 -53.415074) (xy 303.482943 -53.379383)
			(xy 303.528793 -53.349917) (xy 303.57837 -53.327275) (xy 303.630665 -53.31192) (xy 303.684613 -53.304164)
			(xy 303.739115 -53.304164) (xy 303.793063 -53.31192) (xy 303.845358 -53.327275) (xy 303.894935 -53.349917)
			(xy 303.940785 -53.379383) (xy 303.981976 -53.415074) (xy 304.017667 -53.456265) (xy 304.043557 -53.496551)
			(xy 316.333364 -53.496551) (xy 316.333364 -53.442049) (xy 316.34112 -53.388101) (xy 316.356475 -53.335806)
			(xy 316.379115 -53.286228) (xy 316.40858 -53.240377) (xy 316.444271 -53.199186) (xy 316.48546 -53.163493)
			(xy 316.531309 -53.134025) (xy 316.580885 -53.111382) (xy 316.633179 -53.096025) (xy 316.687127 -53.088265)
			(xy 316.714378 -53.087778) (xy 316.741749 -53.088238) (xy 316.795929 -53.096054) (xy 316.848433 -53.111544)
			(xy 316.89818 -53.134387) (xy 316.944145 -53.164115) (xy 316.965076 -53.181758) (xy 316.96533 -53.182012)
			(xy 316.972431 -53.187577) (xy 316.989337 -53.193836) (xy 316.99835 -53.194204) (xy 317.065406 -53.194204)
			(xy 317.074423 -53.193849) (xy 317.09134 -53.1876) (xy 317.098426 -53.182012) (xy 317.098426 -53.181758)
			(xy 317.09868 -53.181758) (xy 317.119603 -53.164108) (xy 317.165579 -53.134399) (xy 317.215329 -53.111566)
			(xy 317.267831 -53.096077) (xy 317.322008 -53.088251) (xy 317.349378 -53.087778) (xy 317.376631 -53.088268)
			(xy 317.430582 -53.096022) (xy 317.482881 -53.111376) (xy 317.532462 -53.134016) (xy 317.578316 -53.163482)
			(xy 317.61951 -53.199175) (xy 317.655205 -53.240366) (xy 317.684674 -53.286219) (xy 317.707317 -53.335799)
			(xy 317.722673 -53.388096) (xy 317.730431 -53.442047) (xy 317.730431 -53.496553) (xy 317.722673 -53.550504)
			(xy 317.707317 -53.602801) (xy 317.684674 -53.652381) (xy 317.655205 -53.698234) (xy 317.61951 -53.739425)
			(xy 317.578316 -53.775118) (xy 317.532462 -53.804584) (xy 317.482881 -53.827224) (xy 317.430582 -53.842578)
			(xy 317.376631 -53.850332) (xy 317.349378 -53.850794) (xy 317.322007 -53.850342) (xy 317.267827 -53.842521)
			(xy 317.215324 -53.827029) (xy 317.165578 -53.804184) (xy 317.119611 -53.774457) (xy 317.09868 -53.756814)
			(xy 317.098426 -53.75656) (xy 317.09134 -53.750973) (xy 317.074423 -53.744728) (xy 317.065406 -53.744368)
			(xy 316.99835 -53.744368) (xy 316.989336 -53.744756) (xy 316.97242 -53.750983) (xy 316.96533 -53.75656)
			(xy 316.96533 -53.756814) (xy 316.965076 -53.756814) (xy 316.944128 -53.774433) (xy 316.898159 -53.804147)
			(xy 316.848416 -53.826987) (xy 316.795919 -53.842483) (xy 316.741746 -53.850317) (xy 316.714378 -53.850794)
			(xy 316.687127 -53.850335) (xy 316.633179 -53.842575) (xy 316.580885 -53.827218) (xy 316.531309 -53.804575)
			(xy 316.48546 -53.775107) (xy 316.444271 -53.739414) (xy 316.40858 -53.698223) (xy 316.379115 -53.652372)
			(xy 316.356475 -53.602794) (xy 316.34112 -53.550499) (xy 316.333364 -53.496551) (xy 304.043557 -53.496551)
			(xy 304.047133 -53.502115) (xy 304.069775 -53.551692) (xy 304.08513 -53.603987) (xy 304.092886 -53.657935)
			(xy 304.093372 -53.685186) (xy 304.092905 -53.712556) (xy 304.085088 -53.766736) (xy 304.0696 -53.819239)
			(xy 304.046758 -53.868986) (xy 304.017033 -53.914952) (xy 303.999392 -53.935884) (xy 303.999138 -53.936138)
			(xy 303.993564 -53.943233) (xy 303.987311 -53.960144) (xy 303.986946 -53.969158) (xy 303.986946 -54.036214)
			(xy 303.987286 -54.045233) (xy 303.993544 -54.06215) (xy 303.999138 -54.069234) (xy 303.999392 -54.069234)
			(xy 303.999392 -54.069488) (xy 304.017038 -54.090415) (xy 304.046749 -54.136389) (xy 304.069584 -54.186138)
			(xy 304.085073 -54.23864) (xy 304.092899 -54.292816) (xy 304.093372 -54.320186) (xy 304.092886 -54.347437)
			(xy 304.08513 -54.401385) (xy 304.069775 -54.45368) (xy 304.047133 -54.503257) (xy 304.017667 -54.549107)
			(xy 303.981976 -54.590298) (xy 303.940785 -54.625989) (xy 303.894935 -54.655455) (xy 303.845358 -54.678097)
			(xy 303.793063 -54.693452) (xy 303.739115 -54.701208) (xy 303.684613 -54.701208) (xy 303.630665 -54.693452)
			(xy 303.57837 -54.678097) (xy 303.528793 -54.655455) (xy 303.482943 -54.625989) (xy 303.441752 -54.590298)
			(xy 303.406061 -54.549107) (xy 303.376595 -54.503257) (xy 303.353953 -54.45368) (xy 303.338598 -54.401385)
			(xy 303.330842 -54.347437) (xy 303.330356 -54.320186) (xy 301.101791 -54.320186) (xy 301.092738 -54.339899)
			(xy 301.063013 -54.385867) (xy 301.045372 -54.4068) (xy 301.045118 -54.407054) (xy 301.039547 -54.414151)
			(xy 301.033291 -54.43106) (xy 301.032926 -54.440074) (xy 301.032926 -54.50713) (xy 301.033263 -54.516149)
			(xy 301.039524 -54.533066) (xy 301.045118 -54.54015) (xy 301.045372 -54.54015) (xy 301.045372 -54.540404)
			(xy 301.063022 -54.561327) (xy 301.092733 -54.607302) (xy 301.115567 -54.657052) (xy 301.131056 -54.709555)
			(xy 301.13888 -54.763732) (xy 301.138997 -54.770528) (xy 304.270918 -54.770528) (xy 304.271396 -54.743158)
			(xy 304.27921 -54.688979) (xy 304.294696 -54.636476) (xy 304.317536 -54.586729) (xy 304.347258 -54.540762)
			(xy 304.364898 -54.51983) (xy 304.365152 -54.519576) (xy 304.370761 -54.512505) (xy 304.376993 -54.495576)
			(xy 304.377344 -54.486556) (xy 304.377344 -54.4195) (xy 304.376999 -54.410482) (xy 304.370744 -54.393564)
			(xy 304.365152 -54.38648) (xy 304.364898 -54.38648) (xy 304.364898 -54.386226) (xy 304.347257 -54.365295)
			(xy 304.317546 -54.319322) (xy 304.29471 -54.269574) (xy 304.279219 -54.217073) (xy 304.271392 -54.162897)
			(xy 304.270918 -54.135528) (xy 304.271404 -54.108277) (xy 304.27916 -54.054329) (xy 304.294515 -54.002034)
			(xy 304.317157 -53.952457) (xy 304.346623 -53.906607) (xy 304.382314 -53.865416) (xy 304.423505 -53.829725)
			(xy 304.469355 -53.800259) (xy 304.518932 -53.777617) (xy 304.571227 -53.762262) (xy 304.625175 -53.754506)
			(xy 304.679677 -53.754506) (xy 304.733625 -53.762262) (xy 304.78592 -53.777617) (xy 304.835497 -53.800259)
			(xy 304.881347 -53.829725) (xy 304.922538 -53.865416) (xy 304.958229 -53.906607) (xy 304.987695 -53.952457)
			(xy 304.99277 -53.96357) (xy 308.971948 -53.96357) (xy 308.976019 -53.907948) (xy 308.988145 -53.853511)
			(xy 309.008068 -53.80142) (xy 309.035364 -53.752785) (xy 309.06945 -53.708642) (xy 309.109599 -53.669933)
			(xy 309.154957 -53.637482) (xy 309.204557 -53.611981) (xy 309.257341 -53.593974) (xy 309.312184 -53.583844)
			(xy 309.367918 -53.581807) (xy 309.423355 -53.587907) (xy 309.477312 -53.602013) (xy 309.528641 -53.623825)
			(xy 309.576247 -53.652879) (xy 309.619115 -53.688554) (xy 309.656332 -53.730091) (xy 309.687105 -53.776604)
			(xy 309.710777 -53.827101) (xy 309.726845 -53.880508) (xy 309.734965 -53.935684) (xy 309.735474 -53.96357)
			(xy 309.734965 -53.991456) (xy 309.726845 -54.046632) (xy 309.710777 -54.100039) (xy 309.687105 -54.150536)
			(xy 309.656332 -54.197049) (xy 309.619115 -54.238586) (xy 309.576247 -54.274261) (xy 309.528641 -54.303315)
			(xy 309.477312 -54.325127) (xy 309.423355 -54.339233) (xy 309.367918 -54.345333) (xy 309.312184 -54.343296)
			(xy 309.257341 -54.333166) (xy 309.204557 -54.315159) (xy 309.154957 -54.289658) (xy 309.109599 -54.257207)
			(xy 309.06945 -54.218498) (xy 309.035364 -54.174355) (xy 309.008068 -54.12572) (xy 308.988145 -54.073629)
			(xy 308.976019 -54.019192) (xy 308.971948 -53.96357) (xy 304.99277 -53.96357) (xy 305.010337 -54.002034)
			(xy 305.025692 -54.054329) (xy 305.033448 -54.108277) (xy 305.033934 -54.135528) (xy 305.0335 -54.1629)
			(xy 305.025677 -54.217081) (xy 305.010181 -54.269585) (xy 304.987332 -54.319331) (xy 304.957599 -54.365296)
			(xy 304.939954 -54.386226) (xy 304.9397 -54.38648) (xy 304.934116 -54.393568) (xy 304.927868 -54.410484)
			(xy 304.927508 -54.4195) (xy 304.927508 -54.486556) (xy 304.927885 -54.495571) (xy 304.934119 -54.512488)
			(xy 304.9397 -54.519576) (xy 304.939954 -54.519576) (xy 304.939954 -54.51983) (xy 304.957567 -54.540784)
			(xy 304.987284 -54.58675) (xy 305.010126 -54.636492) (xy 305.025623 -54.688988) (xy 305.033457 -54.74316)
			(xy 305.033934 -54.770528) (xy 305.033448 -54.797779) (xy 305.025692 -54.851727) (xy 305.010337 -54.904022)
			(xy 304.987695 -54.953599) (xy 304.964911 -54.989051) (xy 314.100968 -54.989051) (xy 314.100968 -54.934549)
			(xy 314.108724 -54.880603) (xy 314.124078 -54.828309) (xy 314.146718 -54.778732) (xy 314.176182 -54.732882)
			(xy 314.211871 -54.691691) (xy 314.253059 -54.655999) (xy 314.298907 -54.626531) (xy 314.348482 -54.603888)
			(xy 314.400775 -54.58853) (xy 314.454721 -54.58077) (xy 314.481972 -54.580282) (xy 314.510063 -54.580799)
			(xy 314.565639 -54.589022) (xy 314.619407 -54.605309) (xy 314.670205 -54.629308) (xy 314.716932 -54.6605)
			(xy 314.758578 -54.698209) (xy 314.794241 -54.741619) (xy 314.809124 -54.765448) (xy 314.814458 -54.774338)
			(xy 314.831476 -54.78653) (xy 314.924694 -54.80685) (xy 314.945268 -54.802532) (xy 314.953904 -54.79669)
			(xy 314.977965 -54.780685) (xy 315.029897 -54.755344) (xy 315.085056 -54.738119) (xy 315.142181 -54.729406)
			(xy 315.171074 -54.728872) (xy 315.198325 -54.729379) (xy 315.252274 -54.737132) (xy 315.304569 -54.752484)
			(xy 315.354148 -54.775122) (xy 315.4 -54.804586) (xy 315.441193 -54.840275) (xy 315.476887 -54.881463)
			(xy 315.506356 -54.927311) (xy 315.529 -54.976887) (xy 315.544358 -55.029181) (xy 315.552117 -55.083129)
			(xy 315.552582 -55.11038) (xy 315.552109 -55.13775) (xy 315.544293 -55.191929) (xy 315.528806 -55.244432)
			(xy 315.505966 -55.294179) (xy 315.476243 -55.340146) (xy 315.458602 -55.361078) (xy 315.458348 -55.361332)
			(xy 315.452778 -55.368429) (xy 315.446522 -55.385338) (xy 315.446156 -55.394352) (xy 315.446156 -55.461408)
			(xy 315.446497 -55.470427) (xy 315.452755 -55.487344) (xy 315.458348 -55.494428) (xy 315.458602 -55.494428)
			(xy 315.458602 -55.494682) (xy 315.476222 -55.515631) (xy 315.505945 -55.561597) (xy 315.52879 -55.611341)
			(xy 315.544287 -55.66384) (xy 315.552116 -55.718016) (xy 315.552119 -55.772754) (xy 315.544293 -55.826931)
			(xy 315.528801 -55.879431) (xy 315.50596 -55.929177) (xy 315.47624 -55.975145) (xy 315.458602 -55.996078)
			(xy 315.458348 -55.996332) (xy 315.452778 -56.003429) (xy 315.446522 -56.020338) (xy 315.446156 -56.029352)
			(xy 315.446156 -56.096408) (xy 315.446497 -56.105427) (xy 315.452755 -56.122344) (xy 315.458348 -56.129428)
			(xy 315.458602 -56.129428) (xy 315.458602 -56.129682) (xy 315.476246 -56.15061) (xy 315.505957 -56.196584)
			(xy 315.528792 -56.246332) (xy 315.544282 -56.298834) (xy 315.552109 -56.353011) (xy 315.552582 -56.38038)
			(xy 315.552096 -56.407631) (xy 315.54434 -56.461579) (xy 315.528985 -56.513874) (xy 315.506343 -56.563451)
			(xy 315.476877 -56.609301) (xy 315.441186 -56.650492) (xy 315.399995 -56.686183) (xy 315.354145 -56.715649)
			(xy 315.304568 -56.738291) (xy 315.252273 -56.753646) (xy 315.198325 -56.761402) (xy 315.143823 -56.761402)
			(xy 315.089875 -56.753646) (xy 315.03758 -56.738291) (xy 314.988003 -56.715649) (xy 314.942153 -56.686183)
			(xy 314.900962 -56.650492) (xy 314.865271 -56.609301) (xy 314.835805 -56.563451) (xy 314.813163 -56.513874)
			(xy 314.797808 -56.461579) (xy 314.790052 -56.407631) (xy 314.789566 -56.38038) (xy 314.790004 -56.353009)
			(xy 314.797826 -56.298828) (xy 314.813321 -56.246324) (xy 314.836169 -56.196577) (xy 314.865901 -56.150612)
			(xy 314.883546 -56.129682) (xy 314.8838 -56.129428) (xy 314.889381 -56.122338) (xy 314.895631 -56.105424)
			(xy 314.895992 -56.096408) (xy 314.895992 -56.029352) (xy 314.895612 -56.020337) (xy 314.88938 -56.00342)
			(xy 314.8838 -55.996332) (xy 314.883546 -55.996332) (xy 314.883546 -55.996078) (xy 314.865885 -55.975162)
			(xy 314.836159 -55.929191) (xy 314.813314 -55.879443) (xy 314.797819 -55.826938) (xy 314.789991 -55.772757)
			(xy 314.789994 -55.718013) (xy 314.797825 -55.663833) (xy 314.813325 -55.611329) (xy 314.836174 -55.561582)
			(xy 314.865903 -55.515614) (xy 314.883546 -55.494682) (xy 314.8838 -55.494428) (xy 314.889381 -55.487338)
			(xy 314.895631 -55.470424) (xy 314.895992 -55.461408) (xy 314.895992 -55.394352) (xy 314.895612 -55.385337)
			(xy 314.88938 -55.36842) (xy 314.8838 -55.361332) (xy 314.883546 -55.360824) (xy 314.872599 -55.348092)
			(xy 314.85276 -55.320999) (xy 314.843922 -55.306722) (xy 314.838588 -55.297832) (xy 314.82157 -55.28564)
			(xy 314.728352 -55.26532) (xy 314.707778 -55.269638) (xy 314.699142 -55.27548) (xy 314.675067 -55.291462)
			(xy 314.62314 -55.316809) (xy 314.567985 -55.33404) (xy 314.510864 -55.342761) (xy 314.481972 -55.343298)
			(xy 314.454721 -55.34283) (xy 314.400775 -55.33507) (xy 314.348482 -55.319712) (xy 314.298907 -55.297069)
			(xy 314.253059 -55.267601) (xy 314.211871 -55.231909) (xy 314.176182 -55.190718) (xy 314.146718 -55.144868)
			(xy 314.124078 -55.095291) (xy 314.108724 -55.042997) (xy 314.100968 -54.989051) (xy 304.964911 -54.989051)
			(xy 304.958229 -54.999449) (xy 304.922538 -55.04064) (xy 304.881347 -55.076331) (xy 304.835497 -55.105797)
			(xy 304.78592 -55.128439) (xy 304.733625 -55.143794) (xy 304.679677 -55.15155) (xy 304.625175 -55.15155)
			(xy 304.571227 -55.143794) (xy 304.518932 -55.128439) (xy 304.469355 -55.105797) (xy 304.423505 -55.076331)
			(xy 304.382314 -55.04064) (xy 304.346623 -54.999449) (xy 304.317157 -54.953599) (xy 304.294515 -54.904022)
			(xy 304.27916 -54.851727) (xy 304.271404 -54.797779) (xy 304.270918 -54.770528) (xy 301.138997 -54.770528)
			(xy 301.139352 -54.791102) (xy 301.138866 -54.818353) (xy 301.13111 -54.872301) (xy 301.115755 -54.924596)
			(xy 301.093113 -54.974173) (xy 301.063647 -55.020023) (xy 301.027956 -55.061214) (xy 300.986765 -55.096905)
			(xy 300.940915 -55.126371) (xy 300.891338 -55.149013) (xy 300.839043 -55.164368) (xy 300.785095 -55.172124)
			(xy 300.730593 -55.172124) (xy 300.676645 -55.164368) (xy 300.62435 -55.149013) (xy 300.574773 -55.126371)
			(xy 300.528923 -55.096905) (xy 300.487732 -55.061214) (xy 300.452041 -55.020023) (xy 300.422575 -54.974173)
			(xy 300.399933 -54.924596) (xy 300.384578 -54.872301) (xy 300.376822 -54.818353) (xy 300.376336 -54.791102)
			(xy 298.478382 -54.791102) (xy 298.475185 -54.813179) (xy 298.459619 -54.865814) (xy 298.436672 -54.915676)
			(xy 298.406818 -54.961736) (xy 298.370674 -55.003044) (xy 298.328984 -55.038748) (xy 298.282609 -55.068111)
			(xy 298.232506 -55.090527) (xy 298.179708 -55.105533) (xy 298.152566 -55.109618) (xy 298.14647 -55.11038)
			(xy 298.14266 -55.110888) (xy 298.12615 -55.120286) (xy 298.120054 -55.127652) (xy 298.114315 -55.135276)
			(xy 298.108439 -55.153417) (xy 298.108624 -55.162958) (xy 298.143168 -55.721758) (xy 298.143199 -55.722266)
			(xy 310.033922 -55.722266) (xy 310.037993 -55.666644) (xy 310.050119 -55.612207) (xy 310.070042 -55.560116)
			(xy 310.097338 -55.511481) (xy 310.131424 -55.467338) (xy 310.171573 -55.428629) (xy 310.216931 -55.396178)
			(xy 310.266531 -55.370677) (xy 310.319315 -55.35267) (xy 310.374158 -55.34254) (xy 310.429892 -55.340503)
			(xy 310.485329 -55.346603) (xy 310.539286 -55.360709) (xy 310.590615 -55.382521) (xy 310.638221 -55.411575)
			(xy 310.649367 -55.420851) (xy 312.424568 -55.420851) (xy 312.424568 -55.366349) (xy 312.432324 -55.312403)
			(xy 312.447678 -55.260109) (xy 312.470318 -55.210532) (xy 312.499782 -55.164682) (xy 312.535471 -55.123491)
			(xy 312.576659 -55.087799) (xy 312.622507 -55.058331) (xy 312.672082 -55.035688) (xy 312.724375 -55.02033)
			(xy 312.778321 -55.01257) (xy 312.805572 -55.012082) (xy 312.831887 -55.012507) (xy 312.884017 -55.019751)
			(xy 312.934661 -55.034079) (xy 312.982859 -55.05522) (xy 313.027702 -55.082773) (xy 313.06834 -55.116218)
			(xy 313.086496 -55.135272) (xy 313.094021 -55.14267) (xy 313.113298 -55.151197) (xy 313.123834 -55.151782)
			(xy 313.19851 -55.151782) (xy 313.209063 -55.151277) (xy 313.228358 -55.142725) (xy 313.235848 -55.135272)
			(xy 313.253982 -55.116195) (xy 313.294617 -55.082741) (xy 313.339462 -55.055185) (xy 313.387667 -55.034051)
			(xy 313.438318 -55.019738) (xy 313.490455 -55.012518) (xy 313.516772 -55.012082) (xy 313.544025 -55.012563)
			(xy 313.597978 -55.020317) (xy 313.650278 -55.03567) (xy 313.69986 -55.05831) (xy 313.745716 -55.087777)
			(xy 313.786911 -55.12347) (xy 313.822606 -55.164662) (xy 313.852076 -55.210515) (xy 313.87472 -55.260096)
			(xy 313.890077 -55.312395) (xy 313.897835 -55.366347) (xy 313.897835 -55.420853) (xy 313.890077 -55.474805)
			(xy 313.87472 -55.527104) (xy 313.852076 -55.576685) (xy 313.822606 -55.622538) (xy 313.786911 -55.66373)
			(xy 313.745716 -55.699423) (xy 313.69986 -55.72889) (xy 313.650278 -55.75153) (xy 313.597978 -55.766883)
			(xy 313.544025 -55.774637) (xy 313.516772 -55.775098) (xy 313.490457 -55.77465) (xy 313.438328 -55.767411)
			(xy 313.387685 -55.753088) (xy 313.339486 -55.731952) (xy 313.294643 -55.704403) (xy 313.254004 -55.670961)
			(xy 313.235848 -55.651908) (xy 313.228347 -55.644483) (xy 313.209051 -55.635972) (xy 313.19851 -55.635398)
			(xy 313.123834 -55.635398) (xy 313.113285 -55.635933) (xy 313.09399 -55.644464) (xy 313.086496 -55.651908)
			(xy 313.068337 -55.67096) (xy 313.027708 -55.704417) (xy 312.982868 -55.731976) (xy 312.934668 -55.753115)
			(xy 312.884021 -55.767433) (xy 312.831888 -55.774659) (xy 312.805572 -55.775098) (xy 312.778321 -55.77463)
			(xy 312.724375 -55.76687) (xy 312.672082 -55.751512) (xy 312.622507 -55.728869) (xy 312.576659 -55.699401)
			(xy 312.535471 -55.663709) (xy 312.499782 -55.622518) (xy 312.470318 -55.576668) (xy 312.447678 -55.527091)
			(xy 312.432324 -55.474797) (xy 312.424568 -55.420851) (xy 310.649367 -55.420851) (xy 310.681089 -55.44725)
			(xy 310.718306 -55.488787) (xy 310.749079 -55.5353) (xy 310.772751 -55.585797) (xy 310.788819 -55.639204)
			(xy 310.796939 -55.69438) (xy 310.797448 -55.722266) (xy 310.796939 -55.750152) (xy 310.788819 -55.805328)
			(xy 310.772751 -55.858735) (xy 310.749079 -55.909232) (xy 310.718306 -55.955745) (xy 310.681089 -55.997282)
			(xy 310.638221 -56.032957) (xy 310.590615 -56.062011) (xy 310.539286 -56.083823) (xy 310.485329 -56.097929)
			(xy 310.429892 -56.104029) (xy 310.374158 -56.101992) (xy 310.319315 -56.091862) (xy 310.266531 -56.073855)
			(xy 310.216931 -56.048354) (xy 310.171573 -56.015903) (xy 310.131424 -55.977194) (xy 310.097338 -55.933051)
			(xy 310.070042 -55.884416) (xy 310.050119 -55.832325) (xy 310.037993 -55.777888) (xy 310.033922 -55.722266)
			(xy 298.143199 -55.722266) (xy 298.168568 -56.133746) (xy 298.186094 -56.416448) (xy 298.187026 -56.423836)
			(xy 298.192579 -56.437645) (xy 298.197016 -56.443626) (xy 298.201588 -56.449214) (xy 298.222924 -56.464454)
			(xy 298.229782 -56.466994) (xy 298.257231 -56.477325) (xy 298.308833 -56.505197) (xy 298.355564 -56.540635)
			(xy 298.396323 -56.582805) (xy 298.430152 -56.630713) (xy 298.456254 -56.683233) (xy 298.474015 -56.739127)
			(xy 298.483016 -56.79708) (xy 298.483528 -56.826404) (xy 298.483528 -56.832754) (xy 298.483111 -56.847824)
			(xy 298.480186 -56.877831) (xy 298.477686 -56.892698) (xy 298.471593 -56.923739) (xy 298.450512 -56.983379)
			(xy 298.439694 -57.002934) (xy 305.763422 -57.002934) (xy 305.763924 -56.974842) (xy 305.772148 -56.919265)
			(xy 305.788436 -56.865495) (xy 305.812437 -56.814697) (xy 305.843631 -56.76797) (xy 305.881343 -56.726325)
			(xy 305.924757 -56.690664) (xy 305.948588 -56.675782) (xy 305.957478 -56.670448) (xy 305.96967 -56.65343)
			(xy 305.98999 -56.560212) (xy 305.985672 -56.539638) (xy 305.97983 -56.531002) (xy 305.963832 -56.506937)
			(xy 305.938488 -56.455006) (xy 305.921262 -56.399849) (xy 305.912546 -56.342724) (xy 305.912012 -56.313832)
			(xy 305.912485 -56.286579) (xy 305.920238 -56.232627) (xy 305.935591 -56.180329) (xy 305.958231 -56.130747)
			(xy 305.987698 -56.084893) (xy 306.023391 -56.043699) (xy 306.064583 -56.008005) (xy 306.110437 -55.978537)
			(xy 306.160017 -55.955895) (xy 306.212316 -55.940541) (xy 306.266267 -55.932786) (xy 306.29352 -55.932324)
			(xy 306.320891 -55.932772) (xy 306.375071 -55.940594) (xy 306.427575 -55.956087) (xy 306.477321 -55.978932)
			(xy 306.523287 -56.008661) (xy 306.544218 -56.026304) (xy 306.544472 -56.026558) (xy 306.551557 -56.032146)
			(xy 306.568475 -56.03839) (xy 306.577492 -56.03875) (xy 306.644548 -56.03875) (xy 306.653564 -56.038379)
			(xy 306.670481 -56.032142) (xy 306.677568 -56.026558) (xy 306.677568 -56.026304) (xy 306.677822 -56.026304)
			(xy 306.698755 -56.008663) (xy 306.744723 -55.978939) (xy 306.794469 -55.956093) (xy 306.846971 -55.940597)
			(xy 306.901149 -55.932768) (xy 306.955891 -55.932768) (xy 307.010069 -55.940597) (xy 307.062571 -55.956093)
			(xy 307.112317 -55.978939) (xy 307.158285 -56.008663) (xy 307.179218 -56.026304) (xy 307.179472 -56.026558)
			(xy 307.186557 -56.032146) (xy 307.203475 -56.03839) (xy 307.212492 -56.03875) (xy 307.279548 -56.03875)
			(xy 307.288564 -56.038379) (xy 307.305481 -56.032142) (xy 307.312568 -56.026558) (xy 307.312568 -56.026304)
			(xy 307.312822 -56.026304) (xy 307.333773 -56.008689) (xy 307.379741 -55.978973) (xy 307.429483 -55.956133)
			(xy 307.48198 -55.940636) (xy 307.536152 -55.932801) (xy 307.56352 -55.932324) (xy 307.590773 -55.932747)
			(xy 307.644723 -55.940507) (xy 307.697019 -55.955865) (xy 307.746598 -55.978509) (xy 307.79245 -56.007978)
			(xy 307.833641 -56.043673) (xy 307.869334 -56.084866) (xy 307.898801 -56.130719) (xy 307.921442 -56.180299)
			(xy 307.936798 -56.232597) (xy 307.944554 -56.286547) (xy 307.944554 -56.297068) (xy 308.286402 -56.297068)
			(xy 308.290473 -56.241446) (xy 308.302599 -56.187009) (xy 308.322522 -56.134918) (xy 308.349818 -56.086283)
			(xy 308.383904 -56.04214) (xy 308.424053 -56.003431) (xy 308.469411 -55.97098) (xy 308.519011 -55.945479)
			(xy 308.571795 -55.927472) (xy 308.626638 -55.917342) (xy 308.682372 -55.915305) (xy 308.737809 -55.921405)
			(xy 308.791766 -55.935511) (xy 308.843095 -55.957323) (xy 308.890701 -55.986377) (xy 308.933569 -56.022052)
			(xy 308.970786 -56.063589) (xy 309.001559 -56.110102) (xy 309.025231 -56.160599) (xy 309.041299 -56.214006)
			(xy 309.049419 -56.269182) (xy 309.049928 -56.297068) (xy 309.049419 -56.324954) (xy 309.041299 -56.38013)
			(xy 309.025231 -56.433537) (xy 309.001559 -56.484034) (xy 308.970786 -56.530547) (xy 308.933569 -56.572084)
			(xy 308.890701 -56.607759) (xy 308.843095 -56.636813) (xy 308.791766 -56.658625) (xy 308.737809 -56.672731)
			(xy 308.682372 -56.678831) (xy 308.626638 -56.676794) (xy 308.571795 -56.666664) (xy 308.519011 -56.648657)
			(xy 308.469411 -56.623156) (xy 308.424053 -56.590705) (xy 308.383904 -56.551996) (xy 308.349818 -56.507853)
			(xy 308.322522 -56.459218) (xy 308.302599 -56.407127) (xy 308.290473 -56.35269) (xy 308.286402 -56.297068)
			(xy 307.944554 -56.297068) (xy 307.944554 -56.341053) (xy 307.936798 -56.395003) (xy 307.921442 -56.447301)
			(xy 307.898801 -56.496881) (xy 307.869334 -56.542734) (xy 307.833641 -56.583927) (xy 307.79245 -56.619622)
			(xy 307.746598 -56.649091) (xy 307.697019 -56.671735) (xy 307.644723 -56.687093) (xy 307.590773 -56.694853)
			(xy 307.56352 -56.69534) (xy 307.536149 -56.694877) (xy 307.48197 -56.687061) (xy 307.429466 -56.671572)
			(xy 307.379719 -56.648729) (xy 307.333753 -56.619002) (xy 307.312822 -56.60136) (xy 307.312568 -56.601106)
			(xy 307.305466 -56.595542) (xy 307.288561 -56.589282) (xy 307.279548 -56.588914) (xy 307.212492 -56.588914)
			(xy 307.203474 -56.589264) (xy 307.186557 -56.595516) (xy 307.179472 -56.601106) (xy 307.179472 -56.60136)
			(xy 307.179218 -56.60136) (xy 307.158285 -56.619001) (xy 307.112317 -56.648725) (xy 307.062571 -56.671571)
			(xy 307.010069 -56.687067) (xy 306.955891 -56.694896) (xy 306.901149 -56.694896) (xy 306.846971 -56.687067)
			(xy 306.794469 -56.671571) (xy 306.744723 -56.648725) (xy 306.698755 -56.619001) (xy 306.677822 -56.60136)
			(xy 306.677568 -56.601106) (xy 306.670466 -56.595542) (xy 306.653561 -56.589282) (xy 306.644548 -56.588914)
			(xy 306.577492 -56.588914) (xy 306.568474 -56.589264) (xy 306.551557 -56.595516) (xy 306.544472 -56.601106)
			(xy 306.543964 -56.60136) (xy 306.531229 -56.612304) (xy 306.504138 -56.632145) (xy 306.489862 -56.640984)
			(xy 306.480972 -56.646318) (xy 306.46878 -56.663336) (xy 306.44846 -56.756554) (xy 306.452778 -56.777128)
			(xy 306.45862 -56.785764) (xy 306.474609 -56.809835) (xy 306.499954 -56.861764) (xy 306.517182 -56.91692)
			(xy 306.525901 -56.974042) (xy 306.526438 -57.002934) (xy 306.525952 -57.030185) (xy 306.518196 -57.084133)
			(xy 306.502841 -57.136428) (xy 306.480199 -57.186005) (xy 306.450733 -57.231855) (xy 306.415042 -57.273046)
			(xy 306.373851 -57.308737) (xy 306.328001 -57.338203) (xy 306.278424 -57.360845) (xy 306.226129 -57.3762)
			(xy 306.172181 -57.383956) (xy 306.117679 -57.383956) (xy 306.063731 -57.3762) (xy 306.011436 -57.360845)
			(xy 305.961859 -57.338203) (xy 305.916009 -57.308737) (xy 305.874818 -57.273046) (xy 305.839127 -57.231855)
			(xy 305.809661 -57.186005) (xy 305.787019 -57.136428) (xy 305.771664 -57.084133) (xy 305.763908 -57.030185)
			(xy 305.763422 -57.002934) (xy 298.439694 -57.002934) (xy 298.419892 -57.038729) (xy 298.400724 -57.063894)
			(xy 298.39539 -57.070498) (xy 298.392088 -57.079642) (xy 298.390564 -57.085484) (xy 298.389548 -57.09539)
			(xy 298.389548 -57.128156) (xy 298.378372 -57.128156) (xy 298.378372 -57.178956) (xy 298.378707 -57.187559)
			(xy 298.384423 -57.203787) (xy 298.389548 -57.210706) (xy 298.390818 -57.21223) (xy 298.408213 -57.233106)
			(xy 298.437533 -57.278855) (xy 298.460063 -57.328303) (xy 298.475346 -57.380448) (xy 298.483073 -57.434235)
			(xy 298.483528 -57.461404) (xy 298.483146 -57.48528) (xy 314.80582 -57.48528) (xy 314.809891 -57.429658)
			(xy 314.822017 -57.375221) (xy 314.84194 -57.32313) (xy 314.869236 -57.274495) (xy 314.903322 -57.230352)
			(xy 314.943471 -57.191643) (xy 314.988829 -57.159192) (xy 315.038429 -57.133691) (xy 315.091213 -57.115684)
			(xy 315.146056 -57.105554) (xy 315.20179 -57.103517) (xy 315.257227 -57.109617) (xy 315.311184 -57.123723)
			(xy 315.362513 -57.145535) (xy 315.410119 -57.174589) (xy 315.452987 -57.210264) (xy 315.490204 -57.251801)
			(xy 315.520977 -57.298314) (xy 315.544649 -57.348811) (xy 315.560717 -57.402218) (xy 315.568837 -57.457394)
			(xy 315.569346 -57.48528) (xy 315.568837 -57.513166) (xy 315.560717 -57.568342) (xy 315.544649 -57.621749)
			(xy 315.520977 -57.672246) (xy 315.490204 -57.718759) (xy 315.452987 -57.760296) (xy 315.410119 -57.795971)
			(xy 315.362513 -57.825025) (xy 315.311184 -57.846837) (xy 315.257227 -57.860943) (xy 315.20179 -57.867043)
			(xy 315.146056 -57.865006) (xy 315.091213 -57.854876) (xy 315.038429 -57.836869) (xy 314.988829 -57.811368)
			(xy 314.943471 -57.778917) (xy 314.903322 -57.740208) (xy 314.869236 -57.696065) (xy 314.84194 -57.64743)
			(xy 314.822017 -57.595339) (xy 314.809891 -57.540902) (xy 314.80582 -57.48528) (xy 298.483146 -57.48528)
			(xy 298.483118 -57.487021) (xy 298.476265 -57.537796) (xy 298.46267 -57.587194) (xy 298.442578 -57.634325)
			(xy 298.416352 -57.678338) (xy 298.400724 -57.69864) (xy 298.40047 -57.698894) (xy 298.398946 -57.700672)
			(xy 298.394642 -57.707199) (xy 298.389846 -57.72207) (xy 298.389548 -57.729882) (xy 298.389548 -57.763156)
			(xy 298.378372 -57.763156) (xy 298.378372 -57.813956) (xy 298.378707 -57.822559) (xy 298.384423 -57.838787)
			(xy 298.389548 -57.845706) (xy 298.390818 -57.84723) (xy 298.408213 -57.868106) (xy 298.437533 -57.913855)
			(xy 298.460063 -57.963303) (xy 298.475346 -58.015448) (xy 298.483073 -58.069235) (xy 298.483528 -58.096404)
			(xy 298.483118 -58.122021) (xy 298.476265 -58.172796) (xy 298.46267 -58.222194) (xy 298.442578 -58.269325)
			(xy 298.416352 -58.313338) (xy 298.400724 -58.33364) (xy 298.40047 -58.333894) (xy 298.398946 -58.335672)
			(xy 298.394642 -58.342199) (xy 298.389846 -58.35707) (xy 298.389548 -58.364882) (xy 298.389548 -58.398156)
			(xy 298.378372 -58.398156) (xy 298.378372 -58.448956) (xy 298.378707 -58.457559) (xy 298.384423 -58.473787)
			(xy 298.389548 -58.480706) (xy 298.390818 -58.48223) (xy 298.408213 -58.503106) (xy 298.437533 -58.548855)
			(xy 298.460063 -58.598303) (xy 298.475346 -58.650448) (xy 298.479496 -58.679334) (xy 306.195222 -58.679334)
			(xy 306.195638 -58.653018) (xy 306.202883 -58.600887) (xy 306.217211 -58.550243) (xy 306.238353 -58.502044)
			(xy 306.265909 -58.457202) (xy 306.299356 -58.416565) (xy 306.318412 -58.39841) (xy 306.325813 -58.390888)
			(xy 306.334337 -58.371608) (xy 306.334922 -58.361072) (xy 306.334922 -58.286396) (xy 306.334402 -58.275845)
			(xy 306.32586 -58.256551) (xy 306.318412 -58.249058) (xy 306.299345 -58.230913) (xy 306.265889 -58.190282)
			(xy 306.238331 -58.145439) (xy 306.217194 -58.097236) (xy 306.20288 -58.046587) (xy 306.195658 -57.994451)
			(xy 306.195222 -57.968134) (xy 306.195708 -57.940883) (xy 306.203464 -57.886935) (xy 306.218819 -57.83464)
			(xy 306.241461 -57.785063) (xy 306.270927 -57.739213) (xy 306.306618 -57.698022) (xy 306.347809 -57.662331)
			(xy 306.393659 -57.632865) (xy 306.443236 -57.610223) (xy 306.495531 -57.594868) (xy 306.549479 -57.587112)
			(xy 306.603981 -57.587112) (xy 306.657929 -57.594868) (xy 306.710224 -57.610223) (xy 306.759801 -57.632865)
			(xy 306.805651 -57.662331) (xy 306.846842 -57.698022) (xy 306.882533 -57.739213) (xy 306.911999 -57.785063)
			(xy 306.934641 -57.83464) (xy 306.949996 -57.886935) (xy 306.957752 -57.940883) (xy 306.958238 -57.968134)
			(xy 306.957813 -57.99445) (xy 306.950572 -58.046581) (xy 306.943304 -58.072274) (xy 310.193434 -58.072274)
			(xy 310.197505 -58.016652) (xy 310.209631 -57.962215) (xy 310.229554 -57.910124) (xy 310.25685 -57.861489)
			(xy 310.290936 -57.817346) (xy 310.331085 -57.778637) (xy 310.376443 -57.746186) (xy 310.426043 -57.720685)
			(xy 310.478827 -57.702678) (xy 310.53367 -57.692548) (xy 310.589404 -57.690511) (xy 310.644841 -57.696611)
			(xy 310.698798 -57.710717) (xy 310.750127 -57.732529) (xy 310.797733 -57.761583) (xy 310.840601 -57.797258)
			(xy 310.877818 -57.838795) (xy 310.908591 -57.885308) (xy 310.932263 -57.935805) (xy 310.948331 -57.989212)
			(xy 310.956451 -58.044388) (xy 310.95696 -58.072274) (xy 310.95689 -58.076084) (xy 315.557914 -58.076084)
			(xy 315.561985 -58.020462) (xy 315.574111 -57.966025) (xy 315.594034 -57.913934) (xy 315.62133 -57.865299)
			(xy 315.655416 -57.821156) (xy 315.695565 -57.782447) (xy 315.740923 -57.749996) (xy 315.790523 -57.724495)
			(xy 315.843307 -57.706488) (xy 315.89815 -57.696358) (xy 315.953884 -57.694321) (xy 316.009321 -57.700421)
			(xy 316.063278 -57.714527) (xy 316.114607 -57.736339) (xy 316.162213 -57.765393) (xy 316.205081 -57.801068)
			(xy 316.242298 -57.842605) (xy 316.258634 -57.867296) (xy 317.842898 -57.867296) (xy 317.846969 -57.811674)
			(xy 317.859095 -57.757237) (xy 317.879018 -57.705146) (xy 317.906314 -57.656511) (xy 317.9404 -57.612368)
			(xy 317.980549 -57.573659) (xy 318.025907 -57.541208) (xy 318.075507 -57.515707) (xy 318.128291 -57.4977)
			(xy 318.183134 -57.48757) (xy 318.238868 -57.485533) (xy 318.294305 -57.491633) (xy 318.348262 -57.505739)
			(xy 318.399591 -57.527551) (xy 318.447197 -57.556605) (xy 318.490065 -57.59228) (xy 318.527282 -57.633817)
			(xy 318.558055 -57.68033) (xy 318.581727 -57.730827) (xy 318.597795 -57.784234) (xy 318.605915 -57.83941)
			(xy 318.606424 -57.867296) (xy 318.605915 -57.895182) (xy 318.597795 -57.950358) (xy 318.581727 -58.003765)
			(xy 318.558055 -58.054262) (xy 318.527282 -58.100775) (xy 318.490065 -58.142312) (xy 318.447197 -58.177987)
			(xy 318.399591 -58.207041) (xy 318.348262 -58.228853) (xy 318.294305 -58.242959) (xy 318.238868 -58.249059)
			(xy 318.183134 -58.247022) (xy 318.128291 -58.236892) (xy 318.075507 -58.218885) (xy 318.025907 -58.193384)
			(xy 317.980549 -58.160933) (xy 317.9404 -58.122224) (xy 317.906314 -58.078081) (xy 317.879018 -58.029446)
			(xy 317.859095 -57.977355) (xy 317.846969 -57.922918) (xy 317.842898 -57.867296) (xy 316.258634 -57.867296)
			(xy 316.273071 -57.889118) (xy 316.296743 -57.939615) (xy 316.312811 -57.993022) (xy 316.320931 -58.048198)
			(xy 316.32144 -58.076084) (xy 316.320931 -58.10397) (xy 316.312811 -58.159146) (xy 316.296743 -58.212553)
			(xy 316.273071 -58.26305) (xy 316.242298 -58.309563) (xy 316.205081 -58.3511) (xy 316.162213 -58.386775)
			(xy 316.114607 -58.415829) (xy 316.063278 -58.437641) (xy 316.009321 -58.451747) (xy 315.953884 -58.457847)
			(xy 315.89815 -58.45581) (xy 315.843307 -58.44568) (xy 315.790523 -58.427673) (xy 315.740923 -58.402172)
			(xy 315.695565 -58.369721) (xy 315.655416 -58.331012) (xy 315.62133 -58.286869) (xy 315.594034 -58.238234)
			(xy 315.574111 -58.186143) (xy 315.561985 -58.131706) (xy 315.557914 -58.076084) (xy 310.95689 -58.076084)
			(xy 310.956451 -58.10016) (xy 310.948331 -58.155336) (xy 310.932263 -58.208743) (xy 310.908591 -58.25924)
			(xy 310.877818 -58.305753) (xy 310.840601 -58.34729) (xy 310.797733 -58.382965) (xy 310.750127 -58.412019)
			(xy 310.698798 -58.433831) (xy 310.644841 -58.447937) (xy 310.589404 -58.454037) (xy 310.53367 -58.452)
			(xy 310.478827 -58.44187) (xy 310.426043 -58.423863) (xy 310.376443 -58.398362) (xy 310.331085 -58.365911)
			(xy 310.290936 -58.327202) (xy 310.25685 -58.283059) (xy 310.229554 -58.234424) (xy 310.209631 -58.182333)
			(xy 310.197505 -58.127896) (xy 310.193434 -58.072274) (xy 306.943304 -58.072274) (xy 306.936246 -58.097225)
			(xy 306.915106 -58.145424) (xy 306.887551 -58.190267) (xy 306.854104 -58.230904) (xy 306.835048 -58.249058)
			(xy 306.82767 -58.2566) (xy 306.819131 -58.275864) (xy 306.818538 -58.286396) (xy 306.818538 -58.361072)
			(xy 306.819058 -58.371623) (xy 306.827598 -58.390919) (xy 306.835048 -58.39841) (xy 306.854111 -58.416558)
			(xy 306.887565 -58.457191) (xy 306.915122 -58.502033) (xy 306.936259 -58.550235) (xy 306.939365 -58.561224)
			(xy 316.762128 -58.561224) (xy 316.766199 -58.505602) (xy 316.778325 -58.451165) (xy 316.798248 -58.399074)
			(xy 316.825544 -58.350439) (xy 316.85963 -58.306296) (xy 316.899779 -58.267587) (xy 316.945137 -58.235136)
			(xy 316.994737 -58.209635) (xy 317.047521 -58.191628) (xy 317.102364 -58.181498) (xy 317.158098 -58.179461)
			(xy 317.213535 -58.185561) (xy 317.267492 -58.199667) (xy 317.318821 -58.221479) (xy 317.366427 -58.250533)
			(xy 317.409295 -58.286208) (xy 317.446512 -58.327745) (xy 317.477285 -58.374258) (xy 317.500957 -58.424755)
			(xy 317.517025 -58.478162) (xy 317.525145 -58.533338) (xy 317.525654 -58.561224) (xy 317.525145 -58.58911)
			(xy 317.517025 -58.644286) (xy 317.500957 -58.697693) (xy 317.477285 -58.74819) (xy 317.446512 -58.794703)
			(xy 317.409295 -58.83624) (xy 317.366427 -58.871915) (xy 317.318821 -58.900969) (xy 317.267492 -58.922781)
			(xy 317.213535 -58.936887) (xy 317.158098 -58.942987) (xy 317.102364 -58.94095) (xy 317.047521 -58.93082)
			(xy 316.994737 -58.912813) (xy 316.945137 -58.887312) (xy 316.899779 -58.854861) (xy 316.85963 -58.816152)
			(xy 316.825544 -58.772009) (xy 316.798248 -58.723374) (xy 316.778325 -58.671283) (xy 316.766199 -58.616846)
			(xy 316.762128 -58.561224) (xy 306.939365 -58.561224) (xy 306.950575 -58.600883) (xy 306.9578 -58.653018)
			(xy 306.958238 -58.679334) (xy 306.957752 -58.706585) (xy 306.949996 -58.760533) (xy 306.934641 -58.812828)
			(xy 306.911999 -58.862405) (xy 306.882533 -58.908255) (xy 306.846842 -58.949446) (xy 306.805651 -58.985137)
			(xy 306.759801 -59.014603) (xy 306.710224 -59.037245) (xy 306.657929 -59.0526) (xy 306.603981 -59.060356)
			(xy 306.549479 -59.060356) (xy 306.495531 -59.0526) (xy 306.443236 -59.037245) (xy 306.393659 -59.014603)
			(xy 306.347809 -58.985137) (xy 306.306618 -58.949446) (xy 306.270927 -58.908255) (xy 306.241461 -58.862405)
			(xy 306.218819 -58.812828) (xy 306.203464 -58.760533) (xy 306.195708 -58.706585) (xy 306.195222 -58.679334)
			(xy 298.479496 -58.679334) (xy 298.483073 -58.704235) (xy 298.483528 -58.731404) (xy 298.483528 -58.739024)
			(xy 298.482352 -58.769202) (xy 298.471653 -58.828639) (xy 298.451728 -58.885649) (xy 298.423075 -58.938811)
			(xy 298.386408 -58.986798) (xy 298.36491 -59.00801) (xy 298.362116 -59.01055) (xy 298.355637 -59.01843)
			(xy 298.34896 -59.037688) (xy 298.349162 -59.047888) (xy 298.356997 -59.174634) (xy 315.292992 -59.174634)
			(xy 315.297063 -59.119012) (xy 315.309189 -59.064575) (xy 315.329112 -59.012484) (xy 315.356408 -58.963849)
			(xy 315.390494 -58.919706) (xy 315.430643 -58.880997) (xy 315.476001 -58.848546) (xy 315.525601 -58.823045)
			(xy 315.578385 -58.805038) (xy 315.633228 -58.794908) (xy 315.688962 -58.792871) (xy 315.744399 -58.798971)
			(xy 315.798356 -58.813077) (xy 315.849685 -58.834889) (xy 315.897291 -58.863943) (xy 315.940159 -58.899618)
			(xy 315.977376 -58.941155) (xy 316.008149 -58.987668) (xy 316.031821 -59.038165) (xy 316.047889 -59.091572)
			(xy 316.056009 -59.146748) (xy 316.056518 -59.174634) (xy 316.056009 -59.20252) (xy 316.047889 -59.257696)
			(xy 316.031821 -59.311103) (xy 316.008149 -59.3616) (xy 315.977376 -59.408113) (xy 315.940159 -59.44965)
			(xy 315.897291 -59.485325) (xy 315.849685 -59.514379) (xy 315.798356 -59.536191) (xy 315.744399 -59.550297)
			(xy 315.688962 -59.556397) (xy 315.633228 -59.55436) (xy 315.578385 -59.54423) (xy 315.525601 -59.526223)
			(xy 315.476001 -59.500722) (xy 315.430643 -59.468271) (xy 315.390494 -59.429562) (xy 315.356408 -59.385419)
			(xy 315.329112 -59.336784) (xy 315.309189 -59.284693) (xy 315.297063 -59.230256) (xy 315.292992 -59.174634)
			(xy 298.356997 -59.174634) (xy 298.409212 -60.01925) (xy 306.335684 -60.01925) (xy 306.335684 -59.96475)
			(xy 306.34344 -59.910804) (xy 306.358794 -59.858512) (xy 306.381433 -59.808936) (xy 306.410898 -59.763087)
			(xy 306.446587 -59.721898) (xy 306.487775 -59.686207) (xy 306.533622 -59.656741) (xy 306.583197 -59.634099)
			(xy 306.635489 -59.618743) (xy 306.689434 -59.610985) (xy 306.716684 -59.610498) (xy 306.744054 -59.610974)
			(xy 306.798233 -59.618789) (xy 306.850736 -59.634276) (xy 306.900483 -59.657116) (xy 306.94645 -59.686838)
			(xy 306.967382 -59.704478) (xy 306.967636 -59.704732) (xy 306.974734 -59.710301) (xy 306.991642 -59.716557)
			(xy 307.000656 -59.716924) (xy 307.067712 -59.716924) (xy 307.076729 -59.716567) (xy 307.093645 -59.710319)
			(xy 307.100732 -59.704732) (xy 307.100732 -59.704478) (xy 307.100986 -59.704478) (xy 307.121919 -59.686837)
			(xy 307.167887 -59.657113) (xy 307.217633 -59.634267) (xy 307.270135 -59.618771) (xy 307.324313 -59.610942)
			(xy 307.379055 -59.610942) (xy 307.433233 -59.618771) (xy 307.485735 -59.634267) (xy 307.535481 -59.657113)
			(xy 307.581449 -59.686837) (xy 307.602382 -59.704478) (xy 307.602636 -59.704732) (xy 307.609734 -59.710301)
			(xy 307.626642 -59.716557) (xy 307.635656 -59.716924) (xy 307.702712 -59.716924) (xy 307.711729 -59.716567)
			(xy 307.728645 -59.710319) (xy 307.735732 -59.704732) (xy 307.735732 -59.704478) (xy 307.735986 -59.704478)
			(xy 307.75691 -59.686829) (xy 307.802885 -59.657119) (xy 307.852635 -59.634285) (xy 307.905137 -59.618797)
			(xy 307.959314 -59.610971) (xy 307.986684 -59.610498) (xy 308.013938 -59.610948) (xy 308.067892 -59.618704)
			(xy 308.120192 -59.634058) (xy 308.169775 -59.6567) (xy 308.215631 -59.686168) (xy 308.256826 -59.721863)
			(xy 308.292522 -59.763056) (xy 308.321992 -59.808911) (xy 308.344636 -59.858493) (xy 308.359993 -59.910793)
			(xy 308.367751 -59.964746) (xy 308.367751 -60.019254) (xy 308.359993 -60.073207) (xy 308.344636 -60.125507)
			(xy 308.321992 -60.175089) (xy 308.292522 -60.220944) (xy 308.256826 -60.262137) (xy 308.215631 -60.297832)
			(xy 308.169775 -60.3273) (xy 308.120192 -60.349942) (xy 308.067892 -60.365296) (xy 308.013938 -60.373052)
			(xy 307.986684 -60.373514) (xy 307.959314 -60.373054) (xy 307.905134 -60.365234) (xy 307.852631 -60.349743)
			(xy 307.802885 -60.326901) (xy 307.756918 -60.297175) (xy 307.735986 -60.279534) (xy 307.735732 -60.27928)
			(xy 307.728642 -60.273698) (xy 307.711728 -60.267449) (xy 307.702712 -60.267088) (xy 307.635656 -60.267088)
			(xy 307.626642 -60.267474) (xy 307.609725 -60.273702) (xy 307.602636 -60.27928) (xy 307.602382 -60.279534)
			(xy 307.581449 -60.297175) (xy 307.535481 -60.326899) (xy 307.485735 -60.349745) (xy 307.433233 -60.365241)
			(xy 307.379055 -60.37307) (xy 307.324313 -60.37307) (xy 307.270135 -60.365241) (xy 307.217633 -60.349745)
			(xy 307.167887 -60.326899) (xy 307.121919 -60.297175) (xy 307.100986 -60.279534) (xy 307.100732 -60.27928)
			(xy 307.093642 -60.273698) (xy 307.076728 -60.267449) (xy 307.067712 -60.267088) (xy 307.000656 -60.267088)
			(xy 306.991642 -60.267474) (xy 306.974725 -60.273702) (xy 306.967636 -60.27928) (xy 306.967636 -60.279534)
			(xy 306.967382 -60.279534) (xy 306.946434 -60.297153) (xy 306.900465 -60.326867) (xy 306.850722 -60.349706)
			(xy 306.798225 -60.365202) (xy 306.744052 -60.373036) (xy 306.716684 -60.373514) (xy 306.689434 -60.373015)
			(xy 306.635489 -60.365257) (xy 306.583197 -60.349901) (xy 306.533622 -60.327259) (xy 306.487775 -60.297793)
			(xy 306.446587 -60.262102) (xy 306.410898 -60.220913) (xy 306.381433 -60.175064) (xy 306.358794 -60.125488)
			(xy 306.34344 -60.073196) (xy 306.335684 -60.01925) (xy 298.409212 -60.01925) (xy 298.441618 -60.54344)
			(xy 298.441872 -60.546488) (xy 298.443396 -60.604908) (xy 298.443396 -60.605416) (xy 298.442792 -60.633356)
			(xy 317.996822 -60.633356) (xy 318.000893 -60.577734) (xy 318.013019 -60.523297) (xy 318.032942 -60.471206)
			(xy 318.060238 -60.422571) (xy 318.094324 -60.378428) (xy 318.134473 -60.339719) (xy 318.179831 -60.307268)
			(xy 318.229431 -60.281767) (xy 318.282215 -60.26376) (xy 318.337058 -60.25363) (xy 318.392792 -60.251593)
			(xy 318.448229 -60.257693) (xy 318.502186 -60.271799) (xy 318.553515 -60.293611) (xy 318.601121 -60.322665)
			(xy 318.643989 -60.35834) (xy 318.681206 -60.399877) (xy 318.711979 -60.44639) (xy 318.735651 -60.496887)
			(xy 318.751719 -60.550294) (xy 318.759839 -60.60547) (xy 318.760348 -60.633356) (xy 318.759839 -60.661242)
			(xy 318.751719 -60.716418) (xy 318.735651 -60.769825) (xy 318.711979 -60.820322) (xy 318.681206 -60.866835)
			(xy 318.643989 -60.908372) (xy 318.601121 -60.944047) (xy 318.553515 -60.973101) (xy 318.502186 -60.994913)
			(xy 318.448229 -61.009019) (xy 318.392792 -61.015119) (xy 318.337058 -61.013082) (xy 318.282215 -61.002952)
			(xy 318.229431 -60.984945) (xy 318.179831 -60.959444) (xy 318.134473 -60.926993) (xy 318.094324 -60.888284)
			(xy 318.060238 -60.844141) (xy 318.032942 -60.795506) (xy 318.013019 -60.743415) (xy 318.000893 -60.688978)
			(xy 317.996822 -60.633356) (xy 298.442792 -60.633356) (xy 298.44238 -60.652406) (xy 298.402711 -61.487812)
			(xy 316.504318 -61.487812) (xy 316.508389 -61.43219) (xy 316.520515 -61.377753) (xy 316.540438 -61.325662)
			(xy 316.567734 -61.277027) (xy 316.60182 -61.232884) (xy 316.641969 -61.194175) (xy 316.687327 -61.161724)
			(xy 316.736927 -61.136223) (xy 316.789711 -61.118216) (xy 316.844554 -61.108086) (xy 316.900288 -61.106049)
			(xy 316.955725 -61.112149) (xy 317.009682 -61.126255) (xy 317.061011 -61.148067) (xy 317.108617 -61.177121)
			(xy 317.151485 -61.212796) (xy 317.188702 -61.254333) (xy 317.219475 -61.300846) (xy 317.243147 -61.351343)
			(xy 317.259215 -61.40475) (xy 317.267335 -61.459926) (xy 317.267844 -61.487812) (xy 317.267335 -61.515698)
			(xy 317.259215 -61.570874) (xy 317.243147 -61.624281) (xy 317.219475 -61.674778) (xy 317.188702 -61.721291)
			(xy 317.151485 -61.762828) (xy 317.108617 -61.798503) (xy 317.061011 -61.827557) (xy 317.009682 -61.849369)
			(xy 316.955725 -61.863475) (xy 316.900288 -61.869575) (xy 316.844554 -61.867538) (xy 316.789711 -61.857408)
			(xy 316.736927 -61.839401) (xy 316.687327 -61.8139) (xy 316.641969 -61.781449) (xy 316.60182 -61.74274)
			(xy 316.567734 -61.698597) (xy 316.540438 -61.649962) (xy 316.520515 -61.597871) (xy 316.508389 -61.543434)
			(xy 316.504318 -61.487812) (xy 298.402711 -61.487812) (xy 298.372643 -62.121034) (xy 314.442092 -62.121034)
			(xy 314.446163 -62.065412) (xy 314.458289 -62.010975) (xy 314.478212 -61.958884) (xy 314.505508 -61.910249)
			(xy 314.539594 -61.866106) (xy 314.579743 -61.827397) (xy 314.625101 -61.794946) (xy 314.674701 -61.769445)
			(xy 314.727485 -61.751438) (xy 314.782328 -61.741308) (xy 314.838062 -61.739271) (xy 314.893499 -61.745371)
			(xy 314.947456 -61.759477) (xy 314.998785 -61.781289) (xy 315.046391 -61.810343) (xy 315.089259 -61.846018)
			(xy 315.126476 -61.887555) (xy 315.157249 -61.934068) (xy 315.180921 -61.984565) (xy 315.196989 -62.037972)
			(xy 315.205109 -62.093148) (xy 315.205618 -62.121034) (xy 315.205109 -62.14892) (xy 315.196989 -62.204096)
			(xy 315.180921 -62.257503) (xy 315.157249 -62.308) (xy 315.126476 -62.354513) (xy 315.089259 -62.39605)
			(xy 315.046391 -62.431725) (xy 314.998785 -62.460779) (xy 314.947456 -62.482591) (xy 314.893499 -62.496697)
			(xy 314.838062 -62.502797) (xy 314.782328 -62.50076) (xy 314.727485 -62.49063) (xy 314.674701 -62.472623)
			(xy 314.625101 -62.447122) (xy 314.579743 -62.414671) (xy 314.539594 -62.375962) (xy 314.505508 -62.331819)
			(xy 314.478212 -62.283184) (xy 314.458289 -62.231093) (xy 314.446163 -62.176656) (xy 314.442092 -62.121034)
			(xy 298.372643 -62.121034) (xy 298.320765 -63.21355) (xy 306.320688 -63.21355) (xy 306.320688 -63.15905)
			(xy 306.328444 -63.105104) (xy 306.343799 -63.05281) (xy 306.366439 -63.003235) (xy 306.395905 -62.957386)
			(xy 306.431595 -62.916197) (xy 306.472784 -62.880506) (xy 306.518633 -62.85104) (xy 306.568208 -62.8284)
			(xy 306.620502 -62.813045) (xy 306.674448 -62.805288) (xy 306.701698 -62.804802) (xy 306.729068 -62.805269)
			(xy 306.783247 -62.813086) (xy 306.83575 -62.828575) (xy 306.885497 -62.851417) (xy 306.931464 -62.881141)
			(xy 306.952396 -62.898782) (xy 306.95265 -62.899036) (xy 306.959744 -62.904612) (xy 306.976655 -62.910864)
			(xy 306.98567 -62.911228) (xy 307.052726 -62.911228) (xy 307.061743 -62.910878) (xy 307.07866 -62.904625)
			(xy 307.085746 -62.899036) (xy 307.085746 -62.898782) (xy 307.086 -62.898782) (xy 307.106933 -62.881141)
			(xy 307.152901 -62.851417) (xy 307.202647 -62.828571) (xy 307.255149 -62.813075) (xy 307.309327 -62.805246)
			(xy 307.364069 -62.805246) (xy 307.418247 -62.813075) (xy 307.470749 -62.828571) (xy 307.520495 -62.851417)
			(xy 307.566463 -62.881141) (xy 307.587396 -62.898782) (xy 307.58765 -62.899036) (xy 307.594744 -62.904612)
			(xy 307.611655 -62.910864) (xy 307.62067 -62.911228) (xy 307.687726 -62.911228) (xy 307.696743 -62.910878)
			(xy 307.71366 -62.904625) (xy 307.720746 -62.899036) (xy 307.720746 -62.898782) (xy 307.721 -62.898782)
			(xy 307.741919 -62.881127) (xy 307.787896 -62.851418) (xy 307.837647 -62.828585) (xy 307.89015 -62.813098)
			(xy 307.944328 -62.805274) (xy 307.971698 -62.804802) (xy 307.998952 -62.805245) (xy 308.052904 -62.813002)
			(xy 308.105204 -62.828358) (xy 308.154786 -62.851001) (xy 308.20064 -62.88047) (xy 308.241834 -62.916164)
			(xy 308.277529 -62.957358) (xy 308.306998 -63.003213) (xy 308.329641 -63.052794) (xy 308.33946 -63.086234)
			(xy 311.587386 -63.086234) (xy 311.591457 -63.030612) (xy 311.603583 -62.976175) (xy 311.623506 -62.924084)
			(xy 311.650802 -62.875449) (xy 311.684888 -62.831306) (xy 311.725037 -62.792597) (xy 311.770395 -62.760146)
			(xy 311.819995 -62.734645) (xy 311.872779 -62.716638) (xy 311.927622 -62.706508) (xy 311.983356 -62.704471)
			(xy 312.038793 -62.710571) (xy 312.09275 -62.724677) (xy 312.144079 -62.746489) (xy 312.191685 -62.775543)
			(xy 312.234553 -62.811218) (xy 312.27177 -62.852755) (xy 312.302543 -62.899268) (xy 312.326215 -62.949765)
			(xy 312.342283 -63.003172) (xy 312.350403 -63.058348) (xy 312.350912 -63.086234) (xy 312.350403 -63.11412)
			(xy 312.342283 -63.169296) (xy 312.326215 -63.222703) (xy 312.302543 -63.2732) (xy 312.30239 -63.273432)
			(xy 313.776612 -63.273432) (xy 313.780683 -63.21781) (xy 313.792809 -63.163373) (xy 313.812732 -63.111282)
			(xy 313.840028 -63.062647) (xy 313.874114 -63.018504) (xy 313.914263 -62.979795) (xy 313.959621 -62.947344)
			(xy 314.009221 -62.921843) (xy 314.062005 -62.903836) (xy 314.116848 -62.893706) (xy 314.172582 -62.891669)
			(xy 314.228019 -62.897769) (xy 314.281976 -62.911875) (xy 314.333305 -62.933687) (xy 314.380911 -62.962741)
			(xy 314.423779 -62.998416) (xy 314.460996 -63.039953) (xy 314.491769 -63.086466) (xy 314.515441 -63.136963)
			(xy 314.531509 -63.19037) (xy 314.539629 -63.245546) (xy 314.540138 -63.273432) (xy 314.539629 -63.301318)
			(xy 314.531509 -63.356494) (xy 314.515441 -63.409901) (xy 314.491769 -63.460398) (xy 314.460996 -63.506911)
			(xy 314.423779 -63.548448) (xy 314.380911 -63.584123) (xy 314.333305 -63.613177) (xy 314.281976 -63.634989)
			(xy 314.228019 -63.649095) (xy 314.172582 -63.655195) (xy 314.116848 -63.653158) (xy 314.062005 -63.643028)
			(xy 314.009221 -63.625021) (xy 313.959621 -63.59952) (xy 313.914263 -63.567069) (xy 313.874114 -63.52836)
			(xy 313.840028 -63.484217) (xy 313.812732 -63.435582) (xy 313.792809 -63.383491) (xy 313.780683 -63.329054)
			(xy 313.776612 -63.273432) (xy 312.30239 -63.273432) (xy 312.27177 -63.319713) (xy 312.234553 -63.36125)
			(xy 312.191685 -63.396925) (xy 312.144079 -63.425979) (xy 312.09275 -63.447791) (xy 312.038793 -63.461897)
			(xy 311.983356 -63.467997) (xy 311.927622 -63.46596) (xy 311.872779 -63.45583) (xy 311.819995 -63.437823)
			(xy 311.770395 -63.412322) (xy 311.725037 -63.379871) (xy 311.684888 -63.341162) (xy 311.650802 -63.297019)
			(xy 311.623506 -63.248384) (xy 311.603583 -63.196293) (xy 311.591457 -63.141856) (xy 311.587386 -63.086234)
			(xy 308.33946 -63.086234) (xy 308.344998 -63.105094) (xy 308.352755 -63.159046) (xy 308.352755 -63.213554)
			(xy 308.344998 -63.267506) (xy 308.329641 -63.319806) (xy 308.306998 -63.369387) (xy 308.277529 -63.415242)
			(xy 308.241834 -63.456436) (xy 308.20064 -63.49213) (xy 308.154786 -63.521599) (xy 308.105204 -63.544242)
			(xy 308.052904 -63.559598) (xy 307.998952 -63.567355) (xy 307.971698 -63.567818) (xy 307.944327 -63.567373)
			(xy 307.890146 -63.559553) (xy 307.837642 -63.54406) (xy 307.787895 -63.521213) (xy 307.74193 -63.491483)
			(xy 307.721 -63.473838) (xy 307.720746 -63.473584) (xy 307.713652 -63.468009) (xy 307.696741 -63.461756)
			(xy 307.687726 -63.461392) (xy 307.62067 -63.461392) (xy 307.611652 -63.461737) (xy 307.594735 -63.467993)
			(xy 307.58765 -63.473584) (xy 307.587396 -63.473838) (xy 307.566463 -63.491479) (xy 307.520495 -63.521203)
			(xy 307.470749 -63.544049) (xy 307.418247 -63.559545) (xy 307.364069 -63.567374) (xy 307.309327 -63.567374)
			(xy 307.255149 -63.559545) (xy 307.202647 -63.544049) (xy 307.152901 -63.521203) (xy 307.106933 -63.491479)
			(xy 307.086 -63.473838) (xy 307.085746 -63.473584) (xy 307.078652 -63.468009) (xy 307.061741 -63.461756)
			(xy 307.052726 -63.461392) (xy 306.98567 -63.461392) (xy 306.976652 -63.461737) (xy 306.959735 -63.467993)
			(xy 306.95265 -63.473584) (xy 306.95265 -63.473838) (xy 306.952396 -63.473838) (xy 306.931481 -63.491499)
			(xy 306.885503 -63.521206) (xy 306.835751 -63.544037) (xy 306.783247 -63.559524) (xy 306.729068 -63.567347)
			(xy 306.701698 -63.567818) (xy 306.674448 -63.567312) (xy 306.620502 -63.559555) (xy 306.568208 -63.5442)
			(xy 306.518633 -63.52156) (xy 306.472784 -63.492094) (xy 306.431595 -63.456403) (xy 306.395905 -63.415214)
			(xy 306.366439 -63.369365) (xy 306.343799 -63.31979) (xy 306.328444 -63.267496) (xy 306.320688 -63.21355)
			(xy 298.320765 -63.21355) (xy 298.231142 -65.100962) (xy 304.332384 -65.100962) (xy 304.336455 -65.04534)
			(xy 304.348581 -64.990903) (xy 304.368504 -64.938812) (xy 304.3958 -64.890177) (xy 304.429886 -64.846034)
			(xy 304.470035 -64.807325) (xy 304.515393 -64.774874) (xy 304.564993 -64.749373) (xy 304.617777 -64.731366)
			(xy 304.67262 -64.721236) (xy 304.728354 -64.719199) (xy 304.783791 -64.725299) (xy 304.837748 -64.739405)
			(xy 304.889077 -64.761217) (xy 304.936683 -64.790271) (xy 304.979551 -64.825946) (xy 305.016768 -64.867483)
			(xy 305.047541 -64.913996) (xy 305.071213 -64.964493) (xy 305.087281 -65.0179) (xy 305.095401 -65.073076)
			(xy 305.09591 -65.100962) (xy 305.095401 -65.128848) (xy 305.087281 -65.184024) (xy 305.071213 -65.237431)
			(xy 305.047541 -65.287928) (xy 305.016768 -65.334441) (xy 304.979551 -65.375978) (xy 304.936683 -65.411653)
			(xy 304.889077 -65.440707) (xy 304.837748 -65.462519) (xy 304.783791 -65.476625) (xy 304.728354 -65.482725)
			(xy 304.67262 -65.480688) (xy 304.617777 -65.470558) (xy 304.564993 -65.452551) (xy 304.515393 -65.42705)
			(xy 304.470035 -65.394599) (xy 304.429886 -65.35589) (xy 304.3958 -65.311747) (xy 304.368504 -65.263112)
			(xy 304.348581 -65.211021) (xy 304.336455 -65.156584) (xy 304.332384 -65.100962) (xy 298.231142 -65.100962)
			(xy 298.211651 -65.511426) (xy 298.584872 -65.511426) (xy 298.588943 -65.455804) (xy 298.601069 -65.401367)
			(xy 298.620992 -65.349276) (xy 298.648288 -65.300641) (xy 298.682374 -65.256498) (xy 298.722523 -65.217789)
			(xy 298.767881 -65.185338) (xy 298.817481 -65.159837) (xy 298.870265 -65.14183) (xy 298.925108 -65.1317)
			(xy 298.980842 -65.129663) (xy 299.036279 -65.135763) (xy 299.090236 -65.149869) (xy 299.141565 -65.171681)
			(xy 299.189171 -65.200735) (xy 299.232039 -65.23641) (xy 299.269256 -65.277947) (xy 299.300029 -65.32446)
			(xy 299.323701 -65.374957) (xy 299.339769 -65.428364) (xy 299.347889 -65.48354) (xy 299.348398 -65.511426)
			(xy 299.347889 -65.539312) (xy 299.339769 -65.594488) (xy 299.323701 -65.647895) (xy 299.300029 -65.698392)
			(xy 299.269256 -65.744905) (xy 299.232039 -65.786442) (xy 299.189171 -65.822117) (xy 299.141565 -65.851171)
			(xy 299.090236 -65.872983) (xy 299.036279 -65.887089) (xy 298.980842 -65.893189) (xy 298.925108 -65.891152)
			(xy 298.870265 -65.881022) (xy 298.817481 -65.863015) (xy 298.767881 -65.837514) (xy 298.722523 -65.805063)
			(xy 298.682374 -65.766354) (xy 298.648288 -65.722211) (xy 298.620992 -65.673576) (xy 298.601069 -65.621485)
			(xy 298.588943 -65.567048) (xy 298.584872 -65.511426) (xy 298.211651 -65.511426) (xy 298.134844 -67.128949)
			(xy 298.566598 -67.128949) (xy 298.566598 -67.074451) (xy 298.574354 -67.020507) (xy 298.589708 -66.968216)
			(xy 298.612346 -66.918643) (xy 298.64181 -66.872796) (xy 298.677498 -66.831608) (xy 298.718684 -66.795918)
			(xy 298.76453 -66.766453) (xy 298.814103 -66.743812) (xy 298.866394 -66.728457) (xy 298.920337 -66.720699)
			(xy 298.947586 -66.720212) (xy 298.974956 -66.720683) (xy 299.029135 -66.728499) (xy 299.081638 -66.743987)
			(xy 299.131385 -66.766828) (xy 299.177352 -66.796551) (xy 299.198284 -66.814192) (xy 299.198538 -66.814446)
			(xy 299.205634 -66.820018) (xy 299.222544 -66.826272) (xy 299.231558 -66.826638) (xy 299.298614 -66.826638)
			(xy 299.307631 -66.82628) (xy 299.324547 -66.820032) (xy 299.331634 -66.814446) (xy 299.331634 -66.814192)
			(xy 299.331888 -66.814192) (xy 299.352813 -66.796544) (xy 299.398788 -66.766834) (xy 299.448537 -66.744)
			(xy 299.501039 -66.728511) (xy 299.555216 -66.720685) (xy 299.582586 -66.720212) (xy 299.609841 -66.720634)
			(xy 299.663796 -66.72839) (xy 299.716099 -66.743745) (xy 299.765683 -66.766388) (xy 299.811541 -66.795857)
			(xy 299.852737 -66.831553) (xy 299.888434 -66.872748) (xy 299.917905 -66.918605) (xy 299.94055 -66.968188)
			(xy 299.955907 -67.02049) (xy 299.963665 -67.074445) (xy 299.963665 -67.128955) (xy 299.955907 -67.18291)
			(xy 299.94055 -67.235212) (xy 299.917905 -67.284795) (xy 299.888434 -67.330652) (xy 299.852737 -67.371847)
			(xy 299.811541 -67.407543) (xy 299.765683 -67.437012) (xy 299.716099 -67.459655) (xy 299.663796 -67.47501)
			(xy 299.609841 -67.482766) (xy 299.582586 -67.483228) (xy 299.555215 -67.482788) (xy 299.501034 -67.474966)
			(xy 299.44853 -67.459472) (xy 299.398783 -67.436624) (xy 299.352818 -67.406893) (xy 299.331888 -67.389248)
			(xy 299.331634 -67.388994) (xy 299.324542 -67.383415) (xy 299.307629 -67.377164) (xy 299.298614 -67.376802)
			(xy 299.231558 -67.376802) (xy 299.222544 -67.377187) (xy 299.205627 -67.383415) (xy 299.198538 -67.388994)
			(xy 299.198538 -67.389248) (xy 299.198284 -67.389248) (xy 299.177324 -67.406853) (xy 299.13136 -67.436572)
			(xy 299.08162 -67.459415) (xy 299.029125 -67.474914) (xy 298.974953 -67.48275) (xy 298.947586 -67.483228)
			(xy 298.920337 -67.482701) (xy 298.866394 -67.474943) (xy 298.814103 -67.459588) (xy 298.76453 -67.436947)
			(xy 298.718684 -67.407482) (xy 298.677498 -67.371792) (xy 298.64181 -67.330604) (xy 298.612346 -67.284757)
			(xy 298.589708 -67.235184) (xy 298.574354 -67.182893) (xy 298.566598 -67.128949) (xy 298.134844 -67.128949)
			(xy 298.117792 -67.488054) (xy 302.979072 -67.488054) (xy 302.983143 -67.432432) (xy 302.995269 -67.377995)
			(xy 303.015192 -67.325904) (xy 303.042488 -67.277269) (xy 303.076574 -67.233126) (xy 303.116723 -67.194417)
			(xy 303.162081 -67.161966) (xy 303.211681 -67.136465) (xy 303.264465 -67.118458) (xy 303.319308 -67.108328)
			(xy 303.375042 -67.106291) (xy 303.430479 -67.112391) (xy 303.484436 -67.126497) (xy 303.535765 -67.148309)
			(xy 303.583371 -67.177363) (xy 303.626239 -67.213038) (xy 303.663456 -67.254575) (xy 303.694229 -67.301088)
			(xy 303.717901 -67.351585) (xy 303.733969 -67.404992) (xy 303.742089 -67.460168) (xy 303.742598 -67.488054)
			(xy 303.742089 -67.51594) (xy 303.738904 -67.537584) (xy 304.27117 -67.537584) (xy 304.275241 -67.481962)
			(xy 304.287367 -67.427525) (xy 304.30729 -67.375434) (xy 304.334586 -67.326799) (xy 304.368672 -67.282656)
			(xy 304.408821 -67.243947) (xy 304.454179 -67.211496) (xy 304.503779 -67.185995) (xy 304.556563 -67.167988)
			(xy 304.611406 -67.157858) (xy 304.66714 -67.155821) (xy 304.722577 -67.161921) (xy 304.776534 -67.176027)
			(xy 304.827863 -67.197839) (xy 304.875469 -67.226893) (xy 304.918337 -67.262568) (xy 304.955554 -67.304105)
			(xy 304.986327 -67.350618) (xy 305.009999 -67.401115) (xy 305.026067 -67.454522) (xy 305.034187 -67.509698)
			(xy 305.034696 -67.537584) (xy 305.034187 -67.56547) (xy 305.030142 -67.592956) (xy 305.545234 -67.592956)
			(xy 305.549305 -67.537334) (xy 305.561431 -67.482897) (xy 305.581354 -67.430806) (xy 305.60865 -67.382171)
			(xy 305.642736 -67.338028) (xy 305.682885 -67.299319) (xy 305.728243 -67.266868) (xy 305.777843 -67.241367)
			(xy 305.830627 -67.22336) (xy 305.88547 -67.21323) (xy 305.941204 -67.211193) (xy 305.996641 -67.217293)
			(xy 306.050598 -67.231399) (xy 306.101927 -67.253211) (xy 306.149533 -67.282265) (xy 306.192401 -67.31794)
			(xy 306.229618 -67.359477) (xy 306.260391 -67.40599) (xy 306.284063 -67.456487) (xy 306.300131 -67.509894)
			(xy 306.308248 -67.565047) (xy 308.646616 -67.565047) (xy 308.646616 -67.510553) (xy 308.654371 -67.456612)
			(xy 308.669724 -67.404325) (xy 308.692361 -67.354754) (xy 308.721822 -67.30891) (xy 308.757507 -67.267724)
			(xy 308.79869 -67.232036) (xy 308.844533 -67.202572) (xy 308.894102 -67.179932) (xy 308.946389 -67.164576)
			(xy 309.000329 -67.156818) (xy 309.027576 -67.15633) (xy 309.054946 -67.156803) (xy 309.109125 -67.164618)
			(xy 309.161628 -67.180105) (xy 309.211375 -67.202945) (xy 309.257342 -67.232669) (xy 309.278274 -67.25031)
			(xy 309.278528 -67.250564) (xy 309.285626 -67.256134) (xy 309.302534 -67.262389) (xy 309.311548 -67.262756)
			(xy 309.378604 -67.262756) (xy 309.387622 -67.26241) (xy 309.404539 -67.256156) (xy 309.411624 -67.250564)
			(xy 309.411624 -67.25031) (xy 309.411878 -67.25031) (xy 309.432809 -67.232669) (xy 309.478782 -67.202957)
			(xy 309.52853 -67.180122) (xy 309.581031 -67.164631) (xy 309.635207 -67.156804) (xy 309.662576 -67.15633)
			(xy 309.689833 -67.156715) (xy 309.743792 -67.16447) (xy 309.796098 -67.179826) (xy 309.845686 -67.202469)
			(xy 309.891547 -67.23194) (xy 309.932746 -67.267637) (xy 309.968446 -67.308834) (xy 309.997919 -67.354693)
			(xy 310.020566 -67.40428) (xy 310.035925 -67.456585) (xy 310.043683 -67.510543) (xy 310.043683 -67.565057)
			(xy 310.035925 -67.619015) (xy 310.020566 -67.67132) (xy 309.997919 -67.720907) (xy 309.968446 -67.766766)
			(xy 309.932746 -67.807963) (xy 309.891547 -67.84366) (xy 309.845686 -67.873131) (xy 309.796098 -67.895774)
			(xy 309.743792 -67.91113) (xy 309.689833 -67.918885) (xy 309.662576 -67.919346) (xy 309.635205 -67.918907)
			(xy 309.581024 -67.911085) (xy 309.52852 -67.89559) (xy 309.478773 -67.872742) (xy 309.432808 -67.843011)
			(xy 309.411878 -67.825366) (xy 309.411624 -67.825112) (xy 309.404534 -67.819531) (xy 309.38762 -67.81328)
			(xy 309.378604 -67.81292) (xy 309.311548 -67.81292) (xy 309.302533 -67.813296) (xy 309.285616 -67.81953)
			(xy 309.278528 -67.825112) (xy 309.278528 -67.825366) (xy 309.278274 -67.825366) (xy 309.25732 -67.842979)
			(xy 309.211354 -67.872696) (xy 309.161612 -67.895537) (xy 309.109116 -67.911034) (xy 309.054944 -67.918869)
			(xy 309.027576 -67.919346) (xy 309.000329 -67.918782) (xy 308.946389 -67.911024) (xy 308.894102 -67.895668)
			(xy 308.844533 -67.873028) (xy 308.79869 -67.843564) (xy 308.757507 -67.807876) (xy 308.721822 -67.76669)
			(xy 308.692361 -67.720846) (xy 308.669724 -67.671275) (xy 308.654371 -67.618988) (xy 308.646616 -67.565047)
			(xy 306.308248 -67.565047) (xy 306.308251 -67.56507) (xy 306.30876 -67.592956) (xy 306.308251 -67.620842)
			(xy 306.300131 -67.676018) (xy 306.284063 -67.729425) (xy 306.260391 -67.779922) (xy 306.229618 -67.826435)
			(xy 306.192401 -67.867972) (xy 306.149533 -67.903647) (xy 306.101927 -67.932701) (xy 306.050598 -67.954513)
			(xy 305.996641 -67.968619) (xy 305.941204 -67.974719) (xy 305.88547 -67.972682) (xy 305.830627 -67.962552)
			(xy 305.777843 -67.944545) (xy 305.728243 -67.919044) (xy 305.682885 -67.886593) (xy 305.642736 -67.847884)
			(xy 305.60865 -67.803741) (xy 305.581354 -67.755106) (xy 305.561431 -67.703015) (xy 305.549305 -67.648578)
			(xy 305.545234 -67.592956) (xy 305.030142 -67.592956) (xy 305.026067 -67.620646) (xy 305.009999 -67.674053)
			(xy 304.986327 -67.72455) (xy 304.955554 -67.771063) (xy 304.918337 -67.8126) (xy 304.875469 -67.848275)
			(xy 304.827863 -67.877329) (xy 304.776534 -67.899141) (xy 304.722577 -67.913247) (xy 304.66714 -67.919347)
			(xy 304.611406 -67.91731) (xy 304.556563 -67.90718) (xy 304.503779 -67.889173) (xy 304.454179 -67.863672)
			(xy 304.408821 -67.831221) (xy 304.368672 -67.792512) (xy 304.334586 -67.748369) (xy 304.30729 -67.699734)
			(xy 304.287367 -67.647643) (xy 304.275241 -67.593206) (xy 304.27117 -67.537584) (xy 303.738904 -67.537584)
			(xy 303.733969 -67.571116) (xy 303.717901 -67.624523) (xy 303.694229 -67.67502) (xy 303.663456 -67.721533)
			(xy 303.626239 -67.76307) (xy 303.583371 -67.798745) (xy 303.535765 -67.827799) (xy 303.484436 -67.849611)
			(xy 303.430479 -67.863717) (xy 303.375042 -67.869817) (xy 303.319308 -67.86778) (xy 303.264465 -67.85765)
			(xy 303.211681 -67.839643) (xy 303.162081 -67.814142) (xy 303.116723 -67.781691) (xy 303.076574 -67.742982)
			(xy 303.042488 -67.698839) (xy 303.015192 -67.650204) (xy 302.995269 -67.598113) (xy 302.983143 -67.543676)
			(xy 302.979072 -67.488054) (xy 298.117792 -67.488054) (xy 298.065628 -68.586604) (xy 300.825154 -68.586604)
			(xy 300.825609 -68.559233) (xy 300.833428 -68.505053) (xy 300.848919 -68.452549) (xy 300.871763 -68.402803)
			(xy 300.901491 -68.356837) (xy 300.919134 -68.335906) (xy 300.919388 -68.335652) (xy 300.924958 -68.328554)
			(xy 300.931215 -68.311646) (xy 300.93158 -68.302632) (xy 300.93158 -68.235576) (xy 300.931239 -68.226557)
			(xy 300.924981 -68.20964) (xy 300.919388 -68.202556) (xy 300.919134 -68.202556) (xy 300.919134 -68.202302)
			(xy 300.901488 -68.181376) (xy 300.871776 -68.135402) (xy 300.848941 -68.085653) (xy 300.833451 -68.033151)
			(xy 300.825626 -67.978974) (xy 300.825154 -67.951604) (xy 300.825681 -67.924355) (xy 300.833436 -67.87041)
			(xy 300.848789 -67.818119) (xy 300.871427 -67.768544) (xy 300.900889 -67.722695) (xy 300.936576 -67.681506)
			(xy 300.977762 -67.645815) (xy 301.023607 -67.616347) (xy 301.073179 -67.593704) (xy 301.125469 -67.578345)
			(xy 301.179413 -67.570584) (xy 301.206662 -67.570096) (xy 301.232977 -67.570523) (xy 301.285108 -67.577767)
			(xy 301.335751 -67.592094) (xy 301.38395 -67.613234) (xy 301.428792 -67.640787) (xy 301.46943 -67.674232)
			(xy 301.487586 -67.693286) (xy 301.495113 -67.700681) (xy 301.514389 -67.70921) (xy 301.524924 -67.709796)
			(xy 301.5996 -67.709796) (xy 301.610151 -67.709281) (xy 301.629447 -67.700736) (xy 301.636938 -67.693286)
			(xy 301.655079 -67.674216) (xy 301.695712 -67.640761) (xy 301.740556 -67.613204) (xy 301.788759 -67.592068)
			(xy 301.839409 -67.577754) (xy 301.891545 -67.570533) (xy 301.917862 -67.570096) (xy 301.945231 -67.570585)
			(xy 301.999409 -67.578398) (xy 302.051912 -67.593881) (xy 302.101659 -67.616718) (xy 302.147627 -67.646437)
			(xy 302.16856 -67.664076) (xy 302.168814 -67.66433) (xy 302.17589 -67.669932) (xy 302.192815 -67.676168)
			(xy 302.201834 -67.676522) (xy 302.26889 -67.676522) (xy 302.277906 -67.676155) (xy 302.294823 -67.669914)
			(xy 302.30191 -67.66433) (xy 302.30191 -67.664076) (xy 302.302164 -67.664076) (xy 302.323096 -67.646437)
			(xy 302.369069 -67.616726) (xy 302.418817 -67.59389) (xy 302.471317 -67.578399) (xy 302.525493 -67.57057)
			(xy 302.552862 -67.570096) (xy 302.580114 -67.570591) (xy 302.634064 -67.578343) (xy 302.686362 -67.593694)
			(xy 302.735942 -67.616332) (xy 302.781795 -67.645797) (xy 302.822989 -67.681487) (xy 302.858683 -67.722677)
			(xy 302.888151 -67.768528) (xy 302.910794 -67.818106) (xy 302.92615 -67.870403) (xy 302.933907 -67.924352)
			(xy 302.93437 -67.951604) (xy 302.933914 -67.978975) (xy 302.926095 -68.033154) (xy 302.910604 -68.085658)
			(xy 302.88776 -68.135405) (xy 302.858033 -68.181371) (xy 302.84039 -68.202302) (xy 302.840136 -68.202556)
			(xy 302.834554 -68.209645) (xy 302.828306 -68.22656) (xy 302.827944 -68.235576) (xy 302.827944 -68.302632)
			(xy 302.828276 -68.311652) (xy 302.83454 -68.328569) (xy 302.840136 -68.335652) (xy 302.84039 -68.335652)
			(xy 302.84039 -68.335906) (xy 302.858044 -68.356826) (xy 302.887754 -68.402802) (xy 302.910587 -68.452553)
			(xy 302.926075 -68.505056) (xy 302.933898 -68.559234) (xy 302.93437 -68.586604) (xy 302.933948 -68.613859)
			(xy 302.92619 -68.667813) (xy 302.910831 -68.720114) (xy 302.894199 -68.75653) (xy 306.370228 -68.75653)
			(xy 306.370705 -68.72916) (xy 306.378519 -68.674981) (xy 306.394005 -68.622478) (xy 306.416845 -68.572731)
			(xy 306.446567 -68.526764) (xy 306.464208 -68.505832) (xy 306.464462 -68.505578) (xy 306.470071 -68.498507)
			(xy 306.476303 -68.481578) (xy 306.476654 -68.472558) (xy 306.476654 -68.405502) (xy 306.476306 -68.396484)
			(xy 306.470053 -68.379567) (xy 306.464462 -68.372482) (xy 306.464208 -68.372482) (xy 306.464208 -68.372228)
			(xy 306.44657 -68.351295) (xy 306.416858 -68.305323) (xy 306.394021 -68.255575) (xy 306.37853 -68.203075)
			(xy 306.370702 -68.148899) (xy 306.370228 -68.12153) (xy 306.370683 -68.094276) (xy 306.378437 -68.040323)
			(xy 306.393791 -67.988023) (xy 306.416433 -67.938441) (xy 306.445901 -67.892586) (xy 306.481596 -67.851392)
			(xy 306.52279 -67.815697) (xy 306.568646 -67.78623) (xy 306.618229 -67.763589) (xy 306.670529 -67.748236)
			(xy 306.724482 -67.740483) (xy 306.751736 -67.740022) (xy 306.779107 -67.740462) (xy 306.833288 -67.748285)
			(xy 306.885791 -67.76378) (xy 306.935538 -67.786628) (xy 306.981503 -67.816358) (xy 307.002434 -67.834002)
			(xy 307.002688 -67.834256) (xy 307.009769 -67.83985) (xy 307.02669 -67.846091) (xy 307.035708 -67.846448)
			(xy 307.102764 -67.846448) (xy 307.11178 -67.846085) (xy 307.128698 -67.839843) (xy 307.135784 -67.834256)
			(xy 307.135784 -67.834002) (xy 307.136038 -67.834002) (xy 307.156983 -67.816379) (xy 307.202952 -67.786665)
			(xy 307.252696 -67.763825) (xy 307.305194 -67.748331) (xy 307.359368 -67.740498) (xy 307.386736 -67.740022)
			(xy 307.413051 -67.740458) (xy 307.465181 -67.747699) (xy 307.515825 -67.762023) (xy 307.564024 -67.783162)
			(xy 307.608867 -67.810713) (xy 307.649505 -67.844158) (xy 307.66766 -67.863212) (xy 307.675193 -67.8706)
			(xy 307.694464 -67.879132) (xy 307.704998 -67.879722) (xy 307.779674 -67.879722) (xy 307.790223 -67.879186)
			(xy 307.809518 -67.870655) (xy 307.817012 -67.863212) (xy 307.835171 -67.84416) (xy 307.8758 -67.810702)
			(xy 307.920639 -67.783142) (xy 307.968839 -67.762003) (xy 308.019486 -67.747685) (xy 308.07162 -67.74046)
			(xy 308.097936 -67.740022) (xy 308.12519 -67.740444) (xy 308.179141 -67.748207) (xy 308.231439 -67.763568)
			(xy 308.281018 -67.786215) (xy 308.32687 -67.815688) (xy 308.36806 -67.851386) (xy 308.403751 -67.892583)
			(xy 308.433216 -67.93844) (xy 308.455855 -67.988023) (xy 308.471207 -68.040324) (xy 308.47896 -68.094276)
			(xy 308.479444 -68.12153) (xy 308.479009 -68.148902) (xy 308.471186 -68.203082) (xy 308.45569 -68.255586)
			(xy 308.432841 -68.305333) (xy 308.403109 -68.351298) (xy 308.385464 -68.372228) (xy 308.38521 -68.372482)
			(xy 308.379626 -68.37957) (xy 308.373377 -68.396486) (xy 308.373018 -68.405502) (xy 308.373018 -68.472558)
			(xy 308.373391 -68.481573) (xy 308.379627 -68.498491) (xy 308.38521 -68.505578) (xy 308.385464 -68.505578)
			(xy 308.385464 -68.505832) (xy 308.403079 -68.526784) (xy 308.432796 -68.57275) (xy 308.455637 -68.622493)
			(xy 308.471133 -68.674989) (xy 308.478967 -68.729162) (xy 308.479444 -68.75653) (xy 308.47895 -68.78378)
			(xy 308.471191 -68.837726) (xy 308.455833 -68.890018) (xy 308.433191 -68.939593) (xy 308.403725 -68.985442)
			(xy 308.368035 -69.026631) (xy 308.326847 -69.062322) (xy 308.280999 -69.091789) (xy 308.231424 -69.114431)
			(xy 308.179132 -69.129789) (xy 308.125186 -69.13755) (xy 308.097936 -69.138038) (xy 308.07162 -69.137633)
			(xy 308.019488 -69.130388) (xy 307.968843 -69.116058) (xy 307.920644 -69.094914) (xy 307.875802 -69.067356)
			(xy 307.835166 -69.033905) (xy 307.817012 -69.014848) (xy 307.809481 -69.007457) (xy 307.790208 -68.998925)
			(xy 307.779674 -68.998338) (xy 307.704998 -68.998338) (xy 307.694445 -68.998841) (xy 307.675149 -69.007393)
			(xy 307.66766 -69.014848) (xy 307.649526 -69.033925) (xy 307.608891 -69.067378) (xy 307.564046 -69.094933)
			(xy 307.515841 -69.116068) (xy 307.46519 -69.130381) (xy 307.413053 -69.137602) (xy 307.386736 -69.138038)
			(xy 307.359366 -69.137566) (xy 307.305186 -69.129752) (xy 307.252683 -69.114265) (xy 307.202936 -69.091424)
			(xy 307.156969 -69.0617) (xy 307.136038 -69.044058) (xy 307.135784 -69.043804) (xy 307.128706 -69.038205)
			(xy 307.111783 -69.031966) (xy 307.102764 -69.031612) (xy 307.035708 -69.031612) (xy 307.026691 -69.03197)
			(xy 307.009774 -69.038217) (xy 307.002688 -69.043804) (xy 307.002688 -69.044058) (xy 307.002434 -69.044058)
			(xy 306.981495 -69.061688) (xy 306.935524 -69.091403) (xy 306.885779 -69.114241) (xy 306.83328 -69.129734)
			(xy 306.779105 -69.137564) (xy 306.751736 -69.138038) (xy 306.724485 -69.137511) (xy 306.670538 -69.12976)
			(xy 306.618243 -69.11441) (xy 306.568665 -69.091774) (xy 306.522814 -69.062312) (xy 306.481621 -69.026625)
			(xy 306.445927 -68.985439) (xy 306.416458 -68.939593) (xy 306.393813 -68.890018) (xy 306.378454 -68.837726)
			(xy 306.370693 -68.783781) (xy 306.370228 -68.75653) (xy 302.894199 -68.75653) (xy 302.888186 -68.769697)
			(xy 302.858714 -68.815552) (xy 302.823015 -68.856745) (xy 302.781818 -68.892439) (xy 302.73596 -68.921906)
			(xy 302.686375 -68.944546) (xy 302.634072 -68.959899) (xy 302.580117 -68.967651) (xy 302.552862 -68.968112)
			(xy 302.525493 -68.967607) (xy 302.471316 -68.959798) (xy 302.418813 -68.944318) (xy 302.369066 -68.921485)
			(xy 302.323097 -68.891769) (xy 302.302164 -68.874132) (xy 302.30191 -68.873878) (xy 302.294827 -68.868287)
			(xy 302.277907 -68.862044) (xy 302.26889 -68.861686) (xy 302.201834 -68.861686) (xy 302.192819 -68.862062)
			(xy 302.175902 -68.868297) (xy 302.168814 -68.873878) (xy 302.168814 -68.874132) (xy 302.16856 -68.874132)
			(xy 302.14762 -68.891761) (xy 302.101649 -68.921474) (xy 302.051903 -68.944311) (xy 301.999405 -68.959804)
			(xy 301.945231 -68.967636) (xy 301.917862 -68.968112) (xy 301.891547 -68.967666) (xy 301.839418 -68.960426)
			(xy 301.788775 -68.946103) (xy 301.740576 -68.924966) (xy 301.695733 -68.897417) (xy 301.655094 -68.863975)
			(xy 301.636938 -68.844922) (xy 301.629401 -68.837538) (xy 301.610133 -68.829003) (xy 301.5996 -68.828412)
			(xy 301.524924 -68.828412) (xy 301.514374 -68.828937) (xy 301.495078 -68.837475) (xy 301.487586 -68.844922)
			(xy 301.469435 -68.863982) (xy 301.428803 -68.897437) (xy 301.383962 -68.924995) (xy 301.335761 -68.946133)
			(xy 301.285113 -68.96045) (xy 301.232978 -68.967674) (xy 301.206662 -68.968112) (xy 301.17941 -68.967658)
			(xy 301.125461 -68.959896) (xy 301.073166 -68.944536) (xy 301.023589 -68.921891) (xy 300.977739 -68.892421)
			(xy 300.936549 -68.856726) (xy 300.900859 -68.815534) (xy 300.871393 -68.769681) (xy 300.848752 -68.720102)
			(xy 300.833397 -68.667805) (xy 300.82564 -68.613856) (xy 300.825154 -68.586604) (xy 298.065628 -68.586604)
			(xy 298.015406 -69.64426) (xy 298.014239 -69.666429) (xy 298.010172 -69.710642) (xy 298.007278 -69.732652)
			(xy 298.0055 -69.745606) (xy 298.00169 -69.771514) (xy 298.00169 -69.771768) (xy 298.000928 -69.775832)
			(xy 298.000928 -69.77634) (xy 297.748646 -71.555864) (xy 303.394362 -71.555864) (xy 303.398433 -71.500242)
			(xy 303.410559 -71.445805) (xy 303.430482 -71.393714) (xy 303.457778 -71.345079) (xy 303.491864 -71.300936)
			(xy 303.532013 -71.262227) (xy 303.577371 -71.229776) (xy 303.626971 -71.204275) (xy 303.679755 -71.186268)
			(xy 303.734598 -71.176138) (xy 303.790332 -71.174101) (xy 303.845769 -71.180201) (xy 303.899726 -71.194307)
			(xy 303.951055 -71.216119) (xy 303.998661 -71.245173) (xy 304.041529 -71.280848) (xy 304.078746 -71.322385)
			(xy 304.109519 -71.368898) (xy 304.133191 -71.419395) (xy 304.149259 -71.472802) (xy 304.157379 -71.527978)
			(xy 304.157888 -71.555864) (xy 304.157379 -71.58375) (xy 304.15154 -71.623428) (xy 304.903376 -71.623428)
			(xy 304.907447 -71.567806) (xy 304.919573 -71.513369) (xy 304.939496 -71.461278) (xy 304.966792 -71.412643)
			(xy 305.000878 -71.3685) (xy 305.041027 -71.329791) (xy 305.086385 -71.29734) (xy 305.135985 -71.271839)
			(xy 305.188769 -71.253832) (xy 305.243612 -71.243702) (xy 305.299346 -71.241665) (xy 305.354783 -71.247765)
			(xy 305.40874 -71.261871) (xy 305.460069 -71.283683) (xy 305.507675 -71.312737) (xy 305.550543 -71.348412)
			(xy 305.58776 -71.389949) (xy 305.618533 -71.436462) (xy 305.642205 -71.486959) (xy 305.658273 -71.540366)
			(xy 305.666393 -71.595542) (xy 305.666902 -71.623428) (xy 305.666393 -71.651314) (xy 305.658273 -71.70649)
			(xy 305.642205 -71.759897) (xy 305.618533 -71.810394) (xy 305.58776 -71.856907) (xy 305.550543 -71.898444)
			(xy 305.507675 -71.934119) (xy 305.460069 -71.963173) (xy 305.40874 -71.984985) (xy 305.354783 -71.999091)
			(xy 305.299346 -72.005191) (xy 305.243612 -72.003154) (xy 305.188769 -71.993024) (xy 305.135985 -71.975017)
			(xy 305.086385 -71.949516) (xy 305.041027 -71.917065) (xy 305.000878 -71.878356) (xy 304.966792 -71.834213)
			(xy 304.939496 -71.785578) (xy 304.919573 -71.733487) (xy 304.907447 -71.67905) (xy 304.903376 -71.623428)
			(xy 304.15154 -71.623428) (xy 304.149259 -71.638926) (xy 304.133191 -71.692333) (xy 304.109519 -71.74283)
			(xy 304.078746 -71.789343) (xy 304.041529 -71.83088) (xy 303.998661 -71.866555) (xy 303.951055 -71.895609)
			(xy 303.899726 -71.917421) (xy 303.845769 -71.931527) (xy 303.790332 -71.937627) (xy 303.734598 -71.93559)
			(xy 303.679755 -71.92546) (xy 303.626971 -71.907453) (xy 303.577371 -71.881952) (xy 303.532013 -71.849501)
			(xy 303.491864 -71.810792) (xy 303.457778 -71.766649) (xy 303.430482 -71.718014) (xy 303.410559 -71.665923)
			(xy 303.398433 -71.611486) (xy 303.394362 -71.555864) (xy 297.748646 -71.555864) (xy 296.912077 -77.456792)
			(xy 297.701968 -77.456792) (xy 297.706039 -77.40117) (xy 297.718165 -77.346733) (xy 297.738088 -77.294642)
			(xy 297.765384 -77.246007) (xy 297.79947 -77.201864) (xy 297.839619 -77.163155) (xy 297.884977 -77.130704)
			(xy 297.934577 -77.105203) (xy 297.987361 -77.087196) (xy 298.042204 -77.077066) (xy 298.097938 -77.075029)
			(xy 298.153375 -77.081129) (xy 298.207332 -77.095235) (xy 298.258661 -77.117047) (xy 298.306267 -77.146101)
			(xy 298.349135 -77.181776) (xy 298.386352 -77.223313) (xy 298.417125 -77.269826) (xy 298.440797 -77.320323)
			(xy 298.456865 -77.37373) (xy 298.464985 -77.428906) (xy 298.465494 -77.456792) (xy 298.464985 -77.484678)
			(xy 298.456865 -77.539854) (xy 298.440797 -77.593261) (xy 298.417125 -77.643758) (xy 298.386352 -77.690271)
			(xy 298.349135 -77.731808) (xy 298.306267 -77.767483) (xy 298.258661 -77.796537) (xy 298.210591 -77.816964)
			(xy 299.312836 -77.816964) (xy 299.316907 -77.761342) (xy 299.329033 -77.706905) (xy 299.348956 -77.654814)
			(xy 299.376252 -77.606179) (xy 299.410338 -77.562036) (xy 299.450487 -77.523327) (xy 299.495845 -77.490876)
			(xy 299.545445 -77.465375) (xy 299.598229 -77.447368) (xy 299.653072 -77.437238) (xy 299.708806 -77.435201)
			(xy 299.764243 -77.441301) (xy 299.8182 -77.455407) (xy 299.869529 -77.477219) (xy 299.917135 -77.506273)
			(xy 299.960003 -77.541948) (xy 299.99722 -77.583485) (xy 300.027993 -77.629998) (xy 300.051665 -77.680495)
			(xy 300.067733 -77.733902) (xy 300.075853 -77.789078) (xy 300.076362 -77.816964) (xy 300.075853 -77.84485)
			(xy 300.067733 -77.900026) (xy 300.051665 -77.953433) (xy 300.027993 -78.00393) (xy 299.99722 -78.050443)
			(xy 299.960003 -78.09198) (xy 299.917135 -78.127655) (xy 299.869529 -78.156709) (xy 299.8182 -78.178521)
			(xy 299.764243 -78.192627) (xy 299.708806 -78.198727) (xy 299.653072 -78.19669) (xy 299.598229 -78.18656)
			(xy 299.545445 -78.168553) (xy 299.495845 -78.143052) (xy 299.450487 -78.110601) (xy 299.410338 -78.071892)
			(xy 299.376252 -78.027749) (xy 299.348956 -77.979114) (xy 299.329033 -77.927023) (xy 299.316907 -77.872586)
			(xy 299.312836 -77.816964) (xy 298.210591 -77.816964) (xy 298.207332 -77.818349) (xy 298.153375 -77.832455)
			(xy 298.097938 -77.838555) (xy 298.042204 -77.836518) (xy 297.987361 -77.826388) (xy 297.934577 -77.808381)
			(xy 297.884977 -77.78288) (xy 297.839619 -77.750429) (xy 297.79947 -77.71172) (xy 297.765384 -77.667577)
			(xy 297.738088 -77.618942) (xy 297.718165 -77.566851) (xy 297.706039 -77.512414) (xy 297.701968 -77.456792)
			(xy 296.912077 -77.456792) (xy 296.72544 -78.773274) (xy 299.771306 -78.773274) (xy 299.775377 -78.717652)
			(xy 299.787503 -78.663215) (xy 299.807426 -78.611124) (xy 299.834722 -78.562489) (xy 299.868808 -78.518346)
			(xy 299.908957 -78.479637) (xy 299.954315 -78.447186) (xy 300.003915 -78.421685) (xy 300.056699 -78.403678)
			(xy 300.111542 -78.393548) (xy 300.167276 -78.391511) (xy 300.222713 -78.397611) (xy 300.27667 -78.411717)
			(xy 300.327999 -78.433529) (xy 300.375605 -78.462583) (xy 300.418473 -78.498258) (xy 300.45569 -78.539795)
			(xy 300.486463 -78.586308) (xy 300.510135 -78.636805) (xy 300.526203 -78.690212) (xy 300.534323 -78.745388)
			(xy 300.534832 -78.773274) (xy 300.534323 -78.80116) (xy 300.526203 -78.856336) (xy 300.510135 -78.909743)
			(xy 300.486463 -78.96024) (xy 300.45569 -79.006753) (xy 300.418473 -79.04829) (xy 300.375605 -79.083965)
			(xy 300.327999 -79.113019) (xy 300.27667 -79.134831) (xy 300.222713 -79.148937) (xy 300.167276 -79.155037)
			(xy 300.111542 -79.153) (xy 300.056699 -79.14287) (xy 300.003915 -79.124863) (xy 299.954315 -79.099362)
			(xy 299.908957 -79.066911) (xy 299.868808 -79.028202) (xy 299.834722 -78.984059) (xy 299.807426 -78.935424)
			(xy 299.787503 -78.883333) (xy 299.775377 -78.828896) (xy 299.771306 -78.773274) (xy 296.72544 -78.773274)
			(xy 296.651189 -79.297022) (xy 298.841412 -79.297022) (xy 298.845483 -79.2414) (xy 298.857609 -79.186963)
			(xy 298.877532 -79.134872) (xy 298.904828 -79.086237) (xy 298.938914 -79.042094) (xy 298.979063 -79.003385)
			(xy 299.024421 -78.970934) (xy 299.074021 -78.945433) (xy 299.126805 -78.927426) (xy 299.181648 -78.917296)
			(xy 299.237382 -78.915259) (xy 299.292819 -78.921359) (xy 299.346776 -78.935465) (xy 299.398105 -78.957277)
			(xy 299.445711 -78.986331) (xy 299.488579 -79.022006) (xy 299.525796 -79.063543) (xy 299.556569 -79.110056)
			(xy 299.580241 -79.160553) (xy 299.596309 -79.21396) (xy 299.604429 -79.269136) (xy 299.604938 -79.297022)
			(xy 299.604429 -79.324908) (xy 299.596309 -79.380084) (xy 299.580241 -79.433491) (xy 299.556569 -79.483988)
			(xy 299.525796 -79.530501) (xy 299.488579 -79.572038) (xy 299.445711 -79.607713) (xy 299.398105 -79.636767)
			(xy 299.346776 -79.658579) (xy 299.292819 -79.672685) (xy 299.237382 -79.678785) (xy 299.181648 -79.676748)
			(xy 299.126805 -79.666618) (xy 299.074021 -79.648611) (xy 299.024421 -79.62311) (xy 298.979063 -79.590659)
			(xy 298.938914 -79.55195) (xy 298.904828 -79.507807) (xy 298.877532 -79.459172) (xy 298.857609 -79.407081)
			(xy 298.845483 -79.352644) (xy 298.841412 -79.297022) (xy 296.651189 -79.297022) (xy 296.512337 -80.276446)
			(xy 299.688248 -80.276446) (xy 299.692319 -80.220824) (xy 299.704445 -80.166387) (xy 299.724368 -80.114296)
			(xy 299.751664 -80.065661) (xy 299.78575 -80.021518) (xy 299.825899 -79.982809) (xy 299.871257 -79.950358)
			(xy 299.920857 -79.924857) (xy 299.973641 -79.90685) (xy 300.028484 -79.89672) (xy 300.084218 -79.894683)
			(xy 300.139655 -79.900783) (xy 300.193612 -79.914889) (xy 300.244941 -79.936701) (xy 300.292547 -79.965755)
			(xy 300.335415 -80.00143) (xy 300.372632 -80.042967) (xy 300.403405 -80.08948) (xy 300.427077 -80.139977)
			(xy 300.443145 -80.193384) (xy 300.451265 -80.24856) (xy 300.451774 -80.276446) (xy 300.451265 -80.304332)
			(xy 300.443145 -80.359508) (xy 300.427077 -80.412915) (xy 300.403405 -80.463412) (xy 300.372632 -80.509925)
			(xy 300.335415 -80.551462) (xy 300.292547 -80.587137) (xy 300.244941 -80.616191) (xy 300.193612 -80.638003)
			(xy 300.139655 -80.652109) (xy 300.084218 -80.658209) (xy 300.028484 -80.656172) (xy 299.973641 -80.646042)
			(xy 299.920857 -80.628035) (xy 299.871257 -80.602534) (xy 299.825899 -80.570083) (xy 299.78575 -80.531374)
			(xy 299.751664 -80.487231) (xy 299.724368 -80.438596) (xy 299.704445 -80.386505) (xy 299.692319 -80.332068)
			(xy 299.688248 -80.276446) (xy 296.512337 -80.276446) (xy 296.40006 -81.068418) (xy 298.049948 -81.068418)
			(xy 298.054019 -81.012796) (xy 298.066145 -80.958359) (xy 298.086068 -80.906268) (xy 298.113364 -80.857633)
			(xy 298.14745 -80.81349) (xy 298.187599 -80.774781) (xy 298.232957 -80.74233) (xy 298.282557 -80.716829)
			(xy 298.335341 -80.698822) (xy 298.390184 -80.688692) (xy 298.445918 -80.686655) (xy 298.501355 -80.692755)
			(xy 298.555312 -80.706861) (xy 298.606641 -80.728673) (xy 298.654247 -80.757727) (xy 298.697115 -80.793402)
			(xy 298.734332 -80.834939) (xy 298.765105 -80.881452) (xy 298.788777 -80.931949) (xy 298.804845 -80.985356)
			(xy 298.812965 -81.040532) (xy 298.813474 -81.068418) (xy 298.812965 -81.096304) (xy 298.804845 -81.15148)
			(xy 298.788777 -81.204887) (xy 298.765105 -81.255384) (xy 298.734332 -81.301897) (xy 298.697115 -81.343434)
			(xy 298.654247 -81.379109) (xy 298.606641 -81.408163) (xy 298.555312 -81.429975) (xy 298.501355 -81.444081)
			(xy 298.445918 -81.450181) (xy 298.390184 -81.448144) (xy 298.335341 -81.438014) (xy 298.282557 -81.420007)
			(xy 298.232957 -81.394506) (xy 298.187599 -81.362055) (xy 298.14745 -81.323346) (xy 298.113364 -81.279203)
			(xy 298.086068 -81.230568) (xy 298.066145 -81.178477) (xy 298.054019 -81.12404) (xy 298.049948 -81.068418)
			(xy 296.40006 -81.068418) (xy 296.220913 -82.332068) (xy 301.91024 -82.332068) (xy 301.914311 -82.276446)
			(xy 301.926437 -82.222009) (xy 301.94636 -82.169918) (xy 301.973656 -82.121283) (xy 302.007742 -82.07714)
			(xy 302.047891 -82.038431) (xy 302.093249 -82.00598) (xy 302.142849 -81.980479) (xy 302.195633 -81.962472)
			(xy 302.250476 -81.952342) (xy 302.30621 -81.950305) (xy 302.361647 -81.956405) (xy 302.415604 -81.970511)
			(xy 302.466933 -81.992323) (xy 302.514539 -82.021377) (xy 302.557407 -82.057052) (xy 302.594624 -82.098589)
			(xy 302.625397 -82.145102) (xy 302.649069 -82.195599) (xy 302.665137 -82.249006) (xy 302.673257 -82.304182)
			(xy 302.673766 -82.332068) (xy 302.673257 -82.359954) (xy 302.665137 -82.41513) (xy 302.649069 -82.468537)
			(xy 302.625397 -82.519034) (xy 302.594624 -82.565547) (xy 302.557407 -82.607084) (xy 302.514539 -82.642759)
			(xy 302.466933 -82.671813) (xy 302.415604 -82.693625) (xy 302.361647 -82.707731) (xy 302.30621 -82.713831)
			(xy 302.250476 -82.711794) (xy 302.195633 -82.701664) (xy 302.142849 -82.683657) (xy 302.093249 -82.658156)
			(xy 302.047891 -82.625705) (xy 302.007742 -82.586996) (xy 301.973656 -82.542853) (xy 301.94636 -82.494218)
			(xy 301.926437 -82.442127) (xy 301.914311 -82.38769) (xy 301.91024 -82.332068) (xy 296.220913 -82.332068)
			(xy 295.780231 -85.44052) (xy 299.277276 -85.44052) (xy 299.281347 -85.384898) (xy 299.293473 -85.330461)
			(xy 299.313396 -85.27837) (xy 299.340692 -85.229735) (xy 299.374778 -85.185592) (xy 299.414927 -85.146883)
			(xy 299.460285 -85.114432) (xy 299.509885 -85.088931) (xy 299.562669 -85.070924) (xy 299.617512 -85.060794)
			(xy 299.673246 -85.058757) (xy 299.728683 -85.064857) (xy 299.78264 -85.078963) (xy 299.833969 -85.100775)
			(xy 299.881575 -85.129829) (xy 299.924443 -85.165504) (xy 299.96166 -85.207041) (xy 299.992433 -85.253554)
			(xy 300.016105 -85.304051) (xy 300.032173 -85.357458) (xy 300.040293 -85.412634) (xy 300.040802 -85.44052)
			(xy 300.040293 -85.468406) (xy 300.032173 -85.523582) (xy 300.016105 -85.576989) (xy 299.992433 -85.627486)
			(xy 299.96166 -85.673999) (xy 299.924443 -85.715536) (xy 299.881575 -85.751211) (xy 299.833969 -85.780265)
			(xy 299.78264 -85.802077) (xy 299.728683 -85.816183) (xy 299.673246 -85.822283) (xy 299.617512 -85.820246)
			(xy 299.562669 -85.810116) (xy 299.509885 -85.792109) (xy 299.460285 -85.766608) (xy 299.414927 -85.734157)
			(xy 299.374778 -85.695448) (xy 299.340692 -85.651305) (xy 299.313396 -85.60267) (xy 299.293473 -85.550579)
			(xy 299.281347 -85.496142) (xy 299.277276 -85.44052) (xy 295.780231 -85.44052) (xy 295.102534 -90.2208)
			(xy 295.10212 -90.229901) (xy 295.106988 -90.247444) (xy 295.117688 -90.262174) (xy 295.132866 -90.272229)
			(xy 295.14165 -90.274648) (xy 296.90441 -90.574114) (xy 296.91691 -90.575522) (xy 296.940726 -90.567511)
			(xy 296.949876 -90.558874) (xy 296.951654 -90.556842) (xy 301.480982 -84.657946) (xy 301.486202 -84.650538)
			(xy 301.491526 -84.633227) (xy 301.491396 -84.624164) (xy 301.490888 -84.61502) (xy 301.483522 -84.59851)
			(xy 301.47895 -84.593684) (xy 301.458575 -84.572133) (xy 301.424061 -84.523904) (xy 301.39741 -84.470923)
			(xy 301.379262 -84.414461) (xy 301.370053 -84.355875) (xy 301.369476 -84.326222) (xy 301.369476 -84.325968)
			(xy 301.369936 -84.29942) (xy 301.3773 -84.246838) (xy 301.391883 -84.195785) (xy 301.413402 -84.147246)
			(xy 301.441442 -84.102159) (xy 301.475462 -84.061394) (xy 301.514804 -84.025738) (xy 301.558709 -83.995881)
			(xy 301.606329 -83.972398) (xy 301.656745 -83.955743) (xy 301.708983 -83.946238) (xy 301.73549 -83.944714)
			(xy 301.750984 -83.94446) (xy 301.751238 -83.94446) (xy 301.775488 -83.944835) (xy 301.823597 -83.95098)
			(xy 301.870538 -83.963178) (xy 301.915552 -83.981233) (xy 301.936912 -83.99272) (xy 301.937166 -83.99272)
			(xy 301.945272 -83.996854) (xy 301.96323 -83.999723) (xy 301.972218 -83.998308) (xy 301.980854 -83.99653)
			(xy 301.996094 -83.986878) (xy 303.019714 -82.653886) (xy 303.152302 -82.48142) (xy 303.361598 -82.208624)
			(xy 303.36363 -82.201258) (xy 303.364392 -82.198464) (xy 303.372692 -82.169342) (xy 303.397225 -82.113982)
			(xy 303.4302 -82.063196) (xy 303.470788 -82.01826) (xy 303.517968 -81.980305) (xy 303.54397 -81.964784)
			(xy 303.55286 -81.959704) (xy 304.79873 -80.336898) (xy 304.803856 -80.329717) (xy 304.809317 -80.312954)
			(xy 304.809398 -80.304132) (xy 304.80889 -80.295242) (xy 304.802286 -80.278732) (xy 304.796698 -80.272382)
			(xy 304.7788 -80.251363) (xy 304.748618 -80.20514) (xy 304.725412 -80.155049) (xy 304.709667 -80.102137)
			(xy 304.701711 -80.047508) (xy 304.701194 -80.019906) (xy 304.701657 -79.992653) (xy 304.709413 -79.938701)
			(xy 304.724769 -79.886403) (xy 304.747411 -79.836822) (xy 304.776879 -79.790969) (xy 304.812572 -79.749775)
			(xy 304.853765 -79.714081) (xy 304.899619 -79.684613) (xy 304.949199 -79.66197) (xy 305.001498 -79.646614)
			(xy 305.055449 -79.638857) (xy 305.082702 -79.638398) (xy 305.082956 -79.638398) (xy 305.111384 -79.638943)
			(xy 305.167606 -79.647426) (xy 305.221944 -79.664165) (xy 305.247802 -79.67599) (xy 305.258216 -79.679546)
			(xy 305.275234 -79.68361) (xy 305.286965 -79.683083) (xy 305.308021 -79.672752) (xy 305.31562 -79.663798)
			(xy 316.329822 -65.318894) (xy 316.33367 -65.313519) (xy 316.338681 -65.301291) (xy 316.339728 -65.294764)
			(xy 316.341506 -65.28181) (xy 316.336172 -65.26911) (xy 316.327174 -65.246089) (xy 316.314516 -65.19831)
			(xy 316.308127 -65.149298) (xy 316.307724 -65.124584) (xy 316.307724 -65.115948) (xy 316.308752 -65.089075)
			(xy 316.317427 -65.036003) (xy 316.33347 -64.984675) (xy 316.356562 -64.936109) (xy 316.386247 -64.891268)
			(xy 316.421935 -64.85104) (xy 316.462919 -64.816223) (xy 316.508387 -64.787508) (xy 316.557437 -64.765462)
			(xy 316.609097 -64.750525) (xy 316.662344 -64.74299) (xy 316.689232 -64.742568) (xy 316.693042 -64.742568)
			(xy 316.704377 -64.742742) (xy 316.726998 -64.744265) (xy 316.738254 -64.745616) (xy 316.739016 -64.745616)
			(xy 316.745536 -64.746265) (xy 316.758525 -64.744589) (xy 316.76467 -64.742314) (xy 316.770004 -64.740028)
			(xy 316.780418 -64.732154) (xy 317.212726 -64.169036) (xy 317.319406 -64.030098) (xy 317.696088 -63.538862)
			(xy 317.700152 -63.53302) (xy 317.73368 -63.473584) (xy 317.95085 -63.088012) (xy 317.983108 -63.0301)
			(xy 317.987737 -63.019622) (xy 317.988004 -62.996739) (xy 317.983616 -62.986158) (xy 317.98006 -62.978538)
			(xy 317.97371 -62.972188) (xy 317.95456 -62.951826) (xy 317.921819 -62.906523) (xy 317.89604 -62.856926)
			(xy 317.877773 -62.804099) (xy 317.867411 -62.749172) (xy 317.865174 -62.693321) (xy 317.871111 -62.637741)
			(xy 317.885095 -62.583622) (xy 317.906825 -62.532123) (xy 317.935838 -62.484346) (xy 317.971512 -62.441314)
			(xy 318.013084 -62.403949) (xy 318.059662 -62.373049) (xy 318.110251 -62.349276) (xy 318.163768 -62.33314)
			(xy 318.219066 -62.324986) (xy 318.247014 -62.324488) (xy 318.24803 -62.324488) (xy 318.250062 -62.324488)
			(xy 318.267588 -62.324996) (xy 318.284317 -62.326077) (xy 318.317511 -62.330784) (xy 318.333882 -62.334394)
			(xy 318.344687 -62.33634) (xy 318.366174 -62.331946) (xy 318.383912 -62.319046) (xy 318.389762 -62.309756)
			(xy 318.424814 -62.247526) (xy 318.444626 -62.21222) (xy 318.448302 -62.205118) (xy 318.451524 -62.189465)
			(xy 318.450976 -62.181486) (xy 318.450214 -62.175898) (xy 318.44869 -62.171326) (xy 318.44168 -62.14902)
			(xy 318.432509 -62.103172) (xy 318.430402 -62.079886) (xy 318.429386 -62.055502) (xy 318.429386 -62.051438)
			(xy 318.429881 -62.023715) (xy 318.437903 -61.968853) (xy 318.453785 -61.915731) (xy 318.477191 -61.865468)
			(xy 318.507628 -61.819123) (xy 318.544454 -61.777674) (xy 318.586894 -61.741994) (xy 318.634052 -61.712835)
			(xy 318.684936 -61.690811) (xy 318.71158 -61.683138) (xy 318.711834 -61.683138) (xy 318.714628 -61.682376)
			(xy 318.723445 -61.678981) (xy 318.738029 -61.666995) (xy 318.743076 -61.659008) (xy 318.77127 -61.60262)
			(xy 318.774826 -61.592968) (xy 318.830706 -61.382148) (xy 318.840612 -61.34481) (xy 319.01638 -60.682124)
			(xy 319.015364 -60.672726) (xy 319.01384 -60.654184) (xy 319.013586 -60.650374) (xy 319.013078 -60.63361)
			(xy 319.013078 -60.633102) (xy 319.013689 -60.603382) (xy 319.022983 -60.544671) (xy 319.041254 -60.488107)
			(xy 319.068061 -60.435053) (xy 319.08496 -60.410598) (xy 319.087592 -60.406752) (xy 319.091552 -60.398315)
			(xy 319.092834 -60.393834) (xy 319.134744 -60.235846) (xy 319.195958 -60.004706) (xy 319.197736 -59.991752)
			(xy 319.197736 -58.819288) (xy 319.19759 -58.813071) (xy 319.194635 -58.800994) (xy 319.191894 -58.795412)
			(xy 319.175892 -58.765186) (xy 319.17132 -58.761884) (xy 319.168526 -58.760106) (xy 319.16624 -58.758328)
			(xy 319.145726 -58.742873) (xy 319.108636 -58.707345) (xy 319.076646 -58.667163) (xy 319.050333 -58.623053)
			(xy 319.030175 -58.575814) (xy 319.016533 -58.526297) (xy 319.009656 -58.475399) (xy 319.009268 -58.449718)
			(xy 319.009716 -58.423574) (xy 319.016889 -58.37178) (xy 319.031063 -58.32145) (xy 319.051972 -58.273524)
			(xy 319.079224 -58.228899) (xy 319.112312 -58.188411) (xy 319.131188 -58.170318) (xy 319.131696 -58.16981)
			(xy 319.13195 -58.169556) (xy 319.135977 -58.16553) (xy 319.142266 -58.15604) (xy 319.144396 -58.15076)
			(xy 319.146428 -58.145426) (xy 319.148206 -58.133742) (xy 318.859154 -55.372762) (xy 318.77762 -54.592474)
			(xy 318.776866 -54.586971) (xy 318.77327 -54.576465) (xy 318.770508 -54.571646) (xy 318.767564 -54.566962)
			(xy 318.759999 -54.558893) (xy 318.755522 -54.555644) (xy 318.755268 -54.555644) (xy 318.733345 -54.540386)
			(xy 318.693585 -54.504721) (xy 318.659187 -54.46386) (xy 318.630823 -54.418602) (xy 318.609046 -54.369831)
			(xy 318.594282 -54.3185) (xy 318.58682 -54.265612) (xy 318.586358 -54.238906) (xy 318.586436 -54.226168)
			(xy 318.588089 -54.200747) (xy 318.58966 -54.188106) (xy 318.594295 -54.158019) (xy 318.611878 -54.09974)
			(xy 318.638507 -54.045) (xy 318.673505 -53.995194) (xy 318.694308 -53.972968) (xy 318.698372 -53.968904)
			(xy 318.70396 -53.959506) (xy 318.705992 -53.954172) (xy 318.707695 -53.948887) (xy 318.708985 -53.937862)
			(xy 318.708532 -53.932328) (xy 318.703198 -53.881528) (xy 318.550036 -52.416964) (xy 318.479424 -51.742086)
			(xy 318.477261 -51.731466) (xy 318.465408 -51.713344) (xy 318.447142 -51.701715) (xy 318.436498 -51.699668)
			(xy 318.434466 -51.699414) (xy 318.40592 -51.695727) (xy 318.350312 -51.680876) (xy 318.297563 -51.657848)
			(xy 318.248867 -51.627163) (xy 318.205329 -51.589517) (xy 318.167934 -51.545763) (xy 318.152272 -51.521614)
			(xy 318.151256 -51.520344) (xy 318.144523 -51.511333) (xy 318.125285 -51.499728) (xy 318.114172 -51.497992)
			(xy 318.074548 -51.493928) (xy 318.07404 -51.493928) (xy 318.050418 -51.491388) (xy 318.04991 -51.491388)
			(xy 318.034162 -51.489864) (xy 318.022528 -51.489268) (xy 318.000701 -51.497338) (xy 317.992252 -51.505358)
			(xy 317.991998 -51.505612) (xy 317.973903 -51.524179) (xy 317.933567 -51.556748) (xy 317.889193 -51.583558)
			(xy 317.8416 -51.604116) (xy 317.791661 -51.618043) (xy 317.740298 -51.625083) (xy 317.714376 -51.6255)
			(xy 317.687126 -51.625013) (xy 317.633181 -51.617253) (xy 317.58089 -51.601896) (xy 317.531316 -51.579253)
			(xy 317.485469 -51.549786) (xy 317.444283 -51.514095) (xy 317.408595 -51.472905) (xy 317.379131 -51.427056)
			(xy 317.356493 -51.37748) (xy 317.34114 -51.325187) (xy 317.333385 -51.271242) (xy 317.332868 -51.243992)
			(xy 317.333293 -51.218481) (xy 317.340089 -51.167914) (xy 317.353559 -51.118702) (xy 317.373463 -51.071722)
			(xy 317.399446 -51.027812) (xy 317.41491 -51.007518) (xy 317.41745 -51.00447) (xy 317.418466 -51.002946)
			(xy 317.421768 -50.996342) (xy 317.424114 -50.99112) (xy 317.426682 -50.979966) (xy 317.426848 -50.974244)
			(xy 317.426848 -50.94224) (xy 317.438024 -50.94224) (xy 317.438024 -50.89144) (xy 317.437691 -50.882836)
			(xy 317.431982 -50.866602) (xy 317.426848 -50.85969) (xy 317.425578 -50.858166) (xy 317.408184 -50.83729)
			(xy 317.378864 -50.79154) (xy 317.356335 -50.742092) (xy 317.341052 -50.689947) (xy 317.333326 -50.636161)
			(xy 317.332868 -50.608992) (xy 317.333354 -50.581741) (xy 317.341112 -50.527792) (xy 317.356467 -50.475497)
			(xy 317.379108 -50.425919) (xy 317.408575 -50.380068) (xy 317.444266 -50.338877) (xy 317.485456 -50.303184)
			(xy 317.531305 -50.273716) (xy 317.580882 -50.251073) (xy 317.633177 -50.235715) (xy 317.687125 -50.227955)
			(xy 317.714376 -50.227484) (xy 317.742415 -50.227985) (xy 317.797887 -50.236207) (xy 317.851557 -50.252463)
			(xy 317.902269 -50.276403) (xy 317.948928 -50.30751) (xy 317.99053 -50.345113) (xy 318.008762 -50.366422)
			(xy 318.009016 -50.366676) (xy 318.015874 -50.374804) (xy 318.039496 -50.386488) (xy 318.045846 -50.389536)
			(xy 318.050737 -50.391615) (xy 318.061109 -50.393922) (xy 318.06642 -50.394108) (xy 318.123824 -50.394108)
			(xy 318.129199 -50.393941) (xy 318.139698 -50.391628) (xy 318.144652 -50.389536) (xy 318.151002 -50.386488)
			(xy 318.164972 -50.379884) (xy 318.169388 -50.377589) (xy 318.177316 -50.371577) (xy 318.18072 -50.367946)
			(xy 318.181736 -50.366676) (xy 318.206882 -50.33899) (xy 318.22657 -50.319964) (xy 318.270427 -50.287192)
			(xy 318.294258 -50.273712) (xy 318.30264 -50.269394) (xy 318.30772 -50.2666) (xy 318.314832 -50.25263)
			(xy 318.318052 -50.245932) (xy 318.320878 -50.231347) (xy 318.32042 -50.223928) (xy 318.295782 -49.98847)
			(xy 318.293824 -49.976034) (xy 318.279707 -49.955229) (xy 318.268858 -49.948846) (xy 318.23152 -49.929288)
			(xy 318.193166 -49.908968) (xy 318.181901 -49.903955) (xy 318.157274 -49.904356) (xy 318.146176 -49.90973)
			(xy 318.11802 -49.92434) (xy 318.058066 -49.945046) (xy 317.995518 -49.955577) (xy 317.963804 -49.956212)
			(xy 317.938292 -49.955788) (xy 317.887723 -49.948994) (xy 317.838509 -49.935528) (xy 317.791527 -49.915629)
			(xy 317.747612 -49.889651) (xy 317.72733 -49.87417) (xy 317.724282 -49.87163) (xy 317.722758 -49.870614)
			(xy 317.716154 -49.867312) (xy 317.710932 -49.864966) (xy 317.699778 -49.862396) (xy 317.694056 -49.862232)
			(xy 317.662052 -49.862232) (xy 317.662052 -49.851056) (xy 317.611252 -49.851056) (xy 317.602648 -49.851389)
			(xy 317.586417 -49.857102) (xy 317.579502 -49.862232) (xy 317.577978 -49.863502) (xy 317.5571 -49.880892)
			(xy 317.511349 -49.910203) (xy 317.461901 -49.932722) (xy 317.409756 -49.947993) (xy 317.355971 -49.955707)
			(xy 317.328804 -49.956212) (xy 317.303292 -49.955788) (xy 317.252723 -49.948994) (xy 317.203509 -49.935528)
			(xy 317.156527 -49.915629) (xy 317.112612 -49.889651) (xy 317.09233 -49.87417) (xy 317.089282 -49.87163)
			(xy 317.087758 -49.870614) (xy 317.081154 -49.867312) (xy 317.075932 -49.864966) (xy 317.064778 -49.862396)
			(xy 317.059056 -49.862232) (xy 317.027052 -49.862232) (xy 317.027052 -49.851056) (xy 316.976252 -49.851056)
			(xy 316.967648 -49.851389) (xy 316.951417 -49.857102) (xy 316.944502 -49.862232) (xy 316.942978 -49.863502)
			(xy 316.9221 -49.880892) (xy 316.876349 -49.910203) (xy 316.826901 -49.932722) (xy 316.774756 -49.947993)
			(xy 316.720971 -49.955707) (xy 316.693804 -49.956212) (xy 316.666551 -49.955749) (xy 316.612599 -49.947992)
			(xy 316.5603 -49.932636) (xy 316.510719 -49.909994) (xy 316.464865 -49.880526) (xy 316.423671 -49.844832)
			(xy 316.387977 -49.803639) (xy 316.358508 -49.757785) (xy 316.335865 -49.708204) (xy 316.320509 -49.655905)
			(xy 316.312751 -49.601953) (xy 316.312751 -49.547447) (xy 316.320509 -49.493495) (xy 316.335865 -49.441196)
			(xy 316.358508 -49.391615) (xy 316.387977 -49.345761) (xy 316.423671 -49.304568) (xy 316.464865 -49.268874)
			(xy 316.510719 -49.239406) (xy 316.5603 -49.216764) (xy 316.612599 -49.201408) (xy 316.666551 -49.193651)
			(xy 316.693804 -49.193196) (xy 316.719315 -49.193621) (xy 316.769884 -49.200415) (xy 316.819097 -49.213883)
			(xy 316.866079 -49.233783) (xy 316.909993 -49.259762) (xy 316.930278 -49.275238) (xy 316.933326 -49.277778)
			(xy 316.93485 -49.278794) (xy 316.941454 -49.282096) (xy 316.946676 -49.284441) (xy 316.95783 -49.287009)
			(xy 316.963552 -49.287176) (xy 316.995556 -49.287176) (xy 316.995556 -49.298352) (xy 317.046356 -49.298352)
			(xy 317.054959 -49.298018) (xy 317.071189 -49.292304) (xy 317.078106 -49.287176) (xy 317.07963 -49.285906)
			(xy 317.100506 -49.26851) (xy 317.146254 -49.239188) (xy 317.195702 -49.216656) (xy 317.247848 -49.201372)
			(xy 317.301635 -49.193645) (xy 317.328804 -49.193196) (xy 317.354315 -49.193621) (xy 317.404884 -49.200415)
			(xy 317.454097 -49.213883) (xy 317.501079 -49.233783) (xy 317.544993 -49.259762) (xy 317.565278 -49.275238)
			(xy 317.568326 -49.277778) (xy 317.56985 -49.278794) (xy 317.576454 -49.282096) (xy 317.581676 -49.284441)
			(xy 317.59283 -49.287009) (xy 317.598552 -49.287176) (xy 317.630556 -49.287176) (xy 317.630556 -49.298352)
			(xy 317.681356 -49.298352) (xy 317.689959 -49.298018) (xy 317.706189 -49.292304) (xy 317.713106 -49.287176)
			(xy 317.71463 -49.285906) (xy 317.721996 -49.279302) (xy 317.723012 -49.278794) (xy 317.724282 -49.277778)
			(xy 317.72479 -49.27727) (xy 317.746888 -49.26076) (xy 317.778892 -49.240948) (xy 317.779146 -49.240948)
			(xy 317.7794 -49.240694) (xy 317.784202 -49.237842) (xy 317.792537 -49.230413) (xy 317.79591 -49.225962)
			(xy 317.799466 -49.221136) (xy 317.803784 -49.210468) (xy 317.815722 -49.13503) (xy 317.816339 -49.12437)
			(xy 317.809901 -49.104035) (xy 317.803276 -49.09566) (xy 311.977786 -42.736516) (xy 311.970596 -42.729965)
			(xy 311.952704 -42.722382) (xy 311.933274 -42.722037) (xy 311.915124 -42.728981) (xy 311.907682 -42.735246)
			(xy 311.904126 -42.738548) (xy 311.89803 -42.744136) (xy 311.889648 -42.768012) (xy 311.89168 -42.780712)
			(xy 311.893864 -42.79522) (xy 311.89628 -42.824462) (xy 311.896506 -42.839132) (xy 311.896506 -42.84091)
			(xy 311.89602 -42.868161) (xy 311.888262 -42.922108) (xy 311.872906 -42.974402) (xy 311.850263 -43.023978)
			(xy 311.820797 -43.069827) (xy 311.785105 -43.111016) (xy 311.743914 -43.146706) (xy 311.698064 -43.176171)
			(xy 311.648487 -43.198811) (xy 311.596192 -43.214165) (xy 311.542245 -43.221921) (xy 311.487743 -43.22192)
			(xy 311.433796 -43.214163) (xy 311.381502 -43.198807) (xy 311.331926 -43.176165) (xy 311.286076 -43.146699)
			(xy 311.244887 -43.111007) (xy 311.209196 -43.069817) (xy 311.179731 -43.023967) (xy 311.15709 -42.97439)
			(xy 311.141736 -42.922096) (xy 311.13398 -42.868149) (xy 311.13398 -42.813647) (xy 311.141737 -42.7597)
			(xy 311.157092 -42.707406) (xy 311.179733 -42.657829) (xy 311.209199 -42.61198) (xy 311.24489 -42.57079)
			(xy 311.28608 -42.535099) (xy 311.331929 -42.505633) (xy 311.381506 -42.482992) (xy 311.4338 -42.467637)
			(xy 311.487747 -42.45988) (xy 311.514998 -42.459402) (xy 311.538092 -42.459755) (xy 311.583938 -42.465362)
			(xy 311.606438 -42.470578) (xy 311.614058 -42.472356) (xy 311.629044 -42.471594) (xy 311.643014 -42.466514)
			(xy 311.654952 -42.45737) (xy 311.657492 -42.453814) (xy 311.69737 -42.39895) (xy 311.702953 -42.390615)
			(xy 311.707672 -42.371134) (xy 311.70452 -42.351338) (xy 311.699656 -42.342562) (xy 311.359804 -41.787064)
			(xy 311.098946 -41.360344) (xy 311.096372 -41.356348) (xy 311.089981 -41.349314) (xy 311.086246 -41.346374)
			(xy 311.07888 -41.340786) (xy 311.069736 -41.338246) (xy 311.043309 -41.33008) (xy 310.99296 -41.307184)
			(xy 310.946444 -41.27726) (xy 310.904735 -41.240933) (xy 310.868708 -41.198965) (xy 310.839116 -41.152236)
			(xy 310.82742 -41.127172) (xy 310.817265 -41.103354) (xy 310.802767 -41.053646) (xy 310.795144 -41.002432)
			(xy 310.7944 -40.97655) (xy 310.7944 -40.968422) (xy 310.794654 -40.953182) (xy 310.794654 -40.951404)
			(xy 310.795518 -40.938299) (xy 310.798825 -40.912241) (xy 310.801258 -40.899334) (xy 310.803036 -40.89019)
			(xy 310.801512 -40.881046) (xy 310.800539 -40.876408) (xy 310.797093 -40.867583) (xy 310.794654 -40.86352)
			(xy 310.65978 -40.643302) (xy 310.496966 -40.37711) (xy 310.493591 -40.371992) (xy 310.484866 -40.363383)
			(xy 310.479694 -40.360092) (xy 310.469026 -40.353742) (xy 310.462168 -40.353234) (xy 310.456326 -40.35298)
			(xy 310.427808 -40.350877) (xy 310.371831 -40.339206) (xy 310.318222 -40.319312) (xy 310.268182 -40.291642)
			(xy 310.222831 -40.256815) (xy 310.183184 -40.215611) (xy 310.150129 -40.168952) (xy 310.124407 -40.117883)
			(xy 310.106593 -40.063548) (xy 310.097086 -40.007163) (xy 310.096154 -39.978584) (xy 310.096154 -39.971472)
			(xy 310.096589 -39.946615) (xy 310.103114 -39.89733) (xy 310.115985 -39.84931) (xy 310.12511 -39.826184)
			(xy 310.12892 -39.816786) (xy 310.13146 -39.811452) (xy 310.133492 -39.79926) (xy 310.133238 -39.793418)
			(xy 310.132593 -39.787443) (xy 310.128873 -39.776018) (xy 310.125872 -39.770812) (xy 309.767986 -39.186104)
			(xy 309.75935 -39.180008) (xy 309.721091 -39.152733) (xy 309.649336 -39.092061) (xy 309.583593 -39.024922)
			(xy 309.55361 -38.988746) (xy 309.553102 -38.988238) (xy 309.5498 -38.984174) (xy 309.541164 -38.977316)
			(xy 309.517288 -38.965886) (xy 309.511963 -38.963423) (xy 309.500547 -38.960724) (xy 309.494682 -38.960552)
			(xy 309.426356 -38.961314) (xy 309.420412 -38.961508) (xy 309.408864 -38.964341) (xy 309.403496 -38.966902)
			(xy 309.403242 -38.966902) (xy 309.398321 -38.969658) (xy 309.389729 -38.976962) (xy 309.386224 -38.98138)
			(xy 309.38597 -38.981634) (xy 309.370165 -39.001752) (xy 309.334044 -39.037985) (xy 309.293405 -39.069066)
			(xy 309.248977 -39.094436) (xy 309.201557 -39.113642) (xy 309.151996 -39.126339) (xy 309.126636 -39.129716)
			(xy 309.118 -39.130732) (xy 309.081932 -39.132256) (xy 309.054447 -39.13178) (xy 309.000044 -39.123905)
			(xy 308.947332 -39.108312) (xy 308.8974 -39.085323) (xy 308.851279 -39.055414) (xy 308.809921 -39.019203)
			(xy 308.774183 -38.977436) (xy 308.759098 -38.954456) (xy 308.759098 -38.954202) (xy 308.756558 -38.950138)
			(xy 308.755796 -38.949122) (xy 308.751732 -38.945058) (xy 308.742842 -38.938454) (xy 308.723284 -38.926262)
			(xy 308.717957 -38.923221) (xy 308.706274 -38.919495) (xy 308.70017 -38.918896) (xy 308.629558 -38.914324)
			(xy 308.618719 -38.914113) (xy 308.59845 -38.921748) (xy 308.590442 -38.929056) (xy 308.586632 -38.932866)
			(xy 308.584854 -38.935152) (xy 308.584092 -38.936168) (xy 308.56588 -38.958791) (xy 308.523772 -38.998789)
			(xy 308.476095 -39.031951) (xy 308.423948 -39.057516) (xy 308.368532 -39.074892) (xy 308.311124 -39.083681)
			(xy 308.282086 -39.08425) (xy 308.281832 -39.08425) (xy 308.254575 -39.083789) (xy 308.200614 -39.076035)
			(xy 308.148307 -39.06068) (xy 308.098717 -39.038037) (xy 308.052855 -39.008567) (xy 308.011654 -38.972869)
			(xy 307.975953 -38.931671) (xy 307.946478 -38.885811) (xy 307.923831 -38.836223) (xy 307.908472 -38.783917)
			(xy 307.900713 -38.729957) (xy 307.900713 -38.675443) (xy 307.908472 -38.621483) (xy 307.923831 -38.569177)
			(xy 307.946478 -38.519589) (xy 307.975953 -38.473729) (xy 308.011654 -38.432531) (xy 308.052855 -38.396833)
			(xy 308.098717 -38.367363) (xy 308.148307 -38.34472) (xy 308.200614 -38.329365) (xy 308.254575 -38.321611)
			(xy 308.281832 -38.321234) (xy 308.309315 -38.321714) (xy 308.363713 -38.329597) (xy 308.416419 -38.345197)
			(xy 308.466344 -38.36819) (xy 308.512459 -38.398101) (xy 308.55381 -38.434314) (xy 308.589542 -38.476081)
			(xy 308.604666 -38.499034) (xy 308.604666 -38.499288) (xy 308.607206 -38.503352) (xy 308.607968 -38.504368)
			(xy 308.612032 -38.508432) (xy 308.620922 -38.515036) (xy 308.64048 -38.527228) (xy 308.645858 -38.530307)
			(xy 308.657676 -38.534029) (xy 308.663848 -38.534594) (xy 308.734714 -38.539166) (xy 308.738016 -38.539166)
			(xy 308.778148 -38.519608) (xy 308.779926 -38.517322) (xy 308.797584 -38.495332) (xy 308.838281 -38.456293)
			(xy 308.884275 -38.423659) (xy 308.934565 -38.39814) (xy 308.988061 -38.38029) (xy 309.043598 -38.370496)
			(xy 309.071772 -38.36924) (xy 309.078376 -38.368986) (xy 309.08879 -38.363652) (xy 309.094172 -38.360682)
			(xy 309.10342 -38.35259) (xy 309.107078 -38.34765) (xy 309.125112 -38.321996) (xy 309.127906 -38.317678)
			(xy 309.132494 -38.308397) (xy 309.134586 -38.287818) (xy 309.13197 -38.2778) (xy 309.122306 -38.250424)
			(xy 309.105785 -38.194763) (xy 309.09895 -38.166548) (xy 309.097426 -38.159436) (xy 309.097172 -38.158674)
			(xy 309.080154 -38.130988) (xy 309.074058 -38.125654) (xy 309.041038 -38.096444) (xy 309.007916 -38.065097)
			(xy 308.946908 -37.997304) (xy 308.892333 -37.924234) (xy 308.868064 -37.885624) (xy 308.609238 -37.462968)
			(xy 308.593372 -37.43665) (xy 308.564522 -37.382383) (xy 308.55158 -37.35451) (xy 308.535324 -37.31641)
			(xy 308.5338 -37.3126) (xy 308.445154 -37.168328) (xy 308.423621 -37.132478) (xy 308.385979 -37.057791)
			(xy 308.354774 -36.980195) (xy 308.33023 -36.900241) (xy 308.320948 -36.859464) (xy 308.312312 -36.814252)
			(xy 308.310788 -36.8046) (xy 308.284118 -36.760912) (xy 308.276752 -36.755324) (xy 308.256611 -36.739193)
			(xy 308.220442 -36.702389) (xy 308.189575 -36.661038) (xy 308.164575 -36.615897) (xy 308.154832 -36.592002)
			(xy 308.151022 -36.582096) (xy 307.71592 -36.143438) (xy 307.708673 -36.137539) (xy 307.69122 -36.130905)
			(xy 307.681884 -36.130484) (xy 307.677566 -36.130484) (xy 307.667601 -36.130964) (xy 307.649167 -36.138542)
			(xy 307.641752 -36.145216) (xy 307.641498 -36.14547) (xy 307.619874 -36.166451) (xy 307.571241 -36.202014)
			(xy 307.517624 -36.229495) (xy 307.460356 -36.248212) (xy 307.400858 -36.257698) (xy 307.370734 -36.258246)
			(xy 307.34348 -36.257763) (xy 307.289527 -36.25001) (xy 307.237226 -36.234658) (xy 307.187642 -36.21202)
			(xy 307.141784 -36.182555) (xy 307.100587 -36.146864) (xy 307.064888 -36.105673) (xy 307.035415 -36.059821)
			(xy 307.012767 -36.010242) (xy 306.997405 -35.957944) (xy 306.989643 -35.903992) (xy 306.989226 -35.876738)
			(xy 306.989226 -35.876484) (xy 306.98965 -35.851359) (xy 306.996282 -35.801546) (xy 307.009376 -35.753031)
			(xy 307.028708 -35.706646) (xy 307.053944 -35.663191) (xy 307.068982 -35.643058) (xy 307.073433 -35.636318)
			(xy 307.07824 -35.620907) (xy 307.07838 -35.612832) (xy 307.078126 -35.605212) (xy 307.07711 -35.58159)
			(xy 307.076357 -35.572422) (xy 307.069201 -35.55549) (xy 307.06314 -35.54857) (xy 306.87772 -35.363404)
			(xy 306.840382 -35.32378) (xy 306.83835 -35.321494) (xy 306.832 -35.314382) (xy 306.823618 -35.310064)
			(xy 306.819192 -35.307872) (xy 306.809726 -35.305059) (xy 306.804822 -35.304476) (xy 306.787804 -35.302952)
			(xy 306.783253 -35.302686) (xy 306.77418 -35.303573) (xy 306.76977 -35.30473) (xy 306.761134 -35.307016)
			(xy 306.753006 -35.313366) (xy 306.715726 -35.341181) (xy 306.63688 -35.390536) (xy 306.553782 -35.432338)
			(xy 306.467155 -35.466223) (xy 306.377749 -35.491899) (xy 306.286341 -35.509142) (xy 306.193726 -35.517801)
			(xy 306.147216 -35.518344) (xy 306.124356 -35.51809) (xy 306.123594 -35.51809) (xy 306.077442 -35.516467)
			(xy 305.985714 -35.505732) (xy 305.895372 -35.48656) (xy 305.80719 -35.459115) (xy 305.721924 -35.423632)
			(xy 305.640305 -35.380415) (xy 305.563033 -35.329835) (xy 305.49077 -35.272325) (xy 305.457098 -35.240722)
			(xy 305.425997 -35.210265) (xy 305.368648 -35.144765) (xy 305.317231 -35.074514) (xy 305.294284 -35.037522)
			(xy 305.291744 -35.033712) (xy 305.28133 -35.021774) (xy 305.279806 -35.020504) (xy 305.257184 -35.002317)
			(xy 305.217186 -34.960258) (xy 305.184018 -34.912626) (xy 305.158447 -34.860521) (xy 305.141062 -34.805144)
			(xy 305.132264 -34.747773) (xy 305.131724 -34.718752) (xy 305.131724 -34.718498) (xy 305.132188 -34.689997)
			(xy 305.140606 -34.633623) (xy 305.148488 -34.60623) (xy 305.150012 -34.599118) (xy 305.15179 -34.588196)
			(xy 305.15179 -34.58464) (xy 305.151536 -34.581846) (xy 305.151028 -34.567622) (xy 305.151028 -34.566606)
			(xy 305.150012 -34.520886) (xy 305.150447 -34.4783) (xy 305.157688 -34.393435) (xy 305.172143 -34.309498)
			(xy 305.193704 -34.2271) (xy 305.222216 -34.146841) (xy 305.23942 -34.107882) (xy 305.242601 -34.098749)
			(xy 305.242596 -34.079425) (xy 305.23942 -34.07029) (xy 305.222212 -34.031333) (xy 305.19372 -33.951069)
			(xy 305.17217 -33.86867) (xy 305.157719 -33.784734) (xy 305.150472 -33.699872) (xy 305.150012 -33.657286)
			(xy 305.15179 -33.595818) (xy 305.152552 -33.583626) (xy 305.15052 -33.578038) (xy 305.14417 -33.565846)
			(xy 305.140106 -33.560258) (xy 305.117246 -33.536128) (xy 305.110061 -33.529922) (xy 305.09244 -33.522892)
			(xy 305.082956 -33.522412) (xy 304.701194 -33.522412) (xy 304.655567 -33.521851) (xy 304.564703 -33.513419)
			(xy 304.474988 -33.496726) (xy 304.430938 -33.48482) (xy 304.393014 -33.473753) (xy 304.318884 -33.446418)
			(xy 304.282856 -33.43021) (xy 304.272696 -33.425638) (xy 304.262536 -33.420812) (xy 304.229516 -33.420812)
			(xy 304.219881 -33.421273) (xy 304.201991 -33.428447) (xy 304.194718 -33.434782) (xy 304.16386 -33.463683)
			(xy 304.098031 -33.516746) (xy 304.027944 -33.564044) (xy 303.954104 -33.605236) (xy 303.877041 -33.640027)
			(xy 303.797308 -33.668166) (xy 303.715479 -33.689452) (xy 303.63214 -33.703731) (xy 303.547892 -33.710902)
			(xy 303.505616 -33.711388) (xy 303.505108 -33.711388) (xy 303.462278 -33.710931) (xy 303.376934 -33.703583)
			(xy 303.292535 -33.688942) (xy 303.209702 -33.667114) (xy 303.129048 -33.638262) (xy 303.051166 -33.602597)
			(xy 302.97663 -33.560383) (xy 302.90599 -33.51193) (xy 302.839767 -33.457596) (xy 302.77845 -33.397782)
			(xy 302.722489 -33.332929) (xy 302.672297 -33.263514) (xy 302.64989 -33.22701) (xy 302.647386 -33.223188)
			(xy 302.641256 -33.216414) (xy 302.637698 -33.213548) (xy 302.61508 -33.19536) (xy 302.575088 -33.153299)
			(xy 302.541928 -33.105666) (xy 302.516365 -33.05356) (xy 302.498988 -32.998184) (xy 302.490199 -32.940815)
			(xy 302.489616 -32.911796) (xy 302.489616 -32.911542) (xy 302.49012 -32.883107) (xy 302.498539 -32.826865)
			(xy 302.50638 -32.799528) (xy 302.507904 -32.792416) (xy 302.509682 -32.781494) (xy 302.509682 -32.777938)
			(xy 302.509428 -32.775144) (xy 302.50892 -32.76092) (xy 302.50892 -32.759904) (xy 302.507904 -32.714184)
			(xy 302.508339 -32.671598) (xy 302.515581 -32.586733) (xy 302.530035 -32.502796) (xy 302.551596 -32.420398)
			(xy 302.580108 -32.340139) (xy 302.597312 -32.30118) (xy 302.600492 -32.292047) (xy 302.600487 -32.272723)
			(xy 302.597312 -32.263588) (xy 302.580103 -32.224632) (xy 302.551608 -32.144368) (xy 302.530056 -32.061969)
			(xy 302.515604 -31.978032) (xy 302.508357 -31.89317) (xy 302.507904 -31.850584) (xy 302.50892 -31.804864)
			(xy 302.50892 -31.803848) (xy 302.509428 -31.789624) (xy 302.509682 -31.78683) (xy 302.509682 -31.783274)
			(xy 302.507904 -31.772352) (xy 302.50638 -31.76524) (xy 302.498552 -31.7379) (xy 302.490133 -31.68166)
			(xy 302.489616 -31.653226) (xy 302.489616 -31.652972) (xy 302.49016 -31.623952) (xy 302.498957 -31.566582)
			(xy 302.516342 -31.511206) (xy 302.541915 -31.459103) (xy 302.575086 -31.411475) (xy 302.615088 -31.369422)
			(xy 302.637698 -31.35122) (xy 302.641263 -31.348361) (xy 302.647392 -31.341585) (xy 302.64989 -31.337758)
			(xy 302.672309 -31.301263) (xy 302.722501 -31.23185) (xy 302.778462 -31.166999) (xy 302.83978 -31.107188)
			(xy 302.906002 -31.052857) (xy 302.976641 -31.004406) (xy 303.051175 -30.962194) (xy 303.129056 -30.926531)
			(xy 303.209709 -30.89768) (xy 303.292539 -30.875854) (xy 303.376937 -30.861213) (xy 303.462279 -30.853866)
			(xy 303.505108 -30.85338) (xy 303.505362 -30.85338) (xy 303.547812 -30.85382) (xy 303.632405 -30.861037)
			(xy 303.716078 -30.875421) (xy 303.798225 -30.896868) (xy 303.87825 -30.925223) (xy 303.955575 -30.96028)
			(xy 304.029638 -31.001786) (xy 304.099903 -31.04944) (xy 304.165861 -31.102896) (xy 304.19675 -31.132018)
			(xy 304.203493 -31.137279) (xy 304.219459 -31.143385) (xy 304.227992 -31.143956) (xy 305.076606 -31.143956)
			(xy 305.082956 -31.143448) (xy 305.09145 -31.14207) (xy 305.106861 -31.13444) (xy 305.118869 -31.122131)
			(xy 305.122834 -31.114492) (xy 305.132486 -31.091124) (xy 305.133502 -31.080964) (xy 305.133502 -31.080456)
			(xy 305.135785 -31.060694) (xy 305.14393 -31.021753) (xy 305.149758 -31.002732) (xy 305.151011 -30.998273)
			(xy 305.15203 -30.989069) (xy 305.15179 -30.984444) (xy 305.15179 -30.983936) (xy 305.150904 -30.96814)
			(xy 305.150014 -30.936511) (xy 305.150012 -30.92069) (xy 305.150447 -30.878104) (xy 305.157688 -30.793239)
			(xy 305.172142 -30.709302) (xy 305.193703 -30.626904) (xy 305.222215 -30.546645) (xy 305.23942 -30.507686)
			(xy 305.242602 -30.498553) (xy 305.242598 -30.479229) (xy 305.23942 -30.470094) (xy 305.222212 -30.431137)
			(xy 305.19372 -30.350874) (xy 305.172169 -30.268474) (xy 305.157718 -30.184538) (xy 305.15047 -30.099676)
			(xy 305.150012 -30.05709) (xy 305.150266 -30.030166) (xy 305.150266 -30.029912) (xy 305.150087 -30.020569)
			(xy 305.143837 -30.002977) (xy 305.138074 -29.995622) (xy 305.091592 -29.948124) (xy 305.084421 -29.942066)
			(xy 305.066936 -29.935273) (xy 305.057556 -29.934916) (xy 305.045618 -29.934916) (xy 304.998897 -29.934339)
			(xy 304.905878 -29.92545) (xy 304.814114 -29.907817) (xy 304.724425 -29.881597) (xy 304.637614 -29.847024)
			(xy 304.595784 -29.826204) (xy 304.590358 -29.823618) (xy 304.578678 -29.820788) (xy 304.57267 -29.820616)
			(xy 304.239168 -29.820616) (xy 304.234277 -29.820751) (xy 304.224683 -29.822666) (xy 304.220118 -29.824426)
			(xy 304.194718 -29.834586) (xy 304.194464 -29.83484) (xy 304.193194 -29.83611) (xy 304.18786 -29.84119)
			(xy 304.153298 -29.872925) (xy 304.079177 -29.930473) (xy 303.999979 -29.980804) (xy 303.916404 -30.023474)
			(xy 303.82919 -30.058105) (xy 303.739109 -30.084392) (xy 303.646958 -30.102101) (xy 303.55355 -30.111077)
			(xy 303.506632 -30.1117) (xy 303.505108 -30.1117) (xy 303.458579 -30.11115) (xy 303.365929 -30.102456)
			(xy 303.274491 -30.08517) (xy 303.18506 -30.059443) (xy 303.098415 -30.025498) (xy 303.015307 -29.983631)
			(xy 302.93646 -29.934206) (xy 302.862559 -29.877651) (xy 302.794247 -29.81446) (xy 302.732118 -29.745181)
			(xy 302.676711 -29.670416) (xy 302.652176 -29.630878) (xy 302.649636 -29.627068) (xy 302.639222 -29.61513)
			(xy 302.637698 -29.61386) (xy 302.615079 -29.595672) (xy 302.575086 -29.553611) (xy 302.541925 -29.505979)
			(xy 302.51636 -29.453873) (xy 302.498981 -29.398497) (xy 302.49019 -29.341128) (xy 302.489616 -29.312108)
			(xy 302.489616 -29.311854) (xy 302.490083 -29.283354) (xy 302.498507 -29.226981) (xy 302.50638 -29.199586)
			(xy 302.507904 -29.192474) (xy 302.509682 -29.181552) (xy 302.509682 -29.177996) (xy 302.509428 -29.175202)
			(xy 302.50892 -29.160978) (xy 302.50892 -29.159962) (xy 302.507904 -29.114242) (xy 302.508337 -29.071655)
			(xy 302.515573 -28.986789) (xy 302.530023 -28.90285) (xy 302.55158 -28.82045) (xy 302.580088 -28.740189)
			(xy 302.597312 -28.701238) (xy 302.600504 -28.692105) (xy 302.600519 -28.672773) (xy 302.597312 -28.663646)
			(xy 302.580101 -28.62469) (xy 302.551601 -28.544427) (xy 302.530045 -28.462028) (xy 302.515587 -28.378091)
			(xy 302.508335 -28.293228) (xy 302.507904 -28.250642) (xy 302.50892 -28.204922) (xy 302.50892 -28.203906)
			(xy 302.509428 -28.189682) (xy 302.509682 -28.186888) (xy 302.509682 -28.183332) (xy 302.507904 -28.17241)
			(xy 302.50638 -28.165298) (xy 302.498555 -28.137958) (xy 302.490142 -28.081717) (xy 302.489616 -28.053284)
			(xy 302.489616 -28.05303) (xy 302.490156 -28.024008) (xy 302.498945 -27.966633) (xy 302.516324 -27.911251)
			(xy 302.541892 -27.859142) (xy 302.57506 -27.811507) (xy 302.61506 -27.769447) (xy 302.637698 -27.751278)
			(xy 302.641266 -27.748422) (xy 302.647402 -27.74165) (xy 302.64989 -27.737816) (xy 302.674528 -27.6987)
			(xy 302.699627 -27.661791) (xy 302.755448 -27.592137) (xy 302.817273 -27.527751) (xy 302.884607 -27.469151)
			(xy 302.956909 -27.416805) (xy 303.033603 -27.371132) (xy 303.114072 -27.332499) (xy 303.197673 -27.301215)
			(xy 303.283736 -27.27753) (xy 303.371572 -27.261634) (xy 303.460477 -27.253655) (xy 303.505108 -27.253184)
			(xy 303.505362 -27.253184) (xy 303.552882 -27.253738) (xy 303.647488 -27.262793) (xy 303.740803 -27.280815)
			(xy 303.831978 -27.307641) (xy 303.920184 -27.343026) (xy 304.004621 -27.386649) (xy 304.044858 -27.411934)
			(xy 304.082794 -27.436962) (xy 304.154409 -27.492928) (xy 304.18786 -27.523694) (xy 304.193194 -27.528774)
			(xy 304.194464 -27.530044) (xy 304.194718 -27.530298) (xy 304.220118 -27.540458) (xy 304.224685 -27.542212)
			(xy 304.234278 -27.544127) (xy 304.239168 -27.544268) (xy 306.17287 -27.544268) (xy 306.221785 -27.544894)
			(xy 306.319141 -27.554525) (xy 306.415087 -27.573638) (xy 306.508701 -27.602051) (xy 306.554124 -27.620214)
			(xy 308.001162 -28.220924) (xy 308.010635 -28.223956) (xy 308.030493 -28.223297) (xy 308.048601 -28.215117)
			(xy 308.055772 -28.208224) (xy 308.056026 -28.20797) (xy 308.07415 -28.189319) (xy 308.114572 -28.156599)
			(xy 308.15906 -28.129666) (xy 308.206791 -28.109018) (xy 308.256882 -28.095037) (xy 308.308407 -28.087982)
			(xy 308.33441 -28.087574) (xy 308.361661 -28.08806) (xy 308.415609 -28.095818) (xy 308.467903 -28.111174)
			(xy 308.517481 -28.133815) (xy 308.52576 -28.139136) (xy 312.597798 -28.139136) (xy 312.601869 -28.083514)
			(xy 312.613995 -28.029077) (xy 312.633918 -27.976986) (xy 312.661214 -27.928351) (xy 312.6953 -27.884208)
			(xy 312.735449 -27.845499) (xy 312.780807 -27.813048) (xy 312.830407 -27.787547) (xy 312.883191 -27.76954)
			(xy 312.938034 -27.75941) (xy 312.993768 -27.757373) (xy 313.049205 -27.763473) (xy 313.103162 -27.777579)
			(xy 313.154491 -27.799391) (xy 313.202097 -27.828445) (xy 313.244965 -27.86412) (xy 313.282182 -27.905657)
			(xy 313.312955 -27.95217) (xy 313.336627 -28.002667) (xy 313.352695 -28.056074) (xy 313.360815 -28.11125)
			(xy 313.361324 -28.139136) (xy 313.867798 -28.139136) (xy 313.871869 -28.083514) (xy 313.883995 -28.029077)
			(xy 313.903918 -27.976986) (xy 313.931214 -27.928351) (xy 313.9653 -27.884208) (xy 314.005449 -27.845499)
			(xy 314.050807 -27.813048) (xy 314.100407 -27.787547) (xy 314.153191 -27.76954) (xy 314.208034 -27.75941)
			(xy 314.263768 -27.757373) (xy 314.319205 -27.763473) (xy 314.373162 -27.777579) (xy 314.424491 -27.799391)
			(xy 314.472097 -27.828445) (xy 314.514965 -27.86412) (xy 314.552182 -27.905657) (xy 314.582955 -27.95217)
			(xy 314.606627 -28.002667) (xy 314.622695 -28.056074) (xy 314.630815 -28.11125) (xy 314.631324 -28.139136)
			(xy 314.630815 -28.167022) (xy 314.622695 -28.222198) (xy 314.606627 -28.275605) (xy 314.582955 -28.326102)
			(xy 314.552182 -28.372615) (xy 314.514965 -28.414152) (xy 314.472097 -28.449827) (xy 314.424491 -28.478881)
			(xy 314.373162 -28.500693) (xy 314.319205 -28.514799) (xy 314.263768 -28.520899) (xy 314.208034 -28.518862)
			(xy 314.153191 -28.508732) (xy 314.100407 -28.490725) (xy 314.050807 -28.465224) (xy 314.005449 -28.432773)
			(xy 313.9653 -28.394064) (xy 313.931214 -28.349921) (xy 313.903918 -28.301286) (xy 313.883995 -28.249195)
			(xy 313.871869 -28.194758) (xy 313.867798 -28.139136) (xy 313.361324 -28.139136) (xy 313.360815 -28.167022)
			(xy 313.352695 -28.222198) (xy 313.336627 -28.275605) (xy 313.312955 -28.326102) (xy 313.282182 -28.372615)
			(xy 313.244965 -28.414152) (xy 313.202097 -28.449827) (xy 313.154491 -28.478881) (xy 313.103162 -28.500693)
			(xy 313.049205 -28.514799) (xy 312.993768 -28.520899) (xy 312.938034 -28.518862) (xy 312.883191 -28.508732)
			(xy 312.830407 -28.490725) (xy 312.780807 -28.465224) (xy 312.735449 -28.432773) (xy 312.6953 -28.394064)
			(xy 312.661214 -28.349921) (xy 312.633918 -28.301286) (xy 312.613995 -28.249195) (xy 312.601869 -28.194758)
			(xy 312.597798 -28.139136) (xy 308.52576 -28.139136) (xy 308.563331 -28.163282) (xy 308.604522 -28.198973)
			(xy 308.640214 -28.240163) (xy 308.669681 -28.286012) (xy 308.692323 -28.335589) (xy 308.70768 -28.387883)
			(xy 308.715439 -28.441831) (xy 308.715918 -28.469082) (xy 308.715918 -28.480004) (xy 308.71454 -28.509045)
			(xy 308.704077 -28.566233) (xy 308.685055 -28.62117) (xy 308.671976 -28.647136) (xy 308.668263 -28.656645)
			(xy 308.667915 -28.677039) (xy 308.675535 -28.695958) (xy 308.68239 -28.703524) (xy 309.101236 -29.12237)
			(xy 318.806576 -29.12237) (xy 318.806576 -28.25877) (xy 318.807066 -28.228786) (xy 318.814894 -28.16933)
			(xy 318.830415 -28.111405) (xy 318.853364 -28.056001) (xy 318.883348 -28.004067) (xy 318.919854 -27.956491)
			(xy 318.962259 -27.914086) (xy 319.009835 -27.87758) (xy 319.061769 -27.847596) (xy 319.117173 -27.824647)
			(xy 319.175098 -27.809126) (xy 319.234554 -27.801298) (xy 319.294522 -27.801298) (xy 319.353978 -27.809126)
			(xy 319.411903 -27.824647) (xy 319.467307 -27.847596) (xy 319.519241 -27.87758) (xy 319.566817 -27.914086)
			(xy 319.609222 -27.956491) (xy 319.645728 -28.004067) (xy 319.675712 -28.056001) (xy 319.698661 -28.111405)
			(xy 319.714182 -28.16933) (xy 319.72201 -28.228786) (xy 319.7225 -28.25877) (xy 319.7225 -29.12237)
			(xy 319.72201 -29.152354) (xy 319.714182 -29.21181) (xy 319.698661 -29.269735) (xy 319.675712 -29.325139)
			(xy 319.645728 -29.377073) (xy 319.609222 -29.424649) (xy 319.566817 -29.467054) (xy 319.519241 -29.50356)
			(xy 319.467307 -29.533544) (xy 319.411903 -29.556493) (xy 319.353978 -29.572014) (xy 319.294522 -29.579842)
			(xy 319.234554 -29.579842) (xy 319.175098 -29.572014) (xy 319.117173 -29.556493) (xy 319.061769 -29.533544)
			(xy 319.009835 -29.50356) (xy 318.962259 -29.467054) (xy 318.919854 -29.424649) (xy 318.883348 -29.377073)
			(xy 318.853364 -29.325139) (xy 318.830415 -29.269735) (xy 318.814894 -29.21181) (xy 318.807066 -29.152354)
			(xy 318.806576 -29.12237) (xy 309.101236 -29.12237) (xy 309.388002 -29.409136) (xy 309.38851 -29.409644)
			(xy 309.389272 -29.410406) (xy 309.396141 -29.416274) (xy 309.412829 -29.423161) (xy 309.430871 -29.423791)
			(xy 309.439564 -29.421328) (xy 309.44058 -29.421074) (xy 309.441596 -29.420566) (xy 309.468162 -29.412663)
			(xy 309.522862 -29.403737) (xy 309.550562 -29.402786) (xy 309.564024 -29.402786) (xy 309.590667 -29.403692)
			(xy 309.643321 -29.412028) (xy 309.694303 -29.427611) (xy 309.742619 -29.45014) (xy 309.787328 -29.479174)
			(xy 309.827562 -29.514149) (xy 309.862535 -29.554383) (xy 309.891567 -29.599094) (xy 309.914094 -29.647411)
			(xy 309.929675 -29.698393) (xy 309.938009 -29.751047) (xy 309.938928 -29.77769) (xy 309.938928 -29.784802)
			(xy 309.938345 -29.814703) (xy 309.929033 -29.873775) (xy 309.920386 -29.902404) (xy 309.918354 -29.909008)
			(xy 309.917592 -29.922724) (xy 309.91937 -29.929836) (xy 309.921198 -29.936607) (xy 309.928043 -29.948841)
			(xy 309.932832 -29.953966) (xy 310.355653 -30.376876) (xy 311.088786 -30.376876) (xy 311.089326 -30.34796)
			(xy 311.098046 -30.290788) (xy 311.115298 -30.235588) (xy 311.140685 -30.183626) (xy 311.173626 -30.136091)
			(xy 311.213367 -30.094075) (xy 311.235852 -30.075886) (xy 311.244664 -30.068284) (xy 311.254843 -30.047379)
			(xy 311.25541 -30.035754) (xy 311.25541 -29.955998) (xy 311.254854 -29.944368) (xy 311.244677 -29.923459)
			(xy 311.235852 -29.915866) (xy 311.213342 -29.897706) (xy 311.173611 -29.855679) (xy 311.140676 -29.808137)
			(xy 311.115293 -29.75617) (xy 311.098042 -29.700967) (xy 311.089318 -29.643794) (xy 311.088786 -29.614876)
			(xy 311.089272 -29.587625) (xy 311.097028 -29.533677) (xy 311.112383 -29.481382) (xy 311.135025 -29.431805)
			(xy 311.164491 -29.385955) (xy 311.200182 -29.344764) (xy 311.241373 -29.309073) (xy 311.287223 -29.279607)
			(xy 311.3368 -29.256965) (xy 311.389095 -29.24161) (xy 311.443043 -29.233854) (xy 311.497545 -29.233854)
			(xy 311.551493 -29.24161) (xy 311.603788 -29.256965) (xy 311.653365 -29.279607) (xy 311.699215 -29.309073)
			(xy 311.740406 -29.344764) (xy 311.776097 -29.385955) (xy 311.805563 -29.431805) (xy 311.828205 -29.481382)
			(xy 311.84356 -29.533677) (xy 311.851316 -29.587625) (xy 311.851802 -29.614876) (xy 311.851266 -29.643792)
			(xy 311.84254 -29.700963) (xy 311.825286 -29.756161) (xy 311.799898 -29.808123) (xy 311.766957 -29.855657)
			(xy 311.72722 -29.897675) (xy 311.704736 -29.915866) (xy 311.695943 -29.923487) (xy 311.685754 -29.944378)
			(xy 311.685178 -29.955998) (xy 311.685178 -30.035754) (xy 311.685708 -30.047387) (xy 311.695904 -30.068295)
			(xy 311.704736 -30.075886) (xy 311.72722 -30.094076) (xy 311.766954 -30.136097) (xy 311.799892 -30.183632)
			(xy 311.82528 -30.235594) (xy 311.842536 -30.290791) (xy 311.851266 -30.34796) (xy 311.851802 -30.376876)
			(xy 314.128912 -30.376876) (xy 314.12948 -30.347961) (xy 314.138198 -30.290792) (xy 314.155446 -30.235594)
			(xy 314.180828 -30.183632) (xy 314.213763 -30.136097) (xy 314.253496 -30.094077) (xy 314.275978 -30.075886)
			(xy 314.284794 -30.068288) (xy 314.29497 -30.04738) (xy 314.295536 -30.035754) (xy 314.295536 -29.955998)
			(xy 314.295006 -29.944364) (xy 314.284813 -29.923453) (xy 314.275978 -29.915866) (xy 314.253474 -29.8977)
			(xy 314.213741 -29.855674) (xy 314.180805 -29.808134) (xy 314.15542 -29.756168) (xy 314.138168 -29.700966)
			(xy 314.129444 -29.643793) (xy 314.128912 -29.614876) (xy 314.129398 -29.587625) (xy 314.137154 -29.533677)
			(xy 314.152509 -29.481382) (xy 314.175151 -29.431805) (xy 314.204617 -29.385955) (xy 314.240308 -29.344764)
			(xy 314.281499 -29.309073) (xy 314.327349 -29.279607) (xy 314.376926 -29.256965) (xy 314.429221 -29.24161)
			(xy 314.483169 -29.233854) (xy 314.537671 -29.233854) (xy 314.591619 -29.24161) (xy 314.643914 -29.256965)
			(xy 314.693491 -29.279607) (xy 314.739341 -29.309073) (xy 314.780532 -29.344764) (xy 314.816223 -29.385955)
			(xy 314.845689 -29.431805) (xy 314.868331 -29.481382) (xy 314.883686 -29.533677) (xy 314.891442 -29.587625)
			(xy 314.891928 -29.614876) (xy 314.89142 -29.643794) (xy 314.882693 -29.700967) (xy 314.865434 -29.756167)
			(xy 314.840041 -29.808129) (xy 314.807094 -29.855662) (xy 314.76735 -29.897677) (xy 314.744862 -29.915866)
			(xy 314.736074 -29.923491) (xy 314.725881 -29.944378) (xy 314.725304 -29.955998) (xy 314.725304 -30.035754)
			(xy 314.725825 -30.047388) (xy 314.736026 -30.068298) (xy 314.744862 -30.075886) (xy 314.767331 -30.094095)
			(xy 314.807069 -30.136109) (xy 314.840011 -30.18364) (xy 314.865402 -30.235598) (xy 314.882661 -30.290793)
			(xy 314.891392 -30.347961) (xy 314.891928 -30.376876) (xy 314.891442 -30.404127) (xy 314.883686 -30.458075)
			(xy 314.868331 -30.51037) (xy 314.845689 -30.559947) (xy 314.816223 -30.605797) (xy 314.780532 -30.646988)
			(xy 314.739341 -30.682679) (xy 314.693491 -30.712145) (xy 314.643914 -30.734787) (xy 314.591619 -30.750142)
			(xy 314.537671 -30.757898) (xy 314.483169 -30.757898) (xy 314.429221 -30.750142) (xy 314.376926 -30.734787)
			(xy 314.327349 -30.712145) (xy 314.281499 -30.682679) (xy 314.240308 -30.646988) (xy 314.204617 -30.605797)
			(xy 314.175151 -30.559947) (xy 314.152509 -30.51037) (xy 314.137154 -30.458075) (xy 314.129398 -30.404127)
			(xy 314.128912 -30.376876) (xy 311.851802 -30.376876) (xy 311.851316 -30.404127) (xy 311.84356 -30.458075)
			(xy 311.828205 -30.51037) (xy 311.805563 -30.559947) (xy 311.776097 -30.605797) (xy 311.740406 -30.646988)
			(xy 311.699215 -30.682679) (xy 311.653365 -30.712145) (xy 311.603788 -30.734787) (xy 311.551493 -30.750142)
			(xy 311.497545 -30.757898) (xy 311.443043 -30.757898) (xy 311.389095 -30.750142) (xy 311.3368 -30.734787)
			(xy 311.287223 -30.712145) (xy 311.241373 -30.682679) (xy 311.200182 -30.646988) (xy 311.164491 -30.605797)
			(xy 311.135025 -30.559947) (xy 311.112383 -30.51037) (xy 311.097028 -30.458075) (xy 311.089272 -30.404127)
			(xy 311.088786 -30.376876) (xy 310.355653 -30.376876) (xy 310.901131 -30.922468) (xy 316.952376 -30.922468)
			(xy 316.952376 -30.058868) (xy 316.952866 -30.028884) (xy 316.960694 -29.969428) (xy 316.976215 -29.911503)
			(xy 316.999164 -29.856099) (xy 317.029148 -29.804165) (xy 317.065654 -29.756589) (xy 317.108059 -29.714184)
			(xy 317.155635 -29.677678) (xy 317.207569 -29.647694) (xy 317.262973 -29.624745) (xy 317.320898 -29.609224)
			(xy 317.380354 -29.601396) (xy 317.440322 -29.601396) (xy 317.499778 -29.609224) (xy 317.557703 -29.624745)
			(xy 317.613107 -29.647694) (xy 317.665041 -29.677678) (xy 317.712617 -29.714184) (xy 317.755022 -29.756589)
			(xy 317.791528 -29.804165) (xy 317.821512 -29.856099) (xy 317.844461 -29.911503) (xy 317.859982 -29.969428)
			(xy 317.86781 -30.028884) (xy 317.8683 -30.058868) (xy 317.8683 -30.922468) (xy 317.86781 -30.952452)
			(xy 317.859982 -31.011908) (xy 317.844461 -31.069833) (xy 317.821512 -31.125237) (xy 317.791528 -31.177171)
			(xy 317.755022 -31.224747) (xy 317.712617 -31.267152) (xy 317.665041 -31.303658) (xy 317.613107 -31.333642)
			(xy 317.557703 -31.356591) (xy 317.499778 -31.372112) (xy 317.440322 -31.37994) (xy 317.380354 -31.37994)
			(xy 317.320898 -31.372112) (xy 317.262973 -31.356591) (xy 317.207569 -31.333642) (xy 317.155635 -31.303658)
			(xy 317.108059 -31.267152) (xy 317.065654 -31.224747) (xy 317.029148 -31.177171) (xy 316.999164 -31.125237)
			(xy 316.976215 -31.069833) (xy 316.960694 -31.011908) (xy 316.952866 -30.952452) (xy 316.952376 -30.922468)
			(xy 310.901131 -30.922468) (xy 311.143396 -31.164784) (xy 311.147968 -31.169102) (xy 311.148476 -31.16961)
			(xy 311.164827 -31.185672) (xy 311.19621 -31.219085) (xy 311.211214 -31.236412) (xy 311.21731 -31.243778)
			(xy 311.241948 -31.256986) (xy 311.246157 -31.259008) (xy 311.255101 -31.261688) (xy 311.259728 -31.26232)
			(xy 311.31891 -31.269432) (xy 311.323693 -31.269892) (xy 311.333279 -31.269246) (xy 311.33796 -31.268162)
			(xy 311.34685 -31.265876) (xy 311.354724 -31.260288) (xy 311.37943 -31.242877) (xy 311.433187 -31.215257)
			(xy 311.490626 -31.196458) (xy 311.550311 -31.186949) (xy 311.58053 -31.186374) (xy 311.60778 -31.186862)
			(xy 311.661726 -31.194622) (xy 311.714018 -31.209979) (xy 311.763593 -31.232622) (xy 311.80944 -31.262089)
			(xy 311.850629 -31.29778) (xy 311.886319 -31.338969) (xy 311.915784 -31.384818) (xy 311.938425 -31.434393)
			(xy 311.953781 -31.486686) (xy 311.961539 -31.540632) (xy 311.962038 -31.567882) (xy 311.962292 -31.567882)
			(xy 311.961768 -31.596582) (xy 311.953161 -31.653332) (xy 311.936154 -31.708154) (xy 311.930771 -31.719266)
			(xy 312.485276 -31.719266) (xy 312.489347 -31.663644) (xy 312.501473 -31.609207) (xy 312.521396 -31.557116)
			(xy 312.548692 -31.508481) (xy 312.582778 -31.464338) (xy 312.622927 -31.425629) (xy 312.668285 -31.393178)
			(xy 312.717885 -31.367677) (xy 312.770669 -31.34967) (xy 312.825512 -31.33954) (xy 312.881246 -31.337503)
			(xy 312.936683 -31.343603) (xy 312.99064 -31.357709) (xy 313.041969 -31.379521) (xy 313.089575 -31.408575)
			(xy 313.132443 -31.44425) (xy 313.16966 -31.485787) (xy 313.200433 -31.5323) (xy 313.224105 -31.582797)
			(xy 313.240173 -31.636204) (xy 313.244323 -31.664402) (xy 313.760864 -31.664402) (xy 313.764935 -31.60878)
			(xy 313.777061 -31.554343) (xy 313.796984 -31.502252) (xy 313.82428 -31.453617) (xy 313.858366 -31.409474)
			(xy 313.898515 -31.370765) (xy 313.943873 -31.338314) (xy 313.993473 -31.312813) (xy 314.046257 -31.294806)
			(xy 314.1011 -31.284676) (xy 314.156834 -31.282639) (xy 314.212271 -31.288739) (xy 314.266228 -31.302845)
			(xy 314.317557 -31.324657) (xy 314.365163 -31.353711) (xy 314.408031 -31.389386) (xy 314.445248 -31.430923)
			(xy 314.476021 -31.477436) (xy 314.499693 -31.527933) (xy 314.515761 -31.58134) (xy 314.523881 -31.636516)
			(xy 314.52439 -31.664402) (xy 314.523881 -31.692288) (xy 314.515761 -31.747464) (xy 314.506821 -31.777178)
			(xy 315.026038 -31.777178) (xy 315.030109 -31.721556) (xy 315.042235 -31.667119) (xy 315.062158 -31.615028)
			(xy 315.089454 -31.566393) (xy 315.12354 -31.52225) (xy 315.163689 -31.483541) (xy 315.209047 -31.45109)
			(xy 315.258647 -31.425589) (xy 315.311431 -31.407582) (xy 315.366274 -31.397452) (xy 315.422008 -31.395415)
			(xy 315.477445 -31.401515) (xy 315.531402 -31.415621) (xy 315.582731 -31.437433) (xy 315.630337 -31.466487)
			(xy 315.673205 -31.502162) (xy 315.710422 -31.543699) (xy 315.741195 -31.590212) (xy 315.764867 -31.640709)
			(xy 315.780935 -31.694116) (xy 315.789055 -31.749292) (xy 315.789564 -31.777178) (xy 315.789055 -31.805064)
			(xy 315.780935 -31.86024) (xy 315.764867 -31.913647) (xy 315.741195 -31.964144) (xy 315.710422 -32.010657)
			(xy 315.673205 -32.052194) (xy 315.630337 -32.087869) (xy 315.582731 -32.116923) (xy 315.531402 -32.138735)
			(xy 315.477445 -32.152841) (xy 315.422008 -32.158941) (xy 315.366274 -32.156904) (xy 315.311431 -32.146774)
			(xy 315.258647 -32.128767) (xy 315.209047 -32.103266) (xy 315.163689 -32.070815) (xy 315.12354 -32.032106)
			(xy 315.089454 -31.987963) (xy 315.062158 -31.939328) (xy 315.042235 -31.887237) (xy 315.030109 -31.8328)
			(xy 315.026038 -31.777178) (xy 314.506821 -31.777178) (xy 314.499693 -31.800871) (xy 314.476021 -31.851368)
			(xy 314.445248 -31.897881) (xy 314.408031 -31.939418) (xy 314.365163 -31.975093) (xy 314.317557 -32.004147)
			(xy 314.266228 -32.025959) (xy 314.212271 -32.040065) (xy 314.156834 -32.046165) (xy 314.1011 -32.044128)
			(xy 314.046257 -32.033998) (xy 313.993473 -32.015991) (xy 313.943873 -31.99049) (xy 313.898515 -31.958039)
			(xy 313.858366 -31.91933) (xy 313.82428 -31.875187) (xy 313.796984 -31.826552) (xy 313.777061 -31.774461)
			(xy 313.764935 -31.720024) (xy 313.760864 -31.664402) (xy 313.244323 -31.664402) (xy 313.248293 -31.69138)
			(xy 313.248802 -31.719266) (xy 313.248293 -31.747152) (xy 313.240173 -31.802328) (xy 313.224105 -31.855735)
			(xy 313.200433 -31.906232) (xy 313.16966 -31.952745) (xy 313.132443 -31.994282) (xy 313.089575 -32.029957)
			(xy 313.041969 -32.059011) (xy 312.99064 -32.080823) (xy 312.936683 -32.094929) (xy 312.881246 -32.101029)
			(xy 312.825512 -32.098992) (xy 312.770669 -32.088862) (xy 312.717885 -32.070855) (xy 312.668285 -32.045354)
			(xy 312.622927 -32.012903) (xy 312.582778 -31.974194) (xy 312.548692 -31.930051) (xy 312.521396 -31.881416)
			(xy 312.501473 -31.829325) (xy 312.489347 -31.774888) (xy 312.485276 -31.719266) (xy 311.930771 -31.719266)
			(xy 311.911129 -31.759811) (xy 311.878652 -31.807139) (xy 311.839454 -31.849069) (xy 311.794419 -31.884658)
			(xy 311.76976 -31.899352) (xy 311.760362 -31.904686) (xy 311.75452 -31.91256) (xy 311.75161 -31.916601)
			(xy 311.747254 -31.925553) (xy 311.745884 -31.93034) (xy 311.727596 -32.002476) (xy 311.726893 -32.006307)
			(xy 311.726514 -32.014088) (xy 311.726834 -32.01797) (xy 311.727596 -32.02305) (xy 311.728474 -32.02691)
			(xy 311.731278 -32.034313) (xy 311.733184 -32.037782) (xy 312.136536 -32.671258) (xy 312.169025 -32.722312)
			(xy 318.806576 -32.722312) (xy 318.806576 -31.858712) (xy 318.807066 -31.828728) (xy 318.814894 -31.769272)
			(xy 318.830415 -31.711347) (xy 318.853364 -31.655943) (xy 318.883348 -31.604009) (xy 318.919854 -31.556433)
			(xy 318.962259 -31.514028) (xy 319.009835 -31.477522) (xy 319.061769 -31.447538) (xy 319.117173 -31.424589)
			(xy 319.175098 -31.409068) (xy 319.234554 -31.40124) (xy 319.294522 -31.40124) (xy 319.353978 -31.409068)
			(xy 319.411903 -31.424589) (xy 319.467307 -31.447538) (xy 319.519241 -31.477522) (xy 319.566817 -31.514028)
			(xy 319.609222 -31.556433) (xy 319.645728 -31.604009) (xy 319.675712 -31.655943) (xy 319.698661 -31.711347)
			(xy 319.714182 -31.769272) (xy 319.72201 -31.828728) (xy 319.7225 -31.858712) (xy 319.7225 -32.722312)
			(xy 319.72201 -32.752296) (xy 319.714182 -32.811752) (xy 319.698661 -32.869677) (xy 319.675712 -32.925081)
			(xy 319.645728 -32.977015) (xy 319.609222 -33.024591) (xy 319.566817 -33.066996) (xy 319.519241 -33.103502)
			(xy 319.467307 -33.133486) (xy 319.411903 -33.156435) (xy 319.353978 -33.171956) (xy 319.294522 -33.179784)
			(xy 319.234554 -33.179784) (xy 319.175098 -33.171956) (xy 319.117173 -33.156435) (xy 319.061769 -33.133486)
			(xy 319.009835 -33.103502) (xy 318.962259 -33.066996) (xy 318.919854 -33.024591) (xy 318.883348 -32.977015)
			(xy 318.853364 -32.925081) (xy 318.830415 -32.869677) (xy 318.814894 -32.811752) (xy 318.807066 -32.752296)
			(xy 318.806576 -32.722312) (xy 312.169025 -32.722312) (xy 312.250328 -32.850074) (xy 312.256369 -32.858604)
			(xy 312.273683 -32.870277) (xy 312.283856 -32.87268) (xy 312.28411 -32.87268) (xy 312.312492 -32.878412)
			(xy 312.367222 -32.897305) (xy 312.418471 -32.924249) (xy 312.465061 -32.958625) (xy 312.505924 -32.999644)
			(xy 312.540122 -33.046365) (xy 312.56687 -33.097716) (xy 312.585555 -33.152518) (xy 312.595747 -33.209514)
			(xy 312.597038 -33.23844) (xy 312.597038 -33.248092) (xy 312.596646 -33.27256) (xy 312.590408 -33.321096)
			(xy 312.584592 -33.344866) (xy 312.581798 -33.35528) (xy 312.583322 -33.36544) (xy 312.584278 -33.37056)
			(xy 312.587993 -33.380288) (xy 312.590688 -33.384744) (xy 313.315144 -34.52241) (xy 316.952376 -34.52241)
			(xy 316.952376 -33.65881) (xy 316.952866 -33.628826) (xy 316.960694 -33.56937) (xy 316.976215 -33.511445)
			(xy 316.999164 -33.456041) (xy 317.029148 -33.404107) (xy 317.065654 -33.356531) (xy 317.108059 -33.314126)
			(xy 317.155635 -33.27762) (xy 317.207569 -33.247636) (xy 317.262973 -33.224687) (xy 317.320898 -33.209166)
			(xy 317.380354 -33.201338) (xy 317.440322 -33.201338) (xy 317.499778 -33.209166) (xy 317.557703 -33.224687)
			(xy 317.613107 -33.247636) (xy 317.665041 -33.27762) (xy 317.712617 -33.314126) (xy 317.755022 -33.356531)
			(xy 317.791528 -33.404107) (xy 317.821512 -33.456041) (xy 317.844461 -33.511445) (xy 317.859982 -33.56937)
			(xy 317.86781 -33.628826) (xy 317.8683 -33.65881) (xy 317.8683 -34.52241) (xy 317.86781 -34.552394)
			(xy 317.859982 -34.61185) (xy 317.844461 -34.669775) (xy 317.821512 -34.725179) (xy 317.791528 -34.777113)
			(xy 317.755022 -34.824689) (xy 317.712617 -34.867094) (xy 317.665041 -34.9036) (xy 317.613107 -34.933584)
			(xy 317.557703 -34.956533) (xy 317.499778 -34.972054) (xy 317.440322 -34.979882) (xy 317.380354 -34.979882)
			(xy 317.320898 -34.972054) (xy 317.262973 -34.956533) (xy 317.207569 -34.933584) (xy 317.155635 -34.9036)
			(xy 317.108059 -34.867094) (xy 317.065654 -34.824689) (xy 317.029148 -34.777113) (xy 316.999164 -34.725179)
			(xy 316.976215 -34.669775) (xy 316.960694 -34.61185) (xy 316.952866 -34.552394) (xy 316.952376 -34.52241)
			(xy 313.315144 -34.52241) (xy 313.787925 -35.264852) (xy 314.10224 -35.264852) (xy 314.106311 -35.20923)
			(xy 314.118437 -35.154793) (xy 314.13836 -35.102702) (xy 314.165656 -35.054067) (xy 314.199742 -35.009924)
			(xy 314.239891 -34.971215) (xy 314.285249 -34.938764) (xy 314.334849 -34.913263) (xy 314.387633 -34.895256)
			(xy 314.442476 -34.885126) (xy 314.49821 -34.883089) (xy 314.553647 -34.889189) (xy 314.607604 -34.903295)
			(xy 314.658933 -34.925107) (xy 314.706539 -34.954161) (xy 314.749407 -34.989836) (xy 314.786624 -35.031373)
			(xy 314.817397 -35.077886) (xy 314.841069 -35.128383) (xy 314.857137 -35.18179) (xy 314.865257 -35.236966)
			(xy 314.865766 -35.264852) (xy 314.865257 -35.292738) (xy 314.857137 -35.347914) (xy 314.841069 -35.401321)
			(xy 314.817397 -35.451818) (xy 314.786624 -35.498331) (xy 314.749407 -35.539868) (xy 314.706539 -35.575543)
			(xy 314.658933 -35.604597) (xy 314.607604 -35.626409) (xy 314.553647 -35.640515) (xy 314.49821 -35.646615)
			(xy 314.442476 -35.644578) (xy 314.387633 -35.634448) (xy 314.334849 -35.616441) (xy 314.285249 -35.59094)
			(xy 314.239891 -35.558489) (xy 314.199742 -35.51978) (xy 314.165656 -35.475637) (xy 314.13836 -35.427002)
			(xy 314.118437 -35.374911) (xy 314.106311 -35.320474) (xy 314.10224 -35.264852) (xy 313.787925 -35.264852)
			(xy 314.438787 -36.286948) (xy 315.40018 -36.286948) (xy 315.404251 -36.231326) (xy 315.416377 -36.176889)
			(xy 315.4363 -36.124798) (xy 315.463596 -36.076163) (xy 315.497682 -36.03202) (xy 315.537831 -35.993311)
			(xy 315.583189 -35.96086) (xy 315.632789 -35.935359) (xy 315.685573 -35.917352) (xy 315.740416 -35.907222)
			(xy 315.79615 -35.905185) (xy 315.851587 -35.911285) (xy 315.905544 -35.925391) (xy 315.956873 -35.947203)
			(xy 316.004479 -35.976257) (xy 316.047347 -36.011932) (xy 316.084564 -36.053469) (xy 316.115337 -36.099982)
			(xy 316.139009 -36.150479) (xy 316.155077 -36.203886) (xy 316.163197 -36.259062) (xy 316.163706 -36.286948)
			(xy 316.163197 -36.314834) (xy 316.155077 -36.37001) (xy 316.139009 -36.423417) (xy 316.115337 -36.473914)
			(xy 316.087792 -36.515548) (xy 317.213994 -36.515548) (xy 317.218065 -36.459926) (xy 317.230191 -36.405489)
			(xy 317.250114 -36.353398) (xy 317.27741 -36.304763) (xy 317.311496 -36.26062) (xy 317.351645 -36.221911)
			(xy 317.397003 -36.18946) (xy 317.446603 -36.163959) (xy 317.499387 -36.145952) (xy 317.55423 -36.135822)
			(xy 317.609964 -36.133785) (xy 317.665401 -36.139885) (xy 317.719358 -36.153991) (xy 317.770687 -36.175803)
			(xy 317.818293 -36.204857) (xy 317.861161 -36.240532) (xy 317.898378 -36.282069) (xy 317.929151 -36.328582)
			(xy 317.952823 -36.379079) (xy 317.968891 -36.432486) (xy 317.977011 -36.487662) (xy 317.97752 -36.515548)
			(xy 317.977011 -36.543434) (xy 317.968891 -36.59861) (xy 317.968434 -36.60013) (xy 322.197991 -36.60013)
			(xy 322.201996 -36.512222) (xy 322.213979 -36.425042) (xy 322.233839 -36.339313) (xy 322.261414 -36.255745)
			(xy 322.296473 -36.175031) (xy 322.338726 -36.097839) (xy 322.387824 -36.02481) (xy 322.44336 -35.956548)
			(xy 322.504872 -35.893618) (xy 322.571853 -35.836544) (xy 322.643746 -35.785796) (xy 322.719955 -35.741796)
			(xy 322.79985 -35.704909) (xy 322.882769 -35.67544) (xy 322.968024 -35.653633) (xy 323.054908 -35.639669)
			(xy 323.142702 -35.633663) (xy 323.230679 -35.635667) (xy 323.318109 -35.645662) (xy 323.404268 -35.663566)
			(xy 323.488442 -35.68923) (xy 323.569933 -35.722443) (xy 323.648067 -35.762929) (xy 323.722195 -35.810351)
			(xy 323.791703 -35.864318) (xy 323.856017 -35.924383) (xy 323.914601 -35.990047) (xy 323.966972 -36.060766)
			(xy 324.012695 -36.135954) (xy 324.051392 -36.214989) (xy 324.082741 -36.297215) (xy 324.106483 -36.381951)
			(xy 324.122421 -36.468495) (xy 324.130423 -36.55613) (xy 324.130924 -36.60013) (xy 324.130423 -36.64413)
			(xy 324.122421 -36.731765) (xy 324.106483 -36.818309) (xy 324.082741 -36.903045) (xy 324.051392 -36.985271)
			(xy 324.012695 -37.064306) (xy 323.966972 -37.139494) (xy 323.914601 -37.210213) (xy 323.856017 -37.275877)
			(xy 323.791703 -37.335942) (xy 323.722195 -37.389909) (xy 323.648067 -37.437331) (xy 323.569933 -37.477817)
			(xy 323.488442 -37.51103) (xy 323.404268 -37.536694) (xy 323.318109 -37.554598) (xy 323.230679 -37.564593)
			(xy 323.142702 -37.566597) (xy 323.054908 -37.560591) (xy 322.968024 -37.546627) (xy 322.882769 -37.52482)
			(xy 322.79985 -37.495351) (xy 322.719955 -37.458464) (xy 322.643746 -37.414464) (xy 322.571853 -37.363716)
			(xy 322.504872 -37.306642) (xy 322.44336 -37.243712) (xy 322.387824 -37.17545) (xy 322.338726 -37.102421)
			(xy 322.296473 -37.025229) (xy 322.261414 -36.944515) (xy 322.233839 -36.860947) (xy 322.213979 -36.775218)
			(xy 322.201996 -36.688038) (xy 322.197991 -36.60013) (xy 317.968434 -36.60013) (xy 317.952823 -36.652017)
			(xy 317.929151 -36.702514) (xy 317.898378 -36.749027) (xy 317.861161 -36.790564) (xy 317.818293 -36.826239)
			(xy 317.770687 -36.855293) (xy 317.719358 -36.877105) (xy 317.665401 -36.891211) (xy 317.609964 -36.897311)
			(xy 317.55423 -36.895274) (xy 317.499387 -36.885144) (xy 317.446603 -36.867137) (xy 317.397003 -36.841636)
			(xy 317.351645 -36.809185) (xy 317.311496 -36.770476) (xy 317.27741 -36.726333) (xy 317.250114 -36.677698)
			(xy 317.230191 -36.625607) (xy 317.218065 -36.57117) (xy 317.213994 -36.515548) (xy 316.087792 -36.515548)
			(xy 316.084564 -36.520427) (xy 316.047347 -36.561964) (xy 316.004479 -36.597639) (xy 315.956873 -36.626693)
			(xy 315.905544 -36.648505) (xy 315.851587 -36.662611) (xy 315.79615 -36.668711) (xy 315.740416 -36.666674)
			(xy 315.685573 -36.656544) (xy 315.632789 -36.638537) (xy 315.583189 -36.613036) (xy 315.537831 -36.580585)
			(xy 315.497682 -36.541876) (xy 315.463596 -36.497733) (xy 315.4363 -36.449098) (xy 315.416377 -36.397007)
			(xy 315.404251 -36.34257) (xy 315.40018 -36.286948) (xy 314.438787 -36.286948) (xy 315.385804 -37.774118)
			(xy 315.664594 -37.774118) (xy 315.668665 -37.718496) (xy 315.680791 -37.664059) (xy 315.700714 -37.611968)
			(xy 315.72801 -37.563333) (xy 315.762096 -37.51919) (xy 315.802245 -37.480481) (xy 315.847603 -37.44803)
			(xy 315.897203 -37.422529) (xy 315.949987 -37.404522) (xy 316.00483 -37.394392) (xy 316.060564 -37.392355)
			(xy 316.116001 -37.398455) (xy 316.169958 -37.412561) (xy 316.221287 -37.434373) (xy 316.268893 -37.463427)
			(xy 316.311761 -37.499102) (xy 316.348978 -37.540639) (xy 316.379751 -37.587152) (xy 316.403423 -37.637649)
			(xy 316.419491 -37.691056) (xy 316.427611 -37.746232) (xy 316.42812 -37.774118) (xy 316.427611 -37.802004)
			(xy 316.419491 -37.85718) (xy 316.403423 -37.910587) (xy 316.379751 -37.961084) (xy 316.348978 -38.007597)
			(xy 316.311761 -38.049134) (xy 316.268893 -38.084809) (xy 316.221287 -38.113863) (xy 316.169958 -38.135675)
			(xy 316.116001 -38.149781) (xy 316.060564 -38.155881) (xy 316.00483 -38.153844) (xy 315.949987 -38.143714)
			(xy 315.897203 -38.125707) (xy 315.847603 -38.100206) (xy 315.802245 -38.067755) (xy 315.762096 -38.029046)
			(xy 315.72801 -37.984903) (xy 315.700714 -37.936268) (xy 315.680791 -37.884177) (xy 315.668665 -37.82974)
			(xy 315.664594 -37.774118) (xy 315.385804 -37.774118) (xy 316.165738 -38.998906) (xy 316.247272 -39.126922)
			(xy 316.250066 -39.130986) (xy 318.121836 -41.268753) (xy 326.04375 -41.268753) (xy 326.04375 -41.214247)
			(xy 326.051507 -41.160295) (xy 326.066863 -41.107997) (xy 326.089506 -41.058416) (xy 326.118974 -41.012563)
			(xy 326.154668 -40.971369) (xy 326.195861 -40.935675) (xy 326.241714 -40.906207) (xy 326.291295 -40.883564)
			(xy 326.343593 -40.868207) (xy 326.397545 -40.86045) (xy 326.424798 -40.859964) (xy 326.453536 -40.860499)
			(xy 326.510363 -40.86912) (xy 326.565253 -40.886168) (xy 326.616965 -40.911257) (xy 326.664328 -40.943819)
			(xy 326.685656 -40.963088) (xy 326.692514 -40.969692) (xy 326.710548 -40.976804) (xy 326.799448 -40.976804)
			(xy 326.817482 -40.969692) (xy 326.82434 -40.963088) (xy 326.845675 -40.943827) (xy 326.893034 -40.911257)
			(xy 326.944744 -40.886162) (xy 326.999633 -40.869109) (xy 327.056459 -40.860485) (xy 327.085198 -40.859964)
			(xy 327.112449 -40.860483) (xy 327.166396 -40.868239) (xy 327.21869 -40.883594) (xy 327.268267 -40.906235)
			(xy 327.314117 -40.935701) (xy 327.355307 -40.971392) (xy 327.390998 -41.012581) (xy 327.420464 -41.058431)
			(xy 327.443105 -41.108008) (xy 327.45846 -41.160302) (xy 327.466217 -41.214249) (xy 327.466217 -41.268751)
			(xy 327.45846 -41.322698) (xy 327.443105 -41.374992) (xy 327.420464 -41.424569) (xy 327.390998 -41.470419)
			(xy 327.355307 -41.511608) (xy 327.314117 -41.547299) (xy 327.268267 -41.576765) (xy 327.21869 -41.599406)
			(xy 327.166396 -41.614761) (xy 327.112449 -41.622517) (xy 327.085198 -41.62298) (xy 327.05646 -41.622436)
			(xy 326.999635 -41.613815) (xy 326.944745 -41.596769) (xy 326.893033 -41.571682) (xy 326.845669 -41.539123)
			(xy 326.82434 -41.519856) (xy 326.817482 -41.513252) (xy 326.799448 -41.50614) (xy 326.710548 -41.50614)
			(xy 326.692514 -41.513252) (xy 326.685656 -41.519856) (xy 326.664329 -41.539127) (xy 326.616967 -41.571693)
			(xy 326.565255 -41.596786) (xy 326.510365 -41.613836) (xy 326.453537 -41.622459) (xy 326.424798 -41.62298)
			(xy 326.397545 -41.62255) (xy 326.343593 -41.614793) (xy 326.291295 -41.599436) (xy 326.241714 -41.576793)
			(xy 326.195861 -41.547325) (xy 326.154668 -41.511631) (xy 326.118974 -41.470437) (xy 326.089506 -41.424584)
			(xy 326.066863 -41.375003) (xy 326.051507 -41.322705) (xy 326.04375 -41.268753) (xy 318.121836 -41.268753)
			(xy 319.904912 -43.305222) (xy 328.50709 -43.305222) (xy 328.507571 -43.277852) (xy 328.515386 -43.223674)
			(xy 328.530872 -43.171171) (xy 328.55371 -43.121424) (xy 328.583431 -43.075456) (xy 328.60107 -43.054524)
			(xy 328.601324 -43.05427) (xy 328.60689 -43.04717) (xy 328.613148 -43.030263) (xy 328.613516 -43.02125)
			(xy 328.613516 -42.954194) (xy 328.613158 -42.945177) (xy 328.606911 -42.928261) (xy 328.601324 -42.921174)
			(xy 328.60107 -42.921174) (xy 328.60107 -42.92092) (xy 328.583422 -42.899995) (xy 328.553713 -42.85402)
			(xy 328.530879 -42.80427) (xy 328.51539 -42.751768) (xy 328.507563 -42.697592) (xy 328.50709 -42.670222)
			(xy 328.50763 -42.641484) (xy 328.516249 -42.584657) (xy 328.533295 -42.529767) (xy 328.558383 -42.478055)
			(xy 328.590945 -42.430691) (xy 328.610214 -42.409364) (xy 328.616818 -42.402506) (xy 328.62393 -42.384472)
			(xy 328.62393 -42.295572) (xy 328.616818 -42.277538) (xy 328.610214 -42.27068) (xy 328.590965 -42.249334)
			(xy 328.5584 -42.201975) (xy 328.533308 -42.150266) (xy 328.516257 -42.095378) (xy 328.507633 -42.038554)
			(xy 328.50763 -41.981078) (xy 328.51625 -41.924253) (xy 328.533296 -41.869364) (xy 328.558384 -41.817653)
			(xy 328.590945 -41.770291) (xy 328.610214 -41.748964) (xy 328.616818 -41.742106) (xy 328.62393 -41.724072)
			(xy 328.62393 -41.635172) (xy 328.616818 -41.617138) (xy 328.610214 -41.61028) (xy 328.59095 -41.588947)
			(xy 328.558383 -41.541587) (xy 328.53329 -41.489876) (xy 328.516238 -41.434987) (xy 328.507613 -41.378161)
			(xy 328.50709 -41.349422) (xy 328.507576 -41.322171) (xy 328.515332 -41.268223) (xy 328.530687 -41.215928)
			(xy 328.553329 -41.166351) (xy 328.582795 -41.120501) (xy 328.618486 -41.07931) (xy 328.659677 -41.043619)
			(xy 328.705527 -41.014153) (xy 328.755104 -40.991511) (xy 328.807399 -40.976156) (xy 328.861347 -40.9684)
			(xy 328.915849 -40.9684) (xy 328.969797 -40.976156) (xy 329.022092 -40.991511) (xy 329.071669 -41.014153)
			(xy 329.117519 -41.043619) (xy 329.15871 -41.07931) (xy 329.194401 -41.120501) (xy 329.223867 -41.166351)
			(xy 329.246509 -41.215928) (xy 329.261864 -41.268223) (xy 329.26962 -41.322171) (xy 329.270106 -41.349422)
			(xy 329.269594 -41.378161) (xy 329.260968 -41.434989) (xy 329.243915 -41.48988) (xy 329.218821 -41.541591)
			(xy 329.186254 -41.588954) (xy 329.166982 -41.61028) (xy 329.160378 -41.617138) (xy 329.153266 -41.635172)
			(xy 329.153266 -41.724072) (xy 329.160378 -41.742106) (xy 329.166982 -41.748964) (xy 329.186274 -41.770272)
			(xy 329.218838 -41.817638) (xy 329.243928 -41.869353) (xy 329.260976 -41.924246) (xy 329.269597 -41.981076)
			(xy 329.269594 -42.038556) (xy 329.260969 -42.095385) (xy 329.243917 -42.150277) (xy 329.218822 -42.20199)
			(xy 329.186254 -42.249353) (xy 329.166982 -42.27068) (xy 329.160378 -42.277538) (xy 329.153266 -42.295572)
			(xy 329.153266 -42.384472) (xy 329.160378 -42.402506) (xy 329.166982 -42.409364) (xy 329.186266 -42.430679)
			(xy 329.21883 -42.478045) (xy 329.24392 -42.529759) (xy 329.260967 -42.584653) (xy 329.269587 -42.641482)
			(xy 329.270106 -42.670222) (xy 329.269651 -42.697593) (xy 329.261831 -42.751772) (xy 329.246339 -42.804275)
			(xy 329.225784 -42.849038) (xy 331.091792 -42.849038) (xy 331.095863 -42.793416) (xy 331.107989 -42.738979)
			(xy 331.127912 -42.686888) (xy 331.155208 -42.638253) (xy 331.189294 -42.59411) (xy 331.229443 -42.555401)
			(xy 331.274801 -42.52295) (xy 331.324401 -42.497449) (xy 331.377185 -42.479442) (xy 331.432028 -42.469312)
			(xy 331.487762 -42.467275) (xy 331.543199 -42.473375) (xy 331.597156 -42.487481) (xy 331.648485 -42.509293)
			(xy 331.696091 -42.538347) (xy 331.738959 -42.574022) (xy 331.776176 -42.615559) (xy 331.806949 -42.662072)
			(xy 331.830621 -42.712569) (xy 331.846689 -42.765976) (xy 331.854809 -42.821152) (xy 331.855318 -42.849038)
			(xy 331.854809 -42.876924) (xy 331.846689 -42.9321) (xy 331.830621 -42.985507) (xy 331.806949 -43.036004)
			(xy 331.776176 -43.082517) (xy 331.738959 -43.124054) (xy 331.696091 -43.159729) (xy 331.648485 -43.188783)
			(xy 331.597156 -43.210595) (xy 331.543199 -43.224701) (xy 331.487762 -43.230801) (xy 331.432028 -43.228764)
			(xy 331.377185 -43.218634) (xy 331.324401 -43.200627) (xy 331.274801 -43.175126) (xy 331.229443 -43.142675)
			(xy 331.189294 -43.103966) (xy 331.155208 -43.059823) (xy 331.127912 -43.011188) (xy 331.107989 -42.959097)
			(xy 331.095863 -42.90466) (xy 331.091792 -42.849038) (xy 329.225784 -42.849038) (xy 329.223495 -42.854022)
			(xy 329.193768 -42.899988) (xy 329.176126 -42.92092) (xy 329.175872 -42.921174) (xy 329.170287 -42.928262)
			(xy 329.16404 -42.945178) (xy 329.16368 -42.954194) (xy 329.16368 -43.02125) (xy 329.164065 -43.030264)
			(xy 329.170294 -43.047181) (xy 329.175872 -43.05427) (xy 329.176126 -43.05427) (xy 329.176126 -43.054524)
			(xy 329.193747 -43.075471) (xy 329.223461 -43.12144) (xy 329.2463 -43.171184) (xy 329.261795 -43.223681)
			(xy 329.269629 -43.277854) (xy 329.270106 -43.305222) (xy 329.26962 -43.332473) (xy 329.261864 -43.386421)
			(xy 329.246509 -43.438716) (xy 329.223867 -43.488293) (xy 329.194401 -43.534143) (xy 329.15871 -43.575334)
			(xy 329.117519 -43.611025) (xy 329.071669 -43.640491) (xy 329.022092 -43.663133) (xy 328.969797 -43.678488)
			(xy 328.915849 -43.686244) (xy 328.861347 -43.686244) (xy 328.807399 -43.678488) (xy 328.755104 -43.663133)
			(xy 328.705527 -43.640491) (xy 328.659677 -43.611025) (xy 328.618486 -43.575334) (xy 328.582795 -43.534143)
			(xy 328.553329 -43.488293) (xy 328.530687 -43.438716) (xy 328.515332 -43.386421) (xy 328.507576 -43.332473)
			(xy 328.50709 -43.305222) (xy 319.904912 -43.305222) (xy 320.282317 -43.73626) (xy 330.41285 -43.73626)
			(xy 330.416921 -43.680638) (xy 330.429047 -43.626201) (xy 330.44897 -43.57411) (xy 330.476266 -43.525475)
			(xy 330.510352 -43.481332) (xy 330.550501 -43.442623) (xy 330.595859 -43.410172) (xy 330.645459 -43.384671)
			(xy 330.698243 -43.366664) (xy 330.753086 -43.356534) (xy 330.80882 -43.354497) (xy 330.864257 -43.360597)
			(xy 330.918214 -43.374703) (xy 330.969543 -43.396515) (xy 331.017149 -43.425569) (xy 331.060017 -43.461244)
			(xy 331.097234 -43.502781) (xy 331.128007 -43.549294) (xy 331.136233 -43.566842) (xy 333.53324 -43.566842)
			(xy 333.537311 -43.51122) (xy 333.549437 -43.456783) (xy 333.56936 -43.404692) (xy 333.596656 -43.356057)
			(xy 333.630742 -43.311914) (xy 333.670891 -43.273205) (xy 333.716249 -43.240754) (xy 333.765849 -43.215253)
			(xy 333.818633 -43.197246) (xy 333.873476 -43.187116) (xy 333.92921 -43.185079) (xy 333.984647 -43.191179)
			(xy 334.038604 -43.205285) (xy 334.089933 -43.227097) (xy 334.137539 -43.256151) (xy 334.180407 -43.291826)
			(xy 334.217624 -43.333363) (xy 334.248397 -43.379876) (xy 334.272069 -43.430373) (xy 334.288137 -43.48378)
			(xy 334.296257 -43.538956) (xy 334.296766 -43.566842) (xy 334.296257 -43.594728) (xy 334.288137 -43.649904)
			(xy 334.272069 -43.703311) (xy 334.248397 -43.753808) (xy 334.217624 -43.800321) (xy 334.180407 -43.841858)
			(xy 334.16232 -43.85691) (xy 334.919572 -43.85691) (xy 334.923643 -43.801288) (xy 334.935769 -43.746851)
			(xy 334.955692 -43.69476) (xy 334.982988 -43.646125) (xy 335.017074 -43.601982) (xy 335.057223 -43.563273)
			(xy 335.102581 -43.530822) (xy 335.152181 -43.505321) (xy 335.204965 -43.487314) (xy 335.259808 -43.477184)
			(xy 335.315542 -43.475147) (xy 335.370979 -43.481247) (xy 335.424936 -43.495353) (xy 335.476265 -43.517165)
			(xy 335.523871 -43.546219) (xy 335.566739 -43.581894) (xy 335.603956 -43.623431) (xy 335.634729 -43.669944)
			(xy 335.658401 -43.720441) (xy 335.674469 -43.773848) (xy 335.682589 -43.829024) (xy 335.683098 -43.85691)
			(xy 335.682589 -43.884796) (xy 335.674469 -43.939972) (xy 335.658401 -43.993379) (xy 335.634729 -44.043876)
			(xy 335.603956 -44.090389) (xy 335.566739 -44.131926) (xy 335.523871 -44.167601) (xy 335.476265 -44.196655)
			(xy 335.424936 -44.218467) (xy 335.370979 -44.232573) (xy 335.315542 -44.238673) (xy 335.259808 -44.236636)
			(xy 335.204965 -44.226506) (xy 335.152181 -44.208499) (xy 335.102581 -44.182998) (xy 335.057223 -44.150547)
			(xy 335.017074 -44.111838) (xy 334.982988 -44.067695) (xy 334.955692 -44.01906) (xy 334.935769 -43.966969)
			(xy 334.923643 -43.912532) (xy 334.919572 -43.85691) (xy 334.16232 -43.85691) (xy 334.137539 -43.877533)
			(xy 334.089933 -43.906587) (xy 334.038604 -43.928399) (xy 333.984647 -43.942505) (xy 333.92921 -43.948605)
			(xy 333.873476 -43.946568) (xy 333.818633 -43.936438) (xy 333.765849 -43.918431) (xy 333.716249 -43.89293)
			(xy 333.670891 -43.860479) (xy 333.630742 -43.82177) (xy 333.596656 -43.777627) (xy 333.56936 -43.728992)
			(xy 333.549437 -43.676901) (xy 333.537311 -43.622464) (xy 333.53324 -43.566842) (xy 331.136233 -43.566842)
			(xy 331.151679 -43.599791) (xy 331.167747 -43.653198) (xy 331.175867 -43.708374) (xy 331.176376 -43.73626)
			(xy 331.175867 -43.764146) (xy 331.167747 -43.819322) (xy 331.151679 -43.872729) (xy 331.128007 -43.923226)
			(xy 331.097234 -43.969739) (xy 331.060017 -44.011276) (xy 331.017149 -44.046951) (xy 330.969543 -44.076005)
			(xy 330.918214 -44.097817) (xy 330.864257 -44.111923) (xy 330.80882 -44.118023) (xy 330.753086 -44.115986)
			(xy 330.698243 -44.105856) (xy 330.645459 -44.087849) (xy 330.595859 -44.062348) (xy 330.550501 -44.029897)
			(xy 330.510352 -43.991188) (xy 330.476266 -43.947045) (xy 330.44897 -43.89841) (xy 330.429047 -43.846319)
			(xy 330.416921 -43.791882) (xy 330.41285 -43.73626) (xy 320.282317 -43.73626) (xy 321.489034 -45.114464)
			(xy 330.265276 -45.114464) (xy 330.269347 -45.058842) (xy 330.281473 -45.004405) (xy 330.301396 -44.952314)
			(xy 330.328692 -44.903679) (xy 330.362778 -44.859536) (xy 330.402927 -44.820827) (xy 330.448285 -44.788376)
			(xy 330.497885 -44.762875) (xy 330.550669 -44.744868) (xy 330.605512 -44.734738) (xy 330.661246 -44.732701)
			(xy 330.716683 -44.738801) (xy 330.77064 -44.752907) (xy 330.821969 -44.774719) (xy 330.869575 -44.803773)
			(xy 330.912443 -44.839448) (xy 330.94966 -44.880985) (xy 330.980433 -44.927498) (xy 331.004105 -44.977995)
			(xy 331.020173 -45.031402) (xy 331.028293 -45.086578) (xy 331.028802 -45.114464) (xy 331.028293 -45.14235)
			(xy 331.020173 -45.197526) (xy 331.004105 -45.250933) (xy 330.980433 -45.30143) (xy 330.94966 -45.347943)
			(xy 330.944018 -45.35424) (xy 334.90357 -45.35424) (xy 334.907641 -45.298618) (xy 334.919767 -45.244181)
			(xy 334.93969 -45.19209) (xy 334.966986 -45.143455) (xy 335.001072 -45.099312) (xy 335.041221 -45.060603)
			(xy 335.086579 -45.028152) (xy 335.136179 -45.002651) (xy 335.188963 -44.984644) (xy 335.243806 -44.974514)
			(xy 335.29954 -44.972477) (xy 335.354977 -44.978577) (xy 335.408934 -44.992683) (xy 335.460263 -45.014495)
			(xy 335.507869 -45.043549) (xy 335.550737 -45.079224) (xy 335.587954 -45.120761) (xy 335.618727 -45.167274)
			(xy 335.642399 -45.217771) (xy 335.658467 -45.271178) (xy 335.666587 -45.326354) (xy 335.667096 -45.35424)
			(xy 335.666587 -45.382126) (xy 335.658467 -45.437302) (xy 335.642399 -45.490709) (xy 335.618727 -45.541206)
			(xy 335.587954 -45.587719) (xy 335.550737 -45.629256) (xy 335.507869 -45.664931) (xy 335.460263 -45.693985)
			(xy 335.408934 -45.715797) (xy 335.354977 -45.729903) (xy 335.29954 -45.736003) (xy 335.243806 -45.733966)
			(xy 335.188963 -45.723836) (xy 335.136179 -45.705829) (xy 335.086579 -45.680328) (xy 335.041221 -45.647877)
			(xy 335.001072 -45.609168) (xy 334.966986 -45.565025) (xy 334.93969 -45.51639) (xy 334.919767 -45.464299)
			(xy 334.907641 -45.409862) (xy 334.90357 -45.35424) (xy 330.944018 -45.35424) (xy 330.912443 -45.38948)
			(xy 330.869575 -45.425155) (xy 330.821969 -45.454209) (xy 330.77064 -45.476021) (xy 330.716683 -45.490127)
			(xy 330.661246 -45.496227) (xy 330.605512 -45.49419) (xy 330.550669 -45.48406) (xy 330.497885 -45.466053)
			(xy 330.448285 -45.440552) (xy 330.402927 -45.408101) (xy 330.362778 -45.369392) (xy 330.328692 -45.325249)
			(xy 330.301396 -45.276614) (xy 330.281473 -45.224523) (xy 330.269347 -45.170086) (xy 330.265276 -45.114464)
			(xy 321.489034 -45.114464) (xy 322.336361 -46.082204) (xy 328.252328 -46.082204) (xy 328.252759 -46.05495)
			(xy 328.260517 -46.000996) (xy 328.275874 -45.948695) (xy 328.298519 -45.899113) (xy 328.327989 -45.853258)
			(xy 328.363687 -45.812064) (xy 328.404883 -45.77637) (xy 328.450741 -45.746903) (xy 328.500325 -45.724263)
			(xy 328.552627 -45.70891) (xy 328.606582 -45.701157) (xy 328.633836 -45.700696) (xy 328.66074 -45.701131)
			(xy 328.714011 -45.708708) (xy 328.76569 -45.723692) (xy 328.814751 -45.745786) (xy 328.860224 -45.774553)
			(xy 328.901204 -45.809422) (xy 328.936881 -45.849701) (xy 328.952098 -45.871892) (xy 328.95921 -45.882814)
			(xy 328.98207 -45.894752) (xy 329.094338 -45.89272) (xy 329.11669 -45.879766) (xy 329.123548 -45.86859)
			(xy 329.13845 -45.844976) (xy 329.174133 -45.802024) (xy 329.215694 -45.764732) (xy 329.262247 -45.733896)
			(xy 329.312798 -45.710175) (xy 329.366266 -45.694075) (xy 329.42151 -45.68594) (xy 329.44943 -45.685456)
			(xy 329.476424 -45.6859) (xy 329.529873 -45.69351) (xy 329.581716 -45.708574) (xy 329.630921 -45.730792)
			(xy 329.676504 -45.75972) (xy 329.697334 -45.776896) (xy 329.705462 -45.784008) (xy 329.726036 -45.790104)
			(xy 329.81138 -45.779182) (xy 329.821925 -45.777408) (xy 329.840208 -45.766353) (xy 329.846686 -45.757846)
			(xy 329.862055 -45.736627) (xy 329.897639 -45.698174) (xy 329.938153 -45.664954) (xy 329.982834 -45.637594)
			(xy 330.03084 -45.616609) (xy 330.081266 -45.602393) (xy 330.133164 -45.595215) (xy 330.15936 -45.594778)
			(xy 330.186614 -45.595267) (xy 330.240567 -45.603019) (xy 330.292868 -45.618371) (xy 330.342451 -45.64101)
			(xy 330.388308 -45.670476) (xy 330.429503 -45.706168) (xy 330.4652 -45.74736) (xy 330.494671 -45.793214)
			(xy 330.517315 -45.842795) (xy 330.532673 -45.895094) (xy 330.540431 -45.949046) (xy 330.540431 -46.003554)
			(xy 330.532673 -46.057506) (xy 330.517315 -46.109805) (xy 330.494671 -46.159386) (xy 330.4652 -46.20524)
			(xy 330.429503 -46.246432) (xy 330.388308 -46.282124) (xy 330.342451 -46.31159) (xy 330.292868 -46.334229)
			(xy 330.240567 -46.349581) (xy 330.186614 -46.357333) (xy 330.15936 -46.357794) (xy 330.132366 -46.357344)
			(xy 330.078918 -46.349734) (xy 330.027075 -46.33467) (xy 329.977871 -46.312454) (xy 329.932287 -46.283528)
			(xy 329.911456 -46.266354) (xy 329.903328 -46.259242) (xy 329.882754 -46.253146) (xy 329.79741 -46.264068)
			(xy 329.786869 -46.265855) (xy 329.768586 -46.276902) (xy 329.762104 -46.285404) (xy 329.744487 -46.309701)
			(xy 329.702894 -46.352963) (xy 329.6793 -46.37151) (xy 329.671426 -46.377352) (xy 329.661012 -46.394878)
			(xy 329.647804 -46.485302) (xy 329.65263 -46.504606) (xy 329.658472 -46.51248) (xy 329.658472 -46.512734)
			(xy 329.675975 -46.537478) (xy 329.703777 -46.591331) (xy 329.722714 -46.648903) (xy 329.729917 -46.693836)
			(xy 334.87614 -46.693836) (xy 334.876626 -46.666585) (xy 334.884382 -46.612637) (xy 334.899737 -46.560342)
			(xy 334.922379 -46.510765) (xy 334.951845 -46.464915) (xy 334.987536 -46.423724) (xy 335.028727 -46.388033)
			(xy 335.074577 -46.358567) (xy 335.124154 -46.335925) (xy 335.176449 -46.32057) (xy 335.230397 -46.312814)
			(xy 335.284899 -46.312814) (xy 335.338847 -46.32057) (xy 335.391142 -46.335925) (xy 335.440719 -46.358567)
			(xy 335.486569 -46.388033) (xy 335.52776 -46.423724) (xy 335.563451 -46.464915) (xy 335.592917 -46.510765)
			(xy 335.615559 -46.560342) (xy 335.630914 -46.612637) (xy 335.63867 -46.666585) (xy 335.639156 -46.693836)
			(xy 335.638689 -46.720264) (xy 335.631379 -46.772612) (xy 335.616904 -46.823447) (xy 335.595542 -46.871793)
			(xy 335.582006 -46.894496) (xy 335.581752 -46.89475) (xy 335.576415 -46.904768) (xy 335.574158 -46.927318)
			(xy 335.577434 -46.938184) (xy 335.603596 -47.01286) (xy 335.60796 -47.023386) (xy 335.624062 -47.03947)
			(xy 335.634584 -47.043848) (xy 335.634838 -47.043848) (xy 335.659345 -47.052922) (xy 335.705798 -47.076864)
			(xy 335.74855 -47.106919) (xy 335.786802 -47.142525) (xy 335.819839 -47.183018) (xy 335.847043 -47.227638)
			(xy 335.867905 -47.275553) (xy 335.882035 -47.325866) (xy 335.889169 -47.377636) (xy 335.8896 -47.403766)
			(xy 335.889114 -47.431017) (xy 335.881358 -47.484965) (xy 335.866003 -47.53726) (xy 335.843361 -47.586837)
			(xy 335.813895 -47.632687) (xy 335.778204 -47.673878) (xy 335.737013 -47.709569) (xy 335.691163 -47.739035)
			(xy 335.641586 -47.761677) (xy 335.589291 -47.777032) (xy 335.535343 -47.784788) (xy 335.480841 -47.784788)
			(xy 335.426893 -47.777032) (xy 335.374598 -47.761677) (xy 335.325021 -47.739035) (xy 335.279171 -47.709569)
			(xy 335.23798 -47.673878) (xy 335.202289 -47.632687) (xy 335.172823 -47.586837) (xy 335.150181 -47.53726)
			(xy 335.134826 -47.484965) (xy 335.12707 -47.431017) (xy 335.126584 -47.403766) (xy 335.12706 -47.377339)
			(xy 335.134369 -47.324991) (xy 335.148841 -47.274157) (xy 335.1702 -47.225809) (xy 335.183734 -47.203106)
			(xy 335.183988 -47.202852) (xy 335.189323 -47.192834) (xy 335.19158 -47.170284) (xy 335.188306 -47.159418)
			(xy 335.162144 -47.084742) (xy 335.157761 -47.074226) (xy 335.141672 -47.058138) (xy 335.131156 -47.053754)
			(xy 335.130902 -47.053754) (xy 335.106383 -47.044712) (xy 335.059932 -47.020764) (xy 335.017181 -46.990703)
			(xy 334.978931 -46.955091) (xy 334.945896 -46.914595) (xy 334.918694 -46.869971) (xy 334.897834 -46.822054)
			(xy 334.883705 -46.771739) (xy 334.876571 -46.719967) (xy 334.87614 -46.693836) (xy 329.729917 -46.693836)
			(xy 329.732307 -46.708745) (xy 329.732894 -46.739048) (xy 329.732467 -46.766301) (xy 329.724703 -46.820252)
			(xy 329.709341 -46.872548) (xy 329.686694 -46.922127) (xy 329.657221 -46.967977) (xy 329.621524 -47.009167)
			(xy 329.580328 -47.044858) (xy 329.534472 -47.074323) (xy 329.48489 -47.096963) (xy 329.432591 -47.112317)
			(xy 329.378639 -47.120071) (xy 329.351386 -47.120556) (xy 329.325352 -47.12011) (xy 329.27377 -47.113021)
			(xy 329.223628 -47.098992) (xy 329.175857 -47.078281) (xy 329.131342 -47.051272) (xy 329.110848 -47.035212)
			(xy 329.103084 -47.029482) (xy 329.084679 -47.023734) (xy 329.075034 -47.024036) (xy 328.995278 -47.030386)
			(xy 328.977498 -47.039022) (xy 328.971148 -47.046388) (xy 328.952966 -47.066033) (xy 328.912059 -47.100555)
			(xy 328.86673 -47.129024) (xy 328.817869 -47.150882) (xy 328.766433 -47.1657) (xy 328.713432 -47.173187)
			(xy 328.686668 -47.173642) (xy 328.659418 -47.173152) (xy 328.605472 -47.165392) (xy 328.553179 -47.150035)
			(xy 328.503604 -47.127392) (xy 328.457755 -47.097926) (xy 328.416566 -47.062235) (xy 328.380875 -47.021046)
			(xy 328.351409 -46.975198) (xy 328.328766 -46.925623) (xy 328.313408 -46.87333) (xy 328.305648 -46.819384)
			(xy 328.30516 -46.792134) (xy 328.305695 -46.76336) (xy 328.314345 -46.706467) (xy 328.33144 -46.651517)
			(xy 328.35659 -46.599757) (xy 328.389228 -46.55236) (xy 328.408538 -46.531022) (xy 328.415904 -46.523148)
			(xy 328.423016 -46.503336) (xy 328.41565 -46.40707) (xy 328.405744 -46.388274) (xy 328.397362 -46.38167)
			(xy 328.375186 -46.363435) (xy 328.335974 -46.321503) (xy 328.303486 -46.27417) (xy 328.278455 -46.222504)
			(xy 328.261448 -46.167671) (xy 328.252846 -46.110909) (xy 328.252328 -46.082204) (xy 322.336361 -46.082204)
			(xy 323.097398 -46.951392) (xy 323.125935 -46.984709) (xy 323.177702 -47.055538) (xy 323.223046 -47.130642)
			(xy 323.261617 -47.209439) (xy 323.293115 -47.29132) (xy 323.317298 -47.375651) (xy 323.333977 -47.461781)
			(xy 323.338952 -47.505366) (xy 323.360796 -47.713646) (xy 323.422522 -48.30699) (xy 334.75371 -48.30699)
			(xy 334.757781 -48.251368) (xy 334.769907 -48.196931) (xy 334.78983 -48.14484) (xy 334.817126 -48.096205)
			(xy 334.851212 -48.052062) (xy 334.891361 -48.013353) (xy 334.936719 -47.980902) (xy 334.986319 -47.955401)
			(xy 335.039103 -47.937394) (xy 335.093946 -47.927264) (xy 335.14968 -47.925227) (xy 335.205117 -47.931327)
			(xy 335.259074 -47.945433) (xy 335.310403 -47.967245) (xy 335.358009 -47.996299) (xy 335.400877 -48.031974)
			(xy 335.438094 -48.073511) (xy 335.468867 -48.120024) (xy 335.492539 -48.170521) (xy 335.508607 -48.223928)
			(xy 335.516727 -48.279104) (xy 335.517236 -48.30699) (xy 335.516727 -48.334876) (xy 335.508607 -48.390052)
			(xy 335.492539 -48.443459) (xy 335.468867 -48.493956) (xy 335.438094 -48.540469) (xy 335.400877 -48.582006)
			(xy 335.358009 -48.617681) (xy 335.310403 -48.646735) (xy 335.259074 -48.668547) (xy 335.205117 -48.682653)
			(xy 335.14968 -48.688753) (xy 335.093946 -48.686716) (xy 335.039103 -48.676586) (xy 334.986319 -48.658579)
			(xy 334.936719 -48.633078) (xy 334.891361 -48.600627) (xy 334.851212 -48.561918) (xy 334.817126 -48.517775)
			(xy 334.78983 -48.46914) (xy 334.769907 -48.417049) (xy 334.757781 -48.362612) (xy 334.75371 -48.30699)
			(xy 323.422522 -48.30699) (xy 323.44995 -48.570642) (xy 323.468973 -48.753014) (xy 331.368144 -48.753014)
			(xy 331.372215 -48.697392) (xy 331.384341 -48.642955) (xy 331.404264 -48.590864) (xy 331.43156 -48.542229)
			(xy 331.465646 -48.498086) (xy 331.505795 -48.459377) (xy 331.551153 -48.426926) (xy 331.600753 -48.401425)
			(xy 331.653537 -48.383418) (xy 331.70838 -48.373288) (xy 331.764114 -48.371251) (xy 331.819551 -48.377351)
			(xy 331.873508 -48.391457) (xy 331.924837 -48.413269) (xy 331.972443 -48.442323) (xy 332.015311 -48.477998)
			(xy 332.052528 -48.519535) (xy 332.083301 -48.566048) (xy 332.106973 -48.616545) (xy 332.123041 -48.669952)
			(xy 332.131161 -48.725128) (xy 332.13167 -48.753014) (xy 332.131161 -48.7809) (xy 332.123041 -48.836076)
			(xy 332.120597 -48.8442) (xy 332.387192 -48.8442) (xy 332.391263 -48.788578) (xy 332.403389 -48.734141)
			(xy 332.423312 -48.68205) (xy 332.450608 -48.633415) (xy 332.484694 -48.589272) (xy 332.524843 -48.550563)
			(xy 332.570201 -48.518112) (xy 332.619801 -48.492611) (xy 332.672585 -48.474604) (xy 332.727428 -48.464474)
			(xy 332.783162 -48.462437) (xy 332.838599 -48.468537) (xy 332.892556 -48.482643) (xy 332.943885 -48.504455)
			(xy 332.991491 -48.533509) (xy 333.034359 -48.569184) (xy 333.071576 -48.610721) (xy 333.102349 -48.657234)
			(xy 333.126021 -48.707731) (xy 333.142089 -48.761138) (xy 333.150209 -48.816314) (xy 333.150718 -48.8442)
			(xy 333.150209 -48.872086) (xy 333.147211 -48.89246) (xy 333.41386 -48.89246) (xy 333.417931 -48.836838)
			(xy 333.430057 -48.782401) (xy 333.44998 -48.73031) (xy 333.477276 -48.681675) (xy 333.511362 -48.637532)
			(xy 333.551511 -48.598823) (xy 333.596869 -48.566372) (xy 333.646469 -48.540871) (xy 333.699253 -48.522864)
			(xy 333.754096 -48.512734) (xy 333.80983 -48.510697) (xy 333.865267 -48.516797) (xy 333.919224 -48.530903)
			(xy 333.970553 -48.552715) (xy 334.018159 -48.581769) (xy 334.061027 -48.617444) (xy 334.098244 -48.658981)
			(xy 334.129017 -48.705494) (xy 334.152689 -48.755991) (xy 334.168757 -48.809398) (xy 334.176877 -48.864574)
			(xy 334.177386 -48.89246) (xy 334.176877 -48.920346) (xy 334.168757 -48.975522) (xy 334.152689 -49.028929)
			(xy 334.129017 -49.079426) (xy 334.098244 -49.125939) (xy 334.061027 -49.167476) (xy 334.018159 -49.203151)
			(xy 333.970553 -49.232205) (xy 333.919224 -49.254017) (xy 333.865267 -49.268123) (xy 333.80983 -49.274223)
			(xy 333.754096 -49.272186) (xy 333.699253 -49.262056) (xy 333.646469 -49.244049) (xy 333.596869 -49.218548)
			(xy 333.551511 -49.186097) (xy 333.511362 -49.147388) (xy 333.477276 -49.103245) (xy 333.44998 -49.05461)
			(xy 333.430057 -49.002519) (xy 333.417931 -48.948082) (xy 333.41386 -48.89246) (xy 333.147211 -48.89246)
			(xy 333.142089 -48.927262) (xy 333.126021 -48.980669) (xy 333.102349 -49.031166) (xy 333.071576 -49.077679)
			(xy 333.034359 -49.119216) (xy 332.991491 -49.154891) (xy 332.943885 -49.183945) (xy 332.892556 -49.205757)
			(xy 332.838599 -49.219863) (xy 332.783162 -49.225963) (xy 332.727428 -49.223926) (xy 332.672585 -49.213796)
			(xy 332.619801 -49.195789) (xy 332.570201 -49.170288) (xy 332.524843 -49.137837) (xy 332.484694 -49.099128)
			(xy 332.450608 -49.054985) (xy 332.423312 -49.00635) (xy 332.403389 -48.954259) (xy 332.391263 -48.899822)
			(xy 332.387192 -48.8442) (xy 332.120597 -48.8442) (xy 332.106973 -48.889483) (xy 332.083301 -48.93998)
			(xy 332.052528 -48.986493) (xy 332.015311 -49.02803) (xy 331.972443 -49.063705) (xy 331.924837 -49.092759)
			(xy 331.873508 -49.114571) (xy 331.819551 -49.128677) (xy 331.764114 -49.134777) (xy 331.70838 -49.13274)
			(xy 331.653537 -49.12261) (xy 331.600753 -49.104603) (xy 331.551153 -49.079102) (xy 331.505795 -49.046651)
			(xy 331.465646 -49.007942) (xy 331.43156 -48.963799) (xy 331.404264 -48.915164) (xy 331.384341 -48.863073)
			(xy 331.372215 -48.808636) (xy 331.368144 -48.753014) (xy 323.468973 -48.753014) (xy 323.517006 -49.213516)
			(xy 323.519546 -49.224946) (xy 323.722746 -49.81067) (xy 323.736971 -49.853106) (xy 323.758596 -49.939961)
			(xy 323.772269 -50.028418) (xy 323.775578 -50.073052) (xy 323.784214 -50.210212) (xy 323.834983 -51.019456)
			(xy 334.94929 -51.019456) (xy 334.953361 -50.963834) (xy 334.965487 -50.909397) (xy 334.98541 -50.857306)
			(xy 335.012706 -50.808671) (xy 335.046792 -50.764528) (xy 335.086941 -50.725819) (xy 335.132299 -50.693368)
			(xy 335.181899 -50.667867) (xy 335.234683 -50.64986) (xy 335.289526 -50.63973) (xy 335.34526 -50.637693)
			(xy 335.400697 -50.643793) (xy 335.454654 -50.657899) (xy 335.505983 -50.679711) (xy 335.553589 -50.708765)
			(xy 335.596457 -50.74444) (xy 335.633674 -50.785977) (xy 335.664447 -50.83249) (xy 335.688119 -50.882987)
			(xy 335.704187 -50.936394) (xy 335.712307 -50.99157) (xy 335.712816 -51.019456) (xy 335.712307 -51.047342)
			(xy 335.704187 -51.102518) (xy 335.688119 -51.155925) (xy 335.664447 -51.206422) (xy 335.633674 -51.252935)
			(xy 335.596457 -51.294472) (xy 335.553589 -51.330147) (xy 335.505983 -51.359201) (xy 335.454654 -51.381013)
			(xy 335.400697 -51.395119) (xy 335.34526 -51.401219) (xy 335.289526 -51.399182) (xy 335.234683 -51.389052)
			(xy 335.181899 -51.371045) (xy 335.132299 -51.345544) (xy 335.086941 -51.313093) (xy 335.046792 -51.274384)
			(xy 335.012706 -51.230241) (xy 334.98541 -51.181606) (xy 334.965487 -51.129515) (xy 334.953361 -51.075078)
			(xy 334.94929 -51.019456) (xy 323.834983 -51.019456) (xy 323.918834 -52.356004) (xy 323.920358 -52.36591)
			(xy 323.922811 -52.373765) (xy 323.931881 -52.387487) (xy 323.938138 -52.392834) (xy 323.958966 -52.409344)
			(xy 323.968872 -52.415694) (xy 323.976875 -52.419071) (xy 323.99415 -52.420763) (xy 324.002654 -52.418996)
			(xy 324.027039 -52.413423) (xy 324.076703 -52.407433) (xy 324.101714 -52.407058) (xy 324.101968 -52.407058)
			(xy 324.131926 -52.407565) (xy 324.191231 -52.416088) (xy 324.24872 -52.432964) (xy 324.303222 -52.457851)
			(xy 324.353627 -52.490242) (xy 324.398909 -52.529477) (xy 324.438146 -52.574757) (xy 324.470539 -52.62516)
			(xy 324.495429 -52.679661) (xy 324.512308 -52.737149) (xy 324.520834 -52.796454) (xy 324.521322 -52.826412)
			(xy 324.520874 -52.853854) (xy 324.513715 -52.90827) (xy 324.499521 -52.961288) (xy 324.478534 -53.012001)
			(xy 324.451113 -53.059545) (xy 324.417726 -53.103107) (xy 324.39864 -53.12283) (xy 324.393814 -53.12791)
			(xy 324.37832 -53.164232) (xy 324.37832 -53.178964) (xy 324.378687 -53.186999) (xy 324.383742 -53.202258)
			(xy 324.388226 -53.208936) (xy 324.390766 -53.211984) (xy 324.408165 -53.232856) (xy 324.437489 -53.278602)
			(xy 324.460013 -53.328051) (xy 324.475281 -53.3802) (xy 324.482981 -53.433989) (xy 324.483476 -53.461158)
			(xy 324.483476 -53.461412) (xy 324.483051 -53.486923) (xy 324.476255 -53.537491) (xy 324.462786 -53.586703)
			(xy 324.442883 -53.633683) (xy 324.416902 -53.677595) (xy 324.401434 -53.697886) (xy 324.398894 -53.700934)
			(xy 324.397878 -53.702458) (xy 324.394576 -53.709062) (xy 324.392233 -53.714285) (xy 324.389669 -53.725438)
			(xy 324.389496 -53.73116) (xy 324.389496 -53.763164) (xy 324.37832 -53.763164) (xy 324.37832 -53.813964)
			(xy 324.378655 -53.822567) (xy 324.384369 -53.838797) (xy 324.389496 -53.845714) (xy 324.390766 -53.847238)
			(xy 324.408158 -53.868115) (xy 324.437474 -53.913866) (xy 324.46 -53.963314) (xy 324.47528 -54.015458)
			(xy 324.483005 -54.069244) (xy 324.483476 -54.096412) (xy 324.483051 -54.121923) (xy 324.476255 -54.172491)
			(xy 324.462786 -54.221703) (xy 324.442883 -54.268683) (xy 324.416902 -54.312595) (xy 324.401434 -54.332886)
			(xy 324.398894 -54.335934) (xy 324.397878 -54.337458) (xy 324.394576 -54.344062) (xy 324.392233 -54.349285)
			(xy 324.389669 -54.360438) (xy 324.389496 -54.36616) (xy 324.389496 -54.398164) (xy 324.37832 -54.398164)
			(xy 324.37832 -54.448964) (xy 324.378655 -54.457567) (xy 324.384369 -54.473797) (xy 324.389496 -54.480714)
			(xy 324.390766 -54.482238) (xy 324.408158 -54.503115) (xy 324.437474 -54.548866) (xy 324.46 -54.598314)
			(xy 324.47528 -54.650458) (xy 324.483005 -54.704244) (xy 324.483476 -54.731412) (xy 324.482923 -54.760556)
			(xy 324.478221 -54.791102) (xy 326.376284 -54.791102) (xy 326.376731 -54.763731) (xy 326.38455 -54.70955)
			(xy 326.400043 -54.657046) (xy 326.422889 -54.607299) (xy 326.45262 -54.561334) (xy 326.470264 -54.540404)
			(xy 326.470518 -54.54015) (xy 326.476092 -54.533055) (xy 326.482346 -54.516145) (xy 326.48271 -54.50713)
			(xy 326.48271 -54.440074) (xy 326.482363 -54.431056) (xy 326.476108 -54.414139) (xy 326.470518 -54.407054)
			(xy 326.470264 -54.407054) (xy 326.470264 -54.4068) (xy 326.452624 -54.385866) (xy 326.422896 -54.3399)
			(xy 326.400048 -54.290154) (xy 326.38455 -54.237652) (xy 326.376721 -54.183472) (xy 326.37672 -54.128731)
			(xy 326.38455 -54.074551) (xy 326.400047 -54.022049) (xy 326.422895 -53.972303) (xy 326.452622 -53.926336)
			(xy 326.470264 -53.905404) (xy 326.470518 -53.90515) (xy 326.476092 -53.898055) (xy 326.482346 -53.881145)
			(xy 326.48271 -53.87213) (xy 326.48271 -53.805074) (xy 326.482363 -53.796056) (xy 326.476108 -53.779139)
			(xy 326.470518 -53.772054) (xy 326.470264 -53.772054) (xy 326.470264 -53.7718) (xy 326.452624 -53.750866)
			(xy 326.422896 -53.7049) (xy 326.400048 -53.655154) (xy 326.38455 -53.602652) (xy 326.376721 -53.548472)
			(xy 326.37672 -53.493731) (xy 326.38455 -53.439551) (xy 326.400047 -53.387049) (xy 326.422895 -53.337303)
			(xy 326.452622 -53.291336) (xy 326.470264 -53.270404) (xy 326.470518 -53.27015) (xy 326.476092 -53.263055)
			(xy 326.482346 -53.246145) (xy 326.48271 -53.23713) (xy 326.48271 -53.170074) (xy 326.482363 -53.161056)
			(xy 326.476108 -53.144139) (xy 326.470518 -53.137054) (xy 326.470264 -53.137054) (xy 326.470264 -53.1368)
			(xy 326.452606 -53.115883) (xy 326.422898 -53.069906) (xy 326.400066 -53.020154) (xy 326.38458 -52.96765)
			(xy 326.376756 -52.913472) (xy 326.376284 -52.886102) (xy 326.37677 -52.858851) (xy 326.384526 -52.804903)
			(xy 326.399881 -52.752608) (xy 326.422523 -52.703031) (xy 326.451989 -52.657181) (xy 326.48768 -52.61599)
			(xy 326.528871 -52.580299) (xy 326.574721 -52.550833) (xy 326.624298 -52.528191) (xy 326.676593 -52.512836)
			(xy 326.730541 -52.50508) (xy 326.785043 -52.50508) (xy 326.838991 -52.512836) (xy 326.891286 -52.528191)
			(xy 326.930399 -52.546054) (xy 331.879373 -52.546054) (xy 331.879373 -52.491546) (xy 331.887131 -52.437594)
			(xy 331.902489 -52.385294) (xy 331.925134 -52.335713) (xy 331.954605 -52.28986) (xy 331.990302 -52.248668)
			(xy 332.031499 -52.212976) (xy 332.077356 -52.183511) (xy 332.126939 -52.160872) (xy 332.179241 -52.145521)
			(xy 332.233194 -52.13777) (xy 332.260448 -52.13731) (xy 332.287817 -52.137804) (xy 332.341995 -52.145615)
			(xy 332.394498 -52.161097) (xy 332.444245 -52.183933) (xy 332.490213 -52.213651) (xy 332.511146 -52.23129)
			(xy 332.5114 -52.231544) (xy 332.518479 -52.237142) (xy 332.535402 -52.243381) (xy 332.54442 -52.243736)
			(xy 332.611476 -52.243736) (xy 332.620491 -52.24336) (xy 332.637407 -52.237125) (xy 332.644496 -52.231544)
			(xy 332.644496 -52.23129) (xy 332.64475 -52.23129) (xy 332.665683 -52.213649) (xy 332.711651 -52.183925)
			(xy 332.761397 -52.161079) (xy 332.813899 -52.145583) (xy 332.868077 -52.137754) (xy 332.922819 -52.137754)
			(xy 332.976997 -52.145583) (xy 333.029499 -52.161079) (xy 333.079245 -52.183925) (xy 333.125213 -52.213649)
			(xy 333.146146 -52.23129) (xy 333.1464 -52.231544) (xy 333.153479 -52.237142) (xy 333.170402 -52.243381)
			(xy 333.17942 -52.243736) (xy 333.246476 -52.243736) (xy 333.255491 -52.24336) (xy 333.272407 -52.237125)
			(xy 333.279496 -52.231544) (xy 333.279496 -52.23129) (xy 333.27975 -52.23129) (xy 333.300689 -52.213659)
			(xy 333.34666 -52.183947) (xy 333.396406 -52.161109) (xy 333.448905 -52.145616) (xy 333.503079 -52.137785)
			(xy 333.530448 -52.13731) (xy 333.557698 -52.137763) (xy 333.611643 -52.145526) (xy 333.663935 -52.160886)
			(xy 333.713508 -52.18353) (xy 333.759355 -52.212999) (xy 333.800541 -52.248693) (xy 333.836229 -52.289884)
			(xy 333.865693 -52.335734) (xy 333.888331 -52.38531) (xy 333.903685 -52.437604) (xy 333.91144 -52.49155)
			(xy 333.91144 -52.54605) (xy 333.905496 -52.587398) (xy 334.955132 -52.587398) (xy 334.959203 -52.531776)
			(xy 334.971329 -52.477339) (xy 334.991252 -52.425248) (xy 335.018548 -52.376613) (xy 335.052634 -52.33247)
			(xy 335.092783 -52.293761) (xy 335.138141 -52.26131) (xy 335.187741 -52.235809) (xy 335.240525 -52.217802)
			(xy 335.295368 -52.207672) (xy 335.351102 -52.205635) (xy 335.406539 -52.211735) (xy 335.460496 -52.225841)
			(xy 335.511825 -52.247653) (xy 335.559431 -52.276707) (xy 335.602299 -52.312382) (xy 335.639516 -52.353919)
			(xy 335.670289 -52.400432) (xy 335.693961 -52.450929) (xy 335.710029 -52.504336) (xy 335.718149 -52.559512)
			(xy 335.718658 -52.587398) (xy 335.718149 -52.615284) (xy 335.710029 -52.67046) (xy 335.693961 -52.723867)
			(xy 335.670289 -52.774364) (xy 335.639516 -52.820877) (xy 335.602299 -52.862414) (xy 335.559431 -52.898089)
			(xy 335.511825 -52.927143) (xy 335.460496 -52.948955) (xy 335.406539 -52.963061) (xy 335.351102 -52.969161)
			(xy 335.295368 -52.967124) (xy 335.240525 -52.956994) (xy 335.187741 -52.938987) (xy 335.138141 -52.913486)
			(xy 335.092783 -52.881035) (xy 335.052634 -52.842326) (xy 335.018548 -52.798183) (xy 334.991252 -52.749548)
			(xy 334.971329 -52.697457) (xy 334.959203 -52.64302) (xy 334.955132 -52.587398) (xy 333.905496 -52.587398)
			(xy 333.903685 -52.599996) (xy 333.888331 -52.65229) (xy 333.865693 -52.701866) (xy 333.836229 -52.747716)
			(xy 333.800541 -52.788907) (xy 333.759355 -52.824601) (xy 333.713508 -52.85407) (xy 333.663935 -52.876714)
			(xy 333.611643 -52.892074) (xy 333.557698 -52.899837) (xy 333.530448 -52.900326) (xy 333.503078 -52.89985)
			(xy 333.448899 -52.892037) (xy 333.396395 -52.876552) (xy 333.346648 -52.853712) (xy 333.300681 -52.823987)
			(xy 333.27975 -52.806346) (xy 333.279496 -52.806092) (xy 333.272415 -52.800497) (xy 333.255494 -52.794256)
			(xy 333.246476 -52.7939) (xy 333.17942 -52.7939) (xy 333.170404 -52.794266) (xy 333.153487 -52.800507)
			(xy 333.1464 -52.806092) (xy 333.146146 -52.806346) (xy 333.125213 -52.823987) (xy 333.079245 -52.853711)
			(xy 333.029499 -52.876557) (xy 332.976997 -52.892053) (xy 332.922819 -52.899882) (xy 332.868077 -52.899882)
			(xy 332.813899 -52.892053) (xy 332.761397 -52.876557) (xy 332.711651 -52.853711) (xy 332.665683 -52.823987)
			(xy 332.64475 -52.806346) (xy 332.644496 -52.806092) (xy 332.637415 -52.800497) (xy 332.620494 -52.794256)
			(xy 332.611476 -52.7939) (xy 332.54442 -52.7939) (xy 332.535404 -52.794266) (xy 332.518487 -52.800507)
			(xy 332.5114 -52.806092) (xy 332.5114 -52.806346) (xy 332.511146 -52.806346) (xy 332.4902 -52.823969)
			(xy 332.444232 -52.853685) (xy 332.394488 -52.876525) (xy 332.34199 -52.892019) (xy 332.287816 -52.899851)
			(xy 332.260448 -52.900326) (xy 332.233194 -52.89983) (xy 332.179241 -52.892079) (xy 332.126939 -52.876728)
			(xy 332.077356 -52.854089) (xy 332.031499 -52.824624) (xy 331.990302 -52.788932) (xy 331.954605 -52.74774)
			(xy 331.925134 -52.701887) (xy 331.902489 -52.652306) (xy 331.887131 -52.600006) (xy 331.879373 -52.546054)
			(xy 326.930399 -52.546054) (xy 326.940863 -52.550833) (xy 326.986713 -52.580299) (xy 327.027904 -52.61599)
			(xy 327.063595 -52.657181) (xy 327.093061 -52.703031) (xy 327.115703 -52.752608) (xy 327.131058 -52.804903)
			(xy 327.138814 -52.858851) (xy 327.1393 -52.886102) (xy 327.138835 -52.913472) (xy 327.131017 -52.967651)
			(xy 327.115528 -53.020155) (xy 327.092686 -53.069901) (xy 327.062961 -53.115868) (xy 327.04532 -53.1368)
			(xy 327.045066 -53.137054) (xy 327.039489 -53.144147) (xy 327.033238 -53.161059) (xy 327.032874 -53.170074)
			(xy 327.032874 -53.23713) (xy 327.033222 -53.246148) (xy 327.039476 -53.263064) (xy 327.045066 -53.27015)
			(xy 327.04532 -53.27015) (xy 327.04532 -53.270404) (xy 327.062961 -53.291336) (xy 327.092682 -53.337305)
			(xy 327.115524 -53.387052) (xy 327.131018 -53.439554) (xy 327.138846 -53.493731) (xy 327.138845 -53.548472)
			(xy 327.131018 -53.602649) (xy 327.115523 -53.655151) (xy 327.09268 -53.704897) (xy 327.062959 -53.750866)
			(xy 327.04639 -53.77053) (xy 327.410572 -53.77053) (xy 327.411084 -53.741613) (xy 327.419811 -53.68444)
			(xy 327.437068 -53.62924) (xy 327.462461 -53.577277) (xy 327.495407 -53.529744) (xy 327.535151 -53.487729)
			(xy 327.557638 -53.46954) (xy 327.566423 -53.461912) (xy 327.576617 -53.441027) (xy 327.577196 -53.429408)
			(xy 327.577196 -53.349652) (xy 327.576672 -53.338018) (xy 327.566473 -53.317109) (xy 327.557638 -53.30952)
			(xy 327.535172 -53.291308) (xy 327.495434 -53.249294) (xy 327.462492 -53.201764) (xy 327.4371 -53.149806)
			(xy 327.419841 -53.094612) (xy 327.411108 -53.037445) (xy 327.410572 -53.00853) (xy 327.411083 -52.981279)
			(xy 327.418836 -52.927331) (xy 327.434187 -52.875035) (xy 327.456824 -52.825456) (xy 327.486287 -52.779604)
			(xy 327.521976 -52.738411) (xy 327.563164 -52.702717) (xy 327.609012 -52.673248) (xy 327.658588 -52.650604)
			(xy 327.710882 -52.635246) (xy 327.764829 -52.627487) (xy 327.79208 -52.627022) (xy 327.818394 -52.627496)
			(xy 327.870522 -52.634728) (xy 327.921165 -52.649046) (xy 327.969364 -52.670177) (xy 328.014208 -52.697722)
			(xy 328.054848 -52.731161) (xy 328.073004 -52.750212) (xy 328.08052 -52.757619) (xy 328.099804 -52.76614)
			(xy 328.110342 -52.766722) (xy 328.185018 -52.766722) (xy 328.195563 -52.766155) (xy 328.214858 -52.757646)
			(xy 328.222356 -52.750212) (xy 328.240494 -52.731139) (xy 328.281127 -52.697683) (xy 328.325971 -52.670126)
			(xy 328.374175 -52.64899) (xy 328.424826 -52.634677) (xy 328.476963 -52.627458) (xy 328.50328 -52.627022)
			(xy 328.530534 -52.627474) (xy 328.584487 -52.635229) (xy 328.636787 -52.650584) (xy 328.686369 -52.673226)
			(xy 328.732223 -52.702695) (xy 328.773417 -52.73839) (xy 328.809111 -52.779585) (xy 328.838578 -52.82544)
			(xy 328.861219 -52.875023) (xy 328.876573 -52.927323) (xy 328.884327 -52.981276) (xy 328.884788 -53.00853)
			(xy 328.884305 -53.036196) (xy 328.876301 -53.090947) (xy 328.86048 -53.143969) (xy 328.837172 -53.194154)
			(xy 328.806866 -53.240449) (xy 328.770197 -53.281886) (xy 328.727931 -53.317598) (xy 328.704702 -53.332634)
			(xy 328.695021 -53.339266) (xy 328.682577 -53.35913) (xy 328.680826 -53.370734) (xy 328.672952 -53.450744)
			(xy 328.6723 -53.462383) (xy 328.680394 -53.484221) (xy 328.688446 -53.492654) (xy 328.6887 -53.492908)
			(xy 328.707267 -53.511003) (xy 328.739847 -53.551332) (xy 328.766662 -53.595703) (xy 328.787217 -53.643299)
			(xy 328.801133 -53.693241) (xy 328.808154 -53.744608) (xy 328.808588 -53.77053) (xy 328.80815 -53.797783)
			(xy 328.800389 -53.851733) (xy 328.785029 -53.90403) (xy 328.762383 -53.953609) (xy 328.732912 -53.99946)
			(xy 328.697215 -54.040651) (xy 328.65602 -54.076342) (xy 328.610165 -54.105807) (xy 328.560583 -54.128446)
			(xy 328.508284 -54.1438) (xy 328.454333 -54.151554) (xy 328.42708 -54.152038) (xy 328.399709 -54.151599)
			(xy 328.345528 -54.143777) (xy 328.293024 -54.128282) (xy 328.243277 -54.105434) (xy 328.197312 -54.075703)
			(xy 328.176382 -54.058058) (xy 328.176128 -54.057804) (xy 328.169037 -54.052223) (xy 328.152124 -54.045973)
			(xy 328.143108 -54.045612) (xy 328.076052 -54.045612) (xy 328.067037 -54.045991) (xy 328.05012 -54.052223)
			(xy 328.043032 -54.057804) (xy 328.043032 -54.058058) (xy 328.042778 -54.058058) (xy 328.021822 -54.075667)
			(xy 327.975856 -54.105385) (xy 327.926115 -54.128228) (xy 327.873619 -54.143725) (xy 327.819448 -54.151561)
			(xy 327.79208 -54.152038) (xy 327.76483 -54.151541) (xy 327.710884 -54.143782) (xy 327.658591 -54.128426)
			(xy 327.609016 -54.105785) (xy 327.563167 -54.076319) (xy 327.521978 -54.040629) (xy 327.486287 -53.999441)
			(xy 327.45682 -53.953593) (xy 327.434177 -53.904018) (xy 327.41882 -53.851726) (xy 327.41106 -53.79778)
			(xy 327.410572 -53.77053) (xy 327.04639 -53.77053) (xy 327.04532 -53.7718) (xy 327.045066 -53.772054)
			(xy 327.039489 -53.779147) (xy 327.033238 -53.796059) (xy 327.032874 -53.805074) (xy 327.032874 -53.87213)
			(xy 327.033222 -53.881148) (xy 327.039476 -53.898064) (xy 327.045066 -53.90515) (xy 327.04532 -53.90515)
			(xy 327.04532 -53.905404) (xy 327.062961 -53.926336) (xy 327.092682 -53.972305) (xy 327.115524 -54.022052)
			(xy 327.131018 -54.074554) (xy 327.138846 -54.128731) (xy 327.138845 -54.183472) (xy 327.131018 -54.237649)
			(xy 327.115523 -54.290151) (xy 327.101731 -54.320186) (xy 329.330304 -54.320186) (xy 329.330761 -54.292815)
			(xy 329.338581 -54.238636) (xy 329.354072 -54.186133) (xy 329.376916 -54.136386) (xy 329.406642 -54.090419)
			(xy 329.424284 -54.069488) (xy 329.424538 -54.069234) (xy 329.430121 -54.062145) (xy 329.436369 -54.04523)
			(xy 329.43673 -54.036214) (xy 329.43673 -53.969158) (xy 329.436339 -53.960145) (xy 329.430114 -53.943228)
			(xy 329.424538 -53.936138) (xy 329.424284 -53.936138) (xy 329.424284 -53.935884) (xy 329.406668 -53.914933)
			(xy 329.376954 -53.868965) (xy 329.354113 -53.819222) (xy 329.338617 -53.766726) (xy 329.330782 -53.712554)
			(xy 329.330304 -53.685186) (xy 329.33079 -53.657935) (xy 329.338546 -53.603987) (xy 329.353901 -53.551692)
			(xy 329.376543 -53.502115) (xy 329.406009 -53.456265) (xy 329.4417 -53.415074) (xy 329.482891 -53.379383)
			(xy 329.528741 -53.349917) (xy 329.578318 -53.327275) (xy 329.630613 -53.31192) (xy 329.684561 -53.304164)
			(xy 329.739063 -53.304164) (xy 329.793011 -53.31192) (xy 329.845306 -53.327275) (xy 329.894883 -53.349917)
			(xy 329.940733 -53.379383) (xy 329.981924 -53.415074) (xy 330.017615 -53.456265) (xy 330.047081 -53.502115)
			(xy 330.069723 -53.551692) (xy 330.085078 -53.603987) (xy 330.092834 -53.657935) (xy 330.09332 -53.685186)
			(xy 330.092865 -53.712557) (xy 330.085048 -53.766737) (xy 330.069557 -53.819241) (xy 330.046712 -53.868988)
			(xy 330.016984 -53.914954) (xy 329.99934 -53.935884) (xy 329.999086 -53.936138) (xy 329.993518 -53.943237)
			(xy 329.98726 -53.960144) (xy 329.986894 -53.969158) (xy 329.986894 -54.036214) (xy 329.987246 -54.045231)
			(xy 329.993497 -54.062148) (xy 329.999086 -54.069234) (xy 329.99934 -54.069234) (xy 329.99934 -54.069488)
			(xy 330.016994 -54.090408) (xy 330.046702 -54.136385) (xy 330.069535 -54.186136) (xy 330.085022 -54.238639)
			(xy 330.092848 -54.292816) (xy 330.09332 -54.320186) (xy 330.092834 -54.347437) (xy 330.085078 -54.401385)
			(xy 330.069723 -54.45368) (xy 330.047081 -54.503257) (xy 330.017615 -54.549107) (xy 329.981924 -54.590298)
			(xy 329.940733 -54.625989) (xy 329.894883 -54.655455) (xy 329.845306 -54.678097) (xy 329.793011 -54.693452)
			(xy 329.739063 -54.701208) (xy 329.684561 -54.701208) (xy 329.630613 -54.693452) (xy 329.578318 -54.678097)
			(xy 329.528741 -54.655455) (xy 329.482891 -54.625989) (xy 329.4417 -54.590298) (xy 329.406009 -54.549107)
			(xy 329.376543 -54.503257) (xy 329.353901 -54.45368) (xy 329.338546 -54.401385) (xy 329.33079 -54.347437)
			(xy 329.330304 -54.320186) (xy 327.101731 -54.320186) (xy 327.09268 -54.339897) (xy 327.062959 -54.385866)
			(xy 327.04532 -54.4068) (xy 327.045066 -54.407054) (xy 327.039489 -54.414147) (xy 327.033238 -54.431059)
			(xy 327.032874 -54.440074) (xy 327.032874 -54.50713) (xy 327.033222 -54.516148) (xy 327.039476 -54.533064)
			(xy 327.045066 -54.54015) (xy 327.04532 -54.54015) (xy 327.04532 -54.540404) (xy 327.062978 -54.561321)
			(xy 327.092686 -54.607298) (xy 327.115518 -54.65705) (xy 327.131005 -54.709554) (xy 327.138828 -54.763732)
			(xy 327.138945 -54.770528) (xy 330.270866 -54.770528) (xy 330.271332 -54.743158) (xy 330.279148 -54.688978)
			(xy 330.294636 -54.636474) (xy 330.317478 -54.586727) (xy 330.347204 -54.540761) (xy 330.364846 -54.51983)
			(xy 330.3651 -54.519576) (xy 330.370703 -54.5125) (xy 330.37694 -54.495575) (xy 330.377292 -54.486556)
			(xy 330.377292 -54.4195) (xy 330.376937 -54.410483) (xy 330.370688 -54.393566) (xy 330.3651 -54.38648)
			(xy 330.364846 -54.38648) (xy 330.364846 -54.386226) (xy 330.347213 -54.365289) (xy 330.317498 -54.319318)
			(xy 330.294661 -54.269572) (xy 330.279168 -54.217072) (xy 330.27134 -54.162897) (xy 330.270866 -54.135528)
			(xy 330.271352 -54.108277) (xy 330.279108 -54.054329) (xy 330.294463 -54.002034) (xy 330.317105 -53.952457)
			(xy 330.346571 -53.906607) (xy 330.382262 -53.865416) (xy 330.423453 -53.829725) (xy 330.469303 -53.800259)
			(xy 330.51888 -53.777617) (xy 330.571175 -53.762262) (xy 330.625123 -53.754506) (xy 330.679625 -53.754506)
			(xy 330.733573 -53.762262) (xy 330.785868 -53.777617) (xy 330.835445 -53.800259) (xy 330.881295 -53.829725)
			(xy 330.922486 -53.865416) (xy 330.958177 -53.906607) (xy 330.987643 -53.952457) (xy 330.992718 -53.96357)
			(xy 334.971896 -53.96357) (xy 334.975967 -53.907948) (xy 334.988093 -53.853511) (xy 335.008016 -53.80142)
			(xy 335.035312 -53.752785) (xy 335.069398 -53.708642) (xy 335.109547 -53.669933) (xy 335.154905 -53.637482)
			(xy 335.204505 -53.611981) (xy 335.257289 -53.593974) (xy 335.312132 -53.583844) (xy 335.367866 -53.581807)
			(xy 335.423303 -53.587907) (xy 335.47726 -53.602013) (xy 335.528589 -53.623825) (xy 335.576195 -53.652879)
			(xy 335.619063 -53.688554) (xy 335.65628 -53.730091) (xy 335.687053 -53.776604) (xy 335.710725 -53.827101)
			(xy 335.726793 -53.880508) (xy 335.734913 -53.935684) (xy 335.735422 -53.96357) (xy 335.734913 -53.991456)
			(xy 335.726793 -54.046632) (xy 335.710725 -54.100039) (xy 335.687053 -54.150536) (xy 335.65628 -54.197049)
			(xy 335.619063 -54.238586) (xy 335.576195 -54.274261) (xy 335.528589 -54.303315) (xy 335.47726 -54.325127)
			(xy 335.423303 -54.339233) (xy 335.367866 -54.345333) (xy 335.312132 -54.343296) (xy 335.257289 -54.333166)
			(xy 335.204505 -54.315159) (xy 335.154905 -54.289658) (xy 335.109547 -54.257207) (xy 335.069398 -54.218498)
			(xy 335.035312 -54.174355) (xy 335.008016 -54.12572) (xy 334.988093 -54.073629) (xy 334.975967 -54.019192)
			(xy 334.971896 -53.96357) (xy 330.992718 -53.96357) (xy 331.010285 -54.002034) (xy 331.02564 -54.054329)
			(xy 331.033396 -54.108277) (xy 331.033882 -54.135528) (xy 331.033437 -54.162899) (xy 331.025615 -54.217079)
			(xy 331.010121 -54.269583) (xy 330.987274 -54.319329) (xy 330.957545 -54.365295) (xy 330.939902 -54.386226)
			(xy 330.939648 -54.38648) (xy 330.934057 -54.393564) (xy 330.927814 -54.410483) (xy 330.927456 -54.4195)
			(xy 330.927456 -54.486556) (xy 330.927822 -54.495572) (xy 330.934062 -54.51249) (xy 330.939648 -54.519576)
			(xy 330.939902 -54.519576) (xy 330.939902 -54.51983) (xy 330.957522 -54.540777) (xy 330.987237 -54.586746)
			(xy 331.010076 -54.63649) (xy 331.025572 -54.688987) (xy 331.033405 -54.74316) (xy 331.033882 -54.770528)
			(xy 331.033396 -54.797779) (xy 331.02564 -54.851727) (xy 331.010285 -54.904022) (xy 330.987643 -54.953599)
			(xy 330.958177 -54.999449) (xy 330.922486 -55.04064) (xy 330.881295 -55.076331) (xy 330.835445 -55.105797)
			(xy 330.785868 -55.128439) (xy 330.733573 -55.143794) (xy 330.679625 -55.15155) (xy 330.625123 -55.15155)
			(xy 330.571175 -55.143794) (xy 330.51888 -55.128439) (xy 330.469303 -55.105797) (xy 330.423453 -55.076331)
			(xy 330.382262 -55.04064) (xy 330.346571 -54.999449) (xy 330.317105 -54.953599) (xy 330.294463 -54.904022)
			(xy 330.279108 -54.851727) (xy 330.271352 -54.797779) (xy 330.270866 -54.770528) (xy 327.138945 -54.770528)
			(xy 327.1393 -54.791102) (xy 327.138814 -54.818353) (xy 327.131058 -54.872301) (xy 327.115703 -54.924596)
			(xy 327.093061 -54.974173) (xy 327.063595 -55.020023) (xy 327.027904 -55.061214) (xy 326.986713 -55.096905)
			(xy 326.940863 -55.126371) (xy 326.891286 -55.149013) (xy 326.838991 -55.164368) (xy 326.785043 -55.172124)
			(xy 326.730541 -55.172124) (xy 326.676593 -55.164368) (xy 326.624298 -55.149013) (xy 326.574721 -55.126371)
			(xy 326.528871 -55.096905) (xy 326.48768 -55.061214) (xy 326.451989 -55.020023) (xy 326.422523 -54.974173)
			(xy 326.399881 -54.924596) (xy 326.384526 -54.872301) (xy 326.37677 -54.818353) (xy 326.376284 -54.791102)
			(xy 324.478221 -54.791102) (xy 324.474054 -54.818167) (xy 324.456524 -54.873757) (xy 324.430741 -54.926034)
			(xy 324.397305 -54.97378) (xy 324.356994 -55.015883) (xy 324.310748 -55.051364) (xy 324.259642 -55.079396)
			(xy 324.204867 -55.099328) (xy 324.17639 -55.105554) (xy 324.174104 -55.106062) (xy 324.165336 -55.108631)
			(xy 324.150278 -55.118954) (xy 324.139779 -55.133891) (xy 324.135166 -55.151556) (xy 324.13575 -55.160672)
			(xy 324.194194 -55.722266) (xy 336.03387 -55.722266) (xy 336.037941 -55.666644) (xy 336.050067 -55.612207)
			(xy 336.06999 -55.560116) (xy 336.097286 -55.511481) (xy 336.131372 -55.467338) (xy 336.171521 -55.428629)
			(xy 336.216879 -55.396178) (xy 336.266479 -55.370677) (xy 336.319263 -55.35267) (xy 336.374106 -55.34254)
			(xy 336.42984 -55.340503) (xy 336.485277 -55.346603) (xy 336.539234 -55.360709) (xy 336.590563 -55.382521)
			(xy 336.638169 -55.411575) (xy 336.681037 -55.44725) (xy 336.718254 -55.488787) (xy 336.749027 -55.5353)
			(xy 336.772699 -55.585797) (xy 336.788767 -55.639204) (xy 336.796887 -55.69438) (xy 336.797396 -55.722266)
			(xy 336.796887 -55.750152) (xy 336.788767 -55.805328) (xy 336.772699 -55.858735) (xy 336.749027 -55.909232)
			(xy 336.718254 -55.955745) (xy 336.681037 -55.997282) (xy 336.638169 -56.032957) (xy 336.590563 -56.062011)
			(xy 336.539234 -56.083823) (xy 336.485277 -56.097929) (xy 336.42984 -56.104029) (xy 336.374106 -56.101992)
			(xy 336.319263 -56.091862) (xy 336.266479 -56.073855) (xy 336.216879 -56.048354) (xy 336.171521 -56.015903)
			(xy 336.131372 -55.977194) (xy 336.097286 -55.933051) (xy 336.06999 -55.884416) (xy 336.050067 -55.832325)
			(xy 336.037941 -55.777888) (xy 336.03387 -55.722266) (xy 324.194194 -55.722266) (xy 324.270878 -56.45912)
			(xy 324.27164 -56.464975) (xy 324.275494 -56.476134) (xy 324.278498 -56.481218) (xy 324.281546 -56.486044)
			(xy 324.290182 -56.494172) (xy 324.295516 -56.497474) (xy 324.319693 -56.512276) (xy 324.363784 -56.547905)
			(xy 324.402117 -56.589666) (xy 324.433849 -56.63664) (xy 324.458279 -56.687793) (xy 324.474871 -56.741997)
			(xy 324.483259 -56.79806) (xy 324.48373 -56.826404) (xy 324.48373 -56.83377) (xy 324.482968 -56.847232)
			(xy 324.481993 -56.861954) (xy 324.478053 -56.891197) (xy 324.475094 -56.905652) (xy 324.46847 -56.934324)
			(xy 324.447597 -56.989341) (xy 324.439874 -57.002934) (xy 331.76337 -57.002934) (xy 331.763897 -56.974844)
			(xy 331.772119 -56.919268) (xy 331.788405 -56.8655) (xy 331.812403 -56.814703) (xy 331.843592 -56.767976)
			(xy 331.881299 -56.72633) (xy 331.924708 -56.690666) (xy 331.948536 -56.675782) (xy 331.957426 -56.670448)
			(xy 331.969618 -56.65343) (xy 331.989938 -56.560212) (xy 331.98562 -56.539638) (xy 331.979778 -56.531002)
			(xy 331.963774 -56.506941) (xy 331.938433 -56.455008) (xy 331.921208 -56.399849) (xy 331.912494 -56.342725)
			(xy 331.91196 -56.313832) (xy 331.912508 -56.286583) (xy 331.920259 -56.232639) (xy 331.935609 -56.180348)
			(xy 331.958244 -56.130773) (xy 331.987704 -56.084924) (xy 332.023389 -56.043734) (xy 332.064572 -56.008042)
			(xy 332.110416 -55.978574) (xy 332.159988 -55.955931) (xy 332.212277 -55.940573) (xy 332.266219 -55.932812)
			(xy 332.293468 -55.932324) (xy 332.320838 -55.932803) (xy 332.375017 -55.940617) (xy 332.42752 -55.956103)
			(xy 332.477267 -55.978942) (xy 332.523234 -56.008664) (xy 332.544166 -56.026304) (xy 332.54442 -56.026558)
			(xy 332.551492 -56.032166) (xy 332.56842 -56.038398) (xy 332.57744 -56.03875) (xy 332.644496 -56.03875)
			(xy 332.653514 -56.038402) (xy 332.670431 -56.032149) (xy 332.677516 -56.026558) (xy 332.677516 -56.026304)
			(xy 332.67777 -56.026304) (xy 332.698703 -56.008663) (xy 332.744671 -55.978939) (xy 332.794417 -55.956093)
			(xy 332.846919 -55.940597) (xy 332.901097 -55.932768) (xy 332.955839 -55.932768) (xy 333.010017 -55.940597)
			(xy 333.062519 -55.956093) (xy 333.112265 -55.978939) (xy 333.158233 -56.008663) (xy 333.179166 -56.026304)
			(xy 333.17942 -56.026558) (xy 333.186492 -56.032166) (xy 333.20342 -56.038398) (xy 333.21244 -56.03875)
			(xy 333.279496 -56.03875) (xy 333.288514 -56.038402) (xy 333.305431 -56.032149) (xy 333.312516 -56.026558)
			(xy 333.312516 -56.026304) (xy 333.31277 -56.026304) (xy 333.333703 -56.008666) (xy 333.379676 -55.978954)
			(xy 333.429423 -55.956118) (xy 333.481923 -55.940626) (xy 333.536099 -55.932798) (xy 333.563468 -55.932324)
			(xy 333.590725 -55.932721) (xy 333.644684 -55.940475) (xy 333.69699 -55.955829) (xy 333.746578 -55.978472)
			(xy 333.792439 -56.007941) (xy 333.833639 -56.043638) (xy 333.869339 -56.084835) (xy 333.898813 -56.130694)
			(xy 333.92146 -56.18028) (xy 333.936819 -56.232585) (xy 333.944577 -56.286543) (xy 333.944577 -56.297068)
			(xy 334.28635 -56.297068) (xy 334.290421 -56.241446) (xy 334.302547 -56.187009) (xy 334.32247 -56.134918)
			(xy 334.349766 -56.086283) (xy 334.383852 -56.04214) (xy 334.424001 -56.003431) (xy 334.469359 -55.97098)
			(xy 334.518959 -55.945479) (xy 334.571743 -55.927472) (xy 334.626586 -55.917342) (xy 334.68232 -55.915305)
			(xy 334.737757 -55.921405) (xy 334.791714 -55.935511) (xy 334.843043 -55.957323) (xy 334.890649 -55.986377)
			(xy 334.933517 -56.022052) (xy 334.970734 -56.063589) (xy 335.001507 -56.110102) (xy 335.025179 -56.160599)
			(xy 335.041247 -56.214006) (xy 335.049367 -56.269182) (xy 335.049876 -56.297068) (xy 335.049367 -56.324954)
			(xy 335.041247 -56.38013) (xy 335.025179 -56.433537) (xy 335.001507 -56.484034) (xy 334.970734 -56.530547)
			(xy 334.933517 -56.572084) (xy 334.890649 -56.607759) (xy 334.843043 -56.636813) (xy 334.791714 -56.658625)
			(xy 334.737757 -56.672731) (xy 334.68232 -56.678831) (xy 334.626586 -56.676794) (xy 334.571743 -56.666664)
			(xy 334.518959 -56.648657) (xy 334.469359 -56.623156) (xy 334.424001 -56.590705) (xy 334.383852 -56.551996)
			(xy 334.349766 -56.507853) (xy 334.32247 -56.459218) (xy 334.302547 -56.407127) (xy 334.290421 -56.35269)
			(xy 334.28635 -56.297068) (xy 333.944577 -56.297068) (xy 333.944577 -56.341057) (xy 333.936819 -56.395015)
			(xy 333.92146 -56.44732) (xy 333.898813 -56.496906) (xy 333.869339 -56.542765) (xy 333.833639 -56.583962)
			(xy 333.792439 -56.619659) (xy 333.746578 -56.649128) (xy 333.69699 -56.671771) (xy 333.644684 -56.687125)
			(xy 333.590725 -56.694879) (xy 333.563468 -56.69534) (xy 333.536096 -56.694907) (xy 333.481915 -56.687084)
			(xy 333.429411 -56.671588) (xy 333.379665 -56.648738) (xy 333.3337 -56.619005) (xy 333.31277 -56.60136)
			(xy 333.312516 -56.601106) (xy 333.305429 -56.595521) (xy 333.288512 -56.589273) (xy 333.279496 -56.588914)
			(xy 333.21244 -56.588914) (xy 333.203425 -56.589287) (xy 333.186508 -56.595523) (xy 333.17942 -56.601106)
			(xy 333.17942 -56.60136) (xy 333.179166 -56.60136) (xy 333.158233 -56.619001) (xy 333.112265 -56.648725)
			(xy 333.062519 -56.671571) (xy 333.010017 -56.687067) (xy 332.955839 -56.694896) (xy 332.901097 -56.694896)
			(xy 332.846919 -56.687067) (xy 332.794417 -56.671571) (xy 332.744671 -56.648725) (xy 332.698703 -56.619001)
			(xy 332.67777 -56.60136) (xy 332.677516 -56.601106) (xy 332.670429 -56.595521) (xy 332.653512 -56.589273)
			(xy 332.644496 -56.588914) (xy 332.57744 -56.588914) (xy 332.568425 -56.589287) (xy 332.551508 -56.595523)
			(xy 332.54442 -56.601106) (xy 332.543912 -56.60136) (xy 332.531181 -56.612308) (xy 332.504087 -56.632147)
			(xy 332.48981 -56.640984) (xy 332.48092 -56.646318) (xy 332.468728 -56.663336) (xy 332.448408 -56.756554)
			(xy 332.452726 -56.777128) (xy 332.458568 -56.785764) (xy 332.474551 -56.809839) (xy 332.499899 -56.861766)
			(xy 332.517129 -56.916921) (xy 332.525849 -56.974042) (xy 332.526386 -57.002934) (xy 332.5259 -57.030185)
			(xy 332.518144 -57.084133) (xy 332.502789 -57.136428) (xy 332.480147 -57.186005) (xy 332.450681 -57.231855)
			(xy 332.41499 -57.273046) (xy 332.373799 -57.308737) (xy 332.327949 -57.338203) (xy 332.278372 -57.360845)
			(xy 332.226077 -57.3762) (xy 332.172129 -57.383956) (xy 332.117627 -57.383956) (xy 332.063679 -57.3762)
			(xy 332.011384 -57.360845) (xy 331.961807 -57.338203) (xy 331.915957 -57.308737) (xy 331.874766 -57.273046)
			(xy 331.839075 -57.231855) (xy 331.809609 -57.186005) (xy 331.786967 -57.136428) (xy 331.771612 -57.084133)
			(xy 331.763856 -57.030185) (xy 331.76337 -57.002934) (xy 324.439874 -57.002934) (xy 324.418528 -57.040504)
			(xy 324.400672 -57.063894) (xy 324.395338 -57.070498) (xy 324.392036 -57.079642) (xy 324.390512 -57.085484)
			(xy 324.389496 -57.09539) (xy 324.389496 -57.128156) (xy 324.37832 -57.128156) (xy 324.37832 -57.178956)
			(xy 324.378654 -57.18756) (xy 324.384365 -57.203791) (xy 324.389496 -57.210706) (xy 324.390766 -57.21223)
			(xy 324.408159 -57.233107) (xy 324.437476 -57.278857) (xy 324.460003 -57.328305) (xy 324.475284 -57.38045)
			(xy 324.483009 -57.434235) (xy 324.483476 -57.461404) (xy 324.4829 -57.491232) (xy 324.473618 -57.550161)
			(xy 324.455281 -57.606928) (xy 324.428335 -57.660151) (xy 324.41134 -57.68467) (xy 324.405752 -57.69229)
			(xy 324.403466 -57.70118) (xy 324.402316 -57.705721) (xy 324.40154 -57.715055) (xy 324.401942 -57.719722)
			(xy 324.418198 -57.87517) (xy 324.419122 -57.880002) (xy 324.422569 -57.889214) (xy 324.425056 -57.893458)
			(xy 324.42531 -57.893966) (xy 324.439101 -57.916819) (xy 324.460852 -57.965561) (xy 324.47559 -58.016861)
			(xy 324.483023 -58.069716) (xy 324.483476 -58.096404) (xy 324.482744 -58.129944) (xy 324.470984 -58.195986)
			(xy 324.460108 -58.227722) (xy 324.456044 -58.238898) (xy 324.46595 -58.33491) (xy 324.468451 -58.360554)
			(xy 324.47112 -58.412015) (xy 324.471284 -58.43778) (xy 324.471284 -58.636154) (xy 324.472808 -58.641996)
			(xy 324.477801 -58.66401) (xy 324.479628 -58.679334) (xy 332.19517 -58.679334) (xy 332.195603 -58.653019)
			(xy 332.202846 -58.600889) (xy 332.217173 -58.550246) (xy 332.238312 -58.502048) (xy 332.265863 -58.457205)
			(xy 332.299307 -58.416566) (xy 332.31836 -58.39841) (xy 332.325753 -58.390881) (xy 332.334284 -58.371607)
			(xy 332.33487 -58.361072) (xy 332.33487 -58.286396) (xy 332.334365 -58.275843) (xy 332.325814 -58.256548)
			(xy 332.31836 -58.249058) (xy 332.299283 -58.230924) (xy 332.26583 -58.190289) (xy 332.238274 -58.145444)
			(xy 332.21714 -58.097239) (xy 332.202827 -58.046588) (xy 332.195606 -57.994451) (xy 332.19517 -57.968134)
			(xy 332.195656 -57.940883) (xy 332.203412 -57.886935) (xy 332.218767 -57.83464) (xy 332.241409 -57.785063)
			(xy 332.270875 -57.739213) (xy 332.306566 -57.698022) (xy 332.347757 -57.662331) (xy 332.393607 -57.632865)
			(xy 332.443184 -57.610223) (xy 332.495479 -57.594868) (xy 332.549427 -57.587112) (xy 332.603929 -57.587112)
			(xy 332.657877 -57.594868) (xy 332.710172 -57.610223) (xy 332.759749 -57.632865) (xy 332.805599 -57.662331)
			(xy 332.84679 -57.698022) (xy 332.882481 -57.739213) (xy 332.911947 -57.785063) (xy 332.934589 -57.83464)
			(xy 332.949944 -57.886935) (xy 332.9577 -57.940883) (xy 332.958186 -57.968134) (xy 332.957746 -57.994449)
			(xy 332.950506 -58.046579) (xy 332.943238 -58.072274) (xy 336.193382 -58.072274) (xy 336.197453 -58.016652)
			(xy 336.209579 -57.962215) (xy 336.229502 -57.910124) (xy 336.256798 -57.861489) (xy 336.290884 -57.817346)
			(xy 336.331033 -57.778637) (xy 336.376391 -57.746186) (xy 336.425991 -57.720685) (xy 336.478775 -57.702678)
			(xy 336.533618 -57.692548) (xy 336.589352 -57.690511) (xy 336.644789 -57.696611) (xy 336.698746 -57.710717)
			(xy 336.750075 -57.732529) (xy 336.797681 -57.761583) (xy 336.840549 -57.797258) (xy 336.877766 -57.838795)
			(xy 336.908539 -57.885308) (xy 336.932211 -57.935805) (xy 336.948279 -57.989212) (xy 336.956399 -58.044388)
			(xy 336.956908 -58.072274) (xy 336.956399 -58.10016) (xy 336.948279 -58.155336) (xy 336.932211 -58.208743)
			(xy 336.908539 -58.25924) (xy 336.877766 -58.305753) (xy 336.840549 -58.34729) (xy 336.797681 -58.382965)
			(xy 336.750075 -58.412019) (xy 336.698746 -58.433831) (xy 336.644789 -58.447937) (xy 336.589352 -58.454037)
			(xy 336.533618 -58.452) (xy 336.478775 -58.44187) (xy 336.425991 -58.423863) (xy 336.376391 -58.398362)
			(xy 336.331033 -58.365911) (xy 336.290884 -58.327202) (xy 336.256798 -58.283059) (xy 336.229502 -58.234424)
			(xy 336.209579 -58.182333) (xy 336.197453 -58.127896) (xy 336.193382 -58.072274) (xy 332.943238 -58.072274)
			(xy 332.936182 -58.097222) (xy 332.915044 -58.145421) (xy 332.887493 -58.190264) (xy 332.85405 -58.230902)
			(xy 332.834996 -58.249058) (xy 332.82761 -58.256593) (xy 332.819077 -58.275863) (xy 332.818486 -58.286396)
			(xy 332.818486 -58.361072) (xy 332.819021 -58.371621) (xy 332.827553 -58.390916) (xy 332.834996 -58.39841)
			(xy 332.854049 -58.416569) (xy 332.887506 -58.457197) (xy 332.915066 -58.502037) (xy 332.936205 -58.550237)
			(xy 332.950522 -58.600884) (xy 332.957747 -58.653018) (xy 332.958186 -58.679334) (xy 332.9577 -58.706585)
			(xy 332.949944 -58.760533) (xy 332.934589 -58.812828) (xy 332.911947 -58.862405) (xy 332.882481 -58.908255)
			(xy 332.84679 -58.949446) (xy 332.805599 -58.985137) (xy 332.759749 -59.014603) (xy 332.710172 -59.037245)
			(xy 332.657877 -59.0526) (xy 332.603929 -59.060356) (xy 332.549427 -59.060356) (xy 332.495479 -59.0526)
			(xy 332.443184 -59.037245) (xy 332.393607 -59.014603) (xy 332.347757 -58.985137) (xy 332.306566 -58.949446)
			(xy 332.270875 -58.908255) (xy 332.241409 -58.862405) (xy 332.218767 -58.812828) (xy 332.203412 -58.760533)
			(xy 332.195656 -58.706585) (xy 332.19517 -58.679334) (xy 324.479628 -58.679334) (xy 324.483145 -58.708833)
			(xy 324.483476 -58.731404) (xy 324.483476 -58.741056) (xy 324.482682 -58.761328) (xy 324.477339 -58.801545)
			(xy 324.472808 -58.82132) (xy 324.471284 -58.827162) (xy 324.471284 -60.019254) (xy 332.335561 -60.019254)
			(xy 332.335561 -59.964746) (xy 332.343319 -59.910793) (xy 332.358677 -59.858494) (xy 332.381321 -59.808912)
			(xy 332.410791 -59.763058) (xy 332.446488 -59.721865) (xy 332.487684 -59.686172) (xy 332.53354 -59.656706)
			(xy 332.583124 -59.634065) (xy 332.635425 -59.618712) (xy 332.689378 -59.610959) (xy 332.716632 -59.610498)
			(xy 332.744003 -59.610946) (xy 332.798183 -59.618768) (xy 332.850686 -59.634261) (xy 332.900433 -59.657107)
			(xy 332.946399 -59.686835) (xy 332.96733 -59.704478) (xy 332.967584 -59.704732) (xy 332.974668 -59.710322)
			(xy 332.991587 -59.716565) (xy 333.000604 -59.716924) (xy 333.06766 -59.716924) (xy 333.076674 -59.716543)
			(xy 333.093591 -59.710311) (xy 333.10068 -59.704732) (xy 333.10068 -59.704478) (xy 333.100934 -59.704478)
			(xy 333.121867 -59.686837) (xy 333.167835 -59.657113) (xy 333.217581 -59.634267) (xy 333.270083 -59.618771)
			(xy 333.324261 -59.610942) (xy 333.379003 -59.610942) (xy 333.433181 -59.618771) (xy 333.485683 -59.634267)
			(xy 333.535429 -59.657113) (xy 333.581397 -59.686837) (xy 333.60233 -59.704478) (xy 333.602584 -59.704732)
			(xy 333.609668 -59.710322) (xy 333.626587 -59.716565) (xy 333.635604 -59.716924) (xy 333.70266 -59.716924)
			(xy 333.711674 -59.716543) (xy 333.728591 -59.710311) (xy 333.73568 -59.704732) (xy 333.73568 -59.704478)
			(xy 333.735934 -59.704478) (xy 333.756877 -59.686853) (xy 333.802847 -59.65714) (xy 333.852592 -59.634301)
			(xy 333.90509 -59.618807) (xy 333.959264 -59.610975) (xy 333.986632 -59.610498) (xy 334.013882 -59.610974)
			(xy 334.067827 -59.618734) (xy 334.120119 -59.634092) (xy 334.169693 -59.656736) (xy 334.21554 -59.686203)
			(xy 334.256727 -59.721895) (xy 334.292416 -59.763086) (xy 334.32188 -59.808935) (xy 334.344519 -59.858511)
			(xy 334.359872 -59.910804) (xy 334.367628 -59.96475) (xy 334.367628 -60.01925) (xy 334.359872 -60.073196)
			(xy 334.344519 -60.125489) (xy 334.32188 -60.175065) (xy 334.292416 -60.220914) (xy 334.256727 -60.262105)
			(xy 334.21554 -60.297797) (xy 334.169693 -60.327264) (xy 334.120119 -60.349908) (xy 334.067827 -60.365266)
			(xy 334.013882 -60.373026) (xy 333.986632 -60.373514) (xy 333.959263 -60.373026) (xy 333.905085 -60.365213)
			(xy 333.852582 -60.349729) (xy 333.802835 -60.326892) (xy 333.756867 -60.297173) (xy 333.735934 -60.279534)
			(xy 333.73568 -60.27928) (xy 333.728605 -60.273677) (xy 333.711679 -60.267441) (xy 333.70266 -60.267088)
			(xy 333.635604 -60.267088) (xy 333.626588 -60.26745) (xy 333.609671 -60.273694) (xy 333.602584 -60.27928)
			(xy 333.60233 -60.279534) (xy 333.581397 -60.297175) (xy 333.535429 -60.326899) (xy 333.485683 -60.349745)
			(xy 333.433181 -60.365241) (xy 333.379003 -60.37307) (xy 333.324261 -60.37307) (xy 333.270083 -60.365241)
			(xy 333.217581 -60.349745) (xy 333.167835 -60.326899) (xy 333.121867 -60.297175) (xy 333.100934 -60.279534)
			(xy 333.10068 -60.27928) (xy 333.093605 -60.273677) (xy 333.076679 -60.267441) (xy 333.06766 -60.267088)
			(xy 333.000604 -60.267088) (xy 332.991588 -60.26745) (xy 332.974671 -60.273694) (xy 332.967584 -60.27928)
			(xy 332.967584 -60.279534) (xy 332.96733 -60.279534) (xy 332.946402 -60.297178) (xy 332.900427 -60.326888)
			(xy 332.850679 -60.349722) (xy 332.798178 -60.365212) (xy 332.744001 -60.37304) (xy 332.716632 -60.373514)
			(xy 332.689378 -60.373041) (xy 332.635425 -60.365288) (xy 332.583124 -60.349935) (xy 332.53354 -60.327294)
			(xy 332.487684 -60.297828) (xy 332.446488 -60.262135) (xy 332.410791 -60.220942) (xy 332.381321 -60.175088)
			(xy 332.358677 -60.125506) (xy 332.343319 -60.073207) (xy 332.335561 -60.019254) (xy 324.471284 -60.019254)
			(xy 324.471284 -60.595256) (xy 324.470787 -60.638727) (xy 324.46317 -60.725336) (xy 324.448042 -60.810953)
			(xy 324.437248 -60.853066) (xy 323.802614 -63.213554) (xy 332.320565 -63.213554) (xy 332.320565 -63.159046)
			(xy 332.328323 -63.105092) (xy 332.343681 -63.052792) (xy 332.366327 -63.00321) (xy 332.395798 -62.957356)
			(xy 332.431496 -62.916163) (xy 332.472693 -62.880471) (xy 332.518551 -62.851005) (xy 332.568135 -62.828365)
			(xy 332.620437 -62.813014) (xy 332.674392 -62.805262) (xy 332.701646 -62.804802) (xy 332.729015 -62.805299)
			(xy 332.783193 -62.813109) (xy 332.835696 -62.828591) (xy 332.885443 -62.851426) (xy 332.931411 -62.881144)
			(xy 332.952344 -62.898782) (xy 332.952598 -62.899036) (xy 332.959678 -62.904632) (xy 332.9766 -62.910872)
			(xy 332.985618 -62.911228) (xy 333.052674 -62.911228) (xy 333.061689 -62.910852) (xy 333.078606 -62.904617)
			(xy 333.085694 -62.899036) (xy 333.085694 -62.898782) (xy 333.085948 -62.898782) (xy 333.106881 -62.881141)
			(xy 333.152849 -62.851417) (xy 333.202595 -62.828571) (xy 333.255097 -62.813075) (xy 333.309275 -62.805246)
			(xy 333.364017 -62.805246) (xy 333.418195 -62.813075) (xy 333.470697 -62.828571) (xy 333.520443 -62.851417)
			(xy 333.566411 -62.881141) (xy 333.587344 -62.898782) (xy 333.587598 -62.899036) (xy 333.594678 -62.904632)
			(xy 333.6116 -62.910872) (xy 333.620618 -62.911228) (xy 333.687674 -62.911228) (xy 333.696689 -62.910852)
			(xy 333.713606 -62.904617) (xy 333.720694 -62.899036) (xy 333.720694 -62.898782) (xy 333.720948 -62.898782)
			(xy 333.741887 -62.881151) (xy 333.787858 -62.851439) (xy 333.837604 -62.828601) (xy 333.890103 -62.813108)
			(xy 333.944277 -62.805278) (xy 333.971646 -62.804802) (xy 333.998896 -62.805271) (xy 334.05284 -62.813033)
			(xy 334.105131 -62.828392) (xy 334.154703 -62.851037) (xy 334.200549 -62.880505) (xy 334.241735 -62.916198)
			(xy 334.277422 -62.957388) (xy 334.306885 -63.003237) (xy 334.329524 -63.052813) (xy 334.344877 -63.105105)
			(xy 334.352632 -63.15905) (xy 334.352632 -63.21355) (xy 334.344877 -63.267495) (xy 334.329524 -63.319787)
			(xy 334.306885 -63.369363) (xy 334.277422 -63.415212) (xy 334.241735 -63.456402) (xy 334.200549 -63.492095)
			(xy 334.154703 -63.521563) (xy 334.105131 -63.544208) (xy 334.05284 -63.559567) (xy 333.998896 -63.567329)
			(xy 333.971646 -63.567818) (xy 333.944276 -63.567345) (xy 333.890096 -63.559532) (xy 333.837592 -63.544046)
			(xy 333.787845 -63.521205) (xy 333.741879 -63.49148) (xy 333.720948 -63.473838) (xy 333.720694 -63.473584)
			(xy 333.713615 -63.467987) (xy 333.696692 -63.461747) (xy 333.687674 -63.461392) (xy 333.620618 -63.461392)
			(xy 333.611602 -63.461759) (xy 333.594685 -63.468) (xy 333.587598 -63.473584) (xy 333.587344 -63.473838)
			(xy 333.566411 -63.491479) (xy 333.520443 -63.521203) (xy 333.470697 -63.544049) (xy 333.418195 -63.559545)
			(xy 333.364017 -63.567374) (xy 333.309275 -63.567374) (xy 333.255097 -63.559545) (xy 333.202595 -63.544049)
			(xy 333.152849 -63.521203) (xy 333.106881 -63.491479) (xy 333.085948 -63.473838) (xy 333.085694 -63.473584)
			(xy 333.078615 -63.467987) (xy 333.061692 -63.461747) (xy 333.052674 -63.461392) (xy 332.985618 -63.461392)
			(xy 332.976602 -63.461759) (xy 332.959685 -63.468) (xy 332.952598 -63.473584) (xy 332.952598 -63.473838)
			(xy 332.952344 -63.473838) (xy 332.931411 -63.491476) (xy 332.885438 -63.521187) (xy 332.835691 -63.544023)
			(xy 332.78319 -63.559514) (xy 332.729015 -63.567344) (xy 332.701646 -63.567818) (xy 332.674392 -63.567338)
			(xy 332.620437 -63.559586) (xy 332.568135 -63.544235) (xy 332.518551 -63.521595) (xy 332.472693 -63.492129)
			(xy 332.431496 -63.456437) (xy 332.395798 -63.415244) (xy 332.366327 -63.36939) (xy 332.343681 -63.319808)
			(xy 332.328323 -63.267508) (xy 332.320565 -63.213554) (xy 323.802614 -63.213554) (xy 323.790818 -63.25743)
			(xy 323.777446 -63.304892) (xy 323.742587 -63.397139) (xy 323.721222 -63.44158) (xy 322.898423 -65.100962)
			(xy 330.332332 -65.100962) (xy 330.336403 -65.04534) (xy 330.348529 -64.990903) (xy 330.368452 -64.938812)
			(xy 330.395748 -64.890177) (xy 330.429834 -64.846034) (xy 330.469983 -64.807325) (xy 330.515341 -64.774874)
			(xy 330.564941 -64.749373) (xy 330.617725 -64.731366) (xy 330.672568 -64.721236) (xy 330.728302 -64.719199)
			(xy 330.783739 -64.725299) (xy 330.837696 -64.739405) (xy 330.889025 -64.761217) (xy 330.936631 -64.790271)
			(xy 330.979499 -64.825946) (xy 331.016716 -64.867483) (xy 331.047489 -64.913996) (xy 331.071161 -64.964493)
			(xy 331.087229 -65.0179) (xy 331.095349 -65.073076) (xy 331.095858 -65.100962) (xy 331.095349 -65.128848)
			(xy 331.087229 -65.184024) (xy 331.071161 -65.237431) (xy 331.047489 -65.287928) (xy 331.016716 -65.334441)
			(xy 330.979499 -65.375978) (xy 330.936631 -65.411653) (xy 330.889025 -65.440707) (xy 330.837696 -65.462519)
			(xy 330.783739 -65.476625) (xy 330.728302 -65.482725) (xy 330.672568 -65.480688) (xy 330.617725 -65.470558)
			(xy 330.564941 -65.452551) (xy 330.515341 -65.42705) (xy 330.469983 -65.394599) (xy 330.429834 -65.35589)
			(xy 330.395748 -65.311747) (xy 330.368452 -65.263112) (xy 330.348529 -65.211021) (xy 330.336403 -65.156584)
			(xy 330.332332 -65.100962) (xy 322.898423 -65.100962) (xy 322.735702 -65.42913) (xy 322.735194 -65.430146)
			(xy 322.711898 -65.478106) (xy 322.656533 -65.569234) (xy 322.624704 -65.61201) (xy 322.514845 -65.75552)
			(xy 324.546466 -65.75552) (xy 324.550537 -65.699898) (xy 324.562663 -65.645461) (xy 324.582586 -65.59337)
			(xy 324.609882 -65.544735) (xy 324.643968 -65.500592) (xy 324.684117 -65.461883) (xy 324.729475 -65.429432)
			(xy 324.779075 -65.403931) (xy 324.831859 -65.385924) (xy 324.886702 -65.375794) (xy 324.942436 -65.373757)
			(xy 324.997873 -65.379857) (xy 325.05183 -65.393963) (xy 325.103159 -65.415775) (xy 325.150765 -65.444829)
			(xy 325.193633 -65.480504) (xy 325.23085 -65.522041) (xy 325.261623 -65.568554) (xy 325.285295 -65.619051)
			(xy 325.301363 -65.672458) (xy 325.309483 -65.727634) (xy 325.309992 -65.75552) (xy 325.309483 -65.783406)
			(xy 325.301363 -65.838582) (xy 325.285295 -65.891989) (xy 325.261623 -65.942486) (xy 325.23085 -65.988999)
			(xy 325.193633 -66.030536) (xy 325.150765 -66.066211) (xy 325.103159 -66.095265) (xy 325.05183 -66.117077)
			(xy 324.997873 -66.131183) (xy 324.942436 -66.137283) (xy 324.886702 -66.135246) (xy 324.831859 -66.125116)
			(xy 324.779075 -66.107109) (xy 324.729475 -66.081608) (xy 324.684117 -66.049157) (xy 324.643968 -66.010448)
			(xy 324.609882 -65.966305) (xy 324.582586 -65.91767) (xy 324.562663 -65.865579) (xy 324.550537 -65.811142)
			(xy 324.546466 -65.75552) (xy 322.514845 -65.75552) (xy 321.463459 -67.128953) (xy 324.566475 -67.128953)
			(xy 324.566475 -67.074447) (xy 324.574233 -67.020496) (xy 324.58959 -66.968198) (xy 324.612234 -66.918618)
			(xy 324.641703 -66.872766) (xy 324.677399 -66.831575) (xy 324.718593 -66.795883) (xy 324.764448 -66.766417)
			(xy 324.81403 -66.743778) (xy 324.866329 -66.728426) (xy 324.920281 -66.720673) (xy 324.947534 -66.720212)
			(xy 324.974905 -66.720655) (xy 325.029085 -66.728478) (xy 325.081589 -66.743972) (xy 325.131335 -66.766819)
			(xy 325.177301 -66.796549) (xy 325.198232 -66.814192) (xy 325.198486 -66.814446) (xy 325.205568 -66.820038)
			(xy 325.222489 -66.82628) (xy 325.231506 -66.826638) (xy 325.298562 -66.826638) (xy 325.307576 -66.826255)
			(xy 325.324493 -66.820024) (xy 325.331582 -66.814446) (xy 325.331582 -66.814192) (xy 325.331836 -66.814192)
			(xy 325.35278 -66.796568) (xy 325.39875 -66.766854) (xy 325.448494 -66.744016) (xy 325.500992 -66.728521)
			(xy 325.555166 -66.720688) (xy 325.582534 -66.720212) (xy 325.609785 -66.72066) (xy 325.663732 -66.728421)
			(xy 325.716025 -66.74378) (xy 325.765601 -66.766424) (xy 325.811449 -66.795893) (xy 325.852638 -66.831586)
			(xy 325.888328 -66.872778) (xy 325.917792 -66.918629) (xy 325.940432 -66.968207) (xy 325.955786 -67.020501)
			(xy 325.963542 -67.074449) (xy 325.963542 -67.128951) (xy 325.955786 -67.182899) (xy 325.940432 -67.235193)
			(xy 325.917792 -67.284771) (xy 325.888328 -67.330622) (xy 325.852638 -67.371814) (xy 325.811449 -67.407507)
			(xy 325.765601 -67.436976) (xy 325.716025 -67.45962) (xy 325.663732 -67.474979) (xy 325.609785 -67.48274)
			(xy 325.582534 -67.483228) (xy 325.555164 -67.48276) (xy 325.500984 -67.474945) (xy 325.44848 -67.459457)
			(xy 325.398733 -67.436616) (xy 325.352767 -67.40689) (xy 325.331836 -67.389248) (xy 325.331582 -67.388994)
			(xy 325.324505 -67.383393) (xy 325.307581 -67.377155) (xy 325.298562 -67.376802) (xy 325.231506 -67.376802)
			(xy 325.222489 -67.377161) (xy 325.205572 -67.383407) (xy 325.198486 -67.388994) (xy 325.198486 -67.389248)
			(xy 325.198232 -67.389248) (xy 325.177292 -67.406877) (xy 325.131322 -67.436593) (xy 325.081577 -67.459431)
			(xy 325.029078 -67.474924) (xy 324.974903 -67.482754) (xy 324.947534 -67.483228) (xy 324.920281 -67.482727)
			(xy 324.866329 -67.474974) (xy 324.81403 -67.459622) (xy 324.764448 -67.436983) (xy 324.718593 -67.407517)
			(xy 324.677399 -67.371825) (xy 324.641703 -67.330634) (xy 324.612234 -67.284782) (xy 324.58959 -67.235202)
			(xy 324.574233 -67.182904) (xy 324.566475 -67.128953) (xy 321.463459 -67.128953) (xy 321.188561 -67.488054)
			(xy 328.97902 -67.488054) (xy 328.983091 -67.432432) (xy 328.995217 -67.377995) (xy 329.01514 -67.325904)
			(xy 329.042436 -67.277269) (xy 329.076522 -67.233126) (xy 329.116671 -67.194417) (xy 329.162029 -67.161966)
			(xy 329.211629 -67.136465) (xy 329.264413 -67.118458) (xy 329.319256 -67.108328) (xy 329.37499 -67.106291)
			(xy 329.430427 -67.112391) (xy 329.484384 -67.126497) (xy 329.535713 -67.148309) (xy 329.583319 -67.177363)
			(xy 329.626187 -67.213038) (xy 329.663404 -67.254575) (xy 329.694177 -67.301088) (xy 329.717849 -67.351585)
			(xy 329.733917 -67.404992) (xy 329.742037 -67.460168) (xy 329.742546 -67.488054) (xy 329.742037 -67.51594)
			(xy 329.738852 -67.537584) (xy 330.271118 -67.537584) (xy 330.275189 -67.481962) (xy 330.287315 -67.427525)
			(xy 330.307238 -67.375434) (xy 330.334534 -67.326799) (xy 330.36862 -67.282656) (xy 330.408769 -67.243947)
			(xy 330.454127 -67.211496) (xy 330.503727 -67.185995) (xy 330.556511 -67.167988) (xy 330.611354 -67.157858)
			(xy 330.667088 -67.155821) (xy 330.722525 -67.161921) (xy 330.776482 -67.176027) (xy 330.827811 -67.197839)
			(xy 330.875417 -67.226893) (xy 330.918285 -67.262568) (xy 330.955502 -67.304105) (xy 330.986275 -67.350618)
			(xy 331.009947 -67.401115) (xy 331.026015 -67.454522) (xy 331.034135 -67.509698) (xy 331.034644 -67.537584)
			(xy 331.034135 -67.56547) (xy 331.03009 -67.592956) (xy 331.545182 -67.592956) (xy 331.549253 -67.537334)
			(xy 331.561379 -67.482897) (xy 331.581302 -67.430806) (xy 331.608598 -67.382171) (xy 331.642684 -67.338028)
			(xy 331.682833 -67.299319) (xy 331.728191 -67.266868) (xy 331.777791 -67.241367) (xy 331.830575 -67.22336)
			(xy 331.885418 -67.21323) (xy 331.941152 -67.211193) (xy 331.996589 -67.217293) (xy 332.050546 -67.231399)
			(xy 332.101875 -67.253211) (xy 332.149481 -67.282265) (xy 332.192349 -67.31794) (xy 332.229566 -67.359477)
			(xy 332.260339 -67.40599) (xy 332.284011 -67.456487) (xy 332.300079 -67.509894) (xy 332.308199 -67.56507)
			(xy 332.308708 -67.592956) (xy 332.308199 -67.620842) (xy 332.300079 -67.676018) (xy 332.284011 -67.729425)
			(xy 332.260339 -67.779922) (xy 332.229566 -67.826435) (xy 332.192349 -67.867972) (xy 332.149481 -67.903647)
			(xy 332.101875 -67.932701) (xy 332.050546 -67.954513) (xy 331.996589 -67.968619) (xy 331.941152 -67.974719)
			(xy 331.885418 -67.972682) (xy 331.830575 -67.962552) (xy 331.777791 -67.944545) (xy 331.728191 -67.919044)
			(xy 331.682833 -67.886593) (xy 331.642684 -67.847884) (xy 331.608598 -67.803741) (xy 331.581302 -67.755106)
			(xy 331.561379 -67.703015) (xy 331.549253 -67.648578) (xy 331.545182 -67.592956) (xy 331.03009 -67.592956)
			(xy 331.026015 -67.620646) (xy 331.009947 -67.674053) (xy 330.986275 -67.72455) (xy 330.955502 -67.771063)
			(xy 330.918285 -67.8126) (xy 330.875417 -67.848275) (xy 330.827811 -67.877329) (xy 330.776482 -67.899141)
			(xy 330.722525 -67.913247) (xy 330.667088 -67.919347) (xy 330.611354 -67.91731) (xy 330.556511 -67.90718)
			(xy 330.503727 -67.889173) (xy 330.454127 -67.863672) (xy 330.408769 -67.831221) (xy 330.36862 -67.792512)
			(xy 330.334534 -67.748369) (xy 330.307238 -67.699734) (xy 330.287315 -67.647643) (xy 330.275189 -67.593206)
			(xy 330.271118 -67.537584) (xy 329.738852 -67.537584) (xy 329.733917 -67.571116) (xy 329.717849 -67.624523)
			(xy 329.694177 -67.67502) (xy 329.663404 -67.721533) (xy 329.626187 -67.76307) (xy 329.583319 -67.798745)
			(xy 329.535713 -67.827799) (xy 329.484384 -67.849611) (xy 329.430427 -67.863717) (xy 329.37499 -67.869817)
			(xy 329.319256 -67.86778) (xy 329.264413 -67.85765) (xy 329.211629 -67.839643) (xy 329.162029 -67.814142)
			(xy 329.116671 -67.781691) (xy 329.076522 -67.742982) (xy 329.042436 -67.698839) (xy 329.01514 -67.650204)
			(xy 328.995217 -67.598113) (xy 328.983091 -67.543676) (xy 328.97902 -67.488054) (xy 321.188561 -67.488054)
			(xy 320.347603 -68.586604) (xy 326.825102 -68.586604) (xy 326.82557 -68.559234) (xy 326.833387 -68.505055)
			(xy 326.848876 -68.452552) (xy 326.871717 -68.402805) (xy 326.901441 -68.356838) (xy 326.919082 -68.335906)
			(xy 326.919336 -68.335652) (xy 326.924911 -68.328558) (xy 326.931164 -68.311647) (xy 326.931528 -68.302632)
			(xy 326.931528 -68.235576) (xy 326.931177 -68.226559) (xy 326.924925 -68.209642) (xy 326.919336 -68.202556)
			(xy 326.919082 -68.202556) (xy 326.919082 -68.202302) (xy 326.901428 -68.181382) (xy 326.871719 -68.135406)
			(xy 326.848886 -68.085655) (xy 326.833398 -68.033152) (xy 326.825574 -67.978974) (xy 326.825102 -67.951604)
			(xy 326.825559 -67.924351) (xy 326.833316 -67.870399) (xy 326.848672 -67.818101) (xy 326.871315 -67.76852)
			(xy 326.900783 -67.722666) (xy 326.936477 -67.681473) (xy 326.977671 -67.645779) (xy 327.023525 -67.616312)
			(xy 327.073106 -67.59367) (xy 327.125405 -67.578314) (xy 327.179357 -67.570559) (xy 327.20661 -67.570096)
			(xy 327.232924 -67.570558) (xy 327.285053 -67.577794) (xy 327.335696 -67.592114) (xy 327.383895 -67.613248)
			(xy 327.428738 -67.640795) (xy 327.469377 -67.674234) (xy 327.487534 -67.693286) (xy 327.495043 -67.700703)
			(xy 327.514333 -67.709219) (xy 327.524872 -67.709796) (xy 327.599548 -67.709796) (xy 327.610096 -67.709254)
			(xy 327.629392 -67.700728) (xy 327.636886 -67.693286) (xy 327.655053 -67.674242) (xy 327.69568 -67.640784)
			(xy 327.740518 -67.613224) (xy 327.788717 -67.592084) (xy 327.839362 -67.577764) (xy 327.891495 -67.570536)
			(xy 327.91781 -67.570096) (xy 327.94518 -67.570557) (xy 327.99936 -67.578376) (xy 328.051863 -67.593867)
			(xy 328.10161 -67.616709) (xy 328.147576 -67.646435) (xy 328.168508 -67.664076) (xy 328.168762 -67.66433)
			(xy 328.175853 -67.66991) (xy 328.192766 -67.67616) (xy 328.201782 -67.676522) (xy 328.268838 -67.676522)
			(xy 328.277856 -67.676179) (xy 328.294773 -67.669921) (xy 328.301858 -67.66433) (xy 328.301858 -67.664076)
			(xy 328.302112 -67.664076) (xy 328.323063 -67.646461) (xy 328.369031 -67.616746) (xy 328.418774 -67.593906)
			(xy 328.47127 -67.578409) (xy 328.525442 -67.570574) (xy 328.55281 -67.570096) (xy 328.580062 -67.570569)
			(xy 328.63401 -67.578326) (xy 328.686305 -67.593683) (xy 328.735883 -67.616326) (xy 328.781733 -67.645793)
			(xy 328.822924 -67.681486) (xy 328.858615 -67.722678) (xy 328.888081 -67.768529) (xy 328.910722 -67.818108)
			(xy 328.926077 -67.870404) (xy 328.933832 -67.924352) (xy 328.934318 -67.951604) (xy 328.933874 -67.978975)
			(xy 328.926054 -68.033156) (xy 328.910561 -68.08566) (xy 328.887714 -68.135407) (xy 328.857983 -68.181372)
			(xy 328.840338 -68.202302) (xy 328.840084 -68.202556) (xy 328.834508 -68.20965) (xy 328.828255 -68.226561)
			(xy 328.827892 -68.235576) (xy 328.827892 -68.302632) (xy 328.828236 -68.31165) (xy 328.834493 -68.328567)
			(xy 328.840084 -68.335652) (xy 328.840338 -68.335652) (xy 328.840338 -68.335906) (xy 328.858 -68.35682)
			(xy 328.887707 -68.402798) (xy 328.910538 -68.45255) (xy 328.926024 -68.505055) (xy 328.933847 -68.559234)
			(xy 328.934318 -68.586604) (xy 328.933826 -68.613855) (xy 328.926069 -68.667802) (xy 328.910714 -68.720096)
			(xy 328.888073 -68.769672) (xy 328.858607 -68.815522) (xy 328.822917 -68.856712) (xy 328.781727 -68.892404)
			(xy 328.735878 -68.92187) (xy 328.686302 -68.944512) (xy 328.634008 -68.959868) (xy 328.580061 -68.967626)
			(xy 328.55281 -68.968112) (xy 328.52544 -68.967637) (xy 328.471262 -68.959821) (xy 328.418759 -68.944334)
			(xy 328.369012 -68.921494) (xy 328.323044 -68.891772) (xy 328.302112 -68.874132) (xy 328.301858 -68.873878)
			(xy 328.294761 -68.868307) (xy 328.277852 -68.862052) (xy 328.268838 -68.861686) (xy 328.201782 -68.861686)
			(xy 328.192765 -68.862038) (xy 328.175848 -68.868289) (xy 328.168762 -68.873878) (xy 328.168762 -68.874132)
			(xy 328.168508 -68.874132) (xy 328.147588 -68.891786) (xy 328.101611 -68.921494) (xy 328.051861 -68.944327)
			(xy 327.999358 -68.959815) (xy 327.94518 -68.96764) (xy 327.91781 -68.968112) (xy 327.891496 -68.967634)
			(xy 327.839369 -68.960401) (xy 327.788726 -68.946084) (xy 327.740527 -68.924953) (xy 327.695683 -68.897409)
			(xy 327.655043 -68.863972) (xy 327.636886 -68.844922) (xy 327.629369 -68.837515) (xy 327.610086 -68.828993)
			(xy 327.599548 -68.828412) (xy 327.524872 -68.828412) (xy 327.514325 -68.828963) (xy 327.495029 -68.837483)
			(xy 327.487534 -68.844922) (xy 327.469408 -68.864007) (xy 327.428771 -68.89746) (xy 327.383925 -68.925015)
			(xy 327.335718 -68.946148) (xy 327.285066 -68.960459) (xy 327.232928 -68.967677) (xy 327.20661 -68.968112)
			(xy 327.179358 -68.967635) (xy 327.125407 -68.95988) (xy 327.07311 -68.944525) (xy 327.02353 -68.921884)
			(xy 326.977677 -68.892418) (xy 326.936485 -68.856725) (xy 326.900791 -68.815534) (xy 326.871322 -68.769682)
			(xy 326.84868 -68.720103) (xy 326.833323 -68.667806) (xy 326.825566 -68.613856) (xy 326.825102 -68.586604)
			(xy 320.347603 -68.586604) (xy 318.177834 -71.42099) (xy 322.597016 -71.42099) (xy 322.601087 -71.365368)
			(xy 322.613213 -71.310931) (xy 322.633136 -71.25884) (xy 322.660432 -71.210205) (xy 322.694518 -71.166062)
			(xy 322.734667 -71.127353) (xy 322.780025 -71.094902) (xy 322.829625 -71.069401) (xy 322.882409 -71.051394)
			(xy 322.937252 -71.041264) (xy 322.992986 -71.039227) (xy 323.048423 -71.045327) (xy 323.10238 -71.059433)
			(xy 323.153709 -71.081245) (xy 323.201315 -71.110299) (xy 323.244183 -71.145974) (xy 323.2814 -71.187511)
			(xy 323.312173 -71.234024) (xy 323.335845 -71.284521) (xy 323.351913 -71.337928) (xy 323.360033 -71.393104)
			(xy 323.360542 -71.42099) (xy 323.360033 -71.448876) (xy 323.351913 -71.504052) (xy 323.336325 -71.555864)
			(xy 329.39431 -71.555864) (xy 329.398381 -71.500242) (xy 329.410507 -71.445805) (xy 329.43043 -71.393714)
			(xy 329.457726 -71.345079) (xy 329.491812 -71.300936) (xy 329.531961 -71.262227) (xy 329.577319 -71.229776)
			(xy 329.626919 -71.204275) (xy 329.679703 -71.186268) (xy 329.734546 -71.176138) (xy 329.79028 -71.174101)
			(xy 329.845717 -71.180201) (xy 329.899674 -71.194307) (xy 329.951003 -71.216119) (xy 329.998609 -71.245173)
			(xy 330.041477 -71.280848) (xy 330.078694 -71.322385) (xy 330.109467 -71.368898) (xy 330.133139 -71.419395)
			(xy 330.149207 -71.472802) (xy 330.157327 -71.527978) (xy 330.157836 -71.555864) (xy 330.157327 -71.58375)
			(xy 330.151488 -71.623428) (xy 330.903324 -71.623428) (xy 330.907395 -71.567806) (xy 330.919521 -71.513369)
			(xy 330.939444 -71.461278) (xy 330.96674 -71.412643) (xy 331.000826 -71.3685) (xy 331.040975 -71.329791)
			(xy 331.086333 -71.29734) (xy 331.135933 -71.271839) (xy 331.188717 -71.253832) (xy 331.24356 -71.243702)
			(xy 331.299294 -71.241665) (xy 331.354731 -71.247765) (xy 331.408688 -71.261871) (xy 331.460017 -71.283683)
			(xy 331.507623 -71.312737) (xy 331.550491 -71.348412) (xy 331.587708 -71.389949) (xy 331.618481 -71.436462)
			(xy 331.642153 -71.486959) (xy 331.658221 -71.540366) (xy 331.666341 -71.595542) (xy 331.66685 -71.623428)
			(xy 331.666341 -71.651314) (xy 331.658221 -71.70649) (xy 331.642153 -71.759897) (xy 331.618481 -71.810394)
			(xy 331.587708 -71.856907) (xy 331.550491 -71.898444) (xy 331.507623 -71.934119) (xy 331.460017 -71.963173)
			(xy 331.408688 -71.984985) (xy 331.354731 -71.999091) (xy 331.299294 -72.005191) (xy 331.24356 -72.003154)
			(xy 331.188717 -71.993024) (xy 331.135933 -71.975017) (xy 331.086333 -71.949516) (xy 331.040975 -71.917065)
			(xy 331.000826 -71.878356) (xy 330.96674 -71.834213) (xy 330.939444 -71.785578) (xy 330.919521 -71.733487)
			(xy 330.907395 -71.67905) (xy 330.903324 -71.623428) (xy 330.151488 -71.623428) (xy 330.149207 -71.638926)
			(xy 330.133139 -71.692333) (xy 330.109467 -71.74283) (xy 330.078694 -71.789343) (xy 330.041477 -71.83088)
			(xy 329.998609 -71.866555) (xy 329.951003 -71.895609) (xy 329.899674 -71.917421) (xy 329.845717 -71.931527)
			(xy 329.79028 -71.937627) (xy 329.734546 -71.93559) (xy 329.679703 -71.92546) (xy 329.626919 -71.907453)
			(xy 329.577319 -71.881952) (xy 329.531961 -71.849501) (xy 329.491812 -71.810792) (xy 329.457726 -71.766649)
			(xy 329.43043 -71.718014) (xy 329.410507 -71.665923) (xy 329.398381 -71.611486) (xy 329.39431 -71.555864)
			(xy 323.336325 -71.555864) (xy 323.335845 -71.557459) (xy 323.312173 -71.607956) (xy 323.2814 -71.654469)
			(xy 323.244183 -71.696006) (xy 323.201315 -71.731681) (xy 323.153709 -71.760735) (xy 323.10238 -71.782547)
			(xy 323.048423 -71.796653) (xy 322.992986 -71.802753) (xy 322.937252 -71.800716) (xy 322.882409 -71.790586)
			(xy 322.829625 -71.772579) (xy 322.780025 -71.747078) (xy 322.734667 -71.714627) (xy 322.694518 -71.675918)
			(xy 322.660432 -71.631775) (xy 322.633136 -71.58314) (xy 322.613213 -71.531049) (xy 322.601087 -71.476612)
			(xy 322.597016 -71.42099) (xy 318.177834 -71.42099) (xy 313.749048 -77.206348) (xy 314.884052 -77.206348)
			(xy 314.888123 -77.150726) (xy 314.900249 -77.096289) (xy 314.920172 -77.044198) (xy 314.947468 -76.995563)
			(xy 314.981554 -76.95142) (xy 315.021703 -76.912711) (xy 315.067061 -76.88026) (xy 315.116661 -76.854759)
			(xy 315.169445 -76.836752) (xy 315.224288 -76.826622) (xy 315.280022 -76.824585) (xy 315.335459 -76.830685)
			(xy 315.389416 -76.844791) (xy 315.440745 -76.866603) (xy 315.484686 -76.89342) (xy 320.334892 -76.89342)
			(xy 320.338963 -76.837798) (xy 320.351089 -76.783361) (xy 320.371012 -76.73127) (xy 320.398308 -76.682635)
			(xy 320.432394 -76.638492) (xy 320.472543 -76.599783) (xy 320.517901 -76.567332) (xy 320.567501 -76.541831)
			(xy 320.620285 -76.523824) (xy 320.675128 -76.513694) (xy 320.730862 -76.511657) (xy 320.786299 -76.517757)
			(xy 320.840256 -76.531863) (xy 320.891585 -76.553675) (xy 320.939191 -76.582729) (xy 320.982059 -76.618404)
			(xy 321.019276 -76.659941) (xy 321.050049 -76.706454) (xy 321.070658 -76.750418) (xy 321.42633 -76.750418)
			(xy 321.430401 -76.694796) (xy 321.442527 -76.640359) (xy 321.46245 -76.588268) (xy 321.489746 -76.539633)
			(xy 321.523832 -76.49549) (xy 321.563981 -76.456781) (xy 321.609339 -76.42433) (xy 321.658939 -76.398829)
			(xy 321.711723 -76.380822) (xy 321.766566 -76.370692) (xy 321.8223 -76.368655) (xy 321.877737 -76.374755)
			(xy 321.931694 -76.388861) (xy 321.983023 -76.410673) (xy 322.030629 -76.439727) (xy 322.073497 -76.475402)
			(xy 322.110714 -76.516939) (xy 322.141487 -76.563452) (xy 322.165159 -76.613949) (xy 322.181227 -76.667356)
			(xy 322.189347 -76.722532) (xy 322.189856 -76.750418) (xy 322.189347 -76.778304) (xy 322.181227 -76.83348)
			(xy 322.165159 -76.886887) (xy 322.141487 -76.937384) (xy 322.110714 -76.983897) (xy 322.073497 -77.025434)
			(xy 322.030629 -77.061109) (xy 321.983023 -77.090163) (xy 321.931694 -77.111975) (xy 321.877737 -77.126081)
			(xy 321.8223 -77.132181) (xy 321.766566 -77.130144) (xy 321.711723 -77.120014) (xy 321.658939 -77.102007)
			(xy 321.609339 -77.076506) (xy 321.563981 -77.044055) (xy 321.523832 -77.005346) (xy 321.489746 -76.961203)
			(xy 321.46245 -76.912568) (xy 321.442527 -76.860477) (xy 321.430401 -76.80604) (xy 321.42633 -76.750418)
			(xy 321.070658 -76.750418) (xy 321.073721 -76.756951) (xy 321.089789 -76.810358) (xy 321.097909 -76.865534)
			(xy 321.098418 -76.89342) (xy 321.097909 -76.921306) (xy 321.089789 -76.976482) (xy 321.073721 -77.029889)
			(xy 321.050049 -77.080386) (xy 321.019276 -77.126899) (xy 320.982059 -77.168436) (xy 320.939191 -77.204111)
			(xy 320.891585 -77.233165) (xy 320.840256 -77.254977) (xy 320.786299 -77.269083) (xy 320.730862 -77.275183)
			(xy 320.675128 -77.273146) (xy 320.620285 -77.263016) (xy 320.567501 -77.245009) (xy 320.517901 -77.219508)
			(xy 320.472543 -77.187057) (xy 320.432394 -77.148348) (xy 320.398308 -77.104205) (xy 320.371012 -77.05557)
			(xy 320.351089 -77.003479) (xy 320.338963 -76.949042) (xy 320.334892 -76.89342) (xy 315.484686 -76.89342)
			(xy 315.488351 -76.895657) (xy 315.531219 -76.931332) (xy 315.568436 -76.972869) (xy 315.599209 -77.019382)
			(xy 315.622881 -77.069879) (xy 315.638949 -77.123286) (xy 315.647069 -77.178462) (xy 315.647578 -77.206348)
			(xy 315.647069 -77.234234) (xy 315.638949 -77.28941) (xy 315.622881 -77.342817) (xy 315.599209 -77.393314)
			(xy 315.568436 -77.439827) (xy 315.531219 -77.481364) (xy 315.488351 -77.517039) (xy 315.440745 -77.546093)
			(xy 315.389416 -77.567905) (xy 315.335459 -77.582011) (xy 315.280022 -77.588111) (xy 315.224288 -77.586074)
			(xy 315.169445 -77.575944) (xy 315.116661 -77.557937) (xy 315.067061 -77.532436) (xy 315.021703 -77.499985)
			(xy 314.981554 -77.461276) (xy 314.947468 -77.417133) (xy 314.920172 -77.368498) (xy 314.900249 -77.316407)
			(xy 314.888123 -77.26197) (xy 314.884052 -77.206348) (xy 313.749048 -77.206348) (xy 312.76887 -78.486762)
			(xy 320.503294 -78.486762) (xy 320.507365 -78.43114) (xy 320.519491 -78.376703) (xy 320.539414 -78.324612)
			(xy 320.56671 -78.275977) (xy 320.600796 -78.231834) (xy 320.640945 -78.193125) (xy 320.686303 -78.160674)
			(xy 320.735903 -78.135173) (xy 320.788687 -78.117166) (xy 320.84353 -78.107036) (xy 320.899264 -78.104999)
			(xy 320.954701 -78.111099) (xy 321.008658 -78.125205) (xy 321.059987 -78.147017) (xy 321.107593 -78.176071)
			(xy 321.150461 -78.211746) (xy 321.187678 -78.253283) (xy 321.218451 -78.299796) (xy 321.242123 -78.350293)
			(xy 321.258191 -78.4037) (xy 321.266311 -78.458876) (xy 321.26682 -78.486762) (xy 321.266311 -78.514648)
			(xy 321.258191 -78.569824) (xy 321.242123 -78.623231) (xy 321.218451 -78.673728) (xy 321.187678 -78.720241)
			(xy 321.150461 -78.761778) (xy 321.107593 -78.797453) (xy 321.059987 -78.826507) (xy 321.008658 -78.848319)
			(xy 320.954701 -78.862425) (xy 320.899264 -78.868525) (xy 320.84353 -78.866488) (xy 320.788687 -78.856358)
			(xy 320.735903 -78.838351) (xy 320.686303 -78.81285) (xy 320.640945 -78.780399) (xy 320.600796 -78.74169)
			(xy 320.56671 -78.697547) (xy 320.539414 -78.648912) (xy 320.519491 -78.596821) (xy 320.507365 -78.542384)
			(xy 320.503294 -78.486762) (xy 312.76887 -78.486762) (xy 312.464958 -78.883764) (xy 312.461582 -78.8899)
			(xy 312.457984 -78.903431) (xy 312.457846 -78.910434) (xy 312.457846 -78.918816) (xy 312.463688 -78.934564)
			(xy 312.469276 -78.941422) (xy 312.485339 -78.961916) (xy 312.512352 -79.006429) (xy 312.533069 -79.0542)
			(xy 312.547103 -79.104342) (xy 312.554196 -79.155926) (xy 312.55462 -79.18196) (xy 312.5541 -79.210634)
			(xy 312.54551 -79.267335) (xy 312.528532 -79.322112) (xy 312.50355 -79.373732) (xy 312.471124 -79.421033)
			(xy 312.431986 -79.46295) (xy 312.40984 -79.481172) (xy 312.4073 -79.483204) (xy 312.403236 -79.487268)
			(xy 312.396543 -79.494674) (xy 312.388944 -79.513111) (xy 312.388504 -79.523082) (xy 312.39079 -79.558896)
			(xy 312.39079 -79.559404) (xy 312.394346 -79.610458) (xy 312.39714 -79.623666) (xy 312.402728 -79.634842)
			(xy 312.402982 -79.635096) (xy 312.403236 -79.635604) (xy 312.40602 -79.639505) (xy 312.412797 -79.646282)
			(xy 312.416698 -79.649066) (xy 312.42254 -79.652622) (xy 312.423302 -79.65313) (xy 312.423556 -79.65313)
			(xy 312.447702 -79.667955) (xy 312.49173 -79.703615) (xy 312.530004 -79.745392) (xy 312.561681 -79.792367)
			(xy 312.586067 -79.843509) (xy 312.602624 -79.897694) (xy 312.610991 -79.953731) (xy 312.611516 -79.98206)
			(xy 312.611055 -80.009315) (xy 312.603303 -80.063271) (xy 312.587951 -80.115574) (xy 312.565311 -80.165159)
			(xy 312.535844 -80.211018) (xy 312.50015 -80.252216) (xy 312.458957 -80.287915) (xy 312.413102 -80.317387)
			(xy 312.363519 -80.340034) (xy 312.311218 -80.355393) (xy 312.257263 -80.363152) (xy 312.230008 -80.363568)
			(xy 312.202859 -80.36309) (xy 312.149108 -80.355394) (xy 312.096992 -80.340155) (xy 312.047562 -80.317682)
			(xy 312.001817 -80.288429) (xy 311.960681 -80.252986) (xy 311.924985 -80.21207) (xy 311.89545 -80.166506)
			(xy 311.872672 -80.117216) (xy 311.857112 -80.065194) (xy 311.849085 -80.011492) (xy 311.8485 -79.984346)
			(xy 311.8485 -79.981806) (xy 311.849041 -79.953228) (xy 311.85764 -79.896721) (xy 311.874585 -79.842133)
			(xy 311.8866 -79.816198) (xy 311.890202 -79.807939) (xy 311.891948 -79.790018) (xy 311.887371 -79.772603)
			(xy 311.877039 -79.757857) (xy 311.869836 -79.752444) (xy 311.864248 -79.74838) (xy 311.856014 -79.743193)
			(xy 311.837061 -79.738853) (xy 311.817855 -79.741882) (xy 311.801157 -79.751843) (xy 311.794906 -79.759302)
			(xy 311.327292 -80.369918) (xy 311.322466 -80.38211) (xy 311.320434 -80.389984) (xy 311.321704 -80.400906)
			(xy 311.323157 -80.413045) (xy 311.324683 -80.437448) (xy 311.324752 -80.449674) (xy 311.324281 -80.477052)
			(xy 311.316456 -80.531245) (xy 311.315007 -80.536158) (xy 312.596911 -80.536158) (xy 312.596911 -80.481642)
			(xy 312.60467 -80.427682) (xy 312.62003 -80.375375) (xy 312.642678 -80.325786) (xy 312.672153 -80.279926)
			(xy 312.707854 -80.238728) (xy 312.749056 -80.20303) (xy 312.79492 -80.173559) (xy 312.84451 -80.150916)
			(xy 312.896819 -80.135562) (xy 312.95078 -80.127808) (xy 312.978038 -80.127348) (xy 313.007945 -80.127911)
			(xy 313.067022 -80.137263) (xy 313.123918 -80.155715) (xy 313.177239 -80.182817) (xy 313.22568 -80.217905)
			(xy 313.247278 -80.2386) (xy 313.247532 -80.238854) (xy 313.255016 -80.24551) (xy 313.273591 -80.25295)
			(xy 313.2836 -80.253332) (xy 313.356244 -80.252824) (xy 313.366174 -80.252292) (xy 313.384476 -80.244562)
			(xy 313.391804 -80.237838) (xy 313.392312 -80.23733) (xy 313.410339 -80.219421) (xy 313.450281 -80.188011)
			(xy 313.494039 -80.16218) (xy 313.540838 -80.142387) (xy 313.589851 -80.12898) (xy 313.64021 -80.122198)
			(xy 313.665616 -80.12176) (xy 313.692864 -80.122311) (xy 313.746806 -80.130069) (xy 313.799094 -80.145424)
			(xy 313.848665 -80.168064) (xy 313.894509 -80.197529) (xy 313.935694 -80.233217) (xy 313.971381 -80.274403)
			(xy 314.000843 -80.320249) (xy 314.023481 -80.369821) (xy 314.038834 -80.42211) (xy 314.04659 -80.476052)
			(xy 314.04659 -80.530548) (xy 314.038834 -80.58449) (xy 314.036281 -80.593184) (xy 314.144404 -80.593184)
			(xy 314.148475 -80.537562) (xy 314.160601 -80.483125) (xy 314.180524 -80.431034) (xy 314.20782 -80.382399)
			(xy 314.241906 -80.338256) (xy 314.282055 -80.299547) (xy 314.327413 -80.267096) (xy 314.377013 -80.241595)
			(xy 314.429797 -80.223588) (xy 314.48464 -80.213458) (xy 314.540374 -80.211421) (xy 314.595811 -80.217521)
			(xy 314.649768 -80.231627) (xy 314.701097 -80.253439) (xy 314.748703 -80.282493) (xy 314.791571 -80.318168)
			(xy 314.828788 -80.359705) (xy 314.859561 -80.406218) (xy 314.883233 -80.456715) (xy 314.899301 -80.510122)
			(xy 314.907421 -80.565298) (xy 314.90793 -80.593184) (xy 314.907421 -80.62107) (xy 314.899301 -80.676246)
			(xy 314.883233 -80.729653) (xy 314.859561 -80.78015) (xy 314.828788 -80.826663) (xy 314.794678 -80.864732)
			(xy 320.080368 -80.864732) (xy 320.080371 -80.810228) (xy 320.08813 -80.756279) (xy 320.103489 -80.703983)
			(xy 320.126134 -80.654406) (xy 320.155604 -80.608556) (xy 320.191299 -80.567366) (xy 320.232492 -80.531676)
			(xy 320.278346 -80.502212) (xy 320.327926 -80.479573) (xy 320.380224 -80.464221) (xy 320.434174 -80.456467)
			(xy 320.488678 -80.456471) (xy 320.542627 -80.464232) (xy 320.594922 -80.479591) (xy 320.6445 -80.502237)
			(xy 320.690349 -80.531707) (xy 320.731538 -80.567403) (xy 320.767228 -80.608597) (xy 320.796691 -80.654451)
			(xy 320.819329 -80.704032) (xy 320.834681 -80.75633) (xy 320.842433 -80.81028) (xy 320.842894 -80.837532)
			(xy 320.842761 -80.852838) (xy 320.840343 -80.883355) (xy 320.838068 -80.898492) (xy 320.836036 -80.911446)
			(xy 320.844672 -80.936084) (xy 320.919602 -81.001616) (xy 320.926278 -81.006994) (xy 320.942186 -81.013357)
			(xy 320.959302 -81.014151) (xy 320.967608 -81.01203) (xy 320.967862 -81.01203) (xy 320.994834 -81.004332)
			(xy 321.050308 -80.99605) (xy 321.078352 -80.99552) (xy 321.105605 -80.996) (xy 321.159557 -81.003751)
			(xy 321.211856 -81.019103) (xy 321.261438 -81.041742) (xy 321.307293 -81.071207) (xy 321.348486 -81.106899)
			(xy 321.384181 -81.148091) (xy 321.413649 -81.193945) (xy 321.43629 -81.243525) (xy 321.451645 -81.295824)
			(xy 321.459399 -81.349775) (xy 321.45986 -81.377028) (xy 321.45986 -81.377282) (xy 321.459719 -81.391625)
			(xy 321.457556 -81.42023) (xy 321.455542 -81.434432) (xy 321.45351 -81.447894) (xy 321.462908 -81.472532)
			(xy 321.541394 -81.53654) (xy 321.54834 -81.541779) (xy 321.564707 -81.547649) (xy 321.582095 -81.547717)
			(xy 321.590416 -81.545176) (xy 321.590924 -81.545176) (xy 321.622251 -81.534548) (xy 321.687392 -81.523061)
			(xy 321.720464 -81.522316) (xy 321.74772 -81.522716) (xy 321.801677 -81.530469) (xy 321.853981 -81.545822)
			(xy 321.903569 -81.568462) (xy 321.949429 -81.597929) (xy 321.990629 -81.633623) (xy 322.02633 -81.674816)
			(xy 322.055805 -81.720672) (xy 322.078454 -81.770255) (xy 322.093816 -81.822557) (xy 322.101579 -81.876512)
			(xy 322.101583 -81.931024) (xy 322.09383 -81.984981) (xy 322.078477 -82.037285) (xy 322.055836 -82.086872)
			(xy 322.026369 -82.132732) (xy 321.990675 -82.173932) (xy 321.94948 -82.209633) (xy 321.903625 -82.239107)
			(xy 321.854041 -82.261756) (xy 321.801739 -82.277117) (xy 321.747784 -82.284879) (xy 321.693272 -82.284883)
			(xy 321.639315 -82.277129) (xy 321.587011 -82.261775) (xy 321.537424 -82.239134) (xy 321.491564 -82.209666)
			(xy 321.450365 -82.173972) (xy 321.414665 -82.132777) (xy 321.385191 -82.086921) (xy 321.362543 -82.037338)
			(xy 321.347182 -81.985036) (xy 321.339421 -81.93108) (xy 321.338956 -81.903824) (xy 321.338956 -81.90357)
			(xy 321.339103 -81.889227) (xy 321.341262 -81.860622) (xy 321.343274 -81.84642) (xy 321.345306 -81.832958)
			(xy 321.335908 -81.80832) (xy 321.257422 -81.744312) (xy 321.250471 -81.739081) (xy 321.234106 -81.733213)
			(xy 321.216721 -81.733139) (xy 321.2084 -81.735676) (xy 321.207892 -81.735676) (xy 321.176564 -81.746298)
			(xy 321.111424 -81.75779) (xy 321.078352 -81.758536) (xy 321.051101 -81.758067) (xy 320.997154 -81.750305)
			(xy 320.944861 -81.734945) (xy 320.895285 -81.7123) (xy 320.849436 -81.682831) (xy 320.808247 -81.647138)
			(xy 320.772557 -81.605948) (xy 320.74309 -81.560097) (xy 320.720448 -81.510521) (xy 320.705091 -81.458226)
			(xy 320.697332 -81.404279) (xy 320.696844 -81.377028) (xy 320.696985 -81.361722) (xy 320.699397 -81.331205)
			(xy 320.70167 -81.316068) (xy 320.703702 -81.303114) (xy 320.695066 -81.278476) (xy 320.620136 -81.212944)
			(xy 320.613445 -81.207588) (xy 320.597544 -81.201222) (xy 320.580435 -81.200416) (xy 320.57213 -81.20253)
			(xy 320.571876 -81.20253) (xy 320.544902 -81.210219) (xy 320.489429 -81.218507) (xy 320.461386 -81.21904)
			(xy 320.434134 -81.21853) (xy 320.380185 -81.210771) (xy 320.327889 -81.195413) (xy 320.278311 -81.172769)
			(xy 320.23246 -81.1433) (xy 320.19127 -81.107606) (xy 320.15558 -81.066412) (xy 320.126114 -81.020559)
			(xy 320.103475 -80.970979) (xy 320.088122 -80.918682) (xy 320.080368 -80.864732) (xy 314.794678 -80.864732)
			(xy 314.791571 -80.8682) (xy 314.748703 -80.903875) (xy 314.701097 -80.932929) (xy 314.649768 -80.954741)
			(xy 314.595811 -80.968847) (xy 314.540374 -80.974947) (xy 314.48464 -80.97291) (xy 314.429797 -80.96278)
			(xy 314.377013 -80.944773) (xy 314.327413 -80.919272) (xy 314.282055 -80.886821) (xy 314.241906 -80.848112)
			(xy 314.20782 -80.803969) (xy 314.180524 -80.755334) (xy 314.160601 -80.703243) (xy 314.148475 -80.648806)
			(xy 314.144404 -80.593184) (xy 314.036281 -80.593184) (xy 314.023481 -80.636779) (xy 314.000843 -80.686351)
			(xy 313.971381 -80.732197) (xy 313.935694 -80.773383) (xy 313.894509 -80.809071) (xy 313.848665 -80.838536)
			(xy 313.799094 -80.861176) (xy 313.746806 -80.876531) (xy 313.692864 -80.884289) (xy 313.665616 -80.884776)
			(xy 313.635711 -80.884172) (xy 313.576635 -80.874829) (xy 313.51974 -80.856386) (xy 313.466418 -80.829293)
			(xy 313.417975 -80.794215) (xy 313.396376 -80.773524) (xy 313.396122 -80.77327) (xy 313.388617 -80.766642)
			(xy 313.370058 -80.759185) (xy 313.360054 -80.758792) (xy 313.28741 -80.7593) (xy 313.277483 -80.759853)
			(xy 313.25918 -80.767568) (xy 313.25185 -80.774286) (xy 313.251342 -80.774794) (xy 313.233341 -80.79273)
			(xy 313.193393 -80.824136) (xy 313.149629 -80.849963) (xy 313.102825 -80.869752) (xy 313.053808 -80.883153)
			(xy 313.003446 -80.889929) (xy 312.978038 -80.890364) (xy 312.95078 -80.889992) (xy 312.896819 -80.882238)
			(xy 312.84451 -80.866884) (xy 312.79492 -80.844241) (xy 312.749056 -80.81477) (xy 312.707854 -80.779072)
			(xy 312.672153 -80.737874) (xy 312.642678 -80.692014) (xy 312.62003 -80.642425) (xy 312.60467 -80.590118)
			(xy 312.596911 -80.536158) (xy 311.315007 -80.536158) (xy 311.300962 -80.583762) (xy 311.278119 -80.633524)
			(xy 311.248395 -80.679509) (xy 311.212401 -80.720771) (xy 311.170877 -80.756463) (xy 311.124677 -80.785851)
			(xy 311.074749 -80.808331) (xy 311.02212 -80.823441) (xy 310.99506 -80.827626) (xy 310.988964 -80.828388)
			(xy 310.984646 -80.82915) (xy 310.976264 -80.833976) (xy 310.966866 -80.840834) (xy 310.113426 -81.955894)
			(xy 310.108722 -81.964923) (xy 310.106232 -81.985109) (xy 310.1086 -81.99501) (xy 310.113426 -82.008218)
			(xy 310.114188 -82.010504) (xy 310.116504 -82.016412) (xy 310.12357 -82.026948) (xy 310.128158 -82.031332)
			(xy 310.13273 -82.035396) (xy 310.143398 -82.040984) (xy 310.15051 -82.042762) (xy 310.178078 -82.049767)
			(xy 310.230912 -82.070829) (xy 310.280038 -82.099494) (xy 310.324368 -82.13513) (xy 310.362922 -82.176948)
			(xy 310.394845 -82.224022) (xy 310.419433 -82.275311) (xy 310.43614 -82.32968) (xy 310.444597 -82.385925)
			(xy 310.44515 -82.414364) (xy 310.444916 -82.427572) (xy 311.132726 -82.427572) (xy 311.136797 -82.37195)
			(xy 311.148923 -82.317513) (xy 311.168846 -82.265422) (xy 311.196142 -82.216787) (xy 311.230228 -82.172644)
			(xy 311.270377 -82.133935) (xy 311.315735 -82.101484) (xy 311.365335 -82.075983) (xy 311.418119 -82.057976)
			(xy 311.472962 -82.047846) (xy 311.528696 -82.045809) (xy 311.584133 -82.051909) (xy 311.63809 -82.066015)
			(xy 311.689419 -82.087827) (xy 311.737025 -82.116881) (xy 311.779893 -82.152556) (xy 311.81711 -82.194093)
			(xy 311.847883 -82.240606) (xy 311.871555 -82.291103) (xy 311.887623 -82.34451) (xy 311.895743 -82.399686)
			(xy 311.896252 -82.427572) (xy 311.896104 -82.4357) (xy 312.01817 -82.4357) (xy 312.022241 -82.380078)
			(xy 312.034367 -82.325641) (xy 312.05429 -82.27355) (xy 312.081586 -82.224915) (xy 312.115672 -82.180772)
			(xy 312.155821 -82.142063) (xy 312.201179 -82.109612) (xy 312.250779 -82.084111) (xy 312.303563 -82.066104)
			(xy 312.358406 -82.055974) (xy 312.41414 -82.053937) (xy 312.469577 -82.060037) (xy 312.523534 -82.074143)
			(xy 312.574863 -82.095955) (xy 312.622469 -82.125009) (xy 312.665337 -82.160684) (xy 312.702554 -82.202221)
			(xy 312.733327 -82.248734) (xy 312.756999 -82.299231) (xy 312.761758 -82.31505) (xy 320.185032 -82.31505)
			(xy 320.189103 -82.259428) (xy 320.201229 -82.204991) (xy 320.221152 -82.1529) (xy 320.248448 -82.104265)
			(xy 320.282534 -82.060122) (xy 320.322683 -82.021413) (xy 320.368041 -81.988962) (xy 320.417641 -81.963461)
			(xy 320.470425 -81.945454) (xy 320.525268 -81.935324) (xy 320.581002 -81.933287) (xy 320.636439 -81.939387)
			(xy 320.690396 -81.953493) (xy 320.741725 -81.975305) (xy 320.789331 -82.004359) (xy 320.832199 -82.040034)
			(xy 320.869416 -82.081571) (xy 320.900189 -82.128084) (xy 320.923861 -82.178581) (xy 320.939929 -82.231988)
			(xy 320.948049 -82.287164) (xy 320.948558 -82.31505) (xy 320.948049 -82.342936) (xy 320.939929 -82.398112)
			(xy 320.923861 -82.451519) (xy 320.900189 -82.502016) (xy 320.869416 -82.548529) (xy 320.832199 -82.590066)
			(xy 320.789331 -82.625741) (xy 320.741725 -82.654795) (xy 320.690396 -82.676607) (xy 320.636439 -82.690713)
			(xy 320.581002 -82.696813) (xy 320.525268 -82.694776) (xy 320.470425 -82.684646) (xy 320.417641 -82.666639)
			(xy 320.368041 -82.641138) (xy 320.322683 -82.608687) (xy 320.282534 -82.569978) (xy 320.248448 -82.525835)
			(xy 320.221152 -82.4772) (xy 320.201229 -82.425109) (xy 320.189103 -82.370672) (xy 320.185032 -82.31505)
			(xy 312.761758 -82.31505) (xy 312.773067 -82.352638) (xy 312.781187 -82.407814) (xy 312.781696 -82.4357)
			(xy 312.781187 -82.463586) (xy 312.773067 -82.518762) (xy 312.756999 -82.572169) (xy 312.733327 -82.622666)
			(xy 312.702554 -82.669179) (xy 312.665337 -82.710716) (xy 312.622469 -82.746391) (xy 312.574863 -82.775445)
			(xy 312.523534 -82.797257) (xy 312.469577 -82.811363) (xy 312.41414 -82.817463) (xy 312.358406 -82.815426)
			(xy 312.303563 -82.805296) (xy 312.250779 -82.787289) (xy 312.201179 -82.761788) (xy 312.155821 -82.729337)
			(xy 312.115672 -82.690628) (xy 312.081586 -82.646485) (xy 312.05429 -82.59785) (xy 312.034367 -82.545759)
			(xy 312.022241 -82.491322) (xy 312.01817 -82.4357) (xy 311.896104 -82.4357) (xy 311.895743 -82.455458)
			(xy 311.887623 -82.510634) (xy 311.871555 -82.564041) (xy 311.847883 -82.614538) (xy 311.81711 -82.661051)
			(xy 311.779893 -82.702588) (xy 311.737025 -82.738263) (xy 311.689419 -82.767317) (xy 311.63809 -82.789129)
			(xy 311.584133 -82.803235) (xy 311.528696 -82.809335) (xy 311.472962 -82.807298) (xy 311.418119 -82.797168)
			(xy 311.365335 -82.779161) (xy 311.315735 -82.75366) (xy 311.270377 -82.721209) (xy 311.230228 -82.6825)
			(xy 311.196142 -82.638357) (xy 311.168846 -82.589722) (xy 311.148923 -82.537631) (xy 311.136797 -82.483194)
			(xy 311.132726 -82.427572) (xy 310.444916 -82.427572) (xy 310.444667 -82.441618) (xy 310.436915 -82.495572)
			(xy 310.421563 -82.547873) (xy 310.398924 -82.597458) (xy 310.36946 -82.643316) (xy 310.333769 -82.684514)
			(xy 310.292578 -82.720213) (xy 310.246726 -82.749687) (xy 310.197147 -82.772336) (xy 310.144848 -82.787698)
			(xy 310.090896 -82.795461) (xy 310.063642 -82.795872) (xy 310.063642 -82.796126) (xy 310.034726 -82.795596)
			(xy 309.977555 -82.786878) (xy 309.922353 -82.769637) (xy 309.870384 -82.744266) (xy 309.822836 -82.711345)
			(xy 309.780799 -82.67163) (xy 309.745233 -82.626027) (xy 309.730648 -82.601054) (xy 309.727092 -82.594704)
			(xy 309.70601 -82.573622) (xy 309.705248 -82.573114) (xy 309.693056 -82.56905) (xy 309.68315 -82.568288)
			(xy 309.67172 -82.567526) (xy 309.660942 -82.567599) (xy 309.640961 -82.575632) (xy 309.633112 -82.58302)
			(xy 308.834536 -83.626198) (xy 308.831488 -83.632802) (xy 308.831488 -83.669378) (xy 308.832504 -83.67268)
			(xy 308.837584 -83.682586) (xy 308.839712 -83.685614) (xy 308.844682 -83.691098) (xy 308.84749 -83.693508)
			(xy 308.87543 -83.716622) (xy 308.887368 -83.719162) (xy 308.915429 -83.725757) (xy 308.969303 -83.74625)
			(xy 309.019486 -83.774607) (xy 309.064836 -83.810186) (xy 309.104323 -83.852176) (xy 309.13705 -83.899625)
			(xy 309.162273 -83.951454) (xy 309.17942 -84.006485) (xy 309.188101 -84.063468) (xy 309.188612 -84.092288)
			(xy 309.188149 -84.119542) (xy 309.180394 -84.173494) (xy 309.165039 -84.225793) (xy 309.142397 -84.275375)
			(xy 309.11293 -84.32123) (xy 309.077236 -84.362425) (xy 309.036043 -84.39812) (xy 308.990189 -84.42759)
			(xy 308.940608 -84.450233) (xy 308.88831 -84.465591) (xy 308.834357 -84.473348) (xy 308.807104 -84.473796)
			(xy 308.780491 -84.473333) (xy 308.727782 -84.465931) (xy 308.676614 -84.451269) (xy 308.627984 -84.429634)
			(xy 308.582835 -84.401445) (xy 308.542045 -84.36725) (xy 308.506408 -84.327715) (xy 308.476616 -84.283608)
			(xy 308.464458 -84.259928) (xy 308.46268 -84.256372) (xy 308.457854 -84.249514) (xy 308.451685 -84.241433)
			(xy 308.434521 -84.230568) (xy 308.42458 -84.228432) (xy 308.402228 -84.226146) (xy 308.391839 -84.226162)
			(xy 308.372421 -84.233492) (xy 308.364636 -84.24037) (xy 308.184002 -84.476336) (xy 311.895234 -84.476336)
			(xy 311.899305 -84.420714) (xy 311.911431 -84.366277) (xy 311.931354 -84.314186) (xy 311.95865 -84.265551)
			(xy 311.992736 -84.221408) (xy 312.032885 -84.182699) (xy 312.078243 -84.150248) (xy 312.127843 -84.124747)
			(xy 312.180627 -84.10674) (xy 312.23547 -84.09661) (xy 312.291204 -84.094573) (xy 312.346641 -84.100673)
			(xy 312.400598 -84.114779) (xy 312.451927 -84.136591) (xy 312.499533 -84.165645) (xy 312.542401 -84.20132)
			(xy 312.579618 -84.242857) (xy 312.610391 -84.28937) (xy 312.634063 -84.339867) (xy 312.650131 -84.393274)
			(xy 312.658251 -84.44845) (xy 312.65876 -84.476336) (xy 312.658251 -84.504222) (xy 312.650131 -84.559398)
			(xy 312.634063 -84.612805) (xy 312.610391 -84.663302) (xy 312.580157 -84.709) (xy 318.895982 -84.709)
			(xy 318.900053 -84.653378) (xy 318.912179 -84.598941) (xy 318.932102 -84.54685) (xy 318.959398 -84.498215)
			(xy 318.993484 -84.454072) (xy 319.033633 -84.415363) (xy 319.078991 -84.382912) (xy 319.128591 -84.357411)
			(xy 319.181375 -84.339404) (xy 319.236218 -84.329274) (xy 319.291952 -84.327237) (xy 319.347389 -84.333337)
			(xy 319.401346 -84.347443) (xy 319.452675 -84.369255) (xy 319.500281 -84.398309) (xy 319.543149 -84.433984)
			(xy 319.580366 -84.475521) (xy 319.611139 -84.522034) (xy 319.634811 -84.572531) (xy 319.650879 -84.625938)
			(xy 319.658999 -84.681114) (xy 319.659508 -84.709) (xy 319.658999 -84.736886) (xy 319.650879 -84.792062)
			(xy 319.634811 -84.845469) (xy 319.611139 -84.895966) (xy 319.580366 -84.942479) (xy 319.543149 -84.984016)
			(xy 319.500281 -85.019691) (xy 319.452675 -85.048745) (xy 319.401346 -85.070557) (xy 319.347389 -85.084663)
			(xy 319.291952 -85.090763) (xy 319.236218 -85.088726) (xy 319.181375 -85.078596) (xy 319.128591 -85.060589)
			(xy 319.078991 -85.035088) (xy 319.033633 -85.002637) (xy 318.993484 -84.963928) (xy 318.959398 -84.919785)
			(xy 318.932102 -84.87115) (xy 318.912179 -84.819059) (xy 318.900053 -84.764622) (xy 318.895982 -84.709)
			(xy 312.580157 -84.709) (xy 312.579618 -84.709815) (xy 312.542401 -84.751352) (xy 312.499533 -84.787027)
			(xy 312.451927 -84.816081) (xy 312.400598 -84.837893) (xy 312.346641 -84.851999) (xy 312.291204 -84.858099)
			(xy 312.23547 -84.856062) (xy 312.180627 -84.845932) (xy 312.127843 -84.827925) (xy 312.078243 -84.802424)
			(xy 312.032885 -84.769973) (xy 311.992736 -84.731264) (xy 311.95865 -84.687121) (xy 311.931354 -84.638486)
			(xy 311.911431 -84.586395) (xy 311.899305 -84.531958) (xy 311.895234 -84.476336) (xy 308.184002 -84.476336)
			(xy 306.827788 -86.247986) (xy 307.43855 -86.247986) (xy 307.442621 -86.192364) (xy 307.454747 -86.137927)
			(xy 307.47467 -86.085836) (xy 307.501966 -86.037201) (xy 307.536052 -85.993058) (xy 307.576201 -85.954349)
			(xy 307.621559 -85.921898) (xy 307.671159 -85.896397) (xy 307.723943 -85.87839) (xy 307.778786 -85.86826)
			(xy 307.83452 -85.866223) (xy 307.889957 -85.872323) (xy 307.943914 -85.886429) (xy 307.995243 -85.908241)
			(xy 308.042849 -85.937295) (xy 308.085717 -85.97297) (xy 308.122934 -86.014507) (xy 308.153707 -86.06102)
			(xy 308.177379 -86.111517) (xy 308.193447 -86.164924) (xy 308.201567 -86.2201) (xy 308.202076 -86.247986)
			(xy 308.201567 -86.275872) (xy 308.193447 -86.331048) (xy 308.177379 -86.384455) (xy 308.153707 -86.434952)
			(xy 308.122934 -86.481465) (xy 308.117975 -86.487) (xy 318.642492 -86.487) (xy 318.64296 -86.45963)
			(xy 318.650778 -86.405451) (xy 318.666266 -86.352948) (xy 318.689108 -86.303201) (xy 318.718831 -86.257234)
			(xy 318.736472 -86.236302) (xy 318.736726 -86.236048) (xy 318.742302 -86.228954) (xy 318.748554 -86.212043)
			(xy 318.748918 -86.203028) (xy 318.748918 -86.135972) (xy 318.748571 -86.126954) (xy 318.742316 -86.110037)
			(xy 318.736726 -86.102952) (xy 318.736472 -86.102952) (xy 318.736472 -86.102698) (xy 318.718814 -86.081781)
			(xy 318.689106 -86.035804) (xy 318.666274 -85.986052) (xy 318.650787 -85.933548) (xy 318.642964 -85.87937)
			(xy 318.642492 -85.852) (xy 318.642978 -85.824749) (xy 318.650734 -85.770801) (xy 318.666089 -85.718506)
			(xy 318.688731 -85.668929) (xy 318.718197 -85.623079) (xy 318.753888 -85.581888) (xy 318.795079 -85.546197)
			(xy 318.840929 -85.516731) (xy 318.890506 -85.494089) (xy 318.942801 -85.478734) (xy 318.996749 -85.470978)
			(xy 319.051251 -85.470978) (xy 319.105199 -85.478734) (xy 319.157494 -85.494089) (xy 319.207071 -85.516731)
			(xy 319.252921 -85.546197) (xy 319.294112 -85.581888) (xy 319.329803 -85.623079) (xy 319.359269 -85.668929)
			(xy 319.381911 -85.718506) (xy 319.397266 -85.770801) (xy 319.405022 -85.824749) (xy 319.405508 -85.852)
			(xy 319.40504 -85.87937) (xy 319.397222 -85.933549) (xy 319.381734 -85.986052) (xy 319.358892 -86.035799)
			(xy 319.329169 -86.081766) (xy 319.311528 -86.102698) (xy 319.311274 -86.102952) (xy 319.305698 -86.110046)
			(xy 319.299446 -86.126957) (xy 319.299082 -86.135972) (xy 319.299082 -86.203028) (xy 319.299429 -86.212046)
			(xy 319.305684 -86.228963) (xy 319.311274 -86.236048) (xy 319.311528 -86.236048) (xy 319.311528 -86.236302)
			(xy 319.329186 -86.257219) (xy 319.358894 -86.303196) (xy 319.381726 -86.352948) (xy 319.397213 -86.405452)
			(xy 319.405036 -86.45963) (xy 319.405508 -86.487) (xy 319.405022 -86.514251) (xy 319.397266 -86.568199)
			(xy 319.381911 -86.620494) (xy 319.359269 -86.670071) (xy 319.329803 -86.715921) (xy 319.294112 -86.757112)
			(xy 319.252921 -86.792803) (xy 319.207071 -86.822269) (xy 319.157494 -86.844911) (xy 319.105199 -86.860266)
			(xy 319.051251 -86.868022) (xy 318.996749 -86.868022) (xy 318.942801 -86.860266) (xy 318.890506 -86.844911)
			(xy 318.840929 -86.822269) (xy 318.795079 -86.792803) (xy 318.753888 -86.757112) (xy 318.718197 -86.715921)
			(xy 318.688731 -86.670071) (xy 318.666089 -86.620494) (xy 318.650734 -86.568199) (xy 318.642978 -86.514251)
			(xy 318.642492 -86.487) (xy 308.117975 -86.487) (xy 308.085717 -86.523002) (xy 308.042849 -86.558677)
			(xy 307.995243 -86.587731) (xy 307.943914 -86.609543) (xy 307.889957 -86.623649) (xy 307.83452 -86.629749)
			(xy 307.778786 -86.627712) (xy 307.723943 -86.617582) (xy 307.671159 -86.599575) (xy 307.621559 -86.574074)
			(xy 307.576201 -86.541623) (xy 307.536052 -86.502914) (xy 307.501966 -86.458771) (xy 307.47467 -86.410136)
			(xy 307.454747 -86.358045) (xy 307.442621 -86.303608) (xy 307.43855 -86.247986) (xy 306.827788 -86.247986)
			(xy 300.572678 -94.419166) (xy 300.570392 -94.424754) (xy 300.336458 -95.405956) (xy 300.210728 -95.933768)
			(xy 300.210728 -95.934276) (xy 299.993347 -96.901) (xy 301.521874 -96.901) (xy 301.525945 -96.845378)
			(xy 301.538071 -96.790941) (xy 301.557994 -96.73885) (xy 301.58529 -96.690215) (xy 301.619376 -96.646072)
			(xy 301.659525 -96.607363) (xy 301.704883 -96.574912) (xy 301.754483 -96.549411) (xy 301.807267 -96.531404)
			(xy 301.86211 -96.521274) (xy 301.917844 -96.519237) (xy 301.973281 -96.525337) (xy 302.027238 -96.539443)
			(xy 302.078567 -96.561255) (xy 302.126173 -96.590309) (xy 302.169041 -96.625984) (xy 302.206258 -96.667521)
			(xy 302.237031 -96.714034) (xy 302.260703 -96.764531) (xy 302.276771 -96.817938) (xy 302.284891 -96.873114)
			(xy 302.2854 -96.901) (xy 302.284891 -96.928886) (xy 302.276771 -96.984062) (xy 302.260703 -97.037469)
			(xy 302.237031 -97.087966) (xy 302.206258 -97.134479) (xy 302.169041 -97.176016) (xy 302.126173 -97.211691)
			(xy 302.078567 -97.240745) (xy 302.027238 -97.262557) (xy 301.973281 -97.276663) (xy 301.917844 -97.282763)
			(xy 301.86211 -97.280726) (xy 301.807267 -97.270596) (xy 301.754483 -97.252589) (xy 301.704883 -97.227088)
			(xy 301.659525 -97.194637) (xy 301.619376 -97.155928) (xy 301.58529 -97.111785) (xy 301.557994 -97.06315)
			(xy 301.538071 -97.011059) (xy 301.525945 -96.956622) (xy 301.521874 -96.901) (xy 299.993347 -96.901)
			(xy 299.499528 -99.097084) (xy 299.355052 -99.739704) (xy 302.321974 -99.739704) (xy 302.326045 -99.684082)
			(xy 302.338171 -99.629645) (xy 302.358094 -99.577554) (xy 302.38539 -99.528919) (xy 302.419476 -99.484776)
			(xy 302.459625 -99.446067) (xy 302.504983 -99.413616) (xy 302.554583 -99.388115) (xy 302.607367 -99.370108)
			(xy 302.66221 -99.359978) (xy 302.717944 -99.357941) (xy 302.773381 -99.364041) (xy 302.827338 -99.378147)
			(xy 302.878667 -99.399959) (xy 302.926273 -99.429013) (xy 302.969141 -99.464688) (xy 303.006358 -99.506225)
			(xy 303.037131 -99.552738) (xy 303.060803 -99.603235) (xy 303.076871 -99.656642) (xy 303.084991 -99.711818)
			(xy 303.0855 -99.739704) (xy 303.084991 -99.76759) (xy 303.076871 -99.822766) (xy 303.060803 -99.876173)
			(xy 303.037131 -99.92667) (xy 303.006358 -99.973183) (xy 302.969141 -100.01472) (xy 302.926273 -100.050395)
			(xy 302.878667 -100.079449) (xy 302.827338 -100.101261) (xy 302.773381 -100.115367) (xy 302.717944 -100.121467)
			(xy 302.66221 -100.11943) (xy 302.607367 -100.1093) (xy 302.554583 -100.091293) (xy 302.504983 -100.065792)
			(xy 302.459625 -100.033341) (xy 302.419476 -99.994632) (xy 302.38539 -99.950489) (xy 302.358094 -99.901854)
			(xy 302.338171 -99.849763) (xy 302.326045 -99.795326) (xy 302.321974 -99.739704) (xy 299.355052 -99.739704)
			(xy 297.755818 -106.852974) (xy 297.754467 -106.860089) (xy 297.755358 -106.874536) (xy 297.757596 -106.881422)
			(xy 297.760136 -106.888026) (xy 297.768772 -106.89971) (xy 297.775122 -106.904536) (xy 297.775376 -106.904536)
			(xy 297.798728 -106.922686) (xy 297.840068 -106.964977) (xy 297.874392 -107.013139) (xy 297.900879 -107.066017)
			(xy 297.918894 -107.122347) (xy 297.928006 -107.180782) (xy 297.928538 -107.210352) (xy 297.928461 -107.22309)
			(xy 297.926811 -107.248512) (xy 297.925236 -107.261152) (xy 297.92107 -107.288442) (xy 297.905903 -107.34152)
			(xy 297.883251 -107.391862) (xy 297.853585 -107.438417) (xy 297.817525 -107.480215) (xy 297.775822 -107.516384)
			(xy 297.729346 -107.546172) (xy 297.679064 -107.568957) (xy 297.652694 -107.577128) (xy 297.646344 -107.578906)
			(xy 297.64101 -107.582208) (xy 297.630088 -107.590844) (xy 297.614594 -107.607354) (xy 297.6118 -107.610402)
			(xy 297.607673 -107.615345) (xy 297.601767 -107.626783) (xy 297.600116 -107.633008) (xy 297.514772 -108.081064)
			(xy 297.269916 -109.367828) (xy 297.269662 -109.376464) (xy 297.270678 -109.38637) (xy 297.27144 -109.389418)
			(xy 297.276489 -109.411109) (xy 297.282096 -109.455292) (xy 297.282616 -109.477556) (xy 297.282616 -109.480604)
			(xy 297.282616 -109.481874) (xy 297.282616 -109.484668) (xy 297.281791 -109.514162) (xy 297.272172 -109.572372)
			(xy 297.253712 -109.62841) (xy 297.226853 -109.680942) (xy 297.209972 -109.70514) (xy 297.20667 -109.709966)
			(xy 297.202352 -109.719872) (xy 297.117262 -110.165896) (xy 296.971466 -110.93323) (xy 296.970813 -110.940965)
			(xy 296.973666 -110.956217) (xy 296.977054 -110.963202) (xy 296.980864 -110.970314) (xy 296.993056 -110.981744)
			(xy 297.001184 -110.985554) (xy 297.026086 -110.997172) (xy 297.072553 -111.026503) (xy 297.114332 -111.062196)
			(xy 297.150559 -111.103513) (xy 297.180484 -111.149599) (xy 297.20349 -111.199501) (xy 297.219099 -111.252187)
			(xy 297.22699 -111.306567) (xy 297.227498 -111.334042) (xy 297.227422 -111.34678) (xy 297.225772 -111.372202)
			(xy 297.224196 -111.384842) (xy 297.219861 -111.413207) (xy 297.203788 -111.468289) (xy 297.17965 -111.520343)
			(xy 297.14799 -111.568197) (xy 297.109522 -111.610771) (xy 297.065114 -111.647106) (xy 297.015766 -111.676382)
			(xy 296.962591 -111.69794) (xy 296.906787 -111.711294) (xy 296.878248 -111.71428) (xy 296.87012 -111.715042)
			(xy 296.862754 -111.71809) (xy 296.862246 -111.718344) (xy 296.858774 -111.719821) (xy 296.852274 -111.723652)
			(xy 296.849292 -111.725964) (xy 296.836338 -111.737394) (xy 296.826178 -111.746284) (xy 296.820895 -111.751563)
			(xy 296.813407 -111.764477) (xy 296.811446 -111.771684) (xy 296.745914 -112.114584) (xy 296.713148 -112.287558)
			(xy 296.710862 -112.299242) (xy 296.715688 -112.317022) (xy 296.717466 -112.322102) (xy 296.720768 -112.330484)
			(xy 296.722038 -112.333024) (xy 296.735873 -112.360552) (xy 296.75545 -112.418965) (xy 296.765378 -112.479767)
			(xy 296.765489 -112.485424) (xy 298.851064 -112.485424) (xy 298.855135 -112.429802) (xy 298.867261 -112.375365)
			(xy 298.887184 -112.323274) (xy 298.91448 -112.274639) (xy 298.948566 -112.230496) (xy 298.988715 -112.191787)
			(xy 299.034073 -112.159336) (xy 299.083673 -112.133835) (xy 299.136457 -112.115828) (xy 299.1913 -112.105698)
			(xy 299.247034 -112.103661) (xy 299.302471 -112.109761) (xy 299.356428 -112.123867) (xy 299.407757 -112.145679)
			(xy 299.455363 -112.174733) (xy 299.498231 -112.210408) (xy 299.535448 -112.251945) (xy 299.566221 -112.298458)
			(xy 299.589893 -112.348955) (xy 299.605961 -112.402362) (xy 299.614081 -112.457538) (xy 299.61459 -112.485424)
			(xy 299.614081 -112.51331) (xy 299.605961 -112.568486) (xy 299.589893 -112.621893) (xy 299.566221 -112.67239)
			(xy 299.535448 -112.718903) (xy 299.498231 -112.76044) (xy 299.455363 -112.796115) (xy 299.407757 -112.825169)
			(xy 299.356428 -112.846981) (xy 299.302471 -112.861087) (xy 299.247034 -112.867187) (xy 299.1913 -112.86515)
			(xy 299.136457 -112.85502) (xy 299.083673 -112.837013) (xy 299.034073 -112.811512) (xy 298.988715 -112.779061)
			(xy 298.948566 -112.740352) (xy 298.91448 -112.696209) (xy 298.887184 -112.647574) (xy 298.867261 -112.595483)
			(xy 298.855135 -112.541046) (xy 298.851064 -112.485424) (xy 296.765489 -112.485424) (xy 296.76598 -112.51057)
			(xy 296.76598 -112.519206) (xy 296.7649 -112.546386) (xy 296.755996 -112.600046) (xy 296.739566 -112.6519)
			(xy 296.715942 -112.700896) (xy 296.685603 -112.746043) (xy 296.649163 -112.786427) (xy 296.628566 -112.804194)
			(xy 296.625518 -112.806734) (xy 296.622216 -112.810036) (xy 296.617574 -112.815015) (xy 296.610878 -112.826859)
			(xy 296.609008 -112.833404) (xy 296.600118 -112.880902) (xy 296.599046 -112.89112) (xy 296.604162 -112.910998)
			(xy 296.616647 -112.927292) (xy 296.634509 -112.937404) (xy 296.654904 -112.939723) (xy 296.664888 -112.93729)
			(xy 296.677334 -112.93348) (xy 296.683176 -112.92967) (xy 296.70621 -112.915602) (xy 296.755399 -112.893388)
			(xy 296.807227 -112.878324) (xy 296.86066 -112.870713) (xy 296.887646 -112.870234) (xy 296.888154 -112.870234)
			(xy 296.915406 -112.870694) (xy 296.969356 -112.878445) (xy 297.021654 -112.893795) (xy 297.071234 -112.916433)
			(xy 297.117088 -112.945896) (xy 297.158282 -112.981586) (xy 297.193976 -113.022775) (xy 297.223445 -113.068626)
			(xy 297.246089 -113.118203) (xy 297.261445 -113.170499) (xy 297.269203 -113.224448) (xy 297.269203 -113.278952)
			(xy 297.261445 -113.332901) (xy 297.246089 -113.385197) (xy 297.223445 -113.434774) (xy 297.223216 -113.43513)
			(xy 299.130718 -113.43513) (xy 299.134789 -113.379508) (xy 299.146915 -113.325071) (xy 299.166838 -113.27298)
			(xy 299.194134 -113.224345) (xy 299.22822 -113.180202) (xy 299.268369 -113.141493) (xy 299.313727 -113.109042)
			(xy 299.363327 -113.083541) (xy 299.416111 -113.065534) (xy 299.470954 -113.055404) (xy 299.526688 -113.053367)
			(xy 299.582125 -113.059467) (xy 299.636082 -113.073573) (xy 299.687411 -113.095385) (xy 299.735017 -113.124439)
			(xy 299.777885 -113.160114) (xy 299.815102 -113.201651) (xy 299.845875 -113.248164) (xy 299.869547 -113.298661)
			(xy 299.885615 -113.352068) (xy 299.893735 -113.407244) (xy 299.894244 -113.43513) (xy 299.893735 -113.463016)
			(xy 299.885615 -113.518192) (xy 299.869547 -113.571599) (xy 299.845875 -113.622096) (xy 299.815102 -113.668609)
			(xy 299.777885 -113.710146) (xy 299.735017 -113.745821) (xy 299.687411 -113.774875) (xy 299.636082 -113.796687)
			(xy 299.582125 -113.810793) (xy 299.526688 -113.816893) (xy 299.470954 -113.814856) (xy 299.416111 -113.804726)
			(xy 299.363327 -113.786719) (xy 299.313727 -113.761218) (xy 299.268369 -113.728767) (xy 299.22822 -113.690058)
			(xy 299.194134 -113.645915) (xy 299.166838 -113.59728) (xy 299.146915 -113.545189) (xy 299.134789 -113.490752)
			(xy 299.130718 -113.43513) (xy 297.223216 -113.43513) (xy 297.193976 -113.480625) (xy 297.158282 -113.521814)
			(xy 297.117088 -113.557504) (xy 297.071234 -113.586967) (xy 297.021654 -113.609605) (xy 296.969356 -113.624955)
			(xy 296.915406 -113.632706) (xy 296.888154 -113.63325) (xy 296.8879 -113.63325) (xy 296.860765 -113.632778)
			(xy 296.807042 -113.625095) (xy 296.754952 -113.609868) (xy 296.705548 -113.587407) (xy 296.65983 -113.558166)
			(xy 296.63898 -113.540794) (xy 296.638218 -113.540286) (xy 296.636948 -113.539016) (xy 296.632122 -113.534952)
			(xy 296.611802 -113.527078) (xy 296.603457 -113.524102) (xy 296.585758 -113.523567) (xy 296.577258 -113.526062)
			(xy 296.49801 -113.552732) (xy 296.492422 -113.555018) (xy 296.482509 -113.560366) (xy 296.468255 -113.577768)
			(xy 296.46499 -113.588546) (xy 296.275742 -114.581432) (xy 298.500038 -114.581432) (xy 298.500524 -114.554181)
			(xy 298.50828 -114.500233) (xy 298.523635 -114.447938) (xy 298.546277 -114.398361) (xy 298.575743 -114.352511)
			(xy 298.611434 -114.31132) (xy 298.652625 -114.275629) (xy 298.698475 -114.246163) (xy 298.748052 -114.223521)
			(xy 298.800347 -114.208166) (xy 298.854295 -114.20041) (xy 298.908797 -114.20041) (xy 298.962745 -114.208166)
			(xy 299.01504 -114.223521) (xy 299.064617 -114.246163) (xy 299.110467 -114.275629) (xy 299.151658 -114.31132)
			(xy 299.187349 -114.352511) (xy 299.216815 -114.398361) (xy 299.239457 -114.447938) (xy 299.254812 -114.500233)
			(xy 299.262568 -114.554181) (xy 299.263054 -114.581432) (xy 299.262038 -114.607848) (xy 299.262038 -114.608102)
			(xy 299.261894 -114.619898) (xy 299.271026 -114.641618) (xy 299.279564 -114.649758) (xy 299.350684 -114.710718)
			(xy 299.373544 -114.71656) (xy 299.385228 -114.71402) (xy 299.385736 -114.71402) (xy 299.417074 -114.707429)
			(xy 299.480716 -114.700297) (xy 299.512736 -114.699796) (xy 299.817536 -114.699796) (xy 299.827611 -114.699417)
			(xy 299.84621 -114.691667) (xy 299.853604 -114.68481) (xy 300.495462 -114.042952) (xy 300.502266 -114.035524)
			(xy 300.510008 -114.016946) (xy 300.510448 -114.006884) (xy 300.510448 -111.065564) (xy 300.510916 -111.032684)
			(xy 300.518277 -110.967336) (xy 300.532913 -110.903225) (xy 300.55464 -110.841157) (xy 300.583185 -110.781915)
			(xy 300.618187 -110.726244) (xy 300.659207 -110.674845) (xy 300.682152 -110.65129) (xy 303.419002 -107.91444)
			(xy 303.442566 -107.891508) (xy 303.49398 -107.850514) (xy 303.549656 -107.815529) (xy 303.608896 -107.786991)
			(xy 303.670957 -107.765259) (xy 303.735059 -107.750605) (xy 303.800398 -107.743214) (xy 303.833276 -107.742736)
			(xy 304.691288 -107.742736) (xy 304.70129 -107.742203) (xy 304.719775 -107.734554) (xy 304.733927 -107.720415)
			(xy 304.741594 -107.701938) (xy 304.742088 -107.691936) (xy 304.742088 -106.413808) (xy 304.741661 -106.403739)
			(xy 304.733942 -106.385141) (xy 304.727102 -106.37774) (xy 303.99228 -105.643172) (xy 303.969391 -105.619567)
			(xy 303.928393 -105.568162) (xy 303.893402 -105.512493) (xy 303.864858 -105.45326) (xy 303.843119 -105.391205)
			(xy 303.828457 -105.327108) (xy 303.821058 -105.261774) (xy 303.820576 -105.228898) (xy 303.820576 -97.780856)
			(xy 303.821031 -97.747975) (xy 303.828393 -97.682627) (xy 303.843031 -97.618515) (xy 303.86476 -97.556447)
			(xy 303.893306 -97.497205) (xy 303.928311 -97.441534) (xy 303.969333 -97.390136) (xy 303.99228 -97.366582)
			(xy 304.90541 -96.453452) (xy 304.911918 -96.446209) (xy 304.919503 -96.428299) (xy 304.919879 -96.408852)
			(xy 304.91684 -96.399604) (xy 304.878994 -96.298766) (xy 304.854864 -96.28124) (xy 304.839878 -96.280224)
			(xy 304.793875 -96.276767) (xy 304.702647 -96.263006) (xy 304.612948 -96.241422) (xy 304.525447 -96.212177)
			(xy 304.440796 -96.175489) (xy 304.359628 -96.131631) (xy 304.282548 -96.080931) (xy 304.210131 -96.023767)
			(xy 304.142919 -95.960567) (xy 304.081413 -95.891801) (xy 304.026071 -95.817983) (xy 303.977307 -95.739663)
			(xy 303.935485 -95.657428) (xy 303.900917 -95.571889) (xy 303.873861 -95.483686) (xy 303.854518 -95.393477)
			(xy 303.843034 -95.301935) (xy 303.839494 -95.209744) (xy 303.843924 -95.117591) (xy 303.856292 -95.026164)
			(xy 303.876504 -94.936146) (xy 303.904411 -94.848208) (xy 303.939804 -94.763007) (xy 303.982418 -94.681179)
			(xy 304.031936 -94.603335) (xy 304.087988 -94.530055) (xy 304.150155 -94.461886) (xy 304.217975 -94.399337)
			(xy 304.29094 -94.342876) (xy 304.368506 -94.292922) (xy 304.450094 -94.24985) (xy 304.535095 -94.213981)
			(xy 304.622875 -94.185582) (xy 304.712778 -94.164866) (xy 304.804134 -94.151986) (xy 304.896261 -94.14704)
			(xy 304.988471 -94.150063) (xy 305.080076 -94.161034) (xy 305.170392 -94.179871) (xy 305.258745 -94.206433)
			(xy 305.344476 -94.240521) (xy 305.426945 -94.281882) (xy 305.466496 -94.305628) (xy 305.47818 -94.312994)
			(xy 305.505866 -94.313502) (xy 305.595528 -94.263464) (xy 305.603182 -94.258748) (xy 305.614861 -94.245101)
			(xy 305.621082 -94.22825) (xy 305.621436 -94.219268) (xy 305.621436 -93.711014) (xy 305.621912 -93.678161)
			(xy 305.629274 -93.612868) (xy 305.643895 -93.548809) (xy 305.665592 -93.486788) (xy 305.694092 -93.427585)
			(xy 305.729037 -93.371942) (xy 305.769989 -93.320558) (xy 305.792886 -93.296994) (xy 311.128156 -87.961724)
			(xy 311.151738 -87.938811) (xy 311.203149 -87.897816) (xy 311.258822 -87.862829) (xy 311.318059 -87.834289)
			(xy 311.380117 -87.812554) (xy 311.444216 -87.797896) (xy 311.509553 -87.7905) (xy 311.54243 -87.79002)
			(xy 312.405268 -87.79002) (xy 312.438616 -87.790529) (xy 312.504882 -87.798091) (xy 312.569859 -87.813133)
			(xy 312.632707 -87.835459) (xy 312.692611 -87.864781) (xy 312.748797 -87.900718) (xy 312.800535 -87.942806)
			(xy 312.847158 -87.9905) (xy 312.88806 -88.043182) (xy 312.922712 -88.100169) (xy 312.950665 -88.160724)
			(xy 312.971558 -88.224063) (xy 312.9788 -88.256618) (xy 312.98261 -88.274398) (xy 313.010296 -88.297004)
			(xy 313.088782 -88.297004) (xy 313.098854 -88.296595) (xy 313.117453 -88.288866) (xy 313.12485 -88.282018)
			(xy 313.425332 -87.981536) (xy 313.448927 -87.958637) (xy 313.500335 -87.917641) (xy 313.556006 -87.882652)
			(xy 313.615241 -87.85411) (xy 313.677297 -87.832372) (xy 313.741394 -87.817712) (xy 313.80673 -87.810314)
			(xy 313.839606 -87.809832) (xy 313.875021 -87.810329) (xy 313.945333 -87.818868) (xy 314.014104 -87.835819)
			(xy 314.08033 -87.860936) (xy 314.143046 -87.893853) (xy 314.201337 -87.934089) (xy 314.254353 -87.981059)
			(xy 314.301321 -88.034076) (xy 314.341555 -88.092368) (xy 314.37447 -88.155084) (xy 314.399586 -88.221311)
			(xy 314.416535 -88.290082) (xy 314.425071 -88.360395) (xy 314.425584 -88.39581) (xy 314.425155 -88.428691)
			(xy 314.417787 -88.49404) (xy 314.403143 -88.558152) (xy 314.38141 -88.620219) (xy 314.352859 -88.679461)
			(xy 314.317852 -88.735132) (xy 314.276828 -88.78653) (xy 314.25388 -88.810084) (xy 313.766708 -89.297256)
			(xy 313.743139 -89.320183) (xy 313.691726 -89.361177) (xy 313.636051 -89.396163) (xy 313.576811 -89.424701)
			(xy 313.514751 -89.446434) (xy 313.45065 -89.461089) (xy 313.385311 -89.468482) (xy 313.352434 -89.46896)
			(xy 313.237118 -89.46896) (xy 313.228499 -89.469243) (xy 313.212225 -89.474919) (xy 313.198775 -89.485695)
			(xy 313.193938 -89.492836) (xy 313.14136 -89.577164) (xy 313.139836 -89.602818) (xy 313.145678 -89.614756)
			(xy 313.157781 -89.640847) (xy 313.174873 -89.695762) (xy 313.183512 -89.752623) (xy 313.184032 -89.78138)
			(xy 313.183546 -89.808631) (xy 313.17579 -89.862579) (xy 313.160435 -89.914874) (xy 313.137793 -89.964451)
			(xy 313.108327 -90.010301) (xy 313.072636 -90.051492) (xy 313.031445 -90.087183) (xy 312.985595 -90.116649)
			(xy 312.936018 -90.139291) (xy 312.883723 -90.154646) (xy 312.829775 -90.162402) (xy 312.775273 -90.162402)
			(xy 312.721325 -90.154646) (xy 312.66903 -90.139291) (xy 312.619453 -90.116649) (xy 312.573603 -90.087183)
			(xy 312.532412 -90.051492) (xy 312.496721 -90.010301) (xy 312.467255 -89.964451) (xy 312.444613 -89.914874)
			(xy 312.429258 -89.862579) (xy 312.421502 -89.808631) (xy 312.421016 -89.78138) (xy 312.421563 -89.752626)
			(xy 312.430213 -89.69577) (xy 312.447284 -89.640853) (xy 312.45937 -89.614756) (xy 312.465212 -89.602818)
			(xy 312.463688 -89.577164) (xy 312.41111 -89.492836) (xy 312.406217 -89.48575) (xy 312.392767 -89.475017)
			(xy 312.376533 -89.469311) (xy 312.36793 -89.46896) (xy 312.27141 -89.46896) (xy 312.261339 -89.469375)
			(xy 312.242741 -89.477101) (xy 312.235342 -89.483946) (xy 307.758098 -93.96095) (xy 308.78094 -93.96095)
			(xy 308.785011 -93.905328) (xy 308.797137 -93.850891) (xy 308.81706 -93.7988) (xy 308.844356 -93.750165)
			(xy 308.878442 -93.706022) (xy 308.918591 -93.667313) (xy 308.963949 -93.634862) (xy 309.013549 -93.609361)
			(xy 309.066333 -93.591354) (xy 309.121176 -93.581224) (xy 309.17691 -93.579187) (xy 309.232347 -93.585287)
			(xy 309.286304 -93.599393) (xy 309.337633 -93.621205) (xy 309.385239 -93.650259) (xy 309.428107 -93.685934)
			(xy 309.465324 -93.727471) (xy 309.496097 -93.773984) (xy 309.516286 -93.817052) (xy 310.159632 -93.817052)
			(xy 310.159632 -93.762548) (xy 310.167388 -93.708597) (xy 310.182743 -93.6563) (xy 310.205383 -93.60672)
			(xy 310.234849 -93.560866) (xy 310.27054 -93.519672) (xy 310.311729 -93.483976) (xy 310.357579 -93.454505)
			(xy 310.407157 -93.431859) (xy 310.459452 -93.416498) (xy 310.513402 -93.408735) (xy 310.540654 -93.408246)
			(xy 310.56856 -93.408749) (xy 310.623778 -93.416869) (xy 310.677225 -93.432943) (xy 310.727761 -93.456628)
			(xy 310.774311 -93.48742) (xy 310.81588 -93.524661) (xy 310.851584 -93.567559) (xy 310.866536 -93.591126)
			(xy 310.87314 -93.602048) (xy 310.89473 -93.614748) (xy 310.992012 -93.619066) (xy 311.004347 -93.618836)
			(xy 311.026637 -93.608351) (xy 311.034684 -93.599) (xy 311.035192 -93.598492) (xy 311.05327 -93.574919)
			(xy 311.095552 -93.533193) (xy 311.143796 -93.498532) (xy 311.196834 -93.471777) (xy 311.253381 -93.453576)
			(xy 311.312068 -93.444369) (xy 311.34177 -93.443806) (xy 311.371113 -93.444357) (xy 311.429107 -93.45334)
			(xy 311.485041 -93.471098) (xy 311.537595 -93.497213) (xy 311.585531 -93.531068) (xy 311.627716 -93.571865)
			(xy 311.663155 -93.618642) (xy 311.677558 -93.644212) (xy 311.684162 -93.656658) (xy 311.708546 -93.670882)
			(xy 311.82691 -93.669866) (xy 311.850786 -93.65488) (xy 311.85739 -93.64218) (xy 311.869755 -93.619105)
			(xy 311.899787 -93.576224) (xy 311.935396 -93.537849) (xy 311.975914 -93.5047) (xy 312.020583 -93.477399)
			(xy 312.068563 -93.456458) (xy 312.118955 -93.44227) (xy 312.170813 -93.435101) (xy 312.196988 -93.434662)
			(xy 312.224239 -93.435184) (xy 312.278187 -93.442939) (xy 312.330482 -93.458293) (xy 312.38006 -93.480933)
			(xy 312.425911 -93.510399) (xy 312.467102 -93.546089) (xy 312.502794 -93.587279) (xy 312.532261 -93.633129)
			(xy 312.554903 -93.682706) (xy 312.570258 -93.735001) (xy 312.578015 -93.788949) (xy 312.578015 -93.843451)
			(xy 312.570258 -93.897399) (xy 312.554903 -93.949694) (xy 312.532261 -93.999271) (xy 312.502794 -94.045121)
			(xy 312.467102 -94.086311) (xy 312.425911 -94.122001) (xy 312.38006 -94.151467) (xy 312.330482 -94.174107)
			(xy 312.278187 -94.189461) (xy 312.224239 -94.197216) (xy 312.196988 -94.197678) (xy 312.167644 -94.197169)
			(xy 312.109647 -94.18818) (xy 312.053712 -94.170414) (xy 312.001157 -94.144293) (xy 311.953222 -94.110431)
			(xy 311.911039 -94.069627) (xy 311.875601 -94.022845) (xy 311.8612 -93.997272) (xy 311.854596 -93.984826)
			(xy 311.830212 -93.970602) (xy 311.711848 -93.971618) (xy 311.687972 -93.986604) (xy 311.681368 -93.999304)
			(xy 311.669027 -94.022393) (xy 311.638994 -94.065275) (xy 311.603381 -94.103651) (xy 311.562859 -94.136799)
			(xy 311.518187 -94.164099) (xy 311.470203 -94.185037) (xy 311.419808 -94.199221) (xy 311.367947 -94.206386)
			(xy 311.34177 -94.206822) (xy 311.313864 -94.206316) (xy 311.258646 -94.198198) (xy 311.205198 -94.182126)
			(xy 311.154661 -94.158442) (xy 311.108111 -94.12765) (xy 311.066542 -94.090408) (xy 311.030839 -94.04751)
			(xy 311.015888 -94.023942) (xy 311.009284 -94.01302) (xy 310.987694 -94.00032) (xy 310.890412 -93.996002)
			(xy 310.87808 -93.996259) (xy 310.855791 -94.006726) (xy 310.84774 -94.016068) (xy 310.847232 -94.016576)
			(xy 310.829131 -94.04013) (xy 310.786855 -94.08186) (xy 310.738616 -94.116523) (xy 310.685582 -94.143282)
			(xy 310.629038 -94.161487) (xy 310.570355 -94.170697) (xy 310.540654 -94.171262) (xy 310.513402 -94.170865)
			(xy 310.459452 -94.163102) (xy 310.407157 -94.147741) (xy 310.357579 -94.125095) (xy 310.311729 -94.095624)
			(xy 310.27054 -94.059928) (xy 310.234849 -94.018734) (xy 310.205383 -93.97288) (xy 310.182743 -93.9233)
			(xy 310.167388 -93.871003) (xy 310.159632 -93.817052) (xy 309.516286 -93.817052) (xy 309.519769 -93.824481)
			(xy 309.535837 -93.877888) (xy 309.543957 -93.933064) (xy 309.544466 -93.96095) (xy 309.543957 -93.988836)
			(xy 309.535837 -94.044012) (xy 309.519769 -94.097419) (xy 309.496097 -94.147916) (xy 309.465324 -94.194429)
			(xy 309.428107 -94.235966) (xy 309.385239 -94.271641) (xy 309.337633 -94.300695) (xy 309.286304 -94.322507)
			(xy 309.232347 -94.336613) (xy 309.17691 -94.342713) (xy 309.121176 -94.340676) (xy 309.066333 -94.330546)
			(xy 309.013549 -94.312539) (xy 308.963949 -94.287038) (xy 308.918591 -94.254587) (xy 308.878442 -94.215878)
			(xy 308.844356 -94.171735) (xy 308.81706 -94.1231) (xy 308.797137 -94.071009) (xy 308.785011 -94.016572)
			(xy 308.78094 -93.96095) (xy 307.758098 -93.96095) (xy 307.495194 -94.22384) (xy 307.488343 -94.231232)
			(xy 307.48063 -94.249837) (xy 307.480208 -94.259908) (xy 307.480208 -95.989648) (xy 307.763924 -95.989648)
			(xy 307.767995 -95.934026) (xy 307.780121 -95.879589) (xy 307.800044 -95.827498) (xy 307.82734 -95.778863)
			(xy 307.861426 -95.73472) (xy 307.901575 -95.696011) (xy 307.946933 -95.66356) (xy 307.996533 -95.638059)
			(xy 308.049317 -95.620052) (xy 308.10416 -95.609922) (xy 308.159894 -95.607885) (xy 308.215331 -95.613985)
			(xy 308.269288 -95.628091) (xy 308.320617 -95.649903) (xy 308.368223 -95.678957) (xy 308.411091 -95.714632)
			(xy 308.448308 -95.756169) (xy 308.479081 -95.802682) (xy 308.502753 -95.853179) (xy 308.518821 -95.906586)
			(xy 308.526941 -95.961762) (xy 308.52745 -95.989648) (xy 310.369456 -95.989648) (xy 310.373527 -95.934026)
			(xy 310.385653 -95.879589) (xy 310.405576 -95.827498) (xy 310.432872 -95.778863) (xy 310.466958 -95.73472)
			(xy 310.507107 -95.696011) (xy 310.552465 -95.66356) (xy 310.602065 -95.638059) (xy 310.654849 -95.620052)
			(xy 310.709692 -95.609922) (xy 310.765426 -95.607885) (xy 310.820863 -95.613985) (xy 310.87482 -95.628091)
			(xy 310.926149 -95.649903) (xy 310.973755 -95.678957) (xy 311.016623 -95.714632) (xy 311.05384 -95.756169)
			(xy 311.084613 -95.802682) (xy 311.108285 -95.853179) (xy 311.124353 -95.906586) (xy 311.132473 -95.961762)
			(xy 311.132982 -95.989648) (xy 311.132473 -96.017534) (xy 311.124353 -96.07271) (xy 311.108285 -96.126117)
			(xy 311.084613 -96.176614) (xy 311.05384 -96.223127) (xy 311.016623 -96.264664) (xy 310.973755 -96.300339)
			(xy 310.926149 -96.329393) (xy 310.87482 -96.351205) (xy 310.820863 -96.365311) (xy 310.765426 -96.371411)
			(xy 310.709692 -96.369374) (xy 310.654849 -96.359244) (xy 310.602065 -96.341237) (xy 310.552465 -96.315736)
			(xy 310.507107 -96.283285) (xy 310.466958 -96.244576) (xy 310.432872 -96.200433) (xy 310.405576 -96.151798)
			(xy 310.385653 -96.099707) (xy 310.373527 -96.04527) (xy 310.369456 -95.989648) (xy 308.52745 -95.989648)
			(xy 308.526941 -96.017534) (xy 308.518821 -96.07271) (xy 308.502753 -96.126117) (xy 308.479081 -96.176614)
			(xy 308.448308 -96.223127) (xy 308.411091 -96.264664) (xy 308.368223 -96.300339) (xy 308.320617 -96.329393)
			(xy 308.269288 -96.351205) (xy 308.215331 -96.365311) (xy 308.159894 -96.371411) (xy 308.10416 -96.369374)
			(xy 308.049317 -96.359244) (xy 307.996533 -96.341237) (xy 307.946933 -96.315736) (xy 307.901575 -96.283285)
			(xy 307.861426 -96.244576) (xy 307.82734 -96.200433) (xy 307.800044 -96.151798) (xy 307.780121 -96.099707)
			(xy 307.767995 -96.04527) (xy 307.763924 -95.989648) (xy 307.480208 -95.989648) (xy 307.480208 -96.264984)
			(xy 307.479658 -96.301728) (xy 307.470469 -96.374638) (xy 307.452233 -96.445827) (xy 307.425236 -96.514176)
			(xy 307.408072 -96.54667) (xy 307.407818 -96.546924) (xy 307.403279 -96.556441) (xy 307.401583 -96.577436)
			(xy 307.404516 -96.587564) (xy 307.429154 -96.658938) (xy 307.433091 -96.668898) (xy 307.447684 -96.684549)
			(xy 307.457348 -96.689164) (xy 307.482742 -96.700583) (xy 307.530229 -96.729647) (xy 307.572984 -96.765309)
			(xy 307.610099 -96.80681) (xy 307.640783 -96.853267) (xy 307.664384 -96.903693) (xy 307.680401 -96.957015)
			(xy 307.687545 -97.005648) (xy 310.369456 -97.005648) (xy 310.373527 -96.950026) (xy 310.385653 -96.895589)
			(xy 310.405576 -96.843498) (xy 310.432872 -96.794863) (xy 310.466958 -96.75072) (xy 310.507107 -96.712011)
			(xy 310.552465 -96.67956) (xy 310.602065 -96.654059) (xy 310.654849 -96.636052) (xy 310.709692 -96.625922)
			(xy 310.765426 -96.623885) (xy 310.820863 -96.629985) (xy 310.87482 -96.644091) (xy 310.926149 -96.665903)
			(xy 310.973755 -96.694957) (xy 311.016623 -96.730632) (xy 311.05384 -96.772169) (xy 311.084613 -96.818682)
			(xy 311.108285 -96.869179) (xy 311.124353 -96.922586) (xy 311.132473 -96.977762) (xy 311.132982 -97.005648)
			(xy 311.132473 -97.033534) (xy 311.124353 -97.08871) (xy 311.108285 -97.142117) (xy 311.084613 -97.192614)
			(xy 311.05384 -97.239127) (xy 311.016623 -97.280664) (xy 310.973755 -97.316339) (xy 310.926149 -97.345393)
			(xy 310.87482 -97.367205) (xy 310.820863 -97.381311) (xy 310.765426 -97.387411) (xy 310.709692 -97.385374)
			(xy 310.654849 -97.375244) (xy 310.602065 -97.357237) (xy 310.552465 -97.331736) (xy 310.507107 -97.299285)
			(xy 310.466958 -97.260576) (xy 310.432872 -97.216433) (xy 310.405576 -97.167798) (xy 310.385653 -97.115707)
			(xy 310.373527 -97.06127) (xy 310.369456 -97.005648) (xy 307.687545 -97.005648) (xy 307.688493 -97.0121)
			(xy 307.688996 -97.039938) (xy 307.688557 -97.067191) (xy 307.680796 -97.121141) (xy 307.665435 -97.173437)
			(xy 307.642789 -97.223015) (xy 307.613317 -97.268866) (xy 307.577621 -97.310056) (xy 307.536426 -97.345747)
			(xy 307.490571 -97.375213) (xy 307.44099 -97.397852) (xy 307.388692 -97.413206) (xy 307.334741 -97.420961)
			(xy 307.307488 -97.421446) (xy 307.281087 -97.421032) (xy 307.228793 -97.413725) (xy 307.178005 -97.39928)
			(xy 307.129694 -97.377972) (xy 307.08478 -97.350208) (xy 307.044122 -97.316518) (xy 307.008496 -97.277546)
			(xy 306.978581 -97.234035) (xy 306.966366 -97.210626) (xy 306.960356 -97.200221) (xy 306.941016 -97.186027)
			(xy 306.929282 -97.183448) (xy 306.847748 -97.169986) (xy 306.835746 -97.1688) (xy 306.812829 -97.176209)
			(xy 306.803806 -97.18421) (xy 306.765452 -97.222564) (xy 306.758646 -97.230046) (xy 306.751054 -97.248777)
			(xy 306.75072 -97.258886) (xy 306.750974 -97.331022) (xy 306.751465 -97.341054) (xy 306.759333 -97.359519)
			(xy 306.766214 -97.366836) (xy 306.766468 -97.36709) (xy 306.784356 -97.385084) (xy 306.815648 -97.425025)
			(xy 306.841371 -97.468761) (xy 306.861069 -97.51552) (xy 306.874396 -97.564478) (xy 306.881116 -97.61477)
			(xy 306.88153 -97.64014) (xy 306.881059 -97.667391) (xy 306.873298 -97.721338) (xy 306.857939 -97.773632)
			(xy 306.835295 -97.823208) (xy 306.805826 -97.869057) (xy 306.770134 -97.910246) (xy 306.728943 -97.945937)
			(xy 306.683092 -97.975403) (xy 306.633515 -97.998045) (xy 306.581221 -98.013402) (xy 306.527273 -98.021161)
			(xy 306.500022 -98.021648) (xy 306.474653 -98.021237) (xy 306.424363 -98.014514) (xy 306.375408 -98.001183)
			(xy 306.328652 -97.981479) (xy 306.284921 -97.955751) (xy 306.244986 -97.924453) (xy 306.226972 -97.906586)
			(xy 306.226718 -97.906332) (xy 306.219367 -97.899507) (xy 306.200919 -97.891676) (xy 306.190904 -97.891092)
			(xy 306.118768 -97.890838) (xy 306.108655 -97.891142) (xy 306.089923 -97.898752) (xy 306.082446 -97.90557)
			(xy 305.817016 -98.171) (xy 307.763924 -98.171) (xy 307.767995 -98.115378) (xy 307.780121 -98.060941)
			(xy 307.800044 -98.00885) (xy 307.82734 -97.960215) (xy 307.861426 -97.916072) (xy 307.901575 -97.877363)
			(xy 307.946933 -97.844912) (xy 307.996533 -97.819411) (xy 308.049317 -97.801404) (xy 308.10416 -97.791274)
			(xy 308.159894 -97.789237) (xy 308.215331 -97.795337) (xy 308.269288 -97.809443) (xy 308.320617 -97.831255)
			(xy 308.368223 -97.860309) (xy 308.411091 -97.895984) (xy 308.448308 -97.937521) (xy 308.479081 -97.984034)
			(xy 308.502753 -98.034531) (xy 308.518821 -98.087938) (xy 308.526941 -98.143114) (xy 308.52745 -98.171)
			(xy 308.526941 -98.198886) (xy 308.518821 -98.254062) (xy 308.502753 -98.307469) (xy 308.479081 -98.357966)
			(xy 308.448308 -98.404479) (xy 308.411091 -98.446016) (xy 308.368223 -98.481691) (xy 308.320617 -98.510745)
			(xy 308.269288 -98.532557) (xy 308.215331 -98.546663) (xy 308.159894 -98.552763) (xy 308.10416 -98.550726)
			(xy 308.049317 -98.540596) (xy 307.996533 -98.522589) (xy 307.946933 -98.497088) (xy 307.901575 -98.464637)
			(xy 307.861426 -98.425928) (xy 307.82734 -98.381785) (xy 307.800044 -98.33315) (xy 307.780121 -98.281059)
			(xy 307.767995 -98.226622) (xy 307.763924 -98.171) (xy 305.817016 -98.171) (xy 305.694842 -98.293174)
			(xy 305.688027 -98.300594) (xy 305.680291 -98.319178) (xy 305.679856 -98.329242) (xy 305.679856 -99.439984)
			(xy 307.509924 -99.439984) (xy 307.513995 -99.384362) (xy 307.526121 -99.329925) (xy 307.546044 -99.277834)
			(xy 307.57334 -99.229199) (xy 307.607426 -99.185056) (xy 307.647575 -99.146347) (xy 307.692933 -99.113896)
			(xy 307.742533 -99.088395) (xy 307.795317 -99.070388) (xy 307.85016 -99.060258) (xy 307.905894 -99.058221)
			(xy 307.961331 -99.064321) (xy 308.015288 -99.078427) (xy 308.066617 -99.100239) (xy 308.114223 -99.129293)
			(xy 308.157091 -99.164968) (xy 308.194308 -99.206505) (xy 308.225081 -99.253018) (xy 308.248753 -99.303515)
			(xy 308.264821 -99.356922) (xy 308.272941 -99.412098) (xy 308.27345 -99.439984) (xy 308.272941 -99.46787)
			(xy 308.264821 -99.523046) (xy 308.248753 -99.576453) (xy 308.225081 -99.62695) (xy 308.194308 -99.673463)
			(xy 308.157091 -99.715) (xy 308.114223 -99.750675) (xy 308.066617 -99.779729) (xy 308.015288 -99.801541)
			(xy 307.961331 -99.815647) (xy 307.905894 -99.821747) (xy 307.85016 -99.81971) (xy 307.795317 -99.80958)
			(xy 307.742533 -99.791573) (xy 307.692933 -99.766072) (xy 307.647575 -99.733621) (xy 307.607426 -99.694912)
			(xy 307.57334 -99.650769) (xy 307.546044 -99.602134) (xy 307.526121 -99.550043) (xy 307.513995 -99.495606)
			(xy 307.509924 -99.439984) (xy 305.679856 -99.439984) (xy 305.679856 -100.039932) (xy 306.076856 -100.039932)
			(xy 306.080927 -99.98431) (xy 306.093053 -99.929873) (xy 306.112976 -99.877782) (xy 306.140272 -99.829147)
			(xy 306.174358 -99.785004) (xy 306.214507 -99.746295) (xy 306.259865 -99.713844) (xy 306.309465 -99.688343)
			(xy 306.362249 -99.670336) (xy 306.417092 -99.660206) (xy 306.472826 -99.658169) (xy 306.528263 -99.664269)
			(xy 306.58222 -99.678375) (xy 306.633549 -99.700187) (xy 306.681155 -99.729241) (xy 306.724023 -99.764916)
			(xy 306.76124 -99.806453) (xy 306.792013 -99.852966) (xy 306.815685 -99.903463) (xy 306.831753 -99.95687)
			(xy 306.839873 -100.012046) (xy 306.840382 -100.039932) (xy 306.839873 -100.067818) (xy 306.831753 -100.122994)
			(xy 306.815685 -100.176401) (xy 306.792013 -100.226898) (xy 306.76124 -100.273411) (xy 306.724023 -100.314948)
			(xy 306.681155 -100.350623) (xy 306.633549 -100.379677) (xy 306.58222 -100.401489) (xy 306.528263 -100.415595)
			(xy 306.472826 -100.421695) (xy 306.417092 -100.419658) (xy 306.362249 -100.409528) (xy 306.309465 -100.391521)
			(xy 306.259865 -100.36602) (xy 306.214507 -100.333569) (xy 306.174358 -100.29486) (xy 306.140272 -100.250717)
			(xy 306.112976 -100.202082) (xy 306.093053 -100.149991) (xy 306.080927 -100.095554) (xy 306.076856 -100.039932)
			(xy 305.679856 -100.039932) (xy 305.679856 -101.240082) (xy 306.493924 -101.240082) (xy 306.497995 -101.18446)
			(xy 306.510121 -101.130023) (xy 306.530044 -101.077932) (xy 306.55734 -101.029297) (xy 306.591426 -100.985154)
			(xy 306.631575 -100.946445) (xy 306.676933 -100.913994) (xy 306.726533 -100.888493) (xy 306.779317 -100.870486)
			(xy 306.83416 -100.860356) (xy 306.889894 -100.858319) (xy 306.945331 -100.864419) (xy 306.999288 -100.878525)
			(xy 307.050617 -100.900337) (xy 307.098223 -100.929391) (xy 307.141091 -100.965066) (xy 307.178308 -101.006603)
			(xy 307.209081 -101.053116) (xy 307.216831 -101.069648) (xy 307.786276 -101.069648) (xy 307.790347 -101.014026)
			(xy 307.802473 -100.959589) (xy 307.822396 -100.907498) (xy 307.849692 -100.858863) (xy 307.883778 -100.81472)
			(xy 307.923927 -100.776011) (xy 307.969285 -100.74356) (xy 308.018885 -100.718059) (xy 308.071669 -100.700052)
			(xy 308.126512 -100.689922) (xy 308.182246 -100.687885) (xy 308.237683 -100.693985) (xy 308.29164 -100.708091)
			(xy 308.342969 -100.729903) (xy 308.390575 -100.758957) (xy 308.433443 -100.794632) (xy 308.47066 -100.836169)
			(xy 308.501433 -100.882682) (xy 308.525105 -100.933179) (xy 308.541173 -100.986586) (xy 308.549293 -101.041762)
			(xy 308.549802 -101.069648) (xy 310.369456 -101.069648) (xy 310.373527 -101.014026) (xy 310.385653 -100.959589)
			(xy 310.405576 -100.907498) (xy 310.432872 -100.858863) (xy 310.466958 -100.81472) (xy 310.507107 -100.776011)
			(xy 310.552465 -100.74356) (xy 310.602065 -100.718059) (xy 310.654849 -100.700052) (xy 310.709692 -100.689922)
			(xy 310.765426 -100.687885) (xy 310.820863 -100.693985) (xy 310.87482 -100.708091) (xy 310.926149 -100.729903)
			(xy 310.973755 -100.758957) (xy 311.016623 -100.794632) (xy 311.05384 -100.836169) (xy 311.084613 -100.882682)
			(xy 311.108285 -100.933179) (xy 311.124353 -100.986586) (xy 311.132473 -101.041762) (xy 311.132982 -101.069648)
			(xy 311.132473 -101.097534) (xy 311.124353 -101.15271) (xy 311.108285 -101.206117) (xy 311.084613 -101.256614)
			(xy 311.05384 -101.303127) (xy 311.016623 -101.344664) (xy 310.973755 -101.380339) (xy 310.926149 -101.409393)
			(xy 310.87482 -101.431205) (xy 310.820863 -101.445311) (xy 310.765426 -101.451411) (xy 310.709692 -101.449374)
			(xy 310.654849 -101.439244) (xy 310.602065 -101.421237) (xy 310.552465 -101.395736) (xy 310.507107 -101.363285)
			(xy 310.466958 -101.324576) (xy 310.432872 -101.280433) (xy 310.405576 -101.231798) (xy 310.385653 -101.179707)
			(xy 310.373527 -101.12527) (xy 310.369456 -101.069648) (xy 308.549802 -101.069648) (xy 308.549293 -101.097534)
			(xy 308.541173 -101.15271) (xy 308.525105 -101.206117) (xy 308.501433 -101.256614) (xy 308.47066 -101.303127)
			(xy 308.433443 -101.344664) (xy 308.390575 -101.380339) (xy 308.342969 -101.409393) (xy 308.29164 -101.431205)
			(xy 308.237683 -101.445311) (xy 308.182246 -101.451411) (xy 308.126512 -101.449374) (xy 308.071669 -101.439244)
			(xy 308.018885 -101.421237) (xy 307.969285 -101.395736) (xy 307.923927 -101.363285) (xy 307.883778 -101.324576)
			(xy 307.849692 -101.280433) (xy 307.822396 -101.231798) (xy 307.802473 -101.179707) (xy 307.790347 -101.12527)
			(xy 307.786276 -101.069648) (xy 307.216831 -101.069648) (xy 307.232753 -101.103613) (xy 307.248821 -101.15702)
			(xy 307.256941 -101.212196) (xy 307.25745 -101.240082) (xy 307.256941 -101.267968) (xy 307.248821 -101.323144)
			(xy 307.232753 -101.376551) (xy 307.209081 -101.427048) (xy 307.178308 -101.473561) (xy 307.141091 -101.515098)
			(xy 307.098223 -101.550773) (xy 307.050617 -101.579827) (xy 306.999288 -101.601639) (xy 306.945331 -101.615745)
			(xy 306.889894 -101.621845) (xy 306.83416 -101.619808) (xy 306.779317 -101.609678) (xy 306.726533 -101.591671)
			(xy 306.676933 -101.56617) (xy 306.631575 -101.533719) (xy 306.591426 -101.49501) (xy 306.55734 -101.450867)
			(xy 306.530044 -101.402232) (xy 306.510121 -101.350141) (xy 306.497995 -101.295704) (xy 306.493924 -101.240082)
			(xy 305.679856 -101.240082) (xy 305.679856 -102.489) (xy 307.001924 -102.489) (xy 307.005995 -102.433378)
			(xy 307.018121 -102.378941) (xy 307.038044 -102.32685) (xy 307.06534 -102.278215) (xy 307.099426 -102.234072)
			(xy 307.139575 -102.195363) (xy 307.184933 -102.162912) (xy 307.234533 -102.137411) (xy 307.287317 -102.119404)
			(xy 307.34216 -102.109274) (xy 307.397894 -102.107237) (xy 307.453331 -102.113337) (xy 307.507288 -102.127443)
			(xy 307.558617 -102.149255) (xy 307.606223 -102.178309) (xy 307.649091 -102.213984) (xy 307.686308 -102.255521)
			(xy 307.717081 -102.302034) (xy 307.740753 -102.352531) (xy 307.756821 -102.405938) (xy 307.764941 -102.461114)
			(xy 307.76545 -102.489) (xy 307.764941 -102.516886) (xy 307.756821 -102.572062) (xy 307.740753 -102.625469)
			(xy 307.717081 -102.675966) (xy 307.686308 -102.722479) (xy 307.649091 -102.764016) (xy 307.606223 -102.799691)
			(xy 307.558617 -102.828745) (xy 307.507288 -102.850557) (xy 307.453331 -102.864663) (xy 307.397894 -102.870763)
			(xy 307.34216 -102.868726) (xy 307.287317 -102.858596) (xy 307.234533 -102.840589) (xy 307.184933 -102.815088)
			(xy 307.139575 -102.782637) (xy 307.099426 -102.743928) (xy 307.06534 -102.699785) (xy 307.038044 -102.65115)
			(xy 307.018121 -102.599059) (xy 307.005995 -102.544622) (xy 307.001924 -102.489) (xy 305.679856 -102.489)
			(xy 305.679856 -103.886) (xy 307.509924 -103.886) (xy 307.513995 -103.830378) (xy 307.526121 -103.775941)
			(xy 307.546044 -103.72385) (xy 307.57334 -103.675215) (xy 307.607426 -103.631072) (xy 307.647575 -103.592363)
			(xy 307.692933 -103.559912) (xy 307.742533 -103.534411) (xy 307.795317 -103.516404) (xy 307.85016 -103.506274)
			(xy 307.905894 -103.504237) (xy 307.961331 -103.510337) (xy 308.015288 -103.524443) (xy 308.066617 -103.546255)
			(xy 308.114223 -103.575309) (xy 308.157091 -103.610984) (xy 308.194308 -103.652521) (xy 308.225081 -103.699034)
			(xy 308.248753 -103.749531) (xy 308.264821 -103.802938) (xy 308.272941 -103.858114) (xy 308.27345 -103.886)
			(xy 308.272941 -103.913886) (xy 308.264821 -103.969062) (xy 308.248753 -104.022469) (xy 308.225081 -104.072966)
			(xy 308.194308 -104.119479) (xy 308.157091 -104.161016) (xy 308.114223 -104.196691) (xy 308.066617 -104.225745)
			(xy 308.015288 -104.247557) (xy 307.961331 -104.261663) (xy 307.905894 -104.267763) (xy 307.85016 -104.265726)
			(xy 307.795317 -104.255596) (xy 307.742533 -104.237589) (xy 307.692933 -104.212088) (xy 307.647575 -104.179637)
			(xy 307.607426 -104.140928) (xy 307.57334 -104.096785) (xy 307.546044 -104.04815) (xy 307.526121 -103.996059)
			(xy 307.513995 -103.941622) (xy 307.509924 -103.886) (xy 305.679856 -103.886) (xy 305.679856 -104.356154)
			(xy 305.680291 -104.366223) (xy 305.688003 -104.384821) (xy 305.694842 -104.392222) (xy 306.318158 -105.015538)
			(xy 306.341068 -105.039091) (xy 306.382032 -105.09047) (xy 306.416985 -105.146112) (xy 306.445489 -105.205317)
			(xy 306.467185 -105.267342) (xy 306.4818 -105.331406) (xy 306.489151 -105.396703) (xy 306.489608 -105.429558)
			(xy 306.489608 -108.910628) (xy 306.490045 -108.919788) (xy 306.496526 -108.936926) (xy 306.508616 -108.950693)
			(xy 306.524773 -108.959333) (xy 306.533804 -108.96092) (xy 306.559995 -108.964898) (xy 306.611023 -108.979127)
			(xy 306.65959 -109.000283) (xy 306.704761 -109.027957) (xy 306.745667 -109.061617) (xy 306.763928 -109.080808)
			(xy 306.771436 -109.088225) (xy 306.790727 -109.09674) (xy 306.801266 -109.097318) (xy 306.875942 -109.097318)
			(xy 306.886489 -109.096766) (xy 306.905784 -109.088246) (xy 306.91328 -109.080808) (xy 306.931454 -109.061771)
			(xy 306.972079 -109.028312) (xy 307.016916 -109.00075) (xy 307.065113 -108.979608) (xy 307.115757 -108.965287)
			(xy 307.167889 -108.958059) (xy 307.194204 -108.957618) (xy 307.221458 -108.958052) (xy 307.275411 -108.96581)
			(xy 307.327711 -108.981168) (xy 307.377293 -109.003813) (xy 307.423148 -109.033283) (xy 307.464341 -109.06898)
			(xy 307.500035 -109.110176) (xy 307.529502 -109.156033) (xy 307.552143 -109.205617) (xy 307.567496 -109.257918)
			(xy 307.57525 -109.311872) (xy 307.575712 -109.339126) (xy 307.575201 -109.367865) (xy 307.566575 -109.424693)
			(xy 307.549522 -109.479584) (xy 307.524427 -109.531295) (xy 307.49186 -109.578657) (xy 307.472588 -109.599984)
			(xy 307.465984 -109.606842) (xy 307.458872 -109.624876) (xy 307.458872 -109.713776) (xy 307.465984 -109.73181)
			(xy 307.472588 -109.738668) (xy 307.491884 -109.759973) (xy 307.524447 -109.807339) (xy 307.549537 -109.859055)
			(xy 307.566584 -109.913949) (xy 307.575204 -109.970779) (xy 307.575201 -110.028259) (xy 307.566576 -110.085088)
			(xy 307.549523 -110.139981) (xy 307.524428 -110.191694) (xy 307.49186 -110.239057) (xy 307.472588 -110.260384)
			(xy 307.465984 -110.267242) (xy 307.458872 -110.285276) (xy 307.458872 -110.374176) (xy 307.465984 -110.39221)
			(xy 307.472588 -110.399068) (xy 307.491884 -110.420373) (xy 307.524447 -110.467739) (xy 307.549537 -110.519455)
			(xy 307.566584 -110.574349) (xy 307.575204 -110.631179) (xy 307.575201 -110.688659) (xy 307.566576 -110.745488)
			(xy 307.549523 -110.800381) (xy 307.524428 -110.852094) (xy 307.49186 -110.899457) (xy 307.472588 -110.920784)
			(xy 307.465984 -110.927642) (xy 307.458872 -110.945676) (xy 307.458872 -111.034576) (xy 307.465984 -111.05261)
			(xy 307.472588 -111.059468) (xy 307.491884 -111.080773) (xy 307.524447 -111.128139) (xy 307.549537 -111.179855)
			(xy 307.566584 -111.234749) (xy 307.575204 -111.291579) (xy 307.575201 -111.349059) (xy 307.566576 -111.405888)
			(xy 307.549523 -111.460781) (xy 307.524428 -111.512494) (xy 307.49186 -111.559857) (xy 307.472588 -111.581184)
			(xy 307.465984 -111.588042) (xy 307.458872 -111.606076) (xy 307.458872 -111.694976) (xy 307.465984 -111.71301)
			(xy 307.472588 -111.719868) (xy 307.491875 -111.741181) (xy 307.524438 -111.788547) (xy 307.549527 -111.840262)
			(xy 307.566574 -111.895156) (xy 307.575193 -111.951986) (xy 307.575712 -111.980726) (xy 307.575246 -112.007978)
			(xy 307.567486 -112.061926) (xy 307.552128 -112.114221) (xy 307.529484 -112.163798) (xy 307.500016 -112.209648)
			(xy 307.464322 -112.250838) (xy 307.42313 -112.286529) (xy 307.377279 -112.315995) (xy 307.3277 -112.338636)
			(xy 307.275404 -112.353991) (xy 307.221456 -112.361748) (xy 307.194204 -112.362234) (xy 307.167891 -112.361753)
			(xy 307.115763 -112.354519) (xy 307.065121 -112.340202) (xy 307.016922 -112.319072) (xy 306.972078 -112.291529)
			(xy 306.931438 -112.258094) (xy 306.91328 -112.239044) (xy 306.905762 -112.231638) (xy 306.886479 -112.223115)
			(xy 306.875942 -112.222534) (xy 306.801266 -112.222534) (xy 306.790717 -112.223075) (xy 306.771421 -112.231601)
			(xy 306.763928 -112.239044) (xy 306.74576 -112.258087) (xy 306.705132 -112.291544) (xy 306.660294 -112.319103)
			(xy 306.612096 -112.340244) (xy 306.561451 -112.354564) (xy 306.509319 -112.361793) (xy 306.483004 -112.362234)
			(xy 306.481988 -112.362234) (xy 306.47231 -112.362682) (xy 306.454319 -112.369828) (xy 306.440234 -112.383106)
			(xy 306.43576 -112.391698) (xy 306.420873 -112.422778) (xy 306.384848 -112.481527) (xy 306.342173 -112.535639)
			(xy 306.318158 -112.560354) (xy 304.903378 -113.975134) (xy 304.879824 -113.998044) (xy 304.828447 -114.039011)
			(xy 304.772805 -114.073967) (xy 304.7136 -114.102474) (xy 304.651576 -114.124172) (xy 304.587511 -114.13879)
			(xy 304.522213 -114.146143) (xy 304.489358 -114.146584) (xy 303.93513 -114.146584) (xy 303.925059 -114.147003)
			(xy 303.90646 -114.154726) (xy 303.899062 -114.16157) (xy 303.356518 -114.704368) (xy 303.332946 -114.727292)
			(xy 303.281534 -114.768286) (xy 303.225859 -114.803272) (xy 303.16662 -114.831811) (xy 303.10456 -114.853544)
			(xy 303.040459 -114.8682) (xy 302.975121 -114.875593) (xy 302.942244 -114.876072) (xy 302.906838 -114.875469)
			(xy 302.836543 -114.866937) (xy 302.767789 -114.849991) (xy 302.70158 -114.824879) (xy 302.638881 -114.791968)
			(xy 302.580608 -114.751738) (xy 302.527611 -114.704774) (xy 302.480662 -114.651764) (xy 302.440448 -114.59348)
			(xy 302.407554 -114.530772) (xy 302.382461 -114.464556) (xy 302.365534 -114.395798) (xy 302.357021 -114.3255)
			(xy 302.35652 -114.290094) (xy 302.35694 -114.257221) (xy 302.364289 -114.191888) (xy 302.378906 -114.127789)
			(xy 302.400606 -114.065728) (xy 302.429118 -114.006487) (xy 302.464082 -113.95081) (xy 302.505058 -113.899397)
			(xy 302.52797 -113.87582) (xy 302.899826 -113.503964) (xy 302.908268 -113.494733) (xy 302.915737 -113.470892)
			(xy 302.91405 -113.458498) (xy 302.896016 -113.363756) (xy 302.880522 -113.344198) (xy 302.868838 -113.339118)
			(xy 302.843738 -113.327576) (xy 302.796868 -113.298332) (xy 302.754707 -113.262633) (xy 302.718136 -113.221226)
			(xy 302.687919 -113.174978) (xy 302.664689 -113.124855) (xy 302.648932 -113.071905) (xy 302.640976 -113.017236)
			(xy 302.640492 -112.989614) (xy 302.640968 -112.962361) (xy 302.648723 -112.908411) (xy 302.664078 -112.856113)
			(xy 302.686719 -112.806533) (xy 302.716185 -112.76068) (xy 302.751877 -112.719487) (xy 302.793069 -112.683793)
			(xy 302.838921 -112.654325) (xy 302.8885 -112.631683) (xy 302.940797 -112.616326) (xy 302.994748 -112.608569)
			(xy 303.022 -112.608106) (xy 303.048275 -112.608479) (xy 303.10033 -112.615679) (xy 303.150903 -112.629956)
			(xy 303.199038 -112.651041) (xy 303.243823 -112.678533) (xy 303.284411 -112.711912) (xy 303.320032 -112.750547)
			(xy 303.350012 -112.793706) (xy 303.373785 -112.840571) (xy 303.390899 -112.890257) (xy 303.396396 -112.915954)
			(xy 303.398428 -112.926368) (xy 303.410112 -112.94364) (xy 303.481994 -112.988344) (xy 303.491025 -112.993417)
			(xy 303.511479 -112.996559) (xy 303.521618 -112.99444) (xy 303.521872 -112.99444) (xy 303.558356 -112.985421)
			(xy 303.632885 -112.975743) (xy 303.670462 -112.975136) (xy 304.225452 -112.975136) (xy 304.235521 -112.974703)
			(xy 304.25412 -112.966989) (xy 304.26152 -112.96015) (xy 305.303174 -111.918496) (xy 305.310004 -111.911088)
			(xy 305.31773 -111.892495) (xy 305.31816 -111.882428) (xy 305.31816 -109.00156) (xy 305.317536 -108.990238)
			(xy 305.307767 -108.969805) (xy 305.299364 -108.96219) (xy 305.22926 -108.905294) (xy 305.206908 -108.89996)
			(xy 305.195732 -108.902246) (xy 305.166103 -108.908069) (xy 305.106038 -108.914304) (xy 305.075844 -108.914692)
			(xy 304.096928 -108.914692) (xy 304.086857 -108.915108) (xy 304.068258 -108.922833) (xy 304.06086 -108.929678)
			(xy 303.010062 -109.980476) (xy 303.003761 -109.987418) (xy 302.996211 -110.00456) (xy 302.995324 -110.023269)
			(xy 302.99787 -110.032292) (xy 303.030636 -110.132114) (xy 303.05248 -110.150656) (xy 303.066958 -110.152688)
			(xy 303.093757 -110.157197) (xy 303.145836 -110.17271) (xy 303.195188 -110.195454) (xy 303.240814 -110.22497)
			(xy 303.281792 -110.26066) (xy 303.317292 -110.301802) (xy 303.346596 -110.347564) (xy 303.369111 -110.397021)
			(xy 303.384383 -110.449172) (xy 303.392101 -110.502962) (xy 303.392586 -110.530132) (xy 303.392152 -110.557385)
			(xy 303.38439 -110.611336) (xy 303.36903 -110.663633) (xy 303.346384 -110.713212) (xy 303.316912 -110.759063)
			(xy 303.281215 -110.800253) (xy 303.24002 -110.835944) (xy 303.194164 -110.86541) (xy 303.144582 -110.888049)
			(xy 303.092283 -110.903402) (xy 303.038331 -110.911156) (xy 303.011078 -110.91164) (xy 302.983902 -110.911196)
			(xy 302.9301 -110.903492) (xy 302.877935 -110.88823) (xy 302.828465 -110.865719) (xy 302.782691 -110.836414)
			(xy 302.74154 -110.800909) (xy 302.705845 -110.759922) (xy 302.676328 -110.714284) (xy 302.653589 -110.664918)
			(xy 302.638086 -110.612825) (xy 302.633634 -110.586012) (xy 302.631602 -110.571534) (xy 302.61306 -110.54969)
			(xy 302.513238 -110.516924) (xy 302.504224 -110.514344) (xy 302.485508 -110.515248) (xy 302.468363 -110.522809)
			(xy 302.461422 -110.529116) (xy 301.69739 -111.293148) (xy 301.690579 -111.300571) (xy 301.682843 -111.319153)
			(xy 301.682404 -111.329216) (xy 301.682404 -111.884206) (xy 302.56429 -111.884206) (xy 302.568361 -111.828584)
			(xy 302.580487 -111.774147) (xy 302.60041 -111.722056) (xy 302.627706 -111.673421) (xy 302.661792 -111.629278)
			(xy 302.701941 -111.590569) (xy 302.747299 -111.558118) (xy 302.796899 -111.532617) (xy 302.849683 -111.51461)
			(xy 302.904526 -111.50448) (xy 302.96026 -111.502443) (xy 303.015697 -111.508543) (xy 303.069654 -111.522649)
			(xy 303.120983 -111.544461) (xy 303.168589 -111.573515) (xy 303.211457 -111.60919) (xy 303.248674 -111.650727)
			(xy 303.279447 -111.69724) (xy 303.303119 -111.747737) (xy 303.319187 -111.801144) (xy 303.327307 -111.85632)
			(xy 303.327816 -111.884206) (xy 303.327307 -111.912092) (xy 303.319187 -111.967268) (xy 303.303119 -112.020675)
			(xy 303.279447 -112.071172) (xy 303.248674 -112.117685) (xy 303.211457 -112.159222) (xy 303.168589 -112.194897)
			(xy 303.120983 -112.223951) (xy 303.069654 -112.245763) (xy 303.015697 -112.259869) (xy 302.96026 -112.265969)
			(xy 302.904526 -112.263932) (xy 302.849683 -112.253802) (xy 302.796899 -112.235795) (xy 302.747299 -112.210294)
			(xy 302.701941 -112.177843) (xy 302.661792 -112.139134) (xy 302.627706 -112.094991) (xy 302.60041 -112.046356)
			(xy 302.580487 -111.994265) (xy 302.568361 -111.939828) (xy 302.56429 -111.884206) (xy 301.682404 -111.884206)
			(xy 301.682404 -112.010444) (xy 301.682758 -112.019422) (xy 301.689009 -112.036259) (xy 301.700663 -112.049923)
			(xy 301.708312 -112.05464) (xy 301.797974 -112.104932) (xy 301.825152 -112.104424) (xy 301.83709 -112.097058)
			(xy 301.859734 -112.083643) (xy 301.907908 -112.062449) (xy 301.958543 -112.048095) (xy 302.010673 -112.040855)
			(xy 302.036988 -112.040416) (xy 302.064243 -112.04083) (xy 302.118199 -112.048586) (xy 302.170501 -112.063942)
			(xy 302.220086 -112.086585) (xy 302.265944 -112.116055) (xy 302.307141 -112.151751) (xy 302.342838 -112.192947)
			(xy 302.372309 -112.238803) (xy 302.394954 -112.288387) (xy 302.410311 -112.340689) (xy 302.418069 -112.394645)
			(xy 302.418069 -112.449155) (xy 302.410311 -112.503111) (xy 302.394954 -112.555413) (xy 302.372309 -112.604997)
			(xy 302.342838 -112.650853) (xy 302.307141 -112.692049) (xy 302.265944 -112.727745) (xy 302.220086 -112.757215)
			(xy 302.170501 -112.779858) (xy 302.118199 -112.795214) (xy 302.064243 -112.80297) (xy 302.036988 -112.803432)
			(xy 302.010676 -112.802946) (xy 301.958555 -112.795686) (xy 301.907922 -112.781345) (xy 301.859735 -112.760196)
			(xy 301.83709 -112.74679) (xy 301.829246 -112.742356) (xy 301.811587 -112.738833) (xy 301.793804 -112.74167)
			(xy 301.785782 -112.745774) (xy 301.708312 -112.789208) (xy 301.700634 -112.79389) (xy 301.688955 -112.807551)
			(xy 301.682747 -112.824417) (xy 301.682404 -112.833404) (xy 301.682404 -112.980724) (xy 301.683088 -112.992888)
			(xy 301.69423 -113.014511) (xy 301.70374 -113.022126) (xy 301.780702 -113.077244) (xy 301.804832 -113.0808)
			(xy 301.816516 -113.076736) (xy 301.846237 -113.067281) (xy 301.907762 -113.057077) (xy 301.938944 -113.056416)
			(xy 301.939706 -113.056416) (xy 301.966959 -113.056854) (xy 302.020909 -113.064612) (xy 302.073206 -113.079969)
			(xy 302.122786 -113.102611) (xy 302.168639 -113.13208) (xy 302.209831 -113.167774) (xy 302.245524 -113.208966)
			(xy 302.274991 -113.254819) (xy 302.297634 -113.304399) (xy 302.312989 -113.356697) (xy 302.320746 -113.410647)
			(xy 302.320746 -113.465153) (xy 302.312989 -113.519103) (xy 302.297634 -113.571401) (xy 302.274991 -113.620981)
			(xy 302.245524 -113.666834) (xy 302.209831 -113.708026) (xy 302.168639 -113.74372) (xy 302.122786 -113.773189)
			(xy 302.073206 -113.795831) (xy 302.020909 -113.811188) (xy 301.966959 -113.818946) (xy 301.939706 -113.819432)
			(xy 301.938944 -113.819432) (xy 301.907761 -113.818785) (xy 301.846236 -113.808573) (xy 301.816516 -113.799112)
			(xy 301.804832 -113.795048) (xy 301.780702 -113.798604) (xy 301.70374 -113.853722) (xy 301.694217 -113.861321)
			(xy 301.68309 -113.882958) (xy 301.682404 -113.895124) (xy 301.682404 -114.270536) (xy 301.681921 -114.303416)
			(xy 301.674561 -114.368762) (xy 301.659926 -114.432873) (xy 301.638201 -114.49494) (xy 301.609659 -114.554182)
			(xy 301.57466 -114.609854) (xy 301.533644 -114.661255) (xy 301.5107 -114.68481) (xy 300.834552 -115.360958)
			(xy 306.318412 -115.360958) (xy 306.318909 -115.333589) (xy 306.326719 -115.279411) (xy 306.342201 -115.226908)
			(xy 306.365036 -115.177161) (xy 306.394754 -115.131193) (xy 306.412392 -115.11026) (xy 306.412646 -115.110006)
			(xy 306.418242 -115.102926) (xy 306.424482 -115.086004) (xy 306.424838 -115.076986) (xy 306.424838 -115.00993)
			(xy 306.424458 -115.000916) (xy 306.418226 -114.983999) (xy 306.412646 -114.97691) (xy 306.412392 -114.97691)
			(xy 306.412392 -114.976656) (xy 306.394764 -114.955715) (xy 306.365051 -114.909744) (xy 306.342213 -114.859999)
			(xy 306.326719 -114.807501) (xy 306.318888 -114.753327) (xy 306.318412 -114.725958) (xy 306.318839 -114.698705)
			(xy 306.326602 -114.644754) (xy 306.341963 -114.592457) (xy 306.364611 -114.542878) (xy 306.394083 -114.497027)
			(xy 306.429781 -114.455837) (xy 306.470977 -114.420146) (xy 306.516833 -114.390681) (xy 306.566415 -114.368041)
			(xy 306.618715 -114.352688) (xy 306.672667 -114.344934) (xy 306.69992 -114.34445) (xy 306.727291 -114.344892)
			(xy 306.781472 -114.352714) (xy 306.833976 -114.368208) (xy 306.883722 -114.391055) (xy 306.929688 -114.420786)
			(xy 306.950618 -114.43843) (xy 306.950872 -114.438684) (xy 306.957964 -114.444263) (xy 306.974876 -114.450515)
			(xy 306.983892 -114.450876) (xy 307.050948 -114.450876) (xy 307.059963 -114.450499) (xy 307.07688 -114.444266)
			(xy 307.083968 -114.438684) (xy 307.083968 -114.43843) (xy 307.084222 -114.43843) (xy 307.105177 -114.420819)
			(xy 307.151143 -114.391102) (xy 307.200884 -114.36826) (xy 307.25338 -114.352762) (xy 307.307552 -114.344927)
			(xy 307.33492 -114.34445) (xy 307.36217 -114.344959) (xy 307.416115 -114.352717) (xy 307.468406 -114.368073)
			(xy 307.517981 -114.390713) (xy 307.563829 -114.420178) (xy 307.605018 -114.455866) (xy 307.640709 -114.497053)
			(xy 307.670176 -114.5429) (xy 307.69282 -114.592473) (xy 307.708178 -114.644764) (xy 307.715939 -114.698708)
			(xy 307.716428 -114.725958) (xy 307.715955 -114.753328) (xy 307.708141 -114.807508) (xy 307.692655 -114.860011)
			(xy 307.669814 -114.909758) (xy 307.64009 -114.955725) (xy 307.622448 -114.976656) (xy 307.622194 -114.97691)
			(xy 307.616596 -114.983989) (xy 307.610357 -115.000912) (xy 307.610002 -115.00993) (xy 307.610002 -115.076986)
			(xy 307.610365 -115.086002) (xy 307.616608 -115.102919) (xy 307.622194 -115.110006) (xy 307.622448 -115.110006)
			(xy 307.622448 -115.11026) (xy 307.640074 -115.131203) (xy 307.669789 -115.177172) (xy 307.692629 -115.226917)
			(xy 307.708123 -115.279415) (xy 307.715953 -115.333589) (xy 307.716428 -115.360958) (xy 307.715906 -115.388209)
			(xy 307.708155 -115.442157) (xy 307.692805 -115.494452) (xy 307.670169 -115.544031) (xy 307.640707 -115.589883)
			(xy 307.60502 -115.631076) (xy 307.563833 -115.66677) (xy 307.517985 -115.696239) (xy 307.46841 -115.718884)
			(xy 307.416117 -115.734242) (xy 307.362171 -115.742001) (xy 307.33492 -115.742466) (xy 307.30755 -115.741996)
			(xy 307.253371 -115.734181) (xy 307.200867 -115.718693) (xy 307.15112 -115.695852) (xy 307.105153 -115.666127)
			(xy 307.084222 -115.648486) (xy 307.083968 -115.648232) (xy 307.076872 -115.64266) (xy 307.059962 -115.636406)
			(xy 307.050948 -115.63604) (xy 306.983892 -115.63604) (xy 306.974874 -115.636384) (xy 306.957956 -115.64264)
			(xy 306.950872 -115.648232) (xy 306.950872 -115.648486) (xy 306.950618 -115.648486) (xy 306.929688 -115.666128)
			(xy 306.883715 -115.69584) (xy 306.833967 -115.718675) (xy 306.781466 -115.734166) (xy 306.727289 -115.741993)
			(xy 306.69992 -115.742466) (xy 306.672666 -115.742026) (xy 306.618712 -115.734271) (xy 306.566411 -115.718915)
			(xy 306.516828 -115.696272) (xy 306.470973 -115.666802) (xy 306.429779 -115.631106) (xy 306.394085 -115.58991)
			(xy 306.364618 -115.544053) (xy 306.341977 -115.494468) (xy 306.326625 -115.442167) (xy 306.318872 -115.388212)
			(xy 306.318412 -115.360958) (xy 300.834552 -115.360958) (xy 300.495462 -115.700048) (xy 300.471867 -115.722947)
			(xy 300.420459 -115.763944) (xy 300.364789 -115.798933) (xy 300.305554 -115.827475) (xy 300.243498 -115.849213)
			(xy 300.1794 -115.863873) (xy 300.114064 -115.871271) (xy 300.081188 -115.871752) (xy 299.512736 -115.871752)
			(xy 299.477329 -115.871177) (xy 299.407032 -115.862643) (xy 299.338277 -115.845696) (xy 299.272066 -115.820582)
			(xy 299.209367 -115.787669) (xy 299.151093 -115.747436) (xy 299.098095 -115.70047) (xy 299.051147 -115.647457)
			(xy 299.010933 -115.589171) (xy 298.97804 -115.52646) (xy 298.952948 -115.460242) (xy 298.936023 -115.391481)
			(xy 298.927512 -115.321181) (xy 298.927012 -115.285774) (xy 298.927429 -115.253698) (xy 298.934417 -115.189928)
			(xy 298.948329 -115.127303) (xy 298.958254 -115.096798) (xy 298.961398 -115.085374) (xy 298.958094 -115.061942)
			(xy 298.951904 -115.05184) (xy 298.898818 -114.974624) (xy 298.878244 -114.963194) (xy 298.866052 -114.962686)
			(xy 298.839542 -114.961195) (xy 298.787304 -114.951685) (xy 298.736888 -114.935026) (xy 298.689268 -114.911539)
			(xy 298.645363 -114.881678) (xy 298.606021 -114.846019) (xy 298.572003 -114.805251) (xy 298.543963 -114.760161)
			(xy 298.522444 -114.71162) (xy 298.507862 -114.660564) (xy 298.500498 -114.607981) (xy 298.500038 -114.581432)
			(xy 296.275742 -114.581432) (xy 296.023944 -115.902486) (xy 296.391074 -115.902486) (xy 296.395145 -115.846864)
			(xy 296.407271 -115.792427) (xy 296.427194 -115.740336) (xy 296.45449 -115.691701) (xy 296.488576 -115.647558)
			(xy 296.528725 -115.608849) (xy 296.574083 -115.576398) (xy 296.623683 -115.550897) (xy 296.676467 -115.53289)
			(xy 296.73131 -115.52276) (xy 296.787044 -115.520723) (xy 296.842481 -115.526823) (xy 296.896438 -115.540929)
			(xy 296.947767 -115.562741) (xy 296.995373 -115.591795) (xy 297.038241 -115.62747) (xy 297.075458 -115.669007)
			(xy 297.106231 -115.71552) (xy 297.129903 -115.766017) (xy 297.145971 -115.819424) (xy 297.154091 -115.8746)
			(xy 297.1546 -115.902486) (xy 297.154091 -115.930372) (xy 297.145971 -115.985548) (xy 297.129903 -116.038955)
			(xy 297.106231 -116.089452) (xy 297.075458 -116.135965) (xy 297.038241 -116.177502) (xy 296.995373 -116.213177)
			(xy 296.947767 -116.242231) (xy 296.896438 -116.264043) (xy 296.842481 -116.278149) (xy 296.787044 -116.284249)
			(xy 296.73131 -116.282212) (xy 296.676467 -116.272082) (xy 296.623683 -116.254075) (xy 296.574083 -116.228574)
			(xy 296.528725 -116.196123) (xy 296.488576 -116.157414) (xy 296.45449 -116.113271) (xy 296.427194 -116.064636)
			(xy 296.407271 -116.012545) (xy 296.395145 -115.958108) (xy 296.391074 -115.902486) (xy 296.023944 -115.902486)
			(xy 295.920049 -116.44757) (xy 298.357034 -116.44757) (xy 298.361105 -116.391948) (xy 298.373231 -116.337511)
			(xy 298.393154 -116.28542) (xy 298.42045 -116.236785) (xy 298.454536 -116.192642) (xy 298.494685 -116.153933)
			(xy 298.540043 -116.121482) (xy 298.589643 -116.095981) (xy 298.642427 -116.077974) (xy 298.69727 -116.067844)
			(xy 298.753004 -116.065807) (xy 298.808441 -116.071907) (xy 298.862398 -116.086013) (xy 298.913727 -116.107825)
			(xy 298.961333 -116.136879) (xy 299.004201 -116.172554) (xy 299.041418 -116.214091) (xy 299.072191 -116.260604)
			(xy 299.095863 -116.311101) (xy 299.111931 -116.364508) (xy 299.120051 -116.419684) (xy 299.12056 -116.44757)
			(xy 299.120051 -116.475456) (xy 299.119781 -116.477288) (xy 303.504344 -116.477288) (xy 303.508415 -116.421666)
			(xy 303.520541 -116.367229) (xy 303.540464 -116.315138) (xy 303.56776 -116.266503) (xy 303.601846 -116.22236)
			(xy 303.641995 -116.183651) (xy 303.687353 -116.1512) (xy 303.736953 -116.125699) (xy 303.789737 -116.107692)
			(xy 303.84458 -116.097562) (xy 303.900314 -116.095525) (xy 303.955751 -116.101625) (xy 304.009708 -116.115731)
			(xy 304.061037 -116.137543) (xy 304.108643 -116.166597) (xy 304.151511 -116.202272) (xy 304.188728 -116.243809)
			(xy 304.219501 -116.290322) (xy 304.243173 -116.340819) (xy 304.259241 -116.394226) (xy 304.267361 -116.449402)
			(xy 304.26787 -116.477288) (xy 304.267361 -116.505174) (xy 304.259241 -116.56035) (xy 304.243173 -116.613757)
			(xy 304.219501 -116.664254) (xy 304.188728 -116.710767) (xy 304.151511 -116.752304) (xy 304.108643 -116.787979)
			(xy 304.061037 -116.817033) (xy 304.009708 -116.838845) (xy 303.955751 -116.852951) (xy 303.900314 -116.859051)
			(xy 303.84458 -116.857014) (xy 303.789737 -116.846884) (xy 303.736953 -116.828877) (xy 303.687353 -116.803376)
			(xy 303.641995 -116.770925) (xy 303.601846 -116.732216) (xy 303.56776 -116.688073) (xy 303.540464 -116.639438)
			(xy 303.520541 -116.587347) (xy 303.508415 -116.53291) (xy 303.504344 -116.477288) (xy 299.119781 -116.477288)
			(xy 299.111931 -116.530632) (xy 299.095863 -116.584039) (xy 299.072191 -116.634536) (xy 299.041418 -116.681049)
			(xy 299.004201 -116.722586) (xy 298.961333 -116.758261) (xy 298.913727 -116.787315) (xy 298.862398 -116.809127)
			(xy 298.808441 -116.823233) (xy 298.753004 -116.829333) (xy 298.69727 -116.827296) (xy 298.642427 -116.817166)
			(xy 298.589643 -116.799159) (xy 298.540043 -116.773658) (xy 298.494685 -116.741207) (xy 298.454536 -116.702498)
			(xy 298.42045 -116.658355) (xy 298.393154 -116.60972) (xy 298.373231 -116.557629) (xy 298.361105 -116.503192)
			(xy 298.357034 -116.44757) (xy 295.920049 -116.44757) (xy 295.868344 -116.718842) (xy 295.744392 -117.369844)
			(xy 295.743884 -117.3734) (xy 295.701751 -117.723666) (xy 301.889666 -117.723666) (xy 301.893737 -117.668044)
			(xy 301.905863 -117.613607) (xy 301.925786 -117.561516) (xy 301.953082 -117.512881) (xy 301.987168 -117.468738)
			(xy 302.027317 -117.430029) (xy 302.072675 -117.397578) (xy 302.122275 -117.372077) (xy 302.175059 -117.35407)
			(xy 302.229902 -117.34394) (xy 302.285636 -117.341903) (xy 302.341073 -117.348003) (xy 302.39503 -117.362109)
			(xy 302.446359 -117.383921) (xy 302.493965 -117.412975) (xy 302.536833 -117.44865) (xy 302.57405 -117.490187)
			(xy 302.604823 -117.5367) (xy 302.628495 -117.587197) (xy 302.644563 -117.640604) (xy 302.652683 -117.69578)
			(xy 302.653192 -117.723666) (xy 302.652683 -117.751552) (xy 302.651628 -117.758718) (xy 306.675028 -117.758718)
			(xy 306.675028 -116.895118) (xy 306.675518 -116.86515) (xy 306.683341 -116.805728) (xy 306.698854 -116.747835)
			(xy 306.72179 -116.692462) (xy 306.751757 -116.640556) (xy 306.788244 -116.593006) (xy 306.830624 -116.550626)
			(xy 306.878174 -116.514139) (xy 306.93008 -116.484172) (xy 306.985453 -116.461236) (xy 307.043346 -116.445723)
			(xy 307.102768 -116.4379) (xy 307.162704 -116.4379) (xy 307.222126 -116.445723) (xy 307.280019 -116.461236)
			(xy 307.335392 -116.484172) (xy 307.387298 -116.514139) (xy 307.434848 -116.550626) (xy 307.477228 -116.593006)
			(xy 307.513715 -116.640556) (xy 307.543682 -116.692462) (xy 307.566618 -116.747835) (xy 307.582131 -116.805728)
			(xy 307.589954 -116.86515) (xy 307.590444 -116.895118) (xy 307.590444 -117.758718) (xy 307.589954 -117.788686)
			(xy 307.582131 -117.848108) (xy 307.566618 -117.906001) (xy 307.543682 -117.961374) (xy 307.513715 -118.01328)
			(xy 307.477228 -118.06083) (xy 307.434848 -118.10321) (xy 307.387298 -118.139697) (xy 307.335392 -118.169664)
			(xy 307.280019 -118.1926) (xy 307.222126 -118.208113) (xy 307.162704 -118.215936) (xy 307.102768 -118.215936)
			(xy 307.043346 -118.208113) (xy 306.985453 -118.1926) (xy 306.93008 -118.169664) (xy 306.878174 -118.139697)
			(xy 306.830624 -118.10321) (xy 306.788244 -118.06083) (xy 306.751757 -118.01328) (xy 306.72179 -117.961374)
			(xy 306.698854 -117.906001) (xy 306.683341 -117.848108) (xy 306.675518 -117.788686) (xy 306.675028 -117.758718)
			(xy 302.651628 -117.758718) (xy 302.644563 -117.806728) (xy 302.628495 -117.860135) (xy 302.604823 -117.910632)
			(xy 302.57405 -117.957145) (xy 302.536833 -117.998682) (xy 302.493965 -118.034357) (xy 302.446359 -118.063411)
			(xy 302.39503 -118.085223) (xy 302.341073 -118.099329) (xy 302.285636 -118.105429) (xy 302.229902 -118.103392)
			(xy 302.175059 -118.093262) (xy 302.122275 -118.075255) (xy 302.072675 -118.049754) (xy 302.027317 -118.017303)
			(xy 301.987168 -117.978594) (xy 301.953082 -117.934451) (xy 301.925786 -117.885816) (xy 301.905863 -117.833725)
			(xy 301.893737 -117.779288) (xy 301.889666 -117.723666) (xy 295.701751 -117.723666) (xy 295.671748 -117.973094)
			(xy 295.671565 -117.979225) (xy 295.673747 -117.991292) (xy 295.676066 -117.99697) (xy 295.67886 -118.002812)
			(xy 295.686988 -118.012972) (xy 295.693592 -118.017544) (xy 295.71513 -118.032854) (xy 295.754169 -118.068466)
			(xy 295.787914 -118.109129) (xy 295.815718 -118.154064) (xy 295.837048 -118.20241) (xy 295.851495 -118.253238)
			(xy 295.858782 -118.305575) (xy 295.8592 -118.331996) (xy 295.858671 -118.36085) (xy 295.84998 -118.417898)
			(xy 295.832796 -118.472988) (xy 295.807512 -118.52486) (xy 295.774703 -118.572333) (xy 295.735119 -118.614324)
			(xy 295.689662 -118.649873) (xy 295.639369 -118.678171) (xy 295.612566 -118.688866) (xy 295.612312 -118.688866)
			(xy 295.599358 -118.693946) (xy 295.599104 -118.693946) (xy 295.590468 -118.704868) (xy 295.585896 -118.711472)
			(xy 295.583976 -118.71507) (xy 295.581171 -118.722726) (xy 295.580308 -118.726712) (xy 295.47885 -119.567198)
			(xy 298.799504 -119.567198) (xy 298.799504 -118.703598) (xy 298.799994 -118.67363) (xy 298.807817 -118.614208)
			(xy 298.82333 -118.556315) (xy 298.846266 -118.500942) (xy 298.876233 -118.449036) (xy 298.91272 -118.401486)
			(xy 298.9551 -118.359106) (xy 299.00265 -118.322619) (xy 299.054556 -118.292652) (xy 299.109929 -118.269716)
			(xy 299.167822 -118.254203) (xy 299.227244 -118.24638) (xy 299.28718 -118.24638) (xy 299.346602 -118.254203)
			(xy 299.404495 -118.269716) (xy 299.459868 -118.292652) (xy 299.511774 -118.322619) (xy 299.559324 -118.359106)
			(xy 299.601704 -118.401486) (xy 299.638191 -118.449036) (xy 299.668158 -118.500942) (xy 299.691094 -118.556315)
			(xy 299.706607 -118.614208) (xy 299.71443 -118.67363) (xy 299.71492 -118.703598) (xy 299.71492 -119.567198)
			(xy 299.71443 -119.597166) (xy 299.706607 -119.656588) (xy 299.691094 -119.714481) (xy 299.668158 -119.769854)
			(xy 299.638191 -119.82176) (xy 299.601704 -119.86931) (xy 299.559324 -119.91169) (xy 299.511774 -119.948177)
			(xy 299.459868 -119.978144) (xy 299.404495 -120.00108) (xy 299.346602 -120.016593) (xy 299.28718 -120.024416)
			(xy 299.227244 -120.024416) (xy 299.167822 -120.016593) (xy 299.109929 -120.00108) (xy 299.054556 -119.978144)
			(xy 299.00265 -119.948177) (xy 298.9551 -119.91169) (xy 298.91272 -119.86931) (xy 298.876233 -119.82176)
			(xy 298.846266 -119.769854) (xy 298.82333 -119.714481) (xy 298.807817 -119.656588) (xy 298.799994 -119.597166)
			(xy 298.799504 -119.567198) (xy 295.47885 -119.567198) (xy 295.425622 -120.008142) (xy 295.331642 -120.786652)
			(xy 295.301162 -121.041414) (xy 295.300908 -121.04497) (xy 295.283798 -121.367296) (xy 296.945304 -121.367296)
			(xy 296.945304 -120.503696) (xy 296.945794 -120.473728) (xy 296.953617 -120.414306) (xy 296.96913 -120.356413)
			(xy 296.992066 -120.30104) (xy 297.022033 -120.249134) (xy 297.05852 -120.201584) (xy 297.1009 -120.159204)
			(xy 297.14845 -120.122717) (xy 297.200356 -120.09275) (xy 297.255729 -120.069814) (xy 297.313622 -120.054301)
			(xy 297.373044 -120.046478) (xy 297.43298 -120.046478) (xy 297.492402 -120.054301) (xy 297.550295 -120.069814)
			(xy 297.605668 -120.09275) (xy 297.657574 -120.122717) (xy 297.705124 -120.159204) (xy 297.747504 -120.201584)
			(xy 297.783991 -120.249134) (xy 297.813958 -120.30104) (xy 297.836894 -120.356413) (xy 297.852407 -120.414306)
			(xy 297.86023 -120.473728) (xy 297.86072 -120.503696) (xy 297.86072 -121.367296) (xy 297.86023 -121.397264)
			(xy 297.852407 -121.456686) (xy 297.836894 -121.514579) (xy 297.813958 -121.569952) (xy 297.783991 -121.621858)
			(xy 297.747504 -121.669408) (xy 297.705124 -121.711788) (xy 297.657574 -121.748275) (xy 297.605668 -121.778242)
			(xy 297.550295 -121.801178) (xy 297.492402 -121.816691) (xy 297.43298 -121.824514) (xy 297.373044 -121.824514)
			(xy 297.313622 -121.816691) (xy 297.255729 -121.801178) (xy 297.200356 -121.778242) (xy 297.14845 -121.748275)
			(xy 297.1009 -121.711788) (xy 297.05852 -121.669408) (xy 297.022033 -121.621858) (xy 296.992066 -121.569952)
			(xy 296.96913 -121.514579) (xy 296.953617 -121.456686) (xy 296.945794 -121.397264) (xy 296.945304 -121.367296)
			(xy 295.283798 -121.367296) (xy 295.188257 -123.16714) (xy 298.799504 -123.16714) (xy 298.799504 -122.30354)
			(xy 298.799994 -122.273572) (xy 298.807817 -122.21415) (xy 298.82333 -122.156257) (xy 298.846266 -122.100884)
			(xy 298.876233 -122.048978) (xy 298.91272 -122.001428) (xy 298.9551 -121.959048) (xy 299.00265 -121.922561)
			(xy 299.054556 -121.892594) (xy 299.109929 -121.869658) (xy 299.167822 -121.854145) (xy 299.227244 -121.846322)
			(xy 299.28718 -121.846322) (xy 299.346602 -121.854145) (xy 299.404495 -121.869658) (xy 299.459868 -121.892594)
			(xy 299.511774 -121.922561) (xy 299.559324 -121.959048) (xy 299.601704 -122.001428) (xy 299.638191 -122.048978)
			(xy 299.668158 -122.100884) (xy 299.691094 -122.156257) (xy 299.706607 -122.21415) (xy 299.71443 -122.273572)
			(xy 299.71492 -122.30354) (xy 299.71492 -123.16714) (xy 299.71443 -123.197108) (xy 299.706607 -123.25653)
			(xy 299.691094 -123.314423) (xy 299.668158 -123.369796) (xy 299.638191 -123.421702) (xy 299.601704 -123.469252)
			(xy 299.559324 -123.511632) (xy 299.511774 -123.548119) (xy 299.459868 -123.578086) (xy 299.404495 -123.601022)
			(xy 299.346602 -123.616535) (xy 299.28718 -123.624358) (xy 299.227244 -123.624358) (xy 299.167822 -123.616535)
			(xy 299.109929 -123.601022) (xy 299.054556 -123.578086) (xy 299.00265 -123.548119) (xy 298.9551 -123.511632)
			(xy 298.91272 -123.469252) (xy 298.876233 -123.421702) (xy 298.846266 -123.369796) (xy 298.82333 -123.314423)
			(xy 298.807817 -123.25653) (xy 298.799994 -123.197108) (xy 298.799504 -123.16714) (xy 295.188257 -123.16714)
			(xy 295.168828 -123.533154) (xy 295.092906 -124.967238) (xy 296.945304 -124.967238) (xy 296.945304 -124.103638)
			(xy 296.945794 -124.07367) (xy 296.953617 -124.014248) (xy 296.96913 -123.956355) (xy 296.992066 -123.900982)
			(xy 297.022033 -123.849076) (xy 297.05852 -123.801526) (xy 297.1009 -123.759146) (xy 297.14845 -123.722659)
			(xy 297.200356 -123.692692) (xy 297.255729 -123.669756) (xy 297.313622 -123.654243) (xy 297.373044 -123.64642)
			(xy 297.43298 -123.64642) (xy 297.492402 -123.654243) (xy 297.550295 -123.669756) (xy 297.605668 -123.692692)
			(xy 297.657574 -123.722659) (xy 297.705124 -123.759146) (xy 297.747504 -123.801526) (xy 297.783991 -123.849076)
			(xy 297.813958 -123.900982) (xy 297.836894 -123.956355) (xy 297.852407 -124.014248) (xy 297.86023 -124.07367)
			(xy 297.86072 -124.103638) (xy 297.86072 -124.967238) (xy 297.86023 -124.997206) (xy 297.852407 -125.056628)
			(xy 297.836894 -125.114521) (xy 297.813958 -125.169894) (xy 297.783991 -125.2218) (xy 297.747504 -125.26935)
			(xy 297.705124 -125.31173) (xy 297.657574 -125.348217) (xy 297.605668 -125.378184) (xy 297.550295 -125.40112)
			(xy 297.492402 -125.416633) (xy 297.43298 -125.424456) (xy 297.373044 -125.424456) (xy 297.313622 -125.416633)
			(xy 297.255729 -125.40112) (xy 297.200356 -125.378184) (xy 297.14845 -125.348217) (xy 297.1009 -125.31173)
			(xy 297.05852 -125.26935) (xy 297.022033 -125.2218) (xy 296.992066 -125.169894) (xy 296.96913 -125.114521)
			(xy 296.953617 -125.056628) (xy 296.945794 -124.997206) (xy 296.945304 -124.967238) (xy 295.092906 -124.967238)
			(xy 294.785319 -130.777234) (xy 298.799504 -130.777234) (xy 298.799504 -129.913634) (xy 298.799994 -129.883666)
			(xy 298.807817 -129.824244) (xy 298.82333 -129.766351) (xy 298.846266 -129.710978) (xy 298.876233 -129.659072)
			(xy 298.91272 -129.611522) (xy 298.9551 -129.569142) (xy 299.00265 -129.532655) (xy 299.054556 -129.502688)
			(xy 299.109929 -129.479752) (xy 299.167822 -129.464239) (xy 299.227244 -129.456416) (xy 299.28718 -129.456416)
			(xy 299.346602 -129.464239) (xy 299.404495 -129.479752) (xy 299.459868 -129.502688) (xy 299.511774 -129.532655)
			(xy 299.559324 -129.569142) (xy 299.601704 -129.611522) (xy 299.638191 -129.659072) (xy 299.668158 -129.710978)
			(xy 299.691094 -129.766351) (xy 299.706607 -129.824244) (xy 299.71443 -129.883666) (xy 299.71492 -129.913634)
			(xy 299.71492 -130.777234) (xy 299.71443 -130.807202) (xy 299.706607 -130.866624) (xy 299.691094 -130.924517)
			(xy 299.668158 -130.97989) (xy 299.638191 -131.031796) (xy 299.601704 -131.079346) (xy 299.559324 -131.121726)
			(xy 299.511774 -131.158213) (xy 299.459868 -131.18818) (xy 299.404495 -131.211116) (xy 299.346602 -131.226629)
			(xy 299.28718 -131.234452) (xy 299.227244 -131.234452) (xy 299.167822 -131.226629) (xy 299.109929 -131.211116)
			(xy 299.054556 -131.18818) (xy 299.00265 -131.158213) (xy 298.9551 -131.121726) (xy 298.91272 -131.079346)
			(xy 298.876233 -131.031796) (xy 298.846266 -130.97989) (xy 298.82333 -130.924517) (xy 298.807817 -130.866624)
			(xy 298.799994 -130.807202) (xy 298.799504 -130.777234) (xy 294.785319 -130.777234) (xy 294.745664 -131.52628)
			(xy 294.690057 -132.577332) (xy 296.945304 -132.577332) (xy 296.945304 -131.713732) (xy 296.945794 -131.683764)
			(xy 296.953617 -131.624342) (xy 296.96913 -131.566449) (xy 296.992066 -131.511076) (xy 297.022033 -131.45917)
			(xy 297.05852 -131.41162) (xy 297.1009 -131.36924) (xy 297.14845 -131.332753) (xy 297.200356 -131.302786)
			(xy 297.255729 -131.27985) (xy 297.313622 -131.264337) (xy 297.373044 -131.256514) (xy 297.43298 -131.256514)
			(xy 297.492402 -131.264337) (xy 297.550295 -131.27985) (xy 297.605668 -131.302786) (xy 297.657574 -131.332753)
			(xy 297.705124 -131.36924) (xy 297.747504 -131.41162) (xy 297.783991 -131.45917) (xy 297.813958 -131.511076)
			(xy 297.836894 -131.566449) (xy 297.852407 -131.624342) (xy 297.86023 -131.683764) (xy 297.86072 -131.713732)
			(xy 297.86072 -132.577332) (xy 297.86023 -132.6073) (xy 297.852407 -132.666722) (xy 297.836894 -132.724615)
			(xy 297.813958 -132.779988) (xy 297.783991 -132.831894) (xy 297.747504 -132.879444) (xy 297.705124 -132.921824)
			(xy 297.657574 -132.958311) (xy 297.605668 -132.988278) (xy 297.550295 -133.011214) (xy 297.492402 -133.026727)
			(xy 297.43298 -133.03455) (xy 297.373044 -133.03455) (xy 297.313622 -133.026727) (xy 297.255729 -133.011214)
			(xy 297.200356 -132.988278) (xy 297.14845 -132.958311) (xy 297.1009 -132.921824) (xy 297.05852 -132.879444)
			(xy 297.022033 -132.831894) (xy 296.992066 -132.779988) (xy 296.96913 -132.724615) (xy 296.953617 -132.666722)
			(xy 296.945794 -132.6073) (xy 296.945304 -132.577332) (xy 294.690057 -132.577332) (xy 294.594834 -134.377176)
			(xy 298.799504 -134.377176) (xy 298.799504 -133.513576) (xy 298.799994 -133.483608) (xy 298.807817 -133.424186)
			(xy 298.82333 -133.366293) (xy 298.846266 -133.31092) (xy 298.876233 -133.259014) (xy 298.91272 -133.211464)
			(xy 298.9551 -133.169084) (xy 299.00265 -133.132597) (xy 299.054556 -133.10263) (xy 299.109929 -133.079694)
			(xy 299.167822 -133.064181) (xy 299.227244 -133.056358) (xy 299.28718 -133.056358) (xy 299.346602 -133.064181)
			(xy 299.404495 -133.079694) (xy 299.459868 -133.10263) (xy 299.511774 -133.132597) (xy 299.559324 -133.169084)
			(xy 299.601704 -133.211464) (xy 299.638191 -133.259014) (xy 299.668158 -133.31092) (xy 299.691094 -133.366293)
			(xy 299.706607 -133.424186) (xy 299.71443 -133.483608) (xy 299.71492 -133.513576) (xy 299.71492 -134.377176)
			(xy 299.71443 -134.407144) (xy 299.706607 -134.466566) (xy 299.691094 -134.524459) (xy 299.668158 -134.579832)
			(xy 299.638191 -134.631738) (xy 299.601704 -134.679288) (xy 299.559324 -134.721668) (xy 299.511774 -134.758155)
			(xy 299.459868 -134.788122) (xy 299.404495 -134.811058) (xy 299.346602 -134.826571) (xy 299.28718 -134.834394)
			(xy 299.227244 -134.834394) (xy 299.167822 -134.826571) (xy 299.109929 -134.811058) (xy 299.054556 -134.788122)
			(xy 299.00265 -134.758155) (xy 298.9551 -134.721668) (xy 298.91272 -134.679288) (xy 298.876233 -134.631738)
			(xy 298.846266 -134.579832) (xy 298.82333 -134.524459) (xy 298.807817 -134.466566) (xy 298.799994 -134.407144)
			(xy 298.799504 -134.377176) (xy 294.594834 -134.377176) (xy 294.499597 -136.177274) (xy 296.945304 -136.177274)
			(xy 296.945304 -135.313674) (xy 296.945794 -135.283706) (xy 296.953617 -135.224284) (xy 296.96913 -135.166391)
			(xy 296.992066 -135.111018) (xy 297.022033 -135.059112) (xy 297.05852 -135.011562) (xy 297.1009 -134.969182)
			(xy 297.14845 -134.932695) (xy 297.200356 -134.902728) (xy 297.255729 -134.879792) (xy 297.313622 -134.864279)
			(xy 297.373044 -134.856456) (xy 297.43298 -134.856456) (xy 297.492402 -134.864279) (xy 297.550295 -134.879792)
			(xy 297.605668 -134.902728) (xy 297.657574 -134.932695) (xy 297.705124 -134.969182) (xy 297.747504 -135.011562)
			(xy 297.783991 -135.059112) (xy 297.813958 -135.111018) (xy 297.836894 -135.166391) (xy 297.852407 -135.224284)
			(xy 297.86023 -135.283706) (xy 297.86072 -135.313674) (xy 297.86072 -136.177274) (xy 297.86023 -136.207242)
			(xy 297.852407 -136.266664) (xy 297.836894 -136.324557) (xy 297.813958 -136.37993) (xy 297.783991 -136.431836)
			(xy 297.747504 -136.479386) (xy 297.705124 -136.521766) (xy 297.657574 -136.558253) (xy 297.605668 -136.58822)
			(xy 297.550295 -136.611156) (xy 297.492402 -136.626669) (xy 297.43298 -136.634492) (xy 297.373044 -136.634492)
			(xy 297.313622 -136.626669) (xy 297.255729 -136.611156) (xy 297.200356 -136.58822) (xy 297.14845 -136.558253)
			(xy 297.1009 -136.521766) (xy 297.05852 -136.479386) (xy 297.022033 -136.431836) (xy 296.992066 -136.37993)
			(xy 296.96913 -136.324557) (xy 296.953617 -136.266664) (xy 296.945794 -136.207242) (xy 296.945304 -136.177274)
			(xy 294.499597 -136.177274) (xy 294.4368 -137.364216) (xy 294.437395 -137.373464) (xy 294.444302 -137.390646)
			(xy 294.450262 -137.397744) (xy 294.499538 -137.451084) (xy 294.503034 -137.454774) (xy 294.511228 -137.460789)
			(xy 294.515794 -137.463022) (xy 294.524684 -137.467086) (xy 294.524938 -137.467086) (xy 294.535098 -137.46734)
			(xy 294.56172 -137.468747) (xy 294.614217 -137.478025) (xy 294.664912 -137.494516) (xy 294.712821 -137.5179)
			(xy 294.75701 -137.547721) (xy 294.79662 -137.5834) (xy 294.830882 -137.624243) (xy 294.859129 -137.669455)
			(xy 294.880811 -137.718157) (xy 294.895507 -137.769402) (xy 294.902931 -137.822193) (xy 294.903398 -137.848848)
			(xy 294.902908 -137.876097) (xy 294.895146 -137.930039) (xy 294.879787 -137.982327) (xy 294.857143 -138.031897)
			(xy 294.827675 -138.077741) (xy 294.791984 -138.118925) (xy 294.750795 -138.15461) (xy 294.704947 -138.184071)
			(xy 294.655373 -138.206707) (xy 294.603082 -138.222059) (xy 294.549139 -138.229813) (xy 294.52189 -138.230356)
			(xy 294.494712 -138.22934) (xy 294.479522 -138.228735) (xy 294.449908 -138.235549) (xy 294.423621 -138.250795)
			(xy 294.412924 -138.261598) (xy 294.402548 -138.27368) (xy 294.389095 -138.302526) (xy 294.386508 -138.31824)
			(xy 294.385746 -138.330686) (xy 294.385238 -138.336528) (xy 294.382698 -138.383264) (xy 294.382698 -138.388598)
			(xy 294.384022 -138.40396) (xy 294.394706 -138.432868) (xy 294.413524 -138.457274) (xy 294.438764 -138.474959)
			(xy 294.468129 -138.484312) (xy 294.483536 -138.484864) (xy 294.4876 -138.484864) (xy 294.489886 -138.48461)
			(xy 294.518334 -138.48334) (xy 294.526716 -138.48334) (xy 294.553741 -138.484152) (xy 294.607166 -138.492461)
			(xy 294.658883 -138.50823) (xy 294.707855 -138.531142) (xy 294.753101 -138.560739) (xy 294.793715 -138.596429)
			(xy 294.828884 -138.637495) (xy 294.857902 -138.683115) (xy 294.880188 -138.732375) (xy 294.895296 -138.784288)
			(xy 294.902923 -138.837814) (xy 294.903398 -138.864848) (xy 294.902908 -138.892097) (xy 294.895146 -138.946039)
			(xy 294.879787 -138.998327) (xy 294.857143 -139.047897) (xy 294.827675 -139.093741) (xy 294.791984 -139.134925)
			(xy 294.750795 -139.17061) (xy 294.704947 -139.200071) (xy 294.655373 -139.222707) (xy 294.603082 -139.238059)
			(xy 294.549139 -139.245813) (xy 294.52189 -139.246356) (xy 294.521128 -139.246356) (xy 294.503432 -139.246145)
			(xy 294.468196 -139.242839) (xy 294.45077 -139.239752) (xy 294.449246 -139.239498) (xy 294.435914 -139.237886)
			(xy 294.409243 -139.240926) (xy 294.384294 -139.250837) (xy 294.3733 -139.258548) (xy 294.372792 -139.258548)
			(xy 294.362368 -139.266922) (xy 294.345959 -139.288022) (xy 294.335611 -139.312667) (xy 294.333422 -139.325858)
			(xy 294.333168 -139.330176) (xy 294.267777 -140.565451) (xy 295.630578 -140.565451) (xy 295.630578 -140.510949)
			(xy 295.638334 -140.457001) (xy 295.653689 -140.404706) (xy 295.676331 -140.355129) (xy 295.705797 -140.309279)
			(xy 295.741488 -140.268088) (xy 295.782679 -140.232397) (xy 295.828529 -140.202931) (xy 295.878106 -140.180289)
			(xy 295.930401 -140.164934) (xy 295.984349 -140.157178) (xy 296.0116 -140.156692) (xy 296.03897 -140.15716)
			(xy 296.093149 -140.164978) (xy 296.145652 -140.180466) (xy 296.195399 -140.203308) (xy 296.241366 -140.233031)
			(xy 296.262298 -140.250672) (xy 296.262552 -140.250926) (xy 296.269646 -140.256502) (xy 296.286557 -140.262754)
			(xy 296.295572 -140.263118) (xy 296.362628 -140.263118) (xy 296.371646 -140.262771) (xy 296.388563 -140.256516)
			(xy 296.395648 -140.250926) (xy 296.395648 -140.250672) (xy 296.395902 -140.250672) (xy 296.416819 -140.233014)
			(xy 296.462796 -140.203306) (xy 296.512548 -140.180474) (xy 296.565052 -140.164987) (xy 296.61923 -140.157164)
			(xy 296.6466 -140.156692) (xy 296.673851 -140.157178) (xy 296.727799 -140.164934) (xy 296.780094 -140.180289)
			(xy 296.829671 -140.202931) (xy 296.875521 -140.232397) (xy 296.916712 -140.268088) (xy 296.952403 -140.309279)
			(xy 296.981869 -140.355129) (xy 297.004511 -140.404706) (xy 297.019866 -140.457001) (xy 297.027622 -140.510949)
			(xy 297.027622 -140.565451) (xy 297.019866 -140.619399) (xy 297.004511 -140.671694) (xy 296.981869 -140.721271)
			(xy 296.952403 -140.767121) (xy 296.916712 -140.808312) (xy 296.875521 -140.844003) (xy 296.829671 -140.873469)
			(xy 296.780094 -140.896111) (xy 296.727799 -140.911466) (xy 296.673851 -140.919222) (xy 296.6466 -140.919708)
			(xy 296.61923 -140.91924) (xy 296.565051 -140.911422) (xy 296.512548 -140.895934) (xy 296.462801 -140.873092)
			(xy 296.416834 -140.843369) (xy 296.395902 -140.825728) (xy 296.395648 -140.825474) (xy 296.388554 -140.819898)
			(xy 296.371643 -140.813646) (xy 296.362628 -140.813282) (xy 296.295572 -140.813282) (xy 296.286554 -140.813629)
			(xy 296.269637 -140.819884) (xy 296.262552 -140.825474) (xy 296.262552 -140.825728) (xy 296.262298 -140.825728)
			(xy 296.241381 -140.843386) (xy 296.195404 -140.873094) (xy 296.145652 -140.895926) (xy 296.093148 -140.911413)
			(xy 296.03897 -140.919236) (xy 296.0116 -140.919708) (xy 295.984349 -140.919222) (xy 295.930401 -140.911466)
			(xy 295.878106 -140.896111) (xy 295.828529 -140.873469) (xy 295.782679 -140.844003) (xy 295.741488 -140.808312)
			(xy 295.705797 -140.767121) (xy 295.676331 -140.721271) (xy 295.653689 -140.671694) (xy 295.638334 -140.619399)
			(xy 295.630578 -140.565451) (xy 294.267777 -140.565451) (xy 294.113112 -143.48714) (xy 298.799504 -143.48714)
			(xy 298.799504 -142.62354) (xy 298.799994 -142.593572) (xy 298.807817 -142.53415) (xy 298.82333 -142.476257)
			(xy 298.846266 -142.420884) (xy 298.876233 -142.368978) (xy 298.91272 -142.321428) (xy 298.9551 -142.279048)
			(xy 299.00265 -142.242561) (xy 299.054556 -142.212594) (xy 299.109929 -142.189658) (xy 299.167822 -142.174145)
			(xy 299.227244 -142.166322) (xy 299.28718 -142.166322) (xy 299.346602 -142.174145) (xy 299.404495 -142.189658)
			(xy 299.459868 -142.212594) (xy 299.511774 -142.242561) (xy 299.559324 -142.279048) (xy 299.601704 -142.321428)
			(xy 299.638191 -142.368978) (xy 299.668158 -142.420884) (xy 299.691094 -142.476257) (xy 299.706607 -142.53415)
			(xy 299.71443 -142.593572) (xy 299.71492 -142.62354) (xy 299.71492 -143.48714) (xy 299.71443 -143.517108)
			(xy 299.706607 -143.57653) (xy 299.691094 -143.634423) (xy 299.668158 -143.689796) (xy 299.638191 -143.741702)
			(xy 299.601704 -143.789252) (xy 299.559324 -143.831632) (xy 299.511774 -143.868119) (xy 299.459868 -143.898086)
			(xy 299.404495 -143.921022) (xy 299.346602 -143.936535) (xy 299.28718 -143.944358) (xy 299.227244 -143.944358)
			(xy 299.167822 -143.936535) (xy 299.109929 -143.921022) (xy 299.054556 -143.898086) (xy 299.00265 -143.868119)
			(xy 298.9551 -143.831632) (xy 298.91272 -143.789252) (xy 298.876233 -143.741702) (xy 298.846266 -143.689796)
			(xy 298.82333 -143.634423) (xy 298.807817 -143.57653) (xy 298.799994 -143.517108) (xy 298.799504 -143.48714)
			(xy 294.113112 -143.48714) (xy 294.017821 -145.287238) (xy 296.945304 -145.287238) (xy 296.945304 -144.423638)
			(xy 296.945794 -144.39367) (xy 296.953617 -144.334248) (xy 296.96913 -144.276355) (xy 296.992066 -144.220982)
			(xy 297.022033 -144.169076) (xy 297.05852 -144.121526) (xy 297.1009 -144.079146) (xy 297.14845 -144.042659)
			(xy 297.200356 -144.012692) (xy 297.255729 -143.989756) (xy 297.313622 -143.974243) (xy 297.373044 -143.96642)
			(xy 297.43298 -143.96642) (xy 297.492402 -143.974243) (xy 297.550295 -143.989756) (xy 297.605668 -144.012692)
			(xy 297.657574 -144.042659) (xy 297.705124 -144.079146) (xy 297.747504 -144.121526) (xy 297.783991 -144.169076)
			(xy 297.813958 -144.220982) (xy 297.836894 -144.276355) (xy 297.852407 -144.334248) (xy 297.86023 -144.39367)
			(xy 297.86072 -144.423638) (xy 297.86072 -145.287238) (xy 297.86023 -145.317206) (xy 297.852407 -145.376628)
			(xy 297.836894 -145.434521) (xy 297.813958 -145.489894) (xy 297.783991 -145.5418) (xy 297.747504 -145.58935)
			(xy 297.705124 -145.63173) (xy 297.657574 -145.668217) (xy 297.605668 -145.698184) (xy 297.550295 -145.72112)
			(xy 297.492402 -145.736633) (xy 297.43298 -145.744456) (xy 297.373044 -145.744456) (xy 297.313622 -145.736633)
			(xy 297.255729 -145.72112) (xy 297.200356 -145.698184) (xy 297.14845 -145.668217) (xy 297.1009 -145.63173)
			(xy 297.05852 -145.58935) (xy 297.022033 -145.5418) (xy 296.992066 -145.489894) (xy 296.96913 -145.434521)
			(xy 296.953617 -145.376628) (xy 296.945794 -145.317206) (xy 296.945304 -145.287238) (xy 294.017821 -145.287238)
			(xy 293.922529 -147.087336) (xy 298.799504 -147.087336) (xy 298.799504 -146.223736) (xy 298.799994 -146.193768)
			(xy 298.807817 -146.134346) (xy 298.82333 -146.076453) (xy 298.846266 -146.02108) (xy 298.876233 -145.969174)
			(xy 298.91272 -145.921624) (xy 298.9551 -145.879244) (xy 299.00265 -145.842757) (xy 299.054556 -145.81279)
			(xy 299.109929 -145.789854) (xy 299.167822 -145.774341) (xy 299.227244 -145.766518) (xy 299.28718 -145.766518)
			(xy 299.346602 -145.774341) (xy 299.404495 -145.789854) (xy 299.459868 -145.81279) (xy 299.511774 -145.842757)
			(xy 299.559324 -145.879244) (xy 299.601704 -145.921624) (xy 299.638191 -145.969174) (xy 299.668158 -146.02108)
			(xy 299.691094 -146.076453) (xy 299.706607 -146.134346) (xy 299.71443 -146.193768) (xy 299.71492 -146.223736)
			(xy 299.71492 -147.087336) (xy 299.71443 -147.117304) (xy 299.706607 -147.176726) (xy 299.691094 -147.234619)
			(xy 299.668158 -147.289992) (xy 299.638191 -147.341898) (xy 299.601704 -147.389448) (xy 299.559324 -147.431828)
			(xy 299.511774 -147.468315) (xy 299.459868 -147.498282) (xy 299.404495 -147.521218) (xy 299.346602 -147.536731)
			(xy 299.28718 -147.544554) (xy 299.227244 -147.544554) (xy 299.167822 -147.536731) (xy 299.109929 -147.521218)
			(xy 299.054556 -147.498282) (xy 299.00265 -147.468315) (xy 298.9551 -147.431828) (xy 298.91272 -147.389448)
			(xy 298.876233 -147.341898) (xy 298.846266 -147.289992) (xy 298.82333 -147.234619) (xy 298.807817 -147.176726)
			(xy 298.799994 -147.117304) (xy 298.799504 -147.087336) (xy 293.922529 -147.087336) (xy 293.827238 -148.887434)
			(xy 296.945304 -148.887434) (xy 296.945304 -148.023834) (xy 296.945794 -147.993866) (xy 296.953617 -147.934444)
			(xy 296.96913 -147.876551) (xy 296.992066 -147.821178) (xy 297.022033 -147.769272) (xy 297.05852 -147.721722)
			(xy 297.1009 -147.679342) (xy 297.14845 -147.642855) (xy 297.200356 -147.612888) (xy 297.255729 -147.589952)
			(xy 297.313622 -147.574439) (xy 297.373044 -147.566616) (xy 297.43298 -147.566616) (xy 297.492402 -147.574439)
			(xy 297.550295 -147.589952) (xy 297.605668 -147.612888) (xy 297.657574 -147.642855) (xy 297.705124 -147.679342)
			(xy 297.747504 -147.721722) (xy 297.783991 -147.769272) (xy 297.813958 -147.821178) (xy 297.836894 -147.876551)
			(xy 297.852407 -147.934444) (xy 297.86023 -147.993866) (xy 297.86072 -148.023834) (xy 297.86072 -148.887434)
			(xy 297.86023 -148.917402) (xy 297.852407 -148.976824) (xy 297.836894 -149.034717) (xy 297.813958 -149.09009)
			(xy 297.783991 -149.141996) (xy 297.747504 -149.189546) (xy 297.705124 -149.231926) (xy 297.657574 -149.268413)
			(xy 297.605668 -149.29838) (xy 297.550295 -149.321316) (xy 297.492402 -149.336829) (xy 297.43298 -149.344652)
			(xy 297.373044 -149.344652) (xy 297.313622 -149.336829) (xy 297.255729 -149.321316) (xy 297.200356 -149.29838)
			(xy 297.14845 -149.268413) (xy 297.1009 -149.231926) (xy 297.05852 -149.189546) (xy 297.022033 -149.141996)
			(xy 296.992066 -149.09009) (xy 296.96913 -149.034717) (xy 296.953617 -148.976824) (xy 296.945794 -148.917402)
			(xy 296.945304 -148.887434) (xy 293.827238 -148.887434) (xy 293.73196 -150.687278) (xy 298.799504 -150.687278)
			(xy 298.799504 -149.823678) (xy 298.799994 -149.79371) (xy 298.807817 -149.734288) (xy 298.82333 -149.676395)
			(xy 298.846266 -149.621022) (xy 298.876233 -149.569116) (xy 298.91272 -149.521566) (xy 298.9551 -149.479186)
			(xy 299.00265 -149.442699) (xy 299.054556 -149.412732) (xy 299.109929 -149.389796) (xy 299.167822 -149.374283)
			(xy 299.227244 -149.36646) (xy 299.28718 -149.36646) (xy 299.346602 -149.374283) (xy 299.404495 -149.389796)
			(xy 299.459868 -149.412732) (xy 299.511774 -149.442699) (xy 299.559324 -149.479186) (xy 299.601704 -149.521566)
			(xy 299.638191 -149.569116) (xy 299.668158 -149.621022) (xy 299.691094 -149.676395) (xy 299.706607 -149.734288)
			(xy 299.71443 -149.79371) (xy 299.71492 -149.823678) (xy 299.71492 -150.687278) (xy 299.71443 -150.717246)
			(xy 299.706607 -150.776668) (xy 299.691094 -150.834561) (xy 299.668158 -150.889934) (xy 299.638191 -150.94184)
			(xy 299.601704 -150.98939) (xy 299.559324 -151.03177) (xy 299.511774 -151.068257) (xy 299.459868 -151.098224)
			(xy 299.404495 -151.12116) (xy 299.346602 -151.136673) (xy 299.28718 -151.144496) (xy 299.227244 -151.144496)
			(xy 299.167822 -151.136673) (xy 299.109929 -151.12116) (xy 299.054556 -151.098224) (xy 299.00265 -151.068257)
			(xy 298.9551 -151.03177) (xy 298.91272 -150.98939) (xy 298.876233 -150.94184) (xy 298.846266 -150.889934)
			(xy 298.82333 -150.834561) (xy 298.807817 -150.776668) (xy 298.799994 -150.717246) (xy 298.799504 -150.687278)
			(xy 293.73196 -150.687278) (xy 293.636669 -152.487376) (xy 296.945304 -152.487376) (xy 296.945304 -151.623776)
			(xy 296.945794 -151.593808) (xy 296.953617 -151.534386) (xy 296.96913 -151.476493) (xy 296.992066 -151.42112)
			(xy 297.022033 -151.369214) (xy 297.05852 -151.321664) (xy 297.1009 -151.279284) (xy 297.14845 -151.242797)
			(xy 297.200356 -151.21283) (xy 297.255729 -151.189894) (xy 297.313622 -151.174381) (xy 297.373044 -151.166558)
			(xy 297.43298 -151.166558) (xy 297.492402 -151.174381) (xy 297.550295 -151.189894) (xy 297.605668 -151.21283)
			(xy 297.657574 -151.242797) (xy 297.705124 -151.279284) (xy 297.747504 -151.321664) (xy 297.783991 -151.369214)
			(xy 297.813958 -151.42112) (xy 297.836894 -151.476493) (xy 297.852407 -151.534386) (xy 297.86023 -151.593808)
			(xy 297.86072 -151.623776) (xy 297.86072 -152.487376) (xy 297.86023 -152.517344) (xy 297.852407 -152.576766)
			(xy 297.836894 -152.634659) (xy 297.813958 -152.690032) (xy 297.783991 -152.741938) (xy 297.747504 -152.789488)
			(xy 297.705124 -152.831868) (xy 297.657574 -152.868355) (xy 297.605668 -152.898322) (xy 297.550295 -152.921258)
			(xy 297.492402 -152.936771) (xy 297.43298 -152.944594) (xy 297.373044 -152.944594) (xy 297.313622 -152.936771)
			(xy 297.255729 -152.921258) (xy 297.200356 -152.898322) (xy 297.14845 -152.868355) (xy 297.1009 -152.831868)
			(xy 297.05852 -152.789488) (xy 297.022033 -152.741938) (xy 296.992066 -152.690032) (xy 296.96913 -152.634659)
			(xy 296.953617 -152.576766) (xy 296.945794 -152.517344) (xy 296.945304 -152.487376) (xy 293.636669 -152.487376)
			(xy 293.541391 -154.28722) (xy 298.799504 -154.28722) (xy 298.799504 -153.42362) (xy 298.799994 -153.393652)
			(xy 298.807817 -153.33423) (xy 298.82333 -153.276337) (xy 298.846266 -153.220964) (xy 298.876233 -153.169058)
			(xy 298.91272 -153.121508) (xy 298.9551 -153.079128) (xy 299.00265 -153.042641) (xy 299.054556 -153.012674)
			(xy 299.109929 -152.989738) (xy 299.167822 -152.974225) (xy 299.227244 -152.966402) (xy 299.28718 -152.966402)
			(xy 299.346602 -152.974225) (xy 299.404495 -152.989738) (xy 299.459868 -153.012674) (xy 299.511774 -153.042641)
			(xy 299.559324 -153.079128) (xy 299.601704 -153.121508) (xy 299.638191 -153.169058) (xy 299.668158 -153.220964)
			(xy 299.691094 -153.276337) (xy 299.706607 -153.33423) (xy 299.71443 -153.393652) (xy 299.71492 -153.42362)
			(xy 299.71492 -154.28722) (xy 299.71443 -154.317188) (xy 299.706607 -154.37661) (xy 299.691094 -154.434503)
			(xy 299.668158 -154.489876) (xy 299.638191 -154.541782) (xy 299.601704 -154.589332) (xy 299.559324 -154.631712)
			(xy 299.511774 -154.668199) (xy 299.459868 -154.698166) (xy 299.404495 -154.721102) (xy 299.346602 -154.736615)
			(xy 299.28718 -154.744438) (xy 299.227244 -154.744438) (xy 299.167822 -154.736615) (xy 299.109929 -154.721102)
			(xy 299.054556 -154.698166) (xy 299.00265 -154.668199) (xy 298.9551 -154.631712) (xy 298.91272 -154.589332)
			(xy 298.876233 -154.541782) (xy 298.846266 -154.489876) (xy 298.82333 -154.434503) (xy 298.807817 -154.37661)
			(xy 298.799994 -154.317188) (xy 298.799504 -154.28722) (xy 293.541391 -154.28722) (xy 293.4461 -156.087318)
			(xy 296.945304 -156.087318) (xy 296.945304 -155.223718) (xy 296.945794 -155.19375) (xy 296.953617 -155.134328)
			(xy 296.96913 -155.076435) (xy 296.992066 -155.021062) (xy 297.022033 -154.969156) (xy 297.05852 -154.921606)
			(xy 297.1009 -154.879226) (xy 297.14845 -154.842739) (xy 297.200356 -154.812772) (xy 297.255729 -154.789836)
			(xy 297.313622 -154.774323) (xy 297.373044 -154.7665) (xy 297.43298 -154.7665) (xy 297.492402 -154.774323)
			(xy 297.550295 -154.789836) (xy 297.605668 -154.812772) (xy 297.657574 -154.842739) (xy 297.705124 -154.879226)
			(xy 297.747504 -154.921606) (xy 297.783991 -154.969156) (xy 297.813958 -155.021062) (xy 297.836894 -155.076435)
			(xy 297.852407 -155.134328) (xy 297.86023 -155.19375) (xy 297.86072 -155.223718) (xy 297.86072 -156.087318)
			(xy 297.86023 -156.117286) (xy 297.852407 -156.176708) (xy 297.836894 -156.234601) (xy 297.813958 -156.289974)
			(xy 297.783991 -156.34188) (xy 297.747504 -156.38943) (xy 297.705124 -156.43181) (xy 297.657574 -156.468297)
			(xy 297.605668 -156.498264) (xy 297.550295 -156.5212) (xy 297.492402 -156.536713) (xy 297.43298 -156.544536)
			(xy 297.373044 -156.544536) (xy 297.313622 -156.536713) (xy 297.255729 -156.5212) (xy 297.200356 -156.498264)
			(xy 297.14845 -156.468297) (xy 297.1009 -156.43181) (xy 297.05852 -156.38943) (xy 297.022033 -156.34188)
			(xy 296.992066 -156.289974) (xy 296.96913 -156.234601) (xy 296.953617 -156.176708) (xy 296.945794 -156.117286)
			(xy 296.945304 -156.087318) (xy 293.4461 -156.087318) (xy 293.395395 -157.045152) (xy 293.610536 -157.045152)
			(xy 293.614607 -156.98953) (xy 293.626733 -156.935093) (xy 293.646656 -156.883002) (xy 293.673952 -156.834367)
			(xy 293.708038 -156.790224) (xy 293.748187 -156.751515) (xy 293.793545 -156.719064) (xy 293.843145 -156.693563)
			(xy 293.895929 -156.675556) (xy 293.950772 -156.665426) (xy 294.006506 -156.663389) (xy 294.061943 -156.669489)
			(xy 294.1159 -156.683595) (xy 294.167229 -156.705407) (xy 294.214835 -156.734461) (xy 294.257703 -156.770136)
			(xy 294.29492 -156.811673) (xy 294.325693 -156.858186) (xy 294.349365 -156.908683) (xy 294.365433 -156.96209)
			(xy 294.373553 -157.017266) (xy 294.374062 -157.045152) (xy 294.626536 -157.045152) (xy 294.630607 -156.98953)
			(xy 294.642733 -156.935093) (xy 294.662656 -156.883002) (xy 294.689952 -156.834367) (xy 294.724038 -156.790224)
			(xy 294.764187 -156.751515) (xy 294.809545 -156.719064) (xy 294.859145 -156.693563) (xy 294.911929 -156.675556)
			(xy 294.966772 -156.665426) (xy 295.022506 -156.663389) (xy 295.077943 -156.669489) (xy 295.1319 -156.683595)
			(xy 295.183229 -156.705407) (xy 295.230835 -156.734461) (xy 295.273703 -156.770136) (xy 295.31092 -156.811673)
			(xy 295.341693 -156.858186) (xy 295.365365 -156.908683) (xy 295.381433 -156.96209) (xy 295.389553 -157.017266)
			(xy 295.390062 -157.045152) (xy 295.389553 -157.073038) (xy 295.381433 -157.128214) (xy 295.365365 -157.181621)
			(xy 295.341693 -157.232118) (xy 295.31092 -157.278631) (xy 295.273703 -157.320168) (xy 295.230835 -157.355843)
			(xy 295.183229 -157.384897) (xy 295.1319 -157.406709) (xy 295.077943 -157.420815) (xy 295.022506 -157.426915)
			(xy 294.966772 -157.424878) (xy 294.911929 -157.414748) (xy 294.859145 -157.396741) (xy 294.809545 -157.37124)
			(xy 294.764187 -157.338789) (xy 294.724038 -157.30008) (xy 294.689952 -157.255937) (xy 294.662656 -157.207302)
			(xy 294.642733 -157.155211) (xy 294.630607 -157.100774) (xy 294.626536 -157.045152) (xy 294.374062 -157.045152)
			(xy 294.373553 -157.073038) (xy 294.365433 -157.128214) (xy 294.349365 -157.181621) (xy 294.325693 -157.232118)
			(xy 294.29492 -157.278631) (xy 294.257703 -157.320168) (xy 294.214835 -157.355843) (xy 294.167229 -157.384897)
			(xy 294.1159 -157.406709) (xy 294.061943 -157.420815) (xy 294.006506 -157.426915) (xy 293.950772 -157.424878)
			(xy 293.895929 -157.414748) (xy 293.843145 -157.396741) (xy 293.793545 -157.37124) (xy 293.748187 -157.338789)
			(xy 293.708038 -157.30008) (xy 293.673952 -157.255937) (xy 293.646656 -157.207302) (xy 293.626733 -157.155211)
			(xy 293.614607 -157.100774) (xy 293.610536 -157.045152) (xy 293.395395 -157.045152) (xy 293.229176 -160.1851)
			(xy 302.088817 -160.1851) (xy 302.092773 -160.093241) (xy 302.10461 -160.002062) (xy 302.124242 -159.912238)
			(xy 302.151523 -159.824435) (xy 302.186251 -159.739302) (xy 302.228169 -159.657469) (xy 302.276967 -159.579542)
			(xy 302.332282 -159.506099) (xy 302.393707 -159.437683) (xy 302.460786 -159.374801) (xy 302.533021 -159.317918)
			(xy 302.60988 -159.267455) (xy 302.690792 -159.223786) (xy 302.775158 -159.187234) (xy 302.862354 -159.15807)
			(xy 302.951735 -159.13651) (xy 303.042638 -159.122714) (xy 303.134391 -159.116782) (xy 303.226313 -159.118761)
			(xy 303.317726 -159.128634) (xy 303.407951 -159.146329) (xy 303.496322 -159.171714) (xy 303.582182 -159.204602)
			(xy 303.664898 -159.24475) (xy 303.743856 -159.291859) (xy 303.818473 -159.345582) (xy 303.888194 -159.40552)
			(xy 303.952505 -159.47123) (xy 304.01093 -159.542226) (xy 304.063035 -159.61798) (xy 304.108434 -159.697934)
			(xy 304.146793 -159.781494) (xy 304.177826 -159.868043) (xy 304.201304 -159.956939) (xy 304.217054 -160.047524)
			(xy 304.224958 -160.139128) (xy 304.225452 -160.1851) (xy 304.224958 -160.231072) (xy 304.217054 -160.322676)
			(xy 304.201304 -160.413261) (xy 304.177826 -160.502157) (xy 304.146793 -160.588706) (xy 304.108434 -160.672266)
			(xy 304.063035 -160.75222) (xy 304.01093 -160.827974) (xy 303.952505 -160.89897) (xy 303.888194 -160.96468)
			(xy 303.818473 -161.024618) (xy 303.743856 -161.078341) (xy 303.664898 -161.12545) (xy 303.582182 -161.165598)
			(xy 303.496322 -161.198486) (xy 303.407951 -161.223871) (xy 303.317726 -161.241566) (xy 303.226313 -161.251439)
			(xy 303.134391 -161.253418) (xy 303.042638 -161.247486) (xy 302.951735 -161.23369) (xy 302.862354 -161.21213)
			(xy 302.775158 -161.182966) (xy 302.690792 -161.146414) (xy 302.60988 -161.102745) (xy 302.533021 -161.052282)
			(xy 302.460786 -160.995399) (xy 302.393707 -160.932517) (xy 302.332282 -160.864101) (xy 302.276967 -160.790658)
			(xy 302.228169 -160.712731) (xy 302.186251 -160.630898) (xy 302.151523 -160.545765) (xy 302.124242 -160.457962)
			(xy 302.10461 -160.368138) (xy 302.092773 -160.276959) (xy 302.088817 -160.1851) (xy 293.229176 -160.1851)
			(xy 292.884006 -166.705534) (xy 293.311832 -166.705534) (xy 293.315903 -166.649912) (xy 293.328029 -166.595475)
			(xy 293.347952 -166.543384) (xy 293.375248 -166.494749) (xy 293.409334 -166.450606) (xy 293.449483 -166.411897)
			(xy 293.494841 -166.379446) (xy 293.544441 -166.353945) (xy 293.597225 -166.335938) (xy 293.652068 -166.325808)
			(xy 293.707802 -166.323771) (xy 293.763239 -166.329871) (xy 293.817196 -166.343977) (xy 293.868525 -166.365789)
			(xy 293.916131 -166.394843) (xy 293.958999 -166.430518) (xy 293.996216 -166.472055) (xy 294.026989 -166.518568)
			(xy 294.050661 -166.569065) (xy 294.066729 -166.622472) (xy 294.074849 -166.677648) (xy 294.075358 -166.705534)
			(xy 294.327832 -166.705534) (xy 294.331903 -166.649912) (xy 294.344029 -166.595475) (xy 294.363952 -166.543384)
			(xy 294.391248 -166.494749) (xy 294.425334 -166.450606) (xy 294.465483 -166.411897) (xy 294.510841 -166.379446)
			(xy 294.560441 -166.353945) (xy 294.613225 -166.335938) (xy 294.668068 -166.325808) (xy 294.723802 -166.323771)
			(xy 294.779239 -166.329871) (xy 294.833196 -166.343977) (xy 294.884525 -166.365789) (xy 294.932131 -166.394843)
			(xy 294.974999 -166.430518) (xy 295.012216 -166.472055) (xy 295.042989 -166.518568) (xy 295.066661 -166.569065)
			(xy 295.082729 -166.622472) (xy 295.090849 -166.677648) (xy 295.091358 -166.705534) (xy 295.343832 -166.705534)
			(xy 295.347903 -166.649912) (xy 295.360029 -166.595475) (xy 295.379952 -166.543384) (xy 295.407248 -166.494749)
			(xy 295.441334 -166.450606) (xy 295.481483 -166.411897) (xy 295.526841 -166.379446) (xy 295.576441 -166.353945)
			(xy 295.629225 -166.335938) (xy 295.684068 -166.325808) (xy 295.739802 -166.323771) (xy 295.795239 -166.329871)
			(xy 295.849196 -166.343977) (xy 295.900525 -166.365789) (xy 295.948131 -166.394843) (xy 295.990999 -166.430518)
			(xy 296.028216 -166.472055) (xy 296.058989 -166.518568) (xy 296.082661 -166.569065) (xy 296.098729 -166.622472)
			(xy 296.106849 -166.677648) (xy 296.107358 -166.705534) (xy 296.106849 -166.73342) (xy 296.098729 -166.788596)
			(xy 296.082661 -166.842003) (xy 296.058989 -166.8925) (xy 296.028216 -166.939013) (xy 295.990999 -166.98055)
			(xy 295.948131 -167.016225) (xy 295.900525 -167.045279) (xy 295.849196 -167.067091) (xy 295.795239 -167.081197)
			(xy 295.739802 -167.087297) (xy 295.684068 -167.08526) (xy 295.629225 -167.07513) (xy 295.576441 -167.057123)
			(xy 295.526841 -167.031622) (xy 295.481483 -166.999171) (xy 295.441334 -166.960462) (xy 295.407248 -166.916319)
			(xy 295.379952 -166.867684) (xy 295.360029 -166.815593) (xy 295.347903 -166.761156) (xy 295.343832 -166.705534)
			(xy 295.091358 -166.705534) (xy 295.090849 -166.73342) (xy 295.082729 -166.788596) (xy 295.066661 -166.842003)
			(xy 295.042989 -166.8925) (xy 295.012216 -166.939013) (xy 294.974999 -166.98055) (xy 294.932131 -167.016225)
			(xy 294.884525 -167.045279) (xy 294.833196 -167.067091) (xy 294.779239 -167.081197) (xy 294.723802 -167.087297)
			(xy 294.668068 -167.08526) (xy 294.613225 -167.07513) (xy 294.560441 -167.057123) (xy 294.510841 -167.031622)
			(xy 294.465483 -166.999171) (xy 294.425334 -166.960462) (xy 294.391248 -166.916319) (xy 294.363952 -166.867684)
			(xy 294.344029 -166.815593) (xy 294.331903 -166.761156) (xy 294.327832 -166.705534) (xy 294.075358 -166.705534)
			(xy 294.074849 -166.73342) (xy 294.066729 -166.788596) (xy 294.050661 -166.842003) (xy 294.026989 -166.8925)
			(xy 293.996216 -166.939013) (xy 293.958999 -166.98055) (xy 293.916131 -167.016225) (xy 293.868525 -167.045279)
			(xy 293.817196 -167.067091) (xy 293.763239 -167.081197) (xy 293.707802 -167.087297) (xy 293.652068 -167.08526)
			(xy 293.597225 -167.07513) (xy 293.544441 -167.057123) (xy 293.494841 -167.031622) (xy 293.449483 -166.999171)
			(xy 293.409334 -166.960462) (xy 293.375248 -166.916319) (xy 293.347952 -166.867684) (xy 293.328029 -166.815593)
			(xy 293.315903 -166.761156) (xy 293.311832 -166.705534) (xy 292.884006 -166.705534) (xy 292.586299 -172.329348)
			(xy 294.047924 -172.329348) (xy 294.051995 -172.273726) (xy 294.064121 -172.219289) (xy 294.084044 -172.167198)
			(xy 294.11134 -172.118563) (xy 294.145426 -172.07442) (xy 294.185575 -172.035711) (xy 294.230933 -172.00326)
			(xy 294.280533 -171.977759) (xy 294.333317 -171.959752) (xy 294.38816 -171.949622) (xy 294.443894 -171.947585)
			(xy 294.499331 -171.953685) (xy 294.553288 -171.967791) (xy 294.604617 -171.989603) (xy 294.652223 -172.018657)
			(xy 294.695091 -172.054332) (xy 294.732308 -172.095869) (xy 294.763081 -172.142382) (xy 294.786753 -172.192879)
			(xy 294.802821 -172.246286) (xy 294.810941 -172.301462) (xy 294.81145 -172.329348) (xy 294.811186 -172.343826)
			(xy 294.985184 -172.343826) (xy 294.989255 -172.288204) (xy 295.001381 -172.233767) (xy 295.021304 -172.181676)
			(xy 295.0486 -172.133041) (xy 295.082686 -172.088898) (xy 295.122835 -172.050189) (xy 295.168193 -172.017738)
			(xy 295.217793 -171.992237) (xy 295.270577 -171.97423) (xy 295.32542 -171.9641) (xy 295.381154 -171.962063)
			(xy 295.436591 -171.968163) (xy 295.490548 -171.982269) (xy 295.541877 -172.004081) (xy 295.589483 -172.033135)
			(xy 295.632351 -172.06881) (xy 295.669568 -172.110347) (xy 295.700341 -172.15686) (xy 295.706662 -172.170344)
			(xy 296.916092 -172.170344) (xy 296.920163 -172.114722) (xy 296.932289 -172.060285) (xy 296.952212 -172.008194)
			(xy 296.979508 -171.959559) (xy 297.013594 -171.915416) (xy 297.053743 -171.876707) (xy 297.099101 -171.844256)
			(xy 297.148701 -171.818755) (xy 297.201485 -171.800748) (xy 297.256328 -171.790618) (xy 297.312062 -171.788581)
			(xy 297.367499 -171.794681) (xy 297.421456 -171.808787) (xy 297.472785 -171.830599) (xy 297.520391 -171.859653)
			(xy 297.563259 -171.895328) (xy 297.600476 -171.936865) (xy 297.631249 -171.983378) (xy 297.654921 -172.033875)
			(xy 297.670989 -172.087282) (xy 297.679109 -172.142458) (xy 297.679618 -172.170344) (xy 297.679109 -172.19823)
			(xy 297.670989 -172.253406) (xy 297.654921 -172.306813) (xy 297.631249 -172.35731) (xy 297.600476 -172.403823)
			(xy 297.563259 -172.44536) (xy 297.520391 -172.481035) (xy 297.472785 -172.510089) (xy 297.421456 -172.531901)
			(xy 297.367499 -172.546007) (xy 297.312062 -172.552107) (xy 297.256328 -172.55007) (xy 297.201485 -172.53994)
			(xy 297.148701 -172.521933) (xy 297.099101 -172.496432) (xy 297.053743 -172.463981) (xy 297.013594 -172.425272)
			(xy 296.979508 -172.381129) (xy 296.952212 -172.332494) (xy 296.932289 -172.280403) (xy 296.920163 -172.225966)
			(xy 296.916092 -172.170344) (xy 295.706662 -172.170344) (xy 295.724013 -172.207357) (xy 295.740081 -172.260764)
			(xy 295.748201 -172.31594) (xy 295.74871 -172.343826) (xy 295.748201 -172.371712) (xy 295.740081 -172.426888)
			(xy 295.724013 -172.480295) (xy 295.700341 -172.530792) (xy 295.669568 -172.577305) (xy 295.632351 -172.618842)
			(xy 295.589483 -172.654517) (xy 295.541877 -172.683571) (xy 295.490548 -172.705383) (xy 295.436591 -172.719489)
			(xy 295.381154 -172.725589) (xy 295.32542 -172.723552) (xy 295.270577 -172.713422) (xy 295.217793 -172.695415)
			(xy 295.168193 -172.669914) (xy 295.122835 -172.637463) (xy 295.082686 -172.598754) (xy 295.0486 -172.554611)
			(xy 295.021304 -172.505976) (xy 295.001381 -172.453885) (xy 294.989255 -172.399448) (xy 294.985184 -172.343826)
			(xy 294.811186 -172.343826) (xy 294.810941 -172.357234) (xy 294.802821 -172.41241) (xy 294.786753 -172.465817)
			(xy 294.763081 -172.516314) (xy 294.732308 -172.562827) (xy 294.695091 -172.604364) (xy 294.652223 -172.640039)
			(xy 294.604617 -172.669093) (xy 294.553288 -172.690905) (xy 294.499331 -172.705011) (xy 294.443894 -172.711111)
			(xy 294.38816 -172.709074) (xy 294.333317 -172.698944) (xy 294.280533 -172.680937) (xy 294.230933 -172.655436)
			(xy 294.185575 -172.622985) (xy 294.145426 -172.584276) (xy 294.11134 -172.540133) (xy 294.084044 -172.491498)
			(xy 294.064121 -172.439407) (xy 294.051995 -172.38497) (xy 294.047924 -172.329348) (xy 292.586299 -172.329348)
			(xy 292.364159 -176.525682) (xy 296.609006 -176.525682) (xy 296.613077 -176.47006) (xy 296.625203 -176.415623)
			(xy 296.645126 -176.363532) (xy 296.672422 -176.314897) (xy 296.706508 -176.270754) (xy 296.746657 -176.232045)
			(xy 296.792015 -176.199594) (xy 296.841615 -176.174093) (xy 296.894399 -176.156086) (xy 296.949242 -176.145956)
			(xy 297.004976 -176.143919) (xy 297.060413 -176.150019) (xy 297.11437 -176.164125) (xy 297.165699 -176.185937)
			(xy 297.213305 -176.214991) (xy 297.256173 -176.250666) (xy 297.29339 -176.292203) (xy 297.324163 -176.338716)
			(xy 297.347835 -176.389213) (xy 297.363903 -176.44262) (xy 297.372023 -176.497796) (xy 297.372532 -176.525682)
			(xy 297.372023 -176.553568) (xy 297.363903 -176.608744) (xy 297.347835 -176.662151) (xy 297.324163 -176.712648)
			(xy 297.29339 -176.759161) (xy 297.256173 -176.800698) (xy 297.213305 -176.836373) (xy 297.165699 -176.865427)
			(xy 297.11437 -176.887239) (xy 297.060413 -176.901345) (xy 297.004976 -176.907445) (xy 296.949242 -176.905408)
			(xy 296.894399 -176.895278) (xy 296.841615 -176.877271) (xy 296.792015 -176.85177) (xy 296.746657 -176.819319)
			(xy 296.706508 -176.78061) (xy 296.672422 -176.736467) (xy 296.645126 -176.687832) (xy 296.625203 -176.635741)
			(xy 296.613077 -176.581304) (xy 296.609006 -176.525682) (xy 292.364159 -176.525682) (xy 292.302103 -177.697949)
			(xy 293.026092 -177.697949) (xy 293.026092 -177.643451) (xy 293.033848 -177.589506) (xy 293.049202 -177.537215)
			(xy 293.071841 -177.48764) (xy 293.101305 -177.441793) (xy 293.136993 -177.400604) (xy 293.17818 -177.364914)
			(xy 293.224026 -177.335449) (xy 293.2736 -177.312807) (xy 293.325891 -177.297451) (xy 293.379835 -177.289693)
			(xy 293.407084 -177.289206) (xy 293.434454 -177.28968) (xy 293.488633 -177.297496) (xy 293.541136 -177.312983)
			(xy 293.590883 -177.335823) (xy 293.63685 -177.365546) (xy 293.657782 -177.383186) (xy 293.658036 -177.38344)
			(xy 293.665133 -177.389011) (xy 293.682042 -177.395266) (xy 293.691056 -177.395632) (xy 293.758112 -177.395632)
			(xy 293.767129 -177.395274) (xy 293.784045 -177.389026) (xy 293.791132 -177.38344) (xy 293.791132 -177.383186)
			(xy 293.791386 -177.383186) (xy 293.812319 -177.365545) (xy 293.858287 -177.335821) (xy 293.908033 -177.312975)
			(xy 293.960535 -177.297479) (xy 294.014713 -177.28965) (xy 294.069455 -177.28965) (xy 294.123633 -177.297479)
			(xy 294.176135 -177.312975) (xy 294.225881 -177.335821) (xy 294.271849 -177.365545) (xy 294.292782 -177.383186)
			(xy 294.293036 -177.38344) (xy 294.300133 -177.389011) (xy 294.317042 -177.395266) (xy 294.326056 -177.395632)
			(xy 294.393112 -177.395632) (xy 294.402129 -177.395274) (xy 294.419045 -177.389026) (xy 294.426132 -177.38344)
			(xy 294.426132 -177.383186) (xy 294.426386 -177.383186) (xy 294.447319 -177.365545) (xy 294.493287 -177.335821)
			(xy 294.543033 -177.312975) (xy 294.595535 -177.297479) (xy 294.649713 -177.28965) (xy 294.704455 -177.28965)
			(xy 294.758633 -177.297479) (xy 294.811135 -177.312975) (xy 294.860881 -177.335821) (xy 294.906849 -177.365545)
			(xy 294.927782 -177.383186) (xy 294.928036 -177.38344) (xy 294.935133 -177.389011) (xy 294.952042 -177.395266)
			(xy 294.961056 -177.395632) (xy 295.028112 -177.395632) (xy 295.037129 -177.395274) (xy 295.054045 -177.389026)
			(xy 295.061132 -177.38344) (xy 295.061132 -177.383186) (xy 295.061386 -177.383186) (xy 295.082311 -177.365538)
			(xy 295.128286 -177.335828) (xy 295.178035 -177.312994) (xy 295.230537 -177.297505) (xy 295.284714 -177.289679)
			(xy 295.312084 -177.289206) (xy 295.339339 -177.28964) (xy 295.393293 -177.297395) (xy 295.445595 -177.31275)
			(xy 295.495179 -177.335393) (xy 295.541036 -177.364862) (xy 295.582232 -177.400557) (xy 295.617929 -177.441751)
			(xy 295.647399 -177.487607) (xy 295.670044 -177.53719) (xy 295.685401 -177.589491) (xy 295.693159 -177.643445)
			(xy 295.693159 -177.697955) (xy 295.685401 -177.751909) (xy 295.670044 -177.80421) (xy 295.647399 -177.853793)
			(xy 295.617929 -177.899649) (xy 295.582232 -177.940843) (xy 295.541036 -177.976538) (xy 295.495179 -178.006007)
			(xy 295.445595 -178.02865) (xy 295.393293 -178.044005) (xy 295.339339 -178.05176) (xy 295.312084 -178.052222)
			(xy 295.284713 -178.051784) (xy 295.230531 -178.043963) (xy 295.178027 -178.028468) (xy 295.128281 -178.005619)
			(xy 295.082316 -177.975887) (xy 295.061386 -177.958242) (xy 295.061132 -177.957988) (xy 295.054041 -177.952407)
			(xy 295.037128 -177.946157) (xy 295.028112 -177.945796) (xy 294.961056 -177.945796) (xy 294.952042 -177.946181)
			(xy 294.935125 -177.952409) (xy 294.928036 -177.957988) (xy 294.927782 -177.958242) (xy 294.906849 -177.975883)
			(xy 294.860881 -178.005607) (xy 294.811135 -178.028453) (xy 294.758633 -178.043949) (xy 294.704455 -178.051778)
			(xy 294.649713 -178.051778) (xy 294.595535 -178.043949) (xy 294.543033 -178.028453) (xy 294.493287 -178.005607)
			(xy 294.447319 -177.975883) (xy 294.426386 -177.958242) (xy 294.426132 -177.957988) (xy 294.419041 -177.952407)
			(xy 294.402128 -177.946157) (xy 294.393112 -177.945796) (xy 294.326056 -177.945796) (xy 294.317042 -177.946181)
			(xy 294.300125 -177.952409) (xy 294.293036 -177.957988) (xy 294.293036 -177.958242) (xy 294.292782 -177.958242)
			(xy 294.271849 -177.975883) (xy 294.225881 -178.005607) (xy 294.176135 -178.028453) (xy 294.123633 -178.043949)
			(xy 294.069455 -178.051778) (xy 294.014713 -178.051778) (xy 293.960535 -178.043949) (xy 293.908033 -178.028453)
			(xy 293.858287 -178.005607) (xy 293.812319 -177.975883) (xy 293.791386 -177.958242) (xy 293.791132 -177.957988)
			(xy 293.784041 -177.952407) (xy 293.767128 -177.946157) (xy 293.758112 -177.945796) (xy 293.691056 -177.945796)
			(xy 293.682042 -177.946181) (xy 293.665125 -177.952409) (xy 293.658036 -177.957988) (xy 293.658036 -177.958242)
			(xy 293.657782 -177.958242) (xy 293.636836 -177.975863) (xy 293.590866 -178.005576) (xy 293.541122 -178.028415)
			(xy 293.488625 -178.043911) (xy 293.434452 -178.051745) (xy 293.407084 -178.052222) (xy 293.379835 -178.051707)
			(xy 293.325891 -178.043949) (xy 293.2736 -178.028593) (xy 293.224026 -178.005951) (xy 293.17818 -177.976486)
			(xy 293.136993 -177.940796) (xy 293.101305 -177.899607) (xy 293.071841 -177.85376) (xy 293.049202 -177.804185)
			(xy 293.033848 -177.751894) (xy 293.026092 -177.697949) (xy 292.302103 -177.697949) (xy 292.117238 -181.190138)
			(xy 295.216578 -181.190138) (xy 295.220649 -181.134516) (xy 295.232775 -181.080079) (xy 295.252698 -181.027988)
			(xy 295.279994 -180.979353) (xy 295.31408 -180.93521) (xy 295.354229 -180.896501) (xy 295.399587 -180.86405)
			(xy 295.449187 -180.838549) (xy 295.501971 -180.820542) (xy 295.556814 -180.810412) (xy 295.612548 -180.808375)
			(xy 295.667985 -180.814475) (xy 295.721942 -180.828581) (xy 295.773271 -180.850393) (xy 295.820877 -180.879447)
			(xy 295.863745 -180.915122) (xy 295.900962 -180.956659) (xy 295.931735 -181.003172) (xy 295.955407 -181.053669)
			(xy 295.971475 -181.107076) (xy 295.979595 -181.162252) (xy 295.980104 -181.190138) (xy 295.979595 -181.218024)
			(xy 295.971475 -181.2732) (xy 295.955407 -181.326607) (xy 295.931735 -181.377104) (xy 295.900962 -181.423617)
			(xy 295.863745 -181.465154) (xy 295.820877 -181.500829) (xy 295.773271 -181.529883) (xy 295.721942 -181.551695)
			(xy 295.667985 -181.565801) (xy 295.612548 -181.571901) (xy 295.556814 -181.569864) (xy 295.501971 -181.559734)
			(xy 295.449187 -181.541727) (xy 295.399587 -181.516226) (xy 295.354229 -181.483775) (xy 295.31408 -181.445066)
			(xy 295.279994 -181.400923) (xy 295.252698 -181.352288) (xy 295.232775 -181.300197) (xy 295.220649 -181.24576)
			(xy 295.216578 -181.190138) (xy 292.117238 -181.190138) (xy 292.048368 -182.491126) (xy 295.811192 -182.491126)
			(xy 295.815263 -182.435504) (xy 295.827389 -182.381067) (xy 295.847312 -182.328976) (xy 295.874608 -182.280341)
			(xy 295.908694 -182.236198) (xy 295.948843 -182.197489) (xy 295.994201 -182.165038) (xy 296.043801 -182.139537)
			(xy 296.096585 -182.12153) (xy 296.151428 -182.1114) (xy 296.207162 -182.109363) (xy 296.262599 -182.115463)
			(xy 296.316556 -182.129569) (xy 296.367885 -182.151381) (xy 296.415491 -182.180435) (xy 296.458359 -182.21611)
			(xy 296.495576 -182.257647) (xy 296.526349 -182.30416) (xy 296.550021 -182.354657) (xy 296.566089 -182.408064)
			(xy 296.574209 -182.46324) (xy 296.574718 -182.491126) (xy 296.574209 -182.519012) (xy 296.566089 -182.574188)
			(xy 296.550021 -182.627595) (xy 296.526349 -182.678092) (xy 296.495576 -182.724605) (xy 296.458359 -182.766142)
			(xy 296.415491 -182.801817) (xy 296.367885 -182.830871) (xy 296.316556 -182.852683) (xy 296.262599 -182.866789)
			(xy 296.207162 -182.872889) (xy 296.151428 -182.870852) (xy 296.096585 -182.860722) (xy 296.043801 -182.842715)
			(xy 295.994201 -182.817214) (xy 295.948843 -182.784763) (xy 295.908694 -182.746054) (xy 295.874608 -182.701911)
			(xy 295.847312 -182.653276) (xy 295.827389 -182.601185) (xy 295.815263 -182.546748) (xy 295.811192 -182.491126)
			(xy 292.048368 -182.491126) (xy 291.912914 -185.049922) (xy 292.35603 -185.049922) (xy 292.360101 -184.9943)
			(xy 292.372227 -184.939863) (xy 292.39215 -184.887772) (xy 292.419446 -184.839137) (xy 292.453532 -184.794994)
			(xy 292.493681 -184.756285) (xy 292.539039 -184.723834) (xy 292.588639 -184.698333) (xy 292.641423 -184.680326)
			(xy 292.696266 -184.670196) (xy 292.752 -184.668159) (xy 292.807437 -184.674259) (xy 292.861394 -184.688365)
			(xy 292.912723 -184.710177) (xy 292.960329 -184.739231) (xy 293.003197 -184.774906) (xy 293.040414 -184.816443)
			(xy 293.071187 -184.862956) (xy 293.094859 -184.913453) (xy 293.110927 -184.96686) (xy 293.119047 -185.022036)
			(xy 293.119556 -185.049922) (xy 293.119047 -185.077808) (xy 293.110927 -185.132984) (xy 293.094859 -185.186391)
			(xy 293.071187 -185.236888) (xy 293.040414 -185.283401) (xy 293.003197 -185.324938) (xy 292.960329 -185.360613)
			(xy 292.912723 -185.389667) (xy 292.861394 -185.411479) (xy 292.807437 -185.425585) (xy 292.752 -185.431685)
			(xy 292.696266 -185.429648) (xy 292.641423 -185.419518) (xy 292.588639 -185.401511) (xy 292.539039 -185.37601)
			(xy 292.493681 -185.343559) (xy 292.453532 -185.30485) (xy 292.419446 -185.260707) (xy 292.39215 -185.212072)
			(xy 292.372227 -185.159981) (xy 292.360101 -185.105544) (xy 292.35603 -185.049922) (xy 291.912914 -185.049922)
			(xy 291.841462 -186.399678) (xy 297.289218 -186.399678) (xy 297.293289 -186.344056) (xy 297.305415 -186.289619)
			(xy 297.325338 -186.237528) (xy 297.352634 -186.188893) (xy 297.38672 -186.14475) (xy 297.426869 -186.106041)
			(xy 297.472227 -186.07359) (xy 297.521827 -186.048089) (xy 297.574611 -186.030082) (xy 297.629454 -186.019952)
			(xy 297.685188 -186.017915) (xy 297.740625 -186.024015) (xy 297.794582 -186.038121) (xy 297.845911 -186.059933)
			(xy 297.893517 -186.088987) (xy 297.936385 -186.124662) (xy 297.973602 -186.166199) (xy 298.004375 -186.212712)
			(xy 298.028047 -186.263209) (xy 298.044115 -186.316616) (xy 298.052235 -186.371792) (xy 298.052744 -186.399678)
			(xy 298.052235 -186.427564) (xy 298.044115 -186.48274) (xy 298.028047 -186.536147) (xy 298.004375 -186.586644)
			(xy 297.973602 -186.633157) (xy 297.936385 -186.674694) (xy 297.893517 -186.710369) (xy 297.845911 -186.739423)
			(xy 297.794582 -186.761235) (xy 297.740625 -186.775341) (xy 297.685188 -186.781441) (xy 297.629454 -186.779404)
			(xy 297.574611 -186.769274) (xy 297.521827 -186.751267) (xy 297.472227 -186.725766) (xy 297.426869 -186.693315)
			(xy 297.38672 -186.654606) (xy 297.352634 -186.610463) (xy 297.325338 -186.561828) (xy 297.305415 -186.509737)
			(xy 297.293289 -186.4553) (xy 297.289218 -186.399678) (xy 291.841462 -186.399678) (xy 291.686996 -189.31763)
			(xy 291.686996 -189.319408) (xy 291.687214 -189.333732) (xy 291.694642 -189.361387) (xy 291.709447 -189.385898)
			(xy 291.730468 -189.405342) (xy 291.756057 -189.418194) (xy 291.784206 -189.423446) (xy 291.798502 -189.422532)
			(xy 291.836094 -189.420754) (xy 291.836348 -189.420754) (xy 291.8636 -189.421243) (xy 291.917548 -189.429006)
			(xy 291.969842 -189.444367) (xy 292.019418 -189.467013) (xy 292.065267 -189.496483) (xy 292.106455 -189.532179)
			(xy 292.142145 -189.573372) (xy 292.17161 -189.619224) (xy 292.19425 -189.668803) (xy 292.209604 -189.721099)
			(xy 292.21736 -189.775048) (xy 292.21736 -189.829552) (xy 292.209604 -189.883501) (xy 292.19425 -189.935797)
			(xy 292.17161 -189.985376) (xy 292.142145 -190.031228) (xy 292.106455 -190.072421) (xy 292.065267 -190.108117)
			(xy 292.019418 -190.137587) (xy 291.969842 -190.160233) (xy 291.917548 -190.175594) (xy 291.8636 -190.183357)
			(xy 291.836348 -190.18377) (xy 291.836094 -190.18377) (xy 291.816588 -190.183538) (xy 291.777777 -190.179596)
			(xy 291.758624 -190.175896) (xy 291.744493 -190.173434) (xy 291.715903 -190.175593) (xy 291.689044 -190.185624)
			(xy 291.666038 -190.202734) (xy 291.648704 -190.225572) (xy 291.638411 -190.252332) (xy 291.636704 -190.266574)
			(xy 291.636704 -190.268352) (xy 291.463476 -193.54165) (xy 291.430964 -194.156076) (xy 291.431363 -194.165358)
			(xy 291.438006 -194.182692) (xy 291.443918 -194.189858) (xy 291.449392 -194.196208) (xy 292.349172 -194.196208)
			(xy 292.353243 -194.140586) (xy 292.365369 -194.086149) (xy 292.385292 -194.034058) (xy 292.412588 -193.985423)
			(xy 292.446674 -193.94128) (xy 292.486823 -193.902571) (xy 292.532181 -193.87012) (xy 292.581781 -193.844619)
			(xy 292.634565 -193.826612) (xy 292.689408 -193.816482) (xy 292.745142 -193.814445) (xy 292.800579 -193.820545)
			(xy 292.854536 -193.834651) (xy 292.905865 -193.856463) (xy 292.953471 -193.885517) (xy 292.996339 -193.921192)
			(xy 293.033556 -193.962729) (xy 293.064329 -194.009242) (xy 293.088001 -194.059739) (xy 293.104069 -194.113146)
			(xy 293.112189 -194.168322) (xy 293.112698 -194.196208) (xy 293.112189 -194.224094) (xy 293.104069 -194.27927)
			(xy 293.090238 -194.32524) (xy 297.568618 -194.32524) (xy 297.572689 -194.269618) (xy 297.584815 -194.215181)
			(xy 297.604738 -194.16309) (xy 297.632034 -194.114455) (xy 297.66612 -194.070312) (xy 297.706269 -194.031603)
			(xy 297.751627 -193.999152) (xy 297.801227 -193.973651) (xy 297.854011 -193.955644) (xy 297.908854 -193.945514)
			(xy 297.964588 -193.943477) (xy 298.020025 -193.949577) (xy 298.073982 -193.963683) (xy 298.125311 -193.985495)
			(xy 298.172917 -194.014549) (xy 298.215785 -194.050224) (xy 298.253002 -194.091761) (xy 298.283775 -194.138274)
			(xy 298.307447 -194.188771) (xy 298.323515 -194.242178) (xy 298.331635 -194.297354) (xy 298.332144 -194.32524)
			(xy 298.331635 -194.353126) (xy 298.323515 -194.408302) (xy 298.307447 -194.461709) (xy 298.283775 -194.512206)
			(xy 298.253002 -194.558719) (xy 298.215785 -194.600256) (xy 298.172917 -194.635931) (xy 298.125311 -194.664985)
			(xy 298.073982 -194.686797) (xy 298.020025 -194.700903) (xy 297.964588 -194.707003) (xy 297.908854 -194.704966)
			(xy 297.854011 -194.694836) (xy 297.801227 -194.676829) (xy 297.751627 -194.651328) (xy 297.706269 -194.618877)
			(xy 297.66612 -194.580168) (xy 297.632034 -194.536025) (xy 297.604738 -194.48739) (xy 297.584815 -194.435299)
			(xy 297.572689 -194.380862) (xy 297.568618 -194.32524) (xy 293.090238 -194.32524) (xy 293.088001 -194.332677)
			(xy 293.064329 -194.383174) (xy 293.033556 -194.429687) (xy 292.996339 -194.471224) (xy 292.953471 -194.506899)
			(xy 292.905865 -194.535953) (xy 292.854536 -194.557765) (xy 292.800579 -194.571871) (xy 292.745142 -194.577971)
			(xy 292.689408 -194.575934) (xy 292.634565 -194.565804) (xy 292.581781 -194.547797) (xy 292.532181 -194.522296)
			(xy 292.486823 -194.489845) (xy 292.446674 -194.451136) (xy 292.412588 -194.406993) (xy 292.385292 -194.358358)
			(xy 292.365369 -194.306267) (xy 292.353243 -194.25183) (xy 292.349172 -194.196208) (xy 291.449392 -194.196208)
			(xy 291.450268 -194.197224) (xy 291.468048 -194.205606) (xy 291.478716 -194.206368) (xy 291.47897 -194.206368)
			(xy 291.50778 -194.208596) (xy 291.564294 -194.220641) (xy 291.618349 -194.241058) (xy 291.668714 -194.269382)
			(xy 291.71424 -194.304966) (xy 291.753889 -194.347) (xy 291.786757 -194.394524) (xy 291.812094 -194.446456)
			(xy 291.829322 -194.501611) (xy 291.83805 -194.558731) (xy 291.838634 -194.587622) (xy 291.838169 -194.614891)
			(xy 291.830404 -194.668874) (xy 291.815036 -194.721203) (xy 291.792376 -194.770811) (xy 291.762888 -194.81669)
			(xy 291.72717 -194.857905) (xy 291.68595 -194.893618) (xy 291.640067 -194.9231) (xy 291.590456 -194.945753)
			(xy 291.538125 -194.961115) (xy 291.484141 -194.968873) (xy 291.456872 -194.969384) (xy 291.43833 -194.968876)
			(xy 291.438076 -194.968876) (xy 291.428143 -194.968894) (xy 291.409447 -194.975548) (xy 291.401754 -194.98183)
			(xy 291.394642 -194.98818) (xy 291.390324 -194.997324) (xy 291.388293 -195.00184) (xy 291.385854 -195.011435)
			(xy 291.385498 -195.016374) (xy 291.332186 -196.022976) (xy 297.965112 -196.022976) (xy 297.969183 -195.967354)
			(xy 297.981309 -195.912917) (xy 298.001232 -195.860826) (xy 298.028528 -195.812191) (xy 298.062614 -195.768048)
			(xy 298.102763 -195.729339) (xy 298.148121 -195.696888) (xy 298.197721 -195.671387) (xy 298.250505 -195.65338)
			(xy 298.305348 -195.64325) (xy 298.361082 -195.641213) (xy 298.416519 -195.647313) (xy 298.470476 -195.661419)
			(xy 298.521805 -195.683231) (xy 298.569411 -195.712285) (xy 298.612279 -195.74796) (xy 298.649496 -195.789497)
			(xy 298.680269 -195.83601) (xy 298.703941 -195.886507) (xy 298.720009 -195.939914) (xy 298.728129 -195.99509)
			(xy 298.728638 -196.022976) (xy 298.728129 -196.050862) (xy 298.720009 -196.106038) (xy 298.703941 -196.159445)
			(xy 298.680269 -196.209942) (xy 298.649496 -196.256455) (xy 298.612279 -196.297992) (xy 298.569411 -196.333667)
			(xy 298.521805 -196.362721) (xy 298.470476 -196.384533) (xy 298.416519 -196.398639) (xy 298.361082 -196.404739)
			(xy 298.305348 -196.402702) (xy 298.250505 -196.392572) (xy 298.197721 -196.374565) (xy 298.148121 -196.349064)
			(xy 298.102763 -196.316613) (xy 298.062614 -196.277904) (xy 298.028528 -196.233761) (xy 298.001232 -196.185126)
			(xy 297.981309 -196.133035) (xy 297.969183 -196.078598) (xy 297.965112 -196.022976) (xy 291.332186 -196.022976)
			(xy 291.072391 -200.928224) (xy 292.89959 -200.928224) (xy 292.903661 -200.872602) (xy 292.915787 -200.818165)
			(xy 292.93571 -200.766074) (xy 292.963006 -200.717439) (xy 292.997092 -200.673296) (xy 293.037241 -200.634587)
			(xy 293.082599 -200.602136) (xy 293.132199 -200.576635) (xy 293.184983 -200.558628) (xy 293.239826 -200.548498)
			(xy 293.29556 -200.546461) (xy 293.350997 -200.552561) (xy 293.404954 -200.566667) (xy 293.456283 -200.588479)
			(xy 293.503889 -200.617533) (xy 293.546757 -200.653208) (xy 293.583974 -200.694745) (xy 293.614747 -200.741258)
			(xy 293.638419 -200.791755) (xy 293.654487 -200.845162) (xy 293.662607 -200.900338) (xy 293.663116 -200.928224)
			(xy 293.662607 -200.95611) (xy 293.654487 -201.011286) (xy 293.638419 -201.064693) (xy 293.636785 -201.068178)
			(xy 295.508932 -201.068178) (xy 295.513003 -201.012556) (xy 295.525129 -200.958119) (xy 295.545052 -200.906028)
			(xy 295.572348 -200.857393) (xy 295.606434 -200.81325) (xy 295.646583 -200.774541) (xy 295.691941 -200.74209)
			(xy 295.741541 -200.716589) (xy 295.794325 -200.698582) (xy 295.849168 -200.688452) (xy 295.904902 -200.686415)
			(xy 295.960339 -200.692515) (xy 296.014296 -200.706621) (xy 296.065625 -200.728433) (xy 296.113231 -200.757487)
			(xy 296.156099 -200.793162) (xy 296.193316 -200.834699) (xy 296.224089 -200.881212) (xy 296.247761 -200.931709)
			(xy 296.263829 -200.985116) (xy 296.271949 -201.040292) (xy 296.272458 -201.068178) (xy 296.271949 -201.096064)
			(xy 296.263829 -201.15124) (xy 296.263754 -201.15149) (xy 296.72102 -201.15149) (xy 296.725091 -201.095868)
			(xy 296.737217 -201.041431) (xy 296.75714 -200.98934) (xy 296.784436 -200.940705) (xy 296.818522 -200.896562)
			(xy 296.858671 -200.857853) (xy 296.904029 -200.825402) (xy 296.953629 -200.799901) (xy 297.006413 -200.781894)
			(xy 297.061256 -200.771764) (xy 297.11699 -200.769727) (xy 297.172427 -200.775827) (xy 297.226384 -200.789933)
			(xy 297.277713 -200.811745) (xy 297.325319 -200.840799) (xy 297.368187 -200.876474) (xy 297.405404 -200.918011)
			(xy 297.436177 -200.964524) (xy 297.459849 -201.015021) (xy 297.475917 -201.068428) (xy 297.484037 -201.123604)
			(xy 297.484546 -201.15149) (xy 297.484037 -201.179376) (xy 297.475917 -201.234552) (xy 297.459849 -201.287959)
			(xy 297.436177 -201.338456) (xy 297.405404 -201.384969) (xy 297.368187 -201.426506) (xy 297.325319 -201.462181)
			(xy 297.277713 -201.491235) (xy 297.226384 -201.513047) (xy 297.172427 -201.527153) (xy 297.11699 -201.533253)
			(xy 297.061256 -201.531216) (xy 297.006413 -201.521086) (xy 296.953629 -201.503079) (xy 296.904029 -201.477578)
			(xy 296.858671 -201.445127) (xy 296.818522 -201.406418) (xy 296.784436 -201.362275) (xy 296.75714 -201.31364)
			(xy 296.737217 -201.261549) (xy 296.725091 -201.207112) (xy 296.72102 -201.15149) (xy 296.263754 -201.15149)
			(xy 296.247761 -201.204647) (xy 296.224089 -201.255144) (xy 296.193316 -201.301657) (xy 296.156099 -201.343194)
			(xy 296.113231 -201.378869) (xy 296.065625 -201.407923) (xy 296.014296 -201.429735) (xy 295.960339 -201.443841)
			(xy 295.904902 -201.449941) (xy 295.849168 -201.447904) (xy 295.794325 -201.437774) (xy 295.741541 -201.419767)
			(xy 295.691941 -201.394266) (xy 295.646583 -201.361815) (xy 295.606434 -201.323106) (xy 295.572348 -201.278963)
			(xy 295.545052 -201.230328) (xy 295.525129 -201.178237) (xy 295.513003 -201.1238) (xy 295.508932 -201.068178)
			(xy 293.636785 -201.068178) (xy 293.614747 -201.11519) (xy 293.583974 -201.161703) (xy 293.546757 -201.20324)
			(xy 293.503889 -201.238915) (xy 293.456283 -201.267969) (xy 293.404954 -201.289781) (xy 293.350997 -201.303887)
			(xy 293.29556 -201.309987) (xy 293.239826 -201.30795) (xy 293.184983 -201.29782) (xy 293.132199 -201.279813)
			(xy 293.082599 -201.254312) (xy 293.037241 -201.221861) (xy 292.997092 -201.183152) (xy 292.963006 -201.139009)
			(xy 292.93571 -201.090374) (xy 292.915787 -201.038283) (xy 292.903661 -200.983846) (xy 292.89959 -200.928224)
			(xy 291.072391 -200.928224) (xy 291.026088 -201.802492) (xy 290.928806 -203.641198) (xy 290.928806 -203.642976)
			(xy 290.92927 -203.656824) (xy 290.936717 -203.6835) (xy 290.951066 -203.707188) (xy 290.971261 -203.726141)
			(xy 290.99581 -203.738961) (xy 291.022904 -203.744702) (xy 291.036756 -203.744322) (xy 291.06114 -203.74356)
			(xy 291.088392 -203.744049) (xy 291.14234 -203.75181) (xy 291.194634 -203.76717) (xy 291.24421 -203.789816)
			(xy 291.290059 -203.819285) (xy 291.331248 -203.85498) (xy 291.366939 -203.896173) (xy 291.392428 -203.935838)
			(xy 292.984172 -203.935838) (xy 292.988243 -203.880216) (xy 293.000369 -203.825779) (xy 293.020292 -203.773688)
			(xy 293.047588 -203.725053) (xy 293.081674 -203.68091) (xy 293.121823 -203.642201) (xy 293.167181 -203.60975)
			(xy 293.216781 -203.584249) (xy 293.269565 -203.566242) (xy 293.324408 -203.556112) (xy 293.380142 -203.554075)
			(xy 293.435579 -203.560175) (xy 293.489536 -203.574281) (xy 293.540865 -203.596093) (xy 293.588471 -203.625147)
			(xy 293.631339 -203.660822) (xy 293.668556 -203.702359) (xy 293.699329 -203.748872) (xy 293.712199 -203.776326)
			(xy 295.45991 -203.776326) (xy 295.463981 -203.720704) (xy 295.476107 -203.666267) (xy 295.49603 -203.614176)
			(xy 295.523326 -203.565541) (xy 295.557412 -203.521398) (xy 295.597561 -203.482689) (xy 295.642919 -203.450238)
			(xy 295.692519 -203.424737) (xy 295.745303 -203.40673) (xy 295.800146 -203.3966) (xy 295.85588 -203.394563)
			(xy 295.911317 -203.400663) (xy 295.965274 -203.414769) (xy 296.016603 -203.436581) (xy 296.064209 -203.465635)
			(xy 296.107077 -203.50131) (xy 296.144294 -203.542847) (xy 296.175067 -203.58936) (xy 296.198739 -203.639857)
			(xy 296.214807 -203.693264) (xy 296.222927 -203.74844) (xy 296.223436 -203.776326) (xy 296.222927 -203.804212)
			(xy 296.214807 -203.859388) (xy 296.198739 -203.912795) (xy 296.175067 -203.963292) (xy 296.144294 -204.009805)
			(xy 296.107077 -204.051342) (xy 296.064209 -204.087017) (xy 296.016603 -204.116071) (xy 295.965274 -204.137883)
			(xy 295.911317 -204.151989) (xy 295.85588 -204.158089) (xy 295.800146 -204.156052) (xy 295.745303 -204.145922)
			(xy 295.692519 -204.127915) (xy 295.642919 -204.102414) (xy 295.597561 -204.069963) (xy 295.557412 -204.031254)
			(xy 295.523326 -203.987111) (xy 295.49603 -203.938476) (xy 295.476107 -203.886385) (xy 295.463981 -203.831948)
			(xy 295.45991 -203.776326) (xy 293.712199 -203.776326) (xy 293.723001 -203.799369) (xy 293.739069 -203.852776)
			(xy 293.747189 -203.907952) (xy 293.747698 -203.935838) (xy 293.747189 -203.963724) (xy 293.739069 -204.0189)
			(xy 293.723001 -204.072307) (xy 293.699329 -204.122804) (xy 293.668556 -204.169317) (xy 293.631339 -204.210854)
			(xy 293.588471 -204.246529) (xy 293.540865 -204.275583) (xy 293.489536 -204.297395) (xy 293.435579 -204.311501)
			(xy 293.380142 -204.317601) (xy 293.324408 -204.315564) (xy 293.269565 -204.305434) (xy 293.216781 -204.287427)
			(xy 293.167181 -204.261926) (xy 293.121823 -204.229475) (xy 293.081674 -204.190766) (xy 293.047588 -204.146623)
			(xy 293.020292 -204.097988) (xy 293.000369 -204.045897) (xy 292.988243 -203.99146) (xy 292.984172 -203.935838)
			(xy 291.392428 -203.935838) (xy 291.396404 -203.942025) (xy 291.419044 -203.991604) (xy 291.434398 -204.0439)
			(xy 291.442154 -204.097848) (xy 291.442154 -204.152352) (xy 291.434398 -204.2063) (xy 291.419044 -204.258596)
			(xy 291.396404 -204.308175) (xy 291.366939 -204.354027) (xy 291.331248 -204.39522) (xy 291.290059 -204.430915)
			(xy 291.24421 -204.460384) (xy 291.194634 -204.48303) (xy 291.14234 -204.49839) (xy 291.088392 -204.506151)
			(xy 291.06114 -204.506576) (xy 291.060886 -204.506576) (xy 291.044357 -204.506433) (xy 291.011417 -204.503634)
			(xy 290.9951 -204.500988) (xy 290.99383 -204.500734) (xy 290.993068 -204.50048) (xy 290.99129 -204.500226)
			(xy 290.978271 -204.499161) (xy 290.952426 -204.502897) (xy 290.940236 -204.507592) (xy 290.927287 -204.513569)
			(xy 290.905103 -204.531475) (xy 290.888734 -204.554816) (xy 290.879456 -204.581772) (xy 290.87826 -204.595984)
			(xy 290.775464 -206.538068) (xy 292.603172 -206.538068) (xy 292.607243 -206.482446) (xy 292.619369 -206.428009)
			(xy 292.639292 -206.375918) (xy 292.666588 -206.327283) (xy 292.700674 -206.28314) (xy 292.740823 -206.244431)
			(xy 292.786181 -206.21198) (xy 292.835781 -206.186479) (xy 292.888565 -206.168472) (xy 292.943408 -206.158342)
			(xy 292.999142 -206.156305) (xy 293.054579 -206.162405) (xy 293.108536 -206.176511) (xy 293.159865 -206.198323)
			(xy 293.207471 -206.227377) (xy 293.250339 -206.263052) (xy 293.287556 -206.304589) (xy 293.318329 -206.351102)
			(xy 293.342001 -206.401599) (xy 293.358069 -206.455006) (xy 293.366189 -206.510182) (xy 293.366698 -206.538068)
			(xy 293.366189 -206.565954) (xy 293.358069 -206.62113) (xy 293.342001 -206.674537) (xy 293.318329 -206.725034)
			(xy 293.287556 -206.771547) (xy 293.250339 -206.813084) (xy 293.207471 -206.848759) (xy 293.159865 -206.877813)
			(xy 293.108536 -206.899625) (xy 293.054579 -206.913731) (xy 292.999142 -206.919831) (xy 292.943408 -206.917794)
			(xy 292.888565 -206.907664) (xy 292.835781 -206.889657) (xy 292.786181 -206.864156) (xy 292.740823 -206.831705)
			(xy 292.700674 -206.792996) (xy 292.666588 -206.748853) (xy 292.639292 -206.700218) (xy 292.619369 -206.648127)
			(xy 292.607243 -206.59369) (xy 292.603172 -206.538068) (xy 290.775464 -206.538068) (xy 290.358353 -214.418418)
			(xy 294.647872 -214.418418) (xy 294.651943 -214.362796) (xy 294.664069 -214.308359) (xy 294.683992 -214.256268)
			(xy 294.711288 -214.207633) (xy 294.745374 -214.16349) (xy 294.785523 -214.124781) (xy 294.830881 -214.09233)
			(xy 294.880481 -214.066829) (xy 294.933265 -214.048822) (xy 294.988108 -214.038692) (xy 295.043842 -214.036655)
			(xy 295.099279 -214.042755) (xy 295.153236 -214.056861) (xy 295.204565 -214.078673) (xy 295.252171 -214.107727)
			(xy 295.295039 -214.143402) (xy 295.332256 -214.184939) (xy 295.363029 -214.231452) (xy 295.386701 -214.281949)
			(xy 295.402769 -214.335356) (xy 295.410889 -214.390532) (xy 295.411398 -214.418418) (xy 295.410889 -214.446304)
			(xy 295.402769 -214.50148) (xy 295.386701 -214.554887) (xy 295.363029 -214.605384) (xy 295.332256 -214.651897)
			(xy 295.295039 -214.693434) (xy 295.252171 -214.729109) (xy 295.204565 -214.758163) (xy 295.153236 -214.779975)
			(xy 295.099279 -214.794081) (xy 295.043842 -214.800181) (xy 294.988108 -214.798144) (xy 294.933265 -214.788014)
			(xy 294.880481 -214.770007) (xy 294.830881 -214.744506) (xy 294.785523 -214.712055) (xy 294.745374 -214.673346)
			(xy 294.711288 -214.629203) (xy 294.683992 -214.580568) (xy 294.664069 -214.528477) (xy 294.651943 -214.47404)
			(xy 294.647872 -214.418418) (xy 290.358353 -214.418418) (xy 290.29901 -215.539574) (xy 292.538148 -215.539574)
			(xy 292.542219 -215.483952) (xy 292.554345 -215.429515) (xy 292.574268 -215.377424) (xy 292.601564 -215.328789)
			(xy 292.63565 -215.284646) (xy 292.675799 -215.245937) (xy 292.721157 -215.213486) (xy 292.770757 -215.187985)
			(xy 292.823541 -215.169978) (xy 292.878384 -215.159848) (xy 292.934118 -215.157811) (xy 292.989555 -215.163911)
			(xy 293.043512 -215.178017) (xy 293.094841 -215.199829) (xy 293.142447 -215.228883) (xy 293.185315 -215.264558)
			(xy 293.222532 -215.306095) (xy 293.253305 -215.352608) (xy 293.276977 -215.403105) (xy 293.293045 -215.456512)
			(xy 293.301165 -215.511688) (xy 293.301674 -215.539574) (xy 293.301165 -215.56746) (xy 293.293045 -215.622636)
			(xy 293.276977 -215.676043) (xy 293.253305 -215.72654) (xy 293.222532 -215.773053) (xy 293.185315 -215.81459)
			(xy 293.142447 -215.850265) (xy 293.094841 -215.879319) (xy 293.043512 -215.901131) (xy 292.989555 -215.915237)
			(xy 292.934118 -215.921337) (xy 292.878384 -215.9193) (xy 292.823541 -215.90917) (xy 292.770757 -215.891163)
			(xy 292.721157 -215.865662) (xy 292.675799 -215.833211) (xy 292.63565 -215.794502) (xy 292.601564 -215.750359)
			(xy 292.574268 -215.701724) (xy 292.554345 -215.649633) (xy 292.542219 -215.595196) (xy 292.538148 -215.539574)
			(xy 290.29901 -215.539574) (xy 289.943286 -222.26016) (xy 289.167824 -236.91088) (xy 289.167824 -236.911896)
			(xy 289.167973 -236.925372) (xy 289.174508 -236.951509) (xy 289.187653 -236.975025) (xy 289.206492 -236.994284)
			(xy 289.229714 -237.007942) (xy 289.255701 -237.01505) (xy 289.26917 -237.015528) (xy 291.605208 -237.015528)
			(xy 291.617003 -237.014854) (xy 291.638078 -237.004238) (xy 291.652238 -236.985362) (xy 291.654992 -236.973872)
			(xy 291.761164 -236.396022) (xy 293.847012 -225.048826) (xy 294.557958 -221.181676) (xy 294.558212 -221.180152)
			(xy 294.559208 -221.170935) (xy 294.555311 -221.152825) (xy 294.550592 -221.144846) (xy 294.545512 -221.136972)
			(xy 294.530018 -221.12605) (xy 294.520112 -221.12351) (xy 294.492859 -221.116264) (xy 294.440693 -221.094847)
			(xy 294.392244 -221.06599) (xy 294.348567 -221.030322) (xy 294.31061 -220.988618) (xy 294.2792 -220.941785)
			(xy 294.255019 -220.890841) (xy 294.238594 -220.836895) (xy 294.230282 -220.781119) (xy 294.22979 -220.752924)
			(xy 294.230252 -220.72567) (xy 294.238006 -220.671716) (xy 294.25336 -220.619416) (xy 294.276001 -220.569832)
			(xy 294.305468 -220.523976) (xy 294.341162 -220.48278) (xy 294.382355 -220.447084) (xy 294.428209 -220.417613)
			(xy 294.477791 -220.394969) (xy 294.530091 -220.379611) (xy 294.584044 -220.371854) (xy 294.611298 -220.371416)
			(xy 294.61206 -220.371416) (xy 294.623519 -220.371507) (xy 294.646395 -220.372907) (xy 294.65778 -220.37421)
			(xy 294.658034 -220.37421) (xy 294.667741 -220.374998) (xy 294.686556 -220.370033) (xy 294.69461 -220.364558)
			(xy 294.701976 -220.359224) (xy 294.706802 -220.351858) (xy 294.709252 -220.347664) (xy 294.7127 -220.338585)
			(xy 294.71366 -220.333824) (xy 294.888158 -219.385388) (xy 295.19626 -217.710258) (xy 295.41978 -216.493852)
			(xy 295.420077 -216.486671) (xy 295.417112 -216.472614) (xy 295.413938 -216.466166) (xy 295.410128 -216.4588)
			(xy 295.39819 -216.44737) (xy 295.390062 -216.44356) (xy 295.36552 -216.431765) (xy 295.319763 -216.402252)
			(xy 295.278664 -216.366538) (xy 295.243056 -216.325346) (xy 295.213661 -216.279513) (xy 295.191077 -216.229968)
			(xy 295.175762 -216.177717) (xy 295.168027 -216.123821) (xy 295.167558 -216.096596) (xy 295.168078 -216.067872)
			(xy 295.176689 -216.011073) (xy 295.193715 -215.956207) (xy 295.218773 -215.904512) (xy 295.251297 -215.857157)
			(xy 295.29055 -215.815211) (xy 295.335647 -215.779623) (xy 295.385568 -215.751196) (xy 295.439186 -215.730572)
			(xy 295.49529 -215.718218) (xy 295.52392 -215.71585) (xy 295.53281 -215.715342) (xy 295.548558 -215.708738)
			(xy 295.554654 -215.702896) (xy 295.560336 -215.697301) (xy 295.568233 -215.683459) (xy 295.570148 -215.675718)
			(xy 297.683936 -204.177646) (xy 297.684776 -204.172197) (xy 297.684386 -204.161181) (xy 297.683174 -204.155802)
			(xy 297.680634 -204.145896) (xy 297.673776 -204.13726) (xy 297.658257 -204.116993) (xy 297.632201 -204.073098)
			(xy 297.612233 -204.026119) (xy 297.598711 -203.976896) (xy 297.591877 -203.926309) (xy 297.59148 -203.900786)
			(xy 297.591559 -203.888048) (xy 297.593213 -203.862627) (xy 297.594782 -203.849986) (xy 297.599126 -203.821723)
			(xy 297.615114 -203.766823) (xy 297.639102 -203.714918) (xy 297.670554 -203.667165) (xy 297.708769 -203.62463)
			(xy 297.752894 -203.588263) (xy 297.777154 -203.573126) (xy 297.787314 -203.567284) (xy 297.795696 -203.562204)
			(xy 297.797474 -203.559664) (xy 298.009056 -202.408282) (xy 298.52112 -199.621902) (xy 298.522378 -199.612791)
			(xy 298.519113 -199.594704) (xy 298.51477 -199.586596) (xy 298.5135 -199.584564) (xy 298.498367 -199.560944)
			(xy 298.474444 -199.510208) (xy 298.458198 -199.456518) (xy 298.449981 -199.401029) (xy 298.449492 -199.372982)
			(xy 298.449929 -199.347046) (xy 298.45696 -199.295653) (xy 298.470889 -199.245686) (xy 298.49146 -199.198068)
			(xy 298.518293 -199.153676) (xy 298.550894 -199.113329) (xy 298.588661 -199.077771) (xy 298.609512 -199.06234)
			(xy 298.61764 -199.056498) (xy 298.62272 -199.04837) (xy 298.62533 -199.044146) (xy 298.629035 -199.034935)
			(xy 298.630086 -199.030082) (xy 298.72051 -198.538592) (xy 298.814998 -198.025004) (xy 298.815453 -198.020221)
			(xy 298.814809 -198.010636) (xy 298.813728 -198.005954) (xy 298.811188 -197.996302) (xy 298.804076 -197.987412)
			(xy 298.78829 -197.967028) (xy 298.761763 -197.92282) (xy 298.741422 -197.875446) (xy 298.727639 -197.825766)
			(xy 298.720664 -197.774684) (xy 298.720256 -197.748906) (xy 298.720765 -197.721001) (xy 298.728889 -197.665784)
			(xy 298.744964 -197.612339) (xy 298.768649 -197.561803) (xy 298.799438 -197.515254) (xy 298.836676 -197.473682)
			(xy 298.879569 -197.437974) (xy 298.903136 -197.423024) (xy 298.90847 -197.419976) (xy 298.908724 -197.419722)
			(xy 298.918122 -197.414134) (xy 298.923964 -197.405752) (xy 298.92699 -197.401176) (xy 298.931208 -197.391053)
			(xy 298.932346 -197.385686) (xy 300.467268 -189.035436) (xy 301.817024 -181.693566) (xy 305.558698 -161.340038)
			(xy 305.559206 -161.33699) (xy 306.107084 -156.740352) (xy 306.106322 -156.728922) (xy 306.105306 -156.72308)
			(xy 306.102258 -156.716222) (xy 306.102004 -156.715714) (xy 306.090798 -156.690406) (xy 306.074975 -156.637369)
			(xy 306.066956 -156.582605) (xy 306.066444 -156.554932) (xy 306.066698 -156.539184) (xy 306.06746 -156.53004)
			(xy 306.06746 -156.529532) (xy 306.070762 -156.499052) (xy 306.073589 -156.481397) (xy 306.082117 -156.44667)
			(xy 306.08778 -156.42971) (xy 306.099018 -156.399433) (xy 306.130178 -156.342872) (xy 306.149756 -156.317188)
			(xy 306.154582 -156.311346) (xy 306.157122 -156.304996) (xy 306.159916 -156.29509) (xy 306.250086 -155.538678)
			(xy 306.29733 -155.143454) (xy 306.297953 -155.13578) (xy 306.295117 -155.120655) (xy 306.291742 -155.113736)
			(xy 306.288186 -155.107132) (xy 306.277772 -155.096464) (xy 306.270406 -155.092654) (xy 306.244467 -155.07836)
			(xy 306.196962 -155.042995) (xy 306.155492 -155.000714) (xy 306.121054 -154.952532) (xy 306.094475 -154.899608)
			(xy 306.076393 -154.843212) (xy 306.067244 -154.7847) (xy 306.066698 -154.755088) (xy 306.067197 -154.727017)
			(xy 306.075429 -154.671482) (xy 306.091713 -154.617754) (xy 306.115698 -154.566993) (xy 306.146864 -154.520297)
			(xy 306.184539 -154.478674) (xy 306.227909 -154.443024) (xy 306.276037 -154.414116) (xy 306.327882 -154.392577)
			(xy 306.354988 -154.385264) (xy 306.362608 -154.383486) (xy 306.375562 -154.375612) (xy 306.380642 -154.36977)
			(xy 306.385454 -154.363764) (xy 306.391654 -154.349688) (xy 306.392834 -154.342084) (xy 306.744878 -151.39035)
			(xy 307.01107 -149.156166) (xy 307.011324 -149.152102) (xy 307.186838 -144.881092) (xy 307.211222 -144.287494)
			(xy 307.316886 -141.717014) (xy 307.316886 -141.716506) (xy 307.317648 -141.698472) (xy 307.317902 -141.695932)
			(xy 307.317902 -141.695424) (xy 307.320696 -141.628368) (xy 307.321966 -141.619224) (xy 307.336698 -141.555216)
			(xy 307.336698 -141.554962) (xy 307.33873 -141.546072) (xy 307.33873 -141.545564) (xy 307.341524 -141.533118)
			(xy 307.46573 -140.995654) (xy 307.465984 -140.993114) (xy 307.673756 -136.095232) (xy 307.753512 -134.216902)
			(xy 307.753512 -131.078478) (xy 307.753512 -131.076192) (xy 307.753766 -131.069588) (xy 307.753766 -131.069334)
			(xy 307.754274 -131.056888) (xy 308.283864 -118.147084) (xy 308.284626 -118.131082) (xy 308.284626 -118.13032)
			(xy 308.285642 -118.105936) (xy 308.285642 -118.105682) (xy 308.285896 -118.101618) (xy 308.385464 -117.327426)
			(xy 308.8513 -113.70818) (xy 308.863492 -113.613184) (xy 308.864202 -113.605751) (xy 308.861741 -113.591033)
			(xy 308.858666 -113.584228) (xy 308.855618 -113.577878) (xy 308.845204 -113.566956) (xy 308.837838 -113.562892)
			(xy 308.82082 -113.552732) (xy 308.819296 -113.551716) (xy 308.81701 -113.550446) (xy 308.815994 -113.549684)
			(xy 308.81574 -113.549684) (xy 308.809136 -113.545366) (xy 308.807612 -113.54435) (xy 308.807104 -113.543842)
			(xy 308.798214 -113.537492) (xy 308.777463 -113.521706) (xy 308.740026 -113.485418) (xy 308.707875 -113.444373)
			(xy 308.681607 -113.399336) (xy 308.661711 -113.351143) (xy 308.648558 -113.300692) (xy 308.645052 -113.274856)
			(xy 308.643782 -113.263172) (xy 308.642258 -113.229898) (xy 308.642782 -113.201387) (xy 308.651258 -113.144998)
			(xy 308.668037 -113.0905) (xy 308.692743 -113.039108) (xy 308.724826 -112.991968) (xy 308.763571 -112.950131)
			(xy 308.808114 -112.91453) (xy 308.857461 -112.885958) (xy 308.883812 -112.87506) (xy 308.89466 -112.870852)
			(xy 308.916772 -112.863605) (xy 308.928008 -112.860582) (xy 308.928262 -112.860582) (xy 308.930548 -112.860074)
			(xy 308.937186 -112.857758) (xy 308.948919 -112.850023) (xy 308.953662 -112.844834) (xy 308.958742 -112.839246)
			(xy 308.961536 -112.832896) (xy 308.963 -112.829483) (xy 308.965045 -112.822344) (xy 308.9656 -112.818672)
			(xy 309.99811 -104.796336) (xy 309.99811 -104.796082) (xy 310.00065 -104.777032) (xy 310.00065 -104.776016)
			(xy 310.002174 -104.76738) (xy 310.002428 -104.764332) (xy 310.021986 -104.611678) (xy 310.022717 -104.606818)
			(xy 310.025785 -104.597481) (xy 310.028082 -104.593136) (xy 310.110124 -104.44861) (xy 310.110632 -104.448102)
			(xy 310.12003 -104.431084) (xy 319.992502 -87.045292) (xy 319.993772 -87.043006) (xy 319.999649 -87.029532)
			(xy 320.004215 -87.000506) (xy 320.000335 -86.971379) (xy 319.98833 -86.94456) (xy 319.969192 -86.922264)
			(xy 319.944502 -86.906333) (xy 319.930526 -86.901782) (xy 319.904498 -86.893633) (xy 319.854887 -86.870979)
			(xy 319.809003 -86.841497) (xy 319.767782 -86.805786) (xy 319.73206 -86.764573) (xy 319.702567 -86.718697)
			(xy 319.6799 -86.669091) (xy 319.664522 -86.616765) (xy 319.656746 -86.562783) (xy 319.656206 -86.535514)
			(xy 319.65671 -86.507777) (xy 319.664752 -86.45289) (xy 319.680656 -86.399744) (xy 319.704085 -86.349461)
			(xy 319.734546 -86.303099) (xy 319.771398 -86.261635) (xy 319.813864 -86.225942) (xy 319.86105 -86.196772)
			(xy 319.911961 -86.17474) (xy 319.965525 -86.160311) (xy 319.99301 -86.156546) (xy 320.0146 -86.154006)
			(xy 320.020188 -86.153752) (xy 320.037714 -86.153752) (xy 320.065554 -86.154251) (xy 320.120646 -86.162332)
			(xy 320.173977 -86.178334) (xy 320.224416 -86.201919) (xy 320.270892 -86.232584) (xy 320.291968 -86.25078)
			(xy 320.292984 -86.251542) (xy 320.294508 -86.253066) (xy 320.304465 -86.262396) (xy 320.328174 -86.275883)
			(xy 320.354605 -86.282618) (xy 320.381877 -86.282122) (xy 320.395092 -86.27872) (xy 320.406553 -86.275025)
			(xy 320.427429 -86.263037) (xy 320.444887 -86.246463) (xy 320.451734 -86.236556) (xy 320.453258 -86.234016)
			(xy 320.504058 -86.144354) (xy 320.740024 -85.72881) (xy 320.743521 -85.720709) (xy 320.745326 -85.70317)
			(xy 320.74358 -85.69452) (xy 320.741548 -85.68563) (xy 320.730372 -85.669882) (xy 320.721736 -85.664294)
			(xy 320.69919 -85.649133) (xy 320.658225 -85.613443) (xy 320.622737 -85.572302) (xy 320.593446 -85.526543)
			(xy 320.570942 -85.477092) (xy 320.555682 -85.424947) (xy 320.547974 -85.371166) (xy 320.547492 -85.344)
			(xy 320.54794 -85.317562) (xy 320.555233 -85.265191) (xy 320.569679 -85.214326) (xy 320.591002 -85.165939)
			(xy 320.618794 -85.120956) (xy 320.652525 -85.080235) (xy 320.69155 -85.044556) (xy 320.735122 -85.0146)
			(xy 320.758566 -85.00237) (xy 320.75882 -85.002116) (xy 320.763621 -84.999588) (xy 320.77208 -84.992796)
			(xy 320.775584 -84.988654) (xy 320.776092 -84.988146) (xy 320.779387 -84.983883) (xy 320.784259 -84.974275)
			(xy 320.785744 -84.969096) (xy 320.80708 -84.884514) (xy 320.805556 -84.87664) (xy 320.789906 -84.856048)
			(xy 320.763614 -84.811508) (xy 320.743468 -84.763872) (xy 320.729824 -84.713983) (xy 320.722923 -84.662724)
			(xy 320.722498 -84.636864) (xy 320.722498 -84.63661) (xy 320.722954 -84.609712) (xy 320.730375 -84.556431)
			(xy 320.745075 -84.504684) (xy 320.755518 -84.479892) (xy 320.754248 -84.468716) (xy 320.707766 -84.399374)
			(xy 320.704464 -84.394548) (xy 320.700654 -84.390738) (xy 320.691256 -84.383626) (xy 320.665094 -84.368132)
			(xy 320.652648 -84.36737) (xy 320.623867 -84.36513) (xy 320.567415 -84.35307) (xy 320.513421 -84.332651)
			(xy 320.463116 -84.304337) (xy 320.417646 -84.268773) (xy 320.378047 -84.22677) (xy 320.345222 -84.179285)
			(xy 320.319919 -84.1274) (xy 320.302714 -84.072297) (xy 320.293999 -84.015233) (xy 320.293492 -83.98637)
			(xy 320.29398 -83.95912) (xy 320.30174 -83.905176) (xy 320.317098 -83.852885) (xy 320.33974 -83.803311)
			(xy 320.369207 -83.757464) (xy 320.404899 -83.716278) (xy 320.446088 -83.680589) (xy 320.491937 -83.651126)
			(xy 320.541513 -83.628487) (xy 320.593805 -83.613133) (xy 320.64775 -83.605378) (xy 320.675 -83.604862)
			(xy 320.701881 -83.605328) (xy 320.755109 -83.612887) (xy 320.80675 -83.627842) (xy 320.85578 -83.649896)
			(xy 320.90123 -83.678613) (xy 320.9422 -83.713424) (xy 320.977879 -83.753641) (xy 321.007561 -83.798467)
			(xy 321.030658 -83.847015) (xy 321.046713 -83.898324) (xy 321.055408 -83.951378) (xy 321.056508 -83.978242)
			(xy 321.056508 -83.98637) (xy 321.055805 -84.020178) (xy 321.043922 -84.08674) (xy 321.032886 -84.118704)
			(xy 321.032886 -84.118958) (xy 321.030972 -84.124656) (xy 321.029566 -84.136592) (xy 321.030092 -84.14258)
			(xy 321.031362 -84.15401) (xy 321.053206 -84.186776) (xy 321.053206 -84.187284) (xy 321.080892 -84.228178)
			(xy 321.083823 -84.231921) (xy 321.09086 -84.238311) (xy 321.094862 -84.240878) (xy 321.107816 -84.248244)
			(xy 321.120516 -84.248498) (xy 321.148816 -84.249754) (xy 321.204627 -84.259449) (xy 321.258439 -84.277142)
			(xy 321.309112 -84.302461) (xy 321.355573 -84.334868) (xy 321.376548 -84.353908) (xy 321.38761 -84.363628)
			(xy 321.413918 -84.376832) (xy 321.442899 -84.381984) (xy 321.472145 -84.378658) (xy 321.499229 -84.367129)
			(xy 321.521899 -84.348354) (xy 321.530472 -84.336382) (xy 321.530726 -84.336128) (xy 321.533266 -84.33181)
			(xy 324.295262 -79.468218) (xy 324.297548 -79.464154) (xy 324.304152 -79.45247) (xy 324.329552 -79.407766)
			(xy 324.356476 -79.360522) (xy 324.356984 -79.359506) (xy 324.358876 -79.355959) (xy 324.363596 -79.34945)
			(xy 324.366382 -79.346552) (xy 324.45198 -79.2607) (xy 324.456298 -79.256382) (xy 326.647302 -77.060298)
			(xy 326.647556 -77.060044) (xy 326.660002 -77.047344) (xy 326.661526 -77.046074) (xy 326.673464 -77.034136)
			(xy 326.694176 -77.013669) (xy 326.737637 -76.974909) (xy 326.760332 -76.956666) (xy 330.94041 -73.655428)
			(xy 330.940918 -73.65492) (xy 331.176376 -73.461626) (xy 331.17663 -73.461372) (xy 331.18171 -73.457308)
			(xy 334.050132 -69.279262) (xy 334.056406 -69.268897) (xy 334.059451 -69.244895) (xy 334.055974 -69.233288)
			(xy 334.032098 -69.166486) (xy 334.029865 -69.160897) (xy 334.023187 -69.150888) (xy 334.01889 -69.146674)
			(xy 334.018636 -69.14642) (xy 333.994506 -69.124068) (xy 333.986886 -69.121528) (xy 333.98333 -69.120512)
			(xy 333.968344 -69.115432) (xy 333.94396 -69.10578) (xy 333.928696 -69.098847) (xy 333.899318 -69.082695)
			(xy 333.885286 -69.073522) (xy 333.854806 -69.050662) (xy 333.846648 -69.043874) (xy 333.831016 -69.029517)
			(xy 333.823564 -69.02196) (xy 333.816706 -69.014848) (xy 333.789528 -69.002656) (xy 333.781908 -69.000116)
			(xy 333.768954 -68.998338) (xy 333.715614 -68.998338) (xy 333.71536 -68.998338) (xy 333.710812 -68.998459)
			(xy 333.701867 -69.000116) (xy 333.69758 -69.00164) (xy 333.677514 -69.01053) (xy 333.673065 -69.012621)
			(xy 333.665003 -69.018245) (xy 333.661512 -69.021706) (xy 333.643418 -69.03976) (xy 333.603273 -69.071398)
			(xy 333.559274 -69.097412) (xy 333.512204 -69.117337) (xy 333.4629 -69.13082) (xy 333.412241 -69.137621)
			(xy 333.386684 -69.138038) (xy 333.361173 -69.137612) (xy 333.310606 -69.130815) (xy 333.261395 -69.117345)
			(xy 333.214416 -69.097441) (xy 333.170506 -69.071457) (xy 333.15021 -69.055996) (xy 333.147162 -69.053456)
			(xy 333.145638 -69.05244) (xy 333.139034 -69.049138) (xy 333.133812 -69.046793) (xy 333.122658 -69.044226)
			(xy 333.116936 -69.044058) (xy 333.084932 -69.044058) (xy 333.084932 -69.032882) (xy 333.034132 -69.032882)
			(xy 333.025528 -69.033217) (xy 333.009297 -69.038928) (xy 333.002382 -69.044058) (xy 333.000858 -69.045328)
			(xy 332.979981 -69.062722) (xy 332.934232 -69.09204) (xy 332.884784 -69.114568) (xy 332.832639 -69.129849)
			(xy 332.778853 -69.137574) (xy 332.751684 -69.138038) (xy 332.724433 -69.137551) (xy 332.670485 -69.129793)
			(xy 332.618191 -69.114437) (xy 332.568613 -69.091795) (xy 332.522763 -69.062329) (xy 332.481572 -69.026638)
			(xy 332.44588 -68.985448) (xy 332.416412 -68.939599) (xy 332.393768 -68.890023) (xy 332.37841 -68.837729)
			(xy 332.37065 -68.783781) (xy 332.370176 -68.75653) (xy 332.370599 -68.731018) (xy 332.377389 -68.680447)
			(xy 332.390852 -68.631231) (xy 332.410748 -68.584246) (xy 332.436724 -68.540328) (xy 332.452218 -68.520056)
			(xy 332.454758 -68.517008) (xy 332.455774 -68.515484) (xy 332.459076 -68.50888) (xy 332.461415 -68.503656)
			(xy 332.463969 -68.492503) (xy 332.464156 -68.486782) (xy 332.464156 -68.454778) (xy 332.475332 -68.454778)
			(xy 332.475332 -68.403978) (xy 332.475003 -68.395373) (xy 332.469296 -68.379137) (xy 332.464156 -68.372228)
			(xy 332.462886 -68.370704) (xy 332.445495 -68.349827) (xy 332.416182 -68.304076) (xy 332.39366 -68.254627)
			(xy 332.378386 -68.202483) (xy 332.370669 -68.148698) (xy 332.370176 -68.12153) (xy 332.370637 -68.094275)
			(xy 332.37839 -68.04032) (xy 332.393743 -67.988018) (xy 332.416384 -67.938433) (xy 332.445851 -67.892575)
			(xy 332.481545 -67.851377) (xy 332.522738 -67.815679) (xy 332.568592 -67.786206) (xy 332.618175 -67.76356)
			(xy 332.670475 -67.7482) (xy 332.724429 -67.74044) (xy 332.751684 -67.740022) (xy 332.777196 -67.740446)
			(xy 332.827765 -67.747238) (xy 332.876979 -67.760704) (xy 332.923962 -67.780604) (xy 332.967877 -67.806582)
			(xy 332.988158 -67.822064) (xy 332.991206 -67.824604) (xy 332.99273 -67.82562) (xy 332.999334 -67.828922)
			(xy 333.004556 -67.831268) (xy 333.01571 -67.833839) (xy 333.021432 -67.834002) (xy 333.053436 -67.834002)
			(xy 333.053436 -67.845178) (xy 333.104236 -67.845178) (xy 333.112841 -67.844847) (xy 333.129077 -67.839141)
			(xy 333.135986 -67.834002) (xy 333.13751 -67.832732) (xy 333.158389 -67.815344) (xy 333.204141 -67.786036)
			(xy 333.25359 -67.76352) (xy 333.305734 -67.74825) (xy 333.359517 -67.740536) (xy 333.386684 -67.740022)
			(xy 333.412241 -67.740446) (xy 333.4629 -67.747246) (xy 333.512203 -67.760728) (xy 333.559274 -67.780652)
			(xy 333.603274 -67.806662) (xy 333.643421 -67.838298) (xy 333.661512 -67.856354) (xy 333.665009 -67.859808)
			(xy 333.67307 -67.86543) (xy 333.677514 -67.86753) (xy 333.69758 -67.87642) (xy 333.701866 -67.87795)
			(xy 333.710811 -67.879617) (xy 333.71536 -67.879722) (xy 333.768954 -67.879722) (xy 333.769208 -67.879722)
			(xy 333.773755 -67.879594) (xy 333.782695 -67.877926) (xy 333.786988 -67.87642) (xy 333.807054 -67.86753)
			(xy 333.811498 -67.865432) (xy 333.819549 -67.859798) (xy 333.823056 -67.856354) (xy 333.84115 -67.8383)
			(xy 333.881296 -67.806662) (xy 333.925295 -67.780647) (xy 333.972365 -67.76072) (xy 334.021668 -67.747234)
			(xy 334.072327 -67.74043) (xy 334.097884 -67.740022) (xy 334.125137 -67.740484) (xy 334.179088 -67.74824)
			(xy 334.231386 -67.763595) (xy 334.280966 -67.786237) (xy 334.326819 -67.815705) (xy 334.368011 -67.851399)
			(xy 334.403704 -67.892592) (xy 334.43317 -67.938446) (xy 334.45581 -67.988027) (xy 334.471163 -68.040326)
			(xy 334.478917 -68.094277) (xy 334.479392 -68.12153) (xy 334.478965 -68.147041) (xy 334.472168 -68.197607)
			(xy 334.458697 -68.246819) (xy 334.438794 -68.293798) (xy 334.412812 -68.337709) (xy 334.39735 -68.358004)
			(xy 334.39481 -68.361052) (xy 334.393794 -68.362576) (xy 334.390492 -68.36918) (xy 334.38815 -68.374403)
			(xy 334.385589 -68.385557) (xy 334.385412 -68.391278) (xy 334.385412 -68.423282) (xy 334.374236 -68.423282)
			(xy 334.374236 -68.474082) (xy 334.374574 -68.482684) (xy 334.380294 -68.498909) (xy 334.385412 -68.505832)
			(xy 334.386682 -68.507356) (xy 334.391254 -68.51269) (xy 334.391508 -68.512944) (xy 334.392778 -68.514468)
			(xy 334.403446 -68.527676) (xy 334.403446 -68.528184) (xy 334.403954 -68.528438) (xy 334.407612 -68.532981)
			(xy 334.416588 -68.540426) (xy 334.421734 -68.54317) (xy 334.427068 -68.54571) (xy 334.438752 -68.54825)
			(xy 334.468216 -68.547742) (xy 334.527398 -68.546218) (xy 334.539431 -68.54532) (xy 334.560655 -68.533917)
			(xy 334.568038 -68.524374) (xy 334.887824 -68.058792) (xy 334.887824 -68.058284) (xy 334.905604 -68.032122)
			(xy 334.911379 -68.022722) (xy 334.915054 -68.000994) (xy 334.912716 -67.990212) (xy 334.89265 -67.91579)
			(xy 334.889602 -67.907662) (xy 334.865218 -67.883278) (xy 334.857598 -67.879468) (xy 334.834105 -67.86728)
			(xy 334.790431 -67.837389) (xy 334.751309 -67.801746) (xy 334.717492 -67.761036) (xy 334.689628 -67.716041)
			(xy 334.668254 -67.667625) (xy 334.65378 -67.616719) (xy 334.646484 -67.5643) (xy 334.646016 -67.537838)
			(xy 334.646477 -67.510584) (xy 334.654229 -67.45663) (xy 334.669582 -67.404329) (xy 334.692223 -67.354746)
			(xy 334.72169 -67.30889) (xy 334.757384 -67.267694) (xy 334.798578 -67.231999) (xy 334.844434 -67.20253)
			(xy 334.894016 -67.179887) (xy 334.946317 -67.164532) (xy 335.00027 -67.156778) (xy 335.027524 -67.15633)
			(xy 335.053808 -67.156782) (xy 335.105874 -67.164034) (xy 335.156446 -67.178383) (xy 335.204561 -67.199556)
			(xy 335.227168 -67.212972) (xy 335.227676 -67.212972) (xy 335.22793 -67.213226) (xy 335.233148 -67.216168)
			(xy 335.244574 -67.21975) (xy 335.250536 -67.220338) (xy 335.262728 -67.221354) (xy 335.350866 -67.182492)
			(xy 335.3615 -67.177138) (xy 335.376718 -67.158864) (xy 335.380076 -67.14744) (xy 336.697828 -60.311792)
			(xy 337.382866 -56.758332) (xy 337.384244 -56.748781) (xy 337.380601 -56.729845) (xy 337.375754 -56.721502)
			(xy 337.372706 -56.716676) (xy 337.368642 -56.710326) (xy 337.361022 -56.701436) (xy 337.360514 -56.700928)
			(xy 337.355434 -56.696356) (xy 337.331717 -56.684235) (xy 337.287595 -56.654402) (xy 337.248049 -56.618723)
			(xy 337.213847 -56.577894) (xy 337.185654 -56.532706) (xy 337.164018 -56.484037) (xy 337.149358 -56.432832)
			(xy 337.141959 -56.380087) (xy 337.141566 -56.353456) (xy 337.142037 -56.326362) (xy 337.149698 -56.272719)
			(xy 337.164874 -56.220701) (xy 337.187258 -56.171353) (xy 337.216401 -56.12567) (xy 337.251716 -56.084571)
			(xy 337.292492 -56.048884) (xy 337.337908 -56.019327) (xy 337.362292 -56.007508) (xy 337.362546 -56.007508)
			(xy 337.370934 -56.003143) (xy 337.383964 -55.989459) (xy 337.391161 -55.971988) (xy 337.391756 -55.96255)
			(xy 337.383882 -55.48503) (xy 337.383516 -55.478107) (xy 337.379534 -55.464835) (xy 337.376008 -55.458868)
			(xy 337.359244 -55.432452) (xy 337.349592 -55.423562) (xy 337.34375 -55.420514) (xy 337.317946 -55.406165)
			(xy 337.270711 -55.370745) (xy 337.229492 -55.328475) (xy 337.195273 -55.280363) (xy 337.168871 -55.227556)
			(xy 337.150913 -55.171313) (xy 337.14183 -55.112976) (xy 337.141312 -55.083456) (xy 337.142582 -55.052976)
			(xy 337.144106 -55.038498) (xy 337.147655 -55.012451) (xy 337.160984 -54.961602) (xy 337.181166 -54.913064)
			(xy 337.207818 -54.867754) (xy 337.240435 -54.82653) (xy 337.278401 -54.790173) (xy 337.320998 -54.759369)
			(xy 337.344004 -54.746652) (xy 337.347052 -54.744874) (xy 337.354099 -54.740124) (xy 337.36479 -54.726925)
			(xy 337.370549 -54.710945) (xy 337.370928 -54.702456) (xy 337.36915 -54.597046) (xy 337.366864 -54.443884)
			(xy 337.366042 -54.435367) (xy 337.359474 -54.419579) (xy 337.348059 -54.406846) (xy 337.340702 -54.402482)
			(xy 337.340448 -54.402482) (xy 337.315053 -54.38801) (xy 337.268596 -54.352542) (xy 337.228095 -54.310402)
			(xy 337.194498 -54.262574) (xy 337.168593 -54.210181) (xy 337.150985 -54.154447) (xy 337.142089 -54.09668)
			(xy 337.141566 -54.067456) (xy 337.142085 -54.039142) (xy 337.150464 -53.983138) (xy 337.16703 -53.928988)
			(xy 337.191419 -53.877883) (xy 337.223097 -53.830945) (xy 337.261366 -53.789206) (xy 337.305385 -53.753583)
			(xy 337.329526 -53.73878) (xy 337.335382 -53.735087) (xy 337.345034 -53.725171) (xy 337.348576 -53.719222)
			(xy 337.35137 -53.714142) (xy 337.354418 -53.701188) (xy 337.354164 -53.683154) (xy 337.349846 -53.4162)
			(xy 337.349106 -53.410634) (xy 337.345513 -53.399998) (xy 337.342734 -53.395118) (xy 337.325716 -53.3781)
			(xy 337.323176 -53.376576) (xy 337.298995 -53.361101) (xy 337.255148 -53.324044) (xy 337.217351 -53.280833)
			(xy 337.186458 -53.232446) (xy 337.163167 -53.179974) (xy 337.148004 -53.124604) (xy 337.144106 -53.09616)
			(xy 337.14309 -53.08727) (xy 337.141566 -53.051456) (xy 337.142035 -53.024351) (xy 337.149686 -52.970683)
			(xy 337.164844 -52.918635) (xy 337.187203 -52.869251) (xy 337.216315 -52.823521) (xy 337.251596 -52.782363)
			(xy 337.292338 -52.746602) (xy 337.314794 -52.731416) (xy 337.319366 -52.728114) (xy 337.32724 -52.72151)
			(xy 337.331812 -52.712874) (xy 337.334722 -52.707073) (xy 337.337809 -52.694471) (xy 337.337908 -52.687982)
			(xy 337.332828 -52.386484) (xy 337.332828 -52.38115) (xy 337.32089 -52.359306) (xy 337.316826 -52.356512)
			(xy 337.294165 -52.341357) (xy 337.25298 -52.305643) (xy 337.217292 -52.264434) (xy 337.187829 -52.218568)
			(xy 337.165189 -52.168978) (xy 337.149832 -52.116671) (xy 337.14207 -52.062713) (xy 337.141566 -52.035456)
			(xy 337.141997 -52.009623) (xy 337.14897 -51.95843) (xy 337.162782 -51.908644) (xy 337.183181 -51.861176)
			(xy 337.209795 -51.816891) (xy 337.242137 -51.7766) (xy 337.279617 -51.741038) (xy 337.300316 -51.725576)
			(xy 337.30057 -51.725322) (xy 337.30534 -51.721667) (xy 337.31317 -51.712554) (xy 337.316064 -51.707288)
			(xy 337.318858 -51.7017) (xy 337.321652 -51.689762) (xy 337.318096 -51.469036) (xy 337.316064 -51.363118)
			(xy 337.314735 -51.352328) (xy 337.304347 -51.333251) (xy 337.295998 -51.326288) (xy 337.295744 -51.326034)
			(xy 337.272267 -51.30788) (xy 337.230688 -51.265537) (xy 337.196152 -51.217276) (xy 337.169491 -51.164258)
			(xy 337.151345 -51.107756) (xy 337.142149 -51.049128) (xy 337.141566 -51.019456) (xy 337.142075 -50.990792)
			(xy 337.150635 -50.934106) (xy 337.167571 -50.879336) (xy 337.192502 -50.827713) (xy 337.224869 -50.780396)
			(xy 337.263945 -50.738448) (xy 337.286092 -50.720244) (xy 337.29041 -50.716688) (xy 337.297522 -50.707798)
			(xy 337.300062 -50.702464) (xy 337.302388 -50.697111) (xy 337.304814 -50.685695) (xy 337.304888 -50.679858)
			(xy 337.301332 -50.451766) (xy 337.298538 -50.288698) (xy 337.297142 -50.278374) (xy 337.2873 -50.260033)
			(xy 337.279488 -50.253138) (xy 337.279234 -50.252884) (xy 337.25693 -50.234689) (xy 337.217532 -50.192728)
			(xy 337.184883 -50.145325) (xy 337.159724 -50.093555) (xy 337.142628 -50.038595) (xy 337.13398 -49.981689)
			(xy 337.133438 -49.95291) (xy 337.133936 -49.925171) (xy 337.141973 -49.870279) (xy 337.157879 -49.81713)
			(xy 337.181318 -49.766847) (xy 337.211795 -49.72049) (xy 337.248668 -49.679039) (xy 337.269582 -49.66081)
			(xy 337.2739 -49.657254) (xy 337.280758 -49.64811) (xy 337.283298 -49.64303) (xy 337.285431 -49.637831)
			(xy 337.287599 -49.626806) (xy 337.287616 -49.621186) (xy 337.2866 -49.558448) (xy 337.281266 -49.258474)
			(xy 337.280055 -49.248848) (xy 337.271428 -49.231487) (xy 337.264502 -49.224692) (xy 337.264248 -49.224438)
			(xy 337.2441 -49.206232) (xy 337.208646 -49.1651) (xy 337.179381 -49.119358) (xy 337.156895 -49.06993)
			(xy 337.141641 -49.017813) (xy 337.133929 -48.964061) (xy 337.133438 -48.93691) (xy 337.133867 -48.910793)
			(xy 337.140998 -48.859048) (xy 337.155128 -48.808762) (xy 337.175992 -48.760876) (xy 337.2032 -48.716288)
			(xy 337.236242 -48.675832) (xy 337.255104 -48.657764) (xy 337.255612 -48.657256) (xy 337.262307 -48.650312)
			(xy 337.270402 -48.632819) (xy 337.27136 -48.62322) (xy 337.259168 -47.891954) (xy 337.256882 -47.750476)
			(xy 337.256374 -47.709836) (xy 337.25618 -47.705545) (xy 337.254516 -47.697118) (xy 337.253072 -47.693072)
			(xy 337.250532 -47.686214) (xy 337.245198 -47.679356) (xy 337.229535 -47.659008) (xy 337.20323 -47.614907)
			(xy 337.183073 -47.567678) (xy 337.16943 -47.518174) (xy 337.162545 -47.467287) (xy 337.16214 -47.441612)
			(xy 337.162739 -47.411077) (xy 337.17246 -47.350786) (xy 337.191654 -47.292811) (xy 337.219834 -47.238631)
			(xy 337.237578 -47.213774) (xy 337.242658 -47.206916) (xy 337.245198 -47.199296) (xy 337.246381 -47.195276)
			(xy 337.247536 -47.186976) (xy 337.247484 -47.182786) (xy 337.23072 -46.161198) (xy 337.230361 -46.153366)
			(xy 337.225452 -46.138487) (xy 337.221068 -46.131988) (xy 337.21929 -46.129956) (xy 337.203118 -46.109459)
			(xy 337.175942 -46.064879) (xy 337.155104 -46.017007) (xy 337.140997 -45.966739) (xy 337.133882 -45.915015)
			(xy 337.133438 -45.88891) (xy 337.13384 -45.864036) (xy 337.140307 -45.814711) (xy 337.153133 -45.766646)
			(xy 337.1721 -45.720656) (xy 337.196886 -45.677523) (xy 337.21167 -45.657516) (xy 337.217004 -45.650404)
			(xy 337.219544 -45.642784) (xy 337.220727 -45.638764) (xy 337.221881 -45.630464) (xy 337.22183 -45.626274)
			(xy 337.213702 -45.1231) (xy 337.21327 -45.115488) (xy 337.2085 -45.101016) (xy 337.204304 -45.094652)
			(xy 337.204304 -45.094398) (xy 337.187602 -45.07001) (xy 337.161129 -45.017163) (xy 337.143125 -44.960865)
			(xy 337.134021 -44.902464) (xy 337.133438 -44.87291) (xy 337.133438 -44.872656) (xy 337.133926 -44.844681)
			(xy 337.1421 -44.789331) (xy 337.158279 -44.735771) (xy 337.182116 -44.685152) (xy 337.197192 -44.661582)
			(xy 337.20151 -44.655232) (xy 337.203796 -44.647612) (xy 337.204794 -44.643948) (xy 337.20582 -44.636423)
			(xy 337.205828 -44.632626) (xy 337.19643 -44.080938) (xy 337.194652 -44.067984) (xy 337.192874 -44.061634)
			(xy 337.191858 -44.06011) (xy 337.189064 -44.055538) (xy 337.175886 -44.032986) (xy 337.155094 -43.98507)
			(xy 337.141009 -43.934772) (xy 337.133893 -43.883026) (xy 337.133438 -43.85691) (xy 337.133438 -43.842178)
			(xy 337.1352 -43.811807) (xy 337.147165 -43.752164) (xy 337.168457 -43.69518) (xy 337.182968 -43.668442)
			(xy 337.18627 -43.6626) (xy 337.187794 -43.657012) (xy 337.188758 -43.653471) (xy 337.189776 -43.646204)
			(xy 337.189826 -43.642534) (xy 337.186016 -43.422316) (xy 337.179412 -43.02887) (xy 337.176618 -43.017694)
			(xy 337.174078 -43.012614) (xy 337.161858 -42.987181) (xy 337.144198 -42.933593) (xy 337.1346 -42.877992)
			(xy 337.133438 -42.8498) (xy 337.133184 -42.837608) (xy 334.372204 -37.702744) (xy 334.372204 -37.70249)
			(xy 334.362044 -37.683694) (xy 333.855822 -36.755324) (xy 333.793592 -36.641024) (xy 333.779368 -36.614862)
			(xy 333.772764 -36.605464) (xy 333.761588 -36.592764) (xy 333.757016 -36.589462) (xy 333.728935 -36.568771)
			(xy 333.675419 -36.524026) (xy 333.650082 -36.500054) (xy 333.613227 -36.463695) (xy 333.546446 -36.384576)
			(xy 333.488231 -36.298958) (xy 333.463138 -36.253674) (xy 333.44358 -36.217098) (xy 333.440024 -36.21278)
			(xy 333.43977 -36.212526) (xy 333.406888 -36.173042) (xy 333.348601 -36.088416) (xy 333.323438 -36.043616)
			(xy 333.167736 -35.757866) (xy 333.111856 -35.655504) (xy 333.088653 -35.61169) (xy 333.05014 -35.520327)
			(xy 333.020977 -35.425564) (xy 333.001459 -35.328356) (xy 332.996032 -35.279076) (xy 332.995778 -35.277044)
			(xy 332.994274 -35.268349) (xy 332.986086 -35.25273) (xy 332.979776 -35.246564) (xy 332.978506 -35.245548)
			(xy 332.974188 -35.24123) (xy 332.97113 -35.238676) (xy 332.964365 -35.234469) (xy 332.960726 -35.232848)
			(xy 332.952598 -35.229546) (xy 332.944724 -35.22726) (xy 332.871826 -35.22726) (xy 332.866949 -35.227358)
			(xy 332.857361 -35.229151) (xy 332.852776 -35.230816) (xy 332.84414 -35.234372) (xy 332.836774 -35.241484)
			(xy 332.805903 -35.270423) (xy 332.740039 -35.323556) (xy 332.66991 -35.370917) (xy 332.596018 -35.412163)
			(xy 332.518897 -35.446997) (xy 332.439101 -35.47517) (xy 332.357204 -35.496478) (xy 332.273795 -35.510768)
			(xy 332.189476 -35.517938) (xy 332.147164 -35.518344) (xy 332.100636 -35.517792) (xy 332.007987 -35.509094)
			(xy 331.916551 -35.491806) (xy 331.827122 -35.466077) (xy 331.740478 -35.43213) (xy 331.657373 -35.390262)
			(xy 331.578528 -35.340837) (xy 331.504628 -35.284283) (xy 331.436317 -35.221092) (xy 331.374188 -35.151814)
			(xy 331.318781 -35.07705) (xy 331.294232 -35.037522) (xy 331.291692 -35.033712) (xy 331.281278 -35.021774)
			(xy 331.279754 -35.020504) (xy 331.25713 -35.002319) (xy 331.217126 -34.960261) (xy 331.183955 -34.912631)
			(xy 331.15838 -34.860525) (xy 331.140992 -34.805147) (xy 331.132193 -34.747774) (xy 331.131672 -34.718752)
			(xy 331.131672 -34.718498) (xy 331.132135 -34.689997) (xy 331.140553 -34.633623) (xy 331.148436 -34.60623)
			(xy 331.14996 -34.599118) (xy 331.151738 -34.588196) (xy 331.151738 -34.58464) (xy 331.151484 -34.581846)
			(xy 331.150976 -34.567622) (xy 331.150976 -34.566606) (xy 331.14996 -34.520886) (xy 331.150395 -34.4783)
			(xy 331.157636 -34.393435) (xy 331.172089 -34.309498) (xy 331.19365 -34.227099) (xy 331.22216 -34.14684)
			(xy 331.239368 -34.107882) (xy 331.242546 -34.098749) (xy 331.242541 -34.079426) (xy 331.239368 -34.07029)
			(xy 331.22216 -34.031334) (xy 331.193666 -33.95107) (xy 331.172115 -33.86867) (xy 331.157663 -33.784734)
			(xy 331.150416 -33.699872) (xy 331.14996 -33.657286) (xy 331.151738 -33.595818) (xy 331.1525 -33.583626)
			(xy 331.150468 -33.578038) (xy 331.145642 -33.56864) (xy 331.137514 -33.55721) (xy 331.095858 -33.513014)
			(xy 331.088411 -33.505786) (xy 331.069394 -33.49753) (xy 331.059028 -33.497012) (xy 330.894182 -33.497012)
			(xy 330.84662 -33.496427) (xy 330.751937 -33.487256) (xy 330.658573 -33.46904) (xy 330.567387 -33.441946)
			(xy 330.523088 -33.424622) (xy 330.519786 -33.423352) (xy 330.513436 -33.420812) (xy 330.229464 -33.420812)
			(xy 330.22794 -33.420812) (xy 330.21941 -33.421398) (xy 330.203449 -33.427502) (xy 330.196698 -33.43275)
			(xy 330.165802 -33.461862) (xy 330.099839 -33.51531) (xy 330.029572 -33.562957) (xy 329.955508 -33.604458)
			(xy 329.878185 -33.639513) (xy 329.798163 -33.667869) (xy 329.716019 -33.68932) (xy 329.632349 -33.70371)
			(xy 329.547759 -33.710936) (xy 329.50531 -33.711388) (xy 329.505056 -33.711388) (xy 329.462225 -33.710933)
			(xy 329.376879 -33.703589) (xy 329.292477 -33.688951) (xy 329.209642 -33.667127) (xy 329.128984 -33.638277)
			(xy 329.051099 -33.602614) (xy 328.97656 -33.560401) (xy 328.905917 -33.51195) (xy 328.839691 -33.457617)
			(xy 328.77837 -33.397804) (xy 328.722406 -33.33295) (xy 328.672212 -33.263535) (xy 328.649838 -33.22701)
			(xy 328.647333 -33.22319) (xy 328.641198 -33.216421) (xy 328.637646 -33.213548) (xy 328.615025 -33.195361)
			(xy 328.575029 -33.153302) (xy 328.541865 -33.10567) (xy 328.516298 -33.053564) (xy 328.498919 -32.998187)
			(xy 328.490128 -32.940816) (xy 328.489564 -32.911796) (xy 328.489564 -32.911542) (xy 328.490068 -32.883107)
			(xy 328.498485 -32.826865) (xy 328.506328 -32.799528) (xy 328.507852 -32.792416) (xy 328.50963 -32.781494)
			(xy 328.50963 -32.777938) (xy 328.509376 -32.775144) (xy 328.508868 -32.76092) (xy 328.508868 -32.759904)
			(xy 328.507852 -32.714184) (xy 328.508287 -32.671598) (xy 328.515528 -32.586733) (xy 328.529982 -32.502796)
			(xy 328.551542 -32.420397) (xy 328.580053 -32.340138) (xy 328.59726 -32.30118) (xy 328.600438 -32.292047)
			(xy 328.600433 -32.272724) (xy 328.59726 -32.263588) (xy 328.580052 -32.224632) (xy 328.551559 -32.144368)
			(xy 328.530008 -32.061968) (xy 328.515556 -31.978032) (xy 328.508309 -31.89317) (xy 328.507852 -31.850584)
			(xy 328.508868 -31.804864) (xy 328.508868 -31.803848) (xy 328.509376 -31.789624) (xy 328.50963 -31.78683)
			(xy 328.50963 -31.783274) (xy 328.507852 -31.772352) (xy 328.506328 -31.76524) (xy 328.4985 -31.7379)
			(xy 328.490079 -31.68166) (xy 328.489564 -31.653226) (xy 328.489564 -31.652972) (xy 328.490109 -31.623952)
			(xy 328.498906 -31.566583) (xy 328.516292 -31.511209) (xy 328.541868 -31.459108) (xy 328.575041 -31.411483)
			(xy 328.615046 -31.369434) (xy 328.637646 -31.35122) (xy 328.641214 -31.348364) (xy 328.647349 -31.341591)
			(xy 328.649838 -31.337758) (xy 328.672256 -31.301261) (xy 328.722447 -31.231846) (xy 328.778407 -31.166992)
			(xy 328.839724 -31.107178) (xy 328.905946 -31.052843) (xy 328.976585 -31.004389) (xy 329.051119 -30.962173)
			(xy 329.129 -30.926506) (xy 329.209653 -30.89765) (xy 329.292484 -30.87582) (xy 329.376883 -30.861175)
			(xy 329.462226 -30.853823) (xy 329.505056 -30.85338) (xy 329.50531 -30.85338) (xy 329.547761 -30.853818)
			(xy 329.632356 -30.86103) (xy 329.716031 -30.87541) (xy 329.798181 -30.896854) (xy 329.878209 -30.925206)
			(xy 329.955536 -30.960261) (xy 330.029602 -31.001764) (xy 330.099871 -31.049416) (xy 330.165832 -31.102871)
			(xy 330.196698 -31.132018) (xy 330.203443 -31.137273) (xy 330.219409 -31.143363) (xy 330.22794 -31.143956)
			(xy 331.076554 -31.143956) (xy 331.082904 -31.143448) (xy 331.091403 -31.142077) (xy 331.106827 -31.134457)
			(xy 331.118849 -31.12215) (xy 331.122782 -31.114492) (xy 331.132434 -31.091124) (xy 331.13345 -31.080964)
			(xy 331.13345 -31.080456) (xy 331.135734 -31.060694) (xy 331.143879 -31.021753) (xy 331.149706 -31.002732)
			(xy 331.15096 -30.998274) (xy 331.15198 -30.989069) (xy 331.151738 -30.984444) (xy 331.151738 -30.983936)
			(xy 331.150852 -30.96814) (xy 331.149962 -30.936511) (xy 331.14996 -30.92069) (xy 331.150395 -30.878103)
			(xy 331.157636 -30.793239) (xy 331.172089 -30.709301) (xy 331.193649 -30.626903) (xy 331.222159 -30.546643)
			(xy 331.239368 -30.507686) (xy 331.242547 -30.498553) (xy 331.242544 -30.479229) (xy 331.239368 -30.470094)
			(xy 331.222159 -30.431138) (xy 331.193665 -30.350874) (xy 331.172114 -30.268474) (xy 331.157662 -30.184538)
			(xy 331.150414 -30.099676) (xy 331.14996 -30.05709) (xy 331.150214 -30.030166) (xy 331.150214 -30.029912)
			(xy 331.150036 -30.020569) (xy 331.143791 -30.002973) (xy 331.138022 -29.995622) (xy 331.09154 -29.948124)
			(xy 331.085141 -29.942778) (xy 331.069847 -29.936163) (xy 331.061568 -29.93517) (xy 331.05725 -29.934916)
			(xy 330.980288 -29.934916) (xy 330.933541 -29.93435) (xy 330.840469 -29.925478) (xy 330.748652 -29.90785)
			(xy 330.658911 -29.881626) (xy 330.57205 -29.84704) (xy 330.5302 -29.826204) (xy 330.524774 -29.823616)
			(xy 330.513095 -29.820782) (xy 330.507086 -29.820616) (xy 330.239116 -29.820616) (xy 330.234226 -29.820756)
			(xy 330.224636 -29.82268) (xy 330.220066 -29.824426) (xy 330.194666 -29.834586) (xy 330.194412 -29.83484)
			(xy 330.193142 -29.83611) (xy 330.187808 -29.84119) (xy 330.153245 -29.872923) (xy 330.079123 -29.930467)
			(xy 329.999925 -29.980794) (xy 329.916349 -30.023459) (xy 329.829135 -30.058086) (xy 329.739055 -30.084368)
			(xy 329.646904 -30.102073) (xy 329.553497 -30.111044) (xy 329.50658 -30.1117) (xy 329.505056 -30.1117)
			(xy 329.458529 -30.111148) (xy 329.365881 -30.102449) (xy 329.274446 -30.085159) (xy 329.185019 -30.059429)
			(xy 329.098376 -30.025481) (xy 329.015273 -29.983612) (xy 328.93643 -29.934185) (xy 328.862533 -29.877629)
			(xy 328.794224 -29.814437) (xy 328.732099 -29.745157) (xy 328.676695 -29.670392) (xy 328.652124 -29.630878)
			(xy 328.649584 -29.627068) (xy 328.63917 -29.61513) (xy 328.637646 -29.61386) (xy 328.615024 -29.595674)
			(xy 328.575027 -29.553615) (xy 328.541861 -29.505983) (xy 328.516293 -29.453877) (xy 328.498912 -29.3985)
			(xy 328.49012 -29.341128) (xy 328.489564 -29.312108) (xy 328.489564 -29.311854) (xy 328.490031 -29.283354)
			(xy 328.498454 -29.226981) (xy 328.506328 -29.199586) (xy 328.507852 -29.192474) (xy 328.50963 -29.181552)
			(xy 328.50963 -29.177996) (xy 328.509376 -29.175202) (xy 328.508868 -29.160978) (xy 328.508868 -29.159962)
			(xy 328.507852 -29.114242) (xy 328.508285 -29.071655) (xy 328.515521 -28.986789) (xy 328.52997 -28.90285)
			(xy 328.551526 -28.820449) (xy 328.580033 -28.740187) (xy 328.59726 -28.701238) (xy 328.60045 -28.692104)
			(xy 328.600465 -28.672773) (xy 328.59726 -28.663646) (xy 328.580049 -28.62469) (xy 328.551552 -28.544427)
			(xy 328.529996 -28.462027) (xy 328.51554 -28.378091) (xy 328.508288 -28.293228) (xy 328.507852 -28.250642)
			(xy 328.508868 -28.204922) (xy 328.508868 -28.203906) (xy 328.509376 -28.189682) (xy 328.50963 -28.186888)
			(xy 328.50963 -28.183332) (xy 328.507852 -28.17241) (xy 328.506328 -28.165298) (xy 328.498503 -28.137958)
			(xy 328.490089 -28.081717) (xy 328.489564 -28.053284) (xy 328.489564 -28.05303) (xy 328.490104 -28.024008)
			(xy 328.498894 -27.966634) (xy 328.516274 -27.911254) (xy 328.541845 -27.859147) (xy 328.575015 -27.811515)
			(xy 328.615019 -27.769459) (xy 328.637646 -27.751278) (xy 328.641217 -27.748424) (xy 328.647358 -27.741655)
			(xy 328.649838 -27.737816) (xy 328.674476 -27.6987) (xy 328.699575 -27.661793) (xy 328.755398 -27.592141)
			(xy 328.817223 -27.527758) (xy 328.884558 -27.469161) (xy 328.956861 -27.416819) (xy 329.033554 -27.37115)
			(xy 329.114024 -27.332521) (xy 329.197624 -27.301241) (xy 329.283687 -27.27756) (xy 329.371522 -27.261668)
			(xy 329.460425 -27.253693) (xy 329.505056 -27.253184) (xy 329.50531 -27.253184) (xy 329.552829 -27.25374)
			(xy 329.647434 -27.262799) (xy 329.740747 -27.280826) (xy 329.831919 -27.307655) (xy 329.920123 -27.343043)
			(xy 330.004556 -27.386669) (xy 330.044806 -27.411934) (xy 330.082741 -27.436963) (xy 330.154354 -27.492932)
			(xy 330.187808 -27.523694) (xy 330.193142 -27.528774) (xy 330.194412 -27.530044) (xy 330.194666 -27.530298)
			(xy 330.220066 -27.540458) (xy 330.224632 -27.542216) (xy 330.234225 -27.544142) (xy 330.239116 -27.544268)
			(xy 331.613764 -27.544268) (xy 331.65279 -27.544646) (xy 331.730604 -27.550748) (xy 331.769212 -27.55646)
			(xy 331.773276 -27.556968) (xy 332.071726 -27.556968) (xy 332.116118 -27.557493) (xy 332.204542 -27.565504)
			(xy 332.291892 -27.581403) (xy 332.377467 -27.605065) (xy 332.419198 -27.620214) (xy 332.449424 -27.632152)
			(xy 333.966058 -28.260802) (xy 333.975409 -28.264185) (xy 333.995276 -28.264325) (xy 334.004666 -28.261056)
			(xy 334.011105 -28.258227) (xy 334.022196 -28.249592) (xy 334.02651 -28.244038) (xy 334.02651 -28.243784)
			(xy 334.04462 -28.220028) (xy 334.086984 -28.177919) (xy 334.135392 -28.142925) (xy 334.188661 -28.115902)
			(xy 334.245491 -28.097509) (xy 334.304492 -28.088195) (xy 334.334358 -28.087574) (xy 334.371696 -28.089352)
			(xy 334.379062 -28.090114) (xy 334.406243 -28.093797) (xy 334.459235 -28.107953) (xy 334.509653 -28.129552)
			(xy 334.52534 -28.139136) (xy 350.698052 -28.139136) (xy 350.702123 -28.083514) (xy 350.714249 -28.029077)
			(xy 350.734172 -27.976986) (xy 350.761468 -27.928351) (xy 350.795554 -27.884208) (xy 350.835703 -27.845499)
			(xy 350.881061 -27.813048) (xy 350.930661 -27.787547) (xy 350.983445 -27.76954) (xy 351.038288 -27.75941)
			(xy 351.094022 -27.757373) (xy 351.149459 -27.763473) (xy 351.203416 -27.777579) (xy 351.254745 -27.799391)
			(xy 351.302351 -27.828445) (xy 351.345219 -27.86412) (xy 351.382436 -27.905657) (xy 351.413209 -27.95217)
			(xy 351.436881 -28.002667) (xy 351.452949 -28.056074) (xy 351.461069 -28.11125) (xy 351.461578 -28.139136)
			(xy 351.968052 -28.139136) (xy 351.972123 -28.083514) (xy 351.984249 -28.029077) (xy 352.004172 -27.976986)
			(xy 352.031468 -27.928351) (xy 352.065554 -27.884208) (xy 352.105703 -27.845499) (xy 352.151061 -27.813048)
			(xy 352.200661 -27.787547) (xy 352.253445 -27.76954) (xy 352.308288 -27.75941) (xy 352.364022 -27.757373)
			(xy 352.419459 -27.763473) (xy 352.473416 -27.777579) (xy 352.524745 -27.799391) (xy 352.572351 -27.828445)
			(xy 352.615219 -27.86412) (xy 352.652436 -27.905657) (xy 352.683209 -27.95217) (xy 352.706881 -28.002667)
			(xy 352.722949 -28.056074) (xy 352.731069 -28.11125) (xy 352.731578 -28.139136) (xy 352.731069 -28.167022)
			(xy 352.722949 -28.222198) (xy 352.706881 -28.275605) (xy 352.683209 -28.326102) (xy 352.652436 -28.372615)
			(xy 352.615219 -28.414152) (xy 352.572351 -28.449827) (xy 352.524745 -28.478881) (xy 352.473416 -28.500693)
			(xy 352.419459 -28.514799) (xy 352.364022 -28.520899) (xy 352.308288 -28.518862) (xy 352.253445 -28.508732)
			(xy 352.200661 -28.490725) (xy 352.151061 -28.465224) (xy 352.105703 -28.432773) (xy 352.065554 -28.394064)
			(xy 352.031468 -28.349921) (xy 352.004172 -28.301286) (xy 351.984249 -28.249195) (xy 351.972123 -28.194758)
			(xy 351.968052 -28.139136) (xy 351.461578 -28.139136) (xy 351.461069 -28.167022) (xy 351.452949 -28.222198)
			(xy 351.436881 -28.275605) (xy 351.413209 -28.326102) (xy 351.382436 -28.372615) (xy 351.345219 -28.414152)
			(xy 351.302351 -28.449827) (xy 351.254745 -28.478881) (xy 351.203416 -28.500693) (xy 351.149459 -28.514799)
			(xy 351.094022 -28.520899) (xy 351.038288 -28.518862) (xy 350.983445 -28.508732) (xy 350.930661 -28.490725)
			(xy 350.881061 -28.465224) (xy 350.835703 -28.432773) (xy 350.795554 -28.394064) (xy 350.761468 -28.349921)
			(xy 350.734172 -28.301286) (xy 350.714249 -28.249195) (xy 350.702123 -28.194758) (xy 350.698052 -28.139136)
			(xy 334.52534 -28.139136) (xy 334.556459 -28.158149) (xy 334.598687 -28.193154) (xy 334.635466 -28.233845)
			(xy 334.666039 -28.279384) (xy 334.689776 -28.328832) (xy 334.706186 -28.38117) (xy 334.714932 -28.435319)
			(xy 334.715866 -28.462732) (xy 334.715866 -28.469082) (xy 334.715866 -28.46959) (xy 334.715866 -28.473908)
			(xy 334.715142 -28.499605) (xy 334.707635 -28.55046) (xy 334.693365 -28.599847) (xy 334.67259 -28.646869)
			(xy 334.659478 -28.66898) (xy 334.658208 -28.670758) (xy 334.657446 -28.672282) (xy 334.656684 -28.673552)
			(xy 334.656176 -28.674314) (xy 334.651238 -28.682283) (xy 334.647076 -28.700549) (xy 334.648048 -28.709874)
			(xy 334.649318 -28.71851) (xy 334.657954 -28.734512) (xy 334.665066 -28.740862) (xy 334.678665 -28.752755)
			(xy 334.705088 -28.777399) (xy 334.717898 -28.790138) (xy 335.049058 -29.12237) (xy 356.907084 -29.12237)
			(xy 356.907084 -28.25877) (xy 356.907574 -28.228802) (xy 356.915397 -28.16938) (xy 356.93091 -28.111487)
			(xy 356.953846 -28.056114) (xy 356.983813 -28.004208) (xy 357.0203 -27.956658) (xy 357.06268 -27.914278)
			(xy 357.11023 -27.877791) (xy 357.162136 -27.847824) (xy 357.217509 -27.824888) (xy 357.275402 -27.809375)
			(xy 357.334824 -27.801552) (xy 357.39476 -27.801552) (xy 357.454182 -27.809375) (xy 357.512075 -27.824888)
			(xy 357.567448 -27.847824) (xy 357.619354 -27.877791) (xy 357.666904 -27.914278) (xy 357.709284 -27.956658)
			(xy 357.745771 -28.004208) (xy 357.775738 -28.056114) (xy 357.798674 -28.111487) (xy 357.814187 -28.16938)
			(xy 357.82201 -28.228802) (xy 357.8225 -28.25877) (xy 357.8225 -29.12237) (xy 357.82201 -29.152338)
			(xy 357.814187 -29.21176) (xy 357.798674 -29.269653) (xy 357.775738 -29.325026) (xy 357.745771 -29.376932)
			(xy 357.709284 -29.424482) (xy 357.666904 -29.466862) (xy 357.619354 -29.503349) (xy 357.567448 -29.533316)
			(xy 357.512075 -29.556252) (xy 357.454182 -29.571765) (xy 357.39476 -29.579588) (xy 357.334824 -29.579588)
			(xy 357.275402 -29.571765) (xy 357.217509 -29.556252) (xy 357.162136 -29.533316) (xy 357.11023 -29.503349)
			(xy 357.06268 -29.466862) (xy 357.0203 -29.424482) (xy 356.983813 -29.376932) (xy 356.953846 -29.325026)
			(xy 356.93091 -29.269653) (xy 356.915397 -29.21176) (xy 356.907574 -29.152338) (xy 356.907084 -29.12237)
			(xy 335.049058 -29.12237) (xy 335.110328 -29.183838) (xy 335.35112 -29.425138) (xy 335.358611 -29.431389)
			(xy 335.376869 -29.438219) (xy 335.396357 -29.43775) (xy 335.405476 -29.434282) (xy 335.40573 -29.434282)
			(xy 335.429679 -29.424362) (xy 335.479591 -29.410363) (xy 335.530942 -29.403268) (xy 335.55686 -29.402786)
			(xy 335.559654 -29.402786) (xy 335.587275 -29.403445) (xy 335.641897 -29.411747) (xy 335.694751 -29.427837)
			(xy 335.744734 -29.451379) (xy 335.7908 -29.48188) (xy 335.831988 -29.518704) (xy 335.867437 -29.561081)
			(xy 335.896407 -29.608126) (xy 335.918291 -29.658856) (xy 335.932634 -29.712211) (xy 335.936336 -29.73959)
			(xy 335.937352 -29.749242) (xy 335.938876 -29.784294) (xy 335.938458 -29.810476) (xy 335.93133 -29.862353)
			(xy 335.917178 -29.912768) (xy 335.907126 -29.936948) (xy 335.907126 -29.937202) (xy 335.904304 -29.944274)
			(xy 335.902491 -29.959383) (xy 335.90357 -29.96692) (xy 335.90484 -29.973778) (xy 335.911952 -29.986986)
			(xy 336.300861 -30.376876) (xy 349.18904 -30.376876) (xy 349.189598 -30.34796) (xy 349.198317 -30.29079)
			(xy 349.215566 -30.235592) (xy 349.24095 -30.18363) (xy 349.273887 -30.136095) (xy 349.313623 -30.094077)
			(xy 349.336106 -30.075886) (xy 349.344911 -30.068276) (xy 349.355095 -30.047378) (xy 349.355664 -30.035754)
			(xy 349.355664 -29.955998) (xy 349.355124 -29.944366) (xy 349.344937 -29.923456) (xy 349.336106 -29.915866)
			(xy 349.313607 -29.897693) (xy 349.273873 -29.855669) (xy 349.240936 -29.808131) (xy 349.21555 -29.756166)
			(xy 349.198297 -29.700965) (xy 349.189572 -29.643793) (xy 349.18904 -29.614876) (xy 349.189526 -29.587625)
			(xy 349.197282 -29.533677) (xy 349.212637 -29.481382) (xy 349.235279 -29.431805) (xy 349.264745 -29.385955)
			(xy 349.300436 -29.344764) (xy 349.341627 -29.309073) (xy 349.387477 -29.279607) (xy 349.437054 -29.256965)
			(xy 349.489349 -29.24161) (xy 349.543297 -29.233854) (xy 349.597799 -29.233854) (xy 349.651747 -29.24161)
			(xy 349.704042 -29.256965) (xy 349.753619 -29.279607) (xy 349.799469 -29.309073) (xy 349.84066 -29.344764)
			(xy 349.876351 -29.385955) (xy 349.905817 -29.431805) (xy 349.928459 -29.481382) (xy 349.943814 -29.533677)
			(xy 349.95157 -29.587625) (xy 349.952056 -29.614876) (xy 349.951537 -29.643793) (xy 349.942811 -29.700965)
			(xy 349.925554 -29.756165) (xy 349.900162 -29.808127) (xy 349.867218 -29.85566) (xy 349.827476 -29.897677)
			(xy 349.80499 -29.915866) (xy 349.796207 -29.923496) (xy 349.78601 -29.944379) (xy 349.785432 -29.955998)
			(xy 349.785432 -30.035754) (xy 349.785943 -30.04739) (xy 349.796151 -30.068299) (xy 349.80499 -30.075886)
			(xy 349.827465 -30.094087) (xy 349.867201 -30.136105) (xy 349.900141 -30.183637) (xy 349.925531 -30.235597)
			(xy 349.942789 -30.290792) (xy 349.95152 -30.347961) (xy 349.952056 -30.376876) (xy 352.229166 -30.376876)
			(xy 352.229714 -30.34796) (xy 352.238433 -30.290789) (xy 352.255684 -30.23559) (xy 352.28107 -30.183627)
			(xy 352.314009 -30.136093) (xy 352.353748 -30.094076) (xy 352.376232 -30.075886) (xy 352.385041 -30.068281)
			(xy 352.395222 -30.047378) (xy 352.39579 -30.035754) (xy 352.39579 -29.955998) (xy 352.395241 -29.944367)
			(xy 352.38506 -29.923457) (xy 352.376232 -29.915866) (xy 352.353739 -29.897686) (xy 352.314003 -29.855665)
			(xy 352.281064 -29.808128) (xy 352.255677 -29.756164) (xy 352.238423 -29.700964) (xy 352.229698 -29.643793)
			(xy 352.229166 -29.614876) (xy 352.229652 -29.587625) (xy 352.237408 -29.533677) (xy 352.252763 -29.481382)
			(xy 352.275405 -29.431805) (xy 352.304871 -29.385955) (xy 352.340562 -29.344764) (xy 352.381753 -29.309073)
			(xy 352.427603 -29.279607) (xy 352.47718 -29.256965) (xy 352.529475 -29.24161) (xy 352.583423 -29.233854)
			(xy 352.637925 -29.233854) (xy 352.691873 -29.24161) (xy 352.744168 -29.256965) (xy 352.793745 -29.279607)
			(xy 352.839595 -29.309073) (xy 352.880786 -29.344764) (xy 352.916477 -29.385955) (xy 352.945943 -29.431805)
			(xy 352.968585 -29.481382) (xy 352.98394 -29.533677) (xy 352.991696 -29.587625) (xy 352.992182 -29.614876)
			(xy 352.991653 -29.643793) (xy 352.982927 -29.700964) (xy 352.965672 -29.756163) (xy 352.940282 -29.808124)
			(xy 352.90734 -29.855659) (xy 352.867601 -29.897676) (xy 352.845116 -29.915866) (xy 352.83632 -29.923483)
			(xy 352.826134 -29.944377) (xy 352.825558 -29.955998) (xy 352.825558 -30.035754) (xy 352.82606 -30.047391)
			(xy 352.836273 -30.068302) (xy 352.845116 -30.075886) (xy 352.867596 -30.094081) (xy 352.907331 -30.1361)
			(xy 352.94027 -30.183635) (xy 352.965659 -30.235595) (xy 352.982916 -30.290792) (xy 352.991646 -30.34796)
			(xy 352.992182 -30.376876) (xy 352.991696 -30.404127) (xy 352.98394 -30.458075) (xy 352.968585 -30.51037)
			(xy 352.945943 -30.559947) (xy 352.916477 -30.605797) (xy 352.880786 -30.646988) (xy 352.839595 -30.682679)
			(xy 352.793745 -30.712145) (xy 352.744168 -30.734787) (xy 352.691873 -30.750142) (xy 352.637925 -30.757898)
			(xy 352.583423 -30.757898) (xy 352.529475 -30.750142) (xy 352.47718 -30.734787) (xy 352.427603 -30.712145)
			(xy 352.381753 -30.682679) (xy 352.340562 -30.646988) (xy 352.304871 -30.605797) (xy 352.275405 -30.559947)
			(xy 352.252763 -30.51037) (xy 352.237408 -30.458075) (xy 352.229652 -30.404127) (xy 352.229166 -30.376876)
			(xy 349.952056 -30.376876) (xy 349.95157 -30.404127) (xy 349.943814 -30.458075) (xy 349.928459 -30.51037)
			(xy 349.905817 -30.559947) (xy 349.876351 -30.605797) (xy 349.84066 -30.646988) (xy 349.799469 -30.682679)
			(xy 349.753619 -30.712145) (xy 349.704042 -30.734787) (xy 349.651747 -30.750142) (xy 349.597799 -30.757898)
			(xy 349.543297 -30.757898) (xy 349.489349 -30.750142) (xy 349.437054 -30.734787) (xy 349.387477 -30.712145)
			(xy 349.341627 -30.682679) (xy 349.300436 -30.646988) (xy 349.264745 -30.605797) (xy 349.235279 -30.559947)
			(xy 349.212637 -30.51037) (xy 349.197282 -30.458075) (xy 349.189526 -30.404127) (xy 349.18904 -30.376876)
			(xy 336.300861 -30.376876) (xy 336.717132 -30.794198) (xy 336.845034 -30.922468) (xy 355.052884 -30.922468)
			(xy 355.052884 -30.058868) (xy 355.053374 -30.0289) (xy 355.061197 -29.969478) (xy 355.07671 -29.911585)
			(xy 355.099646 -29.856212) (xy 355.129613 -29.804306) (xy 355.1661 -29.756756) (xy 355.20848 -29.714376)
			(xy 355.25603 -29.677889) (xy 355.307936 -29.647922) (xy 355.363309 -29.624986) (xy 355.421202 -29.609473)
			(xy 355.480624 -29.60165) (xy 355.54056 -29.60165) (xy 355.599982 -29.609473) (xy 355.657875 -29.624986)
			(xy 355.713248 -29.647922) (xy 355.765154 -29.677889) (xy 355.812704 -29.714376) (xy 355.855084 -29.756756)
			(xy 355.891571 -29.804306) (xy 355.921538 -29.856212) (xy 355.944474 -29.911585) (xy 355.959987 -29.969478)
			(xy 355.96781 -30.0289) (xy 355.9683 -30.058868) (xy 355.9683 -30.922468) (xy 355.96781 -30.952436)
			(xy 355.959987 -31.011858) (xy 355.944474 -31.069751) (xy 355.921538 -31.125124) (xy 355.891571 -31.17703)
			(xy 355.855084 -31.22458) (xy 355.812704 -31.26696) (xy 355.765154 -31.303447) (xy 355.713248 -31.333414)
			(xy 355.657875 -31.35635) (xy 355.599982 -31.371863) (xy 355.54056 -31.379686) (xy 355.480624 -31.379686)
			(xy 355.421202 -31.371863) (xy 355.363309 -31.35635) (xy 355.307936 -31.333414) (xy 355.25603 -31.303447)
			(xy 355.20848 -31.26696) (xy 355.1661 -31.22458) (xy 355.129613 -31.17703) (xy 355.099646 -31.125124)
			(xy 355.07671 -31.069751) (xy 355.061197 -31.011858) (xy 355.053374 -30.952436) (xy 355.052884 -30.922468)
			(xy 336.845034 -30.922468) (xy 336.893916 -30.97149) (xy 336.926837 -31.005317) (xy 336.986848 -31.078186)
			(xy 337.039712 -31.156394) (xy 337.062826 -31.19755) (xy 337.265236 -31.567882) (xy 349.298766 -31.567882)
			(xy 349.302837 -31.51226) (xy 349.314963 -31.457823) (xy 349.334886 -31.405732) (xy 349.362182 -31.357097)
			(xy 349.396268 -31.312954) (xy 349.436417 -31.274245) (xy 349.481775 -31.241794) (xy 349.531375 -31.216293)
			(xy 349.584159 -31.198286) (xy 349.639002 -31.188156) (xy 349.694736 -31.186119) (xy 349.750173 -31.192219)
			(xy 349.80413 -31.206325) (xy 349.855459 -31.228137) (xy 349.903065 -31.257191) (xy 349.945933 -31.292866)
			(xy 349.98315 -31.334403) (xy 350.013923 -31.380916) (xy 350.037595 -31.431413) (xy 350.053663 -31.48482)
			(xy 350.061783 -31.539996) (xy 350.062292 -31.567882) (xy 350.061783 -31.595768) (xy 350.053663 -31.650944)
			(xy 350.037595 -31.704351) (xy 350.030603 -31.719266) (xy 350.58553 -31.719266) (xy 350.589601 -31.663644)
			(xy 350.601727 -31.609207) (xy 350.62165 -31.557116) (xy 350.648946 -31.508481) (xy 350.683032 -31.464338)
			(xy 350.723181 -31.425629) (xy 350.768539 -31.393178) (xy 350.818139 -31.367677) (xy 350.870923 -31.34967)
			(xy 350.925766 -31.33954) (xy 350.9815 -31.337503) (xy 351.036937 -31.343603) (xy 351.090894 -31.357709)
			(xy 351.142223 -31.379521) (xy 351.189829 -31.408575) (xy 351.232697 -31.44425) (xy 351.269914 -31.485787)
			(xy 351.300687 -31.5323) (xy 351.324359 -31.582797) (xy 351.340427 -31.636204) (xy 351.344577 -31.664402)
			(xy 351.861118 -31.664402) (xy 351.865189 -31.60878) (xy 351.877315 -31.554343) (xy 351.897238 -31.502252)
			(xy 351.924534 -31.453617) (xy 351.95862 -31.409474) (xy 351.998769 -31.370765) (xy 352.044127 -31.338314)
			(xy 352.093727 -31.312813) (xy 352.146511 -31.294806) (xy 352.201354 -31.284676) (xy 352.257088 -31.282639)
			(xy 352.312525 -31.288739) (xy 352.366482 -31.302845) (xy 352.417811 -31.324657) (xy 352.465417 -31.353711)
			(xy 352.508285 -31.389386) (xy 352.545502 -31.430923) (xy 352.576275 -31.477436) (xy 352.599947 -31.527933)
			(xy 352.616015 -31.58134) (xy 352.624135 -31.636516) (xy 352.624644 -31.664402) (xy 352.624135 -31.692288)
			(xy 352.616015 -31.747464) (xy 352.607075 -31.777178) (xy 353.126292 -31.777178) (xy 353.130363 -31.721556)
			(xy 353.142489 -31.667119) (xy 353.162412 -31.615028) (xy 353.189708 -31.566393) (xy 353.223794 -31.52225)
			(xy 353.263943 -31.483541) (xy 353.309301 -31.45109) (xy 353.358901 -31.425589) (xy 353.411685 -31.407582)
			(xy 353.466528 -31.397452) (xy 353.522262 -31.395415) (xy 353.577699 -31.401515) (xy 353.631656 -31.415621)
			(xy 353.682985 -31.437433) (xy 353.730591 -31.466487) (xy 353.773459 -31.502162) (xy 353.810676 -31.543699)
			(xy 353.841449 -31.590212) (xy 353.865121 -31.640709) (xy 353.881189 -31.694116) (xy 353.889309 -31.749292)
			(xy 353.889818 -31.777178) (xy 353.889309 -31.805064) (xy 353.881189 -31.86024) (xy 353.865121 -31.913647)
			(xy 353.841449 -31.964144) (xy 353.810676 -32.010657) (xy 353.773459 -32.052194) (xy 353.730591 -32.087869)
			(xy 353.682985 -32.116923) (xy 353.631656 -32.138735) (xy 353.577699 -32.152841) (xy 353.522262 -32.158941)
			(xy 353.466528 -32.156904) (xy 353.411685 -32.146774) (xy 353.358901 -32.128767) (xy 353.309301 -32.103266)
			(xy 353.263943 -32.070815) (xy 353.223794 -32.032106) (xy 353.189708 -31.987963) (xy 353.162412 -31.939328)
			(xy 353.142489 -31.887237) (xy 353.130363 -31.8328) (xy 353.126292 -31.777178) (xy 352.607075 -31.777178)
			(xy 352.599947 -31.800871) (xy 352.576275 -31.851368) (xy 352.545502 -31.897881) (xy 352.508285 -31.939418)
			(xy 352.465417 -31.975093) (xy 352.417811 -32.004147) (xy 352.366482 -32.025959) (xy 352.312525 -32.040065)
			(xy 352.257088 -32.046165) (xy 352.201354 -32.044128) (xy 352.146511 -32.033998) (xy 352.093727 -32.015991)
			(xy 352.044127 -31.99049) (xy 351.998769 -31.958039) (xy 351.95862 -31.91933) (xy 351.924534 -31.875187)
			(xy 351.897238 -31.826552) (xy 351.877315 -31.774461) (xy 351.865189 -31.720024) (xy 351.861118 -31.664402)
			(xy 351.344577 -31.664402) (xy 351.348547 -31.69138) (xy 351.349056 -31.719266) (xy 351.348547 -31.747152)
			(xy 351.340427 -31.802328) (xy 351.324359 -31.855735) (xy 351.300687 -31.906232) (xy 351.269914 -31.952745)
			(xy 351.232697 -31.994282) (xy 351.189829 -32.029957) (xy 351.142223 -32.059011) (xy 351.090894 -32.080823)
			(xy 351.036937 -32.094929) (xy 350.9815 -32.101029) (xy 350.925766 -32.098992) (xy 350.870923 -32.088862)
			(xy 350.818139 -32.070855) (xy 350.768539 -32.045354) (xy 350.723181 -32.012903) (xy 350.683032 -31.974194)
			(xy 350.648946 -31.930051) (xy 350.62165 -31.881416) (xy 350.601727 -31.829325) (xy 350.589601 -31.774888)
			(xy 350.58553 -31.719266) (xy 350.030603 -31.719266) (xy 350.013923 -31.754848) (xy 349.98315 -31.801361)
			(xy 349.945933 -31.842898) (xy 349.903065 -31.878573) (xy 349.855459 -31.907627) (xy 349.80413 -31.929439)
			(xy 349.750173 -31.943545) (xy 349.694736 -31.949645) (xy 349.639002 -31.947608) (xy 349.584159 -31.937478)
			(xy 349.531375 -31.919471) (xy 349.481775 -31.89397) (xy 349.436417 -31.861519) (xy 349.396268 -31.82281)
			(xy 349.362182 -31.778667) (xy 349.334886 -31.730032) (xy 349.314963 -31.677941) (xy 349.302837 -31.623504)
			(xy 349.298766 -31.567882) (xy 337.265236 -31.567882) (xy 337.896207 -32.722312) (xy 356.907084 -32.722312)
			(xy 356.907084 -31.858712) (xy 356.907574 -31.828744) (xy 356.915397 -31.769322) (xy 356.93091 -31.711429)
			(xy 356.953846 -31.656056) (xy 356.983813 -31.60415) (xy 357.0203 -31.5566) (xy 357.06268 -31.51422)
			(xy 357.11023 -31.477733) (xy 357.162136 -31.447766) (xy 357.217509 -31.42483) (xy 357.275402 -31.409317)
			(xy 357.334824 -31.401494) (xy 357.39476 -31.401494) (xy 357.454182 -31.409317) (xy 357.512075 -31.42483)
			(xy 357.567448 -31.447766) (xy 357.619354 -31.477733) (xy 357.666904 -31.51422) (xy 357.709284 -31.5566)
			(xy 357.745771 -31.60415) (xy 357.775738 -31.656056) (xy 357.798674 -31.711429) (xy 357.814187 -31.769322)
			(xy 357.82201 -31.828744) (xy 357.8225 -31.858712) (xy 357.8225 -32.722312) (xy 357.82201 -32.75228)
			(xy 357.814187 -32.811702) (xy 357.798674 -32.869595) (xy 357.775738 -32.924968) (xy 357.745771 -32.976874)
			(xy 357.709284 -33.024424) (xy 357.666904 -33.066804) (xy 357.619354 -33.103291) (xy 357.567448 -33.133258)
			(xy 357.512075 -33.156194) (xy 357.454182 -33.171707) (xy 357.39476 -33.17953) (xy 357.334824 -33.17953)
			(xy 357.275402 -33.171707) (xy 357.217509 -33.156194) (xy 357.162136 -33.133258) (xy 357.11023 -33.103291)
			(xy 357.06268 -33.066804) (xy 357.0203 -33.024424) (xy 356.983813 -32.976874) (xy 356.953846 -32.924968)
			(xy 356.93091 -32.869595) (xy 356.915397 -32.811702) (xy 356.907574 -32.75228) (xy 356.907084 -32.722312)
			(xy 337.896207 -32.722312) (xy 338.880078 -34.52241) (xy 355.052884 -34.52241) (xy 355.052884 -33.65881)
			(xy 355.053374 -33.628842) (xy 355.061197 -33.56942) (xy 355.07671 -33.511527) (xy 355.099646 -33.456154)
			(xy 355.129613 -33.404248) (xy 355.1661 -33.356698) (xy 355.20848 -33.314318) (xy 355.25603 -33.277831)
			(xy 355.307936 -33.247864) (xy 355.363309 -33.224928) (xy 355.421202 -33.209415) (xy 355.480624 -33.201592)
			(xy 355.54056 -33.201592) (xy 355.599982 -33.209415) (xy 355.657875 -33.224928) (xy 355.713248 -33.247864)
			(xy 355.765154 -33.277831) (xy 355.812704 -33.314318) (xy 355.855084 -33.356698) (xy 355.891571 -33.404248)
			(xy 355.921538 -33.456154) (xy 355.944474 -33.511527) (xy 355.959987 -33.56942) (xy 355.96781 -33.628842)
			(xy 355.9683 -33.65881) (xy 355.9683 -34.52241) (xy 355.96781 -34.552378) (xy 355.959987 -34.6118)
			(xy 355.944474 -34.669693) (xy 355.921538 -34.725066) (xy 355.891571 -34.776972) (xy 355.855084 -34.824522)
			(xy 355.812704 -34.866902) (xy 355.765154 -34.903389) (xy 355.713248 -34.933356) (xy 355.657875 -34.956292)
			(xy 355.599982 -34.971805) (xy 355.54056 -34.979628) (xy 355.480624 -34.979628) (xy 355.421202 -34.971805)
			(xy 355.363309 -34.956292) (xy 355.307936 -34.933356) (xy 355.25603 -34.903389) (xy 355.20848 -34.866902)
			(xy 355.1661 -34.824522) (xy 355.129613 -34.776972) (xy 355.099646 -34.725066) (xy 355.07671 -34.669693)
			(xy 355.061197 -34.6118) (xy 355.053374 -34.552378) (xy 355.052884 -34.52241) (xy 338.880078 -34.52241)
			(xy 339.285871 -35.264852) (xy 352.202494 -35.264852) (xy 352.206565 -35.20923) (xy 352.218691 -35.154793)
			(xy 352.238614 -35.102702) (xy 352.26591 -35.054067) (xy 352.299996 -35.009924) (xy 352.340145 -34.971215)
			(xy 352.385503 -34.938764) (xy 352.435103 -34.913263) (xy 352.487887 -34.895256) (xy 352.54273 -34.885126)
			(xy 352.598464 -34.883089) (xy 352.653901 -34.889189) (xy 352.707858 -34.903295) (xy 352.759187 -34.925107)
			(xy 352.806793 -34.954161) (xy 352.849661 -34.989836) (xy 352.886878 -35.031373) (xy 352.917651 -35.077886)
			(xy 352.941323 -35.128383) (xy 352.957391 -35.18179) (xy 352.965511 -35.236966) (xy 352.96602 -35.264852)
			(xy 352.965511 -35.292738) (xy 352.957391 -35.347914) (xy 352.941323 -35.401321) (xy 352.917651 -35.451818)
			(xy 352.886878 -35.498331) (xy 352.849661 -35.539868) (xy 352.806793 -35.575543) (xy 352.759187 -35.604597)
			(xy 352.707858 -35.626409) (xy 352.653901 -35.640515) (xy 352.598464 -35.646615) (xy 352.54273 -35.644578)
			(xy 352.487887 -35.634448) (xy 352.435103 -35.616441) (xy 352.385503 -35.59094) (xy 352.340145 -35.558489)
			(xy 352.299996 -35.51978) (xy 352.26591 -35.475637) (xy 352.238614 -35.427002) (xy 352.218691 -35.374911)
			(xy 352.206565 -35.320474) (xy 352.202494 -35.264852) (xy 339.285871 -35.264852) (xy 339.620306 -35.876738)
			(xy 341.01735 -35.876738) (xy 341.021421 -35.821116) (xy 341.033547 -35.766679) (xy 341.05347 -35.714588)
			(xy 341.080766 -35.665953) (xy 341.114852 -35.62181) (xy 341.155001 -35.583101) (xy 341.200359 -35.55065)
			(xy 341.249959 -35.525149) (xy 341.302743 -35.507142) (xy 341.357586 -35.497012) (xy 341.41332 -35.494975)
			(xy 341.468757 -35.501075) (xy 341.522714 -35.515181) (xy 341.574043 -35.536993) (xy 341.621649 -35.566047)
			(xy 341.664517 -35.601722) (xy 341.701734 -35.643259) (xy 341.732507 -35.689772) (xy 341.756179 -35.740269)
			(xy 341.772247 -35.793676) (xy 341.780367 -35.848852) (xy 341.780876 -35.876738) (xy 345.08897 -35.876738)
			(xy 345.093041 -35.821116) (xy 345.105167 -35.766679) (xy 345.12509 -35.714588) (xy 345.152386 -35.665953)
			(xy 345.186472 -35.62181) (xy 345.226621 -35.583101) (xy 345.271979 -35.55065) (xy 345.321579 -35.525149)
			(xy 345.374363 -35.507142) (xy 345.429206 -35.497012) (xy 345.48494 -35.494975) (xy 345.540377 -35.501075)
			(xy 345.594334 -35.515181) (xy 345.645663 -35.536993) (xy 345.693269 -35.566047) (xy 345.736137 -35.601722)
			(xy 345.773354 -35.643259) (xy 345.804127 -35.689772) (xy 345.827799 -35.740269) (xy 345.843867 -35.793676)
			(xy 345.851987 -35.848852) (xy 345.852496 -35.876738) (xy 345.851987 -35.904624) (xy 345.843867 -35.9598)
			(xy 345.827799 -36.013207) (xy 345.804127 -36.063704) (xy 345.773354 -36.110217) (xy 345.736137 -36.151754)
			(xy 345.693269 -36.187429) (xy 345.645663 -36.216483) (xy 345.594334 -36.238295) (xy 345.540377 -36.252401)
			(xy 345.48494 -36.258501) (xy 345.429206 -36.256464) (xy 345.374363 -36.246334) (xy 345.321579 -36.228327)
			(xy 345.271979 -36.202826) (xy 345.226621 -36.170375) (xy 345.186472 -36.131666) (xy 345.152386 -36.087523)
			(xy 345.12509 -36.038888) (xy 345.105167 -35.986797) (xy 345.093041 -35.93236) (xy 345.08897 -35.876738)
			(xy 341.780876 -35.876738) (xy 341.780367 -35.904624) (xy 341.772247 -35.9598) (xy 341.756179 -36.013207)
			(xy 341.732507 -36.063704) (xy 341.701734 -36.110217) (xy 341.664517 -36.151754) (xy 341.621649 -36.187429)
			(xy 341.574043 -36.216483) (xy 341.522714 -36.238295) (xy 341.468757 -36.252401) (xy 341.41332 -36.258501)
			(xy 341.357586 -36.256464) (xy 341.302743 -36.246334) (xy 341.249959 -36.228327) (xy 341.200359 -36.202826)
			(xy 341.155001 -36.170375) (xy 341.114852 -36.131666) (xy 341.080766 -36.087523) (xy 341.05347 -36.038888)
			(xy 341.033547 -35.986797) (xy 341.021421 -35.93236) (xy 341.01735 -35.876738) (xy 339.620306 -35.876738)
			(xy 339.966403 -36.50996) (xy 342.913968 -36.50996) (xy 342.918039 -36.454338) (xy 342.930165 -36.399901)
			(xy 342.950088 -36.34781) (xy 342.977384 -36.299175) (xy 343.01147 -36.255032) (xy 343.051619 -36.216323)
			(xy 343.096977 -36.183872) (xy 343.146577 -36.158371) (xy 343.199361 -36.140364) (xy 343.254204 -36.130234)
			(xy 343.309938 -36.128197) (xy 343.365375 -36.134297) (xy 343.419332 -36.148403) (xy 343.470661 -36.170215)
			(xy 343.518267 -36.199269) (xy 343.561135 -36.234944) (xy 343.598352 -36.276481) (xy 343.629125 -36.322994)
			(xy 343.652797 -36.373491) (xy 343.668865 -36.426898) (xy 343.67279 -36.453572) (xy 346.228668 -36.453572)
			(xy 346.232739 -36.39795) (xy 346.244865 -36.343513) (xy 346.264788 -36.291422) (xy 346.292084 -36.242787)
			(xy 346.32617 -36.198644) (xy 346.366319 -36.159935) (xy 346.411677 -36.127484) (xy 346.461277 -36.101983)
			(xy 346.514061 -36.083976) (xy 346.568904 -36.073846) (xy 346.624638 -36.071809) (xy 346.680075 -36.077909)
			(xy 346.734032 -36.092015) (xy 346.785361 -36.113827) (xy 346.832967 -36.142881) (xy 346.875835 -36.178556)
			(xy 346.913052 -36.220093) (xy 346.943825 -36.266606) (xy 346.953361 -36.286948) (xy 353.500434 -36.286948)
			(xy 353.504505 -36.231326) (xy 353.516631 -36.176889) (xy 353.536554 -36.124798) (xy 353.56385 -36.076163)
			(xy 353.597936 -36.03202) (xy 353.638085 -35.993311) (xy 353.683443 -35.96086) (xy 353.733043 -35.935359)
			(xy 353.785827 -35.917352) (xy 353.84067 -35.907222) (xy 353.896404 -35.905185) (xy 353.951841 -35.911285)
			(xy 354.005798 -35.925391) (xy 354.057127 -35.947203) (xy 354.104733 -35.976257) (xy 354.147601 -36.011932)
			(xy 354.184818 -36.053469) (xy 354.215591 -36.099982) (xy 354.239263 -36.150479) (xy 354.255331 -36.203886)
			(xy 354.263451 -36.259062) (xy 354.26396 -36.286948) (xy 354.263451 -36.314834) (xy 354.255331 -36.37001)
			(xy 354.239263 -36.423417) (xy 354.215591 -36.473914) (xy 354.188046 -36.515548) (xy 355.314248 -36.515548)
			(xy 355.318319 -36.459926) (xy 355.330445 -36.405489) (xy 355.350368 -36.353398) (xy 355.377664 -36.304763)
			(xy 355.41175 -36.26062) (xy 355.451899 -36.221911) (xy 355.497257 -36.18946) (xy 355.546857 -36.163959)
			(xy 355.599641 -36.145952) (xy 355.654484 -36.135822) (xy 355.710218 -36.133785) (xy 355.765655 -36.139885)
			(xy 355.819612 -36.153991) (xy 355.870941 -36.175803) (xy 355.918547 -36.204857) (xy 355.961415 -36.240532)
			(xy 355.998632 -36.282069) (xy 356.029405 -36.328582) (xy 356.053077 -36.379079) (xy 356.069145 -36.432486)
			(xy 356.077265 -36.487662) (xy 356.077774 -36.515548) (xy 356.077265 -36.543434) (xy 356.069145 -36.59861)
			(xy 356.068688 -36.60013) (xy 360.298245 -36.60013) (xy 360.30225 -36.512222) (xy 360.314233 -36.425042)
			(xy 360.334093 -36.339313) (xy 360.361668 -36.255745) (xy 360.396727 -36.175031) (xy 360.43898 -36.097839)
			(xy 360.488078 -36.02481) (xy 360.543614 -35.956548) (xy 360.605126 -35.893618) (xy 360.672107 -35.836544)
			(xy 360.744 -35.785796) (xy 360.820209 -35.741796) (xy 360.900104 -35.704909) (xy 360.983023 -35.67544)
			(xy 361.068278 -35.653633) (xy 361.155162 -35.639669) (xy 361.242956 -35.633663) (xy 361.330933 -35.635667)
			(xy 361.418363 -35.645662) (xy 361.504522 -35.663566) (xy 361.588696 -35.68923) (xy 361.670187 -35.722443)
			(xy 361.748321 -35.762929) (xy 361.822449 -35.810351) (xy 361.891957 -35.864318) (xy 361.905256 -35.876738)
			(xy 367.017298 -35.876738) (xy 367.021369 -35.821116) (xy 367.033495 -35.766679) (xy 367.053418 -35.714588)
			(xy 367.080714 -35.665953) (xy 367.1148 -35.62181) (xy 367.154949 -35.583101) (xy 367.200307 -35.55065)
			(xy 367.249907 -35.525149) (xy 367.302691 -35.507142) (xy 367.357534 -35.497012) (xy 367.413268 -35.494975)
			(xy 367.468705 -35.501075) (xy 367.522662 -35.515181) (xy 367.573991 -35.536993) (xy 367.621597 -35.566047)
			(xy 367.664465 -35.601722) (xy 367.701682 -35.643259) (xy 367.732455 -35.689772) (xy 367.756127 -35.740269)
			(xy 367.772195 -35.793676) (xy 367.780315 -35.848852) (xy 367.780824 -35.876738) (xy 367.780315 -35.904624)
			(xy 367.772195 -35.9598) (xy 367.756127 -36.013207) (xy 367.732455 -36.063704) (xy 367.701682 -36.110217)
			(xy 367.664465 -36.151754) (xy 367.621597 -36.187429) (xy 367.573991 -36.216483) (xy 367.522662 -36.238295)
			(xy 367.468705 -36.252401) (xy 367.413268 -36.258501) (xy 367.357534 -36.256464) (xy 367.302691 -36.246334)
			(xy 367.249907 -36.228327) (xy 367.200307 -36.202826) (xy 367.154949 -36.170375) (xy 367.1148 -36.131666)
			(xy 367.080714 -36.087523) (xy 367.053418 -36.038888) (xy 367.033495 -35.986797) (xy 367.021369 -35.93236)
			(xy 367.017298 -35.876738) (xy 361.905256 -35.876738) (xy 361.956271 -35.924383) (xy 362.014855 -35.990047)
			(xy 362.067226 -36.060766) (xy 362.112949 -36.135954) (xy 362.151646 -36.214989) (xy 362.182995 -36.297215)
			(xy 362.206737 -36.381951) (xy 362.222675 -36.468495) (xy 362.226461 -36.50996) (xy 368.913916 -36.50996)
			(xy 368.917987 -36.454338) (xy 368.930113 -36.399901) (xy 368.950036 -36.34781) (xy 368.977332 -36.299175)
			(xy 369.011418 -36.255032) (xy 369.051567 -36.216323) (xy 369.096925 -36.183872) (xy 369.146525 -36.158371)
			(xy 369.199309 -36.140364) (xy 369.254152 -36.130234) (xy 369.309886 -36.128197) (xy 369.365323 -36.134297)
			(xy 369.41928 -36.148403) (xy 369.470609 -36.170215) (xy 369.518215 -36.199269) (xy 369.561083 -36.234944)
			(xy 369.5983 -36.276481) (xy 369.629073 -36.322994) (xy 369.652745 -36.373491) (xy 369.668813 -36.426898)
			(xy 369.676933 -36.482074) (xy 369.677442 -36.50996) (xy 369.676933 -36.537846) (xy 369.668813 -36.593022)
			(xy 369.652745 -36.646429) (xy 369.629073 -36.696926) (xy 369.5983 -36.743439) (xy 369.561083 -36.784976)
			(xy 369.518215 -36.820651) (xy 369.470609 -36.849705) (xy 369.41928 -36.871517) (xy 369.365323 -36.885623)
			(xy 369.309886 -36.891723) (xy 369.254152 -36.889686) (xy 369.199309 -36.879556) (xy 369.146525 -36.861549)
			(xy 369.096925 -36.836048) (xy 369.051567 -36.803597) (xy 369.011418 -36.764888) (xy 368.977332 -36.720745)
			(xy 368.950036 -36.67211) (xy 368.930113 -36.620019) (xy 368.917987 -36.565582) (xy 368.913916 -36.50996)
			(xy 362.226461 -36.50996) (xy 362.230677 -36.55613) (xy 362.231178 -36.60013) (xy 362.230677 -36.64413)
			(xy 362.222675 -36.731765) (xy 362.206737 -36.818309) (xy 362.182995 -36.903045) (xy 362.151646 -36.985271)
			(xy 362.112949 -37.064306) (xy 362.067226 -37.139494) (xy 362.014855 -37.210213) (xy 361.956271 -37.275877)
			(xy 361.891957 -37.335942) (xy 361.822449 -37.389909) (xy 361.748321 -37.437331) (xy 361.675315 -37.47516)
			(xy 366.05921 -37.47516) (xy 366.063281 -37.419538) (xy 366.075407 -37.365101) (xy 366.09533 -37.31301)
			(xy 366.122626 -37.264375) (xy 366.156712 -37.220232) (xy 366.196861 -37.181523) (xy 366.242219 -37.149072)
			(xy 366.291819 -37.123571) (xy 366.344603 -37.105564) (xy 366.399446 -37.095434) (xy 366.45518 -37.093397)
			(xy 366.510617 -37.099497) (xy 366.564574 -37.113603) (xy 366.615903 -37.135415) (xy 366.663509 -37.164469)
			(xy 366.706377 -37.200144) (xy 366.743594 -37.241681) (xy 366.774367 -37.288194) (xy 366.798039 -37.338691)
			(xy 366.814107 -37.392098) (xy 366.822227 -37.447274) (xy 366.822736 -37.47516) (xy 366.822227 -37.503046)
			(xy 366.814107 -37.558222) (xy 366.798039 -37.611629) (xy 366.774367 -37.662126) (xy 366.774214 -37.662358)
			(xy 368.248436 -37.662358) (xy 368.252507 -37.606736) (xy 368.264633 -37.552299) (xy 368.284556 -37.500208)
			(xy 368.311852 -37.451573) (xy 368.345938 -37.40743) (xy 368.386087 -37.368721) (xy 368.431445 -37.33627)
			(xy 368.481045 -37.310769) (xy 368.533829 -37.292762) (xy 368.588672 -37.282632) (xy 368.644406 -37.280595)
			(xy 368.699843 -37.286695) (xy 368.7538 -37.300801) (xy 368.805129 -37.322613) (xy 368.852735 -37.351667)
			(xy 368.895603 -37.387342) (xy 368.93282 -37.428879) (xy 368.963593 -37.475392) (xy 368.987265 -37.525889)
			(xy 369.003333 -37.579296) (xy 369.011453 -37.634472) (xy 369.011962 -37.662358) (xy 369.011453 -37.690244)
			(xy 369.003333 -37.74542) (xy 368.987265 -37.798827) (xy 368.963593 -37.849324) (xy 368.93282 -37.895837)
			(xy 368.895603 -37.937374) (xy 368.852735 -37.973049) (xy 368.805129 -38.002103) (xy 368.7538 -38.023915)
			(xy 368.699843 -38.038021) (xy 368.644406 -38.044121) (xy 368.588672 -38.042084) (xy 368.533829 -38.031954)
			(xy 368.481045 -38.013947) (xy 368.431445 -37.988446) (xy 368.386087 -37.955995) (xy 368.345938 -37.917286)
			(xy 368.311852 -37.873143) (xy 368.284556 -37.824508) (xy 368.264633 -37.772417) (xy 368.252507 -37.71798)
			(xy 368.248436 -37.662358) (xy 366.774214 -37.662358) (xy 366.743594 -37.708639) (xy 366.706377 -37.750176)
			(xy 366.663509 -37.785851) (xy 366.615903 -37.814905) (xy 366.564574 -37.836717) (xy 366.510617 -37.850823)
			(xy 366.45518 -37.856923) (xy 366.399446 -37.854886) (xy 366.344603 -37.844756) (xy 366.291819 -37.826749)
			(xy 366.242219 -37.801248) (xy 366.196861 -37.768797) (xy 366.156712 -37.730088) (xy 366.122626 -37.685945)
			(xy 366.09533 -37.63731) (xy 366.075407 -37.585219) (xy 366.063281 -37.530782) (xy 366.05921 -37.47516)
			(xy 361.675315 -37.47516) (xy 361.670187 -37.477817) (xy 361.588696 -37.51103) (xy 361.504522 -37.536694)
			(xy 361.418363 -37.554598) (xy 361.330933 -37.564593) (xy 361.242956 -37.566597) (xy 361.155162 -37.560591)
			(xy 361.068278 -37.546627) (xy 360.983023 -37.52482) (xy 360.900104 -37.495351) (xy 360.820209 -37.458464)
			(xy 360.744 -37.414464) (xy 360.672107 -37.363716) (xy 360.605126 -37.306642) (xy 360.543614 -37.243712)
			(xy 360.488078 -37.17545) (xy 360.43898 -37.102421) (xy 360.396727 -37.025229) (xy 360.361668 -36.944515)
			(xy 360.334093 -36.860947) (xy 360.314233 -36.775218) (xy 360.30225 -36.688038) (xy 360.298245 -36.60013)
			(xy 356.068688 -36.60013) (xy 356.053077 -36.652017) (xy 356.029405 -36.702514) (xy 355.998632 -36.749027)
			(xy 355.961415 -36.790564) (xy 355.918547 -36.826239) (xy 355.870941 -36.855293) (xy 355.819612 -36.877105)
			(xy 355.765655 -36.891211) (xy 355.710218 -36.897311) (xy 355.654484 -36.895274) (xy 355.599641 -36.885144)
			(xy 355.546857 -36.867137) (xy 355.497257 -36.841636) (xy 355.451899 -36.809185) (xy 355.41175 -36.770476)
			(xy 355.377664 -36.726333) (xy 355.350368 -36.677698) (xy 355.330445 -36.625607) (xy 355.318319 -36.57117)
			(xy 355.314248 -36.515548) (xy 354.188046 -36.515548) (xy 354.184818 -36.520427) (xy 354.147601 -36.561964)
			(xy 354.104733 -36.597639) (xy 354.057127 -36.626693) (xy 354.005798 -36.648505) (xy 353.951841 -36.662611)
			(xy 353.896404 -36.668711) (xy 353.84067 -36.666674) (xy 353.785827 -36.656544) (xy 353.733043 -36.638537)
			(xy 353.683443 -36.613036) (xy 353.638085 -36.580585) (xy 353.597936 -36.541876) (xy 353.56385 -36.497733)
			(xy 353.536554 -36.449098) (xy 353.516631 -36.397007) (xy 353.504505 -36.34257) (xy 353.500434 -36.286948)
			(xy 346.953361 -36.286948) (xy 346.967497 -36.317103) (xy 346.983565 -36.37051) (xy 346.991685 -36.425686)
			(xy 346.992194 -36.453572) (xy 346.991685 -36.481458) (xy 346.983565 -36.536634) (xy 346.967497 -36.590041)
			(xy 346.943825 -36.640538) (xy 346.913052 -36.687051) (xy 346.875835 -36.728588) (xy 346.832967 -36.764263)
			(xy 346.785361 -36.793317) (xy 346.734032 -36.815129) (xy 346.680075 -36.829235) (xy 346.624638 -36.835335)
			(xy 346.568904 -36.833298) (xy 346.514061 -36.823168) (xy 346.461277 -36.805161) (xy 346.411677 -36.77966)
			(xy 346.366319 -36.747209) (xy 346.32617 -36.7085) (xy 346.292084 -36.664357) (xy 346.264788 -36.615722)
			(xy 346.244865 -36.563631) (xy 346.232739 -36.509194) (xy 346.228668 -36.453572) (xy 343.67279 -36.453572)
			(xy 343.676985 -36.482074) (xy 343.677494 -36.50996) (xy 343.676985 -36.537846) (xy 343.668865 -36.593022)
			(xy 343.652797 -36.646429) (xy 343.629125 -36.696926) (xy 343.598352 -36.743439) (xy 343.561135 -36.784976)
			(xy 343.518267 -36.820651) (xy 343.470661 -36.849705) (xy 343.419332 -36.871517) (xy 343.365375 -36.885623)
			(xy 343.309938 -36.891723) (xy 343.254204 -36.889686) (xy 343.199361 -36.879556) (xy 343.146577 -36.861549)
			(xy 343.096977 -36.836048) (xy 343.051619 -36.803597) (xy 343.01147 -36.764888) (xy 342.977384 -36.720745)
			(xy 342.950088 -36.67211) (xy 342.930165 -36.620019) (xy 342.918039 -36.565582) (xy 342.913968 -36.50996)
			(xy 339.966403 -36.50996) (xy 340.279736 -37.083238) (xy 340.284169 -37.090667) (xy 340.297021 -37.102234)
			(xy 340.304882 -37.105844) (xy 340.31301 -37.109146) (xy 340.329774 -37.110162) (xy 340.338156 -37.107876)
			(xy 340.363422 -37.10125) (xy 340.415164 -37.094116) (xy 340.44128 -37.093652) (xy 340.469016 -37.094155)
			(xy 340.523902 -37.102197) (xy 340.577046 -37.118101) (xy 340.627327 -37.141531) (xy 340.673687 -37.171993)
			(xy 340.715148 -37.208846) (xy 340.750837 -37.251313) (xy 340.780002 -37.2985) (xy 340.802028 -37.349411)
			(xy 340.816452 -37.402976) (xy 340.820248 -37.430456) (xy 340.821772 -37.444934) (xy 340.823042 -37.47516)
			(xy 340.822581 -37.502014) (xy 340.815046 -37.555192) (xy 340.800134 -37.606789) (xy 340.778139 -37.655787)
			(xy 340.773996 -37.662358) (xy 342.248488 -37.662358) (xy 342.252559 -37.606736) (xy 342.264685 -37.552299)
			(xy 342.284608 -37.500208) (xy 342.311904 -37.451573) (xy 342.34599 -37.40743) (xy 342.386139 -37.368721)
			(xy 342.431497 -37.33627) (xy 342.481097 -37.310769) (xy 342.533881 -37.292762) (xy 342.588724 -37.282632)
			(xy 342.644458 -37.280595) (xy 342.699895 -37.286695) (xy 342.753852 -37.300801) (xy 342.805181 -37.322613)
			(xy 342.852787 -37.351667) (xy 342.895655 -37.387342) (xy 342.932872 -37.428879) (xy 342.963645 -37.475392)
			(xy 342.987317 -37.525889) (xy 343.003385 -37.579296) (xy 343.011505 -37.634472) (xy 343.012014 -37.662358)
			(xy 343.011505 -37.690244) (xy 343.003385 -37.74542) (xy 342.994751 -37.774118) (xy 353.764848 -37.774118)
			(xy 353.768919 -37.718496) (xy 353.781045 -37.664059) (xy 353.800968 -37.611968) (xy 353.828264 -37.563333)
			(xy 353.86235 -37.51919) (xy 353.902499 -37.480481) (xy 353.947857 -37.44803) (xy 353.997457 -37.422529)
			(xy 354.050241 -37.404522) (xy 354.105084 -37.394392) (xy 354.160818 -37.392355) (xy 354.216255 -37.398455)
			(xy 354.270212 -37.412561) (xy 354.321541 -37.434373) (xy 354.369147 -37.463427) (xy 354.412015 -37.499102)
			(xy 354.449232 -37.540639) (xy 354.480005 -37.587152) (xy 354.503677 -37.637649) (xy 354.519745 -37.691056)
			(xy 354.527865 -37.746232) (xy 354.528374 -37.774118) (xy 354.527865 -37.802004) (xy 354.519745 -37.85718)
			(xy 354.503677 -37.910587) (xy 354.480005 -37.961084) (xy 354.449232 -38.007597) (xy 354.412015 -38.049134)
			(xy 354.369147 -38.084809) (xy 354.321541 -38.113863) (xy 354.270212 -38.135675) (xy 354.216255 -38.149781)
			(xy 354.160818 -38.155881) (xy 354.105084 -38.153844) (xy 354.050241 -38.143714) (xy 353.997457 -38.125707)
			(xy 353.947857 -38.100206) (xy 353.902499 -38.067755) (xy 353.86235 -38.029046) (xy 353.828264 -37.984903)
			(xy 353.800968 -37.936268) (xy 353.781045 -37.884177) (xy 353.768919 -37.82974) (xy 353.764848 -37.774118)
			(xy 342.994751 -37.774118) (xy 342.987317 -37.798827) (xy 342.963645 -37.849324) (xy 342.932872 -37.895837)
			(xy 342.895655 -37.937374) (xy 342.852787 -37.973049) (xy 342.805181 -38.002103) (xy 342.753852 -38.023915)
			(xy 342.699895 -38.038021) (xy 342.644458 -38.044121) (xy 342.588724 -38.042084) (xy 342.533881 -38.031954)
			(xy 342.481097 -38.013947) (xy 342.431497 -37.988446) (xy 342.386139 -37.955995) (xy 342.34599 -37.917286)
			(xy 342.311904 -37.873143) (xy 342.284608 -37.824508) (xy 342.264685 -37.772417) (xy 342.252559 -37.71798)
			(xy 342.248488 -37.662358) (xy 340.773996 -37.662358) (xy 340.749495 -37.701219) (xy 340.714767 -37.74219)
			(xy 340.695026 -37.760402) (xy 340.694772 -37.760656) (xy 340.688618 -37.766587) (xy 340.680307 -37.78151)
			(xy 340.678516 -37.789866) (xy 340.676992 -37.797994) (xy 340.679786 -37.815012) (xy 341.016336 -38.430454)
			(xy 341.179935 -38.729948) (xy 346.00112 -38.729948) (xy 346.00112 -38.675452) (xy 346.008875 -38.621512)
			(xy 346.024228 -38.569224) (xy 346.046866 -38.519653) (xy 346.076327 -38.473809) (xy 346.112013 -38.432623)
			(xy 346.153197 -38.396936) (xy 346.199041 -38.367472) (xy 346.248611 -38.344833) (xy 346.300898 -38.329478)
			(xy 346.354838 -38.321721) (xy 346.382086 -38.321234) (xy 346.410391 -38.321719) (xy 346.46638 -38.33007)
			(xy 346.52052 -38.346605) (xy 346.571621 -38.37096) (xy 346.618561 -38.402602) (xy 346.660308 -38.440835)
			(xy 346.695945 -38.484818) (xy 346.710762 -38.50894) (xy 346.718313 -38.521007) (xy 346.738941 -38.540611)
			(xy 346.764183 -38.553753) (xy 346.792074 -38.559408) (xy 346.820441 -38.557138) (xy 346.847077 -38.547118)
			(xy 346.869907 -38.530129) (xy 346.87891 -38.5191) (xy 346.897096 -38.496223) (xy 346.939259 -38.455759)
			(xy 346.987095 -38.422192) (xy 347.039487 -38.396305) (xy 347.095211 -38.378703) (xy 347.152967 -38.369797)
			(xy 347.182186 -38.36924) (xy 347.209443 -38.369606) (xy 347.263402 -38.377362) (xy 347.315708 -38.392719)
			(xy 347.365297 -38.415364) (xy 347.411157 -38.444835) (xy 347.452357 -38.480533) (xy 347.488057 -38.521731)
			(xy 347.51753 -38.567591) (xy 347.540176 -38.617178) (xy 347.555535 -38.669484) (xy 347.563293 -38.723443)
			(xy 347.563293 -38.777957) (xy 347.555535 -38.831916) (xy 347.540176 -38.884222) (xy 347.51753 -38.933809)
			(xy 347.488057 -38.979669) (xy 347.452357 -39.020867) (xy 347.411157 -39.056565) (xy 347.365297 -39.086036)
			(xy 347.315708 -39.108681) (xy 347.263402 -39.124038) (xy 347.209443 -39.131794) (xy 347.182186 -39.132256)
			(xy 347.153883 -39.131719) (xy 347.097896 -39.123379) (xy 347.043757 -39.106853) (xy 346.992656 -39.082506)
			(xy 346.945715 -39.050872) (xy 346.903966 -39.012647) (xy 346.868327 -38.968669) (xy 346.85351 -38.94455)
			(xy 346.845866 -38.932548) (xy 346.825256 -38.91295) (xy 346.800034 -38.899808) (xy 346.772163 -38.894145)
			(xy 346.743812 -38.896403) (xy 346.717189 -38.906404) (xy 346.694364 -38.923372) (xy 346.685362 -38.93439)
			(xy 346.66719 -38.957278) (xy 346.625024 -38.997742) (xy 346.577186 -39.031308) (xy 346.524791 -39.057193)
			(xy 346.469064 -39.074793) (xy 346.411306 -39.083695) (xy 346.382086 -39.08425) (xy 346.354838 -39.083679)
			(xy 346.300898 -39.075922) (xy 346.248611 -39.060567) (xy 346.199041 -39.037928) (xy 346.153197 -39.008464)
			(xy 346.112013 -38.972777) (xy 346.076327 -38.931591) (xy 346.046866 -38.885747) (xy 346.024228 -38.836176)
			(xy 346.008875 -38.783888) (xy 346.00112 -38.729948) (xy 341.179935 -38.729948) (xy 341.50681 -39.328344)
			(xy 341.52317 -39.35881) (xy 341.552151 -39.421605) (xy 341.564722 -39.45382) (xy 341.573543 -39.477592)
			(xy 341.589046 -39.525875) (xy 341.59571 -39.55034) (xy 341.707838 -39.97198) (xy 348.195898 -39.97198)
			(xy 348.199969 -39.916358) (xy 348.212095 -39.861921) (xy 348.232018 -39.80983) (xy 348.259314 -39.761195)
			(xy 348.2934 -39.717052) (xy 348.333549 -39.678343) (xy 348.378907 -39.645892) (xy 348.428507 -39.620391)
			(xy 348.481291 -39.602384) (xy 348.536134 -39.592254) (xy 348.591868 -39.590217) (xy 348.647305 -39.596317)
			(xy 348.701262 -39.610423) (xy 348.752591 -39.632235) (xy 348.800197 -39.661289) (xy 348.843065 -39.696964)
			(xy 348.880282 -39.738501) (xy 348.911055 -39.785014) (xy 348.934727 -39.835511) (xy 348.950795 -39.888918)
			(xy 348.958915 -39.944094) (xy 348.959424 -39.97198) (xy 348.958915 -39.999866) (xy 348.950795 -40.055042)
			(xy 348.934727 -40.108449) (xy 348.911055 -40.158946) (xy 348.880282 -40.205459) (xy 348.843065 -40.246996)
			(xy 348.800197 -40.282671) (xy 348.752591 -40.311725) (xy 348.701262 -40.333537) (xy 348.647305 -40.347643)
			(xy 348.591868 -40.353743) (xy 348.536134 -40.351706) (xy 348.481291 -40.341576) (xy 348.428507 -40.323569)
			(xy 348.378907 -40.298068) (xy 348.333549 -40.265617) (xy 348.2934 -40.226908) (xy 348.259314 -40.182765)
			(xy 348.232018 -40.13413) (xy 348.212095 -40.082039) (xy 348.199969 -40.027602) (xy 348.195898 -39.97198)
			(xy 341.707838 -39.97198) (xy 341.810848 -40.35933) (xy 341.910924 -40.736012) (xy 341.914988 -40.745664)
			(xy 342.038187 -40.971724) (xy 348.894144 -40.971724) (xy 348.898215 -40.916102) (xy 348.910341 -40.861665)
			(xy 348.930264 -40.809574) (xy 348.95756 -40.760939) (xy 348.991646 -40.716796) (xy 349.031795 -40.678087)
			(xy 349.077153 -40.645636) (xy 349.126753 -40.620135) (xy 349.179537 -40.602128) (xy 349.23438 -40.591998)
			(xy 349.290114 -40.589961) (xy 349.345551 -40.596061) (xy 349.399508 -40.610167) (xy 349.450837 -40.631979)
			(xy 349.498443 -40.661033) (xy 349.541311 -40.696708) (xy 349.578528 -40.738245) (xy 349.609301 -40.784758)
			(xy 349.632973 -40.835255) (xy 349.649041 -40.888662) (xy 349.657161 -40.943838) (xy 349.65767 -40.971724)
			(xy 349.657161 -40.99961) (xy 349.649041 -41.054786) (xy 349.632973 -41.108193) (xy 349.609301 -41.15869)
			(xy 349.578528 -41.205203) (xy 349.541311 -41.24674) (xy 349.514862 -41.268751) (xy 364.14405 -41.268751)
			(xy 364.14405 -41.214249) (xy 364.151806 -41.160301) (xy 364.167159 -41.108007) (xy 364.189799 -41.058429)
			(xy 364.219263 -41.012578) (xy 364.254952 -40.971386) (xy 364.296139 -40.935691) (xy 364.341987 -40.906222)
			(xy 364.391562 -40.883576) (xy 364.443855 -40.868216) (xy 364.497801 -40.860453) (xy 364.525052 -40.859964)
			(xy 364.553792 -40.860466) (xy 364.61062 -40.869095) (xy 364.66551 -40.886151) (xy 364.717221 -40.911247)
			(xy 364.764583 -40.943816) (xy 364.78591 -40.963088) (xy 364.792768 -40.969692) (xy 364.810802 -40.976804)
			(xy 364.899702 -40.976804) (xy 364.917736 -40.969692) (xy 364.924594 -40.963088) (xy 364.945907 -40.943801)
			(xy 364.993272 -40.911235) (xy 365.044987 -40.886145) (xy 365.099881 -40.869098) (xy 365.156712 -40.860481)
			(xy 365.185452 -40.859964) (xy 365.212705 -40.86048) (xy 365.266657 -40.868231) (xy 365.318957 -40.883582)
			(xy 365.36854 -40.90622) (xy 365.414395 -40.935684) (xy 365.455591 -40.971375) (xy 365.491287 -41.012566)
			(xy 365.520757 -41.058418) (xy 365.543402 -41.107998) (xy 365.558759 -41.160296) (xy 365.566517 -41.214247)
			(xy 365.566517 -41.268753) (xy 365.558759 -41.322704) (xy 365.543402 -41.375002) (xy 365.520757 -41.424582)
			(xy 365.491287 -41.470434) (xy 365.455591 -41.511625) (xy 365.414395 -41.547316) (xy 365.36854 -41.57678)
			(xy 365.318957 -41.599418) (xy 365.266657 -41.614769) (xy 365.212705 -41.62252) (xy 365.185452 -41.62298)
			(xy 365.156713 -41.622464) (xy 365.099886 -41.613836) (xy 365.044996 -41.596783) (xy 364.993285 -41.571691)
			(xy 364.945922 -41.539126) (xy 364.924594 -41.519856) (xy 364.917736 -41.513252) (xy 364.899702 -41.50614)
			(xy 364.810802 -41.50614) (xy 364.792768 -41.513252) (xy 364.78591 -41.519856) (xy 364.764602 -41.539149)
			(xy 364.717235 -41.571712) (xy 364.665518 -41.5968) (xy 364.610623 -41.613846) (xy 364.553792 -41.622463)
			(xy 364.525052 -41.62298) (xy 364.497801 -41.622547) (xy 364.443854 -41.614784) (xy 364.391562 -41.599424)
			(xy 364.341987 -41.576778) (xy 364.296139 -41.547309) (xy 364.254952 -41.511614) (xy 364.219263 -41.470422)
			(xy 364.189799 -41.424571) (xy 364.167159 -41.374993) (xy 364.151806 -41.322699) (xy 364.14405 -41.268751)
			(xy 349.514862 -41.268751) (xy 349.498443 -41.282415) (xy 349.450837 -41.311469) (xy 349.399508 -41.333281)
			(xy 349.345551 -41.347387) (xy 349.290114 -41.353487) (xy 349.23438 -41.35145) (xy 349.179537 -41.34132)
			(xy 349.126753 -41.323313) (xy 349.077153 -41.297812) (xy 349.031795 -41.265361) (xy 348.991646 -41.226652)
			(xy 348.95756 -41.182509) (xy 348.930264 -41.133874) (xy 348.910341 -41.081783) (xy 348.898215 -41.027346)
			(xy 348.894144 -40.971724) (xy 342.038187 -40.971724) (xy 342.155018 -41.1861) (xy 342.177229 -41.228003)
			(xy 342.214447 -41.315241) (xy 342.243134 -41.405644) (xy 342.263025 -41.49838) (xy 342.273937 -41.592595)
			(xy 342.275414 -41.639998) (xy 342.285574 -42.142918) (xy 342.286082 -42.146728) (xy 342.292686 -42.171874)
			(xy 342.297512 -42.189908) (xy 342.307384 -42.228571) (xy 342.321655 -42.307088) (xy 342.329598 -42.386496)
			(xy 342.330786 -42.426382) (xy 342.348292 -43.305222) (xy 366.607344 -43.305222) (xy 366.607812 -43.277852)
			(xy 366.615628 -43.223672) (xy 366.631116 -43.171169) (xy 366.653957 -43.121422) (xy 366.683682 -43.075455)
			(xy 366.701324 -43.054524) (xy 366.701578 -43.05427) (xy 366.707151 -43.047174) (xy 366.713404 -43.030264)
			(xy 366.71377 -43.02125) (xy 366.71377 -42.954194) (xy 366.713423 -42.945176) (xy 366.707169 -42.928259)
			(xy 366.701578 -42.921174) (xy 366.701324 -42.921174) (xy 366.701324 -42.92092) (xy 366.683685 -42.899988)
			(xy 366.653972 -42.854016) (xy 366.631136 -42.804268) (xy 366.615645 -42.751767) (xy 366.607817 -42.697591)
			(xy 366.607344 -42.670222) (xy 366.607896 -42.641484) (xy 366.616514 -42.584659) (xy 366.633558 -42.529769)
			(xy 366.658643 -42.478057) (xy 366.691201 -42.430692) (xy 366.710468 -42.409364) (xy 366.717072 -42.402506)
			(xy 366.724184 -42.384472) (xy 366.724184 -42.295572) (xy 366.717072 -42.277538) (xy 366.710468 -42.27068)
			(xy 366.691222 -42.249333) (xy 366.65866 -42.201972) (xy 366.633571 -42.150264) (xy 366.616522 -42.095376)
			(xy 366.607899 -42.038553) (xy 366.607896 -41.981079) (xy 366.616515 -41.924255) (xy 366.633559 -41.869366)
			(xy 366.658644 -41.817655) (xy 366.691201 -41.770292) (xy 366.710468 -41.748964) (xy 366.717072 -41.742106)
			(xy 366.724184 -41.724072) (xy 366.724184 -41.635172) (xy 366.717072 -41.617138) (xy 366.710468 -41.61028)
			(xy 366.691213 -41.58894) (xy 366.658643 -41.541582) (xy 366.633547 -41.489874) (xy 366.616493 -41.434986)
			(xy 366.607867 -41.37816) (xy 366.607344 -41.349422) (xy 366.60783 -41.322171) (xy 366.615586 -41.268223)
			(xy 366.630941 -41.215928) (xy 366.653583 -41.166351) (xy 366.683049 -41.120501) (xy 366.71874 -41.07931)
			(xy 366.759931 -41.043619) (xy 366.805781 -41.014153) (xy 366.855358 -40.991511) (xy 366.907653 -40.976156)
			(xy 366.961601 -40.9684) (xy 367.016103 -40.9684) (xy 367.070051 -40.976156) (xy 367.122346 -40.991511)
			(xy 367.171923 -41.014153) (xy 367.217773 -41.043619) (xy 367.258964 -41.07931) (xy 367.294655 -41.120501)
			(xy 367.324121 -41.166351) (xy 367.346763 -41.215928) (xy 367.362118 -41.268223) (xy 367.369874 -41.322171)
			(xy 367.37036 -41.349422) (xy 367.369834 -41.378161) (xy 367.361209 -41.434987) (xy 367.344159 -41.489877)
			(xy 367.319068 -41.541589) (xy 367.286505 -41.588952) (xy 367.267236 -41.61028) (xy 367.260632 -41.617138)
			(xy 367.25352 -41.635172) (xy 367.25352 -41.724072) (xy 367.260632 -41.742106) (xy 367.267236 -41.748964)
			(xy 367.28653 -41.770271) (xy 367.319098 -41.817636) (xy 367.344191 -41.86935) (xy 367.361242 -41.924245)
			(xy 367.369863 -41.981075) (xy 367.369861 -42.038557) (xy 367.361234 -42.095387) (xy 367.34418 -42.150279)
			(xy 367.319082 -42.201992) (xy 367.28651 -42.249354) (xy 367.267236 -42.27068) (xy 367.260632 -42.277538)
			(xy 367.25352 -42.295572) (xy 367.25352 -42.384472) (xy 367.260632 -42.402506) (xy 367.267236 -42.409364)
			(xy 367.286513 -42.430686) (xy 367.319079 -42.478049) (xy 367.344171 -42.529762) (xy 367.36122 -42.584654)
			(xy 367.369841 -42.641483) (xy 367.37036 -42.670222) (xy 367.369917 -42.697593) (xy 367.362095 -42.751774)
			(xy 367.346601 -42.804277) (xy 367.326044 -42.849038) (xy 369.192046 -42.849038) (xy 369.196117 -42.793416)
			(xy 369.208243 -42.738979) (xy 369.228166 -42.686888) (xy 369.255462 -42.638253) (xy 369.289548 -42.59411)
			(xy 369.329697 -42.555401) (xy 369.375055 -42.52295) (xy 369.424655 -42.497449) (xy 369.477439 -42.479442)
			(xy 369.532282 -42.469312) (xy 369.588016 -42.467275) (xy 369.643453 -42.473375) (xy 369.69741 -42.487481)
			(xy 369.748739 -42.509293) (xy 369.796345 -42.538347) (xy 369.839213 -42.574022) (xy 369.87643 -42.615559)
			(xy 369.907203 -42.662072) (xy 369.930875 -42.712569) (xy 369.946943 -42.765976) (xy 369.955063 -42.821152)
			(xy 369.955572 -42.849038) (xy 369.955063 -42.876924) (xy 369.946943 -42.9321) (xy 369.930875 -42.985507)
			(xy 369.907203 -43.036004) (xy 369.87643 -43.082517) (xy 369.839213 -43.124054) (xy 369.796345 -43.159729)
			(xy 369.748739 -43.188783) (xy 369.69741 -43.210595) (xy 369.643453 -43.224701) (xy 369.588016 -43.230801)
			(xy 369.532282 -43.228764) (xy 369.477439 -43.218634) (xy 369.424655 -43.200627) (xy 369.375055 -43.175126)
			(xy 369.329697 -43.142675) (xy 369.289548 -43.103966) (xy 369.255462 -43.059823) (xy 369.228166 -43.011188)
			(xy 369.208243 -42.959097) (xy 369.196117 -42.90466) (xy 369.192046 -42.849038) (xy 367.326044 -42.849038)
			(xy 367.323754 -42.854024) (xy 367.294024 -42.899989) (xy 367.27638 -42.92092) (xy 367.276126 -42.921174)
			(xy 367.270536 -42.928258) (xy 367.264293 -42.945177) (xy 367.263934 -42.954194) (xy 367.263934 -43.02125)
			(xy 367.264308 -43.030265) (xy 367.270543 -43.047183) (xy 367.276126 -43.05427) (xy 367.27638 -43.05427)
			(xy 367.27638 -43.054524) (xy 367.293994 -43.075476) (xy 367.32371 -43.121443) (xy 367.346551 -43.171186)
			(xy 367.362048 -43.223682) (xy 367.369883 -43.277854) (xy 367.37036 -43.305222) (xy 367.369874 -43.332473)
			(xy 367.362118 -43.386421) (xy 367.346763 -43.438716) (xy 367.324121 -43.488293) (xy 367.294655 -43.534143)
			(xy 367.258964 -43.575334) (xy 367.217773 -43.611025) (xy 367.171923 -43.640491) (xy 367.122346 -43.663133)
			(xy 367.070051 -43.678488) (xy 367.016103 -43.686244) (xy 366.961601 -43.686244) (xy 366.907653 -43.678488)
			(xy 366.855358 -43.663133) (xy 366.805781 -43.640491) (xy 366.759931 -43.611025) (xy 366.71874 -43.575334)
			(xy 366.683049 -43.534143) (xy 366.653583 -43.488293) (xy 366.630941 -43.438716) (xy 366.615586 -43.386421)
			(xy 366.60783 -43.332473) (xy 366.607344 -43.305222) (xy 342.348292 -43.305222) (xy 342.356878 -43.73626)
			(xy 368.513104 -43.73626) (xy 368.517175 -43.680638) (xy 368.529301 -43.626201) (xy 368.549224 -43.57411)
			(xy 368.57652 -43.525475) (xy 368.610606 -43.481332) (xy 368.650755 -43.442623) (xy 368.696113 -43.410172)
			(xy 368.745713 -43.384671) (xy 368.798497 -43.366664) (xy 368.85334 -43.356534) (xy 368.909074 -43.354497)
			(xy 368.964511 -43.360597) (xy 369.018468 -43.374703) (xy 369.069797 -43.396515) (xy 369.117403 -43.425569)
			(xy 369.160271 -43.461244) (xy 369.197488 -43.502781) (xy 369.228261 -43.549294) (xy 369.236487 -43.566842)
			(xy 371.633494 -43.566842) (xy 371.637565 -43.51122) (xy 371.649691 -43.456783) (xy 371.669614 -43.404692)
			(xy 371.69691 -43.356057) (xy 371.730996 -43.311914) (xy 371.771145 -43.273205) (xy 371.816503 -43.240754)
			(xy 371.866103 -43.215253) (xy 371.918887 -43.197246) (xy 371.97373 -43.187116) (xy 372.029464 -43.185079)
			(xy 372.084901 -43.191179) (xy 372.138858 -43.205285) (xy 372.190187 -43.227097) (xy 372.237793 -43.256151)
			(xy 372.280661 -43.291826) (xy 372.317878 -43.333363) (xy 372.348651 -43.379876) (xy 372.372323 -43.430373)
			(xy 372.388391 -43.48378) (xy 372.396511 -43.538956) (xy 372.39702 -43.566842) (xy 372.396511 -43.594728)
			(xy 372.388391 -43.649904) (xy 372.372323 -43.703311) (xy 372.348651 -43.753808) (xy 372.317878 -43.800321)
			(xy 372.280661 -43.841858) (xy 372.262574 -43.85691) (xy 373.019826 -43.85691) (xy 373.023897 -43.801288)
			(xy 373.036023 -43.746851) (xy 373.055946 -43.69476) (xy 373.083242 -43.646125) (xy 373.117328 -43.601982)
			(xy 373.157477 -43.563273) (xy 373.202835 -43.530822) (xy 373.252435 -43.505321) (xy 373.305219 -43.487314)
			(xy 373.360062 -43.477184) (xy 373.415796 -43.475147) (xy 373.471233 -43.481247) (xy 373.52519 -43.495353)
			(xy 373.576519 -43.517165) (xy 373.624125 -43.546219) (xy 373.666993 -43.581894) (xy 373.70421 -43.623431)
			(xy 373.734983 -43.669944) (xy 373.758655 -43.720441) (xy 373.774723 -43.773848) (xy 373.782843 -43.829024)
			(xy 373.783352 -43.85691) (xy 373.782843 -43.884796) (xy 373.774723 -43.939972) (xy 373.758655 -43.993379)
			(xy 373.734983 -44.043876) (xy 373.70421 -44.090389) (xy 373.666993 -44.131926) (xy 373.624125 -44.167601)
			(xy 373.576519 -44.196655) (xy 373.52519 -44.218467) (xy 373.471233 -44.232573) (xy 373.415796 -44.238673)
			(xy 373.360062 -44.236636) (xy 373.305219 -44.226506) (xy 373.252435 -44.208499) (xy 373.202835 -44.182998)
			(xy 373.157477 -44.150547) (xy 373.117328 -44.111838) (xy 373.083242 -44.067695) (xy 373.055946 -44.01906)
			(xy 373.036023 -43.966969) (xy 373.023897 -43.912532) (xy 373.019826 -43.85691) (xy 372.262574 -43.85691)
			(xy 372.237793 -43.877533) (xy 372.190187 -43.906587) (xy 372.138858 -43.928399) (xy 372.084901 -43.942505)
			(xy 372.029464 -43.948605) (xy 371.97373 -43.946568) (xy 371.918887 -43.936438) (xy 371.866103 -43.918431)
			(xy 371.816503 -43.89293) (xy 371.771145 -43.860479) (xy 371.730996 -43.82177) (xy 371.69691 -43.777627)
			(xy 371.669614 -43.728992) (xy 371.649691 -43.676901) (xy 371.637565 -43.622464) (xy 371.633494 -43.566842)
			(xy 369.236487 -43.566842) (xy 369.251933 -43.599791) (xy 369.268001 -43.653198) (xy 369.276121 -43.708374)
			(xy 369.27663 -43.73626) (xy 369.276121 -43.764146) (xy 369.268001 -43.819322) (xy 369.251933 -43.872729)
			(xy 369.228261 -43.923226) (xy 369.197488 -43.969739) (xy 369.160271 -44.011276) (xy 369.117403 -44.046951)
			(xy 369.069797 -44.076005) (xy 369.018468 -44.097817) (xy 368.964511 -44.111923) (xy 368.909074 -44.118023)
			(xy 368.85334 -44.115986) (xy 368.798497 -44.105856) (xy 368.745713 -44.087849) (xy 368.696113 -44.062348)
			(xy 368.650755 -44.029897) (xy 368.610606 -43.991188) (xy 368.57652 -43.947045) (xy 368.549224 -43.89841)
			(xy 368.529301 -43.846319) (xy 368.517175 -43.791882) (xy 368.513104 -43.73626) (xy 342.356878 -43.73626)
			(xy 342.38433 -45.114464) (xy 368.36553 -45.114464) (xy 368.369601 -45.058842) (xy 368.381727 -45.004405)
			(xy 368.40165 -44.952314) (xy 368.428946 -44.903679) (xy 368.463032 -44.859536) (xy 368.503181 -44.820827)
			(xy 368.548539 -44.788376) (xy 368.598139 -44.762875) (xy 368.650923 -44.744868) (xy 368.705766 -44.734738)
			(xy 368.7615 -44.732701) (xy 368.816937 -44.738801) (xy 368.870894 -44.752907) (xy 368.922223 -44.774719)
			(xy 368.969829 -44.803773) (xy 369.012697 -44.839448) (xy 369.042679 -44.87291) (xy 375.233182 -44.87291)
			(xy 375.237253 -44.817288) (xy 375.249379 -44.762851) (xy 375.269302 -44.71076) (xy 375.296598 -44.662125)
			(xy 375.330684 -44.617982) (xy 375.370833 -44.579273) (xy 375.416191 -44.546822) (xy 375.465791 -44.521321)
			(xy 375.518575 -44.503314) (xy 375.573418 -44.493184) (xy 375.629152 -44.491147) (xy 375.684589 -44.497247)
			(xy 375.738546 -44.511353) (xy 375.789875 -44.533165) (xy 375.837481 -44.562219) (xy 375.880349 -44.597894)
			(xy 375.917566 -44.639431) (xy 375.948339 -44.685944) (xy 375.972011 -44.736441) (xy 375.988079 -44.789848)
			(xy 375.996199 -44.845024) (xy 375.996708 -44.87291) (xy 375.996199 -44.900796) (xy 375.988079 -44.955972)
			(xy 375.972011 -45.009379) (xy 375.948339 -45.059876) (xy 375.917566 -45.106389) (xy 375.880349 -45.147926)
			(xy 375.837481 -45.183601) (xy 375.789875 -45.212655) (xy 375.738546 -45.234467) (xy 375.684589 -45.248573)
			(xy 375.629152 -45.254673) (xy 375.573418 -45.252636) (xy 375.518575 -45.242506) (xy 375.465791 -45.224499)
			(xy 375.416191 -45.198998) (xy 375.370833 -45.166547) (xy 375.330684 -45.127838) (xy 375.296598 -45.083695)
			(xy 375.269302 -45.03506) (xy 375.249379 -44.982969) (xy 375.237253 -44.928532) (xy 375.233182 -44.87291)
			(xy 369.042679 -44.87291) (xy 369.049914 -44.880985) (xy 369.080687 -44.927498) (xy 369.104359 -44.977995)
			(xy 369.120427 -45.031402) (xy 369.128547 -45.086578) (xy 369.129056 -45.114464) (xy 369.128547 -45.14235)
			(xy 369.120427 -45.197526) (xy 369.104359 -45.250933) (xy 369.080687 -45.30143) (xy 369.049914 -45.347943)
			(xy 369.044272 -45.35424) (xy 373.003824 -45.35424) (xy 373.007895 -45.298618) (xy 373.020021 -45.244181)
			(xy 373.039944 -45.19209) (xy 373.06724 -45.143455) (xy 373.101326 -45.099312) (xy 373.141475 -45.060603)
			(xy 373.186833 -45.028152) (xy 373.236433 -45.002651) (xy 373.289217 -44.984644) (xy 373.34406 -44.974514)
			(xy 373.399794 -44.972477) (xy 373.455231 -44.978577) (xy 373.509188 -44.992683) (xy 373.560517 -45.014495)
			(xy 373.608123 -45.043549) (xy 373.650991 -45.079224) (xy 373.688208 -45.120761) (xy 373.718981 -45.167274)
			(xy 373.742653 -45.217771) (xy 373.758721 -45.271178) (xy 373.766841 -45.326354) (xy 373.76735 -45.35424)
			(xy 373.766841 -45.382126) (xy 373.758721 -45.437302) (xy 373.742653 -45.490709) (xy 373.718981 -45.541206)
			(xy 373.688208 -45.587719) (xy 373.650991 -45.629256) (xy 373.608123 -45.664931) (xy 373.560517 -45.693985)
			(xy 373.509188 -45.715797) (xy 373.455231 -45.729903) (xy 373.399794 -45.736003) (xy 373.34406 -45.733966)
			(xy 373.289217 -45.723836) (xy 373.236433 -45.705829) (xy 373.186833 -45.680328) (xy 373.141475 -45.647877)
			(xy 373.101326 -45.609168) (xy 373.06724 -45.565025) (xy 373.039944 -45.51639) (xy 373.020021 -45.464299)
			(xy 373.007895 -45.409862) (xy 373.003824 -45.35424) (xy 369.044272 -45.35424) (xy 369.012697 -45.38948)
			(xy 368.969829 -45.425155) (xy 368.922223 -45.454209) (xy 368.870894 -45.476021) (xy 368.816937 -45.490127)
			(xy 368.7615 -45.496227) (xy 368.705766 -45.49419) (xy 368.650923 -45.48406) (xy 368.598139 -45.466053)
			(xy 368.548539 -45.440552) (xy 368.503181 -45.408101) (xy 368.463032 -45.369392) (xy 368.428946 -45.325249)
			(xy 368.40165 -45.276614) (xy 368.381727 -45.224523) (xy 368.369601 -45.170086) (xy 368.36553 -45.114464)
			(xy 342.38433 -45.114464) (xy 342.403607 -46.082204) (xy 366.352582 -46.082204) (xy 366.353081 -46.054953)
			(xy 366.360837 -46.001007) (xy 366.376191 -45.948713) (xy 366.398831 -45.899136) (xy 366.428296 -45.853286)
			(xy 366.463986 -45.812096) (xy 366.505175 -45.776405) (xy 366.551024 -45.746938) (xy 366.6006 -45.724296)
			(xy 366.652893 -45.70894) (xy 366.706839 -45.701182) (xy 366.73409 -45.700696) (xy 366.760992 -45.701166)
			(xy 366.814262 -45.708736) (xy 366.86594 -45.723714) (xy 366.915002 -45.745803) (xy 366.960474 -45.774564)
			(xy 367.001456 -45.809428) (xy 367.037134 -45.849703) (xy 367.052352 -45.871892) (xy 367.059464 -45.882814)
			(xy 367.082324 -45.894752) (xy 367.194592 -45.89272) (xy 367.216944 -45.879766) (xy 367.223802 -45.86859)
			(xy 367.238736 -45.844997) (xy 367.274413 -45.802045) (xy 367.315969 -45.764751) (xy 367.362517 -45.733913)
			(xy 367.413062 -45.710188) (xy 367.466526 -45.694084) (xy 367.521766 -45.685944) (xy 367.549684 -45.685456)
			(xy 367.576677 -45.685926) (xy 367.630125 -45.69353) (xy 367.681968 -45.708588) (xy 367.731173 -45.7308)
			(xy 367.776757 -45.759723) (xy 367.797588 -45.776896) (xy 367.805716 -45.784008) (xy 367.82629 -45.790104)
			(xy 367.911634 -45.779182) (xy 367.922185 -45.777434) (xy 367.940465 -45.766361) (xy 367.94694 -45.757846)
			(xy 367.962275 -45.736602) (xy 367.997865 -45.698149) (xy 368.038385 -45.664932) (xy 368.083072 -45.637575)
			(xy 368.131083 -45.616593) (xy 368.181514 -45.602383) (xy 368.233416 -45.595211) (xy 368.259614 -45.594778)
			(xy 368.286864 -45.595293) (xy 368.340808 -45.603051) (xy 368.393099 -45.618407) (xy 368.442672 -45.641048)
			(xy 368.488519 -45.670513) (xy 368.529706 -45.706204) (xy 368.565395 -45.747392) (xy 368.594859 -45.79324)
			(xy 368.617498 -45.842814) (xy 368.632852 -45.895106) (xy 368.640608 -45.94905) (xy 368.640608 -46.00355)
			(xy 368.632852 -46.057494) (xy 368.617498 -46.109786) (xy 368.594859 -46.15936) (xy 368.565395 -46.205208)
			(xy 368.529706 -46.246396) (xy 368.488519 -46.282087) (xy 368.442672 -46.311552) (xy 368.393099 -46.334193)
			(xy 368.340808 -46.349549) (xy 368.286864 -46.357307) (xy 368.259614 -46.357794) (xy 368.232622 -46.357313)
			(xy 368.179175 -46.34971) (xy 368.127332 -46.334654) (xy 368.078127 -46.312445) (xy 368.032542 -46.283525)
			(xy 368.01171 -46.266354) (xy 368.003582 -46.259242) (xy 367.983008 -46.253146) (xy 367.897664 -46.264068)
			(xy 367.887117 -46.265832) (xy 367.868837 -46.276895) (xy 367.862358 -46.285404) (xy 367.844747 -46.309706)
			(xy 367.80315 -46.352965) (xy 367.779554 -46.37151) (xy 367.77168 -46.377352) (xy 367.761266 -46.394878)
			(xy 367.748058 -46.485302) (xy 367.752884 -46.504606) (xy 367.758726 -46.51248) (xy 367.758726 -46.512734)
			(xy 367.776223 -46.537482) (xy 367.804028 -46.591333) (xy 367.822967 -46.648904) (xy 367.83017 -46.693836)
			(xy 372.976394 -46.693836) (xy 372.97688 -46.666585) (xy 372.984636 -46.612637) (xy 372.999991 -46.560342)
			(xy 373.022633 -46.510765) (xy 373.052099 -46.464915) (xy 373.08779 -46.423724) (xy 373.128981 -46.388033)
			(xy 373.174831 -46.358567) (xy 373.224408 -46.335925) (xy 373.276703 -46.32057) (xy 373.330651 -46.312814)
			(xy 373.385153 -46.312814) (xy 373.439101 -46.32057) (xy 373.491396 -46.335925) (xy 373.540973 -46.358567)
			(xy 373.586823 -46.388033) (xy 373.628014 -46.423724) (xy 373.663705 -46.464915) (xy 373.693171 -46.510765)
			(xy 373.715813 -46.560342) (xy 373.731168 -46.612637) (xy 373.738924 -46.666585) (xy 373.73941 -46.693836)
			(xy 373.738936 -46.720263) (xy 373.731627 -46.772611) (xy 373.717154 -46.823446) (xy 373.695795 -46.871793)
			(xy 373.68226 -46.894496) (xy 373.682006 -46.89475) (xy 373.676669 -46.904768) (xy 373.674414 -46.927318)
			(xy 373.677688 -46.938184) (xy 373.70385 -47.01286) (xy 373.708235 -47.023375) (xy 373.724323 -47.039463)
			(xy 373.734838 -47.043848) (xy 373.735092 -47.043848) (xy 373.759611 -47.052892) (xy 373.806062 -47.07684)
			(xy 373.848813 -47.1069) (xy 373.887063 -47.142511) (xy 373.920098 -47.183007) (xy 373.9473 -47.227631)
			(xy 373.968161 -47.275548) (xy 373.98229 -47.325863) (xy 373.989423 -47.377635) (xy 373.989854 -47.403766)
			(xy 373.989368 -47.431017) (xy 373.987845 -47.441612) (xy 375.261884 -47.441612) (xy 375.265955 -47.38599)
			(xy 375.278081 -47.331553) (xy 375.298004 -47.279462) (xy 375.3253 -47.230827) (xy 375.359386 -47.186684)
			(xy 375.399535 -47.147975) (xy 375.444893 -47.115524) (xy 375.494493 -47.090023) (xy 375.547277 -47.072016)
			(xy 375.60212 -47.061886) (xy 375.657854 -47.059849) (xy 375.713291 -47.065949) (xy 375.767248 -47.080055)
			(xy 375.818577 -47.101867) (xy 375.866183 -47.130921) (xy 375.909051 -47.166596) (xy 375.946268 -47.208133)
			(xy 375.977041 -47.254646) (xy 376.000713 -47.305143) (xy 376.016781 -47.35855) (xy 376.024901 -47.413726)
			(xy 376.02541 -47.441612) (xy 376.024901 -47.469498) (xy 376.016781 -47.524674) (xy 376.000713 -47.578081)
			(xy 375.977041 -47.628578) (xy 375.946268 -47.675091) (xy 375.909051 -47.716628) (xy 375.866183 -47.752303)
			(xy 375.818577 -47.781357) (xy 375.767248 -47.803169) (xy 375.713291 -47.817275) (xy 375.657854 -47.823375)
			(xy 375.60212 -47.821338) (xy 375.547277 -47.811208) (xy 375.494493 -47.793201) (xy 375.444893 -47.7677)
			(xy 375.399535 -47.735249) (xy 375.359386 -47.69654) (xy 375.3253 -47.652397) (xy 375.298004 -47.603762)
			(xy 375.278081 -47.551671) (xy 375.265955 -47.497234) (xy 375.261884 -47.441612) (xy 373.987845 -47.441612)
			(xy 373.981612 -47.484965) (xy 373.966257 -47.53726) (xy 373.943615 -47.586837) (xy 373.914149 -47.632687)
			(xy 373.878458 -47.673878) (xy 373.837267 -47.709569) (xy 373.791417 -47.739035) (xy 373.74184 -47.761677)
			(xy 373.689545 -47.777032) (xy 373.635597 -47.784788) (xy 373.581095 -47.784788) (xy 373.527147 -47.777032)
			(xy 373.474852 -47.761677) (xy 373.425275 -47.739035) (xy 373.379425 -47.709569) (xy 373.338234 -47.673878)
			(xy 373.302543 -47.632687) (xy 373.273077 -47.586837) (xy 373.250435 -47.53726) (xy 373.23508 -47.484965)
			(xy 373.227324 -47.431017) (xy 373.226838 -47.403766) (xy 373.227306 -47.377338) (xy 373.234616 -47.324991)
			(xy 373.249091 -47.274156) (xy 373.270452 -47.225809) (xy 373.283988 -47.203106) (xy 373.284242 -47.202852)
			(xy 373.289577 -47.192833) (xy 373.291836 -47.170284) (xy 373.28856 -47.159418) (xy 373.262398 -47.084742)
			(xy 373.258036 -47.074215) (xy 373.241932 -47.058131) (xy 373.23141 -47.053754) (xy 373.231156 -47.053754)
			(xy 373.206648 -47.044682) (xy 373.160196 -47.020739) (xy 373.117444 -46.990684) (xy 373.079192 -46.955077)
			(xy 373.046155 -46.914585) (xy 373.018951 -46.869964) (xy 372.998089 -46.822049) (xy 372.983959 -46.771736)
			(xy 372.976825 -46.719966) (xy 372.976394 -46.693836) (xy 367.83017 -46.693836) (xy 367.83256 -46.708745)
			(xy 367.833148 -46.739048) (xy 367.832667 -46.766299) (xy 367.824905 -46.820244) (xy 367.809546 -46.872537)
			(xy 367.786902 -46.922112) (xy 367.757434 -46.96796) (xy 367.721743 -47.009148) (xy 367.680553 -47.044839)
			(xy 367.634705 -47.074306) (xy 367.585129 -47.096949) (xy 367.532837 -47.112307) (xy 367.478891 -47.120068)
			(xy 367.45164 -47.120556) (xy 367.425606 -47.120136) (xy 367.374022 -47.113041) (xy 367.32388 -47.099005)
			(xy 367.276109 -47.078289) (xy 367.231596 -47.051275) (xy 367.211102 -47.035212) (xy 367.203351 -47.02946)
			(xy 367.184936 -47.023726) (xy 367.175288 -47.024036) (xy 367.095532 -47.030386) (xy 367.077752 -47.039022)
			(xy 367.071402 -47.046388) (xy 367.053243 -47.066055) (xy 367.012331 -47.100575) (xy 366.966997 -47.129042)
			(xy 366.918131 -47.150895) (xy 366.866692 -47.165708) (xy 366.813687 -47.17319) (xy 366.786922 -47.173642)
			(xy 366.759673 -47.173101) (xy 366.705729 -47.165349) (xy 366.653437 -47.149998) (xy 366.603863 -47.127362)
			(xy 366.558014 -47.097901) (xy 366.516824 -47.062216) (xy 366.481132 -47.021031) (xy 366.451665 -46.975187)
			(xy 366.429021 -46.925615) (xy 366.413663 -46.873326) (xy 366.405903 -46.819383) (xy 366.405414 -46.792134)
			(xy 366.405935 -46.76336) (xy 366.414586 -46.706465) (xy 366.431683 -46.651515) (xy 366.456838 -46.599755)
			(xy 366.489479 -46.552359) (xy 366.508792 -46.531022) (xy 366.516158 -46.523148) (xy 366.52327 -46.503336)
			(xy 366.515904 -46.40707) (xy 366.505998 -46.388274) (xy 366.497616 -46.38167) (xy 366.47543 -46.363446)
			(xy 366.436221 -46.321511) (xy 366.403735 -46.274175) (xy 366.378707 -46.222507) (xy 366.361701 -46.167672)
			(xy 366.3531 -46.110909) (xy 366.352582 -46.082204) (xy 342.403607 -46.082204) (xy 342.447923 -48.30699)
			(xy 372.853964 -48.30699) (xy 372.858035 -48.251368) (xy 372.870161 -48.196931) (xy 372.890084 -48.14484)
			(xy 372.91738 -48.096205) (xy 372.951466 -48.052062) (xy 372.991615 -48.013353) (xy 373.036973 -47.980902)
			(xy 373.086573 -47.955401) (xy 373.139357 -47.937394) (xy 373.1942 -47.927264) (xy 373.249934 -47.925227)
			(xy 373.305371 -47.931327) (xy 373.359328 -47.945433) (xy 373.410657 -47.967245) (xy 373.458263 -47.996299)
			(xy 373.501131 -48.031974) (xy 373.538348 -48.073511) (xy 373.569121 -48.120024) (xy 373.592793 -48.170521)
			(xy 373.608861 -48.223928) (xy 373.616981 -48.279104) (xy 373.61749 -48.30699) (xy 373.616981 -48.334876)
			(xy 373.608861 -48.390052) (xy 373.592793 -48.443459) (xy 373.569121 -48.493956) (xy 373.538348 -48.540469)
			(xy 373.501131 -48.582006) (xy 373.458263 -48.617681) (xy 373.410657 -48.646735) (xy 373.359328 -48.668547)
			(xy 373.305371 -48.682653) (xy 373.249934 -48.688753) (xy 373.1942 -48.686716) (xy 373.139357 -48.676586)
			(xy 373.086573 -48.658579) (xy 373.036973 -48.633078) (xy 372.991615 -48.600627) (xy 372.951466 -48.561918)
			(xy 372.91738 -48.517775) (xy 372.890084 -48.46914) (xy 372.870161 -48.417049) (xy 372.858035 -48.362612)
			(xy 372.853964 -48.30699) (xy 342.447923 -48.30699) (xy 342.456808 -48.753014) (xy 369.468398 -48.753014)
			(xy 369.472469 -48.697392) (xy 369.484595 -48.642955) (xy 369.504518 -48.590864) (xy 369.531814 -48.542229)
			(xy 369.5659 -48.498086) (xy 369.606049 -48.459377) (xy 369.651407 -48.426926) (xy 369.701007 -48.401425)
			(xy 369.753791 -48.383418) (xy 369.808634 -48.373288) (xy 369.864368 -48.371251) (xy 369.919805 -48.377351)
			(xy 369.973762 -48.391457) (xy 370.025091 -48.413269) (xy 370.072697 -48.442323) (xy 370.115565 -48.477998)
			(xy 370.152782 -48.519535) (xy 370.183555 -48.566048) (xy 370.207227 -48.616545) (xy 370.223295 -48.669952)
			(xy 370.231415 -48.725128) (xy 370.231924 -48.753014) (xy 370.231415 -48.7809) (xy 370.223295 -48.836076)
			(xy 370.207227 -48.889483) (xy 370.205831 -48.89246) (xy 371.514114 -48.89246) (xy 371.518185 -48.836838)
			(xy 371.530311 -48.782401) (xy 371.550234 -48.73031) (xy 371.57753 -48.681675) (xy 371.611616 -48.637532)
			(xy 371.651765 -48.598823) (xy 371.697123 -48.566372) (xy 371.746723 -48.540871) (xy 371.799507 -48.522864)
			(xy 371.85435 -48.512734) (xy 371.910084 -48.510697) (xy 371.965521 -48.516797) (xy 372.019478 -48.530903)
			(xy 372.070807 -48.552715) (xy 372.118413 -48.581769) (xy 372.161281 -48.617444) (xy 372.198498 -48.658981)
			(xy 372.229271 -48.705494) (xy 372.252943 -48.755991) (xy 372.269011 -48.809398) (xy 372.277131 -48.864574)
			(xy 372.27764 -48.89246) (xy 372.277131 -48.920346) (xy 372.274693 -48.93691) (xy 375.233182 -48.93691)
			(xy 375.237253 -48.881288) (xy 375.249379 -48.826851) (xy 375.269302 -48.77476) (xy 375.296598 -48.726125)
			(xy 375.330684 -48.681982) (xy 375.370833 -48.643273) (xy 375.416191 -48.610822) (xy 375.465791 -48.585321)
			(xy 375.518575 -48.567314) (xy 375.573418 -48.557184) (xy 375.629152 -48.555147) (xy 375.684589 -48.561247)
			(xy 375.738546 -48.575353) (xy 375.789875 -48.597165) (xy 375.837481 -48.626219) (xy 375.880349 -48.661894)
			(xy 375.917566 -48.703431) (xy 375.948339 -48.749944) (xy 375.972011 -48.800441) (xy 375.988079 -48.853848)
			(xy 375.996199 -48.909024) (xy 375.996708 -48.93691) (xy 375.996199 -48.964796) (xy 375.988079 -49.019972)
			(xy 375.972011 -49.073379) (xy 375.948339 -49.123876) (xy 375.917566 -49.170389) (xy 375.880349 -49.211926)
			(xy 375.837481 -49.247601) (xy 375.789875 -49.276655) (xy 375.738546 -49.298467) (xy 375.684589 -49.312573)
			(xy 375.629152 -49.318673) (xy 375.573418 -49.316636) (xy 375.518575 -49.306506) (xy 375.465791 -49.288499)
			(xy 375.416191 -49.262998) (xy 375.370833 -49.230547) (xy 375.330684 -49.191838) (xy 375.296598 -49.147695)
			(xy 375.269302 -49.09906) (xy 375.249379 -49.046969) (xy 375.237253 -48.992532) (xy 375.233182 -48.93691)
			(xy 372.274693 -48.93691) (xy 372.269011 -48.975522) (xy 372.252943 -49.028929) (xy 372.229271 -49.079426)
			(xy 372.198498 -49.125939) (xy 372.161281 -49.167476) (xy 372.118413 -49.203151) (xy 372.070807 -49.232205)
			(xy 372.019478 -49.254017) (xy 371.965521 -49.268123) (xy 371.910084 -49.274223) (xy 371.85435 -49.272186)
			(xy 371.799507 -49.262056) (xy 371.746723 -49.244049) (xy 371.697123 -49.218548) (xy 371.651765 -49.186097)
			(xy 371.611616 -49.147388) (xy 371.57753 -49.103245) (xy 371.550234 -49.05461) (xy 371.530311 -49.002519)
			(xy 371.518185 -48.948082) (xy 371.514114 -48.89246) (xy 370.205831 -48.89246) (xy 370.183555 -48.93998)
			(xy 370.152782 -48.986493) (xy 370.115565 -49.02803) (xy 370.072697 -49.063705) (xy 370.025091 -49.092759)
			(xy 369.973762 -49.114571) (xy 369.919805 -49.128677) (xy 369.864368 -49.134777) (xy 369.808634 -49.13274)
			(xy 369.753791 -49.12261) (xy 369.701007 -49.104603) (xy 369.651407 -49.079102) (xy 369.606049 -49.046651)
			(xy 369.5659 -49.007942) (xy 369.531814 -48.963799) (xy 369.504518 -48.915164) (xy 369.484595 -48.863073)
			(xy 369.472469 -48.808636) (xy 369.468398 -48.753014) (xy 342.456808 -48.753014) (xy 342.473718 -49.601949)
			(xy 354.413082 -49.601949) (xy 354.413082 -49.547451) (xy 354.420837 -49.493507) (xy 354.43619 -49.441217)
			(xy 354.458828 -49.391643) (xy 354.48829 -49.345795) (xy 354.523976 -49.304606) (xy 354.565161 -49.268915)
			(xy 354.611006 -49.239448) (xy 354.660577 -49.216805) (xy 354.712866 -49.201446) (xy 354.766809 -49.193685)
			(xy 354.794058 -49.193196) (xy 354.821427 -49.193688) (xy 354.875605 -49.201499) (xy 354.928108 -49.216983)
			(xy 354.977855 -49.239819) (xy 355.023823 -49.269537) (xy 355.044756 -49.287176) (xy 355.04501 -49.28743)
			(xy 355.052087 -49.29303) (xy 355.069011 -49.299268) (xy 355.07803 -49.299622) (xy 355.145086 -49.299622)
			(xy 355.154102 -49.299253) (xy 355.171018 -49.293013) (xy 355.178106 -49.28743) (xy 355.178106 -49.287176)
			(xy 355.17836 -49.287176) (xy 355.199293 -49.269535) (xy 355.245261 -49.239811) (xy 355.295007 -49.216965)
			(xy 355.347509 -49.201469) (xy 355.401687 -49.19364) (xy 355.456429 -49.19364) (xy 355.510607 -49.201469)
			(xy 355.563109 -49.216965) (xy 355.612855 -49.239811) (xy 355.658823 -49.269535) (xy 355.679756 -49.287176)
			(xy 355.68001 -49.28743) (xy 355.687087 -49.29303) (xy 355.704011 -49.299268) (xy 355.71303 -49.299622)
			(xy 355.780086 -49.299622) (xy 355.789102 -49.299253) (xy 355.806018 -49.293013) (xy 355.813106 -49.28743)
			(xy 355.813106 -49.287176) (xy 355.81336 -49.287176) (xy 355.834293 -49.269535) (xy 355.880261 -49.239811)
			(xy 355.930007 -49.216965) (xy 355.982509 -49.201469) (xy 356.036687 -49.19364) (xy 356.091429 -49.19364)
			(xy 356.145607 -49.201469) (xy 356.198109 -49.216965) (xy 356.247855 -49.239811) (xy 356.293823 -49.269535)
			(xy 356.314756 -49.287176) (xy 356.31501 -49.28743) (xy 356.322087 -49.29303) (xy 356.339011 -49.299268)
			(xy 356.34803 -49.299622) (xy 356.415086 -49.299622) (xy 356.424102 -49.299253) (xy 356.441018 -49.293013)
			(xy 356.448106 -49.28743) (xy 356.448106 -49.287176) (xy 356.44836 -49.287176) (xy 356.469293 -49.269538)
			(xy 356.515266 -49.239827) (xy 356.565013 -49.216991) (xy 356.617514 -49.2015) (xy 356.671689 -49.193671)
			(xy 356.699058 -49.193196) (xy 356.726313 -49.193648) (xy 356.780269 -49.201401) (xy 356.832573 -49.216753)
			(xy 356.882158 -49.239394) (xy 356.928017 -49.268861) (xy 356.969215 -49.304555) (xy 357.004914 -49.345749)
			(xy 357.034386 -49.391605) (xy 357.057032 -49.441188) (xy 357.07239 -49.49349) (xy 357.080149 -49.547445)
			(xy 357.080149 -49.601955) (xy 357.07239 -49.65591) (xy 357.057032 -49.708212) (xy 357.034386 -49.757795)
			(xy 357.004914 -49.803651) (xy 356.969215 -49.844845) (xy 356.928017 -49.880539) (xy 356.882158 -49.910006)
			(xy 356.832573 -49.932647) (xy 356.780269 -49.947999) (xy 356.746092 -49.95291) (xy 375.233182 -49.95291)
			(xy 375.237253 -49.897288) (xy 375.249379 -49.842851) (xy 375.269302 -49.79076) (xy 375.296598 -49.742125)
			(xy 375.330684 -49.697982) (xy 375.370833 -49.659273) (xy 375.416191 -49.626822) (xy 375.465791 -49.601321)
			(xy 375.518575 -49.583314) (xy 375.573418 -49.573184) (xy 375.629152 -49.571147) (xy 375.684589 -49.577247)
			(xy 375.738546 -49.591353) (xy 375.789875 -49.613165) (xy 375.837481 -49.642219) (xy 375.880349 -49.677894)
			(xy 375.917566 -49.719431) (xy 375.948339 -49.765944) (xy 375.972011 -49.816441) (xy 375.988079 -49.869848)
			(xy 375.996199 -49.925024) (xy 375.996708 -49.95291) (xy 375.996199 -49.980796) (xy 375.988079 -50.035972)
			(xy 375.972011 -50.089379) (xy 375.948339 -50.139876) (xy 375.917566 -50.186389) (xy 375.880349 -50.227926)
			(xy 375.837481 -50.263601) (xy 375.789875 -50.292655) (xy 375.738546 -50.314467) (xy 375.684589 -50.328573)
			(xy 375.629152 -50.334673) (xy 375.573418 -50.332636) (xy 375.518575 -50.322506) (xy 375.465791 -50.304499)
			(xy 375.416191 -50.278998) (xy 375.370833 -50.246547) (xy 375.330684 -50.207838) (xy 375.296598 -50.163695)
			(xy 375.269302 -50.11506) (xy 375.249379 -50.062969) (xy 375.237253 -50.008532) (xy 375.233182 -49.95291)
			(xy 356.746092 -49.95291) (xy 356.726313 -49.955752) (xy 356.699058 -49.956212) (xy 356.671689 -49.955709)
			(xy 356.617512 -49.9479) (xy 356.565009 -49.932419) (xy 356.515262 -49.909586) (xy 356.469293 -49.879869)
			(xy 356.44836 -49.862232) (xy 356.448106 -49.861978) (xy 356.441024 -49.856385) (xy 356.424104 -49.850143)
			(xy 356.415086 -49.849786) (xy 356.34803 -49.849786) (xy 356.339015 -49.85016) (xy 356.322098 -49.856396)
			(xy 356.31501 -49.861978) (xy 356.314756 -49.862232) (xy 356.293823 -49.879873) (xy 356.247855 -49.909597)
			(xy 356.198109 -49.932443) (xy 356.145607 -49.947939) (xy 356.091429 -49.955768) (xy 356.036687 -49.955768)
			(xy 355.982509 -49.947939) (xy 355.930007 -49.932443) (xy 355.880261 -49.909597) (xy 355.834293 -49.879873)
			(xy 355.81336 -49.862232) (xy 355.813106 -49.861978) (xy 355.806024 -49.856385) (xy 355.789104 -49.850143)
			(xy 355.780086 -49.849786) (xy 355.71303 -49.849786) (xy 355.704015 -49.85016) (xy 355.687098 -49.856396)
			(xy 355.68001 -49.861978) (xy 355.68001 -49.862232) (xy 355.679756 -49.862232) (xy 355.658823 -49.879873)
			(xy 355.612855 -49.909597) (xy 355.563109 -49.932443) (xy 355.510607 -49.947939) (xy 355.456429 -49.955768)
			(xy 355.401687 -49.955768) (xy 355.347509 -49.947939) (xy 355.295007 -49.932443) (xy 355.245261 -49.909597)
			(xy 355.199293 -49.879873) (xy 355.17836 -49.862232) (xy 355.178106 -49.861978) (xy 355.171024 -49.856385)
			(xy 355.154104 -49.850143) (xy 355.145086 -49.849786) (xy 355.07803 -49.849786) (xy 355.069015 -49.85016)
			(xy 355.052098 -49.856396) (xy 355.04501 -49.861978) (xy 355.04501 -49.862232) (xy 355.044756 -49.862232)
			(xy 355.023818 -49.879863) (xy 354.977846 -49.909575) (xy 354.9281 -49.932412) (xy 354.875601 -49.947905)
			(xy 354.821427 -49.955736) (xy 354.794058 -49.956212) (xy 354.766809 -49.955715) (xy 354.712866 -49.947954)
			(xy 354.660577 -49.932595) (xy 354.611006 -49.909952) (xy 354.565161 -49.880485) (xy 354.523976 -49.844794)
			(xy 354.48829 -49.803605) (xy 354.458828 -49.757757) (xy 354.43619 -49.708183) (xy 354.420837 -49.655893)
			(xy 354.413082 -49.601949) (xy 342.473718 -49.601949) (xy 342.506427 -51.243992) (xy 355.433122 -51.243992)
			(xy 355.433578 -51.216621) (xy 355.441397 -51.162442) (xy 355.456889 -51.109938) (xy 355.479733 -51.060191)
			(xy 355.50946 -51.014225) (xy 355.527102 -50.993294) (xy 355.527356 -50.99304) (xy 355.532939 -50.985951)
			(xy 355.539186 -50.969036) (xy 355.539548 -50.96002) (xy 355.539548 -50.892964) (xy 355.53922 -50.883944)
			(xy 355.532954 -50.867027) (xy 355.527356 -50.859944) (xy 355.527102 -50.859944) (xy 355.527102 -50.85969)
			(xy 355.509445 -50.838772) (xy 355.479736 -50.792796) (xy 355.456903 -50.743044) (xy 355.441416 -50.690541)
			(xy 355.433593 -50.636362) (xy 355.433122 -50.608992) (xy 355.433548 -50.581738) (xy 355.441307 -50.527784)
			(xy 355.456665 -50.475483) (xy 355.479311 -50.425901) (xy 355.508783 -50.380047) (xy 355.54448 -50.338853)
			(xy 355.585677 -50.30316) (xy 355.631535 -50.273693) (xy 355.681119 -50.251052) (xy 355.733421 -50.235699)
			(xy 355.787376 -50.227945) (xy 355.81463 -50.227484) (xy 355.843547 -50.228021) (xy 355.900718 -50.236742)
			(xy 355.955918 -50.253994) (xy 356.007881 -50.279382) (xy 356.055415 -50.312324) (xy 356.097431 -50.352065)
			(xy 356.11562 -50.37455) (xy 356.123219 -50.383365) (xy 356.144126 -50.393542) (xy 356.155752 -50.394108)
			(xy 356.235508 -50.394108) (xy 356.247138 -50.393556) (xy 356.268048 -50.383376) (xy 356.27564 -50.37455)
			(xy 356.293796 -50.352037) (xy 356.335824 -50.312306) (xy 356.383367 -50.279372) (xy 356.435335 -50.253989)
			(xy 356.490538 -50.236739) (xy 356.547712 -50.228016) (xy 356.57663 -50.227484) (xy 356.603882 -50.22795)
			(xy 356.65783 -50.23571) (xy 356.710124 -50.251069) (xy 356.759701 -50.273713) (xy 356.805551 -50.303182)
			(xy 356.846741 -50.338875) (xy 356.882432 -50.380067) (xy 356.911898 -50.425918) (xy 356.934539 -50.475496)
			(xy 356.949894 -50.527792) (xy 356.957652 -50.58174) (xy 356.958138 -50.608992) (xy 356.957685 -50.635307)
			(xy 356.95045 -50.687437) (xy 356.936129 -50.73808) (xy 356.914994 -50.78628) (xy 356.887445 -50.831123)
			(xy 356.854002 -50.871761) (xy 356.834948 -50.889916) (xy 356.827545 -50.897436) (xy 356.81902 -50.916717)
			(xy 356.818438 -50.927254) (xy 356.818438 -51.00193) (xy 356.81898 -51.012478) (xy 356.822063 -51.019456)
			(xy 373.049544 -51.019456) (xy 373.053615 -50.963834) (xy 373.065741 -50.909397) (xy 373.085664 -50.857306)
			(xy 373.11296 -50.808671) (xy 373.147046 -50.764528) (xy 373.187195 -50.725819) (xy 373.232553 -50.693368)
			(xy 373.282153 -50.667867) (xy 373.334937 -50.64986) (xy 373.38978 -50.63973) (xy 373.445514 -50.637693)
			(xy 373.500951 -50.643793) (xy 373.554908 -50.657899) (xy 373.606237 -50.679711) (xy 373.653843 -50.708765)
			(xy 373.696711 -50.74444) (xy 373.733928 -50.785977) (xy 373.764701 -50.83249) (xy 373.788373 -50.882987)
			(xy 373.804441 -50.936394) (xy 373.812561 -50.99157) (xy 373.81307 -51.019456) (xy 373.812561 -51.047342)
			(xy 373.804441 -51.102518) (xy 373.788373 -51.155925) (xy 373.764701 -51.206422) (xy 373.733928 -51.252935)
			(xy 373.696711 -51.294472) (xy 373.653843 -51.330147) (xy 373.606237 -51.359201) (xy 373.554908 -51.381013)
			(xy 373.500951 -51.395119) (xy 373.445514 -51.401219) (xy 373.38978 -51.399182) (xy 373.334937 -51.389052)
			(xy 373.282153 -51.371045) (xy 373.232553 -51.345544) (xy 373.187195 -51.313093) (xy 373.147046 -51.274384)
			(xy 373.11296 -51.230241) (xy 373.085664 -51.181606) (xy 373.065741 -51.129515) (xy 373.053615 -51.075078)
			(xy 373.049544 -51.019456) (xy 356.822063 -51.019456) (xy 356.827505 -51.031775) (xy 356.834948 -51.039268)
			(xy 356.854039 -51.057388) (xy 356.887491 -51.098026) (xy 356.915044 -51.142875) (xy 356.936176 -51.191082)
			(xy 356.950486 -51.241735) (xy 356.957703 -51.293874) (xy 356.958138 -51.320192) (xy 356.957615 -51.347442)
			(xy 356.94986 -51.401387) (xy 356.934508 -51.453679) (xy 356.91187 -51.503254) (xy 356.882407 -51.549103)
			(xy 356.846719 -51.590293) (xy 356.805533 -51.625984) (xy 356.759687 -51.655451) (xy 356.710114 -51.678094)
			(xy 356.657824 -51.693452) (xy 356.60388 -51.701212) (xy 356.57663 -51.7017) (xy 356.548966 -51.701164)
			(xy 356.494218 -51.693169) (xy 356.441197 -51.677357) (xy 356.391013 -51.654057) (xy 356.344717 -51.62376)
			(xy 356.303278 -51.587098) (xy 356.267564 -51.544839) (xy 356.252526 -51.521614) (xy 356.245887 -51.51194)
			(xy 356.226027 -51.499496) (xy 356.214426 -51.497738) (xy 356.134416 -51.489864) (xy 356.122778 -51.489246)
			(xy 356.100941 -51.497316) (xy 356.092506 -51.505358) (xy 356.092252 -51.505612) (xy 356.074179 -51.524201)
			(xy 356.033845 -51.556778) (xy 355.989469 -51.58359) (xy 355.941869 -51.604141) (xy 355.891923 -51.618053)
			(xy 355.840554 -51.625069) (xy 355.81463 -51.6255) (xy 355.787378 -51.625017) (xy 355.733427 -51.617264)
			(xy 355.681129 -51.601911) (xy 355.631548 -51.579271) (xy 355.585695 -51.549806) (xy 355.544501 -51.514114)
			(xy 355.508807 -51.472923) (xy 355.479339 -51.427071) (xy 355.456697 -51.377492) (xy 355.441341 -51.325195)
			(xy 355.433585 -51.271244) (xy 355.433122 -51.243992) (xy 342.506427 -51.243992) (xy 342.522192 -52.035456)
			(xy 375.24131 -52.035456) (xy 375.245381 -51.979834) (xy 375.257507 -51.925397) (xy 375.27743 -51.873306)
			(xy 375.304726 -51.824671) (xy 375.338812 -51.780528) (xy 375.378961 -51.741819) (xy 375.424319 -51.709368)
			(xy 375.473919 -51.683867) (xy 375.526703 -51.66586) (xy 375.581546 -51.65573) (xy 375.63728 -51.653693)
			(xy 375.692717 -51.659793) (xy 375.746674 -51.673899) (xy 375.798003 -51.695711) (xy 375.845609 -51.724765)
			(xy 375.888477 -51.76044) (xy 375.925694 -51.801977) (xy 375.956467 -51.84849) (xy 375.980139 -51.898987)
			(xy 375.996207 -51.952394) (xy 376.004327 -52.00757) (xy 376.004836 -52.035456) (xy 376.004327 -52.063342)
			(xy 375.996207 -52.118518) (xy 375.980139 -52.171925) (xy 375.956467 -52.222422) (xy 375.925694 -52.268935)
			(xy 375.888477 -52.310472) (xy 375.845609 -52.346147) (xy 375.798003 -52.375201) (xy 375.746674 -52.397013)
			(xy 375.692717 -52.411119) (xy 375.63728 -52.417219) (xy 375.581546 -52.415182) (xy 375.526703 -52.405052)
			(xy 375.473919 -52.387045) (xy 375.424319 -52.361544) (xy 375.378961 -52.329093) (xy 375.338812 -52.290384)
			(xy 375.304726 -52.246241) (xy 375.27743 -52.197606) (xy 375.257507 -52.145515) (xy 375.245381 -52.091078)
			(xy 375.24131 -52.035456) (xy 342.522192 -52.035456) (xy 342.53256 -52.555948) (xy 354.884002 -52.555948)
			(xy 354.884002 -52.501452) (xy 354.891757 -52.44751) (xy 354.90711 -52.39522) (xy 354.929748 -52.345648)
			(xy 354.95921 -52.299802) (xy 354.994897 -52.258615) (xy 355.036081 -52.222926) (xy 355.081925 -52.193461)
			(xy 355.131496 -52.170819) (xy 355.183784 -52.155463) (xy 355.237726 -52.147704) (xy 355.264974 -52.147216)
			(xy 355.292344 -52.147693) (xy 355.346523 -52.155508) (xy 355.399026 -52.170994) (xy 355.448773 -52.193833)
			(xy 355.49474 -52.223556) (xy 355.515672 -52.241196) (xy 355.515926 -52.24145) (xy 355.523025 -52.247018)
			(xy 355.539932 -52.253275) (xy 355.548946 -52.253642) (xy 355.616002 -52.253642) (xy 355.62502 -52.253298)
			(xy 355.641938 -52.247043) (xy 355.649022 -52.24145) (xy 355.649022 -52.241196) (xy 355.649276 -52.241196)
			(xy 355.670206 -52.223554) (xy 355.716179 -52.193843) (xy 355.765927 -52.171007) (xy 355.818429 -52.155517)
			(xy 355.872605 -52.14769) (xy 355.899974 -52.147216) (xy 355.92723 -52.147629) (xy 355.981187 -52.155384)
			(xy 356.033491 -52.170738) (xy 356.083078 -52.193381) (xy 356.128937 -52.22285) (xy 356.170136 -52.258546)
			(xy 356.205834 -52.299742) (xy 356.235307 -52.345599) (xy 356.257953 -52.395184) (xy 356.273311 -52.447488)
			(xy 356.281069 -52.501444) (xy 356.281069 -52.555956) (xy 356.273311 -52.609912) (xy 356.257953 -52.662216)
			(xy 356.235307 -52.711801) (xy 356.205834 -52.757658) (xy 356.170136 -52.798854) (xy 356.128937 -52.83455)
			(xy 356.083078 -52.864019) (xy 356.033491 -52.886662) (xy 355.981187 -52.902016) (xy 355.92723 -52.909771)
			(xy 355.899974 -52.910232) (xy 355.872602 -52.909798) (xy 355.818421 -52.901975) (xy 355.765917 -52.886479)
			(xy 355.716171 -52.86363) (xy 355.670206 -52.833897) (xy 355.649276 -52.816252) (xy 355.649022 -52.815998)
			(xy 355.641933 -52.810414) (xy 355.625018 -52.804166) (xy 355.616002 -52.803806) (xy 355.548946 -52.803806)
			(xy 355.539931 -52.804184) (xy 355.523014 -52.810417) (xy 355.515926 -52.815998) (xy 355.515926 -52.816252)
			(xy 355.515672 -52.816252) (xy 355.494717 -52.833863) (xy 355.448752 -52.863581) (xy 355.39901 -52.886423)
			(xy 355.346514 -52.90192) (xy 355.292342 -52.909755) (xy 355.264974 -52.910232) (xy 355.237726 -52.909696)
			(xy 355.183784 -52.901937) (xy 355.131496 -52.886581) (xy 355.081925 -52.863939) (xy 355.036081 -52.834474)
			(xy 354.994897 -52.798785) (xy 354.95921 -52.757598) (xy 354.929748 -52.711752) (xy 354.90711 -52.66218)
			(xy 354.891757 -52.60989) (xy 354.884002 -52.555948) (xy 342.53256 -52.555948) (xy 342.551296 -53.496555)
			(xy 354.433541 -53.496555) (xy 354.433541 -53.442045) (xy 354.441299 -53.388089) (xy 354.456657 -53.335787)
			(xy 354.479303 -53.286202) (xy 354.508775 -53.240346) (xy 354.544474 -53.199151) (xy 354.585672 -53.163456)
			(xy 354.63153 -53.133988) (xy 354.681117 -53.111346) (xy 354.73342 -53.095992) (xy 354.787377 -53.088239)
			(xy 354.814632 -53.087778) (xy 354.842004 -53.088206) (xy 354.896185 -53.09603) (xy 354.94869 -53.111527)
			(xy 354.998436 -53.134378) (xy 355.0444 -53.164112) (xy 355.06533 -53.181758) (xy 355.065584 -53.182012)
			(xy 355.07267 -53.187599) (xy 355.089587 -53.193845) (xy 355.098604 -53.194204) (xy 355.16566 -53.194204)
			(xy 355.174675 -53.193827) (xy 355.191592 -53.187593) (xy 355.19868 -53.182012) (xy 355.19868 -53.181758)
			(xy 355.198934 -53.181758) (xy 355.219874 -53.164129) (xy 355.265846 -53.134417) (xy 355.315591 -53.11158)
			(xy 355.36809 -53.096086) (xy 355.422264 -53.088254) (xy 355.449632 -53.087778) (xy 355.476881 -53.088294)
			(xy 355.530823 -53.096054) (xy 355.583112 -53.111412) (xy 355.632683 -53.134054) (xy 355.678528 -53.16352)
			(xy 355.719713 -53.19921) (xy 355.755399 -53.240398) (xy 355.784862 -53.286245) (xy 355.8075 -53.335818)
			(xy 355.822852 -53.388108) (xy 355.830608 -53.442051) (xy 355.830608 -53.496549) (xy 355.822852 -53.550492)
			(xy 355.8075 -53.602782) (xy 355.784862 -53.652355) (xy 355.755399 -53.698202) (xy 355.719713 -53.73939)
			(xy 355.678528 -53.77508) (xy 355.632683 -53.804546) (xy 355.583112 -53.827188) (xy 355.530823 -53.842546)
			(xy 355.476881 -53.850306) (xy 355.449632 -53.850794) (xy 355.422262 -53.850311) (xy 355.368084 -53.842497)
			(xy 355.315581 -53.827012) (xy 355.265834 -53.804174) (xy 355.219866 -53.774453) (xy 355.198934 -53.756814)
			(xy 355.19868 -53.75656) (xy 355.191607 -53.750954) (xy 355.17468 -53.74472) (xy 355.16566 -53.744368)
			(xy 355.098604 -53.744368) (xy 355.089588 -53.744734) (xy 355.072672 -53.750976) (xy 355.065584 -53.75656)
			(xy 355.065584 -53.756814) (xy 355.06533 -53.756814) (xy 355.044399 -53.774455) (xy 354.998426 -53.804166)
			(xy 354.948678 -53.827001) (xy 354.896177 -53.842492) (xy 354.842001 -53.85032) (xy 354.814632 -53.850794)
			(xy 354.787377 -53.850361) (xy 354.73342 -53.842608) (xy 354.681117 -53.827254) (xy 354.63153 -53.804612)
			(xy 354.585672 -53.775144) (xy 354.544474 -53.739449) (xy 354.508775 -53.698254) (xy 354.479303 -53.652398)
			(xy 354.456657 -53.602813) (xy 354.441299 -53.550511) (xy 354.433541 -53.496555) (xy 342.551296 -53.496555)
			(xy 342.581025 -54.989055) (xy 352.201145 -54.989055) (xy 352.201145 -54.934545) (xy 352.208903 -54.880591)
			(xy 352.224261 -54.828289) (xy 352.246906 -54.778706) (xy 352.276377 -54.73285) (xy 352.312074 -54.691656)
			(xy 352.353271 -54.655961) (xy 352.399129 -54.626493) (xy 352.448714 -54.603851) (xy 352.501016 -54.588497)
			(xy 352.554971 -54.580743) (xy 352.582226 -54.580282) (xy 352.610318 -54.580756) (xy 352.665896 -54.588987)
			(xy 352.719666 -54.605282) (xy 352.770463 -54.629288) (xy 352.81719 -54.660486) (xy 352.858835 -54.698201)
			(xy 352.894496 -54.741616) (xy 352.909378 -54.765448) (xy 352.914712 -54.774338) (xy 352.93173 -54.78653)
			(xy 353.024948 -54.80685) (xy 353.045522 -54.802532) (xy 353.054158 -54.79669) (xy 353.078231 -54.780705)
			(xy 353.130159 -54.755359) (xy 353.185314 -54.738129) (xy 353.242436 -54.729409) (xy 353.271328 -54.728872)
			(xy 353.298579 -54.729352) (xy 353.3129 -54.731412) (xy 361.820714 -54.731412) (xy 361.821184 -54.704042)
			(xy 361.829 -54.649863) (xy 361.844488 -54.59736) (xy 361.867329 -54.547613) (xy 361.897053 -54.501646)
			(xy 361.914694 -54.480714) (xy 361.914948 -54.48046) (xy 361.920521 -54.473365) (xy 361.926775 -54.456454)
			(xy 361.92714 -54.44744) (xy 361.92714 -54.380384) (xy 361.926803 -54.371365) (xy 361.920543 -54.354447)
			(xy 361.914948 -54.347364) (xy 361.914694 -54.347364) (xy 361.914694 -54.34711) (xy 361.897066 -54.326167)
			(xy 361.867344 -54.2802) (xy 361.8445 -54.230455) (xy 361.829004 -54.177955) (xy 361.821175 -54.123779)
			(xy 361.821174 -54.069039) (xy 361.829 -54.014862) (xy 361.844493 -53.962361) (xy 361.867335 -53.912616)
			(xy 361.897056 -53.866647) (xy 361.914694 -53.845714) (xy 361.914948 -53.84546) (xy 361.920521 -53.838365)
			(xy 361.926775 -53.821454) (xy 361.92714 -53.81244) (xy 361.92714 -53.745384) (xy 361.926803 -53.736365)
			(xy 361.920543 -53.719447) (xy 361.914948 -53.712364) (xy 361.914694 -53.712364) (xy 361.914694 -53.71211)
			(xy 361.897066 -53.691167) (xy 361.867344 -53.6452) (xy 361.8445 -53.595455) (xy 361.829004 -53.542955)
			(xy 361.821175 -53.488779) (xy 361.821174 -53.434039) (xy 361.829 -53.379862) (xy 361.844493 -53.327361)
			(xy 361.867335 -53.277616) (xy 361.897056 -53.231647) (xy 361.914694 -53.210714) (xy 361.914948 -53.21046)
			(xy 361.920521 -53.203365) (xy 361.926775 -53.186454) (xy 361.92714 -53.17744) (xy 361.92714 -53.110384)
			(xy 361.926803 -53.101365) (xy 361.920543 -53.084447) (xy 361.914948 -53.077364) (xy 361.914694 -53.077364)
			(xy 361.914694 -53.07711) (xy 361.897045 -53.056186) (xy 361.867335 -53.010211) (xy 361.844501 -52.960461)
			(xy 361.829012 -52.907959) (xy 361.821187 -52.853782) (xy 361.820714 -52.826412) (xy 361.8212 -52.799161)
			(xy 361.828956 -52.745213) (xy 361.844311 -52.692918) (xy 361.866953 -52.643341) (xy 361.896419 -52.597491)
			(xy 361.93211 -52.5563) (xy 361.973301 -52.520609) (xy 362.019151 -52.491143) (xy 362.068728 -52.468501)
			(xy 362.121023 -52.453146) (xy 362.174971 -52.44539) (xy 362.229473 -52.44539) (xy 362.283421 -52.453146)
			(xy 362.335716 -52.468501) (xy 362.385293 -52.491143) (xy 362.431143 -52.520609) (xy 362.472334 -52.5563)
			(xy 362.508025 -52.597491) (xy 362.537491 -52.643341) (xy 362.560133 -52.692918) (xy 362.575488 -52.745213)
			(xy 362.583244 -52.799161) (xy 362.58373 -52.826412) (xy 362.583288 -52.853783) (xy 362.575467 -52.907964)
			(xy 362.559973 -52.960468) (xy 362.537126 -53.010215) (xy 362.507395 -53.05618) (xy 362.48975 -53.07711)
			(xy 362.489496 -53.077364) (xy 362.483918 -53.084456) (xy 362.477666 -53.101369) (xy 362.477304 -53.110384)
			(xy 362.477304 -53.17744) (xy 362.477641 -53.186459) (xy 362.483903 -53.203376) (xy 362.489496 -53.21046)
			(xy 362.48975 -53.21046) (xy 362.48975 -53.210714) (xy 362.507403 -53.231637) (xy 362.537129 -53.277606)
			(xy 362.559976 -53.327353) (xy 362.575472 -53.379857) (xy 362.5833 -53.434038) (xy 362.583299 -53.48878)
			(xy 362.575468 -53.54296) (xy 362.559969 -53.595463) (xy 362.537121 -53.64521) (xy 362.507392 -53.691178)
			(xy 362.48975 -53.71211) (xy 362.489496 -53.712364) (xy 362.483918 -53.719456) (xy 362.477666 -53.736369)
			(xy 362.477304 -53.745384) (xy 362.477304 -53.81244) (xy 362.477641 -53.821459) (xy 362.483903 -53.838376)
			(xy 362.489496 -53.84546) (xy 362.48975 -53.84546) (xy 362.48975 -53.845714) (xy 362.507403 -53.866637)
			(xy 362.537129 -53.912606) (xy 362.559976 -53.962353) (xy 362.575472 -54.014857) (xy 362.5833 -54.069038)
			(xy 362.583299 -54.12378) (xy 362.575468 -54.17796) (xy 362.559969 -54.230463) (xy 362.537121 -54.28021)
			(xy 362.507392 -54.326178) (xy 362.48975 -54.34711) (xy 362.489496 -54.347364) (xy 362.483918 -54.354456)
			(xy 362.477666 -54.371369) (xy 362.477304 -54.380384) (xy 362.477304 -54.44744) (xy 362.477641 -54.456459)
			(xy 362.483903 -54.473376) (xy 362.489496 -54.48046) (xy 362.48975 -54.48046) (xy 362.48975 -54.480714)
			(xy 362.507354 -54.501674) (xy 362.537073 -54.547638) (xy 362.559917 -54.597379) (xy 362.575416 -54.649873)
			(xy 362.583252 -54.704045) (xy 362.58373 -54.731412) (xy 362.583244 -54.758663) (xy 362.57858 -54.791102)
			(xy 364.476538 -54.791102) (xy 364.476996 -54.763731) (xy 364.484814 -54.709552) (xy 364.500305 -54.657048)
			(xy 364.523149 -54.607301) (xy 364.552875 -54.561335) (xy 364.570518 -54.540404) (xy 364.570772 -54.54015)
			(xy 364.576352 -54.533059) (xy 364.582601 -54.516145) (xy 364.582964 -54.50713) (xy 364.582964 -54.440074)
			(xy 364.582627 -54.431055) (xy 364.576367 -54.414138) (xy 364.570772 -54.407054) (xy 364.570518 -54.407054)
			(xy 364.570518 -54.4068) (xy 364.55288 -54.385865) (xy 364.523155 -54.339898) (xy 364.500311 -54.290152)
			(xy 364.484814 -54.23765) (xy 364.476986 -54.183472) (xy 364.476986 -54.128731) (xy 364.484814 -54.074553)
			(xy 364.500309 -54.022051) (xy 364.523154 -53.972305) (xy 364.552878 -53.926337) (xy 364.570518 -53.905404)
			(xy 364.570772 -53.90515) (xy 364.576352 -53.898059) (xy 364.582601 -53.881145) (xy 364.582964 -53.87213)
			(xy 364.582964 -53.805074) (xy 364.582627 -53.796055) (xy 364.576367 -53.779138) (xy 364.570772 -53.772054)
			(xy 364.570518 -53.772054) (xy 364.570518 -53.7718) (xy 364.55288 -53.750865) (xy 364.523155 -53.704898)
			(xy 364.500311 -53.655152) (xy 364.484814 -53.60265) (xy 364.476986 -53.548472) (xy 364.476986 -53.493731)
			(xy 364.484814 -53.439553) (xy 364.500309 -53.387051) (xy 364.523154 -53.337305) (xy 364.552878 -53.291337)
			(xy 364.570518 -53.270404) (xy 364.570772 -53.27015) (xy 364.576352 -53.263059) (xy 364.582601 -53.246145)
			(xy 364.582964 -53.23713) (xy 364.582964 -53.170074) (xy 364.582627 -53.161055) (xy 364.576367 -53.144138)
			(xy 364.570772 -53.137054) (xy 364.570518 -53.137054) (xy 364.570518 -53.1368) (xy 364.552868 -53.115876)
			(xy 364.523157 -53.069902) (xy 364.500323 -53.020152) (xy 364.484835 -52.967649) (xy 364.47701 -52.913472)
			(xy 364.476538 -52.886102) (xy 364.477024 -52.858851) (xy 364.48478 -52.804903) (xy 364.500135 -52.752608)
			(xy 364.522777 -52.703031) (xy 364.552243 -52.657181) (xy 364.587934 -52.61599) (xy 364.629125 -52.580299)
			(xy 364.674975 -52.550833) (xy 364.724552 -52.528191) (xy 364.776847 -52.512836) (xy 364.830795 -52.50508)
			(xy 364.885297 -52.50508) (xy 364.939245 -52.512836) (xy 364.99154 -52.528191) (xy 365.030649 -52.546052)
			(xy 369.979673 -52.546052) (xy 369.979673 -52.491548) (xy 369.98743 -52.4376) (xy 370.002785 -52.385304)
			(xy 370.025427 -52.335726) (xy 370.054894 -52.289875) (xy 370.090586 -52.248685) (xy 370.131777 -52.212993)
			(xy 370.177628 -52.183526) (xy 370.227206 -52.160885) (xy 370.279502 -52.14553) (xy 370.33345 -52.137773)
			(xy 370.360702 -52.13731) (xy 370.388072 -52.137772) (xy 370.442252 -52.145591) (xy 370.494755 -52.161081)
			(xy 370.544502 -52.183923) (xy 370.590468 -52.213648) (xy 370.6114 -52.23129) (xy 370.611654 -52.231544)
			(xy 370.618746 -52.237123) (xy 370.635659 -52.243373) (xy 370.644674 -52.243736) (xy 370.71173 -52.243736)
			(xy 370.720747 -52.243386) (xy 370.737664 -52.237133) (xy 370.74475 -52.231544) (xy 370.74475 -52.23129)
			(xy 370.745004 -52.23129) (xy 370.765937 -52.213649) (xy 370.811905 -52.183925) (xy 370.861651 -52.161079)
			(xy 370.914153 -52.145583) (xy 370.968331 -52.137754) (xy 371.023073 -52.137754) (xy 371.077251 -52.145583)
			(xy 371.129753 -52.161079) (xy 371.179499 -52.183925) (xy 371.225467 -52.213649) (xy 371.2464 -52.23129)
			(xy 371.246654 -52.231544) (xy 371.253746 -52.237123) (xy 371.270659 -52.243373) (xy 371.279674 -52.243736)
			(xy 371.34673 -52.243736) (xy 371.355747 -52.243386) (xy 371.372664 -52.237133) (xy 371.37975 -52.231544)
			(xy 371.37975 -52.23129) (xy 371.380004 -52.23129) (xy 371.400922 -52.213634) (xy 371.446899 -52.183925)
			(xy 371.49665 -52.161093) (xy 371.549154 -52.145605) (xy 371.603332 -52.137782) (xy 371.630702 -52.13731)
			(xy 371.657954 -52.13776) (xy 371.711905 -52.145517) (xy 371.764201 -52.160873) (xy 371.813781 -52.183515)
			(xy 371.859633 -52.212983) (xy 371.900825 -52.248676) (xy 371.936518 -52.289868) (xy 371.965986 -52.335721)
			(xy 371.988628 -52.3853) (xy 372.003983 -52.437597) (xy 372.01174 -52.491548) (xy 372.01174 -52.546052)
			(xy 372.005795 -52.587398) (xy 373.055386 -52.587398) (xy 373.059457 -52.531776) (xy 373.071583 -52.477339)
			(xy 373.091506 -52.425248) (xy 373.118802 -52.376613) (xy 373.152888 -52.33247) (xy 373.193037 -52.293761)
			(xy 373.238395 -52.26131) (xy 373.287995 -52.235809) (xy 373.340779 -52.217802) (xy 373.395622 -52.207672)
			(xy 373.451356 -52.205635) (xy 373.506793 -52.211735) (xy 373.56075 -52.225841) (xy 373.612079 -52.247653)
			(xy 373.659685 -52.276707) (xy 373.702553 -52.312382) (xy 373.73977 -52.353919) (xy 373.770543 -52.400432)
			(xy 373.794215 -52.450929) (xy 373.810283 -52.504336) (xy 373.817879 -52.555952) (xy 380.883879 -52.555952)
			(xy 380.883879 -52.501448) (xy 380.891636 -52.447498) (xy 380.906993 -52.395202) (xy 380.929635 -52.345624)
			(xy 380.959103 -52.299772) (xy 380.994797 -52.258582) (xy 381.03599 -52.22289) (xy 381.081843 -52.193425)
			(xy 381.131423 -52.170785) (xy 381.18372 -52.155432) (xy 381.23767 -52.147678) (xy 381.264922 -52.147216)
			(xy 381.292293 -52.147665) (xy 381.346473 -52.155487) (xy 381.398976 -52.170979) (xy 381.448723 -52.193825)
			(xy 381.494689 -52.223553) (xy 381.51562 -52.241196) (xy 381.515874 -52.24145) (xy 381.522959 -52.247038)
			(xy 381.539877 -52.253283) (xy 381.548894 -52.253642) (xy 381.61595 -52.253642) (xy 381.624966 -52.253274)
			(xy 381.641884 -52.247035) (xy 381.64897 -52.24145) (xy 381.64897 -52.241196) (xy 381.649224 -52.241196)
			(xy 381.670173 -52.223578) (xy 381.716142 -52.193864) (xy 381.765885 -52.171023) (xy 381.818381 -52.155527)
			(xy 381.872554 -52.147693) (xy 381.899922 -52.147216) (xy 381.927174 -52.147655) (xy 381.981123 -52.155415)
			(xy 382.033418 -52.170773) (xy 382.082996 -52.193417) (xy 382.128846 -52.222885) (xy 382.170036 -52.258579)
			(xy 382.205728 -52.299771) (xy 382.235194 -52.345624) (xy 382.257835 -52.395203) (xy 382.27319 -52.447499)
			(xy 382.280946 -52.501448) (xy 382.280946 -52.555952) (xy 382.27319 -52.609901) (xy 382.257835 -52.662197)
			(xy 382.235194 -52.711776) (xy 382.205728 -52.757629) (xy 382.170036 -52.798821) (xy 382.128846 -52.834515)
			(xy 382.082996 -52.863983) (xy 382.033418 -52.886627) (xy 381.981123 -52.901985) (xy 381.927174 -52.909745)
			(xy 381.899922 -52.910232) (xy 381.872551 -52.90977) (xy 381.818372 -52.901953) (xy 381.765868 -52.886464)
			(xy 381.716121 -52.863621) (xy 381.670155 -52.833895) (xy 381.649224 -52.816252) (xy 381.64897 -52.815998)
			(xy 381.641868 -52.810434) (xy 381.624963 -52.804174) (xy 381.61595 -52.803806) (xy 381.548894 -52.803806)
			(xy 381.539877 -52.804159) (xy 381.52296 -52.810409) (xy 381.515874 -52.815998) (xy 381.515874 -52.816252)
			(xy 381.51562 -52.816252) (xy 381.494685 -52.833888) (xy 381.448714 -52.863602) (xy 381.398967 -52.886439)
			(xy 381.346467 -52.901931) (xy 381.292291 -52.909759) (xy 381.264922 -52.910232) (xy 381.23767 -52.909722)
			(xy 381.18372 -52.901968) (xy 381.131423 -52.886615) (xy 381.081843 -52.863975) (xy 381.03599 -52.83451)
			(xy 380.994797 -52.798818) (xy 380.959103 -52.757628) (xy 380.929635 -52.711776) (xy 380.906993 -52.662198)
			(xy 380.891636 -52.609902) (xy 380.883879 -52.555952) (xy 373.817879 -52.555952) (xy 373.818403 -52.559512)
			(xy 373.818912 -52.587398) (xy 373.818403 -52.615284) (xy 373.810283 -52.67046) (xy 373.794215 -52.723867)
			(xy 373.770543 -52.774364) (xy 373.73977 -52.820877) (xy 373.702553 -52.862414) (xy 373.659685 -52.898089)
			(xy 373.612079 -52.927143) (xy 373.56075 -52.948955) (xy 373.506793 -52.963061) (xy 373.451356 -52.969161)
			(xy 373.395622 -52.967124) (xy 373.340779 -52.956994) (xy 373.287995 -52.938987) (xy 373.238395 -52.913486)
			(xy 373.193037 -52.881035) (xy 373.152888 -52.842326) (xy 373.118802 -52.798183) (xy 373.091506 -52.749548)
			(xy 373.071583 -52.697457) (xy 373.059457 -52.64302) (xy 373.055386 -52.587398) (xy 372.005795 -52.587398)
			(xy 372.003983 -52.600003) (xy 371.988628 -52.6523) (xy 371.965986 -52.701879) (xy 371.936518 -52.747732)
			(xy 371.900825 -52.788924) (xy 371.859633 -52.824617) (xy 371.813781 -52.854085) (xy 371.764201 -52.876727)
			(xy 371.711905 -52.892083) (xy 371.657954 -52.89984) (xy 371.630702 -52.900326) (xy 371.603331 -52.899877)
			(xy 371.54915 -52.892058) (xy 371.496646 -52.876566) (xy 371.4469 -52.85372) (xy 371.400934 -52.82399)
			(xy 371.380004 -52.806346) (xy 371.37975 -52.806092) (xy 371.372654 -52.800519) (xy 371.355744 -52.794265)
			(xy 371.34673 -52.7939) (xy 371.279674 -52.7939) (xy 371.270656 -52.794245) (xy 371.253739 -52.800501)
			(xy 371.246654 -52.806092) (xy 371.2464 -52.806346) (xy 371.225467 -52.823987) (xy 371.179499 -52.853711)
			(xy 371.129753 -52.876557) (xy 371.077251 -52.892053) (xy 371.023073 -52.899882) (xy 370.968331 -52.899882)
			(xy 370.914153 -52.892053) (xy 370.861651 -52.876557) (xy 370.811905 -52.853711) (xy 370.765937 -52.823987)
			(xy 370.745004 -52.806346) (xy 370.74475 -52.806092) (xy 370.737654 -52.800519) (xy 370.720744 -52.794265)
			(xy 370.71173 -52.7939) (xy 370.644674 -52.7939) (xy 370.635656 -52.794245) (xy 370.618739 -52.800501)
			(xy 370.611654 -52.806092) (xy 370.611654 -52.806346) (xy 370.6114 -52.806346) (xy 370.590472 -52.82399)
			(xy 370.544499 -52.853703) (xy 370.49475 -52.876539) (xy 370.442249 -52.892029) (xy 370.388072 -52.899854)
			(xy 370.360702 -52.900326) (xy 370.33345 -52.899827) (xy 370.279502 -52.89207) (xy 370.227206 -52.876715)
			(xy 370.177628 -52.854074) (xy 370.131777 -52.824607) (xy 370.090586 -52.788915) (xy 370.054894 -52.747725)
			(xy 370.025427 -52.701874) (xy 370.002785 -52.652296) (xy 369.98743 -52.6) (xy 369.979673 -52.546052)
			(xy 365.030649 -52.546052) (xy 365.041117 -52.550833) (xy 365.086967 -52.580299) (xy 365.128158 -52.61599)
			(xy 365.163849 -52.657181) (xy 365.193315 -52.703031) (xy 365.215957 -52.752608) (xy 365.231312 -52.804903)
			(xy 365.239068 -52.858851) (xy 365.239554 -52.886102) (xy 365.2391 -52.913473) (xy 365.231281 -52.967653)
			(xy 365.21579 -53.020157) (xy 365.192945 -53.069903) (xy 365.163217 -53.115869) (xy 365.145574 -53.1368)
			(xy 365.14532 -53.137054) (xy 365.139737 -53.144143) (xy 365.13349 -53.161058) (xy 365.133128 -53.170074)
			(xy 365.133128 -53.23713) (xy 365.133465 -53.246149) (xy 365.139726 -53.263066) (xy 365.14532 -53.27015)
			(xy 365.145574 -53.27015) (xy 365.145574 -53.270404) (xy 365.163217 -53.291335) (xy 365.192941 -53.337303)
			(xy 365.215786 -53.38705) (xy 365.231283 -53.439552) (xy 365.239111 -53.493731) (xy 365.239111 -53.548472)
			(xy 365.231282 -53.602651) (xy 365.215785 -53.655153) (xy 365.19294 -53.704899) (xy 365.163215 -53.750867)
			(xy 365.146644 -53.77053) (xy 365.510826 -53.77053) (xy 365.511356 -53.741613) (xy 365.520081 -53.684442)
			(xy 365.537336 -53.629243) (xy 365.562726 -53.577281) (xy 365.595668 -53.529747) (xy 365.635407 -53.48773)
			(xy 365.657892 -53.46954) (xy 365.66667 -53.461904) (xy 365.67687 -53.441025) (xy 365.67745 -53.429408)
			(xy 365.67745 -53.349652) (xy 365.676942 -53.338016) (xy 365.666733 -53.317105) (xy 365.657892 -53.30952)
			(xy 365.635416 -53.29132) (xy 365.595681 -53.249302) (xy 365.562741 -53.201769) (xy 365.537352 -53.149809)
			(xy 365.520094 -53.094613) (xy 365.511362 -53.037445) (xy 365.510826 -53.00853) (xy 365.511283 -52.981276)
			(xy 365.519037 -52.927323) (xy 365.534391 -52.875023) (xy 365.557033 -52.825441) (xy 365.586501 -52.779586)
			(xy 365.622195 -52.738392) (xy 365.663389 -52.702698) (xy 365.709245 -52.673231) (xy 365.758827 -52.65059)
			(xy 365.811127 -52.635236) (xy 365.86508 -52.627483) (xy 365.892334 -52.627022) (xy 365.918649 -52.62746)
			(xy 365.970779 -52.6347) (xy 366.021423 -52.649024) (xy 366.069622 -52.670162) (xy 366.114464 -52.697714)
			(xy 366.155103 -52.731158) (xy 366.173258 -52.750212) (xy 366.180792 -52.757599) (xy 366.200063 -52.766131)
			(xy 366.210596 -52.766722) (xy 366.285272 -52.766722) (xy 366.295821 -52.766185) (xy 366.315115 -52.757654)
			(xy 366.32261 -52.750212) (xy 366.34077 -52.731161) (xy 366.381399 -52.697703) (xy 366.426238 -52.670143)
			(xy 366.474438 -52.649004) (xy 366.525085 -52.634686) (xy 366.577218 -52.627461) (xy 366.603534 -52.627022)
			(xy 366.630787 -52.627446) (xy 366.684739 -52.635208) (xy 366.737037 -52.650569) (xy 366.786616 -52.673216)
			(xy 366.832468 -52.702689) (xy 366.873658 -52.738387) (xy 366.909349 -52.779584) (xy 366.938814 -52.82544)
			(xy 366.961453 -52.875023) (xy 366.976805 -52.927324) (xy 366.984558 -52.981276) (xy 366.985042 -53.00853)
			(xy 366.98458 -53.036197) (xy 366.982349 -53.051456) (xy 375.24131 -53.051456) (xy 375.245381 -52.995834)
			(xy 375.257507 -52.941397) (xy 375.27743 -52.889306) (xy 375.304726 -52.840671) (xy 375.338812 -52.796528)
			(xy 375.378961 -52.757819) (xy 375.424319 -52.725368) (xy 375.473919 -52.699867) (xy 375.526703 -52.68186)
			(xy 375.581546 -52.67173) (xy 375.63728 -52.669693) (xy 375.692717 -52.675793) (xy 375.746674 -52.689899)
			(xy 375.798003 -52.711711) (xy 375.845609 -52.740765) (xy 375.888477 -52.77644) (xy 375.925694 -52.817977)
			(xy 375.956467 -52.86449) (xy 375.980139 -52.914987) (xy 375.996207 -52.968394) (xy 376.004327 -53.02357)
			(xy 376.004836 -53.051456) (xy 376.004327 -53.079342) (xy 375.996207 -53.134518) (xy 375.980139 -53.187925)
			(xy 375.956467 -53.238422) (xy 375.925694 -53.284935) (xy 375.888477 -53.326472) (xy 375.845609 -53.362147)
			(xy 375.798003 -53.391201) (xy 375.746674 -53.413013) (xy 375.692717 -53.427119) (xy 375.63728 -53.433219)
			(xy 375.581546 -53.431182) (xy 375.526703 -53.421052) (xy 375.473919 -53.403045) (xy 375.424319 -53.377544)
			(xy 375.378961 -53.345093) (xy 375.338812 -53.306384) (xy 375.304726 -53.262241) (xy 375.27743 -53.213606)
			(xy 375.257507 -53.161515) (xy 375.245381 -53.107078) (xy 375.24131 -53.051456) (xy 366.982349 -53.051456)
			(xy 366.976575 -53.09095) (xy 366.960752 -53.143974) (xy 366.937441 -53.194159) (xy 366.907131 -53.240454)
			(xy 366.870457 -53.28189) (xy 366.828187 -53.317599) (xy 366.804956 -53.332634) (xy 366.795266 -53.339255)
			(xy 366.782828 -53.359128) (xy 366.78108 -53.370734) (xy 366.773206 -53.450744) (xy 366.772568 -53.462382)
			(xy 366.780654 -53.484219) (xy 366.7887 -53.492654) (xy 366.788954 -53.492908) (xy 366.807513 -53.511012)
			(xy 366.840095 -53.551337) (xy 366.866912 -53.595707) (xy 366.887469 -53.643301) (xy 366.901387 -53.693242)
			(xy 366.908408 -53.744608) (xy 366.908842 -53.77053) (xy 366.90835 -53.79778) (xy 366.90059 -53.851726)
			(xy 366.885233 -53.904019) (xy 366.862591 -53.953594) (xy 366.833125 -53.999442) (xy 366.797434 -54.040631)
			(xy 366.756246 -54.076322) (xy 366.710397 -54.105789) (xy 366.660822 -54.128432) (xy 366.60853 -54.14379)
			(xy 366.554584 -54.15155) (xy 366.527334 -54.152038) (xy 366.499964 -54.151567) (xy 366.445784 -54.143753)
			(xy 366.393281 -54.128266) (xy 366.343534 -54.105425) (xy 366.297567 -54.0757) (xy 366.276636 -54.058058)
			(xy 366.276382 -54.057804) (xy 366.269304 -54.052204) (xy 366.252381 -54.045965) (xy 366.243362 -54.045612)
			(xy 366.176306 -54.045612) (xy 366.167289 -54.045969) (xy 366.150372 -54.052216) (xy 366.143286 -54.057804)
			(xy 366.143286 -54.058058) (xy 366.143032 -54.058058) (xy 366.122093 -54.075689) (xy 366.076123 -54.105404)
			(xy 366.026377 -54.128242) (xy 365.973878 -54.143734) (xy 365.919703 -54.151564) (xy 365.892334 -54.152038)
			(xy 365.865083 -54.151513) (xy 365.811136 -54.143762) (xy 365.758841 -54.128411) (xy 365.709263 -54.105775)
			(xy 365.663411 -54.076313) (xy 365.622219 -54.040626) (xy 365.586525 -53.99944) (xy 365.557056 -53.953593)
			(xy 365.534411 -53.904019) (xy 365.519052 -53.851726) (xy 365.511291 -53.797781) (xy 365.510826 -53.77053)
			(xy 365.146644 -53.77053) (xy 365.145574 -53.7718) (xy 365.14532 -53.772054) (xy 365.139737 -53.779143)
			(xy 365.13349 -53.796058) (xy 365.133128 -53.805074) (xy 365.133128 -53.87213) (xy 365.133465 -53.881149)
			(xy 365.139726 -53.898066) (xy 365.14532 -53.90515) (xy 365.145574 -53.90515) (xy 365.145574 -53.905404)
			(xy 365.163217 -53.926335) (xy 365.192941 -53.972303) (xy 365.215786 -54.02205) (xy 365.231283 -54.074552)
			(xy 365.239111 -54.128731) (xy 365.239111 -54.183472) (xy 365.231282 -54.237651) (xy 365.215785 -54.290153)
			(xy 365.201993 -54.320186) (xy 367.430558 -54.320186) (xy 367.431002 -54.292815) (xy 367.438823 -54.238634)
			(xy 367.454316 -54.18613) (xy 367.477163 -54.136384) (xy 367.506894 -54.090418) (xy 367.524538 -54.069488)
			(xy 367.524792 -54.069234) (xy 367.53037 -54.062141) (xy 367.536622 -54.045229) (xy 367.536984 -54.036214)
			(xy 367.536984 -53.969158) (xy 367.536603 -53.960144) (xy 367.530372 -53.943226) (xy 367.524792 -53.936138)
			(xy 367.524538 -53.936138) (xy 367.524538 -53.935884) (xy 367.506931 -53.914926) (xy 367.477213 -53.868961)
			(xy 367.45437 -53.81922) (xy 367.438872 -53.766725) (xy 367.431036 -53.712554) (xy 367.430558 -53.685186)
			(xy 367.431044 -53.657935) (xy 367.4388 -53.603987) (xy 367.454155 -53.551692) (xy 367.476797 -53.502115)
			(xy 367.506263 -53.456265) (xy 367.541954 -53.415074) (xy 367.583145 -53.379383) (xy 367.628995 -53.349917)
			(xy 367.678572 -53.327275) (xy 367.730867 -53.31192) (xy 367.784815 -53.304164) (xy 367.839317 -53.304164)
			(xy 367.893265 -53.31192) (xy 367.94556 -53.327275) (xy 367.995137 -53.349917) (xy 368.040987 -53.379383)
			(xy 368.082178 -53.415074) (xy 368.117869 -53.456265) (xy 368.143759 -53.496551) (xy 380.433564 -53.496551)
			(xy 380.433564 -53.442049) (xy 380.44132 -53.388101) (xy 380.456675 -53.335806) (xy 380.479315 -53.286228)
			(xy 380.508781 -53.240377) (xy 380.544471 -53.199186) (xy 380.585661 -53.163493) (xy 380.63151 -53.134025)
			(xy 380.681087 -53.111382) (xy 380.733381 -53.096024) (xy 380.787329 -53.088265) (xy 380.81458 -53.087778)
			(xy 380.841951 -53.088237) (xy 380.896131 -53.096053) (xy 380.948635 -53.111543) (xy 380.998382 -53.134387)
			(xy 381.044347 -53.164115) (xy 381.065278 -53.181758) (xy 381.065532 -53.182012) (xy 381.072633 -53.187578)
			(xy 381.089539 -53.193837) (xy 381.098552 -53.194204) (xy 381.165608 -53.194204) (xy 381.174625 -53.19385)
			(xy 381.191542 -53.1876) (xy 381.198628 -53.182012) (xy 381.198628 -53.181758) (xy 381.198882 -53.181758)
			(xy 381.219804 -53.164107) (xy 381.26578 -53.134398) (xy 381.315531 -53.111565) (xy 381.368033 -53.096077)
			(xy 381.42221 -53.088251) (xy 381.44958 -53.087778) (xy 381.476833 -53.088268) (xy 381.530784 -53.096022)
			(xy 381.583082 -53.111376) (xy 381.632663 -53.134017) (xy 381.678517 -53.163483) (xy 381.719711 -53.199175)
			(xy 381.755405 -53.240367) (xy 381.784874 -53.286219) (xy 381.807517 -53.335799) (xy 381.822873 -53.388097)
			(xy 381.830631 -53.442047) (xy 381.830631 -53.496553) (xy 381.822873 -53.550503) (xy 381.807517 -53.602801)
			(xy 381.784874 -53.652381) (xy 381.755405 -53.698233) (xy 381.719711 -53.739425) (xy 381.678517 -53.775117)
			(xy 381.632663 -53.804583) (xy 381.583082 -53.827224) (xy 381.530784 -53.842578) (xy 381.476833 -53.850332)
			(xy 381.44958 -53.850794) (xy 381.422209 -53.850341) (xy 381.36803 -53.84252) (xy 381.315526 -53.827028)
			(xy 381.26578 -53.804184) (xy 381.219813 -53.774456) (xy 381.198882 -53.756814) (xy 381.198628 -53.75656)
			(xy 381.191541 -53.750974) (xy 381.174624 -53.744728) (xy 381.165608 -53.744368) (xy 381.098552 -53.744368)
			(xy 381.089538 -53.744757) (xy 381.072622 -53.750983) (xy 381.065532 -53.75656) (xy 381.065532 -53.756814)
			(xy 381.065278 -53.756814) (xy 381.044329 -53.774432) (xy 380.998361 -53.804147) (xy 380.948617 -53.826986)
			(xy 380.896121 -53.842482) (xy 380.841948 -53.850317) (xy 380.81458 -53.850794) (xy 380.787329 -53.850335)
			(xy 380.733381 -53.842576) (xy 380.681087 -53.827218) (xy 380.63151 -53.804575) (xy 380.585661 -53.775107)
			(xy 380.544471 -53.739414) (xy 380.508781 -53.698223) (xy 380.479315 -53.652372) (xy 380.456675 -53.602794)
			(xy 380.44132 -53.550499) (xy 380.433564 -53.496551) (xy 368.143759 -53.496551) (xy 368.147335 -53.502115)
			(xy 368.169977 -53.551692) (xy 368.185332 -53.603987) (xy 368.193088 -53.657935) (xy 368.193574 -53.685186)
			(xy 368.193106 -53.712556) (xy 368.18529 -53.766735) (xy 368.169801 -53.819239) (xy 368.14696 -53.868986)
			(xy 368.117235 -53.914952) (xy 368.099594 -53.935884) (xy 368.09934 -53.936138) (xy 368.093766 -53.943233)
			(xy 368.087513 -53.960144) (xy 368.087148 -53.969158) (xy 368.087148 -54.036214) (xy 368.087488 -54.045233)
			(xy 368.093746 -54.06215) (xy 368.09934 -54.069234) (xy 368.099594 -54.069234) (xy 368.099594 -54.069488)
			(xy 368.11724 -54.090415) (xy 368.146951 -54.136389) (xy 368.169786 -54.186138) (xy 368.185275 -54.23864)
			(xy 368.193101 -54.292816) (xy 368.193574 -54.320186) (xy 368.193088 -54.347437) (xy 368.185332 -54.401385)
			(xy 368.169977 -54.45368) (xy 368.147335 -54.503257) (xy 368.117869 -54.549107) (xy 368.082178 -54.590298)
			(xy 368.040987 -54.625989) (xy 367.995137 -54.655455) (xy 367.94556 -54.678097) (xy 367.893265 -54.693452)
			(xy 367.839317 -54.701208) (xy 367.784815 -54.701208) (xy 367.730867 -54.693452) (xy 367.678572 -54.678097)
			(xy 367.628995 -54.655455) (xy 367.583145 -54.625989) (xy 367.541954 -54.590298) (xy 367.506263 -54.549107)
			(xy 367.476797 -54.503257) (xy 367.454155 -54.45368) (xy 367.4388 -54.401385) (xy 367.431044 -54.347437)
			(xy 367.430558 -54.320186) (xy 365.201993 -54.320186) (xy 365.19294 -54.339899) (xy 365.163215 -54.385867)
			(xy 365.145574 -54.4068) (xy 365.14532 -54.407054) (xy 365.139737 -54.414143) (xy 365.13349 -54.431058)
			(xy 365.133128 -54.440074) (xy 365.133128 -54.50713) (xy 365.133465 -54.516149) (xy 365.139726 -54.533066)
			(xy 365.14532 -54.54015) (xy 365.145574 -54.54015) (xy 365.145574 -54.540404) (xy 365.163224 -54.561327)
			(xy 365.192935 -54.607302) (xy 365.21577 -54.657052) (xy 365.231258 -54.709555) (xy 365.239082 -54.763732)
			(xy 365.239199 -54.770528) (xy 368.37112 -54.770528) (xy 368.371598 -54.743158) (xy 368.379412 -54.688979)
			(xy 368.394898 -54.636476) (xy 368.417737 -54.586729) (xy 368.44746 -54.540762) (xy 368.4651 -54.51983)
			(xy 368.465354 -54.519576) (xy 368.470963 -54.512505) (xy 368.477195 -54.495576) (xy 368.477546 -54.486556)
			(xy 368.477546 -54.4195) (xy 368.477201 -54.410482) (xy 368.470946 -54.393564) (xy 368.465354 -54.38648)
			(xy 368.4651 -54.38648) (xy 368.4651 -54.386226) (xy 368.44746 -54.365295) (xy 368.417748 -54.319322)
			(xy 368.394912 -54.269574) (xy 368.379422 -54.217073) (xy 368.371594 -54.162897) (xy 368.37112 -54.135528)
			(xy 368.371606 -54.108277) (xy 368.379362 -54.054329) (xy 368.394717 -54.002034) (xy 368.417359 -53.952457)
			(xy 368.446825 -53.906607) (xy 368.482516 -53.865416) (xy 368.523707 -53.829725) (xy 368.569557 -53.800259)
			(xy 368.619134 -53.777617) (xy 368.671429 -53.762262) (xy 368.725377 -53.754506) (xy 368.779879 -53.754506)
			(xy 368.833827 -53.762262) (xy 368.886122 -53.777617) (xy 368.935699 -53.800259) (xy 368.981549 -53.829725)
			(xy 369.02274 -53.865416) (xy 369.058431 -53.906607) (xy 369.087897 -53.952457) (xy 369.092972 -53.96357)
			(xy 373.07215 -53.96357) (xy 373.076221 -53.907948) (xy 373.088347 -53.853511) (xy 373.10827 -53.80142)
			(xy 373.135566 -53.752785) (xy 373.169652 -53.708642) (xy 373.209801 -53.669933) (xy 373.255159 -53.637482)
			(xy 373.304759 -53.611981) (xy 373.357543 -53.593974) (xy 373.412386 -53.583844) (xy 373.46812 -53.581807)
			(xy 373.523557 -53.587907) (xy 373.577514 -53.602013) (xy 373.628843 -53.623825) (xy 373.676449 -53.652879)
			(xy 373.719317 -53.688554) (xy 373.756534 -53.730091) (xy 373.787307 -53.776604) (xy 373.810979 -53.827101)
			(xy 373.827047 -53.880508) (xy 373.835167 -53.935684) (xy 373.835676 -53.96357) (xy 373.835167 -53.991456)
			(xy 373.827047 -54.046632) (xy 373.810979 -54.100039) (xy 373.787307 -54.150536) (xy 373.756534 -54.197049)
			(xy 373.719317 -54.238586) (xy 373.676449 -54.274261) (xy 373.628843 -54.303315) (xy 373.577514 -54.325127)
			(xy 373.523557 -54.339233) (xy 373.46812 -54.345333) (xy 373.412386 -54.343296) (xy 373.357543 -54.333166)
			(xy 373.304759 -54.315159) (xy 373.255159 -54.289658) (xy 373.209801 -54.257207) (xy 373.169652 -54.218498)
			(xy 373.135566 -54.174355) (xy 373.10827 -54.12572) (xy 373.088347 -54.073629) (xy 373.076221 -54.019192)
			(xy 373.07215 -53.96357) (xy 369.092972 -53.96357) (xy 369.110539 -54.002034) (xy 369.125894 -54.054329)
			(xy 369.13365 -54.108277) (xy 369.134136 -54.135528) (xy 369.133702 -54.1629) (xy 369.125879 -54.217081)
			(xy 369.110383 -54.269585) (xy 369.087534 -54.319331) (xy 369.057801 -54.365296) (xy 369.040156 -54.386226)
			(xy 369.039902 -54.38648) (xy 369.034318 -54.393568) (xy 369.02807 -54.410484) (xy 369.02771 -54.4195)
			(xy 369.02771 -54.486556) (xy 369.028086 -54.495571) (xy 369.03432 -54.512488) (xy 369.039902 -54.519576)
			(xy 369.040156 -54.519576) (xy 369.040156 -54.51983) (xy 369.057769 -54.540783) (xy 369.087486 -54.58675)
			(xy 369.110328 -54.636492) (xy 369.125825 -54.688988) (xy 369.133659 -54.74316) (xy 369.134136 -54.770528)
			(xy 369.13365 -54.797779) (xy 369.125894 -54.851727) (xy 369.110539 -54.904022) (xy 369.087897 -54.953599)
			(xy 369.065113 -54.989051) (xy 378.201168 -54.989051) (xy 378.201168 -54.934549) (xy 378.208924 -54.880602)
			(xy 378.224278 -54.828308) (xy 378.246918 -54.778732) (xy 378.276382 -54.732881) (xy 378.312072 -54.691691)
			(xy 378.35326 -54.655998) (xy 378.399109 -54.62653) (xy 378.448684 -54.603887) (xy 378.500977 -54.588529)
			(xy 378.554923 -54.58077) (xy 378.582174 -54.580282) (xy 378.610265 -54.580797) (xy 378.665841 -54.589021)
			(xy 378.71961 -54.605308) (xy 378.770407 -54.629308) (xy 378.817134 -54.660499) (xy 378.85878 -54.698208)
			(xy 378.894443 -54.741619) (xy 378.909326 -54.765448) (xy 378.91466 -54.774338) (xy 378.931678 -54.78653)
			(xy 379.024896 -54.80685) (xy 379.04547 -54.802532) (xy 379.054106 -54.79669) (xy 379.078166 -54.780684)
			(xy 379.130099 -54.755343) (xy 379.185258 -54.738119) (xy 379.242383 -54.729406) (xy 379.271276 -54.728872)
			(xy 379.298527 -54.729378) (xy 379.352476 -54.737131) (xy 379.404772 -54.752483) (xy 379.45435 -54.775121)
			(xy 379.500203 -54.804585) (xy 379.541395 -54.840274) (xy 379.577089 -54.881462) (xy 379.606558 -54.927311)
			(xy 379.629202 -54.976887) (xy 379.64456 -55.029181) (xy 379.652319 -55.083129) (xy 379.652784 -55.11038)
			(xy 379.65231 -55.13775) (xy 379.644495 -55.191929) (xy 379.629008 -55.244432) (xy 379.606168 -55.294179)
			(xy 379.576445 -55.340146) (xy 379.558804 -55.361078) (xy 379.55855 -55.361332) (xy 379.55298 -55.36843)
			(xy 379.546724 -55.385338) (xy 379.546358 -55.394352) (xy 379.546358 -55.461408) (xy 379.546699 -55.470427)
			(xy 379.552956 -55.487344) (xy 379.55855 -55.494428) (xy 379.558804 -55.494428) (xy 379.558804 -55.494682)
			(xy 379.576424 -55.515631) (xy 379.606147 -55.561597) (xy 379.628992 -55.611341) (xy 379.644488 -55.66384)
			(xy 379.652318 -55.718016) (xy 379.65232 -55.772754) (xy 379.644495 -55.826931) (xy 379.629002 -55.879431)
			(xy 379.606162 -55.929177) (xy 379.576442 -55.975145) (xy 379.558804 -55.996078) (xy 379.55855 -55.996332)
			(xy 379.55298 -56.00343) (xy 379.546724 -56.020338) (xy 379.546358 -56.029352) (xy 379.546358 -56.096408)
			(xy 379.546699 -56.105427) (xy 379.552956 -56.122344) (xy 379.55855 -56.129428) (xy 379.558804 -56.129428)
			(xy 379.558804 -56.129682) (xy 379.576449 -56.15061) (xy 379.60616 -56.196584) (xy 379.628994 -56.246332)
			(xy 379.644484 -56.298834) (xy 379.652311 -56.353011) (xy 379.652784 -56.38038) (xy 379.652298 -56.407631)
			(xy 379.644542 -56.461579) (xy 379.629187 -56.513874) (xy 379.606545 -56.563451) (xy 379.577079 -56.609301)
			(xy 379.541388 -56.650492) (xy 379.500197 -56.686183) (xy 379.454347 -56.715649) (xy 379.40477 -56.738291)
			(xy 379.352475 -56.753646) (xy 379.298527 -56.761402) (xy 379.244025 -56.761402) (xy 379.190077 -56.753646)
			(xy 379.137782 -56.738291) (xy 379.088205 -56.715649) (xy 379.042355 -56.686183) (xy 379.001164 -56.650492)
			(xy 378.965473 -56.609301) (xy 378.936007 -56.563451) (xy 378.913365 -56.513874) (xy 378.89801 -56.461579)
			(xy 378.890254 -56.407631) (xy 378.889768 -56.38038) (xy 378.890206 -56.353009) (xy 378.898028 -56.298828)
			(xy 378.913523 -56.246324) (xy 378.936371 -56.196577) (xy 378.966103 -56.150612) (xy 378.983748 -56.129682)
			(xy 378.984002 -56.129428) (xy 378.989583 -56.122338) (xy 378.995833 -56.105424) (xy 378.996194 -56.096408)
			(xy 378.996194 -56.029352) (xy 378.995813 -56.020338) (xy 378.989582 -56.00342) (xy 378.984002 -55.996332)
			(xy 378.983748 -55.996332) (xy 378.983748 -55.996078) (xy 378.966087 -55.975162) (xy 378.936361 -55.929191)
			(xy 378.913516 -55.879443) (xy 378.89802 -55.826938) (xy 378.890193 -55.772757) (xy 378.890195 -55.718013)
			(xy 378.898027 -55.663833) (xy 378.913526 -55.611329) (xy 378.936376 -55.561582) (xy 378.966105 -55.515614)
			(xy 378.983748 -55.494682) (xy 378.984002 -55.494428) (xy 378.989583 -55.487338) (xy 378.995833 -55.470424)
			(xy 378.996194 -55.461408) (xy 378.996194 -55.394352) (xy 378.995813 -55.385338) (xy 378.989582 -55.36842)
			(xy 378.984002 -55.361332) (xy 378.983748 -55.360824) (xy 378.972801 -55.348092) (xy 378.952962 -55.320999)
			(xy 378.944124 -55.306722) (xy 378.93879 -55.297832) (xy 378.921772 -55.28564) (xy 378.828554 -55.26532)
			(xy 378.80798 -55.269638) (xy 378.799344 -55.27548) (xy 378.775268 -55.291461) (xy 378.723341 -55.316809)
			(xy 378.668187 -55.33404) (xy 378.611066 -55.342761) (xy 378.582174 -55.343298) (xy 378.554923 -55.34283)
			(xy 378.500977 -55.335071) (xy 378.448684 -55.319713) (xy 378.399109 -55.29707) (xy 378.35326 -55.267602)
			(xy 378.312072 -55.231909) (xy 378.276382 -55.190719) (xy 378.246918 -55.144868) (xy 378.224278 -55.095292)
			(xy 378.208924 -55.042998) (xy 378.201168 -54.989051) (xy 369.065113 -54.989051) (xy 369.058431 -54.999449)
			(xy 369.02274 -55.04064) (xy 368.981549 -55.076331) (xy 368.935699 -55.105797) (xy 368.886122 -55.128439)
			(xy 368.833827 -55.143794) (xy 368.779879 -55.15155) (xy 368.725377 -55.15155) (xy 368.671429 -55.143794)
			(xy 368.619134 -55.128439) (xy 368.569557 -55.105797) (xy 368.523707 -55.076331) (xy 368.482516 -55.04064)
			(xy 368.446825 -54.999449) (xy 368.417359 -54.953599) (xy 368.394717 -54.904022) (xy 368.379362 -54.851727)
			(xy 368.371606 -54.797779) (xy 368.37112 -54.770528) (xy 365.239199 -54.770528) (xy 365.239554 -54.791102)
			(xy 365.239068 -54.818353) (xy 365.231312 -54.872301) (xy 365.215957 -54.924596) (xy 365.193315 -54.974173)
			(xy 365.163849 -55.020023) (xy 365.128158 -55.061214) (xy 365.086967 -55.096905) (xy 365.041117 -55.126371)
			(xy 364.99154 -55.149013) (xy 364.939245 -55.164368) (xy 364.885297 -55.172124) (xy 364.830795 -55.172124)
			(xy 364.776847 -55.164368) (xy 364.724552 -55.149013) (xy 364.674975 -55.126371) (xy 364.629125 -55.096905)
			(xy 364.587934 -55.061214) (xy 364.552243 -55.020023) (xy 364.522777 -54.974173) (xy 364.500135 -54.924596)
			(xy 364.48478 -54.872301) (xy 364.477024 -54.818353) (xy 364.476538 -54.791102) (xy 362.57858 -54.791102)
			(xy 362.575488 -54.812611) (xy 362.560133 -54.864906) (xy 362.537491 -54.914483) (xy 362.508025 -54.960333)
			(xy 362.472334 -55.001524) (xy 362.431143 -55.037215) (xy 362.385293 -55.066681) (xy 362.335716 -55.089323)
			(xy 362.283421 -55.104678) (xy 362.229473 -55.112434) (xy 362.174971 -55.112434) (xy 362.121023 -55.104678)
			(xy 362.068728 -55.089323) (xy 362.019151 -55.066681) (xy 361.973301 -55.037215) (xy 361.93211 -55.001524)
			(xy 361.896419 -54.960333) (xy 361.866953 -54.914483) (xy 361.844311 -54.864906) (xy 361.828956 -54.812611)
			(xy 361.8212 -54.758663) (xy 361.820714 -54.731412) (xy 353.3129 -54.731412) (xy 353.352526 -54.737112)
			(xy 353.40482 -54.752469) (xy 353.454396 -54.775112) (xy 353.500245 -54.804579) (xy 353.541434 -54.840271)
			(xy 353.577125 -54.881462) (xy 353.606592 -54.927311) (xy 353.629234 -54.976888) (xy 353.64459 -55.029182)
			(xy 353.652349 -55.083129) (xy 353.652836 -55.11038) (xy 353.652374 -55.137751) (xy 353.644557 -55.19193)
			(xy 353.629068 -55.244434) (xy 353.606225 -55.294181) (xy 353.576499 -55.340147) (xy 353.558856 -55.361078)
			(xy 353.558602 -55.361332) (xy 353.553038 -55.368434) (xy 353.546778 -55.385339) (xy 353.54641 -55.394352)
			(xy 353.54641 -55.461408) (xy 353.546761 -55.470426) (xy 353.553012 -55.487343) (xy 353.558602 -55.494428)
			(xy 353.558856 -55.494428) (xy 353.558856 -55.494682) (xy 353.576478 -55.51563) (xy 353.606205 -55.561595)
			(xy 353.629052 -55.611339) (xy 353.644551 -55.663838) (xy 353.652382 -55.718015) (xy 353.652382 -55.722266)
			(xy 374.134124 -55.722266) (xy 374.138195 -55.666644) (xy 374.150321 -55.612207) (xy 374.170244 -55.560116)
			(xy 374.19754 -55.511481) (xy 374.231626 -55.467338) (xy 374.271775 -55.428629) (xy 374.317133 -55.396178)
			(xy 374.366733 -55.370677) (xy 374.419517 -55.35267) (xy 374.47436 -55.34254) (xy 374.530094 -55.340503)
			(xy 374.585531 -55.346603) (xy 374.639488 -55.360709) (xy 374.690817 -55.382521) (xy 374.738423 -55.411575)
			(xy 374.749569 -55.420851) (xy 376.524768 -55.420851) (xy 376.524768 -55.366349) (xy 376.532524 -55.312402)
			(xy 376.547878 -55.260108) (xy 376.570518 -55.210532) (xy 376.599982 -55.164681) (xy 376.635672 -55.123491)
			(xy 376.67686 -55.087798) (xy 376.722709 -55.05833) (xy 376.772284 -55.035687) (xy 376.824577 -55.020329)
			(xy 376.878523 -55.01257) (xy 376.905774 -55.012082) (xy 376.932087 -55.012572) (xy 376.984214 -55.019803)
			(xy 377.034856 -55.034118) (xy 377.083055 -55.055247) (xy 377.127899 -55.082788) (xy 377.16854 -55.116223)
			(xy 377.186698 -55.135272) (xy 377.194222 -55.142671) (xy 377.2135 -55.151198) (xy 377.224036 -55.151782)
			(xy 377.298712 -55.151782) (xy 377.309265 -55.151278) (xy 377.32856 -55.142726) (xy 377.33605 -55.135272)
			(xy 377.354183 -55.116194) (xy 377.394818 -55.08274) (xy 377.439663 -55.055184) (xy 377.487868 -55.03405)
			(xy 377.53852 -55.019738) (xy 377.590657 -55.012518) (xy 377.616974 -55.012082) (xy 377.644227 -55.012564)
			(xy 377.69818 -55.020317) (xy 377.750479 -55.035671) (xy 377.800061 -55.058311) (xy 377.845917 -55.087778)
			(xy 377.887111 -55.12347) (xy 377.922807 -55.164663) (xy 377.952276 -55.210516) (xy 377.97492 -55.260096)
			(xy 377.990277 -55.312395) (xy 377.998035 -55.366347) (xy 377.998035 -55.420853) (xy 377.990277 -55.474805)
			(xy 377.97492 -55.527104) (xy 377.952276 -55.576684) (xy 377.922807 -55.622537) (xy 377.887111 -55.66373)
			(xy 377.845917 -55.699422) (xy 377.800061 -55.728889) (xy 377.750479 -55.751529) (xy 377.69818 -55.766883)
			(xy 377.644227 -55.774636) (xy 377.616974 -55.775098) (xy 377.590659 -55.774649) (xy 377.53853 -55.76741)
			(xy 377.487887 -55.753088) (xy 377.439688 -55.731952) (xy 377.394845 -55.704402) (xy 377.354206 -55.670961)
			(xy 377.33605 -55.651908) (xy 377.328548 -55.644484) (xy 377.309253 -55.635972) (xy 377.298712 -55.635398)
			(xy 377.224036 -55.635398) (xy 377.213487 -55.635934) (xy 377.194192 -55.644464) (xy 377.186698 -55.651908)
			(xy 377.168538 -55.670959) (xy 377.127909 -55.704416) (xy 377.08307 -55.731976) (xy 377.03487 -55.753115)
			(xy 376.984223 -55.767433) (xy 376.93209 -55.774659) (xy 376.905774 -55.775098) (xy 376.878523 -55.77463)
			(xy 376.824577 -55.766871) (xy 376.772284 -55.751513) (xy 376.722709 -55.72887) (xy 376.67686 -55.699402)
			(xy 376.635672 -55.663709) (xy 376.599982 -55.622519) (xy 376.570518 -55.576668) (xy 376.547878 -55.527092)
			(xy 376.532524 -55.474798) (xy 376.524768 -55.420851) (xy 374.749569 -55.420851) (xy 374.781291 -55.44725)
			(xy 374.818508 -55.488787) (xy 374.849281 -55.5353) (xy 374.872953 -55.585797) (xy 374.889021 -55.639204)
			(xy 374.897141 -55.69438) (xy 374.89765 -55.722266) (xy 374.897141 -55.750152) (xy 374.889021 -55.805328)
			(xy 374.872953 -55.858735) (xy 374.849281 -55.909232) (xy 374.818508 -55.955745) (xy 374.781291 -55.997282)
			(xy 374.738423 -56.032957) (xy 374.690817 -56.062011) (xy 374.639488 -56.083823) (xy 374.585531 -56.097929)
			(xy 374.530094 -56.104029) (xy 374.47436 -56.101992) (xy 374.419517 -56.091862) (xy 374.366733 -56.073855)
			(xy 374.317133 -56.048354) (xy 374.271775 -56.015903) (xy 374.231626 -55.977194) (xy 374.19754 -55.933051)
			(xy 374.170244 -55.884416) (xy 374.150321 -55.832325) (xy 374.138195 -55.777888) (xy 374.134124 -55.722266)
			(xy 353.652382 -55.722266) (xy 353.652384 -55.772755) (xy 353.644557 -55.826932) (xy 353.629063 -55.879433)
			(xy 353.606219 -55.929179) (xy 353.576496 -55.975146) (xy 353.558856 -55.996078) (xy 353.558602 -55.996332)
			(xy 353.553038 -56.003434) (xy 353.546778 -56.020339) (xy 353.54641 -56.029352) (xy 353.54641 -56.096408)
			(xy 353.546761 -56.105426) (xy 353.553012 -56.122343) (xy 353.558602 -56.129428) (xy 353.558856 -56.129428)
			(xy 353.558856 -56.129682) (xy 353.576493 -56.150616) (xy 353.606207 -56.196587) (xy 353.629044 -56.246334)
			(xy 353.644535 -56.298835) (xy 353.652363 -56.353011) (xy 353.652836 -56.38038) (xy 353.65235 -56.407631)
			(xy 353.644594 -56.461579) (xy 353.629239 -56.513874) (xy 353.606597 -56.563451) (xy 353.577131 -56.609301)
			(xy 353.54144 -56.650492) (xy 353.500249 -56.686183) (xy 353.454399 -56.715649) (xy 353.404822 -56.738291)
			(xy 353.352527 -56.753646) (xy 353.298579 -56.761402) (xy 353.244077 -56.761402) (xy 353.190129 -56.753646)
			(xy 353.137834 -56.738291) (xy 353.088257 -56.715649) (xy 353.042407 -56.686183) (xy 353.001216 -56.650492)
			(xy 352.965525 -56.609301) (xy 352.936059 -56.563451) (xy 352.913417 -56.513874) (xy 352.898062 -56.461579)
			(xy 352.890306 -56.407631) (xy 352.88982 -56.38038) (xy 352.890269 -56.353009) (xy 352.898091 -56.298829)
			(xy 352.913583 -56.246326) (xy 352.936429 -56.196579) (xy 352.966157 -56.150613) (xy 352.9838 -56.129682)
			(xy 352.984054 -56.129428) (xy 352.989641 -56.122342) (xy 352.995886 -56.105425) (xy 352.996246 -56.096408)
			(xy 352.996246 -56.029352) (xy 352.995876 -56.020336) (xy 352.989639 -56.003418) (xy 352.984054 -55.996332)
			(xy 352.9838 -55.996332) (xy 352.9838 -55.996078) (xy 352.966141 -55.975161) (xy 352.936419 -55.929189)
			(xy 352.913576 -55.879441) (xy 352.898083 -55.826936) (xy 352.890257 -55.772756) (xy 352.890259 -55.718014)
			(xy 352.898089 -55.663834) (xy 352.913587 -55.611331) (xy 352.936433 -55.561584) (xy 352.966159 -55.515615)
			(xy 352.9838 -55.494682) (xy 352.984054 -55.494428) (xy 352.989641 -55.487342) (xy 352.995886 -55.470425)
			(xy 352.996246 -55.461408) (xy 352.996246 -55.394352) (xy 352.995876 -55.385336) (xy 352.989639 -55.368418)
			(xy 352.984054 -55.361332) (xy 352.9838 -55.360824) (xy 352.972856 -55.348089) (xy 352.953015 -55.320998)
			(xy 352.944176 -55.306722) (xy 352.938842 -55.297832) (xy 352.921824 -55.28564) (xy 352.828606 -55.26532)
			(xy 352.808032 -55.269638) (xy 352.799396 -55.27548) (xy 352.775333 -55.291482) (xy 352.723402 -55.316825)
			(xy 352.668243 -55.33405) (xy 352.611119 -55.342764) (xy 352.582226 -55.343298) (xy 352.554971 -55.342857)
			(xy 352.501016 -55.335103) (xy 352.448714 -55.319749) (xy 352.399129 -55.297107) (xy 352.353271 -55.267639)
			(xy 352.312074 -55.231944) (xy 352.276377 -55.19075) (xy 352.246906 -55.144894) (xy 352.224261 -55.095311)
			(xy 352.208903 -55.043009) (xy 352.201145 -54.989055) (xy 342.581025 -54.989055) (xy 342.589626 -55.420855)
			(xy 350.524745 -55.420855) (xy 350.524745 -55.366345) (xy 350.532503 -55.312391) (xy 350.547861 -55.260089)
			(xy 350.570506 -55.210506) (xy 350.599977 -55.16465) (xy 350.635674 -55.123456) (xy 350.676871 -55.087761)
			(xy 350.722729 -55.058293) (xy 350.772314 -55.035651) (xy 350.824616 -55.020297) (xy 350.878571 -55.012543)
			(xy 350.905826 -55.012082) (xy 350.93214 -55.012538) (xy 350.984269 -55.019776) (xy 351.034912 -55.034098)
			(xy 351.083111 -55.055232) (xy 351.127954 -55.08278) (xy 351.168593 -55.11622) (xy 351.18675 -55.135272)
			(xy 351.194255 -55.142694) (xy 351.213547 -55.151208) (xy 351.224088 -55.151782) (xy 351.298764 -55.151782)
			(xy 351.309314 -55.151252) (xy 351.32861 -55.142718) (xy 351.336102 -55.135272) (xy 351.354258 -55.116217)
			(xy 351.394888 -55.082761) (xy 351.439729 -55.055203) (xy 351.487929 -55.034064) (xy 351.538576 -55.019747)
			(xy 351.59071 -55.012521) (xy 351.617026 -55.012082) (xy 351.644275 -55.01259) (xy 351.698219 -55.020349)
			(xy 351.750509 -55.035706) (xy 351.800082 -55.058348) (xy 351.845927 -55.087814) (xy 351.887113 -55.123505)
			(xy 351.922801 -55.164693) (xy 351.952264 -55.210541) (xy 351.974903 -55.260115) (xy 351.990256 -55.312407)
			(xy 351.998012 -55.366351) (xy 351.998012 -55.420849) (xy 351.990256 -55.474793) (xy 351.974903 -55.527085)
			(xy 351.952264 -55.576659) (xy 351.922801 -55.622507) (xy 351.887113 -55.663695) (xy 351.845927 -55.699386)
			(xy 351.800082 -55.728852) (xy 351.750509 -55.751494) (xy 351.698219 -55.766851) (xy 351.644275 -55.77461)
			(xy 351.617026 -55.775098) (xy 351.590713 -55.774614) (xy 351.538585 -55.767383) (xy 351.487942 -55.753067)
			(xy 351.439743 -55.731937) (xy 351.394899 -55.704394) (xy 351.354259 -55.670958) (xy 351.336102 -55.651908)
			(xy 351.32858 -55.644507) (xy 351.3093 -55.635982) (xy 351.298764 -55.635398) (xy 351.224088 -55.635398)
			(xy 351.213536 -55.635908) (xy 351.194241 -55.644457) (xy 351.18675 -55.651908) (xy 351.168613 -55.670982)
			(xy 351.127979 -55.704437) (xy 351.083135 -55.731994) (xy 351.034931 -55.753129) (xy 350.98428 -55.767442)
			(xy 350.932143 -55.774662) (xy 350.905826 -55.775098) (xy 350.878571 -55.774657) (xy 350.824616 -55.766903)
			(xy 350.772314 -55.751549) (xy 350.722729 -55.728907) (xy 350.676871 -55.699439) (xy 350.635674 -55.663744)
			(xy 350.599977 -55.62255) (xy 350.570506 -55.576694) (xy 350.547861 -55.527111) (xy 350.532503 -55.474809)
			(xy 350.524745 -55.420855) (xy 342.589626 -55.420855) (xy 342.620092 -56.950356) (xy 342.620092 -56.971184)
			(xy 342.619714 -57.002934) (xy 369.863624 -57.002934) (xy 369.864125 -56.974842) (xy 369.872349 -56.919265)
			(xy 369.888637 -56.865495) (xy 369.912638 -56.814697) (xy 369.943833 -56.76797) (xy 369.981545 -56.726325)
			(xy 370.024959 -56.690664) (xy 370.04879 -56.675782) (xy 370.05768 -56.670448) (xy 370.069872 -56.65343)
			(xy 370.090192 -56.560212) (xy 370.085874 -56.539638) (xy 370.080032 -56.531002) (xy 370.064034 -56.506937)
			(xy 370.03869 -56.455006) (xy 370.021464 -56.399848) (xy 370.012748 -56.342724) (xy 370.012214 -56.313832)
			(xy 370.012685 -56.286579) (xy 370.020438 -56.232627) (xy 370.035791 -56.180328) (xy 370.058432 -56.130747)
			(xy 370.087899 -56.084892) (xy 370.123592 -56.043699) (xy 370.164784 -56.008005) (xy 370.210638 -55.978537)
			(xy 370.260219 -55.955895) (xy 370.312517 -55.94054) (xy 370.366469 -55.932786) (xy 370.393722 -55.932324)
			(xy 370.421093 -55.932771) (xy 370.475273 -55.940593) (xy 370.527777 -55.956086) (xy 370.577523 -55.978932)
			(xy 370.623489 -56.008661) (xy 370.64442 -56.026304) (xy 370.644674 -56.026558) (xy 370.651759 -56.032147)
			(xy 370.668677 -56.038391) (xy 370.677694 -56.03875) (xy 370.74475 -56.03875) (xy 370.753766 -56.03838)
			(xy 370.770683 -56.032143) (xy 370.77777 -56.026558) (xy 370.77777 -56.026304) (xy 370.778024 -56.026304)
			(xy 370.798957 -56.008663) (xy 370.844925 -55.978939) (xy 370.894671 -55.956093) (xy 370.947173 -55.940597)
			(xy 371.001351 -55.932768) (xy 371.056093 -55.932768) (xy 371.110271 -55.940597) (xy 371.162773 -55.956093)
			(xy 371.212519 -55.978939) (xy 371.258487 -56.008663) (xy 371.27942 -56.026304) (xy 371.279674 -56.026558)
			(xy 371.286759 -56.032147) (xy 371.303677 -56.038391) (xy 371.312694 -56.03875) (xy 371.37975 -56.03875)
			(xy 371.388766 -56.03838) (xy 371.405683 -56.032143) (xy 371.41277 -56.026558) (xy 371.41277 -56.026304)
			(xy 371.413024 -56.026304) (xy 371.433974 -56.008688) (xy 371.479942 -55.978972) (xy 371.529685 -55.956132)
			(xy 371.582182 -55.940635) (xy 371.636354 -55.932801) (xy 371.663722 -55.932324) (xy 371.690975 -55.932747)
			(xy 371.744924 -55.940507) (xy 371.797221 -55.955865) (xy 371.846799 -55.97851) (xy 371.892651 -56.007979)
			(xy 371.933842 -56.043674) (xy 371.969534 -56.084867) (xy 371.999001 -56.13072) (xy 372.021642 -56.1803)
			(xy 372.036998 -56.232597) (xy 372.044754 -56.286547) (xy 372.044754 -56.297068) (xy 372.386604 -56.297068)
			(xy 372.390675 -56.241446) (xy 372.402801 -56.187009) (xy 372.422724 -56.134918) (xy 372.45002 -56.086283)
			(xy 372.484106 -56.04214) (xy 372.524255 -56.003431) (xy 372.569613 -55.97098) (xy 372.619213 -55.945479)
			(xy 372.671997 -55.927472) (xy 372.72684 -55.917342) (xy 372.782574 -55.915305) (xy 372.838011 -55.921405)
			(xy 372.891968 -55.935511) (xy 372.943297 -55.957323) (xy 372.990903 -55.986377) (xy 373.033771 -56.022052)
			(xy 373.070988 -56.063589) (xy 373.101761 -56.110102) (xy 373.125433 -56.160599) (xy 373.141501 -56.214006)
			(xy 373.149621 -56.269182) (xy 373.15013 -56.297068) (xy 373.149621 -56.324954) (xy 373.141501 -56.38013)
			(xy 373.125433 -56.433537) (xy 373.101761 -56.484034) (xy 373.070988 -56.530547) (xy 373.033771 -56.572084)
			(xy 372.990903 -56.607759) (xy 372.943297 -56.636813) (xy 372.891968 -56.658625) (xy 372.838011 -56.672731)
			(xy 372.782574 -56.678831) (xy 372.72684 -56.676794) (xy 372.671997 -56.666664) (xy 372.619213 -56.648657)
			(xy 372.569613 -56.623156) (xy 372.524255 -56.590705) (xy 372.484106 -56.551996) (xy 372.45002 -56.507853)
			(xy 372.422724 -56.459218) (xy 372.402801 -56.407127) (xy 372.390675 -56.35269) (xy 372.386604 -56.297068)
			(xy 372.044754 -56.297068) (xy 372.044754 -56.341053) (xy 372.036998 -56.395003) (xy 372.021642 -56.4473)
			(xy 371.999001 -56.49688) (xy 371.969534 -56.542733) (xy 371.933842 -56.583926) (xy 371.892651 -56.619621)
			(xy 371.846799 -56.64909) (xy 371.797221 -56.671735) (xy 371.744924 -56.687093) (xy 371.690975 -56.694853)
			(xy 371.663722 -56.69534) (xy 371.636352 -56.694876) (xy 371.582172 -56.68706) (xy 371.529668 -56.671571)
			(xy 371.479921 -56.648728) (xy 371.433955 -56.619002) (xy 371.413024 -56.60136) (xy 371.41277 -56.601106)
			(xy 371.405667 -56.595543) (xy 371.388763 -56.589282) (xy 371.37975 -56.588914) (xy 371.312694 -56.588914)
			(xy 371.303676 -56.589265) (xy 371.286759 -56.595516) (xy 371.279674 -56.601106) (xy 371.279674 -56.60136)
			(xy 371.27942 -56.60136) (xy 371.258487 -56.619001) (xy 371.212519 -56.648725) (xy 371.162773 -56.671571)
			(xy 371.110271 -56.687067) (xy 371.056093 -56.694896) (xy 371.001351 -56.694896) (xy 370.947173 -56.687067)
			(xy 370.894671 -56.671571) (xy 370.844925 -56.648725) (xy 370.798957 -56.619001) (xy 370.778024 -56.60136)
			(xy 370.77777 -56.601106) (xy 370.770667 -56.595543) (xy 370.753763 -56.589282) (xy 370.74475 -56.588914)
			(xy 370.677694 -56.588914) (xy 370.668676 -56.589265) (xy 370.651759 -56.595516) (xy 370.644674 -56.601106)
			(xy 370.644166 -56.60136) (xy 370.631431 -56.612304) (xy 370.60434 -56.632145) (xy 370.590064 -56.640984)
			(xy 370.581174 -56.646318) (xy 370.568982 -56.663336) (xy 370.548662 -56.756554) (xy 370.55298 -56.777128)
			(xy 370.558822 -56.785764) (xy 370.574811 -56.809834) (xy 370.600156 -56.861764) (xy 370.617384 -56.91692)
			(xy 370.626103 -56.974042) (xy 370.62664 -57.002934) (xy 370.626154 -57.030185) (xy 370.618398 -57.084133)
			(xy 370.603043 -57.136428) (xy 370.580401 -57.186005) (xy 370.550935 -57.231855) (xy 370.515244 -57.273046)
			(xy 370.474053 -57.308737) (xy 370.428203 -57.338203) (xy 370.378626 -57.360845) (xy 370.326331 -57.3762)
			(xy 370.272383 -57.383956) (xy 370.217881 -57.383956) (xy 370.163933 -57.3762) (xy 370.111638 -57.360845)
			(xy 370.062061 -57.338203) (xy 370.016211 -57.308737) (xy 369.97502 -57.273046) (xy 369.939329 -57.231855)
			(xy 369.909863 -57.186005) (xy 369.887221 -57.136428) (xy 369.871866 -57.084133) (xy 369.86411 -57.030185)
			(xy 369.863624 -57.002934) (xy 342.619714 -57.002934) (xy 342.619517 -57.019434) (xy 342.610226 -57.115487)
			(xy 342.60155 -57.162954) (xy 342.538433 -57.48528) (xy 352.906074 -57.48528) (xy 352.910145 -57.429658)
			(xy 352.922271 -57.375221) (xy 352.942194 -57.32313) (xy 352.96949 -57.274495) (xy 353.003576 -57.230352)
			(xy 353.043725 -57.191643) (xy 353.089083 -57.159192) (xy 353.138683 -57.133691) (xy 353.191467 -57.115684)
			(xy 353.24631 -57.105554) (xy 353.302044 -57.103517) (xy 353.357481 -57.109617) (xy 353.411438 -57.123723)
			(xy 353.462767 -57.145535) (xy 353.510373 -57.174589) (xy 353.553241 -57.210264) (xy 353.590458 -57.251801)
			(xy 353.621231 -57.298314) (xy 353.644903 -57.348811) (xy 353.660971 -57.402218) (xy 353.669091 -57.457394)
			(xy 353.6696 -57.48528) (xy 378.906022 -57.48528) (xy 378.910093 -57.429658) (xy 378.922219 -57.375221)
			(xy 378.942142 -57.32313) (xy 378.969438 -57.274495) (xy 379.003524 -57.230352) (xy 379.043673 -57.191643)
			(xy 379.089031 -57.159192) (xy 379.138631 -57.133691) (xy 379.191415 -57.115684) (xy 379.246258 -57.105554)
			(xy 379.301992 -57.103517) (xy 379.357429 -57.109617) (xy 379.411386 -57.123723) (xy 379.462715 -57.145535)
			(xy 379.510321 -57.174589) (xy 379.553189 -57.210264) (xy 379.590406 -57.251801) (xy 379.621179 -57.298314)
			(xy 379.644851 -57.348811) (xy 379.660919 -57.402218) (xy 379.669039 -57.457394) (xy 379.669548 -57.48528)
			(xy 379.669039 -57.513166) (xy 379.660919 -57.568342) (xy 379.644851 -57.621749) (xy 379.621179 -57.672246)
			(xy 379.590406 -57.718759) (xy 379.553189 -57.760296) (xy 379.510321 -57.795971) (xy 379.462715 -57.825025)
			(xy 379.411386 -57.846837) (xy 379.357429 -57.860943) (xy 379.301992 -57.867043) (xy 379.246258 -57.865006)
			(xy 379.191415 -57.854876) (xy 379.138631 -57.836869) (xy 379.089031 -57.811368) (xy 379.043673 -57.778917)
			(xy 379.003524 -57.740208) (xy 378.969438 -57.696065) (xy 378.942142 -57.64743) (xy 378.922219 -57.595339)
			(xy 378.910093 -57.540902) (xy 378.906022 -57.48528) (xy 353.6696 -57.48528) (xy 353.669091 -57.513166)
			(xy 353.660971 -57.568342) (xy 353.644903 -57.621749) (xy 353.621231 -57.672246) (xy 353.590458 -57.718759)
			(xy 353.553241 -57.760296) (xy 353.510373 -57.795971) (xy 353.462767 -57.825025) (xy 353.411438 -57.846837)
			(xy 353.357481 -57.860943) (xy 353.302044 -57.867043) (xy 353.24631 -57.865006) (xy 353.191467 -57.854876)
			(xy 353.138683 -57.836869) (xy 353.089083 -57.811368) (xy 353.043725 -57.778917) (xy 353.003576 -57.740208)
			(xy 352.96949 -57.696065) (xy 352.942194 -57.64743) (xy 352.922271 -57.595339) (xy 352.910145 -57.540902)
			(xy 352.906074 -57.48528) (xy 342.538433 -57.48528) (xy 342.422743 -58.076084) (xy 353.658168 -58.076084)
			(xy 353.662239 -58.020462) (xy 353.674365 -57.966025) (xy 353.694288 -57.913934) (xy 353.721584 -57.865299)
			(xy 353.75567 -57.821156) (xy 353.795819 -57.782447) (xy 353.841177 -57.749996) (xy 353.890777 -57.724495)
			(xy 353.943561 -57.706488) (xy 353.998404 -57.696358) (xy 354.054138 -57.694321) (xy 354.109575 -57.700421)
			(xy 354.163532 -57.714527) (xy 354.214861 -57.736339) (xy 354.262467 -57.765393) (xy 354.305335 -57.801068)
			(xy 354.342552 -57.842605) (xy 354.358888 -57.867296) (xy 355.943152 -57.867296) (xy 355.947223 -57.811674)
			(xy 355.959349 -57.757237) (xy 355.979272 -57.705146) (xy 356.006568 -57.656511) (xy 356.040654 -57.612368)
			(xy 356.080803 -57.573659) (xy 356.126161 -57.541208) (xy 356.175761 -57.515707) (xy 356.228545 -57.4977)
			(xy 356.283388 -57.48757) (xy 356.339122 -57.485533) (xy 356.394559 -57.491633) (xy 356.448516 -57.505739)
			(xy 356.499845 -57.527551) (xy 356.547451 -57.556605) (xy 356.590319 -57.59228) (xy 356.627536 -57.633817)
			(xy 356.658309 -57.68033) (xy 356.681981 -57.730827) (xy 356.698049 -57.784234) (xy 356.706169 -57.83941)
			(xy 356.706678 -57.867296) (xy 356.706169 -57.895182) (xy 356.698049 -57.950358) (xy 356.681981 -58.003765)
			(xy 356.658309 -58.054262) (xy 356.627536 -58.100775) (xy 356.590319 -58.142312) (xy 356.547451 -58.177987)
			(xy 356.499845 -58.207041) (xy 356.448516 -58.228853) (xy 356.394559 -58.242959) (xy 356.339122 -58.249059)
			(xy 356.283388 -58.247022) (xy 356.228545 -58.236892) (xy 356.175761 -58.218885) (xy 356.126161 -58.193384)
			(xy 356.080803 -58.160933) (xy 356.040654 -58.122224) (xy 356.006568 -58.078081) (xy 355.979272 -58.029446)
			(xy 355.959349 -57.977355) (xy 355.947223 -57.922918) (xy 355.943152 -57.867296) (xy 354.358888 -57.867296)
			(xy 354.373325 -57.889118) (xy 354.396997 -57.939615) (xy 354.413065 -57.993022) (xy 354.421185 -58.048198)
			(xy 354.421694 -58.076084) (xy 354.421185 -58.10397) (xy 354.413065 -58.159146) (xy 354.396997 -58.212553)
			(xy 354.373325 -58.26305) (xy 354.342552 -58.309563) (xy 354.305335 -58.3511) (xy 354.262467 -58.386775)
			(xy 354.214861 -58.415829) (xy 354.163532 -58.437641) (xy 354.109575 -58.451747) (xy 354.054138 -58.457847)
			(xy 353.998404 -58.45581) (xy 353.943561 -58.44568) (xy 353.890777 -58.427673) (xy 353.841177 -58.402172)
			(xy 353.795819 -58.369721) (xy 353.75567 -58.331012) (xy 353.721584 -58.286869) (xy 353.694288 -58.238234)
			(xy 353.674365 -58.186143) (xy 353.662239 -58.131706) (xy 353.658168 -58.076084) (xy 342.422743 -58.076084)
			(xy 342.327744 -58.561224) (xy 354.862382 -58.561224) (xy 354.866453 -58.505602) (xy 354.878579 -58.451165)
			(xy 354.898502 -58.399074) (xy 354.925798 -58.350439) (xy 354.959884 -58.306296) (xy 355.000033 -58.267587)
			(xy 355.045391 -58.235136) (xy 355.094991 -58.209635) (xy 355.147775 -58.191628) (xy 355.202618 -58.181498)
			(xy 355.258352 -58.179461) (xy 355.313789 -58.185561) (xy 355.367746 -58.199667) (xy 355.419075 -58.221479)
			(xy 355.466681 -58.250533) (xy 355.509549 -58.286208) (xy 355.546766 -58.327745) (xy 355.577539 -58.374258)
			(xy 355.601211 -58.424755) (xy 355.608721 -58.449718) (xy 357.109012 -58.449718) (xy 357.113083 -58.394096)
			(xy 357.125209 -58.339659) (xy 357.145132 -58.287568) (xy 357.172428 -58.238933) (xy 357.206514 -58.19479)
			(xy 357.246663 -58.156081) (xy 357.292021 -58.12363) (xy 357.341621 -58.098129) (xy 357.394405 -58.080122)
			(xy 357.449248 -58.069992) (xy 357.504982 -58.067955) (xy 357.560419 -58.074055) (xy 357.614376 -58.088161)
			(xy 357.665705 -58.109973) (xy 357.713311 -58.139027) (xy 357.756179 -58.174702) (xy 357.793396 -58.216239)
			(xy 357.824169 -58.262752) (xy 357.847841 -58.313249) (xy 357.863909 -58.366656) (xy 357.872029 -58.421832)
			(xy 357.872538 -58.449718) (xy 357.872029 -58.477604) (xy 357.863909 -58.53278) (xy 357.847841 -58.586187)
			(xy 357.824169 -58.636684) (xy 357.795952 -58.679334) (xy 370.295424 -58.679334) (xy 370.29584 -58.653018)
			(xy 370.303084 -58.600887) (xy 370.317413 -58.550243) (xy 370.338555 -58.502044) (xy 370.36611 -58.457202)
			(xy 370.399558 -58.416565) (xy 370.418614 -58.39841) (xy 370.426015 -58.390889) (xy 370.43454 -58.371608)
			(xy 370.435124 -58.361072) (xy 370.435124 -58.286396) (xy 370.434603 -58.275846) (xy 370.426061 -58.256551)
			(xy 370.418614 -58.249058) (xy 370.399548 -58.230913) (xy 370.366091 -58.190281) (xy 370.338533 -58.145439)
			(xy 370.317396 -58.097236) (xy 370.303082 -58.046587) (xy 370.29586 -57.994451) (xy 370.295424 -57.968134)
			(xy 370.29591 -57.940883) (xy 370.303666 -57.886935) (xy 370.319021 -57.83464) (xy 370.341663 -57.785063)
			(xy 370.371129 -57.739213) (xy 370.40682 -57.698022) (xy 370.448011 -57.662331) (xy 370.493861 -57.632865)
			(xy 370.543438 -57.610223) (xy 370.595733 -57.594868) (xy 370.649681 -57.587112) (xy 370.704183 -57.587112)
			(xy 370.758131 -57.594868) (xy 370.810426 -57.610223) (xy 370.860003 -57.632865) (xy 370.905853 -57.662331)
			(xy 370.947044 -57.698022) (xy 370.982735 -57.739213) (xy 371.012201 -57.785063) (xy 371.034843 -57.83464)
			(xy 371.050198 -57.886935) (xy 371.057954 -57.940883) (xy 371.05844 -57.968134) (xy 371.058014 -57.99445)
			(xy 371.050774 -58.046581) (xy 371.043506 -58.072274) (xy 374.293636 -58.072274) (xy 374.297707 -58.016652)
			(xy 374.309833 -57.962215) (xy 374.329756 -57.910124) (xy 374.357052 -57.861489) (xy 374.391138 -57.817346)
			(xy 374.431287 -57.778637) (xy 374.476645 -57.746186) (xy 374.526245 -57.720685) (xy 374.579029 -57.702678)
			(xy 374.633872 -57.692548) (xy 374.689606 -57.690511) (xy 374.745043 -57.696611) (xy 374.799 -57.710717)
			(xy 374.850329 -57.732529) (xy 374.897935 -57.761583) (xy 374.940803 -57.797258) (xy 374.97802 -57.838795)
			(xy 375.008793 -57.885308) (xy 375.032465 -57.935805) (xy 375.048533 -57.989212) (xy 375.056653 -58.044388)
			(xy 375.057162 -58.072274) (xy 375.057092 -58.076084) (xy 379.658116 -58.076084) (xy 379.662187 -58.020462)
			(xy 379.674313 -57.966025) (xy 379.694236 -57.913934) (xy 379.721532 -57.865299) (xy 379.755618 -57.821156)
			(xy 379.795767 -57.782447) (xy 379.841125 -57.749996) (xy 379.890725 -57.724495) (xy 379.943509 -57.706488)
			(xy 379.998352 -57.696358) (xy 380.054086 -57.694321) (xy 380.109523 -57.700421) (xy 380.16348 -57.714527)
			(xy 380.214809 -57.736339) (xy 380.262415 -57.765393) (xy 380.305283 -57.801068) (xy 380.3425 -57.842605)
			(xy 380.358836 -57.867296) (xy 381.9431 -57.867296) (xy 381.947171 -57.811674) (xy 381.959297 -57.757237)
			(xy 381.97922 -57.705146) (xy 382.006516 -57.656511) (xy 382.040602 -57.612368) (xy 382.080751 -57.573659)
			(xy 382.126109 -57.541208) (xy 382.175709 -57.515707) (xy 382.228493 -57.4977) (xy 382.283336 -57.48757)
			(xy 382.33907 -57.485533) (xy 382.394507 -57.491633) (xy 382.448464 -57.505739) (xy 382.499793 -57.527551)
			(xy 382.547399 -57.556605) (xy 382.590267 -57.59228) (xy 382.627484 -57.633817) (xy 382.658257 -57.68033)
			(xy 382.681929 -57.730827) (xy 382.697997 -57.784234) (xy 382.706117 -57.83941) (xy 382.706626 -57.867296)
			(xy 382.706117 -57.895182) (xy 382.697997 -57.950358) (xy 382.681929 -58.003765) (xy 382.658257 -58.054262)
			(xy 382.627484 -58.100775) (xy 382.590267 -58.142312) (xy 382.547399 -58.177987) (xy 382.499793 -58.207041)
			(xy 382.448464 -58.228853) (xy 382.394507 -58.242959) (xy 382.33907 -58.249059) (xy 382.283336 -58.247022)
			(xy 382.228493 -58.236892) (xy 382.175709 -58.218885) (xy 382.126109 -58.193384) (xy 382.080751 -58.160933)
			(xy 382.040602 -58.122224) (xy 382.006516 -58.078081) (xy 381.97922 -58.029446) (xy 381.959297 -57.977355)
			(xy 381.947171 -57.922918) (xy 381.9431 -57.867296) (xy 380.358836 -57.867296) (xy 380.373273 -57.889118)
			(xy 380.396945 -57.939615) (xy 380.413013 -57.993022) (xy 380.421133 -58.048198) (xy 380.421642 -58.076084)
			(xy 380.421133 -58.10397) (xy 380.413013 -58.159146) (xy 380.396945 -58.212553) (xy 380.373273 -58.26305)
			(xy 380.3425 -58.309563) (xy 380.305283 -58.3511) (xy 380.262415 -58.386775) (xy 380.214809 -58.415829)
			(xy 380.16348 -58.437641) (xy 380.109523 -58.451747) (xy 380.054086 -58.457847) (xy 379.998352 -58.45581)
			(xy 379.943509 -58.44568) (xy 379.890725 -58.427673) (xy 379.841125 -58.402172) (xy 379.795767 -58.369721)
			(xy 379.755618 -58.331012) (xy 379.721532 -58.286869) (xy 379.694236 -58.238234) (xy 379.674313 -58.186143)
			(xy 379.662187 -58.131706) (xy 379.658116 -58.076084) (xy 375.057092 -58.076084) (xy 375.056653 -58.10016)
			(xy 375.048533 -58.155336) (xy 375.032465 -58.208743) (xy 375.008793 -58.25924) (xy 374.97802 -58.305753)
			(xy 374.940803 -58.34729) (xy 374.897935 -58.382965) (xy 374.850329 -58.412019) (xy 374.799 -58.433831)
			(xy 374.745043 -58.447937) (xy 374.689606 -58.454037) (xy 374.633872 -58.452) (xy 374.579029 -58.44187)
			(xy 374.526245 -58.423863) (xy 374.476645 -58.398362) (xy 374.431287 -58.365911) (xy 374.391138 -58.327202)
			(xy 374.357052 -58.283059) (xy 374.329756 -58.234424) (xy 374.309833 -58.182333) (xy 374.297707 -58.127896)
			(xy 374.293636 -58.072274) (xy 371.043506 -58.072274) (xy 371.036448 -58.097225) (xy 371.015308 -58.145424)
			(xy 370.987753 -58.190267) (xy 370.954306 -58.230903) (xy 370.93525 -58.249058) (xy 370.927872 -58.2566)
			(xy 370.919333 -58.275864) (xy 370.91874 -58.286396) (xy 370.91874 -58.361072) (xy 370.919259 -58.371623)
			(xy 370.9278 -58.390919) (xy 370.93525 -58.39841) (xy 370.954313 -58.416558) (xy 370.987767 -58.45719)
			(xy 371.015324 -58.502033) (xy 371.036461 -58.550235) (xy 371.039567 -58.561224) (xy 380.86233 -58.561224)
			(xy 380.866401 -58.505602) (xy 380.878527 -58.451165) (xy 380.89845 -58.399074) (xy 380.925746 -58.350439)
			(xy 380.959832 -58.306296) (xy 380.999981 -58.267587) (xy 381.045339 -58.235136) (xy 381.094939 -58.209635)
			(xy 381.147723 -58.191628) (xy 381.202566 -58.181498) (xy 381.2583 -58.179461) (xy 381.313737 -58.185561)
			(xy 381.367694 -58.199667) (xy 381.419023 -58.221479) (xy 381.466629 -58.250533) (xy 381.509497 -58.286208)
			(xy 381.546714 -58.327745) (xy 381.577487 -58.374258) (xy 381.601159 -58.424755) (xy 381.617227 -58.478162)
			(xy 381.625347 -58.533338) (xy 381.625856 -58.561224) (xy 381.625347 -58.58911) (xy 381.617227 -58.644286)
			(xy 381.601159 -58.697693) (xy 381.577487 -58.74819) (xy 381.546714 -58.794703) (xy 381.509497 -58.83624)
			(xy 381.466629 -58.871915) (xy 381.419023 -58.900969) (xy 381.367694 -58.922781) (xy 381.313737 -58.936887)
			(xy 381.2583 -58.942987) (xy 381.202566 -58.94095) (xy 381.147723 -58.93082) (xy 381.094939 -58.912813)
			(xy 381.045339 -58.887312) (xy 380.999981 -58.854861) (xy 380.959832 -58.816152) (xy 380.925746 -58.772009)
			(xy 380.89845 -58.723374) (xy 380.878527 -58.671283) (xy 380.866401 -58.616846) (xy 380.86233 -58.561224)
			(xy 371.039567 -58.561224) (xy 371.050777 -58.600883) (xy 371.058002 -58.653018) (xy 371.05844 -58.679334)
			(xy 371.057954 -58.706585) (xy 371.050198 -58.760533) (xy 371.034843 -58.812828) (xy 371.012201 -58.862405)
			(xy 370.982735 -58.908255) (xy 370.947044 -58.949446) (xy 370.905853 -58.985137) (xy 370.860003 -59.014603)
			(xy 370.810426 -59.037245) (xy 370.758131 -59.0526) (xy 370.704183 -59.060356) (xy 370.649681 -59.060356)
			(xy 370.595733 -59.0526) (xy 370.543438 -59.037245) (xy 370.493861 -59.014603) (xy 370.448011 -58.985137)
			(xy 370.40682 -58.949446) (xy 370.371129 -58.908255) (xy 370.341663 -58.862405) (xy 370.319021 -58.812828)
			(xy 370.303666 -58.760533) (xy 370.29591 -58.706585) (xy 370.295424 -58.679334) (xy 357.795952 -58.679334)
			(xy 357.793396 -58.683197) (xy 357.756179 -58.724734) (xy 357.713311 -58.760409) (xy 357.665705 -58.789463)
			(xy 357.614376 -58.811275) (xy 357.560419 -58.825381) (xy 357.504982 -58.831481) (xy 357.449248 -58.829444)
			(xy 357.394405 -58.819314) (xy 357.341621 -58.801307) (xy 357.292021 -58.775806) (xy 357.246663 -58.743355)
			(xy 357.206514 -58.704646) (xy 357.172428 -58.660503) (xy 357.145132 -58.611868) (xy 357.125209 -58.559777)
			(xy 357.113083 -58.50534) (xy 357.109012 -58.449718) (xy 355.608721 -58.449718) (xy 355.617279 -58.478162)
			(xy 355.625399 -58.533338) (xy 355.625908 -58.561224) (xy 355.625399 -58.58911) (xy 355.617279 -58.644286)
			(xy 355.601211 -58.697693) (xy 355.577539 -58.74819) (xy 355.546766 -58.794703) (xy 355.509549 -58.83624)
			(xy 355.466681 -58.871915) (xy 355.419075 -58.900969) (xy 355.367746 -58.922781) (xy 355.313789 -58.936887)
			(xy 355.258352 -58.942987) (xy 355.202618 -58.94095) (xy 355.147775 -58.93082) (xy 355.094991 -58.912813)
			(xy 355.045391 -58.887312) (xy 355.000033 -58.854861) (xy 354.959884 -58.816152) (xy 354.925798 -58.772009)
			(xy 354.898502 -58.723374) (xy 354.878579 -58.671283) (xy 354.866453 -58.616846) (xy 354.862382 -58.561224)
			(xy 342.327744 -58.561224) (xy 342.207627 -59.174634) (xy 353.393246 -59.174634) (xy 353.397317 -59.119012)
			(xy 353.409443 -59.064575) (xy 353.429366 -59.012484) (xy 353.456662 -58.963849) (xy 353.490748 -58.919706)
			(xy 353.530897 -58.880997) (xy 353.576255 -58.848546) (xy 353.625855 -58.823045) (xy 353.678639 -58.805038)
			(xy 353.733482 -58.794908) (xy 353.789216 -58.792871) (xy 353.844653 -58.798971) (xy 353.89861 -58.813077)
			(xy 353.949939 -58.834889) (xy 353.997545 -58.863943) (xy 354.040413 -58.899618) (xy 354.07763 -58.941155)
			(xy 354.108403 -58.987668) (xy 354.132075 -59.038165) (xy 354.148143 -59.091572) (xy 354.156263 -59.146748)
			(xy 354.156772 -59.174634) (xy 379.393194 -59.174634) (xy 379.397265 -59.119012) (xy 379.409391 -59.064575)
			(xy 379.429314 -59.012484) (xy 379.45661 -58.963849) (xy 379.490696 -58.919706) (xy 379.530845 -58.880997)
			(xy 379.576203 -58.848546) (xy 379.625803 -58.823045) (xy 379.678587 -58.805038) (xy 379.73343 -58.794908)
			(xy 379.789164 -58.792871) (xy 379.844601 -58.798971) (xy 379.898558 -58.813077) (xy 379.949887 -58.834889)
			(xy 379.997493 -58.863943) (xy 380.040361 -58.899618) (xy 380.077578 -58.941155) (xy 380.108351 -58.987668)
			(xy 380.132023 -59.038165) (xy 380.148091 -59.091572) (xy 380.156211 -59.146748) (xy 380.15672 -59.174634)
			(xy 380.156211 -59.20252) (xy 380.148091 -59.257696) (xy 380.132023 -59.311103) (xy 380.108351 -59.3616)
			(xy 380.077578 -59.408113) (xy 380.040361 -59.44965) (xy 379.997493 -59.485325) (xy 379.949887 -59.514379)
			(xy 379.898558 -59.536191) (xy 379.844601 -59.550297) (xy 379.789164 -59.556397) (xy 379.73343 -59.55436)
			(xy 379.678587 -59.54423) (xy 379.625803 -59.526223) (xy 379.576203 -59.500722) (xy 379.530845 -59.468271)
			(xy 379.490696 -59.429562) (xy 379.45661 -59.385419) (xy 379.429314 -59.336784) (xy 379.409391 -59.284693)
			(xy 379.397265 -59.230256) (xy 379.393194 -59.174634) (xy 354.156772 -59.174634) (xy 354.156263 -59.20252)
			(xy 354.148143 -59.257696) (xy 354.132075 -59.311103) (xy 354.108403 -59.3616) (xy 354.07763 -59.408113)
			(xy 354.040413 -59.44965) (xy 353.997545 -59.485325) (xy 353.949939 -59.514379) (xy 353.89861 -59.536191)
			(xy 353.844653 -59.550297) (xy 353.789216 -59.556397) (xy 353.733482 -59.55436) (xy 353.678639 -59.54423)
			(xy 353.625855 -59.526223) (xy 353.576255 -59.500722) (xy 353.530897 -59.468271) (xy 353.490748 -59.429562)
			(xy 353.456662 -59.385419) (xy 353.429366 -59.336784) (xy 353.409443 -59.284693) (xy 353.397317 -59.230256)
			(xy 353.393246 -59.174634) (xy 342.207627 -59.174634) (xy 342.042236 -60.01925) (xy 370.435884 -60.01925)
			(xy 370.435884 -59.96475) (xy 370.44364 -59.910804) (xy 370.458994 -59.858511) (xy 370.481634 -59.808936)
			(xy 370.511098 -59.763087) (xy 370.546788 -59.721898) (xy 370.587976 -59.686207) (xy 370.633824 -59.65674)
			(xy 370.683398 -59.634099) (xy 370.73569 -59.618743) (xy 370.789636 -59.610985) (xy 370.816886 -59.610498)
			(xy 370.844256 -59.610973) (xy 370.898435 -59.618789) (xy 370.950938 -59.634276) (xy 371.000685 -59.657115)
			(xy 371.046652 -59.686838) (xy 371.067584 -59.704478) (xy 371.067838 -59.704732) (xy 371.074936 -59.710302)
			(xy 371.091844 -59.716558) (xy 371.100858 -59.716924) (xy 371.167914 -59.716924) (xy 371.176931 -59.716568)
			(xy 371.193847 -59.710319) (xy 371.200934 -59.704732) (xy 371.200934 -59.704478) (xy 371.201188 -59.704478)
			(xy 371.222121 -59.686837) (xy 371.268089 -59.657113) (xy 371.317835 -59.634267) (xy 371.370337 -59.618771)
			(xy 371.424515 -59.610942) (xy 371.479257 -59.610942) (xy 371.533435 -59.618771) (xy 371.585937 -59.634267)
			(xy 371.635683 -59.657113) (xy 371.681651 -59.686837) (xy 371.702584 -59.704478) (xy 371.702838 -59.704732)
			(xy 371.709936 -59.710302) (xy 371.726844 -59.716558) (xy 371.735858 -59.716924) (xy 371.802914 -59.716924)
			(xy 371.811931 -59.716568) (xy 371.828847 -59.710319) (xy 371.835934 -59.704732) (xy 371.835934 -59.704478)
			(xy 371.836188 -59.704478) (xy 371.857111 -59.686828) (xy 371.903087 -59.657118) (xy 371.952836 -59.634285)
			(xy 372.005339 -59.618796) (xy 372.059516 -59.610971) (xy 372.086886 -59.610498) (xy 372.11414 -59.610948)
			(xy 372.168093 -59.618704) (xy 372.220394 -59.634059) (xy 372.269976 -59.656701) (xy 372.315832 -59.686169)
			(xy 372.357027 -59.721863) (xy 372.392723 -59.763057) (xy 372.422192 -59.808911) (xy 372.444836 -59.858493)
			(xy 372.460193 -59.910793) (xy 372.467951 -59.964746) (xy 372.467951 -60.019254) (xy 372.460193 -60.073207)
			(xy 372.444836 -60.125507) (xy 372.422192 -60.175089) (xy 372.392723 -60.220943) (xy 372.357027 -60.262137)
			(xy 372.315832 -60.297831) (xy 372.269976 -60.327299) (xy 372.220394 -60.349941) (xy 372.168093 -60.365296)
			(xy 372.11414 -60.373052) (xy 372.086886 -60.373514) (xy 372.059516 -60.373053) (xy 372.005336 -60.365233)
			(xy 371.952833 -60.349743) (xy 371.903087 -60.3269) (xy 371.85712 -60.297175) (xy 371.836188 -60.279534)
			(xy 371.835934 -60.27928) (xy 371.828844 -60.273699) (xy 371.81193 -60.26745) (xy 371.802914 -60.267088)
			(xy 371.735858 -60.267088) (xy 371.726844 -60.267476) (xy 371.709927 -60.273702) (xy 371.702838 -60.27928)
			(xy 371.702584 -60.279534) (xy 371.681651 -60.297175) (xy 371.635683 -60.326899) (xy 371.585937 -60.349745)
			(xy 371.533435 -60.365241) (xy 371.479257 -60.37307) (xy 371.424515 -60.37307) (xy 371.370337 -60.365241)
			(xy 371.317835 -60.349745) (xy 371.268089 -60.326899) (xy 371.222121 -60.297175) (xy 371.201188 -60.279534)
			(xy 371.200934 -60.27928) (xy 371.193844 -60.273699) (xy 371.17693 -60.26745) (xy 371.167914 -60.267088)
			(xy 371.100858 -60.267088) (xy 371.091844 -60.267476) (xy 371.074927 -60.273702) (xy 371.067838 -60.27928)
			(xy 371.067838 -60.279534) (xy 371.067584 -60.279534) (xy 371.046635 -60.297152) (xy 371.000667 -60.326866)
			(xy 370.950923 -60.349706) (xy 370.898426 -60.365202) (xy 370.844254 -60.373036) (xy 370.816886 -60.373514)
			(xy 370.789636 -60.373015) (xy 370.73569 -60.365257) (xy 370.683398 -60.349901) (xy 370.633824 -60.32726)
			(xy 370.587976 -60.297793) (xy 370.546788 -60.262102) (xy 370.511098 -60.220913) (xy 370.481634 -60.175064)
			(xy 370.458994 -60.125489) (xy 370.44364 -60.073196) (xy 370.435884 -60.01925) (xy 342.042236 -60.01925)
			(xy 341.921983 -60.633356) (xy 356.097076 -60.633356) (xy 356.101147 -60.577734) (xy 356.113273 -60.523297)
			(xy 356.133196 -60.471206) (xy 356.160492 -60.422571) (xy 356.194578 -60.378428) (xy 356.234727 -60.339719)
			(xy 356.280085 -60.307268) (xy 356.329685 -60.281767) (xy 356.382469 -60.26376) (xy 356.437312 -60.25363)
			(xy 356.493046 -60.251593) (xy 356.548483 -60.257693) (xy 356.60244 -60.271799) (xy 356.653769 -60.293611)
			(xy 356.701375 -60.322665) (xy 356.744243 -60.35834) (xy 356.78146 -60.399877) (xy 356.812233 -60.44639)
			(xy 356.835905 -60.496887) (xy 356.851973 -60.550294) (xy 356.860093 -60.60547) (xy 356.860602 -60.633356)
			(xy 382.097024 -60.633356) (xy 382.101095 -60.577734) (xy 382.113221 -60.523297) (xy 382.133144 -60.471206)
			(xy 382.16044 -60.422571) (xy 382.194526 -60.378428) (xy 382.234675 -60.339719) (xy 382.280033 -60.307268)
			(xy 382.329633 -60.281767) (xy 382.382417 -60.26376) (xy 382.43726 -60.25363) (xy 382.492994 -60.251593)
			(xy 382.548431 -60.257693) (xy 382.602388 -60.271799) (xy 382.653717 -60.293611) (xy 382.701323 -60.322665)
			(xy 382.744191 -60.35834) (xy 382.781408 -60.399877) (xy 382.812181 -60.44639) (xy 382.835853 -60.496887)
			(xy 382.851921 -60.550294) (xy 382.860041 -60.60547) (xy 382.86055 -60.633356) (xy 382.860041 -60.661242)
			(xy 382.851921 -60.716418) (xy 382.835853 -60.769825) (xy 382.812181 -60.820322) (xy 382.781408 -60.866835)
			(xy 382.744191 -60.908372) (xy 382.701323 -60.944047) (xy 382.653717 -60.973101) (xy 382.602388 -60.994913)
			(xy 382.548431 -61.009019) (xy 382.492994 -61.015119) (xy 382.43726 -61.013082) (xy 382.382417 -61.002952)
			(xy 382.329633 -60.984945) (xy 382.280033 -60.959444) (xy 382.234675 -60.926993) (xy 382.194526 -60.888284)
			(xy 382.16044 -60.844141) (xy 382.133144 -60.795506) (xy 382.113221 -60.743415) (xy 382.101095 -60.688978)
			(xy 382.097024 -60.633356) (xy 356.860602 -60.633356) (xy 356.860093 -60.661242) (xy 356.851973 -60.716418)
			(xy 356.835905 -60.769825) (xy 356.812233 -60.820322) (xy 356.78146 -60.866835) (xy 356.744243 -60.908372)
			(xy 356.701375 -60.944047) (xy 356.653769 -60.973101) (xy 356.60244 -60.994913) (xy 356.548483 -61.009019)
			(xy 356.493046 -61.015119) (xy 356.437312 -61.013082) (xy 356.382469 -61.002952) (xy 356.329685 -60.984945)
			(xy 356.280085 -60.959444) (xy 356.234727 -60.926993) (xy 356.194578 -60.888284) (xy 356.160492 -60.844141)
			(xy 356.133196 -60.795506) (xy 356.113273 -60.743415) (xy 356.101147 -60.688978) (xy 356.097076 -60.633356)
			(xy 341.921983 -60.633356) (xy 341.754665 -61.487812) (xy 354.604572 -61.487812) (xy 354.608643 -61.43219)
			(xy 354.620769 -61.377753) (xy 354.640692 -61.325662) (xy 354.667988 -61.277027) (xy 354.702074 -61.232884)
			(xy 354.742223 -61.194175) (xy 354.787581 -61.161724) (xy 354.837181 -61.136223) (xy 354.889965 -61.118216)
			(xy 354.944808 -61.108086) (xy 355.000542 -61.106049) (xy 355.055979 -61.112149) (xy 355.109936 -61.126255)
			(xy 355.161265 -61.148067) (xy 355.208871 -61.177121) (xy 355.251739 -61.212796) (xy 355.288956 -61.254333)
			(xy 355.319729 -61.300846) (xy 355.343401 -61.351343) (xy 355.359469 -61.40475) (xy 355.367589 -61.459926)
			(xy 355.368098 -61.487812) (xy 380.60452 -61.487812) (xy 380.608591 -61.43219) (xy 380.620717 -61.377753)
			(xy 380.64064 -61.325662) (xy 380.667936 -61.277027) (xy 380.702022 -61.232884) (xy 380.742171 -61.194175)
			(xy 380.787529 -61.161724) (xy 380.837129 -61.136223) (xy 380.889913 -61.118216) (xy 380.944756 -61.108086)
			(xy 381.00049 -61.106049) (xy 381.055927 -61.112149) (xy 381.109884 -61.126255) (xy 381.161213 -61.148067)
			(xy 381.208819 -61.177121) (xy 381.251687 -61.212796) (xy 381.288904 -61.254333) (xy 381.319677 -61.300846)
			(xy 381.343349 -61.351343) (xy 381.359417 -61.40475) (xy 381.367537 -61.459926) (xy 381.368046 -61.487812)
			(xy 381.367537 -61.515698) (xy 381.359417 -61.570874) (xy 381.343349 -61.624281) (xy 381.319677 -61.674778)
			(xy 381.288904 -61.721291) (xy 381.251687 -61.762828) (xy 381.208819 -61.798503) (xy 381.161213 -61.827557)
			(xy 381.109884 -61.849369) (xy 381.055927 -61.863475) (xy 381.00049 -61.869575) (xy 380.944756 -61.867538)
			(xy 380.889913 -61.857408) (xy 380.837129 -61.839401) (xy 380.787529 -61.8139) (xy 380.742171 -61.781449)
			(xy 380.702022 -61.74274) (xy 380.667936 -61.698597) (xy 380.64064 -61.649962) (xy 380.620717 -61.597871)
			(xy 380.608591 -61.543434) (xy 380.60452 -61.487812) (xy 355.368098 -61.487812) (xy 355.367589 -61.515698)
			(xy 355.359469 -61.570874) (xy 355.343401 -61.624281) (xy 355.319729 -61.674778) (xy 355.288956 -61.721291)
			(xy 355.251739 -61.762828) (xy 355.208871 -61.798503) (xy 355.161265 -61.827557) (xy 355.109936 -61.849369)
			(xy 355.055979 -61.863475) (xy 355.000542 -61.869575) (xy 354.944808 -61.867538) (xy 354.889965 -61.857408)
			(xy 354.837181 -61.839401) (xy 354.787581 -61.8139) (xy 354.742223 -61.781449) (xy 354.702074 -61.74274)
			(xy 354.667988 -61.698597) (xy 354.640692 -61.649962) (xy 354.620769 -61.597871) (xy 354.608643 -61.543434)
			(xy 354.604572 -61.487812) (xy 341.754665 -61.487812) (xy 341.630669 -62.121034) (xy 352.542346 -62.121034)
			(xy 352.546417 -62.065412) (xy 352.558543 -62.010975) (xy 352.578466 -61.958884) (xy 352.605762 -61.910249)
			(xy 352.639848 -61.866106) (xy 352.679997 -61.827397) (xy 352.725355 -61.794946) (xy 352.774955 -61.769445)
			(xy 352.827739 -61.751438) (xy 352.882582 -61.741308) (xy 352.938316 -61.739271) (xy 352.993753 -61.745371)
			(xy 353.04771 -61.759477) (xy 353.099039 -61.781289) (xy 353.146645 -61.810343) (xy 353.189513 -61.846018)
			(xy 353.22673 -61.887555) (xy 353.257503 -61.934068) (xy 353.281175 -61.984565) (xy 353.297243 -62.037972)
			(xy 353.305363 -62.093148) (xy 353.305872 -62.121034) (xy 353.305363 -62.14892) (xy 353.297243 -62.204096)
			(xy 353.281175 -62.257503) (xy 353.257503 -62.308) (xy 353.22673 -62.354513) (xy 353.189513 -62.39605)
			(xy 353.146645 -62.431725) (xy 353.099039 -62.460779) (xy 353.04771 -62.482591) (xy 352.993753 -62.496697)
			(xy 352.938316 -62.502797) (xy 352.882582 -62.50076) (xy 352.827739 -62.49063) (xy 352.774955 -62.472623)
			(xy 352.725355 -62.447122) (xy 352.679997 -62.414671) (xy 352.639848 -62.375962) (xy 352.605762 -62.331819)
			(xy 352.578466 -62.283184) (xy 352.558543 -62.231093) (xy 352.546417 -62.176656) (xy 352.542346 -62.121034)
			(xy 341.630669 -62.121034) (xy 341.521454 -62.678772) (xy 355.966272 -62.678772) (xy 355.974025 -62.624824)
			(xy 355.989377 -62.572528) (xy 356.012015 -62.52295) (xy 356.041478 -62.477097) (xy 356.077166 -62.435905)
			(xy 356.118354 -62.400211) (xy 356.164202 -62.370741) (xy 356.213777 -62.348096) (xy 356.26607 -62.332737)
			(xy 356.320017 -62.324976) (xy 356.347268 -62.324488) (xy 356.370823 -62.324856) (xy 356.417567 -62.330721)
			(xy 356.440486 -62.336172) (xy 356.454255 -62.339149) (xy 356.4824 -62.338306) (xy 356.509246 -62.329811)
			(xy 356.532752 -62.31431) (xy 356.551133 -62.292979) (xy 356.562992 -62.26744) (xy 356.567427 -62.239634)
			(xy 356.564103 -62.211673) (xy 356.559104 -62.198504) (xy 356.549791 -62.175116) (xy 356.536667 -62.126514)
			(xy 356.530045 -62.076609) (xy 356.52964 -62.051438) (xy 356.530037 -62.024184) (xy 356.537789 -61.970231)
			(xy 356.55314 -61.917929) (xy 356.575778 -61.868345) (xy 356.605243 -61.822487) (xy 356.640933 -61.78129)
			(xy 356.682124 -61.74559) (xy 356.727975 -61.716117) (xy 356.777555 -61.693468) (xy 356.829853 -61.678106)
			(xy 356.883805 -61.670343) (xy 356.938313 -61.670337) (xy 356.992266 -61.678088) (xy 357.044568 -61.693439)
			(xy 357.094152 -61.716077) (xy 357.14001 -61.745541) (xy 357.181208 -61.781231) (xy 357.216908 -61.822421)
			(xy 357.246382 -61.868273) (xy 357.269031 -61.917852) (xy 357.284393 -61.97015) (xy 357.292157 -62.024102)
			(xy 357.292163 -62.078609) (xy 357.286068 -62.121034) (xy 378.542294 -62.121034) (xy 378.546365 -62.065412)
			(xy 378.558491 -62.010975) (xy 378.578414 -61.958884) (xy 378.60571 -61.910249) (xy 378.639796 -61.866106)
			(xy 378.679945 -61.827397) (xy 378.725303 -61.794946) (xy 378.774903 -61.769445) (xy 378.827687 -61.751438)
			(xy 378.88253 -61.741308) (xy 378.938264 -61.739271) (xy 378.993701 -61.745371) (xy 379.047658 -61.759477)
			(xy 379.098987 -61.781289) (xy 379.146593 -61.810343) (xy 379.189461 -61.846018) (xy 379.226678 -61.887555)
			(xy 379.257451 -61.934068) (xy 379.281123 -61.984565) (xy 379.297191 -62.037972) (xy 379.305311 -62.093148)
			(xy 379.30582 -62.121034) (xy 379.305311 -62.14892) (xy 379.297191 -62.204096) (xy 379.281123 -62.257503)
			(xy 379.257451 -62.308) (xy 379.226678 -62.354513) (xy 379.189461 -62.39605) (xy 379.146593 -62.431725)
			(xy 379.098987 -62.460779) (xy 379.047658 -62.482591) (xy 378.993701 -62.496697) (xy 378.938264 -62.502797)
			(xy 378.88253 -62.50076) (xy 378.827687 -62.49063) (xy 378.774903 -62.472623) (xy 378.725303 -62.447122)
			(xy 378.679945 -62.414671) (xy 378.639796 -62.375962) (xy 378.60571 -62.331819) (xy 378.578414 -62.283184)
			(xy 378.558491 -62.231093) (xy 378.546365 -62.176656) (xy 378.542294 -62.121034) (xy 357.286068 -62.121034)
			(xy 357.284412 -62.132563) (xy 357.269062 -62.184864) (xy 357.246425 -62.234449) (xy 357.216961 -62.280307)
			(xy 357.181271 -62.321506) (xy 357.140082 -62.357206) (xy 357.09423 -62.38668) (xy 357.044651 -62.40933)
			(xy 356.992354 -62.424693) (xy 356.938402 -62.432457) (xy 356.911148 -62.432946) (xy 356.887593 -62.432575)
			(xy 356.840849 -62.426712) (xy 356.81793 -62.421262) (xy 356.804165 -62.418255) (xy 356.776013 -62.419093)
			(xy 356.749159 -62.427588) (xy 356.725647 -62.443094) (xy 356.707262 -62.464431) (xy 356.695404 -62.489978)
			(xy 356.690974 -62.517792) (xy 356.694308 -62.545759) (xy 356.699312 -62.55893) (xy 356.708637 -62.582314)
			(xy 356.721756 -62.630918) (xy 356.728373 -62.680824) (xy 356.728776 -62.705996) (xy 356.728327 -62.733247)
			(xy 356.720571 -62.787195) (xy 356.705216 -62.839489) (xy 356.682576 -62.889067) (xy 356.653111 -62.934918)
			(xy 356.617421 -62.976108) (xy 356.576231 -63.011801) (xy 356.530382 -63.041268) (xy 356.480806 -63.06391)
			(xy 356.428512 -63.079267) (xy 356.374564 -63.087025) (xy 356.320062 -63.087027) (xy 356.266114 -63.079273)
			(xy 356.213819 -63.06392) (xy 356.164241 -63.041281) (xy 356.11839 -63.011817) (xy 356.077198 -62.976127)
			(xy 356.041505 -62.934939) (xy 356.012037 -62.88909) (xy 355.989393 -62.839514) (xy 355.974035 -62.787221)
			(xy 355.966275 -62.733274) (xy 355.966272 -62.678772) (xy 341.521454 -62.678772) (xy 341.441666 -63.086234)
			(xy 349.68764 -63.086234) (xy 349.691711 -63.030612) (xy 349.703837 -62.976175) (xy 349.72376 -62.924084)
			(xy 349.751056 -62.875449) (xy 349.785142 -62.831306) (xy 349.825291 -62.792597) (xy 349.870649 -62.760146)
			(xy 349.920249 -62.734645) (xy 349.973033 -62.716638) (xy 350.027876 -62.706508) (xy 350.08361 -62.704471)
			(xy 350.139047 -62.710571) (xy 350.193004 -62.724677) (xy 350.244333 -62.746489) (xy 350.291939 -62.775543)
			(xy 350.334807 -62.811218) (xy 350.372024 -62.852755) (xy 350.402797 -62.899268) (xy 350.426469 -62.949765)
			(xy 350.442537 -63.003172) (xy 350.450657 -63.058348) (xy 350.451166 -63.086234) (xy 350.450657 -63.11412)
			(xy 350.442537 -63.169296) (xy 350.426469 -63.222703) (xy 350.402797 -63.2732) (xy 350.402644 -63.273432)
			(xy 351.876866 -63.273432) (xy 351.880937 -63.21781) (xy 351.893063 -63.163373) (xy 351.912986 -63.111282)
			(xy 351.940282 -63.062647) (xy 351.974368 -63.018504) (xy 352.014517 -62.979795) (xy 352.059875 -62.947344)
			(xy 352.109475 -62.921843) (xy 352.162259 -62.903836) (xy 352.217102 -62.893706) (xy 352.272836 -62.891669)
			(xy 352.328273 -62.897769) (xy 352.38223 -62.911875) (xy 352.433559 -62.933687) (xy 352.481165 -62.962741)
			(xy 352.524033 -62.998416) (xy 352.56125 -63.039953) (xy 352.592023 -63.086466) (xy 352.615695 -63.136963)
			(xy 352.631763 -63.19037) (xy 352.635174 -63.21355) (xy 370.420888 -63.21355) (xy 370.420888 -63.15905)
			(xy 370.428645 -63.105103) (xy 370.443999 -63.05281) (xy 370.46664 -63.003234) (xy 370.496105 -62.957385)
			(xy 370.531796 -62.916196) (xy 370.572985 -62.880505) (xy 370.618834 -62.85104) (xy 370.66841 -62.828399)
			(xy 370.720703 -62.813045) (xy 370.77465 -62.805288) (xy 370.8019 -62.804802) (xy 370.82927 -62.805268)
			(xy 370.883449 -62.813085) (xy 370.935953 -62.828575) (xy 370.985699 -62.851416) (xy 371.031666 -62.881141)
			(xy 371.052598 -62.898782) (xy 371.052852 -62.899036) (xy 371.059945 -62.904613) (xy 371.076857 -62.910864)
			(xy 371.085872 -62.911228) (xy 371.152928 -62.911228) (xy 371.161946 -62.910878) (xy 371.178862 -62.904625)
			(xy 371.185948 -62.899036) (xy 371.185948 -62.898782) (xy 371.186202 -62.898782) (xy 371.207135 -62.881141)
			(xy 371.253103 -62.851417) (xy 371.302849 -62.828571) (xy 371.355351 -62.813075) (xy 371.409529 -62.805246)
			(xy 371.464271 -62.805246) (xy 371.518449 -62.813075) (xy 371.570951 -62.828571) (xy 371.620697 -62.851417)
			(xy 371.666665 -62.881141) (xy 371.687598 -62.898782) (xy 371.687852 -62.899036) (xy 371.694945 -62.904613)
			(xy 371.711857 -62.910864) (xy 371.720872 -62.911228) (xy 371.787928 -62.911228) (xy 371.796946 -62.910878)
			(xy 371.813862 -62.904625) (xy 371.820948 -62.899036) (xy 371.820948 -62.898782) (xy 371.821202 -62.898782)
			(xy 371.84212 -62.881126) (xy 371.888097 -62.851417) (xy 371.937848 -62.828585) (xy 371.990352 -62.813098)
			(xy 372.04453 -62.805274) (xy 372.0719 -62.804802) (xy 372.099152 -62.805268) (xy 372.153101 -62.813025)
			(xy 372.205397 -62.82838) (xy 372.254976 -62.851022) (xy 372.300827 -62.880489) (xy 372.342019 -62.916181)
			(xy 372.377711 -62.957373) (xy 372.407178 -63.003224) (xy 372.42982 -63.052803) (xy 372.439636 -63.086234)
			(xy 375.687588 -63.086234) (xy 375.691659 -63.030612) (xy 375.703785 -62.976175) (xy 375.723708 -62.924084)
			(xy 375.751004 -62.875449) (xy 375.78509 -62.831306) (xy 375.825239 -62.792597) (xy 375.870597 -62.760146)
			(xy 375.920197 -62.734645) (xy 375.972981 -62.716638) (xy 376.027824 -62.706508) (xy 376.083558 -62.704471)
			(xy 376.138995 -62.710571) (xy 376.192952 -62.724677) (xy 376.213112 -62.733244) (xy 381.966151 -62.733244)
			(xy 381.966152 -62.678737) (xy 381.973911 -62.624785) (xy 381.989268 -62.572487) (xy 382.011913 -62.522906)
			(xy 382.041383 -62.477053) (xy 382.077079 -62.435861) (xy 382.118273 -62.400168) (xy 382.164129 -62.370701)
			(xy 382.213711 -62.34806) (xy 382.26601 -62.332705) (xy 382.319963 -62.32495) (xy 382.347216 -62.324488)
			(xy 382.370771 -62.324865) (xy 382.417515 -62.330724) (xy 382.440434 -62.336172) (xy 382.454192 -62.339197)
			(xy 382.482341 -62.338344) (xy 382.509188 -62.32984) (xy 382.532695 -62.314331) (xy 382.551076 -62.292995)
			(xy 382.562935 -62.267451) (xy 382.567372 -62.239641) (xy 382.564049 -62.211676) (xy 382.559052 -62.198504)
			(xy 382.549741 -62.175115) (xy 382.536616 -62.126514) (xy 382.529993 -62.076609) (xy 382.529588 -62.051438)
			(xy 382.530014 -62.024182) (xy 382.537767 -61.970223) (xy 382.55312 -61.917918) (xy 382.575761 -61.868329)
			(xy 382.605229 -61.822468) (xy 382.640923 -61.781267) (xy 382.682118 -61.745566) (xy 382.727975 -61.716091)
			(xy 382.777559 -61.693442) (xy 382.829863 -61.67808) (xy 382.88382 -61.670319) (xy 382.938332 -61.670315)
			(xy 382.99229 -61.67807) (xy 383.044596 -61.693425) (xy 383.094183 -61.716068) (xy 383.140043 -61.745537)
			(xy 383.181243 -61.781233) (xy 383.216943 -61.822429) (xy 383.246416 -61.868287) (xy 383.269063 -61.917873)
			(xy 383.284423 -61.970176) (xy 383.292182 -62.024134) (xy 383.292184 -62.078646) (xy 383.284427 -62.132604)
			(xy 383.26907 -62.184909) (xy 383.246426 -62.234495) (xy 383.216955 -62.280355) (xy 383.181257 -62.321553)
			(xy 383.140059 -62.357251) (xy 383.094201 -62.386723) (xy 383.044614 -62.409368) (xy 382.99231 -62.424726)
			(xy 382.938352 -62.432483) (xy 382.911096 -62.432946) (xy 382.887541 -62.432566) (xy 382.840797 -62.426709)
			(xy 382.817878 -62.421262) (xy 382.804124 -62.418202) (xy 382.775968 -62.419052) (xy 382.749113 -62.427557)
			(xy 382.7256 -62.44307) (xy 382.707216 -62.464414) (xy 382.695357 -62.489966) (xy 382.690925 -62.517784)
			(xy 382.694257 -62.545756) (xy 382.69926 -62.55893) (xy 382.708582 -62.582315) (xy 382.721703 -62.630918)
			(xy 382.728321 -62.680825) (xy 382.728724 -62.705996) (xy 382.728249 -62.733249) (xy 382.720492 -62.787202)
			(xy 382.705136 -62.839501) (xy 382.682494 -62.889082) (xy 382.653025 -62.934936) (xy 382.617331 -62.97613)
			(xy 382.576137 -63.011824) (xy 382.530283 -63.041293) (xy 382.480702 -63.063936) (xy 382.428403 -63.079292)
			(xy 382.374451 -63.087049) (xy 382.319944 -63.087048) (xy 382.265992 -63.079291) (xy 382.213693 -63.063934)
			(xy 382.164112 -63.04129) (xy 382.118258 -63.011821) (xy 382.077065 -62.976126) (xy 382.041372 -62.934932)
			(xy 382.011904 -62.889077) (xy 381.989262 -62.839496) (xy 381.973907 -62.787196) (xy 381.966151 -62.733244)
			(xy 376.213112 -62.733244) (xy 376.244281 -62.746489) (xy 376.291887 -62.775543) (xy 376.334755 -62.811218)
			(xy 376.371972 -62.852755) (xy 376.402745 -62.899268) (xy 376.426417 -62.949765) (xy 376.442485 -63.003172)
			(xy 376.450605 -63.058348) (xy 376.451114 -63.086234) (xy 376.450605 -63.11412) (xy 376.442485 -63.169296)
			(xy 376.426417 -63.222703) (xy 376.402745 -63.2732) (xy 376.402592 -63.273432) (xy 377.876814 -63.273432)
			(xy 377.880885 -63.21781) (xy 377.893011 -63.163373) (xy 377.912934 -63.111282) (xy 377.94023 -63.062647)
			(xy 377.974316 -63.018504) (xy 378.014465 -62.979795) (xy 378.059823 -62.947344) (xy 378.109423 -62.921843)
			(xy 378.162207 -62.903836) (xy 378.21705 -62.893706) (xy 378.272784 -62.891669) (xy 378.328221 -62.897769)
			(xy 378.382178 -62.911875) (xy 378.433507 -62.933687) (xy 378.481113 -62.962741) (xy 378.523981 -62.998416)
			(xy 378.561198 -63.039953) (xy 378.591971 -63.086466) (xy 378.615643 -63.136963) (xy 378.631711 -63.19037)
			(xy 378.639831 -63.245546) (xy 378.64034 -63.273432) (xy 378.639831 -63.301318) (xy 378.631711 -63.356494)
			(xy 378.615643 -63.409901) (xy 378.591971 -63.460398) (xy 378.561198 -63.506911) (xy 378.523981 -63.548448)
			(xy 378.481113 -63.584123) (xy 378.433507 -63.613177) (xy 378.382178 -63.634989) (xy 378.328221 -63.649095)
			(xy 378.272784 -63.655195) (xy 378.21705 -63.653158) (xy 378.162207 -63.643028) (xy 378.109423 -63.625021)
			(xy 378.059823 -63.59952) (xy 378.014465 -63.567069) (xy 377.974316 -63.52836) (xy 377.94023 -63.484217)
			(xy 377.912934 -63.435582) (xy 377.893011 -63.383491) (xy 377.880885 -63.329054) (xy 377.876814 -63.273432)
			(xy 376.402592 -63.273432) (xy 376.371972 -63.319713) (xy 376.334755 -63.36125) (xy 376.291887 -63.396925)
			(xy 376.244281 -63.425979) (xy 376.192952 -63.447791) (xy 376.138995 -63.461897) (xy 376.083558 -63.467997)
			(xy 376.027824 -63.46596) (xy 375.972981 -63.45583) (xy 375.920197 -63.437823) (xy 375.870597 -63.412322)
			(xy 375.825239 -63.379871) (xy 375.78509 -63.341162) (xy 375.751004 -63.297019) (xy 375.723708 -63.248384)
			(xy 375.703785 -63.196293) (xy 375.691659 -63.141856) (xy 375.687588 -63.086234) (xy 372.439636 -63.086234)
			(xy 372.445175 -63.105099) (xy 372.452932 -63.159048) (xy 372.452932 -63.213552) (xy 372.445175 -63.267501)
			(xy 372.42982 -63.319797) (xy 372.407178 -63.369376) (xy 372.377711 -63.415227) (xy 372.342019 -63.456419)
			(xy 372.300827 -63.492111) (xy 372.254976 -63.521578) (xy 372.205397 -63.54422) (xy 372.153101 -63.559575)
			(xy 372.099152 -63.567332) (xy 372.0719 -63.567818) (xy 372.044529 -63.567372) (xy 371.990348 -63.559552)
			(xy 371.937844 -63.54406) (xy 371.888097 -63.521213) (xy 371.842132 -63.491482) (xy 371.821202 -63.473838)
			(xy 371.820948 -63.473584) (xy 371.813853 -63.46801) (xy 371.796943 -63.461756) (xy 371.787928 -63.461392)
			(xy 371.720872 -63.461392) (xy 371.711854 -63.461738) (xy 371.694937 -63.467993) (xy 371.687852 -63.473584)
			(xy 371.687598 -63.473838) (xy 371.666665 -63.491479) (xy 371.620697 -63.521203) (xy 371.570951 -63.544049)
			(xy 371.518449 -63.559545) (xy 371.464271 -63.567374) (xy 371.409529 -63.567374) (xy 371.355351 -63.559545)
			(xy 371.302849 -63.544049) (xy 371.253103 -63.521203) (xy 371.207135 -63.491479) (xy 371.186202 -63.473838)
			(xy 371.185948 -63.473584) (xy 371.178853 -63.46801) (xy 371.161943 -63.461756) (xy 371.152928 -63.461392)
			(xy 371.085872 -63.461392) (xy 371.076854 -63.461738) (xy 371.059937 -63.467993) (xy 371.052852 -63.473584)
			(xy 371.052852 -63.473838) (xy 371.052598 -63.473838) (xy 371.031683 -63.491498) (xy 370.985705 -63.521205)
			(xy 370.935953 -63.544037) (xy 370.883449 -63.559523) (xy 370.82927 -63.567347) (xy 370.8019 -63.567818)
			(xy 370.77465 -63.567312) (xy 370.720703 -63.559555) (xy 370.66841 -63.544201) (xy 370.618834 -63.52156)
			(xy 370.572985 -63.492095) (xy 370.531796 -63.456404) (xy 370.496105 -63.415215) (xy 370.46664 -63.369366)
			(xy 370.443999 -63.31979) (xy 370.428645 -63.267497) (xy 370.420888 -63.21355) (xy 352.635174 -63.21355)
			(xy 352.639883 -63.245546) (xy 352.640392 -63.273432) (xy 352.639883 -63.301318) (xy 352.631763 -63.356494)
			(xy 352.615695 -63.409901) (xy 352.592023 -63.460398) (xy 352.56125 -63.506911) (xy 352.524033 -63.548448)
			(xy 352.481165 -63.584123) (xy 352.433559 -63.613177) (xy 352.38223 -63.634989) (xy 352.328273 -63.649095)
			(xy 352.272836 -63.655195) (xy 352.217102 -63.653158) (xy 352.162259 -63.643028) (xy 352.109475 -63.625021)
			(xy 352.059875 -63.59952) (xy 352.014517 -63.567069) (xy 351.974368 -63.52836) (xy 351.940282 -63.484217)
			(xy 351.912986 -63.435582) (xy 351.893063 -63.383491) (xy 351.880937 -63.329054) (xy 351.876866 -63.273432)
			(xy 350.402644 -63.273432) (xy 350.372024 -63.319713) (xy 350.334807 -63.36125) (xy 350.291939 -63.396925)
			(xy 350.244333 -63.425979) (xy 350.193004 -63.447791) (xy 350.139047 -63.461897) (xy 350.08361 -63.467997)
			(xy 350.027876 -63.46596) (xy 349.973033 -63.45583) (xy 349.920249 -63.437823) (xy 349.870649 -63.412322)
			(xy 349.825291 -63.379871) (xy 349.785142 -63.341162) (xy 349.751056 -63.297019) (xy 349.72376 -63.248384)
			(xy 349.703837 -63.196293) (xy 349.691711 -63.141856) (xy 349.68764 -63.086234) (xy 341.441666 -63.086234)
			(xy 341.04262 -65.124076) (xy 354.407468 -65.124076) (xy 354.411539 -65.068454) (xy 354.423665 -65.014017)
			(xy 354.443588 -64.961926) (xy 354.470884 -64.913291) (xy 354.50497 -64.869148) (xy 354.545119 -64.830439)
			(xy 354.590477 -64.797988) (xy 354.640077 -64.772487) (xy 354.692861 -64.75448) (xy 354.747704 -64.74435)
			(xy 354.803438 -64.742313) (xy 354.858875 -64.748413) (xy 354.912832 -64.762519) (xy 354.964161 -64.784331)
			(xy 355.011767 -64.813385) (xy 355.054635 -64.84906) (xy 355.091852 -64.890597) (xy 355.122625 -64.93711)
			(xy 355.146297 -64.987607) (xy 355.162365 -65.041014) (xy 355.170485 -65.09619) (xy 355.170572 -65.100962)
			(xy 368.432586 -65.100962) (xy 368.436657 -65.04534) (xy 368.448783 -64.990903) (xy 368.468706 -64.938812)
			(xy 368.496002 -64.890177) (xy 368.530088 -64.846034) (xy 368.570237 -64.807325) (xy 368.615595 -64.774874)
			(xy 368.665195 -64.749373) (xy 368.717979 -64.731366) (xy 368.772822 -64.721236) (xy 368.828556 -64.719199)
			(xy 368.883993 -64.725299) (xy 368.93795 -64.739405) (xy 368.989279 -64.761217) (xy 369.036885 -64.790271)
			(xy 369.079753 -64.825946) (xy 369.11697 -64.867483) (xy 369.147743 -64.913996) (xy 369.171415 -64.964493)
			(xy 369.187483 -65.0179) (xy 369.195603 -65.073076) (xy 369.196112 -65.100962) (xy 369.19569 -65.124076)
			(xy 380.407416 -65.124076) (xy 380.411487 -65.068454) (xy 380.423613 -65.014017) (xy 380.443536 -64.961926)
			(xy 380.470832 -64.913291) (xy 380.504918 -64.869148) (xy 380.545067 -64.830439) (xy 380.590425 -64.797988)
			(xy 380.640025 -64.772487) (xy 380.692809 -64.75448) (xy 380.747652 -64.74435) (xy 380.803386 -64.742313)
			(xy 380.858823 -64.748413) (xy 380.91278 -64.762519) (xy 380.964109 -64.784331) (xy 381.011715 -64.813385)
			(xy 381.054583 -64.84906) (xy 381.0918 -64.890597) (xy 381.122573 -64.93711) (xy 381.146245 -64.987607)
			(xy 381.162313 -65.041014) (xy 381.170433 -65.09619) (xy 381.170942 -65.124076) (xy 381.170433 -65.151962)
			(xy 381.162313 -65.207138) (xy 381.146245 -65.260545) (xy 381.122573 -65.311042) (xy 381.0918 -65.357555)
			(xy 381.054583 -65.399092) (xy 381.011715 -65.434767) (xy 380.964109 -65.463821) (xy 380.91278 -65.485633)
			(xy 380.858823 -65.499739) (xy 380.803386 -65.505839) (xy 380.747652 -65.503802) (xy 380.692809 -65.493672)
			(xy 380.640025 -65.475665) (xy 380.590425 -65.450164) (xy 380.545067 -65.417713) (xy 380.504918 -65.379004)
			(xy 380.470832 -65.334861) (xy 380.443536 -65.286226) (xy 380.423613 -65.234135) (xy 380.411487 -65.179698)
			(xy 380.407416 -65.124076) (xy 369.19569 -65.124076) (xy 369.195603 -65.128848) (xy 369.187483 -65.184024)
			(xy 369.171415 -65.237431) (xy 369.147743 -65.287928) (xy 369.11697 -65.334441) (xy 369.079753 -65.375978)
			(xy 369.036885 -65.411653) (xy 368.989279 -65.440707) (xy 368.93795 -65.462519) (xy 368.883993 -65.476625)
			(xy 368.828556 -65.482725) (xy 368.772822 -65.480688) (xy 368.717979 -65.470558) (xy 368.665195 -65.452551)
			(xy 368.615595 -65.42705) (xy 368.570237 -65.394599) (xy 368.530088 -65.35589) (xy 368.496002 -65.311747)
			(xy 368.468706 -65.263112) (xy 368.448783 -65.211021) (xy 368.436657 -65.156584) (xy 368.432586 -65.100962)
			(xy 355.170572 -65.100962) (xy 355.170994 -65.124076) (xy 355.170485 -65.151962) (xy 355.162365 -65.207138)
			(xy 355.146297 -65.260545) (xy 355.122625 -65.311042) (xy 355.091852 -65.357555) (xy 355.054635 -65.399092)
			(xy 355.011767 -65.434767) (xy 354.964161 -65.463821) (xy 354.912832 -65.485633) (xy 354.858875 -65.499739)
			(xy 354.803438 -65.505839) (xy 354.747704 -65.503802) (xy 354.692861 -65.493672) (xy 354.640077 -65.475665)
			(xy 354.590477 -65.450164) (xy 354.545119 -65.417713) (xy 354.50497 -65.379004) (xy 354.470884 -65.334861)
			(xy 354.443588 -65.286226) (xy 354.423665 -65.234135) (xy 354.411539 -65.179698) (xy 354.407468 -65.124076)
			(xy 341.04262 -65.124076) (xy 340.918972 -65.75552) (xy 362.64672 -65.75552) (xy 362.650791 -65.699898)
			(xy 362.662917 -65.645461) (xy 362.68284 -65.59337) (xy 362.710136 -65.544735) (xy 362.744222 -65.500592)
			(xy 362.784371 -65.461883) (xy 362.829729 -65.429432) (xy 362.879329 -65.403931) (xy 362.932113 -65.385924)
			(xy 362.986956 -65.375794) (xy 363.04269 -65.373757) (xy 363.098127 -65.379857) (xy 363.152084 -65.393963)
			(xy 363.203413 -65.415775) (xy 363.251019 -65.444829) (xy 363.293887 -65.480504) (xy 363.331104 -65.522041)
			(xy 363.361877 -65.568554) (xy 363.385549 -65.619051) (xy 363.401617 -65.672458) (xy 363.409737 -65.727634)
			(xy 363.410246 -65.75552) (xy 363.409737 -65.783406) (xy 363.401617 -65.838582) (xy 363.385549 -65.891989)
			(xy 363.361877 -65.942486) (xy 363.331104 -65.988999) (xy 363.293887 -66.030536) (xy 363.251019 -66.066211)
			(xy 363.203413 -66.095265) (xy 363.152084 -66.117077) (xy 363.098127 -66.131183) (xy 363.04269 -66.137283)
			(xy 362.986956 -66.135246) (xy 362.932113 -66.125116) (xy 362.879329 -66.107109) (xy 362.829729 -66.081608)
			(xy 362.784371 -66.049157) (xy 362.744222 -66.010448) (xy 362.710136 -65.966305) (xy 362.68284 -65.91767)
			(xy 362.662917 -65.865579) (xy 362.650791 -65.811142) (xy 362.64672 -65.75552) (xy 340.918972 -65.75552)
			(xy 340.603535 -67.366388) (xy 342.116408 -67.366388) (xy 342.120479 -67.310766) (xy 342.132605 -67.256329)
			(xy 342.152528 -67.204238) (xy 342.179824 -67.155603) (xy 342.21391 -67.11146) (xy 342.254059 -67.072751)
			(xy 342.299417 -67.0403) (xy 342.349017 -67.014799) (xy 342.401801 -66.996792) (xy 342.456644 -66.986662)
			(xy 342.512378 -66.984625) (xy 342.567815 -66.990725) (xy 342.621772 -67.004831) (xy 342.673101 -67.026643)
			(xy 342.720707 -67.055697) (xy 342.763575 -67.091372) (xy 342.797244 -67.128949) (xy 362.666798 -67.128949)
			(xy 362.666798 -67.074451) (xy 362.674554 -67.020507) (xy 362.689908 -66.968216) (xy 362.712547 -66.918642)
			(xy 362.74201 -66.872795) (xy 362.777699 -66.831607) (xy 362.818885 -66.795918) (xy 362.864732 -66.766452)
			(xy 362.914305 -66.743812) (xy 362.966595 -66.728457) (xy 363.020539 -66.720699) (xy 363.047788 -66.720212)
			(xy 363.075158 -66.720682) (xy 363.129337 -66.728499) (xy 363.18184 -66.743987) (xy 363.231587 -66.766827)
			(xy 363.277554 -66.796551) (xy 363.298486 -66.814192) (xy 363.29874 -66.814446) (xy 363.305836 -66.820019)
			(xy 363.322746 -66.826273) (xy 363.33176 -66.826638) (xy 363.398816 -66.826638) (xy 363.407833 -66.826281)
			(xy 363.424749 -66.820032) (xy 363.431836 -66.814446) (xy 363.431836 -66.814192) (xy 363.43209 -66.814192)
			(xy 363.453014 -66.796543) (xy 363.498989 -66.766833) (xy 363.548739 -66.743999) (xy 363.601241 -66.72851)
			(xy 363.655418 -66.720685) (xy 363.682788 -66.720212) (xy 363.710043 -66.720634) (xy 363.763998 -66.72839)
			(xy 363.8163 -66.743746) (xy 363.865884 -66.766389) (xy 363.911741 -66.795858) (xy 363.952938 -66.831554)
			(xy 363.988635 -66.872749) (xy 364.018105 -66.918605) (xy 364.04075 -66.968189) (xy 364.056107 -67.02049)
			(xy 364.063865 -67.074445) (xy 364.063865 -67.128955) (xy 364.056107 -67.18291) (xy 364.04075 -67.235211)
			(xy 364.018105 -67.284795) (xy 363.988635 -67.330651) (xy 363.952938 -67.371846) (xy 363.911741 -67.407542)
			(xy 363.865884 -67.437011) (xy 363.8163 -67.459654) (xy 363.763998 -67.47501) (xy 363.710043 -67.482766)
			(xy 363.682788 -67.483228) (xy 363.655417 -67.482787) (xy 363.601236 -67.474965) (xy 363.548732 -67.459472)
			(xy 363.498985 -67.436624) (xy 363.45302 -67.406893) (xy 363.43209 -67.389248) (xy 363.431836 -67.388994)
			(xy 363.424744 -67.383416) (xy 363.407831 -67.377164) (xy 363.398816 -67.376802) (xy 363.33176 -67.376802)
			(xy 363.322741 -67.37714) (xy 363.305824 -67.383401) (xy 363.29874 -67.388994) (xy 363.29874 -67.389248)
			(xy 363.298486 -67.389248) (xy 363.277526 -67.406852) (xy 363.231561 -67.436571) (xy 363.181821 -67.459415)
			(xy 363.129326 -67.474914) (xy 363.075155 -67.48275) (xy 363.047788 -67.483228) (xy 363.020539 -67.482701)
			(xy 362.966595 -67.474943) (xy 362.914305 -67.459588) (xy 362.864732 -67.436948) (xy 362.818885 -67.407482)
			(xy 362.777699 -67.371793) (xy 362.74201 -67.330605) (xy 362.712547 -67.284758) (xy 362.689908 -67.235184)
			(xy 362.674554 -67.182893) (xy 362.666798 -67.128949) (xy 342.797244 -67.128949) (xy 342.800792 -67.132909)
			(xy 342.831565 -67.179422) (xy 342.855237 -67.229919) (xy 342.871305 -67.283326) (xy 342.879425 -67.338502)
			(xy 342.879934 -67.366388) (xy 342.879425 -67.394274) (xy 342.871305 -67.44945) (xy 342.859691 -67.488054)
			(xy 367.079274 -67.488054) (xy 367.083345 -67.432432) (xy 367.095471 -67.377995) (xy 367.115394 -67.325904)
			(xy 367.14269 -67.277269) (xy 367.176776 -67.233126) (xy 367.216925 -67.194417) (xy 367.262283 -67.161966)
			(xy 367.311883 -67.136465) (xy 367.364667 -67.118458) (xy 367.41951 -67.108328) (xy 367.475244 -67.106291)
			(xy 367.530681 -67.112391) (xy 367.584638 -67.126497) (xy 367.635967 -67.148309) (xy 367.683573 -67.177363)
			(xy 367.726441 -67.213038) (xy 367.763658 -67.254575) (xy 367.794431 -67.301088) (xy 367.818103 -67.351585)
			(xy 367.834171 -67.404992) (xy 367.842291 -67.460168) (xy 367.8428 -67.488054) (xy 367.842291 -67.51594)
			(xy 367.839106 -67.537584) (xy 368.371372 -67.537584) (xy 368.375443 -67.481962) (xy 368.387569 -67.427525)
			(xy 368.407492 -67.375434) (xy 368.434788 -67.326799) (xy 368.468874 -67.282656) (xy 368.509023 -67.243947)
			(xy 368.554381 -67.211496) (xy 368.603981 -67.185995) (xy 368.656765 -67.167988) (xy 368.711608 -67.157858)
			(xy 368.767342 -67.155821) (xy 368.822779 -67.161921) (xy 368.876736 -67.176027) (xy 368.928065 -67.197839)
			(xy 368.975671 -67.226893) (xy 369.018539 -67.262568) (xy 369.055756 -67.304105) (xy 369.086529 -67.350618)
			(xy 369.110201 -67.401115) (xy 369.126269 -67.454522) (xy 369.134389 -67.509698) (xy 369.134898 -67.537584)
			(xy 369.134389 -67.56547) (xy 369.130344 -67.592956) (xy 369.645436 -67.592956) (xy 369.649507 -67.537334)
			(xy 369.661633 -67.482897) (xy 369.681556 -67.430806) (xy 369.708852 -67.382171) (xy 369.742938 -67.338028)
			(xy 369.783087 -67.299319) (xy 369.828445 -67.266868) (xy 369.878045 -67.241367) (xy 369.930829 -67.22336)
			(xy 369.985672 -67.21323) (xy 370.041406 -67.211193) (xy 370.096843 -67.217293) (xy 370.1508 -67.231399)
			(xy 370.202129 -67.253211) (xy 370.249735 -67.282265) (xy 370.292603 -67.31794) (xy 370.32982 -67.359477)
			(xy 370.360593 -67.40599) (xy 370.384265 -67.456487) (xy 370.400333 -67.509894) (xy 370.40845 -67.565048)
			(xy 372.746816 -67.565048) (xy 372.746816 -67.510553) (xy 372.754571 -67.456612) (xy 372.769924 -67.404324)
			(xy 372.792561 -67.354754) (xy 372.822022 -67.308909) (xy 372.857708 -67.267723) (xy 372.898891 -67.232035)
			(xy 372.944734 -67.202572) (xy 372.994304 -67.179931) (xy 373.046591 -67.164576) (xy 373.100531 -67.156818)
			(xy 373.127778 -67.15633) (xy 373.155148 -67.156802) (xy 373.209327 -67.164617) (xy 373.261831 -67.180104)
			(xy 373.311578 -67.202945) (xy 373.357544 -67.232669) (xy 373.378476 -67.25031) (xy 373.37873 -67.250564)
			(xy 373.385827 -67.256135) (xy 373.402736 -67.262389) (xy 373.41175 -67.262756) (xy 373.478806 -67.262756)
			(xy 373.487824 -67.262411) (xy 373.504742 -67.256156) (xy 373.511826 -67.250564) (xy 373.511826 -67.25031)
			(xy 373.51208 -67.25031) (xy 373.53301 -67.232668) (xy 373.578983 -67.202957) (xy 373.628731 -67.180121)
			(xy 373.681232 -67.164631) (xy 373.735409 -67.156803) (xy 373.762778 -67.15633) (xy 373.790035 -67.156715)
			(xy 373.843993 -67.164471) (xy 373.896299 -67.179826) (xy 373.945887 -67.20247) (xy 373.991748 -67.23194)
			(xy 374.032947 -67.267637) (xy 374.068647 -67.308835) (xy 374.09812 -67.354694) (xy 374.120766 -67.40428)
			(xy 374.136125 -67.456585) (xy 374.143883 -67.510543) (xy 374.143883 -67.565057) (xy 374.136125 -67.619015)
			(xy 374.120766 -67.67132) (xy 374.09812 -67.720906) (xy 374.068647 -67.766765) (xy 374.032947 -67.807963)
			(xy 373.991748 -67.84366) (xy 373.945887 -67.87313) (xy 373.896299 -67.895774) (xy 373.843993 -67.911129)
			(xy 373.790035 -67.918885) (xy 373.762778 -67.919346) (xy 373.735407 -67.918906) (xy 373.681226 -67.911084)
			(xy 373.628722 -67.895589) (xy 373.578976 -67.872742) (xy 373.53301 -67.843011) (xy 373.51208 -67.825366)
			(xy 373.511826 -67.825112) (xy 373.504735 -67.819532) (xy 373.487822 -67.813281) (xy 373.478806 -67.81292)
			(xy 373.41175 -67.81292) (xy 373.402735 -67.813297) (xy 373.385818 -67.81953) (xy 373.37873 -67.825112)
			(xy 373.37873 -67.825366) (xy 373.378476 -67.825366) (xy 373.357522 -67.842978) (xy 373.311556 -67.872695)
			(xy 373.261814 -67.895537) (xy 373.209318 -67.911034) (xy 373.155146 -67.918869) (xy 373.127778 -67.919346)
			(xy 373.100531 -67.918782) (xy 373.046591 -67.911024) (xy 372.994304 -67.895669) (xy 372.944734 -67.873028)
			(xy 372.898891 -67.843565) (xy 372.857708 -67.807877) (xy 372.822022 -67.766691) (xy 372.792561 -67.720846)
			(xy 372.769924 -67.671276) (xy 372.754571 -67.618988) (xy 372.746816 -67.565048) (xy 370.40845 -67.565048)
			(xy 370.408453 -67.56507) (xy 370.408962 -67.592956) (xy 370.408453 -67.620842) (xy 370.400333 -67.676018)
			(xy 370.384265 -67.729425) (xy 370.360593 -67.779922) (xy 370.32982 -67.826435) (xy 370.292603 -67.867972)
			(xy 370.249735 -67.903647) (xy 370.202129 -67.932701) (xy 370.1508 -67.954513) (xy 370.096843 -67.968619)
			(xy 370.041406 -67.974719) (xy 369.985672 -67.972682) (xy 369.930829 -67.962552) (xy 369.878045 -67.944545)
			(xy 369.828445 -67.919044) (xy 369.783087 -67.886593) (xy 369.742938 -67.847884) (xy 369.708852 -67.803741)
			(xy 369.681556 -67.755106) (xy 369.661633 -67.703015) (xy 369.649507 -67.648578) (xy 369.645436 -67.592956)
			(xy 369.130344 -67.592956) (xy 369.126269 -67.620646) (xy 369.110201 -67.674053) (xy 369.086529 -67.72455)
			(xy 369.055756 -67.771063) (xy 369.018539 -67.8126) (xy 368.975671 -67.848275) (xy 368.928065 -67.877329)
			(xy 368.876736 -67.899141) (xy 368.822779 -67.913247) (xy 368.767342 -67.919347) (xy 368.711608 -67.91731)
			(xy 368.656765 -67.90718) (xy 368.603981 -67.889173) (xy 368.554381 -67.863672) (xy 368.509023 -67.831221)
			(xy 368.468874 -67.792512) (xy 368.434788 -67.748369) (xy 368.407492 -67.699734) (xy 368.387569 -67.647643)
			(xy 368.375443 -67.593206) (xy 368.371372 -67.537584) (xy 367.839106 -67.537584) (xy 367.834171 -67.571116)
			(xy 367.818103 -67.624523) (xy 367.794431 -67.67502) (xy 367.763658 -67.721533) (xy 367.726441 -67.76307)
			(xy 367.683573 -67.798745) (xy 367.635967 -67.827799) (xy 367.584638 -67.849611) (xy 367.530681 -67.863717)
			(xy 367.475244 -67.869817) (xy 367.41951 -67.86778) (xy 367.364667 -67.85765) (xy 367.311883 -67.839643)
			(xy 367.262283 -67.814142) (xy 367.216925 -67.781691) (xy 367.176776 -67.742982) (xy 367.14269 -67.698839)
			(xy 367.115394 -67.650204) (xy 367.095471 -67.598113) (xy 367.083345 -67.543676) (xy 367.079274 -67.488054)
			(xy 342.859691 -67.488054) (xy 342.855237 -67.502857) (xy 342.831565 -67.553354) (xy 342.800792 -67.599867)
			(xy 342.763575 -67.641404) (xy 342.720707 -67.677079) (xy 342.673101 -67.706133) (xy 342.621772 -67.727945)
			(xy 342.567815 -67.742051) (xy 342.512378 -67.748151) (xy 342.456644 -67.746114) (xy 342.401801 -67.735984)
			(xy 342.349017 -67.717977) (xy 342.299417 -67.692476) (xy 342.254059 -67.660025) (xy 342.21391 -67.621316)
			(xy 342.179824 -67.577173) (xy 342.152528 -67.528538) (xy 342.132605 -67.476447) (xy 342.120479 -67.42201)
			(xy 342.116408 -67.366388) (xy 340.603535 -67.366388) (xy 340.364595 -68.586604) (xy 364.925356 -68.586604)
			(xy 364.925811 -68.559233) (xy 364.933629 -68.505053) (xy 364.94912 -68.452549) (xy 364.971965 -68.402803)
			(xy 365.001693 -68.356837) (xy 365.019336 -68.335906) (xy 365.01959 -68.335652) (xy 365.02516 -68.328554)
			(xy 365.031417 -68.311646) (xy 365.031782 -68.302632) (xy 365.031782 -68.235576) (xy 365.03144 -68.226557)
			(xy 365.025183 -68.20964) (xy 365.01959 -68.202556) (xy 365.019336 -68.202556) (xy 365.019336 -68.202302)
			(xy 365.00169 -68.181375) (xy 364.971978 -68.135402) (xy 364.949143 -68.085653) (xy 364.933653 -68.033151)
			(xy 364.925828 -67.978974) (xy 364.925356 -67.951604) (xy 364.925881 -67.924354) (xy 364.933636 -67.87041)
			(xy 364.948989 -67.818118) (xy 364.971627 -67.768543) (xy 365.00109 -67.722695) (xy 365.036777 -67.681505)
			(xy 365.077963 -67.645814) (xy 365.123808 -67.616346) (xy 365.173381 -67.593703) (xy 365.225671 -67.578345)
			(xy 365.279615 -67.570584) (xy 365.306864 -67.570096) (xy 365.333179 -67.570522) (xy 365.38531 -67.577766)
			(xy 365.435953 -67.592093) (xy 365.484152 -67.613233) (xy 365.528994 -67.640786) (xy 365.569632 -67.674231)
			(xy 365.587788 -67.693286) (xy 365.595314 -67.700682) (xy 365.614591 -67.70921) (xy 365.625126 -67.709796)
			(xy 365.699802 -67.709796) (xy 365.710354 -67.709282) (xy 365.729649 -67.700736) (xy 365.73714 -67.693286)
			(xy 365.75528 -67.674215) (xy 365.795914 -67.64076) (xy 365.840757 -67.613203) (xy 365.888961 -67.592068)
			(xy 365.939611 -67.577754) (xy 365.991747 -67.570533) (xy 366.018064 -67.570096) (xy 366.045433 -67.570584)
			(xy 366.099612 -67.578397) (xy 366.152114 -67.593881) (xy 366.201862 -67.616718) (xy 366.247829 -67.646437)
			(xy 366.268762 -67.664076) (xy 366.269016 -67.66433) (xy 366.276091 -67.669933) (xy 366.293017 -67.676169)
			(xy 366.302036 -67.676522) (xy 366.369092 -67.676522) (xy 366.378108 -67.676156) (xy 366.395025 -67.669914)
			(xy 366.402112 -67.66433) (xy 366.402112 -67.664076) (xy 366.402366 -67.664076) (xy 366.423297 -67.646436)
			(xy 366.46927 -67.616725) (xy 366.519018 -67.59389) (xy 366.571519 -67.578399) (xy 366.625695 -67.57057)
			(xy 366.653064 -67.570096) (xy 366.680316 -67.570589) (xy 366.734266 -67.578341) (xy 366.786564 -67.593693)
			(xy 366.836144 -67.616331) (xy 366.881998 -67.645796) (xy 366.923191 -67.681487) (xy 366.958885 -67.722677)
			(xy 366.988353 -67.768528) (xy 367.010996 -67.818106) (xy 367.026352 -67.870402) (xy 367.034109 -67.924352)
			(xy 367.034572 -67.951604) (xy 367.034115 -67.978975) (xy 367.026296 -68.033154) (xy 367.010805 -68.085658)
			(xy 366.987961 -68.135405) (xy 366.958234 -68.181371) (xy 366.940592 -68.202302) (xy 366.940338 -68.202556)
			(xy 366.934756 -68.209646) (xy 366.928508 -68.22656) (xy 366.928146 -68.235576) (xy 366.928146 -68.302632)
			(xy 366.928478 -68.311652) (xy 366.934742 -68.328569) (xy 366.940338 -68.335652) (xy 366.940592 -68.335652)
			(xy 366.940592 -68.335906) (xy 366.958246 -68.356826) (xy 366.987956 -68.402802) (xy 367.010789 -68.452553)
			(xy 367.026277 -68.505056) (xy 367.0341 -68.559234) (xy 367.034572 -68.586604) (xy 367.034148 -68.613859)
			(xy 367.02639 -68.667813) (xy 367.011031 -68.720114) (xy 366.994399 -68.75653) (xy 370.47043 -68.75653)
			(xy 370.470906 -68.72916) (xy 370.478721 -68.674981) (xy 370.494207 -68.622478) (xy 370.517046 -68.572731)
			(xy 370.546769 -68.526764) (xy 370.56441 -68.505832) (xy 370.564664 -68.505578) (xy 370.570273 -68.498507)
			(xy 370.576505 -68.481578) (xy 370.576856 -68.472558) (xy 370.576856 -68.405502) (xy 370.576507 -68.396484)
			(xy 370.570255 -68.379567) (xy 370.564664 -68.372482) (xy 370.56441 -68.372482) (xy 370.56441 -68.372228)
			(xy 370.546772 -68.351295) (xy 370.51706 -68.305323) (xy 370.494223 -68.255575) (xy 370.478732 -68.203075)
			(xy 370.470904 -68.148899) (xy 370.47043 -68.12153) (xy 370.470883 -68.094276) (xy 370.478637 -68.040323)
			(xy 370.493991 -67.988023) (xy 370.516633 -67.93844) (xy 370.546102 -67.892585) (xy 370.581797 -67.851391)
			(xy 370.622991 -67.815697) (xy 370.668847 -67.786229) (xy 370.71843 -67.763589) (xy 370.770731 -67.748236)
			(xy 370.824684 -67.740483) (xy 370.851938 -67.740022) (xy 370.879307 -67.740519) (xy 370.933485 -67.748329)
			(xy 370.985988 -67.76381) (xy 371.035736 -67.786645) (xy 371.081704 -67.816364) (xy 371.102636 -67.834002)
			(xy 371.10289 -67.834256) (xy 371.10997 -67.839851) (xy 371.126892 -67.846091) (xy 371.13591 -67.846448)
			(xy 371.202966 -67.846448) (xy 371.211983 -67.846086) (xy 371.2289 -67.839843) (xy 371.235986 -67.834256)
			(xy 371.235986 -67.834002) (xy 371.23624 -67.834002) (xy 371.257184 -67.816378) (xy 371.303154 -67.786664)
			(xy 371.352898 -67.763825) (xy 371.405396 -67.74833) (xy 371.45957 -67.740498) (xy 371.486938 -67.740022)
			(xy 371.513253 -67.740457) (xy 371.565383 -67.747698) (xy 371.616027 -67.762023) (xy 371.664226 -67.783161)
			(xy 371.709069 -67.810713) (xy 371.749707 -67.844158) (xy 371.767862 -67.863212) (xy 371.775394 -67.870601)
			(xy 371.794666 -67.879132) (xy 371.8052 -67.879722) (xy 371.879876 -67.879722) (xy 371.890425 -67.879187)
			(xy 371.90972 -67.870655) (xy 371.917214 -67.863212) (xy 371.935372 -67.844159) (xy 371.976001 -67.810701)
			(xy 372.020841 -67.783141) (xy 372.069041 -67.762002) (xy 372.119688 -67.747685) (xy 372.171822 -67.74046)
			(xy 372.198138 -67.740022) (xy 372.225392 -67.740443) (xy 372.279343 -67.748205) (xy 372.331641 -67.763566)
			(xy 372.38122 -67.786214) (xy 372.427072 -67.815687) (xy 372.468263 -67.851386) (xy 372.503954 -67.892583)
			(xy 372.533418 -67.938439) (xy 372.556057 -67.988023) (xy 372.571409 -68.040323) (xy 372.579162 -68.094276)
			(xy 372.579646 -68.12153) (xy 372.579211 -68.148901) (xy 372.571387 -68.203082) (xy 372.555892 -68.255586)
			(xy 372.533043 -68.305333) (xy 372.503311 -68.351298) (xy 372.485666 -68.372228) (xy 372.485412 -68.372482)
			(xy 372.479828 -68.379571) (xy 372.473579 -68.396486) (xy 372.47322 -68.405502) (xy 372.47322 -68.472558)
			(xy 372.473593 -68.481573) (xy 372.479829 -68.498491) (xy 372.485412 -68.505578) (xy 372.485666 -68.505578)
			(xy 372.485666 -68.505832) (xy 372.503281 -68.526783) (xy 372.532998 -68.57275) (xy 372.555839 -68.622493)
			(xy 372.571336 -68.674989) (xy 372.579169 -68.729162) (xy 372.579646 -68.75653) (xy 372.57915 -68.78378)
			(xy 372.571391 -68.837726) (xy 372.556034 -68.890018) (xy 372.533392 -68.939593) (xy 372.503926 -68.985441)
			(xy 372.468236 -69.02663) (xy 372.427048 -69.062321) (xy 372.3812 -69.091788) (xy 372.331625 -69.114431)
			(xy 372.279333 -69.129789) (xy 372.225388 -69.13755) (xy 372.198138 -69.138038) (xy 372.171822 -69.137632)
			(xy 372.11969 -69.130387) (xy 372.069045 -69.116057) (xy 372.020846 -69.094914) (xy 371.976004 -69.067356)
			(xy 371.935368 -69.033905) (xy 371.917214 -69.014848) (xy 371.909683 -69.007458) (xy 371.89041 -68.998925)
			(xy 371.879876 -68.998338) (xy 371.8052 -68.998338) (xy 371.794647 -68.998842) (xy 371.775351 -69.007394)
			(xy 371.767862 -69.014848) (xy 371.749727 -69.033924) (xy 371.709092 -69.067378) (xy 371.664247 -69.094933)
			(xy 371.616042 -69.116067) (xy 371.565392 -69.130381) (xy 371.513255 -69.137601) (xy 371.486938 -69.138038)
			(xy 371.459568 -69.137565) (xy 371.405388 -69.129751) (xy 371.352885 -69.114264) (xy 371.303138 -69.091424)
			(xy 371.257171 -69.061699) (xy 371.23624 -69.044058) (xy 371.235986 -69.043804) (xy 371.228907 -69.038206)
			(xy 371.211985 -69.031966) (xy 371.202966 -69.031612) (xy 371.13591 -69.031612) (xy 371.126893 -69.031971)
			(xy 371.109976 -69.038217) (xy 371.10289 -69.043804) (xy 371.10289 -69.044058) (xy 371.102636 -69.044058)
			(xy 371.081696 -69.061687) (xy 371.035726 -69.091402) (xy 370.985981 -69.11424) (xy 370.933481 -69.129734)
			(xy 370.879307 -69.137563) (xy 370.851938 -69.138038) (xy 370.824687 -69.137509) (xy 370.77074 -69.129758)
			(xy 370.718446 -69.114409) (xy 370.668868 -69.091773) (xy 370.623016 -69.062312) (xy 370.581823 -69.026625)
			(xy 370.546129 -68.985439) (xy 370.51666 -68.939592) (xy 370.494015 -68.890018) (xy 370.478656 -68.837726)
			(xy 370.470895 -68.78378) (xy 370.47043 -68.75653) (xy 366.994399 -68.75653) (xy 366.988386 -68.769696)
			(xy 366.958914 -68.815551) (xy 366.923216 -68.856745) (xy 366.882019 -68.892438) (xy 366.836161 -68.921905)
			(xy 366.786576 -68.944545) (xy 366.734274 -68.959898) (xy 366.680319 -68.967651) (xy 366.653064 -68.968112)
			(xy 366.625693 -68.967664) (xy 366.571513 -68.959841) (xy 366.51901 -68.944348) (xy 366.469264 -68.921502)
			(xy 366.423297 -68.891775) (xy 366.402366 -68.874132) (xy 366.402112 -68.873878) (xy 366.395028 -68.868288)
			(xy 366.378109 -68.862044) (xy 366.369092 -68.861686) (xy 366.302036 -68.861686) (xy 366.293021 -68.862063)
			(xy 366.276104 -68.868297) (xy 366.269016 -68.873878) (xy 366.269016 -68.874132) (xy 366.268762 -68.874132)
			(xy 366.247821 -68.89176) (xy 366.20185 -68.921473) (xy 366.152105 -68.94431) (xy 366.099606 -68.959804)
			(xy 366.045433 -68.967636) (xy 366.018064 -68.968112) (xy 365.991749 -68.967665) (xy 365.93962 -68.960425)
			(xy 365.888977 -68.946102) (xy 365.840778 -68.924966) (xy 365.795935 -68.897416) (xy 365.755296 -68.863975)
			(xy 365.73714 -68.844922) (xy 365.729603 -68.837539) (xy 365.710335 -68.829003) (xy 365.699802 -68.828412)
			(xy 365.625126 -68.828412) (xy 365.614576 -68.828938) (xy 365.59528 -68.837475) (xy 365.587788 -68.844922)
			(xy 365.569636 -68.863981) (xy 365.529005 -68.897437) (xy 365.484164 -68.924995) (xy 365.435962 -68.946132)
			(xy 365.385314 -68.960449) (xy 365.33318 -68.967674) (xy 365.306864 -68.968112) (xy 365.279612 -68.967656)
			(xy 365.225663 -68.959894) (xy 365.173368 -68.944535) (xy 365.123791 -68.92189) (xy 365.077941 -68.89242)
			(xy 365.036752 -68.856726) (xy 365.001061 -68.815533) (xy 364.971595 -68.769681) (xy 364.948954 -68.720102)
			(xy 364.933599 -68.667805) (xy 364.925842 -68.613856) (xy 364.925356 -68.586604) (xy 340.364595 -68.586604)
			(xy 340.291928 -68.957698) (xy 340.284355 -68.994512) (xy 340.264393 -69.066978) (xy 340.25205 -69.102478)
			(xy 339.609013 -70.895718) (xy 340.004398 -70.895718) (xy 340.008469 -70.840096) (xy 340.020595 -70.785659)
			(xy 340.040518 -70.733568) (xy 340.067814 -70.684933) (xy 340.1019 -70.64079) (xy 340.142049 -70.602081)
			(xy 340.187407 -70.56963) (xy 340.237007 -70.544129) (xy 340.289791 -70.526122) (xy 340.344634 -70.515992)
			(xy 340.400368 -70.513955) (xy 340.455805 -70.520055) (xy 340.509762 -70.534161) (xy 340.561091 -70.555973)
			(xy 340.608697 -70.585027) (xy 340.651565 -70.620702) (xy 340.688782 -70.662239) (xy 340.719555 -70.708752)
			(xy 340.743227 -70.759249) (xy 340.759295 -70.812656) (xy 340.767415 -70.867832) (xy 340.767632 -70.879716)
			(xy 340.99576 -70.879716) (xy 340.999831 -70.824094) (xy 341.011957 -70.769657) (xy 341.03188 -70.717566)
			(xy 341.059176 -70.668931) (xy 341.093262 -70.624788) (xy 341.133411 -70.586079) (xy 341.178769 -70.553628)
			(xy 341.228369 -70.528127) (xy 341.281153 -70.51012) (xy 341.335996 -70.49999) (xy 341.39173 -70.497953)
			(xy 341.447167 -70.504053) (xy 341.501124 -70.518159) (xy 341.552453 -70.539971) (xy 341.600059 -70.569025)
			(xy 341.642927 -70.6047) (xy 341.680144 -70.646237) (xy 341.710917 -70.69275) (xy 341.734589 -70.743247)
			(xy 341.750657 -70.796654) (xy 341.758777 -70.85183) (xy 341.759286 -70.879716) (xy 341.758777 -70.907602)
			(xy 341.750657 -70.962778) (xy 341.734589 -71.016185) (xy 341.710917 -71.066682) (xy 341.680144 -71.113195)
			(xy 341.642927 -71.154732) (xy 341.600059 -71.190407) (xy 341.552453 -71.219461) (xy 341.501124 -71.241273)
			(xy 341.447167 -71.255379) (xy 341.39173 -71.261479) (xy 341.335996 -71.259442) (xy 341.281153 -71.249312)
			(xy 341.228369 -71.231305) (xy 341.178769 -71.205804) (xy 341.133411 -71.173353) (xy 341.093262 -71.134644)
			(xy 341.059176 -71.090501) (xy 341.03188 -71.041866) (xy 341.011957 -70.989775) (xy 340.999831 -70.935338)
			(xy 340.99576 -70.879716) (xy 340.767632 -70.879716) (xy 340.767924 -70.895718) (xy 340.767415 -70.923604)
			(xy 340.759295 -70.97878) (xy 340.743227 -71.032187) (xy 340.719555 -71.082684) (xy 340.688782 -71.129197)
			(xy 340.651565 -71.170734) (xy 340.608697 -71.206409) (xy 340.561091 -71.235463) (xy 340.509762 -71.257275)
			(xy 340.455805 -71.271381) (xy 340.400368 -71.277481) (xy 340.344634 -71.275444) (xy 340.289791 -71.265314)
			(xy 340.237007 -71.247307) (xy 340.187407 -71.221806) (xy 340.142049 -71.189355) (xy 340.1019 -71.150646)
			(xy 340.067814 -71.106503) (xy 340.040518 -71.057868) (xy 340.020595 -71.005777) (xy 340.008469 -70.95134)
			(xy 340.004398 -70.895718) (xy 339.609013 -70.895718) (xy 339.372292 -71.555864) (xy 367.494564 -71.555864)
			(xy 367.498635 -71.500242) (xy 367.510761 -71.445805) (xy 367.530684 -71.393714) (xy 367.55798 -71.345079)
			(xy 367.592066 -71.300936) (xy 367.632215 -71.262227) (xy 367.677573 -71.229776) (xy 367.727173 -71.204275)
			(xy 367.779957 -71.186268) (xy 367.8348 -71.176138) (xy 367.890534 -71.174101) (xy 367.945971 -71.180201)
			(xy 367.999928 -71.194307) (xy 368.051257 -71.216119) (xy 368.098863 -71.245173) (xy 368.141731 -71.280848)
			(xy 368.178948 -71.322385) (xy 368.209721 -71.368898) (xy 368.233393 -71.419395) (xy 368.249461 -71.472802)
			(xy 368.257581 -71.527978) (xy 368.25809 -71.555864) (xy 368.257581 -71.58375) (xy 368.251742 -71.623428)
			(xy 369.003578 -71.623428) (xy 369.007649 -71.567806) (xy 369.019775 -71.513369) (xy 369.039698 -71.461278)
			(xy 369.066994 -71.412643) (xy 369.10108 -71.3685) (xy 369.141229 -71.329791) (xy 369.186587 -71.29734)
			(xy 369.236187 -71.271839) (xy 369.288971 -71.253832) (xy 369.343814 -71.243702) (xy 369.399548 -71.241665)
			(xy 369.454985 -71.247765) (xy 369.508942 -71.261871) (xy 369.560271 -71.283683) (xy 369.607877 -71.312737)
			(xy 369.650745 -71.348412) (xy 369.687962 -71.389949) (xy 369.718735 -71.436462) (xy 369.742407 -71.486959)
			(xy 369.758475 -71.540366) (xy 369.766595 -71.595542) (xy 369.767104 -71.623428) (xy 369.766595 -71.651314)
			(xy 369.758475 -71.70649) (xy 369.742407 -71.759897) (xy 369.718735 -71.810394) (xy 369.687962 -71.856907)
			(xy 369.650745 -71.898444) (xy 369.607877 -71.934119) (xy 369.560271 -71.963173) (xy 369.508942 -71.984985)
			(xy 369.454985 -71.999091) (xy 369.399548 -72.005191) (xy 369.343814 -72.003154) (xy 369.288971 -71.993024)
			(xy 369.236187 -71.975017) (xy 369.186587 -71.949516) (xy 369.141229 -71.917065) (xy 369.10108 -71.878356)
			(xy 369.066994 -71.834213) (xy 369.039698 -71.785578) (xy 369.019775 -71.733487) (xy 369.007649 -71.67905)
			(xy 369.003578 -71.623428) (xy 368.251742 -71.623428) (xy 368.249461 -71.638926) (xy 368.233393 -71.692333)
			(xy 368.209721 -71.74283) (xy 368.178948 -71.789343) (xy 368.141731 -71.83088) (xy 368.098863 -71.866555)
			(xy 368.051257 -71.895609) (xy 367.999928 -71.917421) (xy 367.945971 -71.931527) (xy 367.890534 -71.937627)
			(xy 367.8348 -71.93559) (xy 367.779957 -71.92546) (xy 367.727173 -71.907453) (xy 367.677573 -71.881952)
			(xy 367.632215 -71.849501) (xy 367.592066 -71.810792) (xy 367.55798 -71.766649) (xy 367.530684 -71.718014)
			(xy 367.510761 -71.665923) (xy 367.498635 -71.611486) (xy 367.494564 -71.555864) (xy 339.372292 -71.555864)
			(xy 338.082484 -75.152758) (xy 379.969266 -75.152758) (xy 379.973337 -75.097136) (xy 379.985463 -75.042699)
			(xy 380.005386 -74.990608) (xy 380.032682 -74.941973) (xy 380.066768 -74.89783) (xy 380.106917 -74.859121)
			(xy 380.152275 -74.82667) (xy 380.201875 -74.801169) (xy 380.254659 -74.783162) (xy 380.309502 -74.773032)
			(xy 380.365236 -74.770995) (xy 380.420673 -74.777095) (xy 380.47463 -74.791201) (xy 380.525959 -74.813013)
			(xy 380.573565 -74.842067) (xy 380.616433 -74.877742) (xy 380.65365 -74.919279) (xy 380.684423 -74.965792)
			(xy 380.708095 -75.016289) (xy 380.724088 -75.069446) (xy 381.604518 -75.069446) (xy 381.608589 -75.013824)
			(xy 381.620715 -74.959387) (xy 381.640638 -74.907296) (xy 381.667934 -74.858661) (xy 381.70202 -74.814518)
			(xy 381.742169 -74.775809) (xy 381.787527 -74.743358) (xy 381.837127 -74.717857) (xy 381.889911 -74.69985)
			(xy 381.944754 -74.68972) (xy 382.000488 -74.687683) (xy 382.055925 -74.693783) (xy 382.109882 -74.707889)
			(xy 382.161211 -74.729701) (xy 382.208817 -74.758755) (xy 382.251685 -74.79443) (xy 382.288902 -74.835967)
			(xy 382.319675 -74.88248) (xy 382.343347 -74.932977) (xy 382.359415 -74.986384) (xy 382.367535 -75.04156)
			(xy 382.368044 -75.069446) (xy 382.367535 -75.097332) (xy 382.359415 -75.152508) (xy 382.343347 -75.205915)
			(xy 382.319675 -75.256412) (xy 382.288902 -75.302925) (xy 382.251685 -75.344462) (xy 382.208817 -75.380137)
			(xy 382.161211 -75.409191) (xy 382.109882 -75.431003) (xy 382.055925 -75.445109) (xy 382.000488 -75.451209)
			(xy 381.944754 -75.449172) (xy 381.889911 -75.439042) (xy 381.837127 -75.421035) (xy 381.787527 -75.395534)
			(xy 381.742169 -75.363083) (xy 381.70202 -75.324374) (xy 381.667934 -75.280231) (xy 381.640638 -75.231596)
			(xy 381.620715 -75.179505) (xy 381.608589 -75.125068) (xy 381.604518 -75.069446) (xy 380.724088 -75.069446)
			(xy 380.724163 -75.069696) (xy 380.732283 -75.124872) (xy 380.732792 -75.152758) (xy 380.732283 -75.180644)
			(xy 380.724163 -75.23582) (xy 380.708095 -75.289227) (xy 380.684423 -75.339724) (xy 380.65365 -75.386237)
			(xy 380.616433 -75.427774) (xy 380.573565 -75.463449) (xy 380.525959 -75.492503) (xy 380.47463 -75.514315)
			(xy 380.420673 -75.528421) (xy 380.365236 -75.534521) (xy 380.309502 -75.532484) (xy 380.254659 -75.522354)
			(xy 380.201875 -75.504347) (xy 380.152275 -75.478846) (xy 380.106917 -75.446395) (xy 380.066768 -75.407686)
			(xy 380.032682 -75.363543) (xy 380.005386 -75.314908) (xy 379.985463 -75.262817) (xy 379.973337 -75.20838)
			(xy 379.969266 -75.152758) (xy 338.082484 -75.152758) (xy 337.832192 -75.85075) (xy 337.818566 -75.88763)
			(xy 337.786289 -75.959329) (xy 337.748477 -76.028269) (xy 337.705362 -76.094024) (xy 337.68157 -76.125324)
			(xy 336.719672 -77.365606) (xy 336.694013 -77.39799) (xy 336.638129 -77.458856) (xy 336.577403 -77.514893)
			(xy 336.512251 -77.565716) (xy 336.443119 -77.610977) (xy 336.406998 -77.631036) (xy 335.449371 -78.150664)
			(xy 336.40703 -78.150664) (xy 336.40703 -78.090736) (xy 336.414852 -78.031319) (xy 336.430363 -77.973433)
			(xy 336.453297 -77.918066) (xy 336.483261 -77.866166) (xy 336.519743 -77.818621) (xy 336.562119 -77.776245)
			(xy 336.609664 -77.739762) (xy 336.661564 -77.709797) (xy 336.716931 -77.686864) (xy 336.774817 -77.671353)
			(xy 336.834234 -77.66353) (xy 336.864198 -77.66304) (xy 337.727798 -77.66304) (xy 337.75777 -77.663413)
			(xy 337.817202 -77.671237) (xy 337.875104 -77.686751) (xy 337.930486 -77.709691) (xy 337.982399 -77.739663)
			(xy 338.029957 -77.776155) (xy 338.072344 -77.818542) (xy 338.108836 -77.866099) (xy 338.138808 -77.918013)
			(xy 338.161748 -77.973394) (xy 338.177263 -78.031296) (xy 338.185087 -78.090728) (xy 338.185087 -78.150672)
			(xy 338.177263 -78.210104) (xy 338.161748 -78.268006) (xy 338.138808 -78.323387) (xy 338.108836 -78.375301)
			(xy 338.072344 -78.422858) (xy 338.029957 -78.465245) (xy 337.982399 -78.501737) (xy 337.930486 -78.531709)
			(xy 337.875104 -78.554649) (xy 337.817202 -78.570163) (xy 337.75777 -78.577987) (xy 337.727798 -78.578456)
			(xy 336.864198 -78.578456) (xy 336.834234 -78.57787) (xy 336.774817 -78.570047) (xy 336.716931 -78.554536)
			(xy 336.661564 -78.531603) (xy 336.609664 -78.501638) (xy 336.562119 -78.465155) (xy 336.519743 -78.422779)
			(xy 336.483261 -78.375234) (xy 336.453297 -78.323334) (xy 336.430363 -78.267967) (xy 336.414852 -78.210081)
			(xy 336.40703 -78.150664) (xy 335.449371 -78.150664) (xy 335.119726 -78.329536) (xy 335.11059 -78.335103)
			(xy 335.097529 -78.352018) (xy 335.092446 -78.372775) (xy 335.093818 -78.383384) (xy 335.103724 -78.422246)
			(xy 335.109356 -78.423508) (xy 335.120814 -78.424906) (xy 335.126584 -78.42504) (xy 335.727802 -78.42504)
			(xy 335.757766 -78.42553) (xy 335.817183 -78.433353) (xy 335.875069 -78.448864) (xy 335.930436 -78.471797)
			(xy 335.982336 -78.501762) (xy 336.029881 -78.538245) (xy 336.072257 -78.580621) (xy 336.108739 -78.628166)
			(xy 336.138703 -78.680066) (xy 336.161637 -78.735433) (xy 336.177148 -78.793319) (xy 336.18497 -78.852736)
			(xy 336.18497 -78.912664) (xy 338.40703 -78.912664) (xy 338.40703 -78.852736) (xy 338.414852 -78.79332)
			(xy 338.430363 -78.735433) (xy 338.453296 -78.680067) (xy 338.48326 -78.628167) (xy 338.519742 -78.580622)
			(xy 338.562118 -78.538246) (xy 338.609662 -78.501763) (xy 338.661561 -78.471799) (xy 338.716928 -78.448865)
			(xy 338.774814 -78.433353) (xy 338.83423 -78.42553) (xy 338.864194 -78.42504) (xy 339.727794 -78.42504)
			(xy 339.757766 -78.425412) (xy 339.817199 -78.433236) (xy 339.875101 -78.44875) (xy 339.930483 -78.47169)
			(xy 339.982397 -78.501662) (xy 340.029955 -78.538153) (xy 340.072343 -78.580541) (xy 340.108835 -78.628098)
			(xy 340.138808 -78.680011) (xy 340.161748 -78.735393) (xy 340.177263 -78.793296) (xy 340.185087 -78.852728)
			(xy 340.185087 -78.912672) (xy 340.177263 -78.972104) (xy 340.161748 -79.030007) (xy 340.138808 -79.085389)
			(xy 340.108835 -79.137302) (xy 340.072343 -79.184859) (xy 340.029955 -79.227247) (xy 339.982397 -79.263738)
			(xy 339.930483 -79.29371) (xy 339.875101 -79.31665) (xy 339.817199 -79.332164) (xy 339.757766 -79.339988)
			(xy 339.727794 -79.340456) (xy 338.864194 -79.340456) (xy 338.83423 -79.33987) (xy 338.774814 -79.332047)
			(xy 338.716928 -79.316535) (xy 338.661561 -79.293601) (xy 338.609662 -79.263637) (xy 338.562118 -79.227154)
			(xy 338.519742 -79.184778) (xy 338.48326 -79.137233) (xy 338.453296 -79.085333) (xy 338.430363 -79.029967)
			(xy 338.414852 -78.97208) (xy 338.40703 -78.912664) (xy 336.18497 -78.912664) (xy 336.177148 -78.972081)
			(xy 336.161637 -79.029967) (xy 336.138703 -79.085334) (xy 336.108739 -79.137234) (xy 336.072257 -79.184779)
			(xy 336.029881 -79.227155) (xy 335.982336 -79.263638) (xy 335.930436 -79.293603) (xy 335.875069 -79.316536)
			(xy 335.817183 -79.332047) (xy 335.757766 -79.33987) (xy 335.727802 -79.340456) (xy 335.296256 -79.340456)
			(xy 335.296002 -79.34071) (xy 334.864202 -79.34071) (xy 334.834227 -79.340221) (xy 334.77479 -79.332399)
			(xy 334.716881 -79.31689) (xy 334.66149 -79.293957) (xy 334.609566 -79.263994) (xy 334.561994 -79.227512)
			(xy 334.519589 -79.185135) (xy 334.483075 -79.137588) (xy 334.453078 -79.085683) (xy 334.430108 -79.030308)
			(xy 334.41456 -78.972409) (xy 334.406699 -78.912977) (xy 334.40624 -78.883002) (xy 334.40624 -78.882748)
			(xy 334.406494 -78.868016) (xy 334.407208 -78.850381) (xy 334.411021 -78.815289) (xy 334.414114 -78.797912)
			(xy 334.415384 -78.789276) (xy 334.407002 -78.774036) (xy 334.402064 -78.765775) (xy 334.387336 -78.753409)
			(xy 334.369096 -78.747315) (xy 334.349892 -78.748344) (xy 334.340962 -78.751938) (xy 330.694792 -80.73009)
			(xy 330.450204 -80.862753) (xy 331.324655 -80.862753) (xy 331.324655 -80.808247) (xy 331.332413 -80.754295)
			(xy 331.347769 -80.701996) (xy 331.370413 -80.652415) (xy 331.399882 -80.606561) (xy 331.435577 -80.565368)
			(xy 331.476771 -80.529675) (xy 331.522625 -80.500207) (xy 331.572207 -80.477565) (xy 331.624506 -80.46221)
			(xy 331.678459 -80.454455) (xy 331.705712 -80.453992) (xy 331.733082 -80.454453) (xy 331.787262 -80.462272)
			(xy 331.839765 -80.477763) (xy 331.889511 -80.500605) (xy 331.935478 -80.530331) (xy 331.95641 -80.547972)
			(xy 331.956664 -80.548226) (xy 331.963755 -80.553807) (xy 331.980668 -80.560056) (xy 331.989684 -80.560418)
			(xy 332.05674 -80.560418) (xy 332.065758 -80.560076) (xy 332.082675 -80.553818) (xy 332.08976 -80.548226)
			(xy 332.08976 -80.547972) (xy 332.090014 -80.547972) (xy 332.110964 -80.530355) (xy 332.156932 -80.500641)
			(xy 332.206675 -80.477801) (xy 332.259172 -80.462305) (xy 332.313344 -80.45447) (xy 332.340712 -80.453992)
			(xy 332.367963 -80.454479) (xy 332.421909 -80.462237) (xy 332.474202 -80.477593) (xy 332.523778 -80.500235)
			(xy 332.569627 -80.529701) (xy 332.610816 -80.565393) (xy 332.646506 -80.606583) (xy 332.675971 -80.652432)
			(xy 332.698612 -80.702009) (xy 332.713966 -80.754303) (xy 332.721722 -80.808249) (xy 332.721722 -80.8228)
			(xy 377.396754 -80.8228) (xy 377.400825 -80.767178) (xy 377.412951 -80.712741) (xy 377.432874 -80.66065)
			(xy 377.46017 -80.612015) (xy 377.494256 -80.567872) (xy 377.534405 -80.529163) (xy 377.579763 -80.496712)
			(xy 377.629363 -80.471211) (xy 377.682147 -80.453204) (xy 377.73699 -80.443074) (xy 377.792724 -80.441037)
			(xy 377.848161 -80.447137) (xy 377.902118 -80.461243) (xy 377.953447 -80.483055) (xy 378.001053 -80.512109)
			(xy 378.043921 -80.547784) (xy 378.081138 -80.589321) (xy 378.111911 -80.635834) (xy 378.116208 -80.645)
			(xy 380.871982 -80.645) (xy 380.876053 -80.589378) (xy 380.888179 -80.534941) (xy 380.908102 -80.48285)
			(xy 380.935398 -80.434215) (xy 380.969484 -80.390072) (xy 381.009633 -80.351363) (xy 381.054991 -80.318912)
			(xy 381.104591 -80.293411) (xy 381.157375 -80.275404) (xy 381.212218 -80.265274) (xy 381.267952 -80.263237)
			(xy 381.323389 -80.269337) (xy 381.377346 -80.283443) (xy 381.428675 -80.305255) (xy 381.476281 -80.334309)
			(xy 381.519149 -80.369984) (xy 381.556366 -80.411521) (xy 381.587139 -80.458034) (xy 381.610811 -80.508531)
			(xy 381.626879 -80.561938) (xy 381.634999 -80.617114) (xy 381.635508 -80.645) (xy 381.634999 -80.672886)
			(xy 381.626879 -80.728062) (xy 381.610811 -80.781469) (xy 381.587139 -80.831966) (xy 381.556366 -80.878479)
			(xy 381.519149 -80.920016) (xy 381.476281 -80.955691) (xy 381.428675 -80.984745) (xy 381.377346 -81.006557)
			(xy 381.323389 -81.020663) (xy 381.267952 -81.026763) (xy 381.212218 -81.024726) (xy 381.157375 -81.014596)
			(xy 381.104591 -80.996589) (xy 381.054991 -80.971088) (xy 381.009633 -80.938637) (xy 380.969484 -80.899928)
			(xy 380.935398 -80.855785) (xy 380.908102 -80.80715) (xy 380.888179 -80.755059) (xy 380.876053 -80.700622)
			(xy 380.871982 -80.645) (xy 378.116208 -80.645) (xy 378.135583 -80.686331) (xy 378.151651 -80.739738)
			(xy 378.159771 -80.794914) (xy 378.16028 -80.8228) (xy 378.159771 -80.850686) (xy 378.151651 -80.905862)
			(xy 378.135583 -80.959269) (xy 378.111911 -81.009766) (xy 378.081138 -81.056279) (xy 378.043921 -81.097816)
			(xy 378.001053 -81.133491) (xy 377.953447 -81.162545) (xy 377.902118 -81.184357) (xy 377.848161 -81.198463)
			(xy 377.792724 -81.204563) (xy 377.73699 -81.202526) (xy 377.682147 -81.192396) (xy 377.629363 -81.174389)
			(xy 377.579763 -81.148888) (xy 377.534405 -81.116437) (xy 377.494256 -81.077728) (xy 377.46017 -81.033585)
			(xy 377.432874 -80.98495) (xy 377.412951 -80.932859) (xy 377.400825 -80.878422) (xy 377.396754 -80.8228)
			(xy 332.721722 -80.8228) (xy 332.721722 -80.862751) (xy 332.713966 -80.916697) (xy 332.698612 -80.968991)
			(xy 332.675971 -81.018568) (xy 332.646506 -81.064417) (xy 332.610816 -81.105607) (xy 332.569627 -81.141299)
			(xy 332.523778 -81.170765) (xy 332.474202 -81.193407) (xy 332.421909 -81.208763) (xy 332.367963 -81.216521)
			(xy 332.340712 -81.217008) (xy 332.313342 -81.216533) (xy 332.259164 -81.208717) (xy 332.206661 -81.19323)
			(xy 332.156914 -81.17039) (xy 332.110946 -81.140668) (xy 332.090014 -81.123028) (xy 332.08976 -81.122774)
			(xy 332.082663 -81.117204) (xy 332.065754 -81.110948) (xy 332.05674 -81.110582) (xy 331.989684 -81.110582)
			(xy 331.980667 -81.110935) (xy 331.96375 -81.117186) (xy 331.956664 -81.122774) (xy 331.956664 -81.123028)
			(xy 331.95641 -81.123028) (xy 331.935489 -81.14068) (xy 331.889512 -81.170389) (xy 331.839762 -81.193222)
			(xy 331.787259 -81.20871) (xy 331.733082 -81.216535) (xy 331.705712 -81.217008) (xy 331.678459 -81.216545)
			(xy 331.624506 -81.20879) (xy 331.572207 -81.193435) (xy 331.522625 -81.170793) (xy 331.476771 -81.141325)
			(xy 331.435577 -81.105632) (xy 331.399882 -81.064439) (xy 331.370413 -81.018585) (xy 331.347769 -80.969004)
			(xy 331.332413 -80.916705) (xy 331.324655 -80.862753) (xy 330.450204 -80.862753) (xy 329.894946 -81.163922)
			(xy 329.891694 -81.165761) (xy 329.885705 -81.170227) (xy 329.883008 -81.172812) (xy 329.02271 -82.03311)
			(xy 329.019187 -82.036839) (xy 329.013554 -82.045412) (xy 329.011534 -82.050128) (xy 329.007978 -82.058764)
			(xy 329.007978 -82.09407) (xy 329.008148 -82.100223) (xy 329.011104 -82.112168) (xy 329.01382 -82.117692)
			(xy 329.02755 -82.145209) (xy 329.04701 -82.203542) (xy 329.056877 -82.264238) (xy 329.057508 -82.294984)
			(xy 329.057508 -82.304128) (xy 329.056463 -82.33114) (xy 329.047696 -82.384481) (xy 329.031489 -82.436051)
			(xy 329.008166 -82.484818) (xy 328.978195 -82.529805) (xy 328.942175 -82.570112) (xy 328.900827 -82.604933)
			(xy 328.854979 -82.63357) (xy 328.805548 -82.65545) (xy 328.753524 -82.670135) (xy 328.7268 -82.674206)
			(xy 328.714159 -82.675772) (xy 328.688738 -82.677425) (xy 328.676 -82.677508) (xy 328.675746 -82.677508)
			(xy 328.648438 -82.677004) (xy 328.594389 -82.669149) (xy 328.542009 -82.653679) (xy 328.516996 -82.64271)
			(xy 328.512424 -82.640678) (xy 328.499978 -82.63763) (xy 328.492612 -82.636868) (xy 328.492104 -82.636868)
			(xy 328.482952 -82.636874) (xy 328.465581 -82.642595) (xy 328.451337 -82.654065) (xy 328.446384 -82.66176)
			(xy 328.27357 -82.979768) (xy 330.579982 -82.979768) (xy 330.584053 -82.924146) (xy 330.596179 -82.869709)
			(xy 330.616102 -82.817618) (xy 330.643398 -82.768983) (xy 330.677484 -82.72484) (xy 330.717633 -82.686131)
			(xy 330.762991 -82.65368) (xy 330.812591 -82.628179) (xy 330.865375 -82.610172) (xy 330.920218 -82.600042)
			(xy 330.975952 -82.598005) (xy 331.031389 -82.604105) (xy 331.085346 -82.618211) (xy 331.136675 -82.640023)
			(xy 331.184281 -82.669077) (xy 331.227149 -82.704752) (xy 331.264366 -82.746289) (xy 331.295139 -82.792802)
			(xy 331.318811 -82.843299) (xy 331.334879 -82.896706) (xy 331.342999 -82.951882) (xy 331.343508 -82.979768)
			(xy 331.342999 -83.007654) (xy 331.334879 -83.06283) (xy 331.318811 -83.116237) (xy 331.295139 -83.166734)
			(xy 331.264366 -83.213247) (xy 331.227149 -83.254784) (xy 331.184281 -83.290459) (xy 331.136675 -83.319513)
			(xy 331.085346 -83.341325) (xy 331.031389 -83.355431) (xy 330.975952 -83.361531) (xy 330.920218 -83.359494)
			(xy 330.865375 -83.349364) (xy 330.812591 -83.331357) (xy 330.762991 -83.305856) (xy 330.717633 -83.273405)
			(xy 330.677484 -83.234696) (xy 330.643398 -83.190553) (xy 330.616102 -83.141918) (xy 330.596179 -83.089827)
			(xy 330.584053 -83.03539) (xy 330.579982 -82.979768) (xy 328.27357 -82.979768) (xy 328.266806 -82.992214)
			(xy 328.174096 -83.162648) (xy 327.843388 -83.771994) (xy 327.841197 -83.776991) (xy 327.838755 -83.787623)
			(xy 327.838562 -83.793076) (xy 327.838562 -83.822794) (xy 327.84288 -83.8327) (xy 327.853062 -83.856982)
			(xy 327.867419 -83.907641) (xy 327.874692 -83.95979) (xy 327.875138 -83.986116) (xy 327.875138 -83.991196)
			(xy 327.87432 -84.018312) (xy 327.86596 -84.071913) (xy 327.85009 -84.123789) (xy 327.827032 -84.172893)
			(xy 327.797249 -84.218235) (xy 327.761343 -84.258901) (xy 327.720039 -84.29407) (xy 327.674168 -84.323032)
			(xy 327.624657 -84.345204) (xy 327.572504 -84.360137) (xy 327.5457 -84.364322) (xy 327.545192 -84.364322)
			(xy 327.542398 -84.36483) (xy 327.531444 -84.367558) (xy 327.513234 -84.380855) (xy 327.507346 -84.390484)
			(xy 327.127235 -85.09) (xy 327.912982 -85.09) (xy 327.917053 -85.034378) (xy 327.929179 -84.979941)
			(xy 327.949102 -84.92785) (xy 327.976398 -84.879215) (xy 328.010484 -84.835072) (xy 328.050633 -84.796363)
			(xy 328.095991 -84.763912) (xy 328.145591 -84.738411) (xy 328.198375 -84.720404) (xy 328.253218 -84.710274)
			(xy 328.308952 -84.708237) (xy 328.364389 -84.714337) (xy 328.418346 -84.728443) (xy 328.469675 -84.750255)
			(xy 328.517281 -84.779309) (xy 328.560149 -84.814984) (xy 328.597366 -84.856521) (xy 328.628139 -84.903034)
			(xy 328.651811 -84.953531) (xy 328.667879 -85.006938) (xy 328.675999 -85.062114) (xy 328.676508 -85.09)
			(xy 328.675999 -85.117886) (xy 328.667879 -85.173062) (xy 328.651811 -85.226469) (xy 328.628139 -85.276966)
			(xy 328.597366 -85.323479) (xy 328.560149 -85.365016) (xy 328.517281 -85.400691) (xy 328.469675 -85.429745)
			(xy 328.418346 -85.451557) (xy 328.364389 -85.465663) (xy 328.308952 -85.471763) (xy 328.253218 -85.469726)
			(xy 328.198375 -85.459596) (xy 328.145591 -85.441589) (xy 328.095991 -85.416088) (xy 328.050633 -85.383637)
			(xy 328.010484 -85.344928) (xy 327.976398 -85.300785) (xy 327.949102 -85.25215) (xy 327.929179 -85.200059)
			(xy 327.917053 -85.145622) (xy 327.912982 -85.09) (xy 327.127235 -85.09) (xy 326.64416 -85.979) (xy 328.039982 -85.979)
			(xy 328.044053 -85.923378) (xy 328.056179 -85.868941) (xy 328.076102 -85.81685) (xy 328.103398 -85.768215)
			(xy 328.137484 -85.724072) (xy 328.177633 -85.685363) (xy 328.222991 -85.652912) (xy 328.272591 -85.627411)
			(xy 328.325375 -85.609404) (xy 328.380218 -85.599274) (xy 328.435952 -85.597237) (xy 328.491389 -85.603337)
			(xy 328.545346 -85.617443) (xy 328.596675 -85.639255) (xy 328.644281 -85.668309) (xy 328.687149 -85.703984)
			(xy 328.724366 -85.745521) (xy 328.755139 -85.792034) (xy 328.778811 -85.842531) (xy 328.794879 -85.895938)
			(xy 328.802999 -85.951114) (xy 328.803508 -85.979) (xy 328.802999 -86.006886) (xy 328.794879 -86.062062)
			(xy 328.778811 -86.115469) (xy 328.755139 -86.165966) (xy 328.724366 -86.212479) (xy 328.687149 -86.254016)
			(xy 328.644281 -86.289691) (xy 328.596675 -86.318745) (xy 328.545346 -86.340557) (xy 328.491389 -86.354663)
			(xy 328.435952 -86.360763) (xy 328.380218 -86.358726) (xy 328.325375 -86.348596) (xy 328.272591 -86.330589)
			(xy 328.222991 -86.305088) (xy 328.177633 -86.272637) (xy 328.137484 -86.233928) (xy 328.103398 -86.189785)
			(xy 328.076102 -86.14115) (xy 328.056179 -86.089059) (xy 328.044053 -86.034622) (xy 328.039982 -85.979)
			(xy 326.64416 -85.979) (xy 324.308286 -90.277696) (xy 328.159872 -90.277696) (xy 328.159872 -89.302082)
			(xy 328.160397 -89.277209) (xy 328.168471 -89.228122) (xy 328.1844 -89.180995) (xy 328.207765 -89.137077)
			(xy 328.237945 -89.097532) (xy 328.27414 -89.063406) (xy 328.294492 -89.049098) (xy 328.329544 -89.025476)
			(xy 328.340466 -88.993218) (xy 328.334878 -88.976708) (xy 328.325487 -88.946978) (xy 328.315409 -88.885453)
			(xy 328.314812 -88.85428) (xy 328.315397 -88.823106) (xy 328.325481 -88.761581) (xy 328.334878 -88.731852)
			(xy 328.340466 -88.715342) (xy 328.329544 -88.683084) (xy 328.294492 -88.659462) (xy 328.274123 -88.645174)
			(xy 328.237919 -88.61105) (xy 328.207732 -88.571502) (xy 328.184363 -88.52758) (xy 328.168433 -88.480447)
			(xy 328.160362 -88.431354) (xy 328.159872 -88.406478) (xy 328.159872 -87.43315) (xy 328.160282 -87.409177)
			(xy 328.167786 -87.361821) (xy 328.182618 -87.316227) (xy 328.204411 -87.273519) (xy 328.232626 -87.234754)
			(xy 328.24928 -87.217504) (xy 330.867512 -84.599526) (xy 330.873285 -84.593237) (xy 330.880715 -84.57788)
			(xy 330.88273 -84.560939) (xy 330.881228 -84.552536) (xy 330.86294 -84.46897) (xy 330.860769 -84.460742)
			(xy 330.851905 -84.446232) (xy 330.83879 -84.43541) (xy 330.830936 -84.43214) (xy 330.830682 -84.43214)
			(xy 330.803563 -84.421606) (xy 330.752612 -84.393529) (xy 330.706516 -84.358041) (xy 330.666343 -84.315964)
			(xy 330.633027 -84.268275) (xy 330.607338 -84.216079) (xy 330.589875 -84.160587) (xy 330.58104 -84.103087)
			(xy 330.580492 -84.074) (xy 330.580978 -84.046749) (xy 330.588734 -83.992801) (xy 330.604089 -83.940506)
			(xy 330.626731 -83.890929) (xy 330.656197 -83.845079) (xy 330.691888 -83.803888) (xy 330.733079 -83.768197)
			(xy 330.778929 -83.738731) (xy 330.828506 -83.716089) (xy 330.880801 -83.700734) (xy 330.934749 -83.692978)
			(xy 330.962 -83.692492) (xy 330.991085 -83.69307) (xy 331.048579 -83.701914) (xy 331.104064 -83.719382)
			(xy 331.156255 -83.745069) (xy 331.203943 -83.77838) (xy 331.246023 -83.818543) (xy 331.281519 -83.864627)
			(xy 331.30961 -83.915565) (xy 331.32014 -83.942682) (xy 331.32014 -83.942936) (xy 331.323416 -83.950791)
			(xy 331.334224 -83.963925) (xy 331.348732 -83.972806) (xy 331.35697 -83.97494) (xy 331.440536 -83.993228)
			(xy 331.448943 -83.994787) (xy 331.465918 -83.992831) (xy 331.481281 -83.985352) (xy 331.487526 -83.979512)
			(xy 334.095344 -81.37144) (xy 334.112645 -81.354851) (xy 334.151423 -81.326684) (xy 334.194122 -81.304914)
			(xy 334.239696 -81.290075) (xy 334.287026 -81.282531) (xy 334.31099 -81.282032) (xy 338.0613 -81.282032)
			(xy 338.086396 -81.282574) (xy 338.135901 -81.290866) (xy 338.183382 -81.307145) (xy 338.227561 -81.330972)
			(xy 338.267246 -81.361705) (xy 338.30137 -81.398516) (xy 338.329012 -81.440413) (xy 338.339684 -81.463134)
			(xy 338.339684 -81.463388) (xy 338.372704 -81.537556) (xy 338.37709 -81.54634) (xy 338.391193 -81.559976)
			(xy 338.409378 -81.567333) (xy 338.419186 -81.567782) (xy 338.428992 -81.567292) (xy 338.447181 -81.559963)
			(xy 338.461283 -81.546337) (xy 338.465668 -81.537556) (xy 338.498688 -81.463388) (xy 338.498688 -81.463134)
			(xy 338.509311 -81.440384) (xy 338.536931 -81.398457) (xy 338.57105 -81.361623) (xy 338.610744 -81.33088)
			(xy 338.654941 -81.307059) (xy 338.702444 -81.290804) (xy 338.751969 -81.282554) (xy 338.777072 -81.282032)
			(xy 341.236808 -81.282032) (xy 341.26078 -81.28248) (xy 341.308133 -81.289977) (xy 341.353726 -81.3048)
			(xy 341.396434 -81.326584) (xy 341.435202 -81.35479) (xy 341.452454 -81.37144) (xy 341.582248 -81.501234)
			(xy 351.221292 -81.501234) (xy 351.225363 -81.445612) (xy 351.237489 -81.391175) (xy 351.257412 -81.339084)
			(xy 351.284708 -81.290449) (xy 351.318794 -81.246306) (xy 351.358943 -81.207597) (xy 351.404301 -81.175146)
			(xy 351.453901 -81.149645) (xy 351.506685 -81.131638) (xy 351.561528 -81.121508) (xy 351.617262 -81.119471)
			(xy 351.672699 -81.125571) (xy 351.726656 -81.139677) (xy 351.777985 -81.161489) (xy 351.825591 -81.190543)
			(xy 351.868459 -81.226218) (xy 351.905676 -81.267755) (xy 351.936449 -81.314268) (xy 351.960121 -81.364765)
			(xy 351.975044 -81.414366) (xy 354.132386 -81.414366) (xy 354.136457 -81.358744) (xy 354.148583 -81.304307)
			(xy 354.168506 -81.252216) (xy 354.195802 -81.203581) (xy 354.229888 -81.159438) (xy 354.270037 -81.120729)
			(xy 354.315395 -81.088278) (xy 354.364995 -81.062777) (xy 354.417779 -81.04477) (xy 354.472622 -81.03464)
			(xy 354.528356 -81.032603) (xy 354.583793 -81.038703) (xy 354.63775 -81.052809) (xy 354.689079 -81.074621)
			(xy 354.736685 -81.103675) (xy 354.779553 -81.13935) (xy 354.81677 -81.180887) (xy 354.847543 -81.2274)
			(xy 354.871215 -81.277897) (xy 354.887283 -81.331304) (xy 354.895403 -81.38648) (xy 354.895912 -81.414366)
			(xy 354.895403 -81.442252) (xy 354.887283 -81.497428) (xy 354.886902 -81.498694) (xy 364.632238 -81.498694)
			(xy 364.636309 -81.443072) (xy 364.648435 -81.388635) (xy 364.668358 -81.336544) (xy 364.695654 -81.287909)
			(xy 364.72974 -81.243766) (xy 364.769889 -81.205057) (xy 364.815247 -81.172606) (xy 364.864847 -81.147105)
			(xy 364.917631 -81.129098) (xy 364.972474 -81.118968) (xy 365.028208 -81.116931) (xy 365.083645 -81.123031)
			(xy 365.137602 -81.137137) (xy 365.188931 -81.158949) (xy 365.236537 -81.188003) (xy 365.279405 -81.223678)
			(xy 365.316622 -81.265215) (xy 365.347395 -81.311728) (xy 365.371067 -81.362225) (xy 365.387135 -81.415632)
			(xy 365.395255 -81.470808) (xy 365.395764 -81.498694) (xy 367.679222 -81.498694) (xy 367.683293 -81.443072)
			(xy 367.695419 -81.388635) (xy 367.715342 -81.336544) (xy 367.742638 -81.287909) (xy 367.776724 -81.243766)
			(xy 367.816873 -81.205057) (xy 367.862231 -81.172606) (xy 367.911831 -81.147105) (xy 367.964615 -81.129098)
			(xy 368.019458 -81.118968) (xy 368.075192 -81.116931) (xy 368.130629 -81.123031) (xy 368.184586 -81.137137)
			(xy 368.235915 -81.158949) (xy 368.283521 -81.188003) (xy 368.326389 -81.223678) (xy 368.363606 -81.265215)
			(xy 368.394379 -81.311728) (xy 368.418051 -81.362225) (xy 368.434119 -81.415632) (xy 368.442239 -81.470808)
			(xy 368.442748 -81.498694) (xy 370.219222 -81.498694) (xy 370.223293 -81.443072) (xy 370.235419 -81.388635)
			(xy 370.255342 -81.336544) (xy 370.282638 -81.287909) (xy 370.316724 -81.243766) (xy 370.356873 -81.205057)
			(xy 370.402231 -81.172606) (xy 370.451831 -81.147105) (xy 370.504615 -81.129098) (xy 370.559458 -81.118968)
			(xy 370.615192 -81.116931) (xy 370.670629 -81.123031) (xy 370.724586 -81.137137) (xy 370.775915 -81.158949)
			(xy 370.823521 -81.188003) (xy 370.866389 -81.223678) (xy 370.903606 -81.265215) (xy 370.934379 -81.311728)
			(xy 370.958051 -81.362225) (xy 370.974119 -81.415632) (xy 370.982239 -81.470808) (xy 370.982748 -81.498694)
			(xy 370.982239 -81.52658) (xy 370.981147 -81.534) (xy 380.998982 -81.534) (xy 381.003053 -81.478378)
			(xy 381.015179 -81.423941) (xy 381.035102 -81.37185) (xy 381.062398 -81.323215) (xy 381.096484 -81.279072)
			(xy 381.136633 -81.240363) (xy 381.181991 -81.207912) (xy 381.231591 -81.182411) (xy 381.284375 -81.164404)
			(xy 381.339218 -81.154274) (xy 381.394952 -81.152237) (xy 381.450389 -81.158337) (xy 381.504346 -81.172443)
			(xy 381.555675 -81.194255) (xy 381.603281 -81.223309) (xy 381.646149 -81.258984) (xy 381.683366 -81.300521)
			(xy 381.714139 -81.347034) (xy 381.737811 -81.397531) (xy 381.753879 -81.450938) (xy 381.761999 -81.506114)
			(xy 381.762508 -81.534) (xy 381.761999 -81.561886) (xy 381.753879 -81.617062) (xy 381.737811 -81.670469)
			(xy 381.714139 -81.720966) (xy 381.683366 -81.767479) (xy 381.646149 -81.809016) (xy 381.603281 -81.844691)
			(xy 381.555675 -81.873745) (xy 381.504346 -81.895557) (xy 381.450389 -81.909663) (xy 381.394952 -81.915763)
			(xy 381.339218 -81.913726) (xy 381.284375 -81.903596) (xy 381.231591 -81.885589) (xy 381.181991 -81.860088)
			(xy 381.136633 -81.827637) (xy 381.096484 -81.788928) (xy 381.062398 -81.744785) (xy 381.035102 -81.69615)
			(xy 381.015179 -81.644059) (xy 381.003053 -81.589622) (xy 380.998982 -81.534) (xy 370.981147 -81.534)
			(xy 370.974119 -81.581756) (xy 370.958051 -81.635163) (xy 370.934379 -81.68566) (xy 370.903606 -81.732173)
			(xy 370.866389 -81.77371) (xy 370.823521 -81.809385) (xy 370.775915 -81.838439) (xy 370.724586 -81.860251)
			(xy 370.670629 -81.874357) (xy 370.615192 -81.880457) (xy 370.559458 -81.87842) (xy 370.504615 -81.86829)
			(xy 370.451831 -81.850283) (xy 370.402231 -81.824782) (xy 370.356873 -81.792331) (xy 370.316724 -81.753622)
			(xy 370.282638 -81.709479) (xy 370.255342 -81.660844) (xy 370.235419 -81.608753) (xy 370.223293 -81.554316)
			(xy 370.219222 -81.498694) (xy 368.442748 -81.498694) (xy 368.442239 -81.52658) (xy 368.434119 -81.581756)
			(xy 368.418051 -81.635163) (xy 368.394379 -81.68566) (xy 368.363606 -81.732173) (xy 368.326389 -81.77371)
			(xy 368.283521 -81.809385) (xy 368.235915 -81.838439) (xy 368.184586 -81.860251) (xy 368.130629 -81.874357)
			(xy 368.075192 -81.880457) (xy 368.019458 -81.87842) (xy 367.964615 -81.86829) (xy 367.911831 -81.850283)
			(xy 367.862231 -81.824782) (xy 367.816873 -81.792331) (xy 367.776724 -81.753622) (xy 367.742638 -81.709479)
			(xy 367.715342 -81.660844) (xy 367.695419 -81.608753) (xy 367.683293 -81.554316) (xy 367.679222 -81.498694)
			(xy 365.395764 -81.498694) (xy 365.395255 -81.52658) (xy 365.387135 -81.581756) (xy 365.371067 -81.635163)
			(xy 365.347395 -81.68566) (xy 365.316622 -81.732173) (xy 365.279405 -81.77371) (xy 365.236537 -81.809385)
			(xy 365.188931 -81.838439) (xy 365.137602 -81.860251) (xy 365.083645 -81.874357) (xy 365.028208 -81.880457)
			(xy 364.972474 -81.87842) (xy 364.917631 -81.86829) (xy 364.864847 -81.850283) (xy 364.815247 -81.824782)
			(xy 364.769889 -81.792331) (xy 364.72974 -81.753622) (xy 364.695654 -81.709479) (xy 364.668358 -81.660844)
			(xy 364.648435 -81.608753) (xy 364.636309 -81.554316) (xy 364.632238 -81.498694) (xy 354.886902 -81.498694)
			(xy 354.871215 -81.550835) (xy 354.847543 -81.601332) (xy 354.81677 -81.647845) (xy 354.779553 -81.689382)
			(xy 354.736685 -81.725057) (xy 354.689079 -81.754111) (xy 354.63775 -81.775923) (xy 354.583793 -81.790029)
			(xy 354.528356 -81.796129) (xy 354.472622 -81.794092) (xy 354.417779 -81.783962) (xy 354.364995 -81.765955)
			(xy 354.315395 -81.740454) (xy 354.270037 -81.708003) (xy 354.229888 -81.669294) (xy 354.195802 -81.625151)
			(xy 354.168506 -81.576516) (xy 354.148583 -81.524425) (xy 354.136457 -81.469988) (xy 354.132386 -81.414366)
			(xy 351.975044 -81.414366) (xy 351.976189 -81.418172) (xy 351.984309 -81.473348) (xy 351.984818 -81.501234)
			(xy 351.984309 -81.52912) (xy 351.976189 -81.584296) (xy 351.960121 -81.637703) (xy 351.936449 -81.6882)
			(xy 351.905676 -81.734713) (xy 351.868459 -81.77625) (xy 351.825591 -81.811925) (xy 351.777985 -81.840979)
			(xy 351.726656 -81.862791) (xy 351.672699 -81.876897) (xy 351.617262 -81.882997) (xy 351.561528 -81.88096)
			(xy 351.506685 -81.87083) (xy 351.453901 -81.852823) (xy 351.404301 -81.827322) (xy 351.358943 -81.794871)
			(xy 351.318794 -81.756162) (xy 351.284708 -81.712019) (xy 351.257412 -81.663384) (xy 351.237489 -81.611293)
			(xy 351.225363 -81.556856) (xy 351.221292 -81.501234) (xy 341.582248 -81.501234) (xy 341.877904 -81.79689)
			(xy 341.88713 -81.805062) (xy 341.910629 -81.812362) (xy 341.922862 -81.81086) (xy 342.01735 -81.793842)
			(xy 342.036908 -81.778602) (xy 342.041988 -81.767172) (xy 342.053691 -81.742492) (xy 342.083142 -81.696491)
			(xy 342.118852 -81.65516) (xy 342.160089 -81.619342) (xy 342.206012 -81.58977) (xy 342.255683 -81.567048)
			(xy 342.308085 -81.55164) (xy 342.362149 -81.54386) (xy 342.38946 -81.543398) (xy 342.416712 -81.543893)
			(xy 342.470662 -81.551644) (xy 342.52296 -81.566995) (xy 342.57254 -81.589634) (xy 342.618394 -81.619098)
			(xy 342.659587 -81.654789) (xy 342.695281 -81.695979) (xy 342.72475 -81.74183) (xy 342.747393 -81.791408)
			(xy 342.762749 -81.843704) (xy 342.769457 -81.890362) (xy 355.959916 -81.890362) (xy 355.963987 -81.83474)
			(xy 355.976113 -81.780303) (xy 355.996036 -81.728212) (xy 356.023332 -81.679577) (xy 356.057418 -81.635434)
			(xy 356.097567 -81.596725) (xy 356.142925 -81.564274) (xy 356.192525 -81.538773) (xy 356.245309 -81.520766)
			(xy 356.300152 -81.510636) (xy 356.355886 -81.508599) (xy 356.411323 -81.514699) (xy 356.46528 -81.528805)
			(xy 356.516609 -81.550617) (xy 356.564215 -81.579671) (xy 356.607083 -81.615346) (xy 356.6443 -81.656883)
			(xy 356.675073 -81.703396) (xy 356.698745 -81.753893) (xy 356.714813 -81.8073) (xy 356.722933 -81.862476)
			(xy 356.723442 -81.890362) (xy 356.722933 -81.918248) (xy 356.715935 -81.9658) (xy 374.915428 -81.9658)
			(xy 374.919499 -81.910178) (xy 374.931625 -81.855741) (xy 374.951548 -81.80365) (xy 374.978844 -81.755015)
			(xy 375.01293 -81.710872) (xy 375.053079 -81.672163) (xy 375.098437 -81.639712) (xy 375.148037 -81.614211)
			(xy 375.200821 -81.596204) (xy 375.255664 -81.586074) (xy 375.311398 -81.584037) (xy 375.366835 -81.590137)
			(xy 375.420792 -81.604243) (xy 375.472121 -81.626055) (xy 375.519727 -81.655109) (xy 375.562595 -81.690784)
			(xy 375.599812 -81.732321) (xy 375.630585 -81.778834) (xy 375.654257 -81.829331) (xy 375.670325 -81.882738)
			(xy 375.678445 -81.937914) (xy 375.678954 -81.9658) (xy 377.153422 -81.9658) (xy 377.157493 -81.910178)
			(xy 377.169619 -81.855741) (xy 377.189542 -81.80365) (xy 377.216838 -81.755015) (xy 377.250924 -81.710872)
			(xy 377.291073 -81.672163) (xy 377.336431 -81.639712) (xy 377.386031 -81.614211) (xy 377.438815 -81.596204)
			(xy 377.493658 -81.586074) (xy 377.549392 -81.584037) (xy 377.604829 -81.590137) (xy 377.658786 -81.604243)
			(xy 377.710115 -81.626055) (xy 377.757721 -81.655109) (xy 377.800589 -81.690784) (xy 377.837806 -81.732321)
			(xy 377.868579 -81.778834) (xy 377.892251 -81.829331) (xy 377.908319 -81.882738) (xy 377.916439 -81.937914)
			(xy 377.916948 -81.9658) (xy 379.501652 -81.9658) (xy 379.505723 -81.910178) (xy 379.517849 -81.855741)
			(xy 379.537772 -81.80365) (xy 379.565068 -81.755015) (xy 379.599154 -81.710872) (xy 379.639303 -81.672163)
			(xy 379.684661 -81.639712) (xy 379.734261 -81.614211) (xy 379.787045 -81.596204) (xy 379.841888 -81.586074)
			(xy 379.897622 -81.584037) (xy 379.953059 -81.590137) (xy 380.007016 -81.604243) (xy 380.058345 -81.626055)
			(xy 380.105951 -81.655109) (xy 380.148819 -81.690784) (xy 380.186036 -81.732321) (xy 380.216809 -81.778834)
			(xy 380.240481 -81.829331) (xy 380.256549 -81.882738) (xy 380.264669 -81.937914) (xy 380.265178 -81.9658)
			(xy 380.264669 -81.993686) (xy 380.256549 -82.048862) (xy 380.240481 -82.102269) (xy 380.216809 -82.152766)
			(xy 380.186036 -82.199279) (xy 380.148819 -82.240816) (xy 380.105951 -82.276491) (xy 380.058345 -82.305545)
			(xy 380.007016 -82.327357) (xy 379.953059 -82.341463) (xy 379.897622 -82.347563) (xy 379.841888 -82.345526)
			(xy 379.787045 -82.335396) (xy 379.734261 -82.317389) (xy 379.684661 -82.291888) (xy 379.639303 -82.259437)
			(xy 379.599154 -82.220728) (xy 379.565068 -82.176585) (xy 379.537772 -82.12795) (xy 379.517849 -82.075859)
			(xy 379.505723 -82.021422) (xy 379.501652 -81.9658) (xy 377.916948 -81.9658) (xy 377.916439 -81.993686)
			(xy 377.908319 -82.048862) (xy 377.892251 -82.102269) (xy 377.868579 -82.152766) (xy 377.837806 -82.199279)
			(xy 377.800589 -82.240816) (xy 377.757721 -82.276491) (xy 377.710115 -82.305545) (xy 377.658786 -82.327357)
			(xy 377.604829 -82.341463) (xy 377.549392 -82.347563) (xy 377.493658 -82.345526) (xy 377.438815 -82.335396)
			(xy 377.386031 -82.317389) (xy 377.336431 -82.291888) (xy 377.291073 -82.259437) (xy 377.250924 -82.220728)
			(xy 377.216838 -82.176585) (xy 377.189542 -82.12795) (xy 377.169619 -82.075859) (xy 377.157493 -82.021422)
			(xy 377.153422 -81.9658) (xy 375.678954 -81.9658) (xy 375.678445 -81.993686) (xy 375.670325 -82.048862)
			(xy 375.654257 -82.102269) (xy 375.630585 -82.152766) (xy 375.599812 -82.199279) (xy 375.562595 -82.240816)
			(xy 375.519727 -82.276491) (xy 375.472121 -82.305545) (xy 375.420792 -82.327357) (xy 375.366835 -82.341463)
			(xy 375.311398 -82.347563) (xy 375.255664 -82.345526) (xy 375.200821 -82.335396) (xy 375.148037 -82.317389)
			(xy 375.098437 -82.291888) (xy 375.053079 -82.259437) (xy 375.01293 -82.220728) (xy 374.978844 -82.176585)
			(xy 374.951548 -82.12795) (xy 374.931625 -82.075859) (xy 374.919499 -82.021422) (xy 374.915428 -81.9658)
			(xy 356.715935 -81.9658) (xy 356.714813 -81.973424) (xy 356.698745 -82.026831) (xy 356.675073 -82.077328)
			(xy 356.6443 -82.123841) (xy 356.607083 -82.165378) (xy 356.564215 -82.201053) (xy 356.516609 -82.230107)
			(xy 356.46528 -82.251919) (xy 356.411323 -82.266025) (xy 356.355886 -82.272125) (xy 356.300152 -82.270088)
			(xy 356.245309 -82.259958) (xy 356.192525 -82.241951) (xy 356.142925 -82.21645) (xy 356.097567 -82.183999)
			(xy 356.057418 -82.14529) (xy 356.023332 -82.101147) (xy 355.996036 -82.052512) (xy 355.976113 -82.000421)
			(xy 355.963987 -81.945984) (xy 355.959916 -81.890362) (xy 342.769457 -81.890362) (xy 342.770505 -81.897654)
			(xy 342.770968 -81.924906) (xy 342.77047 -81.952212) (xy 342.762674 -82.006266) (xy 342.747257 -82.058658)
			(xy 342.724533 -82.108319) (xy 342.694966 -82.154235) (xy 342.659158 -82.195471) (xy 342.617841 -82.231185)
			(xy 342.571857 -82.260648) (xy 342.547194 -82.272378) (xy 342.535764 -82.277458) (xy 342.520524 -82.297016)
			(xy 342.503506 -82.391504) (xy 342.502059 -82.403735) (xy 342.509338 -82.42722) (xy 342.517476 -82.436462)
			(xy 342.725248 -82.644234) (xy 351.221292 -82.644234) (xy 351.225363 -82.588612) (xy 351.237489 -82.534175)
			(xy 351.257412 -82.482084) (xy 351.284708 -82.433449) (xy 351.318794 -82.389306) (xy 351.358943 -82.350597)
			(xy 351.404301 -82.318146) (xy 351.453901 -82.292645) (xy 351.506685 -82.274638) (xy 351.561528 -82.264508)
			(xy 351.617262 -82.262471) (xy 351.672699 -82.268571) (xy 351.726656 -82.282677) (xy 351.777985 -82.304489)
			(xy 351.825591 -82.333543) (xy 351.868459 -82.369218) (xy 351.905676 -82.410755) (xy 351.936449 -82.457268)
			(xy 351.960121 -82.507765) (xy 351.976189 -82.561172) (xy 351.984309 -82.616348) (xy 351.984818 -82.644234)
			(xy 351.984309 -82.67212) (xy 351.982507 -82.684366) (xy 354.092254 -82.684366) (xy 354.096325 -82.628744)
			(xy 354.108451 -82.574307) (xy 354.128374 -82.522216) (xy 354.15567 -82.473581) (xy 354.189756 -82.429438)
			(xy 354.229905 -82.390729) (xy 354.275263 -82.358278) (xy 354.324863 -82.332777) (xy 354.377647 -82.31477)
			(xy 354.43249 -82.30464) (xy 354.488224 -82.302603) (xy 354.543661 -82.308703) (xy 354.597618 -82.322809)
			(xy 354.648947 -82.344621) (xy 354.696553 -82.373675) (xy 354.739421 -82.40935) (xy 354.776638 -82.450887)
			(xy 354.807411 -82.4974) (xy 354.831083 -82.547897) (xy 354.847151 -82.601304) (xy 354.853095 -82.641694)
			(xy 363.896146 -82.641694) (xy 363.900217 -82.586072) (xy 363.912343 -82.531635) (xy 363.932266 -82.479544)
			(xy 363.959562 -82.430909) (xy 363.993648 -82.386766) (xy 364.033797 -82.348057) (xy 364.079155 -82.315606)
			(xy 364.128755 -82.290105) (xy 364.181539 -82.272098) (xy 364.236382 -82.261968) (xy 364.292116 -82.259931)
			(xy 364.347553 -82.266031) (xy 364.40151 -82.280137) (xy 364.452839 -82.301949) (xy 364.500445 -82.331003)
			(xy 364.543313 -82.366678) (xy 364.58053 -82.408215) (xy 364.611303 -82.454728) (xy 364.634975 -82.505225)
			(xy 364.651043 -82.558632) (xy 364.659163 -82.613808) (xy 364.659672 -82.641694) (xy 364.659163 -82.66958)
			(xy 364.651043 -82.724756) (xy 364.634975 -82.778163) (xy 364.611303 -82.82866) (xy 364.58053 -82.875173)
			(xy 364.543313 -82.91671) (xy 364.542013 -82.917792) (xy 367.650774 -82.917792) (xy 367.654845 -82.86217)
			(xy 367.666971 -82.807733) (xy 367.686894 -82.755642) (xy 367.71419 -82.707007) (xy 367.748276 -82.662864)
			(xy 367.788425 -82.624155) (xy 367.833783 -82.591704) (xy 367.883383 -82.566203) (xy 367.936167 -82.548196)
			(xy 367.99101 -82.538066) (xy 368.046744 -82.536029) (xy 368.102181 -82.542129) (xy 368.156138 -82.556235)
			(xy 368.207467 -82.578047) (xy 368.255073 -82.607101) (xy 368.296641 -82.641694) (xy 370.219222 -82.641694)
			(xy 370.223293 -82.586072) (xy 370.235419 -82.531635) (xy 370.255342 -82.479544) (xy 370.282638 -82.430909)
			(xy 370.316724 -82.386766) (xy 370.356873 -82.348057) (xy 370.402231 -82.315606) (xy 370.451831 -82.290105)
			(xy 370.504615 -82.272098) (xy 370.559458 -82.261968) (xy 370.615192 -82.259931) (xy 370.670629 -82.266031)
			(xy 370.724586 -82.280137) (xy 370.775915 -82.301949) (xy 370.823521 -82.331003) (xy 370.866389 -82.366678)
			(xy 370.903606 -82.408215) (xy 370.934379 -82.454728) (xy 370.958051 -82.505225) (xy 370.974119 -82.558632)
			(xy 370.982239 -82.613808) (xy 370.982748 -82.641694) (xy 370.982239 -82.66958) (xy 370.974119 -82.724756)
			(xy 370.958051 -82.778163) (xy 370.934379 -82.82866) (xy 370.903606 -82.875173) (xy 370.866389 -82.91671)
			(xy 370.823521 -82.952385) (xy 370.775915 -82.981439) (xy 370.724586 -83.003251) (xy 370.670629 -83.017357)
			(xy 370.615192 -83.023457) (xy 370.559458 -83.02142) (xy 370.504615 -83.01129) (xy 370.451831 -82.993283)
			(xy 370.402231 -82.967782) (xy 370.356873 -82.935331) (xy 370.316724 -82.896622) (xy 370.282638 -82.852479)
			(xy 370.255342 -82.803844) (xy 370.235419 -82.751753) (xy 370.223293 -82.697316) (xy 370.219222 -82.641694)
			(xy 368.296641 -82.641694) (xy 368.297941 -82.642776) (xy 368.335158 -82.684313) (xy 368.365931 -82.730826)
			(xy 368.389603 -82.781323) (xy 368.405671 -82.83473) (xy 368.413791 -82.889906) (xy 368.4143 -82.917792)
			(xy 368.413791 -82.945678) (xy 368.405671 -83.000854) (xy 368.389603 -83.054261) (xy 368.365931 -83.104758)
			(xy 368.363257 -83.1088) (xy 374.915428 -83.1088) (xy 374.919499 -83.053178) (xy 374.931625 -82.998741)
			(xy 374.951548 -82.94665) (xy 374.978844 -82.898015) (xy 375.01293 -82.853872) (xy 375.053079 -82.815163)
			(xy 375.098437 -82.782712) (xy 375.148037 -82.757211) (xy 375.200821 -82.739204) (xy 375.255664 -82.729074)
			(xy 375.311398 -82.727037) (xy 375.366835 -82.733137) (xy 375.420792 -82.747243) (xy 375.472121 -82.769055)
			(xy 375.519727 -82.798109) (xy 375.562595 -82.833784) (xy 375.599812 -82.875321) (xy 375.630585 -82.921834)
			(xy 375.654257 -82.972331) (xy 375.670325 -83.025738) (xy 375.678445 -83.080914) (xy 375.678954 -83.1088)
			(xy 377.280422 -83.1088) (xy 377.284493 -83.053178) (xy 377.296619 -82.998741) (xy 377.316542 -82.94665)
			(xy 377.343838 -82.898015) (xy 377.377924 -82.853872) (xy 377.418073 -82.815163) (xy 377.463431 -82.782712)
			(xy 377.513031 -82.757211) (xy 377.565815 -82.739204) (xy 377.620658 -82.729074) (xy 377.676392 -82.727037)
			(xy 377.731829 -82.733137) (xy 377.785786 -82.747243) (xy 377.837115 -82.769055) (xy 377.884721 -82.798109)
			(xy 377.927589 -82.833784) (xy 377.964806 -82.875321) (xy 377.995579 -82.921834) (xy 378.019251 -82.972331)
			(xy 378.035319 -83.025738) (xy 378.043439 -83.080914) (xy 378.043948 -83.1088) (xy 378.043439 -83.136686)
			(xy 378.035319 -83.191862) (xy 378.019251 -83.245269) (xy 377.995579 -83.295766) (xy 377.964806 -83.342279)
			(xy 377.927589 -83.383816) (xy 377.884721 -83.419491) (xy 377.837115 -83.448545) (xy 377.785786 -83.470357)
			(xy 377.731829 -83.484463) (xy 377.676392 -83.490563) (xy 377.620658 -83.488526) (xy 377.565815 -83.478396)
			(xy 377.513031 -83.460389) (xy 377.463431 -83.434888) (xy 377.418073 -83.402437) (xy 377.377924 -83.363728)
			(xy 377.343838 -83.319585) (xy 377.316542 -83.27095) (xy 377.296619 -83.218859) (xy 377.284493 -83.164422)
			(xy 377.280422 -83.1088) (xy 375.678954 -83.1088) (xy 375.678445 -83.136686) (xy 375.670325 -83.191862)
			(xy 375.654257 -83.245269) (xy 375.630585 -83.295766) (xy 375.599812 -83.342279) (xy 375.562595 -83.383816)
			(xy 375.519727 -83.419491) (xy 375.472121 -83.448545) (xy 375.420792 -83.470357) (xy 375.366835 -83.484463)
			(xy 375.311398 -83.490563) (xy 375.255664 -83.488526) (xy 375.200821 -83.478396) (xy 375.148037 -83.460389)
			(xy 375.098437 -83.434888) (xy 375.053079 -83.402437) (xy 375.01293 -83.363728) (xy 374.978844 -83.319585)
			(xy 374.951548 -83.27095) (xy 374.931625 -83.218859) (xy 374.919499 -83.164422) (xy 374.915428 -83.1088)
			(xy 368.363257 -83.1088) (xy 368.335158 -83.151271) (xy 368.297941 -83.192808) (xy 368.255073 -83.228483)
			(xy 368.207467 -83.257537) (xy 368.156138 -83.279349) (xy 368.102181 -83.293455) (xy 368.046744 -83.299555)
			(xy 367.99101 -83.297518) (xy 367.936167 -83.287388) (xy 367.883383 -83.269381) (xy 367.833783 -83.24388)
			(xy 367.788425 -83.211429) (xy 367.748276 -83.17272) (xy 367.71419 -83.128577) (xy 367.686894 -83.079942)
			(xy 367.666971 -83.027851) (xy 367.654845 -82.973414) (xy 367.650774 -82.917792) (xy 364.542013 -82.917792)
			(xy 364.500445 -82.952385) (xy 364.452839 -82.981439) (xy 364.40151 -83.003251) (xy 364.347553 -83.017357)
			(xy 364.292116 -83.023457) (xy 364.236382 -83.02142) (xy 364.181539 -83.01129) (xy 364.128755 -82.993283)
			(xy 364.079155 -82.967782) (xy 364.033797 -82.935331) (xy 363.993648 -82.896622) (xy 363.959562 -82.852479)
			(xy 363.932266 -82.803844) (xy 363.912343 -82.751753) (xy 363.900217 -82.697316) (xy 363.896146 -82.641694)
			(xy 354.853095 -82.641694) (xy 354.855271 -82.65648) (xy 354.85578 -82.684366) (xy 354.855271 -82.712252)
			(xy 354.847151 -82.767428) (xy 354.831083 -82.820835) (xy 354.807411 -82.871332) (xy 354.776638 -82.917845)
			(xy 354.739421 -82.959382) (xy 354.696553 -82.995057) (xy 354.648947 -83.024111) (xy 354.597618 -83.045923)
			(xy 354.543661 -83.060029) (xy 354.488224 -83.066129) (xy 354.43249 -83.064092) (xy 354.377647 -83.053962)
			(xy 354.324863 -83.035955) (xy 354.275263 -83.010454) (xy 354.229905 -82.978003) (xy 354.189756 -82.939294)
			(xy 354.15567 -82.895151) (xy 354.128374 -82.846516) (xy 354.108451 -82.794425) (xy 354.096325 -82.739988)
			(xy 354.092254 -82.684366) (xy 351.982507 -82.684366) (xy 351.976189 -82.727296) (xy 351.960121 -82.780703)
			(xy 351.936449 -82.8312) (xy 351.905676 -82.877713) (xy 351.868459 -82.91925) (xy 351.825591 -82.954925)
			(xy 351.777985 -82.983979) (xy 351.726656 -83.005791) (xy 351.672699 -83.019897) (xy 351.617262 -83.025997)
			(xy 351.561528 -83.02396) (xy 351.506685 -83.01383) (xy 351.453901 -82.995823) (xy 351.404301 -82.970322)
			(xy 351.358943 -82.937871) (xy 351.318794 -82.899162) (xy 351.284708 -82.855019) (xy 351.257412 -82.806384)
			(xy 351.237489 -82.754293) (xy 351.225363 -82.699856) (xy 351.221292 -82.644234) (xy 342.725248 -82.644234)
			(xy 342.759284 -82.67827) (xy 342.77589 -82.695556) (xy 342.804054 -82.734338) (xy 342.82582 -82.777041)
			(xy 342.840655 -82.822618) (xy 342.848195 -82.869951) (xy 342.848692 -82.893916) (xy 342.848692 -84.144612)
			(xy 345.879928 -84.144612) (xy 345.879928 -83.281012) (xy 345.880418 -83.251028) (xy 345.888246 -83.191572)
			(xy 345.903767 -83.133647) (xy 345.926716 -83.078243) (xy 345.9567 -83.026309) (xy 345.993206 -82.978733)
			(xy 346.035611 -82.936328) (xy 346.083187 -82.899822) (xy 346.135121 -82.869838) (xy 346.190525 -82.846889)
			(xy 346.24845 -82.831368) (xy 346.307906 -82.82354) (xy 346.367874 -82.82354) (xy 346.42733 -82.831368)
			(xy 346.485255 -82.846889) (xy 346.540659 -82.869838) (xy 346.592593 -82.899822) (xy 346.640169 -82.936328)
			(xy 346.682574 -82.978733) (xy 346.71908 -83.026309) (xy 346.749064 -83.078243) (xy 346.772013 -83.133647)
			(xy 346.787534 -83.191572) (xy 346.795362 -83.251028) (xy 346.795852 -83.281012) (xy 346.795852 -83.787234)
			(xy 351.221292 -83.787234) (xy 351.225363 -83.731612) (xy 351.237489 -83.677175) (xy 351.257412 -83.625084)
			(xy 351.284708 -83.576449) (xy 351.318794 -83.532306) (xy 351.358943 -83.493597) (xy 351.404301 -83.461146)
			(xy 351.453901 -83.435645) (xy 351.506685 -83.417638) (xy 351.561528 -83.407508) (xy 351.617262 -83.405471)
			(xy 351.672699 -83.411571) (xy 351.726656 -83.425677) (xy 351.777985 -83.447489) (xy 351.825591 -83.476543)
			(xy 351.868459 -83.512218) (xy 351.905676 -83.553755) (xy 351.936449 -83.600268) (xy 351.960121 -83.650765)
			(xy 351.976189 -83.704172) (xy 351.984309 -83.759348) (xy 351.984818 -83.787234) (xy 351.984309 -83.81512)
			(xy 351.976189 -83.870296) (xy 351.960121 -83.923703) (xy 351.945747 -83.954366) (xy 354.132386 -83.954366)
			(xy 354.136457 -83.898744) (xy 354.148583 -83.844307) (xy 354.168506 -83.792216) (xy 354.195802 -83.743581)
			(xy 354.229888 -83.699438) (xy 354.270037 -83.660729) (xy 354.315395 -83.628278) (xy 354.364995 -83.602777)
			(xy 354.417779 -83.58477) (xy 354.472622 -83.57464) (xy 354.528356 -83.572603) (xy 354.583793 -83.578703)
			(xy 354.63775 -83.592809) (xy 354.689079 -83.614621) (xy 354.736685 -83.643675) (xy 354.779553 -83.67935)
			(xy 354.81677 -83.720887) (xy 354.847543 -83.7674) (xy 354.85565 -83.784694) (xy 365.080548 -83.784694)
			(xy 365.084619 -83.729072) (xy 365.096745 -83.674635) (xy 365.116668 -83.622544) (xy 365.143964 -83.573909)
			(xy 365.17805 -83.529766) (xy 365.218199 -83.491057) (xy 365.263557 -83.458606) (xy 365.313157 -83.433105)
			(xy 365.365941 -83.415098) (xy 365.420784 -83.404968) (xy 365.476518 -83.402931) (xy 365.531955 -83.409031)
			(xy 365.585912 -83.423137) (xy 365.637241 -83.444949) (xy 365.684847 -83.474003) (xy 365.727715 -83.509678)
			(xy 365.764932 -83.551215) (xy 365.795705 -83.597728) (xy 365.819377 -83.648225) (xy 365.835445 -83.701632)
			(xy 365.843565 -83.756808) (xy 365.844074 -83.784694) (xy 365.843565 -83.81258) (xy 365.835445 -83.867756)
			(xy 365.819377 -83.921163) (xy 365.795705 -83.97166) (xy 365.764932 -84.018173) (xy 365.727715 -84.05971)
			(xy 365.684847 -84.095385) (xy 365.637241 -84.124439) (xy 365.585912 -84.146251) (xy 365.531955 -84.160357)
			(xy 365.476518 -84.166457) (xy 365.420784 -84.16442) (xy 365.365941 -84.15429) (xy 365.313157 -84.136283)
			(xy 365.263557 -84.110782) (xy 365.218199 -84.078331) (xy 365.17805 -84.039622) (xy 365.143964 -83.995479)
			(xy 365.116668 -83.946844) (xy 365.096745 -83.894753) (xy 365.084619 -83.840316) (xy 365.080548 -83.784694)
			(xy 354.85565 -83.784694) (xy 354.871215 -83.817897) (xy 354.887283 -83.871304) (xy 354.895403 -83.92648)
			(xy 354.895912 -83.954366) (xy 354.895403 -83.982252) (xy 354.887283 -84.037428) (xy 354.871215 -84.090835)
			(xy 354.847543 -84.141332) (xy 354.81677 -84.187845) (xy 354.779553 -84.229382) (xy 354.736685 -84.265057)
			(xy 354.689079 -84.294111) (xy 354.63775 -84.315923) (xy 354.583793 -84.330029) (xy 354.528356 -84.336129)
			(xy 354.472622 -84.334092) (xy 354.417779 -84.323962) (xy 354.364995 -84.305955) (xy 354.315395 -84.280454)
			(xy 354.270037 -84.248003) (xy 354.229888 -84.209294) (xy 354.195802 -84.165151) (xy 354.168506 -84.116516)
			(xy 354.148583 -84.064425) (xy 354.136457 -84.009988) (xy 354.132386 -83.954366) (xy 351.945747 -83.954366)
			(xy 351.936449 -83.9742) (xy 351.905676 -84.020713) (xy 351.868459 -84.06225) (xy 351.825591 -84.097925)
			(xy 351.777985 -84.126979) (xy 351.726656 -84.148791) (xy 351.672699 -84.162897) (xy 351.617262 -84.168997)
			(xy 351.561528 -84.16696) (xy 351.506685 -84.15683) (xy 351.453901 -84.138823) (xy 351.404301 -84.113322)
			(xy 351.358943 -84.080871) (xy 351.318794 -84.042162) (xy 351.284708 -83.998019) (xy 351.257412 -83.949384)
			(xy 351.237489 -83.897293) (xy 351.225363 -83.842856) (xy 351.221292 -83.787234) (xy 346.795852 -83.787234)
			(xy 346.795852 -84.144612) (xy 346.795362 -84.174596) (xy 346.787534 -84.234052) (xy 346.772013 -84.291977)
			(xy 346.749064 -84.347381) (xy 346.71908 -84.399315) (xy 346.682574 -84.446891) (xy 346.640169 -84.489296)
			(xy 346.592593 -84.525802) (xy 346.540659 -84.555786) (xy 346.485255 -84.578735) (xy 346.42733 -84.594256)
			(xy 346.367874 -84.602084) (xy 346.307906 -84.602084) (xy 346.24845 -84.594256) (xy 346.190525 -84.578735)
			(xy 346.135121 -84.555786) (xy 346.083187 -84.525802) (xy 346.035611 -84.489296) (xy 345.993206 -84.446891)
			(xy 345.9567 -84.399315) (xy 345.926716 -84.347381) (xy 345.903767 -84.291977) (xy 345.888246 -84.234052)
			(xy 345.880418 -84.174596) (xy 345.879928 -84.144612) (xy 342.848692 -84.144612) (xy 342.848692 -86.144608)
			(xy 346.641928 -86.144608) (xy 346.641928 -85.281008) (xy 346.642418 -85.251024) (xy 346.650246 -85.191568)
			(xy 346.665767 -85.133643) (xy 346.688716 -85.078239) (xy 346.7187 -85.026305) (xy 346.755206 -84.978729)
			(xy 346.797611 -84.936324) (xy 346.845187 -84.899818) (xy 346.897121 -84.869834) (xy 346.952525 -84.846885)
			(xy 347.01045 -84.831364) (xy 347.069906 -84.823536) (xy 347.129874 -84.823536) (xy 347.18933 -84.831364)
			(xy 347.247255 -84.846885) (xy 347.302659 -84.869834) (xy 347.354593 -84.899818) (xy 347.394232 -84.930234)
			(xy 351.221292 -84.930234) (xy 351.225363 -84.874612) (xy 351.237489 -84.820175) (xy 351.257412 -84.768084)
			(xy 351.284708 -84.719449) (xy 351.318794 -84.675306) (xy 351.358943 -84.636597) (xy 351.404301 -84.604146)
			(xy 351.453901 -84.578645) (xy 351.506685 -84.560638) (xy 351.561528 -84.550508) (xy 351.617262 -84.548471)
			(xy 351.672699 -84.554571) (xy 351.726656 -84.568677) (xy 351.777985 -84.590489) (xy 351.825591 -84.619543)
			(xy 351.868459 -84.655218) (xy 351.905676 -84.696755) (xy 351.936449 -84.743268) (xy 351.960121 -84.793765)
			(xy 351.976189 -84.847172) (xy 351.984309 -84.902348) (xy 351.984818 -84.930234) (xy 351.984309 -84.95812)
			(xy 351.976189 -85.013296) (xy 351.960121 -85.066703) (xy 351.936449 -85.1172) (xy 351.905676 -85.163713)
			(xy 351.868459 -85.20525) (xy 351.845489 -85.224366) (xy 354.134926 -85.224366) (xy 354.138997 -85.168744)
			(xy 354.151123 -85.114307) (xy 354.171046 -85.062216) (xy 354.198342 -85.013581) (xy 354.232428 -84.969438)
			(xy 354.272577 -84.930729) (xy 354.317935 -84.898278) (xy 354.367535 -84.872777) (xy 354.420319 -84.85477)
			(xy 354.475162 -84.84464) (xy 354.530896 -84.842603) (xy 354.586333 -84.848703) (xy 354.64029 -84.862809)
			(xy 354.645342 -84.864956) (xy 363.863634 -84.864956) (xy 363.867705 -84.809334) (xy 363.879831 -84.754897)
			(xy 363.899754 -84.702806) (xy 363.92705 -84.654171) (xy 363.961136 -84.610028) (xy 364.001285 -84.571319)
			(xy 364.046643 -84.538868) (xy 364.096243 -84.513367) (xy 364.149027 -84.49536) (xy 364.20387 -84.48523)
			(xy 364.259604 -84.483193) (xy 364.315041 -84.489293) (xy 364.368998 -84.503399) (xy 364.420327 -84.525211)
			(xy 364.467933 -84.554265) (xy 364.473791 -84.55914) (xy 367.596928 -84.55914) (xy 367.59742 -84.530678)
			(xy 367.605878 -84.474387) (xy 367.622614 -84.419979) (xy 367.647253 -84.368664) (xy 367.67925 -84.321584)
			(xy 367.717891 -84.279786) (xy 367.762318 -84.244198) (xy 367.786666 -84.229448) (xy 367.798256 -84.22222)
			(xy 367.817381 -84.202733) (xy 367.830658 -84.178874) (xy 367.837138 -84.152349) (xy 367.836356 -84.125056)
			(xy 367.828369 -84.098945) (xy 367.813747 -84.075885) (xy 367.803938 -84.06638) (xy 367.784723 -84.048244)
			(xy 367.751006 -84.007563) (xy 367.723225 -83.962618) (xy 367.70191 -83.914271) (xy 367.68747 -83.863445)
			(xy 367.68018 -83.811113) (xy 367.679732 -83.784694) (xy 367.680218 -83.757443) (xy 367.687974 -83.703495)
			(xy 367.703329 -83.6512) (xy 367.725971 -83.601623) (xy 367.755437 -83.555773) (xy 367.791128 -83.514582)
			(xy 367.832319 -83.478891) (xy 367.878169 -83.449425) (xy 367.927746 -83.426783) (xy 367.980041 -83.411428)
			(xy 368.033989 -83.403672) (xy 368.088491 -83.403672) (xy 368.142439 -83.411428) (xy 368.194734 -83.426783)
			(xy 368.244311 -83.449425) (xy 368.290161 -83.478891) (xy 368.331352 -83.514582) (xy 368.367043 -83.555773)
			(xy 368.396509 -83.601623) (xy 368.419151 -83.6512) (xy 368.434506 -83.703495) (xy 368.442262 -83.757443)
			(xy 368.442748 -83.784694) (xy 370.219222 -83.784694) (xy 370.223293 -83.729072) (xy 370.235419 -83.674635)
			(xy 370.255342 -83.622544) (xy 370.282638 -83.573909) (xy 370.316724 -83.529766) (xy 370.356873 -83.491057)
			(xy 370.402231 -83.458606) (xy 370.451831 -83.433105) (xy 370.504615 -83.415098) (xy 370.559458 -83.404968)
			(xy 370.615192 -83.402931) (xy 370.670629 -83.409031) (xy 370.724586 -83.423137) (xy 370.775915 -83.444949)
			(xy 370.823521 -83.474003) (xy 370.866389 -83.509678) (xy 370.903606 -83.551215) (xy 370.934379 -83.597728)
			(xy 370.958051 -83.648225) (xy 370.974119 -83.701632) (xy 370.982239 -83.756808) (xy 370.982748 -83.784694)
			(xy 370.982239 -83.81258) (xy 370.974119 -83.867756) (xy 370.958051 -83.921163) (xy 370.934379 -83.97166)
			(xy 370.903606 -84.018173) (xy 370.866389 -84.05971) (xy 370.823521 -84.095385) (xy 370.775915 -84.124439)
			(xy 370.724586 -84.146251) (xy 370.670629 -84.160357) (xy 370.615192 -84.166457) (xy 370.559458 -84.16442)
			(xy 370.504615 -84.15429) (xy 370.451831 -84.136283) (xy 370.402231 -84.110782) (xy 370.356873 -84.078331)
			(xy 370.316724 -84.039622) (xy 370.282638 -83.995479) (xy 370.255342 -83.946844) (xy 370.235419 -83.894753)
			(xy 370.223293 -83.840316) (xy 370.219222 -83.784694) (xy 368.442748 -83.784694) (xy 368.442216 -83.813155)
			(xy 368.433766 -83.869445) (xy 368.417039 -83.923852) (xy 368.392406 -83.975167) (xy 368.360416 -84.022248)
			(xy 368.321779 -84.064048) (xy 368.277356 -84.099636) (xy 368.25301 -84.114386) (xy 368.24139 -84.121569)
			(xy 368.222267 -84.141067) (xy 368.208993 -84.164935) (xy 368.202519 -84.191468) (xy 368.203306 -84.218768)
			(xy 368.211299 -84.244883) (xy 368.215685 -84.2518) (xy 374.915428 -84.2518) (xy 374.919499 -84.196178)
			(xy 374.931625 -84.141741) (xy 374.951548 -84.08965) (xy 374.978844 -84.041015) (xy 375.01293 -83.996872)
			(xy 375.053079 -83.958163) (xy 375.098437 -83.925712) (xy 375.148037 -83.900211) (xy 375.200821 -83.882204)
			(xy 375.255664 -83.872074) (xy 375.311398 -83.870037) (xy 375.366835 -83.876137) (xy 375.420792 -83.890243)
			(xy 375.472121 -83.912055) (xy 375.519727 -83.941109) (xy 375.562595 -83.976784) (xy 375.599812 -84.018321)
			(xy 375.630585 -84.064834) (xy 375.654257 -84.115331) (xy 375.662608 -84.143088) (xy 377.35459 -84.143088)
			(xy 377.358661 -84.087466) (xy 377.370787 -84.033029) (xy 377.39071 -83.980938) (xy 377.418006 -83.932303)
			(xy 377.452092 -83.88816) (xy 377.492241 -83.849451) (xy 377.537599 -83.817) (xy 377.587199 -83.791499)
			(xy 377.639983 -83.773492) (xy 377.694826 -83.763362) (xy 377.75056 -83.761325) (xy 377.805997 -83.767425)
			(xy 377.859954 -83.781531) (xy 377.911283 -83.803343) (xy 377.948565 -83.826096) (xy 380.785368 -83.826096)
			(xy 380.789439 -83.770474) (xy 380.801565 -83.716037) (xy 380.821488 -83.663946) (xy 380.848784 -83.615311)
			(xy 380.88287 -83.571168) (xy 380.923019 -83.532459) (xy 380.968377 -83.500008) (xy 381.017977 -83.474507)
			(xy 381.070761 -83.4565) (xy 381.125604 -83.44637) (xy 381.181338 -83.444333) (xy 381.236775 -83.450433)
			(xy 381.290732 -83.464539) (xy 381.342061 -83.486351) (xy 381.389667 -83.515405) (xy 381.432535 -83.55108)
			(xy 381.469752 -83.592617) (xy 381.500525 -83.63913) (xy 381.524197 -83.689627) (xy 381.540265 -83.743034)
			(xy 381.548385 -83.79821) (xy 381.548894 -83.826096) (xy 381.548385 -83.853982) (xy 381.540265 -83.909158)
			(xy 381.524197 -83.962565) (xy 381.500525 -84.013062) (xy 381.469752 -84.059575) (xy 381.432535 -84.101112)
			(xy 381.389667 -84.136787) (xy 381.342061 -84.165841) (xy 381.290732 -84.187653) (xy 381.236775 -84.201759)
			(xy 381.181338 -84.207859) (xy 381.125604 -84.205822) (xy 381.070761 -84.195692) (xy 381.017977 -84.177685)
			(xy 380.968377 -84.152184) (xy 380.923019 -84.119733) (xy 380.88287 -84.081024) (xy 380.848784 -84.036881)
			(xy 380.821488 -83.988246) (xy 380.801565 -83.936155) (xy 380.789439 -83.881718) (xy 380.785368 -83.826096)
			(xy 377.948565 -83.826096) (xy 377.958889 -83.832397) (xy 378.001757 -83.868072) (xy 378.038974 -83.909609)
			(xy 378.069747 -83.956122) (xy 378.093419 -84.006619) (xy 378.109487 -84.060026) (xy 378.117607 -84.115202)
			(xy 378.118116 -84.143088) (xy 378.117607 -84.170974) (xy 378.109487 -84.22615) (xy 378.093419 -84.279557)
			(xy 378.069747 -84.330054) (xy 378.038974 -84.376567) (xy 378.001757 -84.418104) (xy 377.958889 -84.453779)
			(xy 377.942738 -84.463636) (xy 379.522988 -84.463636) (xy 379.527059 -84.408014) (xy 379.539185 -84.353577)
			(xy 379.559108 -84.301486) (xy 379.586404 -84.252851) (xy 379.62049 -84.208708) (xy 379.660639 -84.169999)
			(xy 379.705997 -84.137548) (xy 379.755597 -84.112047) (xy 379.808381 -84.09404) (xy 379.863224 -84.08391)
			(xy 379.918958 -84.081873) (xy 379.974395 -84.087973) (xy 380.028352 -84.102079) (xy 380.079681 -84.123891)
			(xy 380.127287 -84.152945) (xy 380.170155 -84.18862) (xy 380.207372 -84.230157) (xy 380.238145 -84.27667)
			(xy 380.261817 -84.327167) (xy 380.277885 -84.380574) (xy 380.286005 -84.43575) (xy 380.286514 -84.463636)
			(xy 380.286005 -84.491522) (xy 380.277885 -84.546698) (xy 380.261817 -84.600105) (xy 380.238145 -84.650602)
			(xy 380.207372 -84.697115) (xy 380.170155 -84.738652) (xy 380.127287 -84.774327) (xy 380.079681 -84.803381)
			(xy 380.028352 -84.825193) (xy 379.974395 -84.839299) (xy 379.918958 -84.845399) (xy 379.863224 -84.843362)
			(xy 379.808381 -84.833232) (xy 379.755597 -84.815225) (xy 379.705997 -84.789724) (xy 379.660639 -84.757273)
			(xy 379.62049 -84.718564) (xy 379.586404 -84.674421) (xy 379.559108 -84.625786) (xy 379.539185 -84.573695)
			(xy 379.527059 -84.519258) (xy 379.522988 -84.463636) (xy 377.942738 -84.463636) (xy 377.911283 -84.482833)
			(xy 377.859954 -84.504645) (xy 377.805997 -84.518751) (xy 377.75056 -84.524851) (xy 377.694826 -84.522814)
			(xy 377.639983 -84.512684) (xy 377.587199 -84.494677) (xy 377.537599 -84.469176) (xy 377.492241 -84.436725)
			(xy 377.452092 -84.398016) (xy 377.418006 -84.353873) (xy 377.39071 -84.305238) (xy 377.370787 -84.253147)
			(xy 377.358661 -84.19871) (xy 377.35459 -84.143088) (xy 375.662608 -84.143088) (xy 375.670325 -84.168738)
			(xy 375.678445 -84.223914) (xy 375.678954 -84.2518) (xy 375.678445 -84.279686) (xy 375.670325 -84.334862)
			(xy 375.654257 -84.388269) (xy 375.630585 -84.438766) (xy 375.599812 -84.485279) (xy 375.562595 -84.526816)
			(xy 375.519727 -84.562491) (xy 375.472121 -84.591545) (xy 375.420792 -84.613357) (xy 375.366835 -84.627463)
			(xy 375.311398 -84.633563) (xy 375.255664 -84.631526) (xy 375.200821 -84.621396) (xy 375.148037 -84.603389)
			(xy 375.098437 -84.577888) (xy 375.053079 -84.545437) (xy 375.01293 -84.506728) (xy 374.978844 -84.462585)
			(xy 374.951548 -84.41395) (xy 374.931625 -84.361859) (xy 374.919499 -84.307422) (xy 374.915428 -84.2518)
			(xy 368.215685 -84.2518) (xy 368.225925 -84.267947) (xy 368.235738 -84.277454) (xy 368.254965 -84.295578)
			(xy 368.288682 -84.336262) (xy 368.316462 -84.381208) (xy 368.337775 -84.429558) (xy 368.352213 -84.480386)
			(xy 368.359498 -84.53272) (xy 368.359944 -84.55914) (xy 368.359458 -84.586391) (xy 368.351702 -84.640339)
			(xy 368.336347 -84.692634) (xy 368.313705 -84.742211) (xy 368.284239 -84.788061) (xy 368.248548 -84.829252)
			(xy 368.207357 -84.864943) (xy 368.161507 -84.894409) (xy 368.11193 -84.917051) (xy 368.075683 -84.927694)
			(xy 370.219222 -84.927694) (xy 370.223293 -84.872072) (xy 370.235419 -84.817635) (xy 370.255342 -84.765544)
			(xy 370.282638 -84.716909) (xy 370.316724 -84.672766) (xy 370.356873 -84.634057) (xy 370.402231 -84.601606)
			(xy 370.451831 -84.576105) (xy 370.504615 -84.558098) (xy 370.559458 -84.547968) (xy 370.615192 -84.545931)
			(xy 370.670629 -84.552031) (xy 370.724586 -84.566137) (xy 370.775915 -84.587949) (xy 370.823521 -84.617003)
			(xy 370.866389 -84.652678) (xy 370.903606 -84.694215) (xy 370.934379 -84.740728) (xy 370.958051 -84.791225)
			(xy 370.974119 -84.844632) (xy 370.982239 -84.899808) (xy 370.982748 -84.927694) (xy 370.982239 -84.95558)
			(xy 370.974119 -85.010756) (xy 370.958051 -85.064163) (xy 370.934379 -85.11466) (xy 370.903606 -85.161173)
			(xy 370.866389 -85.20271) (xy 370.823521 -85.238385) (xy 370.775915 -85.267439) (xy 370.724586 -85.289251)
			(xy 370.670629 -85.303357) (xy 370.615192 -85.309457) (xy 370.559458 -85.30742) (xy 370.504615 -85.29729)
			(xy 370.451831 -85.279283) (xy 370.402231 -85.253782) (xy 370.356873 -85.221331) (xy 370.316724 -85.182622)
			(xy 370.282638 -85.138479) (xy 370.255342 -85.089844) (xy 370.235419 -85.037753) (xy 370.223293 -84.983316)
			(xy 370.219222 -84.927694) (xy 368.075683 -84.927694) (xy 368.059635 -84.932406) (xy 368.005687 -84.940162)
			(xy 367.951185 -84.940162) (xy 367.897237 -84.932406) (xy 367.844942 -84.917051) (xy 367.795365 -84.894409)
			(xy 367.749515 -84.864943) (xy 367.708324 -84.829252) (xy 367.672633 -84.788061) (xy 367.643167 -84.742211)
			(xy 367.620525 -84.692634) (xy 367.60517 -84.640339) (xy 367.597414 -84.586391) (xy 367.596928 -84.55914)
			(xy 364.473791 -84.55914) (xy 364.510801 -84.58994) (xy 364.548018 -84.631477) (xy 364.578791 -84.67799)
			(xy 364.602463 -84.728487) (xy 364.618531 -84.781894) (xy 364.626651 -84.83707) (xy 364.62716 -84.864956)
			(xy 364.626651 -84.892842) (xy 364.618531 -84.948018) (xy 364.602463 -85.001425) (xy 364.578791 -85.051922)
			(xy 364.548018 -85.098435) (xy 364.510801 -85.139972) (xy 364.467933 -85.175647) (xy 364.420327 -85.204701)
			(xy 364.368998 -85.226513) (xy 364.315041 -85.240619) (xy 364.259604 -85.246719) (xy 364.20387 -85.244682)
			(xy 364.149027 -85.234552) (xy 364.096243 -85.216545) (xy 364.046643 -85.191044) (xy 364.001285 -85.158593)
			(xy 363.961136 -85.119884) (xy 363.92705 -85.075741) (xy 363.899754 -85.027106) (xy 363.879831 -84.975015)
			(xy 363.867705 -84.920578) (xy 363.863634 -84.864956) (xy 354.645342 -84.864956) (xy 354.691619 -84.884621)
			(xy 354.739225 -84.913675) (xy 354.782093 -84.94935) (xy 354.81931 -84.990887) (xy 354.850083 -85.0374)
			(xy 354.873755 -85.087897) (xy 354.889823 -85.141304) (xy 354.897943 -85.19648) (xy 354.898452 -85.224366)
			(xy 354.897943 -85.252252) (xy 354.889823 -85.307428) (xy 354.873755 -85.360835) (xy 354.850083 -85.411332)
			(xy 354.81931 -85.457845) (xy 354.782093 -85.499382) (xy 354.763396 -85.514942) (xy 365.30483 -85.514942)
			(xy 365.308901 -85.45932) (xy 365.321027 -85.404883) (xy 365.34095 -85.352792) (xy 365.368246 -85.304157)
			(xy 365.402332 -85.260014) (xy 365.442481 -85.221305) (xy 365.487839 -85.188854) (xy 365.537439 -85.163353)
			(xy 365.590223 -85.145346) (xy 365.645066 -85.135216) (xy 365.7008 -85.133179) (xy 365.756237 -85.139279)
			(xy 365.810194 -85.153385) (xy 365.861523 -85.175197) (xy 365.909129 -85.204251) (xy 365.951997 -85.239926)
			(xy 365.989214 -85.281463) (xy 366.019987 -85.327976) (xy 366.043659 -85.378473) (xy 366.059727 -85.43188)
			(xy 366.067847 -85.487056) (xy 366.068356 -85.514942) (xy 366.067847 -85.542828) (xy 366.059727 -85.598004)
			(xy 366.043659 -85.651411) (xy 366.019987 -85.701908) (xy 365.989214 -85.748421) (xy 365.951997 -85.789958)
			(xy 365.909129 -85.825633) (xy 365.861523 -85.854687) (xy 365.810194 -85.876499) (xy 365.756237 -85.890605)
			(xy 365.7008 -85.896705) (xy 365.645066 -85.894668) (xy 365.590223 -85.884538) (xy 365.537439 -85.866531)
			(xy 365.487839 -85.84103) (xy 365.442481 -85.808579) (xy 365.402332 -85.76987) (xy 365.368246 -85.725727)
			(xy 365.34095 -85.677092) (xy 365.321027 -85.625001) (xy 365.308901 -85.570564) (xy 365.30483 -85.514942)
			(xy 354.763396 -85.514942) (xy 354.739225 -85.535057) (xy 354.691619 -85.564111) (xy 354.64029 -85.585923)
			(xy 354.586333 -85.600029) (xy 354.530896 -85.606129) (xy 354.475162 -85.604092) (xy 354.420319 -85.593962)
			(xy 354.367535 -85.575955) (xy 354.317935 -85.550454) (xy 354.272577 -85.518003) (xy 354.232428 -85.479294)
			(xy 354.198342 -85.435151) (xy 354.171046 -85.386516) (xy 354.151123 -85.334425) (xy 354.138997 -85.279988)
			(xy 354.134926 -85.224366) (xy 351.845489 -85.224366) (xy 351.825591 -85.240925) (xy 351.777985 -85.269979)
			(xy 351.726656 -85.291791) (xy 351.672699 -85.305897) (xy 351.617262 -85.311997) (xy 351.561528 -85.30996)
			(xy 351.506685 -85.29983) (xy 351.453901 -85.281823) (xy 351.404301 -85.256322) (xy 351.358943 -85.223871)
			(xy 351.318794 -85.185162) (xy 351.284708 -85.141019) (xy 351.257412 -85.092384) (xy 351.237489 -85.040293)
			(xy 351.225363 -84.985856) (xy 351.221292 -84.930234) (xy 347.394232 -84.930234) (xy 347.402169 -84.936324)
			(xy 347.444574 -84.978729) (xy 347.48108 -85.026305) (xy 347.511064 -85.078239) (xy 347.534013 -85.133643)
			(xy 347.549534 -85.191568) (xy 347.557362 -85.251024) (xy 347.557852 -85.281008) (xy 347.557852 -85.803232)
			(xy 351.039936 -85.803232) (xy 351.044007 -85.74761) (xy 351.056133 -85.693173) (xy 351.076056 -85.641082)
			(xy 351.103352 -85.592447) (xy 351.137438 -85.548304) (xy 351.177587 -85.509595) (xy 351.222945 -85.477144)
			(xy 351.272545 -85.451643) (xy 351.325329 -85.433636) (xy 351.380172 -85.423506) (xy 351.435906 -85.421469)
			(xy 351.491343 -85.427569) (xy 351.5453 -85.441675) (xy 351.596629 -85.463487) (xy 351.644235 -85.492541)
			(xy 351.687103 -85.528216) (xy 351.72432 -85.569753) (xy 351.755093 -85.616266) (xy 351.778765 -85.666763)
			(xy 351.794833 -85.72017) (xy 351.802953 -85.775346) (xy 351.803462 -85.803232) (xy 351.802953 -85.831118)
			(xy 351.794833 -85.886294) (xy 351.778765 -85.939701) (xy 351.755093 -85.990198) (xy 351.72432 -86.036711)
			(xy 351.687103 -86.078248) (xy 351.644235 -86.113923) (xy 351.596629 -86.142977) (xy 351.5453 -86.164789)
			(xy 351.491343 -86.178895) (xy 351.435906 -86.184995) (xy 351.380172 -86.182958) (xy 351.325329 -86.172828)
			(xy 351.272545 -86.154821) (xy 351.222945 -86.12932) (xy 351.177587 -86.096869) (xy 351.137438 -86.05816)
			(xy 351.103352 -86.014017) (xy 351.076056 -85.965382) (xy 351.056133 -85.913291) (xy 351.044007 -85.858854)
			(xy 351.039936 -85.803232) (xy 347.557852 -85.803232) (xy 347.557852 -86.144608) (xy 347.557362 -86.174592)
			(xy 347.549534 -86.234048) (xy 347.534013 -86.291973) (xy 347.511064 -86.347377) (xy 347.48108 -86.399311)
			(xy 347.444574 -86.446887) (xy 347.402169 -86.489292) (xy 347.395556 -86.494366) (xy 354.132386 -86.494366)
			(xy 354.136457 -86.438744) (xy 354.148583 -86.384307) (xy 354.168506 -86.332216) (xy 354.195802 -86.283581)
			(xy 354.229888 -86.239438) (xy 354.270037 -86.200729) (xy 354.315395 -86.168278) (xy 354.364995 -86.142777)
			(xy 354.417779 -86.12477) (xy 354.472622 -86.11464) (xy 354.528356 -86.112603) (xy 354.583793 -86.118703)
			(xy 354.63775 -86.132809) (xy 354.689079 -86.154621) (xy 354.705967 -86.164928) (xy 363.895638 -86.164928)
			(xy 363.899709 -86.109306) (xy 363.911835 -86.054869) (xy 363.931758 -86.002778) (xy 363.959054 -85.954143)
			(xy 363.99314 -85.91) (xy 364.033289 -85.871291) (xy 364.078647 -85.83884) (xy 364.128247 -85.813339)
			(xy 364.181031 -85.795332) (xy 364.235874 -85.785202) (xy 364.291608 -85.783165) (xy 364.347045 -85.789265)
			(xy 364.401002 -85.803371) (xy 364.452331 -85.825183) (xy 364.499937 -85.854237) (xy 364.542805 -85.889912)
			(xy 364.580022 -85.931449) (xy 364.610795 -85.977962) (xy 364.634467 -86.028459) (xy 364.647174 -86.070694)
			(xy 370.219222 -86.070694) (xy 370.223293 -86.015072) (xy 370.235419 -85.960635) (xy 370.255342 -85.908544)
			(xy 370.282638 -85.859909) (xy 370.316724 -85.815766) (xy 370.356873 -85.777057) (xy 370.402231 -85.744606)
			(xy 370.451831 -85.719105) (xy 370.504615 -85.701098) (xy 370.559458 -85.690968) (xy 370.615192 -85.688931)
			(xy 370.670629 -85.695031) (xy 370.724586 -85.709137) (xy 370.775915 -85.730949) (xy 370.823521 -85.760003)
			(xy 370.866389 -85.795678) (xy 370.903606 -85.837215) (xy 370.934379 -85.883728) (xy 370.958051 -85.934225)
			(xy 370.974119 -85.987632) (xy 370.982239 -86.042808) (xy 370.982748 -86.070694) (xy 370.982239 -86.09858)
			(xy 370.974119 -86.153756) (xy 370.958051 -86.207163) (xy 370.934379 -86.25766) (xy 370.903606 -86.304173)
			(xy 370.866389 -86.34571) (xy 370.823521 -86.381385) (xy 370.775915 -86.410439) (xy 370.724586 -86.432251)
			(xy 370.670629 -86.446357) (xy 370.615192 -86.452457) (xy 370.559458 -86.45042) (xy 370.504615 -86.44029)
			(xy 370.451831 -86.422283) (xy 370.402231 -86.396782) (xy 370.356873 -86.364331) (xy 370.316724 -86.325622)
			(xy 370.282638 -86.281479) (xy 370.255342 -86.232844) (xy 370.235419 -86.180753) (xy 370.223293 -86.126316)
			(xy 370.219222 -86.070694) (xy 364.647174 -86.070694) (xy 364.650535 -86.081866) (xy 364.658655 -86.137042)
			(xy 364.659164 -86.164928) (xy 364.658655 -86.192814) (xy 364.650535 -86.24799) (xy 364.634467 -86.301397)
			(xy 364.610795 -86.351894) (xy 364.580022 -86.398407) (xy 364.542805 -86.439944) (xy 364.499937 -86.475619)
			(xy 364.452331 -86.504673) (xy 364.449091 -86.50605) (xy 367.536982 -86.50605) (xy 367.541053 -86.450428)
			(xy 367.553179 -86.395991) (xy 367.573102 -86.3439) (xy 367.600398 -86.295265) (xy 367.634484 -86.251122)
			(xy 367.674633 -86.212413) (xy 367.719991 -86.179962) (xy 367.769591 -86.154461) (xy 367.822375 -86.136454)
			(xy 367.877218 -86.126324) (xy 367.932952 -86.124287) (xy 367.988389 -86.130387) (xy 368.042346 -86.144493)
			(xy 368.093675 -86.166305) (xy 368.141281 -86.195359) (xy 368.184149 -86.231034) (xy 368.221366 -86.272571)
			(xy 368.252139 -86.319084) (xy 368.275811 -86.369581) (xy 368.291879 -86.422988) (xy 368.299999 -86.478164)
			(xy 368.300508 -86.50605) (xy 368.299999 -86.533936) (xy 368.29943 -86.5378) (xy 374.915428 -86.5378)
			(xy 374.919499 -86.482178) (xy 374.931625 -86.427741) (xy 374.951548 -86.37565) (xy 374.978844 -86.327015)
			(xy 375.01293 -86.282872) (xy 375.053079 -86.244163) (xy 375.098437 -86.211712) (xy 375.148037 -86.186211)
			(xy 375.200821 -86.168204) (xy 375.255664 -86.158074) (xy 375.311398 -86.156037) (xy 375.366835 -86.162137)
			(xy 375.420792 -86.176243) (xy 375.472121 -86.198055) (xy 375.519727 -86.227109) (xy 375.562595 -86.262784)
			(xy 375.599812 -86.304321) (xy 375.630585 -86.350834) (xy 375.654257 -86.401331) (xy 375.666811 -86.443058)
			(xy 377.293884 -86.443058) (xy 377.297955 -86.387436) (xy 377.310081 -86.332999) (xy 377.330004 -86.280908)
			(xy 377.3573 -86.232273) (xy 377.391386 -86.18813) (xy 377.431535 -86.149421) (xy 377.476893 -86.11697)
			(xy 377.526493 -86.091469) (xy 377.579277 -86.073462) (xy 377.63412 -86.063332) (xy 377.689854 -86.061295)
			(xy 377.745291 -86.067395) (xy 377.799248 -86.081501) (xy 377.850577 -86.103313) (xy 377.898183 -86.132367)
			(xy 377.941051 -86.168042) (xy 377.978268 -86.209579) (xy 378.009041 -86.256092) (xy 378.032713 -86.306589)
			(xy 378.048781 -86.359996) (xy 378.056901 -86.415172) (xy 378.05741 -86.443058) (xy 378.056901 -86.470944)
			(xy 378.048781 -86.52612) (xy 378.045267 -86.5378) (xy 379.480316 -86.5378) (xy 379.484387 -86.482178)
			(xy 379.496513 -86.427741) (xy 379.516436 -86.37565) (xy 379.543732 -86.327015) (xy 379.577818 -86.282872)
			(xy 379.617967 -86.244163) (xy 379.663325 -86.211712) (xy 379.712925 -86.186211) (xy 379.765709 -86.168204)
			(xy 379.820552 -86.158074) (xy 379.876286 -86.156037) (xy 379.931723 -86.162137) (xy 379.98568 -86.176243)
			(xy 380.037009 -86.198055) (xy 380.084615 -86.227109) (xy 380.127483 -86.262784) (xy 380.1647 -86.304321)
			(xy 380.195473 -86.350834) (xy 380.219145 -86.401331) (xy 380.235213 -86.454738) (xy 380.243333 -86.509914)
			(xy 380.243842 -86.5378) (xy 380.243333 -86.565686) (xy 380.235213 -86.620862) (xy 380.219145 -86.674269)
			(xy 380.195473 -86.724766) (xy 380.1647 -86.771279) (xy 380.127483 -86.812816) (xy 380.084615 -86.848491)
			(xy 380.037009 -86.877545) (xy 379.98568 -86.899357) (xy 379.931723 -86.913463) (xy 379.876286 -86.919563)
			(xy 379.820552 -86.917526) (xy 379.765709 -86.907396) (xy 379.712925 -86.889389) (xy 379.663325 -86.863888)
			(xy 379.617967 -86.831437) (xy 379.577818 -86.792728) (xy 379.543732 -86.748585) (xy 379.516436 -86.69995)
			(xy 379.496513 -86.647859) (xy 379.484387 -86.593422) (xy 379.480316 -86.5378) (xy 378.045267 -86.5378)
			(xy 378.032713 -86.579527) (xy 378.009041 -86.630024) (xy 377.978268 -86.676537) (xy 377.941051 -86.718074)
			(xy 377.898183 -86.753749) (xy 377.850577 -86.782803) (xy 377.799248 -86.804615) (xy 377.745291 -86.818721)
			(xy 377.689854 -86.824821) (xy 377.63412 -86.822784) (xy 377.579277 -86.812654) (xy 377.526493 -86.794647)
			(xy 377.476893 -86.769146) (xy 377.431535 -86.736695) (xy 377.391386 -86.697986) (xy 377.3573 -86.653843)
			(xy 377.330004 -86.605208) (xy 377.310081 -86.553117) (xy 377.297955 -86.49868) (xy 377.293884 -86.443058)
			(xy 375.666811 -86.443058) (xy 375.670325 -86.454738) (xy 375.678445 -86.509914) (xy 375.678954 -86.5378)
			(xy 375.678445 -86.565686) (xy 375.670325 -86.620862) (xy 375.654257 -86.674269) (xy 375.630585 -86.724766)
			(xy 375.599812 -86.771279) (xy 375.562595 -86.812816) (xy 375.519727 -86.848491) (xy 375.472121 -86.877545)
			(xy 375.420792 -86.899357) (xy 375.366835 -86.913463) (xy 375.311398 -86.919563) (xy 375.255664 -86.917526)
			(xy 375.200821 -86.907396) (xy 375.148037 -86.889389) (xy 375.098437 -86.863888) (xy 375.053079 -86.831437)
			(xy 375.01293 -86.792728) (xy 374.978844 -86.748585) (xy 374.951548 -86.69995) (xy 374.931625 -86.647859)
			(xy 374.919499 -86.593422) (xy 374.915428 -86.5378) (xy 368.29943 -86.5378) (xy 368.291879 -86.589112)
			(xy 368.275811 -86.642519) (xy 368.252139 -86.693016) (xy 368.221366 -86.739529) (xy 368.184149 -86.781066)
			(xy 368.141281 -86.816741) (xy 368.093675 -86.845795) (xy 368.042346 -86.867607) (xy 367.988389 -86.881713)
			(xy 367.932952 -86.887813) (xy 367.877218 -86.885776) (xy 367.822375 -86.875646) (xy 367.769591 -86.857639)
			(xy 367.719991 -86.832138) (xy 367.674633 -86.799687) (xy 367.634484 -86.760978) (xy 367.600398 -86.716835)
			(xy 367.573102 -86.6682) (xy 367.553179 -86.616109) (xy 367.541053 -86.561672) (xy 367.536982 -86.50605)
			(xy 364.449091 -86.50605) (xy 364.401002 -86.526485) (xy 364.347045 -86.540591) (xy 364.291608 -86.546691)
			(xy 364.235874 -86.544654) (xy 364.181031 -86.534524) (xy 364.128247 -86.516517) (xy 364.078647 -86.491016)
			(xy 364.033289 -86.458565) (xy 363.99314 -86.419856) (xy 363.959054 -86.375713) (xy 363.931758 -86.327078)
			(xy 363.911835 -86.274987) (xy 363.899709 -86.22055) (xy 363.895638 -86.164928) (xy 354.705967 -86.164928)
			(xy 354.736685 -86.183675) (xy 354.779553 -86.21935) (xy 354.81677 -86.260887) (xy 354.847543 -86.3074)
			(xy 354.871215 -86.357897) (xy 354.887283 -86.411304) (xy 354.895403 -86.46648) (xy 354.895912 -86.494366)
			(xy 354.895403 -86.522252) (xy 354.887283 -86.577428) (xy 354.871215 -86.630835) (xy 354.847543 -86.681332)
			(xy 354.81677 -86.727845) (xy 354.779553 -86.769382) (xy 354.736685 -86.805057) (xy 354.689079 -86.834111)
			(xy 354.63775 -86.855923) (xy 354.583793 -86.870029) (xy 354.528356 -86.876129) (xy 354.472622 -86.874092)
			(xy 354.417779 -86.863962) (xy 354.364995 -86.845955) (xy 354.315395 -86.820454) (xy 354.270037 -86.788003)
			(xy 354.229888 -86.749294) (xy 354.195802 -86.705151) (xy 354.168506 -86.656516) (xy 354.148583 -86.604425)
			(xy 354.136457 -86.549988) (xy 354.132386 -86.494366) (xy 347.395556 -86.494366) (xy 347.354593 -86.525798)
			(xy 347.302659 -86.555782) (xy 347.247255 -86.578731) (xy 347.18933 -86.594252) (xy 347.129874 -86.60208)
			(xy 347.069906 -86.60208) (xy 347.01045 -86.594252) (xy 346.952525 -86.578731) (xy 346.897121 -86.555782)
			(xy 346.845187 -86.525798) (xy 346.797611 -86.489292) (xy 346.755206 -86.446887) (xy 346.7187 -86.399311)
			(xy 346.688716 -86.347377) (xy 346.665767 -86.291973) (xy 346.650246 -86.234048) (xy 346.642418 -86.174592)
			(xy 346.641928 -86.144608) (xy 342.848692 -86.144608) (xy 342.848692 -86.156292) (xy 342.849152 -86.167907)
			(xy 342.859285 -86.188807) (xy 342.87758 -86.203117) (xy 342.888824 -86.206076) (xy 342.915357 -86.212278)
			(xy 342.966395 -86.23137) (xy 343.014198 -86.257526) (xy 343.057797 -86.290215) (xy 343.096304 -86.32877)
			(xy 343.128936 -86.37241) (xy 343.155031 -86.420247) (xy 343.174059 -86.471309) (xy 343.185632 -86.524557)
			(xy 343.189514 -86.57891) (xy 343.185629 -86.633263) (xy 343.174053 -86.686511) (xy 343.155023 -86.737572)
			(xy 343.128925 -86.785407) (xy 343.09629 -86.829045) (xy 343.057781 -86.867599) (xy 343.014181 -86.900285)
			(xy 342.966376 -86.926438) (xy 342.915338 -86.945528) (xy 342.888824 -86.95182) (xy 342.877612 -86.954812)
			(xy 342.859401 -86.969162) (xy 342.849261 -86.990012) (xy 342.848692 -87.001604) (xy 342.848692 -88.144604)
			(xy 345.879928 -88.144604) (xy 345.879928 -87.281004) (xy 345.880418 -87.25102) (xy 345.888246 -87.191564)
			(xy 345.903767 -87.133639) (xy 345.926716 -87.078235) (xy 345.9567 -87.026301) (xy 345.993206 -86.978725)
			(xy 346.035611 -86.93632) (xy 346.083187 -86.899814) (xy 346.135121 -86.86983) (xy 346.190525 -86.846881)
			(xy 346.24845 -86.83136) (xy 346.307906 -86.823532) (xy 346.367874 -86.823532) (xy 346.42733 -86.83136)
			(xy 346.485255 -86.846881) (xy 346.540659 -86.86983) (xy 346.592593 -86.899814) (xy 346.640169 -86.93632)
			(xy 346.682574 -86.978725) (xy 346.71908 -87.026301) (xy 346.740016 -87.062564) (xy 351.061018 -87.062564)
			(xy 351.065089 -87.006942) (xy 351.077215 -86.952505) (xy 351.097138 -86.900414) (xy 351.124434 -86.851779)
			(xy 351.15852 -86.807636) (xy 351.198669 -86.768927) (xy 351.244027 -86.736476) (xy 351.293627 -86.710975)
			(xy 351.346411 -86.692968) (xy 351.401254 -86.682838) (xy 351.456988 -86.680801) (xy 351.512425 -86.686901)
			(xy 351.566382 -86.701007) (xy 351.617711 -86.722819) (xy 351.665317 -86.751873) (xy 351.708185 -86.787548)
			(xy 351.745402 -86.829085) (xy 351.776175 -86.875598) (xy 351.799847 -86.926095) (xy 351.815915 -86.979502)
			(xy 351.824035 -87.034678) (xy 351.824544 -87.062564) (xy 351.824035 -87.09045) (xy 351.815915 -87.145626)
			(xy 351.799847 -87.199033) (xy 351.792974 -87.213694) (xy 370.219222 -87.213694) (xy 370.223293 -87.158072)
			(xy 370.235419 -87.103635) (xy 370.255342 -87.051544) (xy 370.282638 -87.002909) (xy 370.316724 -86.958766)
			(xy 370.356873 -86.920057) (xy 370.402231 -86.887606) (xy 370.451831 -86.862105) (xy 370.504615 -86.844098)
			(xy 370.559458 -86.833968) (xy 370.615192 -86.831931) (xy 370.670629 -86.838031) (xy 370.724586 -86.852137)
			(xy 370.775915 -86.873949) (xy 370.823521 -86.903003) (xy 370.866389 -86.938678) (xy 370.903606 -86.980215)
			(xy 370.934379 -87.026728) (xy 370.958051 -87.077225) (xy 370.974119 -87.130632) (xy 370.982239 -87.185808)
			(xy 370.982748 -87.213694) (xy 370.982239 -87.24158) (xy 370.974119 -87.296756) (xy 370.958051 -87.350163)
			(xy 370.934379 -87.40066) (xy 370.903606 -87.447173) (xy 370.866389 -87.48871) (xy 370.823521 -87.524385)
			(xy 370.775915 -87.553439) (xy 370.724586 -87.575251) (xy 370.670629 -87.589357) (xy 370.615192 -87.595457)
			(xy 370.559458 -87.59342) (xy 370.504615 -87.58329) (xy 370.451831 -87.565283) (xy 370.402231 -87.539782)
			(xy 370.356873 -87.507331) (xy 370.316724 -87.468622) (xy 370.282638 -87.424479) (xy 370.255342 -87.375844)
			(xy 370.235419 -87.323753) (xy 370.223293 -87.269316) (xy 370.219222 -87.213694) (xy 351.792974 -87.213694)
			(xy 351.776175 -87.24953) (xy 351.745402 -87.296043) (xy 351.708185 -87.33758) (xy 351.665317 -87.373255)
			(xy 351.617711 -87.402309) (xy 351.566382 -87.424121) (xy 351.512425 -87.438227) (xy 351.456988 -87.444327)
			(xy 351.401254 -87.44229) (xy 351.346411 -87.43216) (xy 351.293627 -87.414153) (xy 351.244027 -87.388652)
			(xy 351.198669 -87.356201) (xy 351.15852 -87.317492) (xy 351.124434 -87.273349) (xy 351.097138 -87.224714)
			(xy 351.077215 -87.172623) (xy 351.065089 -87.118186) (xy 351.061018 -87.062564) (xy 346.740016 -87.062564)
			(xy 346.749064 -87.078235) (xy 346.772013 -87.133639) (xy 346.787534 -87.191564) (xy 346.795362 -87.25102)
			(xy 346.795852 -87.281004) (xy 346.795852 -87.764366) (xy 354.132386 -87.764366) (xy 354.136457 -87.708744)
			(xy 354.148583 -87.654307) (xy 354.168506 -87.602216) (xy 354.195802 -87.553581) (xy 354.229888 -87.509438)
			(xy 354.270037 -87.470729) (xy 354.315395 -87.438278) (xy 354.364995 -87.412777) (xy 354.417779 -87.39477)
			(xy 354.472622 -87.38464) (xy 354.528356 -87.382603) (xy 354.583793 -87.388703) (xy 354.63775 -87.402809)
			(xy 354.689079 -87.424621) (xy 354.736685 -87.453675) (xy 354.779553 -87.48935) (xy 354.81677 -87.530887)
			(xy 354.847543 -87.5774) (xy 354.871215 -87.627897) (xy 354.887283 -87.681304) (xy 354.891844 -87.712296)
			(xy 367.61877 -87.712296) (xy 367.622841 -87.656674) (xy 367.634967 -87.602237) (xy 367.65489 -87.550146)
			(xy 367.682186 -87.501511) (xy 367.716272 -87.457368) (xy 367.756421 -87.418659) (xy 367.801779 -87.386208)
			(xy 367.851379 -87.360707) (xy 367.904163 -87.3427) (xy 367.959006 -87.33257) (xy 368.01474 -87.330533)
			(xy 368.070177 -87.336633) (xy 368.124134 -87.350739) (xy 368.175463 -87.372551) (xy 368.223069 -87.401605)
			(xy 368.265937 -87.43728) (xy 368.303154 -87.478817) (xy 368.333927 -87.52533) (xy 368.357599 -87.575827)
			(xy 368.373667 -87.629234) (xy 368.381256 -87.6808) (xy 374.915428 -87.6808) (xy 374.919499 -87.625178)
			(xy 374.931625 -87.570741) (xy 374.951548 -87.51865) (xy 374.978844 -87.470015) (xy 375.01293 -87.425872)
			(xy 375.053079 -87.387163) (xy 375.098437 -87.354712) (xy 375.148037 -87.329211) (xy 375.200821 -87.311204)
			(xy 375.255664 -87.301074) (xy 375.311398 -87.299037) (xy 375.366835 -87.305137) (xy 375.420792 -87.319243)
			(xy 375.472121 -87.341055) (xy 375.519727 -87.370109) (xy 375.562595 -87.405784) (xy 375.599812 -87.447321)
			(xy 375.630585 -87.493834) (xy 375.654257 -87.544331) (xy 375.670325 -87.597738) (xy 375.678445 -87.652914)
			(xy 375.678954 -87.6808) (xy 377.153422 -87.6808) (xy 377.157493 -87.625178) (xy 377.169619 -87.570741)
			(xy 377.189542 -87.51865) (xy 377.216838 -87.470015) (xy 377.250924 -87.425872) (xy 377.291073 -87.387163)
			(xy 377.336431 -87.354712) (xy 377.386031 -87.329211) (xy 377.438815 -87.311204) (xy 377.493658 -87.301074)
			(xy 377.549392 -87.299037) (xy 377.604829 -87.305137) (xy 377.658786 -87.319243) (xy 377.710115 -87.341055)
			(xy 377.757721 -87.370109) (xy 377.800589 -87.405784) (xy 377.837806 -87.447321) (xy 377.868579 -87.493834)
			(xy 377.892251 -87.544331) (xy 377.908319 -87.597738) (xy 377.916439 -87.652914) (xy 377.916948 -87.6808)
			(xy 377.916439 -87.708686) (xy 377.908319 -87.763862) (xy 377.892251 -87.817269) (xy 377.868579 -87.867766)
			(xy 377.837806 -87.914279) (xy 377.800589 -87.955816) (xy 377.757721 -87.991491) (xy 377.710115 -88.020545)
			(xy 377.658786 -88.042357) (xy 377.604829 -88.056463) (xy 377.549392 -88.062563) (xy 377.493658 -88.060526)
			(xy 377.438815 -88.050396) (xy 377.386031 -88.032389) (xy 377.336431 -88.006888) (xy 377.291073 -87.974437)
			(xy 377.250924 -87.935728) (xy 377.216838 -87.891585) (xy 377.189542 -87.84295) (xy 377.169619 -87.790859)
			(xy 377.157493 -87.736422) (xy 377.153422 -87.6808) (xy 375.678954 -87.6808) (xy 375.678445 -87.708686)
			(xy 375.670325 -87.763862) (xy 375.654257 -87.817269) (xy 375.630585 -87.867766) (xy 375.599812 -87.914279)
			(xy 375.562595 -87.955816) (xy 375.519727 -87.991491) (xy 375.472121 -88.020545) (xy 375.420792 -88.042357)
			(xy 375.366835 -88.056463) (xy 375.311398 -88.062563) (xy 375.255664 -88.060526) (xy 375.200821 -88.050396)
			(xy 375.148037 -88.032389) (xy 375.098437 -88.006888) (xy 375.053079 -87.974437) (xy 375.01293 -87.935728)
			(xy 374.978844 -87.891585) (xy 374.951548 -87.84295) (xy 374.931625 -87.790859) (xy 374.919499 -87.736422)
			(xy 374.915428 -87.6808) (xy 368.381256 -87.6808) (xy 368.381787 -87.68441) (xy 368.382296 -87.712296)
			(xy 368.381787 -87.740182) (xy 368.373667 -87.795358) (xy 368.357599 -87.848765) (xy 368.333927 -87.899262)
			(xy 368.303154 -87.945775) (xy 368.265937 -87.987312) (xy 368.223069 -88.022987) (xy 368.175463 -88.052041)
			(xy 368.124134 -88.073853) (xy 368.070177 -88.087959) (xy 368.01474 -88.094059) (xy 367.959006 -88.092022)
			(xy 367.904163 -88.081892) (xy 367.851379 -88.063885) (xy 367.801779 -88.038384) (xy 367.756421 -88.005933)
			(xy 367.716272 -87.967224) (xy 367.682186 -87.923081) (xy 367.65489 -87.874446) (xy 367.634967 -87.822355)
			(xy 367.622841 -87.767918) (xy 367.61877 -87.712296) (xy 354.891844 -87.712296) (xy 354.895403 -87.73648)
			(xy 354.895912 -87.764366) (xy 354.895403 -87.792252) (xy 354.887283 -87.847428) (xy 354.871215 -87.900835)
			(xy 354.847543 -87.951332) (xy 354.81677 -87.997845) (xy 354.779553 -88.039382) (xy 354.736685 -88.075057)
			(xy 354.689079 -88.104111) (xy 354.63775 -88.125923) (xy 354.583793 -88.140029) (xy 354.528356 -88.146129)
			(xy 354.472622 -88.144092) (xy 354.417779 -88.133962) (xy 354.364995 -88.115955) (xy 354.315395 -88.090454)
			(xy 354.270037 -88.058003) (xy 354.229888 -88.019294) (xy 354.195802 -87.975151) (xy 354.168506 -87.926516)
			(xy 354.148583 -87.874425) (xy 354.136457 -87.819988) (xy 354.132386 -87.764366) (xy 346.795852 -87.764366)
			(xy 346.795852 -88.144604) (xy 346.795362 -88.174588) (xy 346.787534 -88.234044) (xy 346.772013 -88.291969)
			(xy 346.767508 -88.302846) (xy 357.714802 -88.302846) (xy 357.718873 -88.247224) (xy 357.730999 -88.192787)
			(xy 357.750922 -88.140696) (xy 357.778218 -88.092061) (xy 357.812304 -88.047918) (xy 357.852453 -88.009209)
			(xy 357.897811 -87.976758) (xy 357.947411 -87.951257) (xy 358.000195 -87.93325) (xy 358.055038 -87.92312)
			(xy 358.110772 -87.921083) (xy 358.166209 -87.927183) (xy 358.220166 -87.941289) (xy 358.271495 -87.963101)
			(xy 358.319101 -87.992155) (xy 358.361969 -88.02783) (xy 358.399186 -88.069367) (xy 358.429959 -88.11588)
			(xy 358.453631 -88.166377) (xy 358.454646 -88.16975) (xy 364.03102 -88.16975) (xy 364.035091 -88.114128)
			(xy 364.047217 -88.059691) (xy 364.06714 -88.0076) (xy 364.094436 -87.958965) (xy 364.128522 -87.914822)
			(xy 364.168671 -87.876113) (xy 364.214029 -87.843662) (xy 364.263629 -87.818161) (xy 364.316413 -87.800154)
			(xy 364.371256 -87.790024) (xy 364.42699 -87.787987) (xy 364.482427 -87.794087) (xy 364.536384 -87.808193)
			(xy 364.587713 -87.830005) (xy 364.635319 -87.859059) (xy 364.678187 -87.894734) (xy 364.715404 -87.936271)
			(xy 364.746177 -87.982784) (xy 364.769849 -88.033281) (xy 364.785917 -88.086688) (xy 364.787226 -88.095582)
			(xy 365.484662 -88.095582) (xy 365.488733 -88.03996) (xy 365.500859 -87.985523) (xy 365.520782 -87.933432)
			(xy 365.548078 -87.884797) (xy 365.582164 -87.840654) (xy 365.622313 -87.801945) (xy 365.667671 -87.769494)
			(xy 365.717271 -87.743993) (xy 365.770055 -87.725986) (xy 365.824898 -87.715856) (xy 365.880632 -87.713819)
			(xy 365.936069 -87.719919) (xy 365.990026 -87.734025) (xy 366.041355 -87.755837) (xy 366.088961 -87.784891)
			(xy 366.131829 -87.820566) (xy 366.169046 -87.862103) (xy 366.199819 -87.908616) (xy 366.223491 -87.959113)
			(xy 366.239559 -88.01252) (xy 366.247679 -88.067696) (xy 366.248188 -88.095582) (xy 366.247679 -88.123468)
			(xy 366.239559 -88.178644) (xy 366.223491 -88.232051) (xy 366.199819 -88.282548) (xy 366.169046 -88.329061)
			(xy 366.144287 -88.356694) (xy 370.219222 -88.356694) (xy 370.223293 -88.301072) (xy 370.235419 -88.246635)
			(xy 370.255342 -88.194544) (xy 370.282638 -88.145909) (xy 370.316724 -88.101766) (xy 370.356873 -88.063057)
			(xy 370.402231 -88.030606) (xy 370.451831 -88.005105) (xy 370.504615 -87.987098) (xy 370.559458 -87.976968)
			(xy 370.615192 -87.974931) (xy 370.670629 -87.981031) (xy 370.724586 -87.995137) (xy 370.775915 -88.016949)
			(xy 370.823521 -88.046003) (xy 370.866389 -88.081678) (xy 370.903606 -88.123215) (xy 370.934379 -88.169728)
			(xy 370.958051 -88.220225) (xy 370.974119 -88.273632) (xy 370.982239 -88.328808) (xy 370.982748 -88.356694)
			(xy 370.982239 -88.38458) (xy 370.974119 -88.439756) (xy 370.958051 -88.493163) (xy 370.934379 -88.54366)
			(xy 370.903606 -88.590173) (xy 370.866389 -88.63171) (xy 370.823521 -88.667385) (xy 370.775915 -88.696439)
			(xy 370.724586 -88.718251) (xy 370.670629 -88.732357) (xy 370.615192 -88.738457) (xy 370.559458 -88.73642)
			(xy 370.504615 -88.72629) (xy 370.451831 -88.708283) (xy 370.402231 -88.682782) (xy 370.356873 -88.650331)
			(xy 370.316724 -88.611622) (xy 370.282638 -88.567479) (xy 370.255342 -88.518844) (xy 370.235419 -88.466753)
			(xy 370.223293 -88.412316) (xy 370.219222 -88.356694) (xy 366.144287 -88.356694) (xy 366.131829 -88.370598)
			(xy 366.088961 -88.406273) (xy 366.041355 -88.435327) (xy 365.990026 -88.457139) (xy 365.936069 -88.471245)
			(xy 365.880632 -88.477345) (xy 365.824898 -88.475308) (xy 365.770055 -88.465178) (xy 365.717271 -88.447171)
			(xy 365.667671 -88.42167) (xy 365.622313 -88.389219) (xy 365.582164 -88.35051) (xy 365.548078 -88.306367)
			(xy 365.520782 -88.257732) (xy 365.500859 -88.205641) (xy 365.488733 -88.151204) (xy 365.484662 -88.095582)
			(xy 364.787226 -88.095582) (xy 364.794037 -88.141864) (xy 364.794546 -88.16975) (xy 364.794037 -88.197636)
			(xy 364.785917 -88.252812) (xy 364.769849 -88.306219) (xy 364.746177 -88.356716) (xy 364.715404 -88.403229)
			(xy 364.678187 -88.444766) (xy 364.635319 -88.480441) (xy 364.587713 -88.509495) (xy 364.536384 -88.531307)
			(xy 364.482427 -88.545413) (xy 364.42699 -88.551513) (xy 364.371256 -88.549476) (xy 364.316413 -88.539346)
			(xy 364.263629 -88.521339) (xy 364.214029 -88.495838) (xy 364.168671 -88.463387) (xy 364.128522 -88.424678)
			(xy 364.094436 -88.380535) (xy 364.06714 -88.3319) (xy 364.047217 -88.279809) (xy 364.035091 -88.225372)
			(xy 364.03102 -88.16975) (xy 358.454646 -88.16975) (xy 358.469699 -88.219784) (xy 358.477819 -88.27496)
			(xy 358.478328 -88.302846) (xy 358.477819 -88.330732) (xy 358.469699 -88.385908) (xy 358.453631 -88.439315)
			(xy 358.429959 -88.489812) (xy 358.399186 -88.536325) (xy 358.361969 -88.577862) (xy 358.319101 -88.613537)
			(xy 358.271495 -88.642591) (xy 358.220166 -88.664403) (xy 358.166209 -88.678509) (xy 358.110772 -88.684609)
			(xy 358.055038 -88.682572) (xy 358.000195 -88.672442) (xy 357.947411 -88.654435) (xy 357.897811 -88.628934)
			(xy 357.852453 -88.596483) (xy 357.812304 -88.557774) (xy 357.778218 -88.513631) (xy 357.750922 -88.464996)
			(xy 357.730999 -88.412905) (xy 357.718873 -88.358468) (xy 357.714802 -88.302846) (xy 346.767508 -88.302846)
			(xy 346.749064 -88.347373) (xy 346.71908 -88.399307) (xy 346.682574 -88.446883) (xy 346.640169 -88.489288)
			(xy 346.592593 -88.525794) (xy 346.540659 -88.555778) (xy 346.485255 -88.578727) (xy 346.42733 -88.594248)
			(xy 346.367874 -88.602076) (xy 346.307906 -88.602076) (xy 346.24845 -88.594248) (xy 346.190525 -88.578727)
			(xy 346.135121 -88.555778) (xy 346.083187 -88.525794) (xy 346.035611 -88.489288) (xy 345.993206 -88.446883)
			(xy 345.9567 -88.399307) (xy 345.926716 -88.347373) (xy 345.903767 -88.291969) (xy 345.888246 -88.234044)
			(xy 345.880418 -88.174588) (xy 345.879928 -88.144604) (xy 342.848692 -88.144604) (xy 342.848692 -88.756998)
			(xy 351.028762 -88.756998) (xy 351.029248 -88.729747) (xy 351.037004 -88.675799) (xy 351.052359 -88.623504)
			(xy 351.075001 -88.573927) (xy 351.104467 -88.528077) (xy 351.140158 -88.486886) (xy 351.181349 -88.451195)
			(xy 351.227199 -88.421729) (xy 351.276776 -88.399087) (xy 351.329071 -88.383732) (xy 351.383019 -88.375976)
			(xy 351.437521 -88.375976) (xy 351.491469 -88.383732) (xy 351.543764 -88.399087) (xy 351.593341 -88.421729)
			(xy 351.639191 -88.451195) (xy 351.680382 -88.486886) (xy 351.716073 -88.528077) (xy 351.745539 -88.573927)
			(xy 351.768181 -88.623504) (xy 351.783536 -88.675799) (xy 351.791292 -88.729747) (xy 351.791778 -88.756998)
			(xy 351.791327 -88.782508) (xy 351.784543 -88.833076) (xy 351.771081 -88.882289) (xy 351.751182 -88.929269)
			(xy 351.725202 -88.97318) (xy 351.709736 -88.993472) (xy 351.701773 -89.004257) (xy 351.691233 -89.028898)
			(xy 351.690457 -89.034366) (xy 354.132386 -89.034366) (xy 354.136457 -88.978744) (xy 354.148583 -88.924307)
			(xy 354.168506 -88.872216) (xy 354.195802 -88.823581) (xy 354.229888 -88.779438) (xy 354.270037 -88.740729)
			(xy 354.315395 -88.708278) (xy 354.364995 -88.682777) (xy 354.417779 -88.66477) (xy 354.472622 -88.65464)
			(xy 354.528356 -88.652603) (xy 354.583793 -88.658703) (xy 354.63775 -88.672809) (xy 354.689079 -88.694621)
			(xy 354.736685 -88.723675) (xy 354.779553 -88.75935) (xy 354.81677 -88.800887) (xy 354.847543 -88.8474)
			(xy 354.871215 -88.897897) (xy 354.887283 -88.951304) (xy 354.894199 -88.998298) (xy 365.306608 -88.998298)
			(xy 365.310679 -88.942676) (xy 365.322805 -88.888239) (xy 365.342728 -88.836148) (xy 365.370024 -88.787513)
			(xy 365.40411 -88.74337) (xy 365.444259 -88.704661) (xy 365.489617 -88.67221) (xy 365.539217 -88.646709)
			(xy 365.592001 -88.628702) (xy 365.646844 -88.618572) (xy 365.702578 -88.616535) (xy 365.758015 -88.622635)
			(xy 365.811972 -88.636741) (xy 365.863301 -88.658553) (xy 365.910907 -88.687607) (xy 365.953775 -88.723282)
			(xy 365.984895 -88.758014) (xy 367.55578 -88.758014) (xy 367.556266 -88.730763) (xy 367.564022 -88.676815)
			(xy 367.579377 -88.62452) (xy 367.602019 -88.574943) (xy 367.631485 -88.529093) (xy 367.667176 -88.487902)
			(xy 367.708367 -88.452211) (xy 367.754217 -88.422745) (xy 367.803794 -88.400103) (xy 367.856089 -88.384748)
			(xy 367.910037 -88.376992) (xy 367.964539 -88.376992) (xy 368.018487 -88.384748) (xy 368.070782 -88.400103)
			(xy 368.120359 -88.422745) (xy 368.166209 -88.452211) (xy 368.2074 -88.487902) (xy 368.243091 -88.529093)
			(xy 368.272557 -88.574943) (xy 368.295199 -88.62452) (xy 368.310554 -88.676815) (xy 368.31831 -88.730763)
			(xy 368.318796 -88.758014) (xy 368.318796 -88.758268) (xy 368.318301 -88.785979) (xy 368.312775 -88.8238)
			(xy 374.915428 -88.8238) (xy 374.919499 -88.768178) (xy 374.931625 -88.713741) (xy 374.951548 -88.66165)
			(xy 374.978844 -88.613015) (xy 375.01293 -88.568872) (xy 375.053079 -88.530163) (xy 375.098437 -88.497712)
			(xy 375.148037 -88.472211) (xy 375.200821 -88.454204) (xy 375.255664 -88.444074) (xy 375.311398 -88.442037)
			(xy 375.366835 -88.448137) (xy 375.420792 -88.462243) (xy 375.472121 -88.484055) (xy 375.519727 -88.513109)
			(xy 375.562595 -88.548784) (xy 375.599812 -88.590321) (xy 375.630585 -88.636834) (xy 375.654257 -88.687331)
			(xy 375.670325 -88.740738) (xy 375.678445 -88.795914) (xy 375.678954 -88.8238) (xy 377.153422 -88.8238)
			(xy 377.157493 -88.768178) (xy 377.169619 -88.713741) (xy 377.189542 -88.66165) (xy 377.216838 -88.613015)
			(xy 377.250924 -88.568872) (xy 377.291073 -88.530163) (xy 377.336431 -88.497712) (xy 377.386031 -88.472211)
			(xy 377.438815 -88.454204) (xy 377.493658 -88.444074) (xy 377.549392 -88.442037) (xy 377.604829 -88.448137)
			(xy 377.658786 -88.462243) (xy 377.710115 -88.484055) (xy 377.757721 -88.513109) (xy 377.800589 -88.548784)
			(xy 377.837806 -88.590321) (xy 377.868579 -88.636834) (xy 377.892251 -88.687331) (xy 377.908319 -88.740738)
			(xy 377.916439 -88.795914) (xy 377.91686 -88.818974) (xy 379.480316 -88.818974) (xy 379.484387 -88.763352)
			(xy 379.496513 -88.708915) (xy 379.516436 -88.656824) (xy 379.543732 -88.608189) (xy 379.577818 -88.564046)
			(xy 379.617967 -88.525337) (xy 379.663325 -88.492886) (xy 379.712925 -88.467385) (xy 379.765709 -88.449378)
			(xy 379.820552 -88.439248) (xy 379.876286 -88.437211) (xy 379.931723 -88.443311) (xy 379.98568 -88.457417)
			(xy 380.037009 -88.479229) (xy 380.084615 -88.508283) (xy 380.127483 -88.543958) (xy 380.1647 -88.585495)
			(xy 380.195473 -88.632008) (xy 380.219145 -88.682505) (xy 380.235213 -88.735912) (xy 380.243333 -88.791088)
			(xy 380.243842 -88.818974) (xy 380.243333 -88.84686) (xy 380.235213 -88.902036) (xy 380.219145 -88.955443)
			(xy 380.195473 -89.00594) (xy 380.1647 -89.052453) (xy 380.127483 -89.09399) (xy 380.084615 -89.129665)
			(xy 380.037009 -89.158719) (xy 379.98568 -89.180531) (xy 379.931723 -89.194637) (xy 379.876286 -89.200737)
			(xy 379.820552 -89.1987) (xy 379.765709 -89.18857) (xy 379.712925 -89.170563) (xy 379.663325 -89.145062)
			(xy 379.617967 -89.112611) (xy 379.577818 -89.073902) (xy 379.543732 -89.029759) (xy 379.516436 -88.981124)
			(xy 379.496513 -88.929033) (xy 379.484387 -88.874596) (xy 379.480316 -88.818974) (xy 377.91686 -88.818974)
			(xy 377.916948 -88.8238) (xy 377.916439 -88.851686) (xy 377.908319 -88.906862) (xy 377.892251 -88.960269)
			(xy 377.868579 -89.010766) (xy 377.837806 -89.057279) (xy 377.800589 -89.098816) (xy 377.757721 -89.134491)
			(xy 377.710115 -89.163545) (xy 377.658786 -89.185357) (xy 377.604829 -89.199463) (xy 377.549392 -89.205563)
			(xy 377.493658 -89.203526) (xy 377.438815 -89.193396) (xy 377.386031 -89.175389) (xy 377.336431 -89.149888)
			(xy 377.291073 -89.117437) (xy 377.250924 -89.078728) (xy 377.216838 -89.034585) (xy 377.189542 -88.98595)
			(xy 377.169619 -88.933859) (xy 377.157493 -88.879422) (xy 377.153422 -88.8238) (xy 375.678954 -88.8238)
			(xy 375.678445 -88.851686) (xy 375.670325 -88.906862) (xy 375.654257 -88.960269) (xy 375.630585 -89.010766)
			(xy 375.599812 -89.057279) (xy 375.562595 -89.098816) (xy 375.519727 -89.134491) (xy 375.472121 -89.163545)
			(xy 375.420792 -89.185357) (xy 375.366835 -89.199463) (xy 375.311398 -89.205563) (xy 375.255664 -89.203526)
			(xy 375.200821 -89.193396) (xy 375.148037 -89.175389) (xy 375.098437 -89.149888) (xy 375.053079 -89.117437)
			(xy 375.01293 -89.078728) (xy 374.978844 -89.034585) (xy 374.951548 -88.98595) (xy 374.931625 -88.933859)
			(xy 374.919499 -88.879422) (xy 374.915428 -88.8238) (xy 368.312775 -88.8238) (xy 368.310288 -88.840817)
			(xy 368.294412 -88.893916) (xy 368.271008 -88.944153) (xy 368.240571 -88.990467) (xy 368.22253 -89.011506)
			(xy 368.214656 -89.020142) (xy 368.208306 -89.041986) (xy 368.223292 -89.131394) (xy 368.225638 -89.142656)
			(xy 368.238891 -89.161436) (xy 368.248692 -89.167462) (xy 368.273516 -89.182113) (xy 368.318894 -89.217652)
			(xy 368.358408 -89.259615) (xy 368.391156 -89.307046) (xy 368.416393 -89.358866) (xy 368.433545 -89.413893)
			(xy 368.44222 -89.470875) (xy 368.442748 -89.499694) (xy 370.219222 -89.499694) (xy 370.223293 -89.444072)
			(xy 370.235419 -89.389635) (xy 370.255342 -89.337544) (xy 370.282638 -89.288909) (xy 370.316724 -89.244766)
			(xy 370.356873 -89.206057) (xy 370.402231 -89.173606) (xy 370.451831 -89.148105) (xy 370.504615 -89.130098)
			(xy 370.559458 -89.119968) (xy 370.615192 -89.117931) (xy 370.670629 -89.124031) (xy 370.724586 -89.138137)
			(xy 370.775915 -89.159949) (xy 370.823521 -89.189003) (xy 370.866389 -89.224678) (xy 370.903606 -89.266215)
			(xy 370.934379 -89.312728) (xy 370.958051 -89.363225) (xy 370.974119 -89.416632) (xy 370.982239 -89.471808)
			(xy 370.982748 -89.499694) (xy 370.982239 -89.52758) (xy 370.974119 -89.582756) (xy 370.958051 -89.636163)
			(xy 370.934379 -89.68666) (xy 370.903606 -89.733173) (xy 370.866389 -89.77471) (xy 370.823521 -89.810385)
			(xy 370.775915 -89.839439) (xy 370.724586 -89.861251) (xy 370.670629 -89.875357) (xy 370.615192 -89.881457)
			(xy 370.559458 -89.87942) (xy 370.504615 -89.86929) (xy 370.451831 -89.851283) (xy 370.402231 -89.825782)
			(xy 370.356873 -89.793331) (xy 370.316724 -89.754622) (xy 370.282638 -89.710479) (xy 370.255342 -89.661844)
			(xy 370.235419 -89.609753) (xy 370.223293 -89.555316) (xy 370.219222 -89.499694) (xy 368.442748 -89.499694)
			(xy 368.442262 -89.526945) (xy 368.434506 -89.580893) (xy 368.419151 -89.633188) (xy 368.396509 -89.682765)
			(xy 368.367043 -89.728615) (xy 368.331352 -89.769806) (xy 368.290161 -89.805497) (xy 368.244311 -89.834963)
			(xy 368.194734 -89.857605) (xy 368.142439 -89.87296) (xy 368.088491 -89.880716) (xy 368.033989 -89.880716)
			(xy 367.980041 -89.87296) (xy 367.927746 -89.857605) (xy 367.878169 -89.834963) (xy 367.832319 -89.805497)
			(xy 367.791128 -89.769806) (xy 367.755437 -89.728615) (xy 367.725971 -89.682765) (xy 367.703329 -89.633188)
			(xy 367.687974 -89.580893) (xy 367.680218 -89.526945) (xy 367.679732 -89.499694) (xy 367.679732 -89.49944)
			(xy 367.680225 -89.471729) (xy 367.688237 -89.41689) (xy 367.704113 -89.363792) (xy 367.727518 -89.313555)
			(xy 367.757956 -89.26724) (xy 367.775998 -89.246202) (xy 367.783872 -89.237566) (xy 367.790222 -89.215722)
			(xy 367.775236 -89.126314) (xy 367.772874 -89.115057) (xy 367.759632 -89.096276) (xy 367.749836 -89.090246)
			(xy 367.724978 -89.075649) (xy 367.679598 -89.040103) (xy 367.640085 -88.998132) (xy 367.60734 -88.950691)
			(xy 367.582108 -88.898862) (xy 367.564965 -88.843826) (xy 367.556302 -88.786836) (xy 367.55578 -88.758014)
			(xy 365.984895 -88.758014) (xy 365.990992 -88.764819) (xy 366.021765 -88.811332) (xy 366.045437 -88.861829)
			(xy 366.061505 -88.915236) (xy 366.069625 -88.970412) (xy 366.070134 -88.998298) (xy 366.069625 -89.026184)
			(xy 366.061505 -89.08136) (xy 366.045437 -89.134767) (xy 366.021765 -89.185264) (xy 365.990992 -89.231777)
			(xy 365.953775 -89.273314) (xy 365.910907 -89.308989) (xy 365.863301 -89.338043) (xy 365.811972 -89.359855)
			(xy 365.758015 -89.373961) (xy 365.702578 -89.380061) (xy 365.646844 -89.378024) (xy 365.592001 -89.367894)
			(xy 365.539217 -89.349887) (xy 365.489617 -89.324386) (xy 365.444259 -89.291935) (xy 365.40411 -89.253226)
			(xy 365.370024 -89.209083) (xy 365.342728 -89.160448) (xy 365.322805 -89.108357) (xy 365.310679 -89.05392)
			(xy 365.306608 -88.998298) (xy 354.894199 -88.998298) (xy 354.895403 -89.00648) (xy 354.895912 -89.034366)
			(xy 354.895403 -89.062252) (xy 354.887283 -89.117428) (xy 354.871215 -89.170835) (xy 354.847543 -89.221332)
			(xy 354.81677 -89.267845) (xy 354.779553 -89.309382) (xy 354.736685 -89.345057) (xy 354.689079 -89.374111)
			(xy 354.63775 -89.395923) (xy 354.583793 -89.410029) (xy 354.528356 -89.416129) (xy 354.472622 -89.414092)
			(xy 354.417779 -89.403962) (xy 354.364995 -89.385955) (xy 354.315395 -89.360454) (xy 354.270037 -89.328003)
			(xy 354.229888 -89.289294) (xy 354.195802 -89.245151) (xy 354.168506 -89.196516) (xy 354.148583 -89.144425)
			(xy 354.136457 -89.089988) (xy 354.132386 -89.034366) (xy 351.690457 -89.034366) (xy 351.687465 -89.055432)
			(xy 351.690729 -89.082033) (xy 351.7008 -89.106869) (xy 351.716985 -89.12823) (xy 351.73817 -89.144646)
			(xy 351.750376 -89.15019) (xy 351.776044 -89.161469) (xy 351.824052 -89.190426) (xy 351.867306 -89.226095)
			(xy 351.904876 -89.267709) (xy 351.935953 -89.314373) (xy 351.959868 -89.365081) (xy 351.976106 -89.418742)
			(xy 351.984319 -89.474202) (xy 351.984773 -89.499694) (xy 364.315754 -89.499694) (xy 364.319825 -89.444072)
			(xy 364.331951 -89.389635) (xy 364.351874 -89.337544) (xy 364.37917 -89.288909) (xy 364.413256 -89.244766)
			(xy 364.453405 -89.206057) (xy 364.498763 -89.173606) (xy 364.548363 -89.148105) (xy 364.601147 -89.130098)
			(xy 364.65599 -89.119968) (xy 364.711724 -89.117931) (xy 364.767161 -89.124031) (xy 364.821118 -89.138137)
			(xy 364.872447 -89.159949) (xy 364.920053 -89.189003) (xy 364.962921 -89.224678) (xy 365.000138 -89.266215)
			(xy 365.030911 -89.312728) (xy 365.054583 -89.363225) (xy 365.070651 -89.416632) (xy 365.078771 -89.471808)
			(xy 365.07928 -89.499694) (xy 365.078771 -89.52758) (xy 365.070651 -89.582756) (xy 365.054583 -89.636163)
			(xy 365.030911 -89.68666) (xy 365.000138 -89.733173) (xy 364.962921 -89.77471) (xy 364.920053 -89.810385)
			(xy 364.872447 -89.839439) (xy 364.821118 -89.861251) (xy 364.767161 -89.875357) (xy 364.711724 -89.881457)
			(xy 364.65599 -89.87942) (xy 364.601147 -89.86929) (xy 364.548363 -89.851283) (xy 364.498763 -89.825782)
			(xy 364.453405 -89.793331) (xy 364.413256 -89.754622) (xy 364.37917 -89.710479) (xy 364.351874 -89.661844)
			(xy 364.331951 -89.609753) (xy 364.319825 -89.555316) (xy 364.315754 -89.499694) (xy 351.984773 -89.499694)
			(xy 351.984818 -89.502234) (xy 351.984332 -89.529485) (xy 351.976576 -89.583433) (xy 351.961221 -89.635728)
			(xy 351.938579 -89.685305) (xy 351.909113 -89.731155) (xy 351.873422 -89.772346) (xy 351.832231 -89.808037)
			(xy 351.786381 -89.837503) (xy 351.736804 -89.860145) (xy 351.684509 -89.8755) (xy 351.630561 -89.883256)
			(xy 351.576059 -89.883256) (xy 351.522111 -89.8755) (xy 351.469816 -89.860145) (xy 351.420239 -89.837503)
			(xy 351.374389 -89.808037) (xy 351.333198 -89.772346) (xy 351.297507 -89.731155) (xy 351.268041 -89.685305)
			(xy 351.245399 -89.635728) (xy 351.230044 -89.583433) (xy 351.222288 -89.529485) (xy 351.221802 -89.502234)
			(xy 351.22222 -89.476722) (xy 351.229013 -89.426154) (xy 351.242482 -89.37694) (xy 351.262388 -89.329961)
			(xy 351.288375 -89.286051) (xy 351.303844 -89.26576) (xy 351.311777 -89.254953) (xy 351.322323 -89.230319)
			(xy 351.326097 -89.203789) (xy 351.322838 -89.177192) (xy 351.312772 -89.152358) (xy 351.29659 -89.130998)
			(xy 351.275409 -89.114585) (xy 351.263204 -89.109042) (xy 351.237528 -89.097778) (xy 351.189516 -89.068824)
			(xy 351.146258 -89.033155) (xy 351.108686 -88.991539) (xy 351.077609 -88.944873) (xy 351.053696 -88.894161)
			(xy 351.037462 -88.840495) (xy 351.029257 -88.785032) (xy 351.028762 -88.756998) (xy 342.848692 -88.756998)
			(xy 342.848692 -90.1446) (xy 346.641928 -90.1446) (xy 346.641928 -89.281) (xy 346.642418 -89.251016)
			(xy 346.650246 -89.19156) (xy 346.665767 -89.133635) (xy 346.688716 -89.078231) (xy 346.7187 -89.026297)
			(xy 346.755206 -88.978721) (xy 346.797611 -88.936316) (xy 346.845187 -88.89981) (xy 346.897121 -88.869826)
			(xy 346.952525 -88.846877) (xy 347.01045 -88.831356) (xy 347.069906 -88.823528) (xy 347.129874 -88.823528)
			(xy 347.18933 -88.831356) (xy 347.247255 -88.846877) (xy 347.302659 -88.869826) (xy 347.354593 -88.89981)
			(xy 347.402169 -88.936316) (xy 347.444574 -88.978721) (xy 347.48108 -89.026297) (xy 347.511064 -89.078231)
			(xy 347.534013 -89.133635) (xy 347.549534 -89.19156) (xy 347.557362 -89.251016) (xy 347.557852 -89.281)
			(xy 347.557852 -90.1446) (xy 347.557362 -90.174584) (xy 347.549534 -90.23404) (xy 347.534013 -90.291965)
			(xy 347.511064 -90.347369) (xy 347.48108 -90.399303) (xy 347.444574 -90.446879) (xy 347.402169 -90.489284)
			(xy 347.354593 -90.52579) (xy 347.302659 -90.555774) (xy 347.247255 -90.578723) (xy 347.18933 -90.594244)
			(xy 347.129874 -90.602072) (xy 347.069906 -90.602072) (xy 347.01045 -90.594244) (xy 346.952525 -90.578723)
			(xy 346.897121 -90.555774) (xy 346.845187 -90.52579) (xy 346.797611 -90.489284) (xy 346.755206 -90.446879)
			(xy 346.7187 -90.399303) (xy 346.688716 -90.347369) (xy 346.665767 -90.291965) (xy 346.650246 -90.23404)
			(xy 346.642418 -90.174584) (xy 346.641928 -90.1446) (xy 342.848692 -90.1446) (xy 342.848692 -90.645234)
			(xy 348.886524 -90.645234) (xy 348.890595 -90.589612) (xy 348.902721 -90.535175) (xy 348.922644 -90.483084)
			(xy 348.94994 -90.434449) (xy 348.984026 -90.390306) (xy 349.024175 -90.351597) (xy 349.069533 -90.319146)
			(xy 349.119133 -90.293645) (xy 349.171917 -90.275638) (xy 349.22676 -90.265508) (xy 349.282494 -90.263471)
			(xy 349.337931 -90.269571) (xy 349.391888 -90.283677) (xy 349.440574 -90.304366) (xy 354.132386 -90.304366)
			(xy 354.136457 -90.248744) (xy 354.148583 -90.194307) (xy 354.168506 -90.142216) (xy 354.195802 -90.093581)
			(xy 354.229888 -90.049438) (xy 354.270037 -90.010729) (xy 354.315395 -89.978278) (xy 354.364995 -89.952777)
			(xy 354.417779 -89.93477) (xy 354.472622 -89.92464) (xy 354.528356 -89.922603) (xy 354.583793 -89.928703)
			(xy 354.63775 -89.942809) (xy 354.689079 -89.964621) (xy 354.736685 -89.993675) (xy 354.779553 -90.02935)
			(xy 354.81677 -90.070887) (xy 354.847543 -90.1174) (xy 354.861365 -90.146886) (xy 365.677702 -90.146886)
			(xy 365.681773 -90.091264) (xy 365.693899 -90.036827) (xy 365.713822 -89.984736) (xy 365.741118 -89.936101)
			(xy 365.775204 -89.891958) (xy 365.815353 -89.853249) (xy 365.860711 -89.820798) (xy 365.910311 -89.795297)
			(xy 365.963095 -89.77729) (xy 366.017938 -89.76716) (xy 366.073672 -89.765123) (xy 366.129109 -89.771223)
			(xy 366.183066 -89.785329) (xy 366.234395 -89.807141) (xy 366.282001 -89.836195) (xy 366.324869 -89.87187)
			(xy 366.362086 -89.913407) (xy 366.392859 -89.95992) (xy 366.396084 -89.9668) (xy 374.915428 -89.9668)
			(xy 374.919499 -89.911178) (xy 374.931625 -89.856741) (xy 374.951548 -89.80465) (xy 374.978844 -89.756015)
			(xy 375.01293 -89.711872) (xy 375.053079 -89.673163) (xy 375.098437 -89.640712) (xy 375.148037 -89.615211)
			(xy 375.200821 -89.597204) (xy 375.255664 -89.587074) (xy 375.311398 -89.585037) (xy 375.366835 -89.591137)
			(xy 375.420792 -89.605243) (xy 375.472121 -89.627055) (xy 375.519727 -89.656109) (xy 375.562595 -89.691784)
			(xy 375.599812 -89.733321) (xy 375.630585 -89.779834) (xy 375.654257 -89.830331) (xy 375.670325 -89.883738)
			(xy 375.678445 -89.938914) (xy 375.678954 -89.9668) (xy 375.678445 -89.994686) (xy 375.670325 -90.049862)
			(xy 375.654257 -90.103269) (xy 375.630585 -90.153766) (xy 375.599812 -90.200279) (xy 375.562595 -90.241816)
			(xy 375.519727 -90.277491) (xy 375.472121 -90.306545) (xy 375.420792 -90.328357) (xy 375.366835 -90.342463)
			(xy 375.311398 -90.348563) (xy 375.255664 -90.346526) (xy 375.200821 -90.336396) (xy 375.148037 -90.318389)
			(xy 375.098437 -90.292888) (xy 375.053079 -90.260437) (xy 375.01293 -90.221728) (xy 374.978844 -90.177585)
			(xy 374.951548 -90.12895) (xy 374.931625 -90.076859) (xy 374.919499 -90.022422) (xy 374.915428 -89.9668)
			(xy 366.396084 -89.9668) (xy 366.416531 -90.010417) (xy 366.432599 -90.063824) (xy 366.440719 -90.119)
			(xy 366.441228 -90.146886) (xy 366.440719 -90.174772) (xy 366.432599 -90.229948) (xy 366.416531 -90.283355)
			(xy 366.392859 -90.333852) (xy 366.362086 -90.380365) (xy 366.324869 -90.421902) (xy 366.282001 -90.457577)
			(xy 366.234395 -90.486631) (xy 366.183066 -90.508443) (xy 366.129109 -90.522549) (xy 366.073672 -90.528649)
			(xy 366.017938 -90.526612) (xy 365.963095 -90.516482) (xy 365.910311 -90.498475) (xy 365.860711 -90.472974)
			(xy 365.815353 -90.440523) (xy 365.775204 -90.401814) (xy 365.741118 -90.357671) (xy 365.713822 -90.309036)
			(xy 365.693899 -90.256945) (xy 365.681773 -90.202508) (xy 365.677702 -90.146886) (xy 354.861365 -90.146886)
			(xy 354.871215 -90.167897) (xy 354.887283 -90.221304) (xy 354.895403 -90.27648) (xy 354.895912 -90.304366)
			(xy 354.895403 -90.332252) (xy 354.887283 -90.387428) (xy 354.871215 -90.440835) (xy 354.847543 -90.491332)
			(xy 354.81677 -90.537845) (xy 354.779553 -90.579382) (xy 354.736685 -90.615057) (xy 354.691401 -90.642694)
			(xy 367.679222 -90.642694) (xy 367.683293 -90.587072) (xy 367.695419 -90.532635) (xy 367.715342 -90.480544)
			(xy 367.742638 -90.431909) (xy 367.776724 -90.387766) (xy 367.816873 -90.349057) (xy 367.862231 -90.316606)
			(xy 367.911831 -90.291105) (xy 367.964615 -90.273098) (xy 368.019458 -90.262968) (xy 368.075192 -90.260931)
			(xy 368.130629 -90.267031) (xy 368.184586 -90.281137) (xy 368.235915 -90.302949) (xy 368.283521 -90.332003)
			(xy 368.326389 -90.367678) (xy 368.363606 -90.409215) (xy 368.394379 -90.455728) (xy 368.418051 -90.506225)
			(xy 368.434119 -90.559632) (xy 368.442239 -90.614808) (xy 368.442748 -90.642694) (xy 368.442239 -90.67058)
			(xy 368.434119 -90.725756) (xy 368.418051 -90.779163) (xy 368.394379 -90.82966) (xy 368.363606 -90.876173)
			(xy 368.326389 -90.91771) (xy 368.283521 -90.953385) (xy 368.235915 -90.982439) (xy 368.184586 -91.004251)
			(xy 368.130629 -91.018357) (xy 368.075192 -91.024457) (xy 368.019458 -91.02242) (xy 367.964615 -91.01229)
			(xy 367.911831 -90.994283) (xy 367.862231 -90.968782) (xy 367.816873 -90.936331) (xy 367.776724 -90.897622)
			(xy 367.742638 -90.853479) (xy 367.715342 -90.804844) (xy 367.695419 -90.752753) (xy 367.683293 -90.698316)
			(xy 367.679222 -90.642694) (xy 354.691401 -90.642694) (xy 354.689079 -90.644111) (xy 354.63775 -90.665923)
			(xy 354.583793 -90.680029) (xy 354.528356 -90.686129) (xy 354.472622 -90.684092) (xy 354.417779 -90.673962)
			(xy 354.364995 -90.655955) (xy 354.315395 -90.630454) (xy 354.270037 -90.598003) (xy 354.229888 -90.559294)
			(xy 354.195802 -90.515151) (xy 354.168506 -90.466516) (xy 354.148583 -90.414425) (xy 354.136457 -90.359988)
			(xy 354.132386 -90.304366) (xy 349.440574 -90.304366) (xy 349.443217 -90.305489) (xy 349.490823 -90.334543)
			(xy 349.533691 -90.370218) (xy 349.570908 -90.411755) (xy 349.601681 -90.458268) (xy 349.625353 -90.508765)
			(xy 349.641421 -90.562172) (xy 349.649541 -90.617348) (xy 349.65005 -90.645234) (xy 349.649541 -90.67312)
			(xy 349.641421 -90.728296) (xy 349.625353 -90.781703) (xy 349.601681 -90.8322) (xy 349.570908 -90.878713)
			(xy 349.533691 -90.92025) (xy 349.490823 -90.955925) (xy 349.443217 -90.984979) (xy 349.391888 -91.006791)
			(xy 349.337931 -91.020897) (xy 349.282494 -91.026997) (xy 349.22676 -91.02496) (xy 349.171917 -91.01483)
			(xy 349.119133 -90.996823) (xy 349.069533 -90.971322) (xy 349.024175 -90.938871) (xy 348.984026 -90.900162)
			(xy 348.94994 -90.856019) (xy 348.922644 -90.807384) (xy 348.902721 -90.755293) (xy 348.890595 -90.700856)
			(xy 348.886524 -90.645234) (xy 342.848692 -90.645234) (xy 342.848692 -91.1098) (xy 374.915428 -91.1098)
			(xy 374.919499 -91.054178) (xy 374.931625 -90.999741) (xy 374.951548 -90.94765) (xy 374.978844 -90.899015)
			(xy 375.01293 -90.854872) (xy 375.053079 -90.816163) (xy 375.098437 -90.783712) (xy 375.148037 -90.758211)
			(xy 375.200821 -90.740204) (xy 375.255664 -90.730074) (xy 375.311398 -90.728037) (xy 375.366835 -90.734137)
			(xy 375.420792 -90.748243) (xy 375.472121 -90.770055) (xy 375.519727 -90.799109) (xy 375.562595 -90.834784)
			(xy 375.599812 -90.876321) (xy 375.630585 -90.922834) (xy 375.654257 -90.973331) (xy 375.670325 -91.026738)
			(xy 375.678445 -91.081914) (xy 375.678954 -91.1098) (xy 379.582932 -91.1098) (xy 379.587003 -91.054178)
			(xy 379.599129 -90.999741) (xy 379.619052 -90.94765) (xy 379.646348 -90.899015) (xy 379.680434 -90.854872)
			(xy 379.720583 -90.816163) (xy 379.765941 -90.783712) (xy 379.815541 -90.758211) (xy 379.868325 -90.740204)
			(xy 379.923168 -90.730074) (xy 379.978902 -90.728037) (xy 380.034339 -90.734137) (xy 380.088296 -90.748243)
			(xy 380.139625 -90.770055) (xy 380.187231 -90.799109) (xy 380.230099 -90.834784) (xy 380.267316 -90.876321)
			(xy 380.298089 -90.922834) (xy 380.321761 -90.973331) (xy 380.337829 -91.026738) (xy 380.345949 -91.081914)
			(xy 380.346458 -91.1098) (xy 380.345949 -91.137686) (xy 380.337829 -91.192862) (xy 380.321761 -91.246269)
			(xy 380.298089 -91.296766) (xy 380.267316 -91.343279) (xy 380.230099 -91.384816) (xy 380.187231 -91.420491)
			(xy 380.139625 -91.449545) (xy 380.088296 -91.471357) (xy 380.034339 -91.485463) (xy 379.978902 -91.491563)
			(xy 379.923168 -91.489526) (xy 379.868325 -91.479396) (xy 379.815541 -91.461389) (xy 379.765941 -91.435888)
			(xy 379.720583 -91.403437) (xy 379.680434 -91.364728) (xy 379.646348 -91.320585) (xy 379.619052 -91.27195)
			(xy 379.599129 -91.219859) (xy 379.587003 -91.165422) (xy 379.582932 -91.1098) (xy 375.678954 -91.1098)
			(xy 375.678445 -91.137686) (xy 375.670325 -91.192862) (xy 375.654257 -91.246269) (xy 375.630585 -91.296766)
			(xy 375.599812 -91.343279) (xy 375.562595 -91.384816) (xy 375.519727 -91.420491) (xy 375.472121 -91.449545)
			(xy 375.420792 -91.471357) (xy 375.366835 -91.485463) (xy 375.311398 -91.491563) (xy 375.255664 -91.489526)
			(xy 375.200821 -91.479396) (xy 375.148037 -91.461389) (xy 375.098437 -91.435888) (xy 375.053079 -91.403437)
			(xy 375.01293 -91.364728) (xy 374.978844 -91.320585) (xy 374.951548 -91.27195) (xy 374.931625 -91.219859)
			(xy 374.919499 -91.165422) (xy 374.915428 -91.1098) (xy 342.848692 -91.1098) (xy 342.848692 -91.227402)
			(xy 342.848263 -91.251375) (xy 342.840764 -91.29873) (xy 342.825938 -91.344324) (xy 342.804149 -91.387032)
			(xy 342.775937 -91.425798) (xy 342.759284 -91.443048) (xy 342.405377 -91.796955) (xy 348.165847 -91.796955)
			(xy 348.165847 -91.742445) (xy 348.173605 -91.688491) (xy 348.188963 -91.63619) (xy 348.211608 -91.586607)
			(xy 348.241079 -91.540751) (xy 348.276777 -91.499557) (xy 348.317974 -91.463863) (xy 348.363831 -91.434395)
			(xy 348.413416 -91.411753) (xy 348.465718 -91.396399) (xy 348.519673 -91.388645) (xy 348.546928 -91.388184)
			(xy 348.574574 -91.388676) (xy 348.629285 -91.396678) (xy 348.682268 -91.412496) (xy 348.732411 -91.435799)
			(xy 348.778664 -91.466098) (xy 348.820057 -91.502757) (xy 348.838266 -91.523566) (xy 348.845593 -91.531385)
			(xy 348.864916 -91.540599) (xy 348.875604 -91.541346) (xy 348.962726 -91.543886) (xy 348.982792 -91.53525)
			(xy 348.990158 -91.527376) (xy 349.008249 -91.508679) (xy 349.048654 -91.475902) (xy 349.093138 -91.44892)
			(xy 349.140876 -91.428235) (xy 349.190983 -91.41423) (xy 349.242528 -91.407165) (xy 349.268542 -91.406726)
			(xy 349.295794 -91.407147) (xy 349.349742 -91.414909) (xy 349.402036 -91.430269) (xy 349.451612 -91.452914)
			(xy 349.497462 -91.482385) (xy 349.538651 -91.518079) (xy 349.574341 -91.559272) (xy 349.584041 -91.574366)
			(xy 354.132386 -91.574366) (xy 354.136457 -91.518744) (xy 354.148583 -91.464307) (xy 354.168506 -91.412216)
			(xy 354.195802 -91.363581) (xy 354.229888 -91.319438) (xy 354.270037 -91.280729) (xy 354.315395 -91.248278)
			(xy 354.364995 -91.222777) (xy 354.417779 -91.20477) (xy 354.472622 -91.19464) (xy 354.528356 -91.192603)
			(xy 354.583793 -91.198703) (xy 354.63775 -91.212809) (xy 354.689079 -91.234621) (xy 354.736685 -91.263675)
			(xy 354.779553 -91.29935) (xy 354.81677 -91.340887) (xy 354.847543 -91.3874) (xy 354.871215 -91.437897)
			(xy 354.887283 -91.491304) (xy 354.895403 -91.54648) (xy 354.895912 -91.574366) (xy 354.895403 -91.602252)
			(xy 354.887283 -91.657428) (xy 354.871215 -91.710835) (xy 354.847543 -91.761332) (xy 354.81677 -91.807845)
			(xy 354.779553 -91.849382) (xy 354.736685 -91.885057) (xy 354.689079 -91.914111) (xy 354.63775 -91.935923)
			(xy 354.583793 -91.950029) (xy 354.528356 -91.956129) (xy 354.472622 -91.954092) (xy 354.417779 -91.943962)
			(xy 354.364995 -91.925955) (xy 354.315395 -91.900454) (xy 354.270037 -91.868003) (xy 354.229888 -91.829294)
			(xy 354.195802 -91.785151) (xy 354.168506 -91.736516) (xy 354.148583 -91.684425) (xy 354.136457 -91.629988)
			(xy 354.132386 -91.574366) (xy 349.584041 -91.574366) (xy 349.603806 -91.605124) (xy 349.626446 -91.654703)
			(xy 349.6418 -91.706999) (xy 349.649556 -91.760948) (xy 349.649556 -91.815452) (xy 349.6418 -91.869401)
			(xy 349.626446 -91.921697) (xy 349.603806 -91.971276) (xy 349.58465 -92.001086) (xy 356.409242 -92.001086)
			(xy 356.413313 -91.945464) (xy 356.425439 -91.891027) (xy 356.445362 -91.838936) (xy 356.472658 -91.790301)
			(xy 356.506744 -91.746158) (xy 356.546893 -91.707449) (xy 356.592251 -91.674998) (xy 356.641851 -91.649497)
			(xy 356.694635 -91.63149) (xy 356.749478 -91.62136) (xy 356.805212 -91.619323) (xy 356.860649 -91.625423)
			(xy 356.914074 -91.63939) (xy 367.28349 -91.63939) (xy 367.287561 -91.583768) (xy 367.299687 -91.529331)
			(xy 367.31961 -91.47724) (xy 367.346906 -91.428605) (xy 367.380992 -91.384462) (xy 367.421141 -91.345753)
			(xy 367.466499 -91.313302) (xy 367.516099 -91.287801) (xy 367.568883 -91.269794) (xy 367.623726 -91.259664)
			(xy 367.67946 -91.257627) (xy 367.734897 -91.263727) (xy 367.788854 -91.277833) (xy 367.840183 -91.299645)
			(xy 367.887789 -91.328699) (xy 367.930657 -91.364374) (xy 367.967874 -91.405911) (xy 367.998647 -91.452424)
			(xy 368.022319 -91.502921) (xy 368.038387 -91.556328) (xy 368.046507 -91.611504) (xy 368.047016 -91.63939)
			(xy 368.046507 -91.667276) (xy 368.038387 -91.722452) (xy 368.022319 -91.775859) (xy 367.998647 -91.826356)
			(xy 367.967874 -91.872869) (xy 367.930657 -91.914406) (xy 367.887789 -91.950081) (xy 367.840183 -91.979135)
			(xy 367.788854 -92.000947) (xy 367.734897 -92.015053) (xy 367.67946 -92.021153) (xy 367.623726 -92.019116)
			(xy 367.568883 -92.008986) (xy 367.516099 -91.990979) (xy 367.466499 -91.965478) (xy 367.421141 -91.933027)
			(xy 367.380992 -91.894318) (xy 367.346906 -91.850175) (xy 367.31961 -91.80154) (xy 367.299687 -91.749449)
			(xy 367.287561 -91.695012) (xy 367.28349 -91.63939) (xy 356.914074 -91.63939) (xy 356.914606 -91.639529)
			(xy 356.965935 -91.661341) (xy 357.013541 -91.690395) (xy 357.056409 -91.72607) (xy 357.093626 -91.767607)
			(xy 357.124399 -91.81412) (xy 357.148071 -91.864617) (xy 357.164139 -91.918024) (xy 357.172259 -91.9732)
			(xy 357.172768 -92.001086) (xy 357.172259 -92.028972) (xy 357.164139 -92.084148) (xy 357.160472 -92.096336)
			(xy 364.008414 -92.096336) (xy 364.012485 -92.040714) (xy 364.024611 -91.986277) (xy 364.044534 -91.934186)
			(xy 364.07183 -91.885551) (xy 364.105916 -91.841408) (xy 364.146065 -91.802699) (xy 364.191423 -91.770248)
			(xy 364.241023 -91.744747) (xy 364.293807 -91.72674) (xy 364.34865 -91.71661) (xy 364.404384 -91.714573)
			(xy 364.459821 -91.720673) (xy 364.513778 -91.734779) (xy 364.565107 -91.756591) (xy 364.612713 -91.785645)
			(xy 364.655581 -91.82132) (xy 364.692798 -91.862857) (xy 364.723571 -91.90937) (xy 364.747243 -91.959867)
			(xy 364.763311 -92.013274) (xy 364.771431 -92.06845) (xy 364.77194 -92.096336) (xy 364.771431 -92.124222)
			(xy 364.763311 -92.179398) (xy 364.747243 -92.232805) (xy 364.723571 -92.283302) (xy 364.692798 -92.329815)
			(xy 364.659846 -92.366592) (xy 366.150396 -92.366592) (xy 366.154467 -92.31097) (xy 366.166593 -92.256533)
			(xy 366.186516 -92.204442) (xy 366.213812 -92.155807) (xy 366.247898 -92.111664) (xy 366.288047 -92.072955)
			(xy 366.333405 -92.040504) (xy 366.383005 -92.015003) (xy 366.435789 -91.996996) (xy 366.490632 -91.986866)
			(xy 366.546366 -91.984829) (xy 366.601803 -91.990929) (xy 366.65576 -92.005035) (xy 366.707089 -92.026847)
			(xy 366.754695 -92.055901) (xy 366.797563 -92.091576) (xy 366.83478 -92.133113) (xy 366.865553 -92.179626)
			(xy 366.889225 -92.230123) (xy 366.905293 -92.28353) (xy 366.913413 -92.338706) (xy 366.913922 -92.366592)
			(xy 366.913413 -92.394478) (xy 366.905293 -92.449654) (xy 366.889225 -92.503061) (xy 366.865553 -92.553558)
			(xy 366.83478 -92.600071) (xy 366.797563 -92.641608) (xy 366.754695 -92.677283) (xy 366.707089 -92.706337)
			(xy 366.65576 -92.728149) (xy 366.601803 -92.742255) (xy 366.546366 -92.748355) (xy 366.490632 -92.746318)
			(xy 366.435789 -92.736188) (xy 366.383005 -92.718181) (xy 366.333405 -92.69268) (xy 366.288047 -92.660229)
			(xy 366.247898 -92.62152) (xy 366.213812 -92.577377) (xy 366.186516 -92.528742) (xy 366.166593 -92.476651)
			(xy 366.154467 -92.422214) (xy 366.150396 -92.366592) (xy 364.659846 -92.366592) (xy 364.655581 -92.371352)
			(xy 364.612713 -92.407027) (xy 364.565107 -92.436081) (xy 364.513778 -92.457893) (xy 364.459821 -92.471999)
			(xy 364.404384 -92.478099) (xy 364.34865 -92.476062) (xy 364.293807 -92.465932) (xy 364.241023 -92.447925)
			(xy 364.191423 -92.422424) (xy 364.146065 -92.389973) (xy 364.105916 -92.351264) (xy 364.07183 -92.307121)
			(xy 364.044534 -92.258486) (xy 364.024611 -92.206395) (xy 364.012485 -92.151958) (xy 364.008414 -92.096336)
			(xy 357.160472 -92.096336) (xy 357.148071 -92.137555) (xy 357.124399 -92.188052) (xy 357.093626 -92.234565)
			(xy 357.056409 -92.276102) (xy 357.013541 -92.311777) (xy 356.965935 -92.340831) (xy 356.914606 -92.362643)
			(xy 356.860649 -92.376749) (xy 356.805212 -92.382849) (xy 356.749478 -92.380812) (xy 356.694635 -92.370682)
			(xy 356.641851 -92.352675) (xy 356.592251 -92.327174) (xy 356.546893 -92.294723) (xy 356.506744 -92.256014)
			(xy 356.472658 -92.211871) (xy 356.445362 -92.163236) (xy 356.425439 -92.111145) (xy 356.413313 -92.056708)
			(xy 356.409242 -92.001086) (xy 349.58465 -92.001086) (xy 349.574341 -92.017128) (xy 349.538651 -92.058321)
			(xy 349.497462 -92.094015) (xy 349.451612 -92.123486) (xy 349.402036 -92.146131) (xy 349.349742 -92.161491)
			(xy 349.295794 -92.169253) (xy 349.268542 -92.169742) (xy 349.240896 -92.169228) (xy 349.186185 -92.161234)
			(xy 349.133202 -92.145422) (xy 349.083058 -92.122123) (xy 349.036805 -92.091827) (xy 348.995412 -92.055169)
			(xy 348.977204 -92.03436) (xy 348.969885 -92.026532) (xy 348.950556 -92.017322) (xy 348.939866 -92.01658)
			(xy 348.852744 -92.01404) (xy 348.832678 -92.022676) (xy 348.825312 -92.03055) (xy 348.807192 -92.049218)
			(xy 348.766793 -92.081997) (xy 348.722315 -92.108981) (xy 348.674582 -92.129672) (xy 348.624481 -92.143683)
			(xy 348.57294 -92.150757) (xy 348.546928 -92.1512) (xy 348.519673 -92.150755) (xy 348.465718 -92.143001)
			(xy 348.413416 -92.127647) (xy 348.363831 -92.105005) (xy 348.317974 -92.075537) (xy 348.276777 -92.039843)
			(xy 348.241079 -91.998649) (xy 348.211608 -91.952793) (xy 348.188963 -91.90321) (xy 348.173605 -91.850909)
			(xy 348.165847 -91.796955) (xy 342.405377 -91.796955) (xy 342.29675 -91.905582) (xy 342.27949 -91.922271)
			(xy 342.240673 -91.950523) (xy 342.197915 -91.972355) (xy 342.152267 -91.987229) (xy 342.104855 -91.994778)
			(xy 342.08085 -91.995244) (xy 338.727034 -91.995244) (xy 338.700408 -91.994672) (xy 338.647968 -91.985398)
			(xy 338.597929 -91.967178) (xy 338.551804 -91.940563) (xy 338.510988 -91.906357) (xy 338.476717 -91.865596)
			(xy 338.462874 -91.842844) (xy 338.428076 -91.782646) (xy 338.398612 -91.769184) (xy 338.38261 -91.772486)
			(xy 338.364197 -91.775925) (xy 338.326918 -91.779611) (xy 338.308188 -91.779852) (xy 338.289457 -91.779621)
			(xy 338.252178 -91.775934) (xy 338.233766 -91.772486) (xy 338.217764 -91.769184) (xy 338.1883 -91.782646)
			(xy 338.153502 -91.842844) (xy 338.139668 -91.865608) (xy 338.105424 -91.906404) (xy 338.064616 -91.940633)
			(xy 338.018484 -91.967256) (xy 337.968429 -91.985464) (xy 337.915974 -91.994703) (xy 337.889342 -91.995244)
			(xy 329.87742 -91.995244) (xy 329.853414 -91.994799) (xy 329.805999 -91.987253) (xy 329.760351 -91.972375)
			(xy 329.717596 -91.950532) (xy 329.678788 -91.922264) (xy 329.66152 -91.905582) (xy 328.24928 -90.493342)
			(xy 328.232674 -90.476057) (xy 328.204511 -90.437273) (xy 328.182746 -90.39457) (xy 328.167911 -90.348994)
			(xy 328.16037 -90.30166) (xy 328.159872 -90.277696) (xy 324.308286 -90.277696) (xy 323.762687 -91.281758)
			(xy 325.860408 -91.281758) (xy 325.864479 -91.226136) (xy 325.876605 -91.171699) (xy 325.896528 -91.119608)
			(xy 325.923824 -91.070973) (xy 325.95791 -91.02683) (xy 325.998059 -90.988121) (xy 326.043417 -90.95567)
			(xy 326.093017 -90.930169) (xy 326.145801 -90.912162) (xy 326.200644 -90.902032) (xy 326.256378 -90.899995)
			(xy 326.311815 -90.906095) (xy 326.365772 -90.920201) (xy 326.417101 -90.942013) (xy 326.464707 -90.971067)
			(xy 326.507575 -91.006742) (xy 326.544792 -91.048279) (xy 326.575565 -91.094792) (xy 326.599237 -91.145289)
			(xy 326.615305 -91.198696) (xy 326.623425 -91.253872) (xy 326.623934 -91.281758) (xy 326.623425 -91.309644)
			(xy 326.615305 -91.36482) (xy 326.599237 -91.418227) (xy 326.575565 -91.468724) (xy 326.544792 -91.515237)
			(xy 326.507575 -91.556774) (xy 326.464707 -91.592449) (xy 326.417101 -91.621503) (xy 326.365772 -91.643315)
			(xy 326.311815 -91.657421) (xy 326.256378 -91.663521) (xy 326.200644 -91.661484) (xy 326.145801 -91.651354)
			(xy 326.093017 -91.633347) (xy 326.043417 -91.607846) (xy 325.998059 -91.575395) (xy 325.95791 -91.536686)
			(xy 325.923824 -91.492543) (xy 325.896528 -91.443908) (xy 325.876605 -91.391817) (xy 325.864479 -91.33738)
			(xy 325.860408 -91.281758) (xy 323.762687 -91.281758) (xy 323.572632 -91.631516) (xy 323.57187 -91.632786)
			(xy 323.5706 -91.635326) (xy 323.553836 -91.664282) (xy 323.553074 -91.665552) (xy 323.55155 -91.668092)
			(xy 323.551042 -91.6686) (xy 323.383148 -91.947746) (xy 322.475109 -93.460824) (xy 332.40218 -93.460824)
			(xy 332.402666 -93.433573) (xy 332.410422 -93.379625) (xy 332.425777 -93.32733) (xy 332.448419 -93.277753)
			(xy 332.477885 -93.231903) (xy 332.513576 -93.190712) (xy 332.554767 -93.155021) (xy 332.600617 -93.125555)
			(xy 332.650194 -93.102913) (xy 332.702489 -93.087558) (xy 332.756437 -93.079802) (xy 332.810939 -93.079802)
			(xy 332.864887 -93.087558) (xy 332.917182 -93.102913) (xy 332.966759 -93.125555) (xy 332.982156 -93.13545)
			(xy 351.144584 -93.13545) (xy 351.148655 -93.079828) (xy 351.160781 -93.025391) (xy 351.180704 -92.9733)
			(xy 351.208 -92.924665) (xy 351.242086 -92.880522) (xy 351.282235 -92.841813) (xy 351.327593 -92.809362)
			(xy 351.377193 -92.783861) (xy 351.429977 -92.765854) (xy 351.48482 -92.755724) (xy 351.540554 -92.753687)
			(xy 351.595991 -92.759787) (xy 351.649948 -92.773893) (xy 351.701277 -92.795705) (xy 351.748883 -92.824759)
			(xy 351.791751 -92.860434) (xy 351.828968 -92.901971) (xy 351.859741 -92.948484) (xy 351.883413 -92.998981)
			(xy 351.899481 -93.052388) (xy 351.907601 -93.107564) (xy 351.90811 -93.13545) (xy 351.907948 -93.14434)
			(xy 352.13112 -93.14434) (xy 352.135191 -93.088718) (xy 352.147317 -93.034281) (xy 352.16724 -92.98219)
			(xy 352.194536 -92.933555) (xy 352.228622 -92.889412) (xy 352.268771 -92.850703) (xy 352.314129 -92.818252)
			(xy 352.363729 -92.792751) (xy 352.416513 -92.774744) (xy 352.471356 -92.764614) (xy 352.52709 -92.762577)
			(xy 352.582527 -92.768677) (xy 352.636484 -92.782783) (xy 352.687813 -92.804595) (xy 352.735419 -92.833649)
			(xy 352.748297 -92.844366) (xy 353.159566 -92.844366) (xy 353.163637 -92.788744) (xy 353.175763 -92.734307)
			(xy 353.195686 -92.682216) (xy 353.222982 -92.633581) (xy 353.257068 -92.589438) (xy 353.297217 -92.550729)
			(xy 353.342575 -92.518278) (xy 353.392175 -92.492777) (xy 353.444959 -92.47477) (xy 353.499802 -92.46464)
			(xy 353.555536 -92.462603) (xy 353.610973 -92.468703) (xy 353.66493 -92.482809) (xy 353.716259 -92.504621)
			(xy 353.763865 -92.533675) (xy 353.806733 -92.56935) (xy 353.84395 -92.610887) (xy 353.874723 -92.6574)
			(xy 353.898395 -92.707897) (xy 353.914463 -92.761304) (xy 353.922583 -92.81648) (xy 353.923092 -92.844366)
			(xy 353.922583 -92.872252) (xy 353.914463 -92.927428) (xy 353.898395 -92.980835) (xy 353.874723 -93.031332)
			(xy 353.84395 -93.077845) (xy 353.806733 -93.119382) (xy 353.763865 -93.155057) (xy 353.716259 -93.184111)
			(xy 353.66493 -93.205923) (xy 353.610973 -93.220029) (xy 353.555536 -93.226129) (xy 353.499802 -93.224092)
			(xy 353.444959 -93.213962) (xy 353.392175 -93.195955) (xy 353.342575 -93.170454) (xy 353.297217 -93.138003)
			(xy 353.257068 -93.099294) (xy 353.222982 -93.055151) (xy 353.195686 -93.006516) (xy 353.175763 -92.954425)
			(xy 353.163637 -92.899988) (xy 353.159566 -92.844366) (xy 352.748297 -92.844366) (xy 352.778287 -92.869324)
			(xy 352.815504 -92.910861) (xy 352.846277 -92.957374) (xy 352.869949 -93.007871) (xy 352.886017 -93.061278)
			(xy 352.894137 -93.116454) (xy 352.894646 -93.14434) (xy 352.894137 -93.172226) (xy 352.886017 -93.227402)
			(xy 352.876237 -93.25991) (xy 355.188518 -93.25991) (xy 355.192589 -93.204288) (xy 355.204715 -93.149851)
			(xy 355.224638 -93.09776) (xy 355.251934 -93.049125) (xy 355.28602 -93.004982) (xy 355.326169 -92.966273)
			(xy 355.371527 -92.933822) (xy 355.421127 -92.908321) (xy 355.473911 -92.890314) (xy 355.528754 -92.880184)
			(xy 355.584488 -92.878147) (xy 355.639925 -92.884247) (xy 355.693882 -92.898353) (xy 355.745211 -92.920165)
			(xy 355.792817 -92.949219) (xy 355.819735 -92.97162) (xy 366.878106 -92.97162) (xy 366.882177 -92.915998)
			(xy 366.894303 -92.861561) (xy 366.914226 -92.80947) (xy 366.941522 -92.760835) (xy 366.975608 -92.716692)
			(xy 367.015757 -92.677983) (xy 367.061115 -92.645532) (xy 367.110715 -92.620031) (xy 367.163499 -92.602024)
			(xy 367.218342 -92.591894) (xy 367.274076 -92.589857) (xy 367.329513 -92.595957) (xy 367.38347 -92.610063)
			(xy 367.434799 -92.631875) (xy 367.482405 -92.660929) (xy 367.525273 -92.696604) (xy 367.56249 -92.738141)
			(xy 367.593263 -92.784654) (xy 367.616935 -92.835151) (xy 367.633003 -92.888558) (xy 367.641123 -92.943734)
			(xy 367.641632 -92.97162) (xy 367.641123 -92.999506) (xy 367.633003 -93.054682) (xy 367.616935 -93.108089)
			(xy 367.593263 -93.158586) (xy 367.56249 -93.205099) (xy 367.525273 -93.246636) (xy 367.482405 -93.282311)
			(xy 367.434799 -93.311365) (xy 367.38347 -93.333177) (xy 367.329513 -93.347283) (xy 367.274076 -93.353383)
			(xy 367.218342 -93.351346) (xy 367.163499 -93.341216) (xy 367.110715 -93.323209) (xy 367.061115 -93.297708)
			(xy 367.015757 -93.265257) (xy 366.975608 -93.226548) (xy 366.941522 -93.182405) (xy 366.914226 -93.13377)
			(xy 366.894303 -93.081679) (xy 366.882177 -93.027242) (xy 366.878106 -92.97162) (xy 355.819735 -92.97162)
			(xy 355.835685 -92.984894) (xy 355.872902 -93.026431) (xy 355.903675 -93.072944) (xy 355.927347 -93.123441)
			(xy 355.943415 -93.176848) (xy 355.951535 -93.232024) (xy 355.952044 -93.25991) (xy 355.951535 -93.287796)
			(xy 355.943415 -93.342972) (xy 355.927347 -93.396379) (xy 355.903675 -93.446876) (xy 355.872902 -93.493389)
			(xy 355.835685 -93.534926) (xy 355.792817 -93.570601) (xy 355.745211 -93.599655) (xy 355.737189 -93.603064)
			(xy 375.71629 -93.603064) (xy 375.720361 -93.547442) (xy 375.732487 -93.493005) (xy 375.75241 -93.440914)
			(xy 375.779706 -93.392279) (xy 375.813792 -93.348136) (xy 375.853941 -93.309427) (xy 375.899299 -93.276976)
			(xy 375.948899 -93.251475) (xy 376.001683 -93.233468) (xy 376.056526 -93.223338) (xy 376.11226 -93.221301)
			(xy 376.167697 -93.227401) (xy 376.221654 -93.241507) (xy 376.272983 -93.263319) (xy 376.320589 -93.292373)
			(xy 376.363457 -93.328048) (xy 376.400674 -93.369585) (xy 376.431447 -93.416098) (xy 376.455119 -93.466595)
			(xy 376.471187 -93.520002) (xy 376.479307 -93.575178) (xy 376.479816 -93.603064) (xy 376.479538 -93.618304)
			(xy 377.288042 -93.618304) (xy 377.292113 -93.562682) (xy 377.304239 -93.508245) (xy 377.324162 -93.456154)
			(xy 377.351458 -93.407519) (xy 377.385544 -93.363376) (xy 377.425693 -93.324667) (xy 377.471051 -93.292216)
			(xy 377.520651 -93.266715) (xy 377.573435 -93.248708) (xy 377.628278 -93.238578) (xy 377.684012 -93.236541)
			(xy 377.739449 -93.242641) (xy 377.793406 -93.256747) (xy 377.844735 -93.278559) (xy 377.892341 -93.307613)
			(xy 377.935209 -93.343288) (xy 377.972426 -93.384825) (xy 378.003199 -93.431338) (xy 378.026871 -93.481835)
			(xy 378.042939 -93.535242) (xy 378.051059 -93.590418) (xy 378.051568 -93.618304) (xy 378.051059 -93.64619)
			(xy 378.042939 -93.701366) (xy 378.026871 -93.754773) (xy 378.003199 -93.80527) (xy 377.972426 -93.851783)
			(xy 377.935209 -93.89332) (xy 377.892341 -93.928995) (xy 377.844735 -93.958049) (xy 377.793406 -93.979861)
			(xy 377.739449 -93.993967) (xy 377.684012 -94.000067) (xy 377.628278 -93.99803) (xy 377.573435 -93.9879)
			(xy 377.520651 -93.969893) (xy 377.471051 -93.944392) (xy 377.425693 -93.911941) (xy 377.385544 -93.873232)
			(xy 377.351458 -93.829089) (xy 377.324162 -93.780454) (xy 377.304239 -93.728363) (xy 377.292113 -93.673926)
			(xy 377.288042 -93.618304) (xy 376.479538 -93.618304) (xy 376.479307 -93.63095) (xy 376.471187 -93.686126)
			(xy 376.455119 -93.739533) (xy 376.431447 -93.79003) (xy 376.400674 -93.836543) (xy 376.363457 -93.87808)
			(xy 376.320589 -93.913755) (xy 376.272983 -93.942809) (xy 376.221654 -93.964621) (xy 376.167697 -93.978727)
			(xy 376.11226 -93.984827) (xy 376.056526 -93.98279) (xy 376.001683 -93.97266) (xy 375.948899 -93.954653)
			(xy 375.899299 -93.929152) (xy 375.853941 -93.896701) (xy 375.813792 -93.857992) (xy 375.779706 -93.813849)
			(xy 375.75241 -93.765214) (xy 375.732487 -93.713123) (xy 375.720361 -93.658686) (xy 375.71629 -93.603064)
			(xy 355.737189 -93.603064) (xy 355.693882 -93.621467) (xy 355.639925 -93.635573) (xy 355.584488 -93.641673)
			(xy 355.528754 -93.639636) (xy 355.473911 -93.629506) (xy 355.421127 -93.611499) (xy 355.371527 -93.585998)
			(xy 355.326169 -93.553547) (xy 355.28602 -93.514838) (xy 355.251934 -93.470695) (xy 355.224638 -93.42206)
			(xy 355.204715 -93.369969) (xy 355.192589 -93.315532) (xy 355.188518 -93.25991) (xy 352.876237 -93.25991)
			(xy 352.869949 -93.280809) (xy 352.846277 -93.331306) (xy 352.815504 -93.377819) (xy 352.778287 -93.419356)
			(xy 352.735419 -93.455031) (xy 352.687813 -93.484085) (xy 352.636484 -93.505897) (xy 352.582527 -93.520003)
			(xy 352.52709 -93.526103) (xy 352.471356 -93.524066) (xy 352.416513 -93.513936) (xy 352.363729 -93.495929)
			(xy 352.314129 -93.470428) (xy 352.268771 -93.437977) (xy 352.228622 -93.399268) (xy 352.194536 -93.355125)
			(xy 352.16724 -93.30649) (xy 352.147317 -93.254399) (xy 352.135191 -93.199962) (xy 352.13112 -93.14434)
			(xy 351.907948 -93.14434) (xy 351.907601 -93.163336) (xy 351.899481 -93.218512) (xy 351.883413 -93.271919)
			(xy 351.859741 -93.322416) (xy 351.828968 -93.368929) (xy 351.791751 -93.410466) (xy 351.748883 -93.446141)
			(xy 351.701277 -93.475195) (xy 351.649948 -93.497007) (xy 351.595991 -93.511113) (xy 351.540554 -93.517213)
			(xy 351.48482 -93.515176) (xy 351.429977 -93.505046) (xy 351.377193 -93.487039) (xy 351.327593 -93.461538)
			(xy 351.282235 -93.429087) (xy 351.242086 -93.390378) (xy 351.208 -93.346235) (xy 351.180704 -93.2976)
			(xy 351.160781 -93.245509) (xy 351.148655 -93.191072) (xy 351.144584 -93.13545) (xy 332.982156 -93.13545)
			(xy 333.012609 -93.155021) (xy 333.0538 -93.190712) (xy 333.089491 -93.231903) (xy 333.118957 -93.277753)
			(xy 333.141599 -93.32733) (xy 333.156954 -93.379625) (xy 333.16471 -93.433573) (xy 333.165196 -93.460824)
			(xy 333.165196 -93.461332) (xy 333.164683 -93.487984) (xy 333.157222 -93.540765) (xy 333.14249 -93.591994)
			(xy 333.120775 -93.640676) (xy 333.10703 -93.663516) (xy 333.100196 -93.675215) (xy 333.092338 -93.701133)
			(xy 333.09158 -93.728205) (xy 333.097974 -93.754522) (xy 333.111069 -93.778229) (xy 333.129943 -93.797652)
			(xy 333.153263 -93.811423) (xy 333.166212 -93.815408) (xy 333.192774 -93.823156) (xy 333.243499 -93.845255)
			(xy 333.290498 -93.874453) (xy 333.332784 -93.910135) (xy 333.369471 -93.951553) (xy 333.399788 -93.997838)
			(xy 333.423098 -94.048018) (xy 333.438913 -94.101039) (xy 333.446901 -94.155789) (xy 333.44739 -94.183454)
			(xy 333.446904 -94.210705) (xy 333.445344 -94.221554) (xy 336.16976 -94.221554) (xy 336.173831 -94.165932)
			(xy 336.185957 -94.111495) (xy 336.20588 -94.059404) (xy 336.233176 -94.010769) (xy 336.267262 -93.966626)
			(xy 336.307411 -93.927917) (xy 336.352769 -93.895466) (xy 336.402369 -93.869965) (xy 336.455153 -93.851958)
			(xy 336.509996 -93.841828) (xy 336.56573 -93.839791) (xy 336.621167 -93.845891) (xy 336.675124 -93.859997)
			(xy 336.726453 -93.881809) (xy 336.774059 -93.910863) (xy 336.816927 -93.946538) (xy 336.854144 -93.988075)
			(xy 336.884917 -94.034588) (xy 336.908589 -94.085085) (xy 336.924657 -94.138492) (xy 336.932777 -94.193668)
			(xy 336.933286 -94.221554) (xy 336.932777 -94.24944) (xy 336.924657 -94.304616) (xy 336.908589 -94.358023)
			(xy 336.884917 -94.40852) (xy 336.854144 -94.455033) (xy 336.816927 -94.49657) (xy 336.774059 -94.532245)
			(xy 336.726453 -94.561299) (xy 336.675124 -94.583111) (xy 336.621167 -94.597217) (xy 336.56573 -94.603317)
			(xy 336.509996 -94.60128) (xy 336.455153 -94.59115) (xy 336.402369 -94.573143) (xy 336.352769 -94.547642)
			(xy 336.307411 -94.515191) (xy 336.267262 -94.476482) (xy 336.233176 -94.432339) (xy 336.20588 -94.383704)
			(xy 336.185957 -94.331613) (xy 336.173831 -94.277176) (xy 336.16976 -94.221554) (xy 333.445344 -94.221554)
			(xy 333.439148 -94.264653) (xy 333.423793 -94.316948) (xy 333.401151 -94.366525) (xy 333.371685 -94.412375)
			(xy 333.335994 -94.453566) (xy 333.294803 -94.489257) (xy 333.248953 -94.518723) (xy 333.199376 -94.541365)
			(xy 333.147081 -94.55672) (xy 333.093133 -94.564476) (xy 333.038631 -94.564476) (xy 332.984683 -94.55672)
			(xy 332.932388 -94.541365) (xy 332.882811 -94.518723) (xy 332.836961 -94.489257) (xy 332.79577 -94.453566)
			(xy 332.760079 -94.412375) (xy 332.730613 -94.366525) (xy 332.707971 -94.316948) (xy 332.692616 -94.264653)
			(xy 332.68486 -94.210705) (xy 332.684374 -94.183454) (xy 332.684374 -94.182946) (xy 332.684866 -94.156293)
			(xy 332.692332 -94.103511) (xy 332.70707 -94.052282) (xy 332.728792 -94.003601) (xy 332.74254 -93.980762)
			(xy 332.74936 -93.969059) (xy 332.757206 -93.943143) (xy 332.757959 -93.916077) (xy 332.751565 -93.889766)
			(xy 332.738475 -93.866063) (xy 332.719611 -93.846639) (xy 332.696302 -93.83286) (xy 332.683358 -93.82887)
			(xy 332.656812 -93.821071) (xy 332.606092 -93.798974) (xy 332.559097 -93.769781) (xy 332.516813 -93.734104)
			(xy 332.480126 -93.692693) (xy 332.449808 -93.646416) (xy 332.426493 -93.596244) (xy 332.410671 -93.54323)
			(xy 332.402675 -93.488486) (xy 332.40218 -93.460824) (xy 322.475109 -93.460824) (xy 322.184268 -93.945456)
			(xy 322.181443 -93.951085) (xy 322.178358 -93.963291) (xy 322.178172 -93.969586) (xy 322.178172 -93.97873)
			(xy 322.178271 -93.982409) (xy 322.179423 -93.989676) (xy 322.180458 -93.993208) (xy 322.198238 -94.052644)
			(xy 322.200778 -94.057216) (xy 322.204588 -94.064836) (xy 322.208619 -94.07181) (xy 322.220129 -94.083066)
			(xy 322.227194 -94.086934) (xy 322.250737 -94.099104) (xy 322.294513 -94.128977) (xy 322.333732 -94.164623)
			(xy 322.367637 -94.205356) (xy 322.394864 -94.24924) (xy 327.636122 -94.24924) (xy 327.640193 -94.193618)
			(xy 327.652319 -94.139181) (xy 327.672242 -94.08709) (xy 327.699538 -94.038455) (xy 327.733624 -93.994312)
			(xy 327.773773 -93.955603) (xy 327.819131 -93.923152) (xy 327.868731 -93.897651) (xy 327.921515 -93.879644)
			(xy 327.976358 -93.869514) (xy 328.032092 -93.867477) (xy 328.087529 -93.873577) (xy 328.141486 -93.887683)
			(xy 328.192815 -93.909495) (xy 328.240421 -93.938549) (xy 328.283289 -93.974224) (xy 328.320506 -94.015761)
			(xy 328.351279 -94.062274) (xy 328.374951 -94.112771) (xy 328.391019 -94.166178) (xy 328.399139 -94.221354)
			(xy 328.399648 -94.24924) (xy 328.399574 -94.253304) (xy 328.652122 -94.253304) (xy 328.656193 -94.197682)
			(xy 328.668319 -94.143245) (xy 328.688242 -94.091154) (xy 328.715538 -94.042519) (xy 328.749624 -93.998376)
			(xy 328.789773 -93.959667) (xy 328.835131 -93.927216) (xy 328.884731 -93.901715) (xy 328.937515 -93.883708)
			(xy 328.992358 -93.873578) (xy 329.048092 -93.871541) (xy 329.103529 -93.877641) (xy 329.157486 -93.891747)
			(xy 329.208815 -93.913559) (xy 329.256421 -93.942613) (xy 329.299289 -93.978288) (xy 329.336506 -94.019825)
			(xy 329.367279 -94.066338) (xy 329.390951 -94.116835) (xy 329.407019 -94.170242) (xy 329.415139 -94.225418)
			(xy 329.415648 -94.253304) (xy 329.415139 -94.28119) (xy 329.407019 -94.336366) (xy 329.390951 -94.389773)
			(xy 329.367279 -94.44027) (xy 329.336506 -94.486783) (xy 329.299289 -94.52832) (xy 329.256421 -94.563995)
			(xy 329.208815 -94.593049) (xy 329.157486 -94.614861) (xy 329.103529 -94.628967) (xy 329.048092 -94.635067)
			(xy 328.992358 -94.63303) (xy 328.937515 -94.6229) (xy 328.884731 -94.604893) (xy 328.835131 -94.579392)
			(xy 328.789773 -94.546941) (xy 328.749624 -94.508232) (xy 328.715538 -94.464089) (xy 328.688242 -94.415454)
			(xy 328.668319 -94.363363) (xy 328.656193 -94.308926) (xy 328.652122 -94.253304) (xy 328.399574 -94.253304)
			(xy 328.399139 -94.277126) (xy 328.391019 -94.332302) (xy 328.374951 -94.385709) (xy 328.351279 -94.436206)
			(xy 328.320506 -94.482719) (xy 328.283289 -94.524256) (xy 328.240421 -94.559931) (xy 328.192815 -94.588985)
			(xy 328.141486 -94.610797) (xy 328.087529 -94.624903) (xy 328.032092 -94.631003) (xy 327.976358 -94.628966)
			(xy 327.921515 -94.618836) (xy 327.868731 -94.600829) (xy 327.819131 -94.575328) (xy 327.773773 -94.542877)
			(xy 327.733624 -94.504168) (xy 327.699538 -94.460025) (xy 327.672242 -94.41139) (xy 327.652319 -94.359299)
			(xy 327.640193 -94.304862) (xy 327.636122 -94.24924) (xy 322.394864 -94.24924) (xy 322.395577 -94.25039)
			(xy 322.417012 -94.29886) (xy 322.43153 -94.34983) (xy 322.438851 -94.402319) (xy 322.439284 -94.428818)
			(xy 322.438785 -94.456558) (xy 322.43075 -94.511452) (xy 322.414853 -94.564605) (xy 322.391428 -94.614896)
			(xy 322.360968 -94.661266) (xy 322.324116 -94.702738) (xy 322.281648 -94.738437) (xy 322.234459 -94.767612)
			(xy 322.183544 -94.789647) (xy 322.129975 -94.804079) (xy 322.10248 -94.807786) (xy 322.088764 -94.80931)
			(xy 322.057776 -94.81058) (xy 322.028368 -94.810018) (xy 321.970256 -94.800952) (xy 321.914224 -94.78307)
			(xy 321.861604 -94.756795) (xy 321.837304 -94.740222) (xy 321.833748 -94.737682) (xy 321.824096 -94.73311)
			(xy 321.816524 -94.729905) (xy 321.800205 -94.727959) (xy 321.792092 -94.7293) (xy 321.765168 -94.734888)
			(xy 321.76466 -94.734888) (xy 321.720464 -94.743778) (xy 321.710869 -94.74622) (xy 321.694415 -94.757202)
			(xy 321.68846 -94.765114) (xy 321.622941 -94.87389) (xy 338.405861 -94.87389) (xy 338.405861 -94.81391)
			(xy 338.413691 -94.754443) (xy 338.429215 -94.696507) (xy 338.45217 -94.641093) (xy 338.482161 -94.58915)
			(xy 338.518676 -94.541565) (xy 338.561089 -94.499155) (xy 338.608676 -94.462643) (xy 338.660622 -94.432655)
			(xy 338.716037 -94.409705) (xy 338.773975 -94.394184) (xy 338.833442 -94.386359) (xy 338.863432 -94.385892)
			(xy 339.727032 -94.385892) (xy 339.757012 -94.386476) (xy 339.816458 -94.394306) (xy 339.874374 -94.409828)
			(xy 339.929769 -94.432777) (xy 339.981694 -94.462759) (xy 339.984135 -94.464632) (xy 342.457784 -94.464632)
			(xy 342.461855 -94.40901) (xy 342.473981 -94.354573) (xy 342.493904 -94.302482) (xy 342.5212 -94.253847)
			(xy 342.555286 -94.209704) (xy 342.595435 -94.170995) (xy 342.640793 -94.138544) (xy 342.690393 -94.113043)
			(xy 342.743177 -94.095036) (xy 342.79802 -94.084906) (xy 342.853754 -94.082869) (xy 342.909191 -94.088969)
			(xy 342.963148 -94.103075) (xy 343.014477 -94.124887) (xy 343.062083 -94.153941) (xy 343.104951 -94.189616)
			(xy 343.142168 -94.231153) (xy 343.172941 -94.277666) (xy 343.196613 -94.328163) (xy 343.212681 -94.38157)
			(xy 343.215448 -94.40037) (xy 365.065054 -94.40037) (xy 365.069125 -94.344748) (xy 365.081251 -94.290311)
			(xy 365.101174 -94.23822) (xy 365.12847 -94.189585) (xy 365.162556 -94.145442) (xy 365.202705 -94.106733)
			(xy 365.248063 -94.074282) (xy 365.297663 -94.048781) (xy 365.350447 -94.030774) (xy 365.40529 -94.020644)
			(xy 365.461024 -94.018607) (xy 365.516461 -94.024707) (xy 365.570418 -94.038813) (xy 365.621747 -94.060625)
			(xy 365.669353 -94.089679) (xy 365.712221 -94.125354) (xy 365.749438 -94.166891) (xy 365.780211 -94.213404)
			(xy 365.803883 -94.263901) (xy 365.819951 -94.317308) (xy 365.826456 -94.361508) (xy 366.046764 -94.361508)
			(xy 366.050835 -94.305886) (xy 366.062961 -94.251449) (xy 366.082884 -94.199358) (xy 366.11018 -94.150723)
			(xy 366.144266 -94.10658) (xy 366.184415 -94.067871) (xy 366.229773 -94.03542) (xy 366.279373 -94.009919)
			(xy 366.332157 -93.991912) (xy 366.387 -93.981782) (xy 366.442734 -93.979745) (xy 366.498171 -93.985845)
			(xy 366.552128 -93.999951) (xy 366.603457 -94.021763) (xy 366.651063 -94.050817) (xy 366.693931 -94.086492)
			(xy 366.731148 -94.128029) (xy 366.761921 -94.174542) (xy 366.785593 -94.225039) (xy 366.801661 -94.278446)
			(xy 366.809781 -94.333622) (xy 366.81029 -94.361508) (xy 366.809781 -94.389394) (xy 366.801661 -94.44457)
			(xy 366.785593 -94.497977) (xy 366.761921 -94.548474) (xy 366.731148 -94.594987) (xy 366.693931 -94.636524)
			(xy 366.659057 -94.665546) (xy 379.166626 -94.665546) (xy 379.170697 -94.609924) (xy 379.182823 -94.555487)
			(xy 379.202746 -94.503396) (xy 379.230042 -94.454761) (xy 379.264128 -94.410618) (xy 379.304277 -94.371909)
			(xy 379.349635 -94.339458) (xy 379.399235 -94.313957) (xy 379.452019 -94.29595) (xy 379.506862 -94.28582)
			(xy 379.562596 -94.283783) (xy 379.618033 -94.289883) (xy 379.67199 -94.303989) (xy 379.723319 -94.325801)
			(xy 379.770925 -94.354855) (xy 379.813793 -94.39053) (xy 379.85101 -94.432067) (xy 379.881783 -94.47858)
			(xy 379.905455 -94.529077) (xy 379.921523 -94.582484) (xy 379.929643 -94.63766) (xy 379.930152 -94.665546)
			(xy 379.929643 -94.693432) (xy 379.921523 -94.748608) (xy 379.905455 -94.802015) (xy 379.881783 -94.852512)
			(xy 379.85101 -94.899025) (xy 379.813793 -94.940562) (xy 379.770925 -94.976237) (xy 379.723319 -95.005291)
			(xy 379.67199 -95.027103) (xy 379.618033 -95.041209) (xy 379.562596 -95.047309) (xy 379.506862 -95.045272)
			(xy 379.452019 -95.035142) (xy 379.399235 -95.017135) (xy 379.349635 -94.991634) (xy 379.304277 -94.959183)
			(xy 379.264128 -94.920474) (xy 379.230042 -94.876331) (xy 379.202746 -94.827696) (xy 379.182823 -94.775605)
			(xy 379.170697 -94.721168) (xy 379.166626 -94.665546) (xy 366.659057 -94.665546) (xy 366.651063 -94.672199)
			(xy 366.603457 -94.701253) (xy 366.552128 -94.723065) (xy 366.498171 -94.737171) (xy 366.442734 -94.743271)
			(xy 366.387 -94.741234) (xy 366.332157 -94.731104) (xy 366.279373 -94.713097) (xy 366.229773 -94.687596)
			(xy 366.184415 -94.655145) (xy 366.144266 -94.616436) (xy 366.11018 -94.572293) (xy 366.082884 -94.523658)
			(xy 366.062961 -94.471567) (xy 366.050835 -94.41713) (xy 366.046764 -94.361508) (xy 365.826456 -94.361508)
			(xy 365.828071 -94.372484) (xy 365.82858 -94.40037) (xy 365.828071 -94.428256) (xy 365.819951 -94.483432)
			(xy 365.803883 -94.536839) (xy 365.780211 -94.587336) (xy 365.749438 -94.633849) (xy 365.712221 -94.675386)
			(xy 365.669353 -94.711061) (xy 365.621747 -94.740115) (xy 365.570418 -94.761927) (xy 365.516461 -94.776033)
			(xy 365.461024 -94.782133) (xy 365.40529 -94.780096) (xy 365.350447 -94.769966) (xy 365.297663 -94.751959)
			(xy 365.248063 -94.726458) (xy 365.202705 -94.694007) (xy 365.162556 -94.655298) (xy 365.12847 -94.611155)
			(xy 365.101174 -94.56252) (xy 365.081251 -94.510429) (xy 365.069125 -94.455992) (xy 365.065054 -94.40037)
			(xy 343.215448 -94.40037) (xy 343.220801 -94.436746) (xy 343.22131 -94.464632) (xy 343.220801 -94.492518)
			(xy 343.212681 -94.547694) (xy 343.196613 -94.601101) (xy 343.172941 -94.651598) (xy 343.142168 -94.698111)
			(xy 343.104951 -94.739648) (xy 343.062083 -94.775323) (xy 343.014477 -94.804377) (xy 342.963148 -94.826189)
			(xy 342.909191 -94.840295) (xy 342.853754 -94.846395) (xy 342.79802 -94.844358) (xy 342.743177 -94.834228)
			(xy 342.690393 -94.816221) (xy 342.640793 -94.79072) (xy 342.595435 -94.758269) (xy 342.555286 -94.71956)
			(xy 342.5212 -94.675417) (xy 342.493904 -94.626782) (xy 342.473981 -94.574691) (xy 342.461855 -94.520254)
			(xy 342.457784 -94.464632) (xy 339.984135 -94.464632) (xy 340.029262 -94.499262) (xy 340.071659 -94.541662)
			(xy 340.108159 -94.589232) (xy 340.138137 -94.64116) (xy 340.161082 -94.696556) (xy 340.1766 -94.754473)
			(xy 340.184426 -94.81392) (xy 340.184426 -94.87388) (xy 340.1766 -94.933327) (xy 340.161082 -94.991244)
			(xy 340.138137 -95.04664) (xy 340.108159 -95.098568) (xy 340.071659 -95.146138) (xy 340.029262 -95.188538)
			(xy 339.981694 -95.225041) (xy 339.929769 -95.255023) (xy 339.874374 -95.277972) (xy 339.816458 -95.293494)
			(xy 339.757012 -95.301324) (xy 339.727032 -95.301816) (xy 338.863432 -95.301816) (xy 338.833442 -95.301441)
			(xy 338.773975 -95.293616) (xy 338.716037 -95.278095) (xy 338.660622 -95.255145) (xy 338.608676 -95.225157)
			(xy 338.561089 -95.188645) (xy 338.518676 -95.146235) (xy 338.482161 -95.09865) (xy 338.45217 -95.046707)
			(xy 338.429215 -94.991293) (xy 338.413691 -94.933357) (xy 338.405861 -94.87389) (xy 321.622941 -94.87389)
			(xy 321.45224 -95.15729) (xy 321.361054 -95.30969) (xy 321.35828 -95.315201) (xy 321.355205 -95.327147)
			(xy 321.354958 -95.333312) (xy 321.354958 -95.367602) (xy 321.355466 -95.374714) (xy 321.35699 -95.385382)
			(xy 321.362832 -95.405194) (xy 321.36588 -95.415608) (xy 321.386454 -95.440246) (xy 321.390772 -95.444564)
			(xy 321.399916 -95.45066) (xy 321.401186 -95.451422) (xy 321.40271 -95.452184) (xy 321.426462 -95.464913)
			(xy 321.470555 -95.495891) (xy 321.510011 -95.532595) (xy 321.54409 -95.574338) (xy 321.572155 -95.62034)
			(xy 321.593683 -95.669741) (xy 321.608269 -95.721617) (xy 321.615642 -95.774998) (xy 321.61607 -95.801942)
			(xy 321.615567 -95.829989) (xy 321.613134 -95.8469) (xy 323.324726 -95.8469) (xy 323.328797 -95.791278)
			(xy 323.340923 -95.736841) (xy 323.360846 -95.68475) (xy 323.388142 -95.636115) (xy 323.422228 -95.591972)
			(xy 323.462377 -95.553263) (xy 323.507735 -95.520812) (xy 323.557335 -95.495311) (xy 323.610119 -95.477304)
			(xy 323.664962 -95.467174) (xy 323.720696 -95.465137) (xy 323.776133 -95.471237) (xy 323.83009 -95.485343)
			(xy 323.881419 -95.507155) (xy 323.929025 -95.536209) (xy 323.971893 -95.571884) (xy 324.00911 -95.613421)
			(xy 324.039883 -95.659934) (xy 324.063555 -95.710431) (xy 324.079623 -95.763838) (xy 324.085231 -95.801942)
			(xy 324.915528 -95.801942) (xy 324.919599 -95.74632) (xy 324.931725 -95.691883) (xy 324.951648 -95.639792)
			(xy 324.978944 -95.591157) (xy 325.01303 -95.547014) (xy 325.053179 -95.508305) (xy 325.098537 -95.475854)
			(xy 325.148137 -95.450353) (xy 325.200921 -95.432346) (xy 325.255764 -95.422216) (xy 325.311498 -95.420179)
			(xy 325.366935 -95.426279) (xy 325.420892 -95.440385) (xy 325.472221 -95.462197) (xy 325.519827 -95.491251)
			(xy 325.562695 -95.526926) (xy 325.599912 -95.568463) (xy 325.630685 -95.614976) (xy 325.654357 -95.665473)
			(xy 325.670425 -95.71888) (xy 325.678545 -95.774056) (xy 325.679054 -95.801942) (xy 325.921368 -95.801942)
			(xy 325.925439 -95.74632) (xy 325.937565 -95.691883) (xy 325.957488 -95.639792) (xy 325.984784 -95.591157)
			(xy 326.01887 -95.547014) (xy 326.059019 -95.508305) (xy 326.104377 -95.475854) (xy 326.153977 -95.450353)
			(xy 326.206761 -95.432346) (xy 326.261604 -95.422216) (xy 326.317338 -95.420179) (xy 326.372775 -95.426279)
			(xy 326.426732 -95.440385) (xy 326.478061 -95.462197) (xy 326.525667 -95.491251) (xy 326.568535 -95.526926)
			(xy 326.605752 -95.568463) (xy 326.636525 -95.614976) (xy 326.660197 -95.665473) (xy 326.676265 -95.71888)
			(xy 326.684385 -95.774056) (xy 326.684894 -95.801942) (xy 326.684385 -95.829828) (xy 326.67724 -95.878379)
			(xy 331.320012 -95.878379) (xy 331.327765 -95.824422) (xy 331.343118 -95.772116) (xy 331.365759 -95.722529)
			(xy 331.395226 -95.676668) (xy 331.43092 -95.635467) (xy 331.472115 -95.599766) (xy 331.517971 -95.570291)
			(xy 331.567554 -95.547641) (xy 331.619857 -95.532279) (xy 331.673813 -95.524517) (xy 331.728325 -95.524513)
			(xy 331.782283 -95.532266) (xy 331.834588 -95.54762) (xy 331.884176 -95.570261) (xy 331.930036 -95.599729)
			(xy 331.971236 -95.635424) (xy 332.006937 -95.676619) (xy 332.036412 -95.722475) (xy 332.05906 -95.772059)
			(xy 332.074422 -95.824362) (xy 332.082183 -95.878318) (xy 332.082648 -95.905574) (xy 332.082648 -95.906082)
			(xy 332.082565 -95.916454) (xy 332.081423 -95.937166) (xy 332.080362 -95.947484) (xy 332.0793 -95.96203)
			(xy 332.084505 -95.990715) (xy 332.097592 -96.016765) (xy 332.117497 -96.038065) (xy 332.142604 -96.052883)
			(xy 332.170871 -96.060014) (xy 332.200002 -96.058881) (xy 332.213966 -96.054672) (xy 332.243575 -96.045318)
			(xy 332.304841 -96.035236) (xy 332.335886 -96.034606) (xy 332.33614 -96.034606) (xy 332.363387 -96.035121)
			(xy 332.417327 -96.042882) (xy 332.469613 -96.05824) (xy 332.519182 -96.080883) (xy 332.565023 -96.110349)
			(xy 332.606205 -96.146039) (xy 332.641888 -96.187226) (xy 332.671347 -96.233073) (xy 332.693982 -96.282645)
			(xy 332.709331 -96.334934) (xy 332.717083 -96.388874) (xy 332.71708 -96.44337) (xy 332.709322 -96.497309)
			(xy 332.693966 -96.549596) (xy 332.671326 -96.599166) (xy 332.641862 -96.645009) (xy 332.606174 -96.686192)
			(xy 332.564988 -96.721878) (xy 332.519143 -96.751339) (xy 332.469572 -96.773975) (xy 332.417284 -96.789328)
			(xy 332.363344 -96.797082) (xy 332.308848 -96.797082) (xy 332.254908 -96.789326) (xy 332.20262 -96.773973)
			(xy 332.15305 -96.751335) (xy 332.107206 -96.721873) (xy 332.066021 -96.686187) (xy 332.030333 -96.645002)
			(xy 332.00087 -96.599159) (xy 331.978231 -96.549589) (xy 331.962876 -96.497302) (xy 331.955119 -96.443362)
			(xy 331.954632 -96.416114) (xy 331.954632 -96.415606) (xy 331.954714 -96.405234) (xy 331.955857 -96.384522)
			(xy 331.956918 -96.374204) (xy 331.958018 -96.359659) (xy 331.952809 -96.330969) (xy 331.939716 -96.304915)
			(xy 331.919804 -96.283613) (xy 331.894691 -96.268796) (xy 331.866417 -96.261667) (xy 331.83728 -96.262805)
			(xy 331.823314 -96.267016) (xy 331.793707 -96.276374) (xy 331.732439 -96.286453) (xy 331.701394 -96.287082)
			(xy 331.70114 -96.287082) (xy 331.673884 -96.286688) (xy 331.619926 -96.278936) (xy 331.567621 -96.263583)
			(xy 331.518033 -96.240943) (xy 331.472171 -96.211476) (xy 331.430971 -96.175783) (xy 331.395269 -96.134589)
			(xy 331.365793 -96.088734) (xy 331.343143 -96.03915) (xy 331.32778 -95.986848) (xy 331.320017 -95.932891)
			(xy 331.320012 -95.878379) (xy 326.67724 -95.878379) (xy 326.676265 -95.885004) (xy 326.660197 -95.938411)
			(xy 326.636525 -95.988908) (xy 326.605752 -96.035421) (xy 326.568535 -96.076958) (xy 326.525667 -96.112633)
			(xy 326.478061 -96.141687) (xy 326.426732 -96.163499) (xy 326.372775 -96.177605) (xy 326.317338 -96.183705)
			(xy 326.261604 -96.181668) (xy 326.206761 -96.171538) (xy 326.153977 -96.153531) (xy 326.104377 -96.12803)
			(xy 326.059019 -96.095579) (xy 326.01887 -96.05687) (xy 325.984784 -96.012727) (xy 325.957488 -95.964092)
			(xy 325.937565 -95.912001) (xy 325.925439 -95.857564) (xy 325.921368 -95.801942) (xy 325.679054 -95.801942)
			(xy 325.678545 -95.829828) (xy 325.670425 -95.885004) (xy 325.654357 -95.938411) (xy 325.630685 -95.988908)
			(xy 325.599912 -96.035421) (xy 325.562695 -96.076958) (xy 325.519827 -96.112633) (xy 325.472221 -96.141687)
			(xy 325.420892 -96.163499) (xy 325.366935 -96.177605) (xy 325.311498 -96.183705) (xy 325.255764 -96.181668)
			(xy 325.200921 -96.171538) (xy 325.148137 -96.153531) (xy 325.098537 -96.12803) (xy 325.053179 -96.095579)
			(xy 325.01303 -96.05687) (xy 324.978944 -96.012727) (xy 324.951648 -95.964092) (xy 324.931725 -95.912001)
			(xy 324.919599 -95.857564) (xy 324.915528 -95.801942) (xy 324.085231 -95.801942) (xy 324.087743 -95.819014)
			(xy 324.088252 -95.8469) (xy 324.087743 -95.874786) (xy 324.079623 -95.929962) (xy 324.063555 -95.983369)
			(xy 324.039883 -96.033866) (xy 324.00911 -96.080379) (xy 323.971893 -96.121916) (xy 323.929025 -96.157591)
			(xy 323.881419 -96.186645) (xy 323.83009 -96.208457) (xy 323.776133 -96.222563) (xy 323.720696 -96.228663)
			(xy 323.664962 -96.226626) (xy 323.610119 -96.216496) (xy 323.557335 -96.198489) (xy 323.507735 -96.172988)
			(xy 323.462377 -96.140537) (xy 323.422228 -96.101828) (xy 323.388142 -96.057685) (xy 323.360846 -96.00905)
			(xy 323.340923 -95.956959) (xy 323.328797 -95.902522) (xy 323.324726 -95.8469) (xy 321.613134 -95.8469)
			(xy 321.607578 -95.885512) (xy 321.591769 -95.939333) (xy 321.568462 -95.990356) (xy 321.538132 -96.037543)
			(xy 321.501394 -96.079934) (xy 321.458998 -96.116665) (xy 321.411807 -96.146989) (xy 321.36078 -96.170289)
			(xy 321.306957 -96.18609) (xy 321.251433 -96.194071) (xy 321.223386 -96.194626) (xy 321.193088 -96.194044)
			(xy 321.133219 -96.184685) (xy 321.075503 -96.166223) (xy 321.021317 -96.139097) (xy 320.99631 -96.121982)
			(xy 320.995802 -96.121728) (xy 320.989452 -96.11741) (xy 320.96456 -96.109028) (xy 320.951098 -96.108266)
			(xy 320.94424 -96.10979) (xy 320.88963 -96.121474) (xy 320.880797 -96.124116) (xy 320.865702 -96.134674)
			(xy 320.860166 -96.142048) (xy 320.747898 -96.327976) (xy 320.719592 -96.374966) (xy 326.62698 -96.374966)
			(xy 326.631051 -96.319344) (xy 326.643177 -96.264907) (xy 326.6631 -96.212816) (xy 326.690396 -96.164181)
			(xy 326.724482 -96.120038) (xy 326.764631 -96.081329) (xy 326.809989 -96.048878) (xy 326.859589 -96.023377)
			(xy 326.912373 -96.00537) (xy 326.967216 -95.99524) (xy 327.02295 -95.993203) (xy 327.078387 -95.999303)
			(xy 327.132344 -96.013409) (xy 327.183673 -96.035221) (xy 327.231279 -96.064275) (xy 327.274147 -96.09995)
			(xy 327.311364 -96.141487) (xy 327.342137 -96.188) (xy 327.365809 -96.238497) (xy 327.380808 -96.288352)
			(xy 328.052174 -96.288352) (xy 328.056245 -96.23273) (xy 328.068371 -96.178293) (xy 328.088294 -96.126202)
			(xy 328.11559 -96.077567) (xy 328.149676 -96.033424) (xy 328.189825 -95.994715) (xy 328.235183 -95.962264)
			(xy 328.284783 -95.936763) (xy 328.337567 -95.918756) (xy 328.39241 -95.908626) (xy 328.448144 -95.906589)
			(xy 328.503581 -95.912689) (xy 328.557538 -95.926795) (xy 328.608867 -95.948607) (xy 328.656473 -95.977661)
			(xy 328.699341 -96.013336) (xy 328.736558 -96.054873) (xy 328.767331 -96.101386) (xy 328.791003 -96.151883)
			(xy 328.807071 -96.20529) (xy 328.815191 -96.260466) (xy 328.815422 -96.273112) (xy 329.397866 -96.273112)
			(xy 329.401937 -96.21749) (xy 329.414063 -96.163053) (xy 329.433986 -96.110962) (xy 329.461282 -96.062327)
			(xy 329.495368 -96.018184) (xy 329.535517 -95.979475) (xy 329.580875 -95.947024) (xy 329.630475 -95.921523)
			(xy 329.683259 -95.903516) (xy 329.738102 -95.893386) (xy 329.793836 -95.891349) (xy 329.849273 -95.897449)
			(xy 329.90323 -95.911555) (xy 329.954559 -95.933367) (xy 330.002165 -95.962421) (xy 330.045033 -95.998096)
			(xy 330.08225 -96.039633) (xy 330.113023 -96.086146) (xy 330.136695 -96.136643) (xy 330.152763 -96.19005)
			(xy 330.160883 -96.245226) (xy 330.161392 -96.273112) (xy 330.160883 -96.300998) (xy 330.152763 -96.356174)
			(xy 330.136695 -96.409581) (xy 330.113023 -96.460078) (xy 330.08225 -96.506591) (xy 330.045033 -96.548128)
			(xy 330.002165 -96.583803) (xy 329.954559 -96.612857) (xy 329.90323 -96.634669) (xy 329.849273 -96.648775)
			(xy 329.793836 -96.654875) (xy 329.738102 -96.652838) (xy 329.683259 -96.642708) (xy 329.630475 -96.624701)
			(xy 329.580875 -96.5992) (xy 329.535517 -96.566749) (xy 329.495368 -96.52804) (xy 329.461282 -96.483897)
			(xy 329.433986 -96.435262) (xy 329.414063 -96.383171) (xy 329.401937 -96.328734) (xy 329.397866 -96.273112)
			(xy 328.815422 -96.273112) (xy 328.8157 -96.288352) (xy 328.815191 -96.316238) (xy 328.807071 -96.371414)
			(xy 328.791003 -96.424821) (xy 328.767331 -96.475318) (xy 328.736558 -96.521831) (xy 328.699341 -96.563368)
			(xy 328.656473 -96.599043) (xy 328.608867 -96.628097) (xy 328.557538 -96.649909) (xy 328.503581 -96.664015)
			(xy 328.448144 -96.670115) (xy 328.39241 -96.668078) (xy 328.337567 -96.657948) (xy 328.284783 -96.639941)
			(xy 328.235183 -96.61444) (xy 328.189825 -96.581989) (xy 328.149676 -96.54328) (xy 328.11559 -96.499137)
			(xy 328.088294 -96.450502) (xy 328.068371 -96.398411) (xy 328.056245 -96.343974) (xy 328.052174 -96.288352)
			(xy 327.380808 -96.288352) (xy 327.381877 -96.291904) (xy 327.389997 -96.34708) (xy 327.390506 -96.374966)
			(xy 327.389997 -96.402852) (xy 327.381877 -96.458028) (xy 327.365809 -96.511435) (xy 327.342137 -96.561932)
			(xy 327.311364 -96.608445) (xy 327.274147 -96.649982) (xy 327.231279 -96.685657) (xy 327.183673 -96.714711)
			(xy 327.132344 -96.736523) (xy 327.078387 -96.750629) (xy 327.02295 -96.756729) (xy 326.967216 -96.754692)
			(xy 326.912373 -96.744562) (xy 326.859589 -96.726555) (xy 326.809989 -96.701054) (xy 326.764631 -96.668603)
			(xy 326.724482 -96.629894) (xy 326.690396 -96.585751) (xy 326.6631 -96.537116) (xy 326.643177 -96.485025)
			(xy 326.631051 -96.430588) (xy 326.62698 -96.374966) (xy 320.719592 -96.374966) (xy 320.644774 -96.499172)
			(xy 320.63436 -96.516444) (xy 320.633852 -96.51746) (xy 319.826589 -97.953576) (xy 320.542918 -97.953576)
			(xy 320.546989 -97.897954) (xy 320.559115 -97.843517) (xy 320.579038 -97.791426) (xy 320.606334 -97.742791)
			(xy 320.64042 -97.698648) (xy 320.680569 -97.659939) (xy 320.725927 -97.627488) (xy 320.775527 -97.601987)
			(xy 320.828311 -97.58398) (xy 320.883154 -97.57385) (xy 320.938888 -97.571813) (xy 320.994325 -97.577913)
			(xy 321.048282 -97.592019) (xy 321.099611 -97.613831) (xy 321.147217 -97.642885) (xy 321.190085 -97.67856)
			(xy 321.227302 -97.720097) (xy 321.258075 -97.76661) (xy 321.281747 -97.817107) (xy 321.282991 -97.821242)
			(xy 321.857368 -97.821242) (xy 321.861439 -97.76562) (xy 321.873565 -97.711183) (xy 321.893488 -97.659092)
			(xy 321.920784 -97.610457) (xy 321.95487 -97.566314) (xy 321.995019 -97.527605) (xy 322.040377 -97.495154)
			(xy 322.089977 -97.469653) (xy 322.142761 -97.451646) (xy 322.197604 -97.441516) (xy 322.253338 -97.439479)
			(xy 322.308775 -97.445579) (xy 322.362732 -97.459685) (xy 322.414061 -97.481497) (xy 322.461667 -97.510551)
			(xy 322.504535 -97.546226) (xy 322.541752 -97.587763) (xy 322.572525 -97.634276) (xy 322.596197 -97.684773)
			(xy 322.612265 -97.73818) (xy 322.620385 -97.793356) (xy 322.620894 -97.821242) (xy 322.620397 -97.848448)
			(xy 323.12842 -97.848448) (xy 323.12842 -97.793952) (xy 323.136175 -97.740012) (xy 323.151528 -97.687724)
			(xy 323.174166 -97.638153) (xy 323.203627 -97.592309) (xy 323.239313 -97.551123) (xy 323.280497 -97.515436)
			(xy 323.326341 -97.485972) (xy 323.375911 -97.463333) (xy 323.428198 -97.447978) (xy 323.482138 -97.440221)
			(xy 323.509386 -97.439734) (xy 323.538303 -97.44025) (xy 323.595475 -97.448977) (xy 323.650675 -97.466235)
			(xy 323.702636 -97.491627) (xy 323.75017 -97.524572) (xy 323.792186 -97.564314) (xy 323.810376 -97.5868)
			(xy 323.818003 -97.595586) (xy 323.838889 -97.605781) (xy 323.850508 -97.606358) (xy 323.930264 -97.606358)
			(xy 323.941901 -97.605856) (xy 323.962811 -97.595642) (xy 323.970396 -97.5868) (xy 323.988589 -97.564318)
			(xy 324.030609 -97.524583) (xy 324.078143 -97.491644) (xy 324.130104 -97.466255) (xy 324.185301 -97.448999)
			(xy 324.24247 -97.440269) (xy 324.271386 -97.439734) (xy 324.298643 -97.440112) (xy 324.352601 -97.447868)
			(xy 324.404906 -97.463225) (xy 324.454494 -97.485869) (xy 324.500354 -97.51534) (xy 324.541553 -97.551037)
			(xy 324.577252 -97.592235) (xy 324.606724 -97.638094) (xy 324.62937 -97.687681) (xy 324.644729 -97.739985)
			(xy 324.652487 -97.793943) (xy 324.652487 -97.821242) (xy 324.905368 -97.821242) (xy 324.909439 -97.76562)
			(xy 324.921565 -97.711183) (xy 324.941488 -97.659092) (xy 324.968784 -97.610457) (xy 325.00287 -97.566314)
			(xy 325.043019 -97.527605) (xy 325.088377 -97.495154) (xy 325.137977 -97.469653) (xy 325.190761 -97.451646)
			(xy 325.245604 -97.441516) (xy 325.301338 -97.439479) (xy 325.356775 -97.445579) (xy 325.410732 -97.459685)
			(xy 325.462061 -97.481497) (xy 325.509667 -97.510551) (xy 325.552535 -97.546226) (xy 325.589752 -97.587763)
			(xy 325.620525 -97.634276) (xy 325.644197 -97.684773) (xy 325.660265 -97.73818) (xy 325.668385 -97.793356)
			(xy 325.668894 -97.821242) (xy 325.668385 -97.849128) (xy 325.660265 -97.904304) (xy 325.644197 -97.957711)
			(xy 325.620525 -98.008208) (xy 325.589752 -98.054721) (xy 325.552535 -98.096258) (xy 325.509667 -98.131933)
			(xy 325.462061 -98.160987) (xy 325.410732 -98.182799) (xy 325.356775 -98.196905) (xy 325.301338 -98.203005)
			(xy 325.245604 -98.200968) (xy 325.190761 -98.190838) (xy 325.137977 -98.172831) (xy 325.088377 -98.14733)
			(xy 325.043019 -98.114879) (xy 325.00287 -98.07617) (xy 324.968784 -98.032027) (xy 324.941488 -97.983392)
			(xy 324.921565 -97.931301) (xy 324.909439 -97.876864) (xy 324.905368 -97.821242) (xy 324.652487 -97.821242)
			(xy 324.652487 -97.848457) (xy 324.644729 -97.902415) (xy 324.62937 -97.954719) (xy 324.606724 -98.004306)
			(xy 324.577252 -98.050165) (xy 324.541553 -98.091363) (xy 324.500354 -98.12706) (xy 324.454494 -98.156531)
			(xy 324.404906 -98.179175) (xy 324.352601 -98.194532) (xy 324.298643 -98.202288) (xy 324.271386 -98.20275)
			(xy 324.24247 -98.202189) (xy 324.1853 -98.193471) (xy 324.130102 -98.176223) (xy 324.078139 -98.15084)
			(xy 324.030605 -98.117902) (xy 323.988587 -98.078167) (xy 323.970396 -98.055684) (xy 323.962784 -98.046882)
			(xy 323.941887 -98.036696) (xy 323.930264 -98.036126) (xy 323.850508 -98.036126) (xy 323.838877 -98.036675)
			(xy 323.817967 -98.046856) (xy 323.810376 -98.055684) (xy 323.792194 -98.078176) (xy 323.750173 -98.117911)
			(xy 323.702637 -98.15085) (xy 323.650673 -98.176237) (xy 323.595474 -98.193491) (xy 323.538303 -98.202217)
			(xy 323.509386 -98.20275) (xy 323.482138 -98.202179) (xy 323.428198 -98.194422) (xy 323.375911 -98.179067)
			(xy 323.326341 -98.156428) (xy 323.280497 -98.126964) (xy 323.239313 -98.091277) (xy 323.203627 -98.050091)
			(xy 323.174166 -98.004247) (xy 323.151528 -97.954676) (xy 323.136175 -97.902388) (xy 323.12842 -97.848448)
			(xy 322.620397 -97.848448) (xy 322.620385 -97.849128) (xy 322.612265 -97.904304) (xy 322.596197 -97.957711)
			(xy 322.572525 -98.008208) (xy 322.541752 -98.054721) (xy 322.504535 -98.096258) (xy 322.461667 -98.131933)
			(xy 322.414061 -98.160987) (xy 322.362732 -98.182799) (xy 322.308775 -98.196905) (xy 322.253338 -98.203005)
			(xy 322.197604 -98.200968) (xy 322.142761 -98.190838) (xy 322.089977 -98.172831) (xy 322.040377 -98.14733)
			(xy 321.995019 -98.114879) (xy 321.95487 -98.07617) (xy 321.920784 -98.032027) (xy 321.893488 -97.983392)
			(xy 321.873565 -97.931301) (xy 321.861439 -97.876864) (xy 321.857368 -97.821242) (xy 321.282991 -97.821242)
			(xy 321.297815 -97.870514) (xy 321.305935 -97.92569) (xy 321.306444 -97.953576) (xy 321.305935 -97.981462)
			(xy 321.297815 -98.036638) (xy 321.281747 -98.090045) (xy 321.258075 -98.140542) (xy 321.227302 -98.187055)
			(xy 321.190085 -98.228592) (xy 321.147217 -98.264267) (xy 321.099611 -98.293321) (xy 321.048282 -98.315133)
			(xy 320.994325 -98.329239) (xy 320.938888 -98.335339) (xy 320.883154 -98.333302) (xy 320.828311 -98.323172)
			(xy 320.775527 -98.305165) (xy 320.725927 -98.279664) (xy 320.680569 -98.247213) (xy 320.64042 -98.208504)
			(xy 320.606334 -98.164361) (xy 320.579038 -98.115726) (xy 320.559115 -98.063635) (xy 320.546989 -98.009198)
			(xy 320.542918 -97.953576) (xy 319.826589 -97.953576) (xy 319.373556 -98.759518) (xy 331.371194 -98.759518)
			(xy 331.371672 -98.732148) (xy 331.379487 -98.67797) (xy 331.394974 -98.625467) (xy 331.417813 -98.57572)
			(xy 331.447534 -98.529752) (xy 331.465174 -98.50882) (xy 331.465428 -98.508566) (xy 331.470996 -98.501467)
			(xy 331.477253 -98.48456) (xy 331.47762 -98.475546) (xy 331.47762 -98.40849) (xy 331.477263 -98.399473)
			(xy 331.471015 -98.382557) (xy 331.465428 -98.37547) (xy 331.465174 -98.37547) (xy 331.465174 -98.375216)
			(xy 331.447549 -98.35427) (xy 331.41782 -98.308306) (xy 331.394971 -98.258562) (xy 331.379471 -98.206061)
			(xy 331.37164 -98.151884) (xy 331.371638 -98.097143) (xy 331.379465 -98.042965) (xy 331.394961 -97.990464)
			(xy 331.417807 -97.940718) (xy 331.447533 -97.894752) (xy 331.465174 -97.87382) (xy 331.465428 -97.873566)
			(xy 331.470996 -97.866467) (xy 331.477253 -97.84956) (xy 331.47762 -97.840546) (xy 331.47762 -97.77349)
			(xy 331.477263 -97.764473) (xy 331.471015 -97.747557) (xy 331.465428 -97.74047) (xy 331.465174 -97.74047)
			(xy 331.465174 -97.740216) (xy 331.447525 -97.719292) (xy 331.417815 -97.673317) (xy 331.394982 -97.623567)
			(xy 331.379493 -97.571065) (xy 331.371667 -97.516888) (xy 331.371194 -97.489518) (xy 331.37168 -97.462267)
			(xy 331.379436 -97.408319) (xy 331.394791 -97.356024) (xy 331.417433 -97.306447) (xy 331.446899 -97.260597)
			(xy 331.48259 -97.219406) (xy 331.523781 -97.183715) (xy 331.569631 -97.154249) (xy 331.619208 -97.131607)
			(xy 331.671503 -97.116252) (xy 331.725451 -97.108496) (xy 331.779953 -97.108496) (xy 331.833901 -97.116252)
			(xy 331.886196 -97.131607) (xy 331.935773 -97.154249) (xy 331.981623 -97.183715) (xy 332.022814 -97.219406)
			(xy 332.058505 -97.260597) (xy 332.087971 -97.306447) (xy 332.110613 -97.356024) (xy 332.125968 -97.408319)
			(xy 332.133724 -97.462267) (xy 332.13421 -97.489518) (xy 332.133752 -97.516888) (xy 332.125932 -97.571068)
			(xy 332.110441 -97.623571) (xy 332.087597 -97.673318) (xy 332.057872 -97.719284) (xy 332.04023 -97.740216)
			(xy 332.039976 -97.74047) (xy 332.034393 -97.747559) (xy 332.028145 -97.764474) (xy 332.027784 -97.77349)
			(xy 332.027784 -97.840546) (xy 332.02817 -97.84956) (xy 332.034398 -97.866477) (xy 332.039976 -97.873566)
			(xy 332.04023 -97.873566) (xy 332.04023 -97.87382) (xy 332.05789 -97.894738) (xy 332.087617 -97.940707)
			(xy 332.110464 -97.990455) (xy 332.125961 -98.04296) (xy 332.133789 -98.097142) (xy 332.133787 -98.151886)
			(xy 332.125955 -98.206066) (xy 332.110455 -98.25857) (xy 332.087604 -98.308317) (xy 332.057874 -98.354284)
			(xy 332.04023 -98.375216) (xy 332.039976 -98.37547) (xy 332.034393 -98.382559) (xy 332.028145 -98.399474)
			(xy 332.027784 -98.40849) (xy 332.027784 -98.475546) (xy 332.02817 -98.48456) (xy 332.034398 -98.501477)
			(xy 332.036031 -98.503552) (xy 333.025963 -98.503552) (xy 333.025963 -98.449048) (xy 333.03372 -98.395097)
			(xy 333.049076 -98.3428) (xy 333.071718 -98.293221) (xy 333.101186 -98.247369) (xy 333.13688 -98.206177)
			(xy 333.178072 -98.170484) (xy 333.223924 -98.141017) (xy 333.273504 -98.118375) (xy 333.325801 -98.103019)
			(xy 333.379752 -98.095263) (xy 333.407004 -98.0948) (xy 333.433318 -98.095265) (xy 333.485447 -98.1025)
			(xy 333.536089 -98.11682) (xy 333.584288 -98.137953) (xy 333.629132 -98.165499) (xy 333.669771 -98.198938)
			(xy 333.687928 -98.21799) (xy 333.695439 -98.225404) (xy 333.714727 -98.233922) (xy 333.725266 -98.2345)
			(xy 333.799942 -98.2345) (xy 333.81049 -98.233953) (xy 333.829785 -98.225431) (xy 333.83728 -98.21799)
			(xy 333.85545 -98.198949) (xy 333.896077 -98.165491) (xy 333.940914 -98.13793) (xy 333.989112 -98.116789)
			(xy 334.039757 -98.102469) (xy 334.091889 -98.095241) (xy 334.118204 -98.0948) (xy 334.145456 -98.09527)
			(xy 334.199404 -98.103027) (xy 334.251699 -98.118383) (xy 334.301277 -98.141025) (xy 334.347128 -98.170492)
			(xy 334.388319 -98.206184) (xy 334.424011 -98.247375) (xy 334.453477 -98.293226) (xy 334.473172 -98.336354)
			(xy 335.049368 -98.336354) (xy 335.049849 -98.308984) (xy 335.057661 -98.254805) (xy 335.073145 -98.202301)
			(xy 335.095984 -98.152554) (xy 335.125707 -98.106587) (xy 335.143348 -98.085656) (xy 335.143602 -98.085402)
			(xy 335.149194 -98.078319) (xy 335.155437 -98.0614) (xy 335.155794 -98.052382) (xy 335.155794 -97.985326)
			(xy 335.155426 -97.97631) (xy 335.149186 -97.959393) (xy 335.143602 -97.952306) (xy 335.143348 -97.952306)
			(xy 335.143348 -97.952052) (xy 335.125661 -97.931156) (xy 335.095937 -97.885182) (xy 335.073093 -97.83543)
			(xy 335.057599 -97.782922) (xy 335.049775 -97.728738) (xy 335.049779 -97.673992) (xy 335.057614 -97.61981)
			(xy 335.073117 -97.567305) (xy 335.09597 -97.517557) (xy 335.125703 -97.471588) (xy 335.143348 -97.450656)
			(xy 335.143602 -97.450402) (xy 335.149194 -97.443319) (xy 335.155437 -97.4264) (xy 335.155794 -97.417382)
			(xy 335.155794 -97.350326) (xy 335.155426 -97.34131) (xy 335.149186 -97.324393) (xy 335.143602 -97.317306)
			(xy 335.143348 -97.317306) (xy 335.143348 -97.317052) (xy 335.125727 -97.296105) (xy 335.096011 -97.250137)
			(xy 335.073171 -97.200393) (xy 335.057676 -97.147896) (xy 335.049844 -97.093722) (xy 335.049368 -97.066354)
			(xy 335.049854 -97.039103) (xy 335.05761 -96.985155) (xy 335.072965 -96.93286) (xy 335.095607 -96.883283)
			(xy 335.125073 -96.837433) (xy 335.160764 -96.796242) (xy 335.201955 -96.760551) (xy 335.247805 -96.731085)
			(xy 335.297382 -96.708443) (xy 335.349677 -96.693088) (xy 335.403625 -96.685332) (xy 335.458127 -96.685332)
			(xy 335.512075 -96.693088) (xy 335.56437 -96.708443) (xy 335.613947 -96.731085) (xy 335.659797 -96.760551)
			(xy 335.700988 -96.796242) (xy 335.727273 -96.826578) (xy 357.466898 -96.826578) (xy 357.470969 -96.770956)
			(xy 357.483095 -96.716519) (xy 357.503018 -96.664428) (xy 357.530314 -96.615793) (xy 357.5644 -96.57165)
			(xy 357.604549 -96.532941) (xy 357.649907 -96.50049) (xy 357.699507 -96.474989) (xy 357.752291 -96.456982)
			(xy 357.807134 -96.446852) (xy 357.862868 -96.444815) (xy 357.918305 -96.450915) (xy 357.972262 -96.465021)
			(xy 358.023591 -96.486833) (xy 358.071197 -96.515887) (xy 358.114065 -96.551562) (xy 358.151282 -96.593099)
			(xy 358.182055 -96.639612) (xy 358.205727 -96.690109) (xy 358.221795 -96.743516) (xy 358.229915 -96.798692)
			(xy 358.230424 -96.826578) (xy 358.229915 -96.854464) (xy 358.226917 -96.874838) (xy 359.401362 -96.874838)
			(xy 359.405433 -96.819216) (xy 359.417559 -96.764779) (xy 359.437482 -96.712688) (xy 359.464778 -96.664053)
			(xy 359.498864 -96.61991) (xy 359.539013 -96.581201) (xy 359.584371 -96.54875) (xy 359.633971 -96.523249)
			(xy 359.686755 -96.505242) (xy 359.741598 -96.495112) (xy 359.797332 -96.493075) (xy 359.852769 -96.499175)
			(xy 359.906726 -96.513281) (xy 359.958055 -96.535093) (xy 360.005661 -96.564147) (xy 360.048529 -96.599822)
			(xy 360.085746 -96.641359) (xy 360.116519 -96.687872) (xy 360.140191 -96.738369) (xy 360.156259 -96.791776)
			(xy 360.164379 -96.846952) (xy 360.164888 -96.874838) (xy 360.164379 -96.902724) (xy 360.156259 -96.9579)
			(xy 360.140191 -97.011307) (xy 360.116519 -97.061804) (xy 360.085746 -97.108317) (xy 360.048529 -97.149854)
			(xy 360.005661 -97.185529) (xy 359.958055 -97.214583) (xy 359.950631 -97.217738) (xy 365.510824 -97.217738)
			(xy 365.514895 -97.162116) (xy 365.527021 -97.107679) (xy 365.546944 -97.055588) (xy 365.57424 -97.006953)
			(xy 365.608326 -96.96281) (xy 365.648475 -96.924101) (xy 365.693833 -96.89165) (xy 365.743433 -96.866149)
			(xy 365.796217 -96.848142) (xy 365.85106 -96.838012) (xy 365.906794 -96.835975) (xy 365.962231 -96.842075)
			(xy 366.016188 -96.856181) (xy 366.067517 -96.877993) (xy 366.115123 -96.907047) (xy 366.157991 -96.942722)
			(xy 366.195208 -96.984259) (xy 366.225981 -97.030772) (xy 366.249653 -97.081269) (xy 366.265721 -97.134676)
			(xy 366.273841 -97.189852) (xy 366.27435 -97.217738) (xy 366.273841 -97.245624) (xy 366.265721 -97.3008)
			(xy 366.249653 -97.354207) (xy 366.225981 -97.404704) (xy 366.195208 -97.451217) (xy 366.157991 -97.492754)
			(xy 366.115123 -97.528429) (xy 366.067517 -97.557483) (xy 366.016188 -97.579295) (xy 365.962231 -97.593401)
			(xy 365.906794 -97.599501) (xy 365.85106 -97.597464) (xy 365.796217 -97.587334) (xy 365.743433 -97.569327)
			(xy 365.693833 -97.543826) (xy 365.648475 -97.511375) (xy 365.608326 -97.472666) (xy 365.57424 -97.428523)
			(xy 365.546944 -97.379888) (xy 365.527021 -97.327797) (xy 365.514895 -97.27336) (xy 365.510824 -97.217738)
			(xy 359.950631 -97.217738) (xy 359.906726 -97.236395) (xy 359.852769 -97.250501) (xy 359.797332 -97.256601)
			(xy 359.741598 -97.254564) (xy 359.686755 -97.244434) (xy 359.633971 -97.226427) (xy 359.584371 -97.200926)
			(xy 359.539013 -97.168475) (xy 359.498864 -97.129766) (xy 359.464778 -97.085623) (xy 359.437482 -97.036988)
			(xy 359.417559 -96.984897) (xy 359.405433 -96.93046) (xy 359.401362 -96.874838) (xy 358.226917 -96.874838)
			(xy 358.221795 -96.90964) (xy 358.205727 -96.963047) (xy 358.182055 -97.013544) (xy 358.151282 -97.060057)
			(xy 358.114065 -97.101594) (xy 358.071197 -97.137269) (xy 358.023591 -97.166323) (xy 357.972262 -97.188135)
			(xy 357.918305 -97.202241) (xy 357.862868 -97.208341) (xy 357.807134 -97.206304) (xy 357.752291 -97.196174)
			(xy 357.699507 -97.178167) (xy 357.649907 -97.152666) (xy 357.604549 -97.120215) (xy 357.5644 -97.081506)
			(xy 357.530314 -97.037363) (xy 357.503018 -96.988728) (xy 357.483095 -96.936637) (xy 357.470969 -96.8822)
			(xy 357.466898 -96.826578) (xy 335.727273 -96.826578) (xy 335.736679 -96.837433) (xy 335.766145 -96.883283)
			(xy 335.788787 -96.93286) (xy 335.804142 -96.985155) (xy 335.811898 -97.039103) (xy 335.812384 -97.066354)
			(xy 335.811895 -97.093723) (xy 335.804083 -97.147902) (xy 335.7886 -97.200405) (xy 335.765763 -97.250152)
			(xy 335.736043 -97.29612) (xy 335.718404 -97.317052) (xy 335.71815 -97.317306) (xy 335.712549 -97.324382)
			(xy 335.706312 -97.341307) (xy 335.705958 -97.350326) (xy 335.705958 -97.417382) (xy 335.706311 -97.4264)
			(xy 335.71256 -97.443317) (xy 335.71815 -97.450402) (xy 335.718404 -97.450402) (xy 335.718404 -97.450656)
			(xy 335.735998 -97.471626) (xy 335.765723 -97.517588) (xy 335.788569 -97.567328) (xy 335.804067 -97.619824)
			(xy 335.8119 -97.673997) (xy 335.811904 -97.728733) (xy 335.804082 -97.782908) (xy 335.788593 -97.835407)
			(xy 335.765756 -97.885151) (xy 335.73604 -97.931119) (xy 335.718404 -97.952052) (xy 335.71815 -97.952306)
			(xy 335.712549 -97.959382) (xy 335.706312 -97.976307) (xy 335.705958 -97.985326) (xy 335.705958 -98.052382)
			(xy 335.706311 -98.0614) (xy 335.71256 -98.078317) (xy 335.71815 -98.085402) (xy 335.718404 -98.085402)
			(xy 335.718404 -98.085656) (xy 335.736037 -98.106593) (xy 335.765749 -98.152565) (xy 335.788586 -98.202311)
			(xy 335.792404 -98.215249) (xy 337.158596 -98.215249) (xy 337.158596 -98.160751) (xy 337.166352 -98.106807)
			(xy 337.181705 -98.054516) (xy 337.204344 -98.004942) (xy 337.233808 -97.959095) (xy 337.269496 -97.917907)
			(xy 337.310682 -97.882217) (xy 337.356528 -97.852752) (xy 337.406101 -97.830111) (xy 337.458391 -97.814755)
			(xy 337.512335 -97.806997) (xy 337.539584 -97.80651) (xy 337.569852 -97.807077) (xy 337.629627 -97.816648)
			(xy 337.687141 -97.835535) (xy 337.740952 -97.863266) (xy 337.78971 -97.899145) (xy 337.811364 -97.920302)
			(xy 337.818785 -97.927252) (xy 337.837527 -97.935099) (xy 337.847686 -97.935542) (xy 337.919822 -97.935542)
			(xy 337.929984 -97.935129) (xy 337.94872 -97.927256) (xy 337.956144 -97.920302) (xy 337.977796 -97.899144)
			(xy 338.026551 -97.863261) (xy 338.080363 -97.83553) (xy 338.137879 -97.816648) (xy 338.197656 -97.807089)
			(xy 338.227924 -97.80651) (xy 338.25776 -97.807056) (xy 338.316701 -97.816363) (xy 338.373475 -97.83473)
			(xy 338.426699 -97.861709) (xy 338.475075 -97.896644) (xy 338.496656 -97.917254) (xy 338.503768 -97.924366)
			(xy 338.52231 -97.931986) (xy 338.614004 -97.931986) (xy 338.632546 -97.924366) (xy 338.639658 -97.917254)
			(xy 338.661247 -97.896655) (xy 338.709619 -97.861718) (xy 338.762841 -97.834741) (xy 338.819615 -97.816382)
			(xy 338.878556 -97.807088) (xy 338.90839 -97.80651) (xy 338.935645 -97.806936) (xy 338.989599 -97.814692)
			(xy 339.041901 -97.830048) (xy 339.091485 -97.852691) (xy 339.137341 -97.88216) (xy 339.178537 -97.917856)
			(xy 339.214234 -97.959051) (xy 339.243704 -98.004907) (xy 339.266348 -98.05449) (xy 339.281705 -98.106791)
			(xy 339.289463 -98.160745) (xy 339.289463 -98.215255) (xy 339.281705 -98.269209) (xy 339.280486 -98.273362)
			(xy 359.51363 -98.273362) (xy 359.517701 -98.21774) (xy 359.529827 -98.163303) (xy 359.54975 -98.111212)
			(xy 359.577046 -98.062577) (xy 359.611132 -98.018434) (xy 359.651281 -97.979725) (xy 359.696639 -97.947274)
			(xy 359.746239 -97.921773) (xy 359.799023 -97.903766) (xy 359.853866 -97.893636) (xy 359.9096 -97.891599)
			(xy 359.965037 -97.897699) (xy 360.018994 -97.911805) (xy 360.070323 -97.933617) (xy 360.117929 -97.962671)
			(xy 360.160797 -97.998346) (xy 360.198014 -98.039883) (xy 360.228787 -98.086396) (xy 360.252459 -98.136893)
			(xy 360.268527 -98.1903) (xy 360.276647 -98.245476) (xy 360.277156 -98.273362) (xy 360.276647 -98.301248)
			(xy 360.268527 -98.356424) (xy 360.252459 -98.409831) (xy 360.228787 -98.460328) (xy 360.198014 -98.506841)
			(xy 360.160797 -98.548378) (xy 360.117929 -98.584053) (xy 360.070323 -98.613107) (xy 360.018994 -98.634919)
			(xy 359.965037 -98.649025) (xy 359.9096 -98.655125) (xy 359.853866 -98.653088) (xy 359.799023 -98.642958)
			(xy 359.746239 -98.624951) (xy 359.696639 -98.59945) (xy 359.651281 -98.566999) (xy 359.611132 -98.52829)
			(xy 359.577046 -98.484147) (xy 359.54975 -98.435512) (xy 359.529827 -98.383421) (xy 359.517701 -98.328984)
			(xy 359.51363 -98.273362) (xy 339.280486 -98.273362) (xy 339.266348 -98.32151) (xy 339.243704 -98.371093)
			(xy 339.214234 -98.416949) (xy 339.178537 -98.458144) (xy 339.137341 -98.49384) (xy 339.091485 -98.523309)
			(xy 339.041901 -98.545952) (xy 338.989599 -98.561308) (xy 338.935645 -98.569064) (xy 338.90839 -98.569526)
			(xy 338.878555 -98.56896) (xy 338.819615 -98.559657) (xy 338.762842 -98.541294) (xy 338.709617 -98.514319)
			(xy 338.66124 -98.47939) (xy 338.639658 -98.458782) (xy 338.632546 -98.45167) (xy 338.614004 -98.44405)
			(xy 338.52231 -98.44405) (xy 338.503768 -98.45167) (xy 338.496656 -98.458782) (xy 338.475094 -98.479412)
			(xy 338.426716 -98.514346) (xy 338.373487 -98.541319) (xy 338.316707 -98.559671) (xy 338.25776 -98.568954)
			(xy 338.227924 -98.569526) (xy 338.197657 -98.568944) (xy 338.137883 -98.559375) (xy 338.080369 -98.540491)
			(xy 338.026558 -98.512763) (xy 337.977799 -98.476889) (xy 337.956144 -98.455734) (xy 337.948716 -98.448792)
			(xy 337.92998 -98.440939) (xy 337.919822 -98.440494) (xy 337.847686 -98.440494) (xy 337.837523 -98.440902)
			(xy 337.818786 -98.448778) (xy 337.811364 -98.455734) (xy 337.789714 -98.476895) (xy 337.740958 -98.512776)
			(xy 337.687146 -98.540506) (xy 337.629629 -98.559387) (xy 337.569852 -98.568947) (xy 337.539584 -98.569526)
			(xy 337.512335 -98.569003) (xy 337.458391 -98.561245) (xy 337.406101 -98.545889) (xy 337.356528 -98.523248)
			(xy 337.310682 -98.493783) (xy 337.269496 -98.458093) (xy 337.233808 -98.416905) (xy 337.204344 -98.371058)
			(xy 337.181705 -98.321484) (xy 337.166352 -98.269193) (xy 337.158596 -98.215249) (xy 335.792404 -98.215249)
			(xy 335.804079 -98.25481) (xy 335.811909 -98.308985) (xy 335.812384 -98.336354) (xy 335.811898 -98.363605)
			(xy 335.804142 -98.417553) (xy 335.788787 -98.469848) (xy 335.766145 -98.519425) (xy 335.736679 -98.565275)
			(xy 335.700988 -98.606466) (xy 335.659797 -98.642157) (xy 335.613947 -98.671623) (xy 335.56437 -98.694265)
			(xy 335.512075 -98.70962) (xy 335.458127 -98.717376) (xy 335.403625 -98.717376) (xy 335.349677 -98.70962)
			(xy 335.297382 -98.694265) (xy 335.247805 -98.671623) (xy 335.201955 -98.642157) (xy 335.160764 -98.606466)
			(xy 335.125073 -98.565275) (xy 335.095607 -98.519425) (xy 335.072965 -98.469848) (xy 335.05761 -98.417553)
			(xy 335.049854 -98.363605) (xy 335.049368 -98.336354) (xy 334.473172 -98.336354) (xy 334.476118 -98.342804)
			(xy 334.491474 -98.3951) (xy 334.49923 -98.449048) (xy 334.49923 -98.503552) (xy 334.491474 -98.5575)
			(xy 334.476118 -98.609796) (xy 334.453477 -98.659374) (xy 334.424011 -98.705225) (xy 334.388319 -98.746416)
			(xy 334.347128 -98.782108) (xy 334.301277 -98.811575) (xy 334.251699 -98.834217) (xy 334.199404 -98.849573)
			(xy 334.145456 -98.85733) (xy 334.118204 -98.857816) (xy 334.09189 -98.857341) (xy 334.039762 -98.850107)
			(xy 333.98912 -98.835789) (xy 333.940921 -98.814658) (xy 333.896077 -98.787113) (xy 333.855437 -98.753677)
			(xy 333.83728 -98.734626) (xy 333.829764 -98.727217) (xy 333.81048 -98.718696) (xy 333.799942 -98.718116)
			(xy 333.725266 -98.718116) (xy 333.714718 -98.718663) (xy 333.695422 -98.727185) (xy 333.687928 -98.734626)
			(xy 333.669757 -98.753666) (xy 333.62913 -98.787123) (xy 333.584293 -98.814684) (xy 333.536095 -98.835825)
			(xy 333.485451 -98.850146) (xy 333.433319 -98.857375) (xy 333.407004 -98.857816) (xy 333.379752 -98.857337)
			(xy 333.325801 -98.849581) (xy 333.273504 -98.834225) (xy 333.223924 -98.811583) (xy 333.178072 -98.782116)
			(xy 333.13688 -98.746423) (xy 333.101186 -98.705231) (xy 333.071718 -98.659379) (xy 333.049076 -98.6098)
			(xy 333.03372 -98.557503) (xy 333.025963 -98.503552) (xy 332.036031 -98.503552) (xy 332.039976 -98.508566)
			(xy 332.04023 -98.509074) (xy 332.051175 -98.521807) (xy 332.071016 -98.548899) (xy 332.079854 -98.563176)
			(xy 332.085188 -98.572066) (xy 332.102206 -98.584258) (xy 332.195424 -98.604578) (xy 332.215998 -98.60026)
			(xy 332.224634 -98.594418) (xy 332.248689 -98.578403) (xy 332.300623 -98.553064) (xy 332.355784 -98.535842)
			(xy 332.412911 -98.527132) (xy 332.441804 -98.5266) (xy 332.469056 -98.52707) (xy 332.523004 -98.534827)
			(xy 332.575299 -98.550183) (xy 332.624877 -98.572825) (xy 332.670728 -98.602292) (xy 332.711919 -98.637984)
			(xy 332.747611 -98.679175) (xy 332.777077 -98.725026) (xy 332.799718 -98.774604) (xy 332.815074 -98.8269)
			(xy 332.82283 -98.880848) (xy 332.82283 -98.935352) (xy 332.815074 -98.9893) (xy 332.799718 -99.041596)
			(xy 332.777077 -99.091174) (xy 332.747611 -99.137025) (xy 332.73442 -99.152248) (xy 355.277702 -99.152248)
			(xy 355.277702 -99.097752) (xy 355.285457 -99.04381) (xy 355.30081 -98.99152) (xy 355.323448 -98.941948)
			(xy 355.35291 -98.896102) (xy 355.388597 -98.854915) (xy 355.429781 -98.819226) (xy 355.475625 -98.789761)
			(xy 355.525196 -98.767119) (xy 355.577484 -98.751763) (xy 355.631426 -98.744004) (xy 355.658674 -98.743516)
			(xy 355.688256 -98.744117) (xy 355.746712 -98.753246) (xy 355.803058 -98.771289) (xy 355.855944 -98.797813)
			(xy 355.904101 -98.832184) (xy 355.925628 -98.852482) (xy 355.932994 -98.859594) (xy 355.952044 -98.867214)
			(xy 356.046024 -98.86442) (xy 356.06482 -98.855784) (xy 356.071678 -98.848164) (xy 356.089826 -98.828878)
			(xy 356.130555 -98.795029) (xy 356.175571 -98.767135) (xy 356.224011 -98.745731) (xy 356.274944 -98.731228)
			(xy 356.327393 -98.723904) (xy 356.353872 -98.72345) (xy 356.381123 -98.723995) (xy 356.435071 -98.731748)
			(xy 356.487367 -98.7471) (xy 356.536945 -98.769739) (xy 356.582796 -98.799203) (xy 356.623988 -98.834892)
			(xy 356.659681 -98.876081) (xy 356.689148 -98.921931) (xy 356.71179 -98.971507) (xy 356.727146 -99.023801)
			(xy 356.734903 -99.077749) (xy 356.734903 -99.132251) (xy 356.727146 -99.186199) (xy 356.71179 -99.238493)
			(xy 356.689148 -99.288069) (xy 356.659681 -99.333919) (xy 356.623988 -99.375108) (xy 356.582796 -99.410797)
			(xy 356.536945 -99.440261) (xy 356.487367 -99.4629) (xy 356.435071 -99.478252) (xy 356.381123 -99.486005)
			(xy 356.353872 -99.486466) (xy 356.324288 -99.485904) (xy 356.26583 -99.476766) (xy 356.209483 -99.458714)
			(xy 356.156599 -99.432181) (xy 356.108443 -99.397802) (xy 356.086918 -99.3775) (xy 356.079552 -99.370388)
			(xy 356.060502 -99.362768) (xy 355.966522 -99.365562) (xy 355.947726 -99.374198) (xy 355.940868 -99.381818)
			(xy 355.922694 -99.401079) (xy 355.881971 -99.43493) (xy 355.83696 -99.462828) (xy 355.788526 -99.484237)
			(xy 355.737597 -99.498745) (xy 355.685151 -99.506075) (xy 355.658674 -99.506532) (xy 355.631426 -99.505996)
			(xy 355.577484 -99.498237) (xy 355.525196 -99.482881) (xy 355.475625 -99.460239) (xy 355.429781 -99.430774)
			(xy 355.388597 -99.395085) (xy 355.35291 -99.353898) (xy 355.323448 -99.308052) (xy 355.30081 -99.25848)
			(xy 355.285457 -99.20619) (xy 355.277702 -99.152248) (xy 332.73442 -99.152248) (xy 332.711919 -99.178216)
			(xy 332.670728 -99.213908) (xy 332.624877 -99.243375) (xy 332.575299 -99.266017) (xy 332.523004 -99.281373)
			(xy 332.469056 -99.28913) (xy 332.441804 -99.289616) (xy 332.413713 -99.289119) (xy 332.358135 -99.280892)
			(xy 332.304367 -99.264601) (xy 332.253569 -99.240599) (xy 332.206842 -99.209405) (xy 332.165197 -99.171693)
			(xy 332.129535 -99.12828) (xy 332.114652 -99.10445) (xy 332.109318 -99.09556) (xy 332.0923 -99.083368)
			(xy 331.999082 -99.063048) (xy 331.978508 -99.067366) (xy 331.969872 -99.073208) (xy 331.945818 -99.089223)
			(xy 331.893883 -99.114562) (xy 331.838722 -99.131784) (xy 331.781595 -99.140494) (xy 331.752702 -99.141026)
			(xy 331.725452 -99.14052) (xy 331.671506 -99.132765) (xy 331.619212 -99.117411) (xy 331.569636 -99.094771)
			(xy 331.523787 -99.065307) (xy 331.482597 -99.029617) (xy 331.446905 -98.988429) (xy 331.417439 -98.942581)
			(xy 331.394796 -98.893007) (xy 331.37944 -98.840714) (xy 331.371681 -98.786768) (xy 331.371194 -98.759518)
			(xy 319.373556 -98.759518) (xy 318.985773 -99.449382) (xy 320.106038 -99.449382) (xy 320.110109 -99.39376)
			(xy 320.122235 -99.339323) (xy 320.142158 -99.287232) (xy 320.169454 -99.238597) (xy 320.20354 -99.194454)
			(xy 320.243689 -99.155745) (xy 320.289047 -99.123294) (xy 320.338647 -99.097793) (xy 320.391431 -99.079786)
			(xy 320.446274 -99.069656) (xy 320.502008 -99.067619) (xy 320.557445 -99.073719) (xy 320.611402 -99.087825)
			(xy 320.662731 -99.109637) (xy 320.710337 -99.138691) (xy 320.753205 -99.174366) (xy 320.790422 -99.215903)
			(xy 320.821195 -99.262416) (xy 320.844867 -99.312913) (xy 320.860935 -99.36632) (xy 320.869055 -99.421496)
			(xy 320.869564 -99.449382) (xy 320.869397 -99.458526) (xy 325.838564 -99.458526) (xy 325.842635 -99.402904)
			(xy 325.854761 -99.348467) (xy 325.874684 -99.296376) (xy 325.90198 -99.247741) (xy 325.936066 -99.203598)
			(xy 325.976215 -99.164889) (xy 326.021573 -99.132438) (xy 326.071173 -99.106937) (xy 326.123957 -99.08893)
			(xy 326.1788 -99.0788) (xy 326.234534 -99.076763) (xy 326.289971 -99.082863) (xy 326.343928 -99.096969)
			(xy 326.395257 -99.118781) (xy 326.442863 -99.147835) (xy 326.485731 -99.18351) (xy 326.522948 -99.225047)
			(xy 326.553721 -99.27156) (xy 326.577393 -99.322057) (xy 326.593461 -99.375464) (xy 326.601581 -99.43064)
			(xy 326.60209 -99.458526) (xy 326.601581 -99.486412) (xy 326.596585 -99.520357) (xy 370.426625 -99.520357)
			(xy 370.426625 -99.465843) (xy 370.434384 -99.411884) (xy 370.449743 -99.359579) (xy 370.47239 -99.309992)
			(xy 370.501865 -99.264133) (xy 370.537566 -99.222936) (xy 370.578767 -99.18724) (xy 370.624629 -99.15777)
			(xy 370.674218 -99.135128) (xy 370.726525 -99.119775) (xy 370.780485 -99.112022) (xy 370.807742 -99.111562)
			(xy 370.834964 -99.112001) (xy 370.888857 -99.119729) (xy 370.941105 -99.135037) (xy 370.990648 -99.157614)
			(xy 371.036479 -99.187003) (xy 371.077669 -99.222605) (xy 371.113382 -99.2637) (xy 371.128544 -99.286314)
			(xy 371.137173 -99.298701) (xy 371.16016 -99.318238) (xy 371.187857 -99.330197) (xy 371.21784 -99.333532)
			(xy 371.247488 -99.327951) (xy 371.274206 -99.313941) (xy 371.295659 -99.292729) (xy 371.303296 -99.27971)
			(xy 371.317739 -99.254195) (xy 371.353158 -99.207477) (xy 371.39531 -99.16673) (xy 371.443202 -99.132915)
			(xy 371.495705 -99.106828) (xy 371.551582 -99.089084) (xy 371.609517 -99.0801) (xy 371.63883 -99.079558)
			(xy 371.666077 -99.080114) (xy 371.720017 -99.087874) (xy 371.772303 -99.10323) (xy 371.821872 -99.125871)
			(xy 371.867715 -99.155335) (xy 371.908898 -99.191023) (xy 371.944583 -99.232209) (xy 371.974044 -99.278054)
			(xy 371.996681 -99.327625) (xy 372.012033 -99.379912) (xy 372.019788 -99.433853) (xy 372.019788 -99.488347)
			(xy 372.012033 -99.542288) (xy 371.996681 -99.594575) (xy 371.974044 -99.644146) (xy 371.944583 -99.689991)
			(xy 371.908898 -99.731177) (xy 371.867715 -99.766865) (xy 371.821872 -99.796329) (xy 371.772303 -99.81897)
			(xy 371.720017 -99.834326) (xy 371.666077 -99.842086) (xy 371.63883 -99.842574) (xy 371.61161 -99.842064)
			(xy 371.557721 -99.834346) (xy 371.505476 -99.819049) (xy 371.455934 -99.796483) (xy 371.410102 -99.767107)
			(xy 371.368909 -99.731515) (xy 371.333192 -99.690431) (xy 371.318028 -99.667822) (xy 371.30944 -99.655403)
			(xy 371.286446 -99.635857) (xy 371.258739 -99.623894) (xy 371.228744 -99.620561) (xy 371.199087 -99.62615)
			(xy 371.172363 -99.640172) (xy 371.150911 -99.661399) (xy 371.143276 -99.674426) (xy 371.128868 -99.699962)
			(xy 371.093441 -99.746678) (xy 371.051282 -99.787422) (xy 371.003385 -99.821235) (xy 370.950877 -99.847318)
			(xy 370.894995 -99.865058) (xy 370.837057 -99.874038) (xy 370.807742 -99.874578) (xy 370.780485 -99.874178)
			(xy 370.726525 -99.866425) (xy 370.674218 -99.851072) (xy 370.624629 -99.82843) (xy 370.578767 -99.79896)
			(xy 370.537566 -99.763264) (xy 370.501865 -99.722067) (xy 370.47239 -99.676208) (xy 370.449743 -99.626621)
			(xy 370.434384 -99.574316) (xy 370.426625 -99.520357) (xy 326.596585 -99.520357) (xy 326.593461 -99.541588)
			(xy 326.577393 -99.594995) (xy 326.553721 -99.645492) (xy 326.522948 -99.692005) (xy 326.485731 -99.733542)
			(xy 326.442863 -99.769217) (xy 326.395257 -99.798271) (xy 326.343928 -99.820083) (xy 326.289971 -99.834189)
			(xy 326.234534 -99.840289) (xy 326.1788 -99.838252) (xy 326.123957 -99.828122) (xy 326.071173 -99.810115)
			(xy 326.021573 -99.784614) (xy 325.976215 -99.752163) (xy 325.936066 -99.713454) (xy 325.90198 -99.669311)
			(xy 325.874684 -99.620676) (xy 325.854761 -99.568585) (xy 325.842635 -99.514148) (xy 325.838564 -99.458526)
			(xy 320.869397 -99.458526) (xy 320.869055 -99.477268) (xy 320.860935 -99.532444) (xy 320.844867 -99.585851)
			(xy 320.821195 -99.636348) (xy 320.790422 -99.682861) (xy 320.753205 -99.724398) (xy 320.710337 -99.760073)
			(xy 320.662731 -99.789127) (xy 320.611402 -99.810939) (xy 320.557445 -99.825045) (xy 320.502008 -99.831145)
			(xy 320.446274 -99.829108) (xy 320.391431 -99.818978) (xy 320.338647 -99.800971) (xy 320.289047 -99.77547)
			(xy 320.243689 -99.743019) (xy 320.20354 -99.70431) (xy 320.169454 -99.660167) (xy 320.142158 -99.611532)
			(xy 320.122235 -99.559441) (xy 320.110109 -99.505004) (xy 320.106038 -99.449382) (xy 318.985773 -99.449382)
			(xy 318.007429 -101.18985) (xy 329.19339 -101.18985) (xy 329.19339 -101.13535) (xy 329.201146 -101.081404)
			(xy 329.216501 -101.029111) (xy 329.239141 -100.979536) (xy 329.268606 -100.933687) (xy 329.304297 -100.892498)
			(xy 329.345485 -100.856808) (xy 329.391334 -100.827342) (xy 329.440909 -100.804702) (xy 329.493202 -100.789347)
			(xy 329.547148 -100.78159) (xy 329.574398 -100.781104) (xy 329.601768 -100.78157) (xy 329.655947 -100.789388)
			(xy 329.708451 -100.804877) (xy 329.758197 -100.827719) (xy 329.804164 -100.857443) (xy 329.825096 -100.875084)
			(xy 329.82535 -100.875338) (xy 329.832444 -100.880914) (xy 329.849355 -100.887166) (xy 329.85837 -100.88753)
			(xy 329.925426 -100.88753) (xy 329.934443 -100.887179) (xy 329.95136 -100.880927) (xy 329.958446 -100.875338)
			(xy 329.958446 -100.875084) (xy 329.9587 -100.875084) (xy 329.979619 -100.857429) (xy 330.025596 -100.82772)
			(xy 330.075347 -100.804887) (xy 330.12785 -100.7894) (xy 330.182028 -100.781576) (xy 330.209398 -100.781104)
			(xy 330.236652 -100.781543) (xy 330.290605 -100.7893) (xy 330.342905 -100.804656) (xy 330.392487 -100.827299)
			(xy 330.438341 -100.856768) (xy 330.479536 -100.892463) (xy 330.515231 -100.933657) (xy 330.5447 -100.979512)
			(xy 330.56278 -101.019102) (xy 349.382078 -101.019102) (xy 349.386149 -100.96348) (xy 349.398275 -100.909043)
			(xy 349.418198 -100.856952) (xy 349.445494 -100.808317) (xy 349.47958 -100.764174) (xy 349.519729 -100.725465)
			(xy 349.565087 -100.693014) (xy 349.614687 -100.667513) (xy 349.667471 -100.649506) (xy 349.722314 -100.639376)
			(xy 349.778048 -100.637339) (xy 349.833485 -100.643439) (xy 349.887442 -100.657545) (xy 349.938771 -100.679357)
			(xy 349.986377 -100.708411) (xy 350.029245 -100.744086) (xy 350.066462 -100.785623) (xy 350.097235 -100.832136)
			(xy 350.120907 -100.882633) (xy 350.136975 -100.93604) (xy 350.142848 -100.975946) (xy 352.819522 -100.975946)
			(xy 352.819522 -100.921454) (xy 352.827277 -100.867516) (xy 352.842628 -100.81523) (xy 352.865264 -100.765661)
			(xy 352.894723 -100.719818) (xy 352.930406 -100.678633) (xy 352.971587 -100.642946) (xy 353.017428 -100.613482)
			(xy 353.066994 -100.590841) (xy 353.119278 -100.575485) (xy 353.173216 -100.567725) (xy 353.200462 -100.567236)
			(xy 353.228365 -100.567766) (xy 353.283576 -100.575903) (xy 353.337012 -100.591994) (xy 353.387536 -100.615696)
			(xy 353.434069 -100.646503) (xy 353.475619 -100.683759) (xy 353.493832 -100.704904) (xy 353.494086 -100.705158)
			(xy 353.502 -100.713719) (xy 353.52332 -100.723098) (xy 353.53498 -100.723192) (xy 353.62769 -100.719382)
			(xy 353.648518 -100.707952) (xy 353.655376 -100.6983) (xy 353.670737 -100.677075) (xy 353.706324 -100.638624)
			(xy 353.746841 -100.605407) (xy 353.791522 -100.578048) (xy 353.839529 -100.557064) (xy 353.889956 -100.542848)
			(xy 353.941854 -100.53567) (xy 353.96805 -100.535232) (xy 353.997917 -100.535824) (xy 354.056921 -100.54514)
			(xy 354.113752 -100.563538) (xy 354.167022 -100.590567) (xy 354.215429 -100.625567) (xy 354.25779 -100.667683)
			(xy 354.275898 -100.691442) (xy 354.282756 -100.70084) (xy 354.302822 -100.711508) (xy 354.393246 -100.715826)
			(xy 354.404525 -100.71583) (xy 354.425355 -100.707245) (xy 354.433378 -100.699316) (xy 354.433632 -100.699062)
			(xy 354.451835 -100.679437) (xy 354.492736 -100.644911) (xy 354.53806 -100.616438) (xy 354.586918 -100.594576)
			(xy 354.63835 -100.579755) (xy 354.691349 -100.572265) (xy 354.718112 -100.571808) (xy 354.747239 -100.572336)
			(xy 354.804813 -100.581206) (xy 354.86037 -100.598723) (xy 354.912619 -100.62448) (xy 354.960347 -100.657879)
			(xy 355.002445 -100.698144) (xy 355.020626 -100.720906) (xy 355.028349 -100.729903) (xy 355.049672 -100.740219)
			(xy 355.06152 -100.740718) (xy 355.154992 -100.739702) (xy 355.176074 -100.72878) (xy 355.183186 -100.718874)
			(xy 355.201274 -100.695097) (xy 355.243635 -100.652975) (xy 355.292044 -100.617971) (xy 355.345318 -100.590942)
			(xy 355.402155 -100.572549) (xy 355.461165 -100.563241) (xy 355.491034 -100.562664) (xy 355.518282 -100.563209)
			(xy 355.572222 -100.570968) (xy 355.624508 -100.586325) (xy 355.674078 -100.608967) (xy 355.71992 -100.638432)
			(xy 355.761103 -100.674121) (xy 355.796789 -100.715307) (xy 355.82625 -100.761152) (xy 355.848887 -100.810723)
			(xy 355.864239 -100.863012) (xy 355.871994 -100.916952) (xy 355.871994 -100.971448) (xy 355.864239 -101.025388)
			(xy 355.848887 -101.077677) (xy 355.837591 -101.102414) (xy 357.314498 -101.102414) (xy 357.318569 -101.046792)
			(xy 357.330695 -100.992355) (xy 357.350618 -100.940264) (xy 357.377914 -100.891629) (xy 357.412 -100.847486)
			(xy 357.452149 -100.808777) (xy 357.497507 -100.776326) (xy 357.547107 -100.750825) (xy 357.599891 -100.732818)
			(xy 357.654734 -100.722688) (xy 357.710468 -100.720651) (xy 357.765905 -100.726751) (xy 357.819862 -100.740857)
			(xy 357.871191 -100.762669) (xy 357.918797 -100.791723) (xy 357.961665 -100.827398) (xy 357.998882 -100.868935)
			(xy 358.029655 -100.915448) (xy 358.053327 -100.965945) (xy 358.069395 -101.019352) (xy 358.077515 -101.074528)
			(xy 358.078024 -101.102414) (xy 358.077954 -101.106224) (xy 358.867708 -101.106224) (xy 358.871779 -101.050602)
			(xy 358.883905 -100.996165) (xy 358.903828 -100.944074) (xy 358.931124 -100.895439) (xy 358.96521 -100.851296)
			(xy 359.005359 -100.812587) (xy 359.050717 -100.780136) (xy 359.100317 -100.754635) (xy 359.153101 -100.736628)
			(xy 359.207944 -100.726498) (xy 359.263678 -100.724461) (xy 359.319115 -100.730561) (xy 359.373072 -100.744667)
			(xy 359.424401 -100.766479) (xy 359.472007 -100.795533) (xy 359.514875 -100.831208) (xy 359.552092 -100.872745)
			(xy 359.582865 -100.919258) (xy 359.606537 -100.969755) (xy 359.622605 -101.023162) (xy 359.630725 -101.078338)
			(xy 359.631234 -101.106224) (xy 359.630725 -101.13411) (xy 359.622605 -101.189286) (xy 359.606537 -101.242693)
			(xy 359.582865 -101.29319) (xy 359.552092 -101.339703) (xy 359.514875 -101.38124) (xy 359.472007 -101.416915)
			(xy 359.424401 -101.445969) (xy 359.373072 -101.467781) (xy 359.319115 -101.481887) (xy 359.263678 -101.487987)
			(xy 359.207944 -101.48595) (xy 359.153101 -101.47582) (xy 359.100317 -101.457813) (xy 359.050717 -101.432312)
			(xy 359.005359 -101.399861) (xy 358.96521 -101.361152) (xy 358.931124 -101.317009) (xy 358.903828 -101.268374)
			(xy 358.883905 -101.216283) (xy 358.871779 -101.161846) (xy 358.867708 -101.106224) (xy 358.077954 -101.106224)
			(xy 358.077515 -101.1303) (xy 358.069395 -101.185476) (xy 358.053327 -101.238883) (xy 358.029655 -101.28938)
			(xy 357.998882 -101.335893) (xy 357.961665 -101.37743) (xy 357.918797 -101.413105) (xy 357.871191 -101.442159)
			(xy 357.819862 -101.463971) (xy 357.765905 -101.478077) (xy 357.710468 -101.484177) (xy 357.654734 -101.48214)
			(xy 357.599891 -101.47201) (xy 357.547107 -101.454003) (xy 357.497507 -101.428502) (xy 357.452149 -101.396051)
			(xy 357.412 -101.357342) (xy 357.377914 -101.313199) (xy 357.350618 -101.264564) (xy 357.330695 -101.212473)
			(xy 357.318569 -101.158036) (xy 357.314498 -101.102414) (xy 355.837591 -101.102414) (xy 355.82625 -101.127248)
			(xy 355.796789 -101.173093) (xy 355.761103 -101.214279) (xy 355.71992 -101.249968) (xy 355.674078 -101.279433)
			(xy 355.624508 -101.302075) (xy 355.572222 -101.317432) (xy 355.518282 -101.325191) (xy 355.491034 -101.32568)
			(xy 355.461908 -101.325124) (xy 355.404336 -101.31626) (xy 355.348779 -101.298749) (xy 355.296529 -101.272997)
			(xy 355.2488 -101.239603) (xy 355.206701 -101.199343) (xy 355.18852 -101.176582) (xy 355.180779 -101.167604)
			(xy 355.159469 -101.157279) (xy 355.147626 -101.15677) (xy 355.054154 -101.157786) (xy 355.033072 -101.168708)
			(xy 355.02596 -101.178614) (xy 355.009286 -101.200574) (xy 354.970658 -101.239916) (xy 354.926767 -101.273287)
			(xy 354.87853 -101.299993) (xy 354.826951 -101.319475) (xy 354.773104 -101.33133) (xy 354.718112 -101.335309)
			(xy 354.66312 -101.33133) (xy 354.609273 -101.319475) (xy 354.557694 -101.299993) (xy 354.509457 -101.273287)
			(xy 354.465566 -101.239916) (xy 354.426938 -101.200574) (xy 354.410264 -101.178614) (xy 354.403406 -101.169216)
			(xy 354.38334 -101.158548) (xy 354.292916 -101.15423) (xy 354.281641 -101.154275) (xy 354.260813 -101.162827)
			(xy 354.252784 -101.17074) (xy 354.25253 -101.170994) (xy 354.234358 -101.190648) (xy 354.193448 -101.22517)
			(xy 354.148118 -101.253637) (xy 354.099254 -101.275493) (xy 354.047817 -101.290309) (xy 353.994814 -101.297794)
			(xy 353.96805 -101.298248) (xy 353.940144 -101.297785) (xy 353.88493 -101.289635) (xy 353.831492 -101.273531)
			(xy 353.780969 -101.249817) (xy 353.734438 -101.218997) (xy 353.692891 -101.18173) (xy 353.67468 -101.16058)
			(xy 353.674426 -101.160326) (xy 353.666495 -101.151784) (xy 353.645188 -101.142391) (xy 353.633532 -101.142292)
			(xy 353.540822 -101.146102) (xy 353.519994 -101.157532) (xy 353.513136 -101.167184) (xy 353.497763 -101.188399)
			(xy 353.462178 -101.226851) (xy 353.421664 -101.26007) (xy 353.376984 -101.28743) (xy 353.32898 -101.308416)
			(xy 353.278554 -101.322633) (xy 353.226658 -101.329814) (xy 353.200462 -101.330252) (xy 353.173216 -101.329675)
			(xy 353.119278 -101.321915) (xy 353.066994 -101.306559) (xy 353.017428 -101.283918) (xy 352.971587 -101.254454)
			(xy 352.930406 -101.218767) (xy 352.894723 -101.177582) (xy 352.865264 -101.131739) (xy 352.842628 -101.08217)
			(xy 352.827277 -101.029884) (xy 352.819522 -100.975946) (xy 350.142848 -100.975946) (xy 350.145095 -100.991216)
			(xy 350.145604 -101.019102) (xy 350.145095 -101.046988) (xy 350.136975 -101.102164) (xy 350.120907 -101.155571)
			(xy 350.097235 -101.206068) (xy 350.066462 -101.252581) (xy 350.029245 -101.294118) (xy 349.986377 -101.329793)
			(xy 349.938771 -101.358847) (xy 349.887442 -101.380659) (xy 349.833485 -101.394765) (xy 349.778048 -101.400865)
			(xy 349.722314 -101.398828) (xy 349.667471 -101.388698) (xy 349.614687 -101.370691) (xy 349.565087 -101.34519)
			(xy 349.519729 -101.312739) (xy 349.47958 -101.27403) (xy 349.445494 -101.229887) (xy 349.418198 -101.181252)
			(xy 349.398275 -101.129161) (xy 349.386149 -101.074724) (xy 349.382078 -101.019102) (xy 330.56278 -101.019102)
			(xy 330.567343 -101.029094) (xy 330.5827 -101.081393) (xy 330.590457 -101.135346) (xy 330.590457 -101.189854)
			(xy 330.5827 -101.243807) (xy 330.567343 -101.296106) (xy 330.5447 -101.345688) (xy 330.515231 -101.391543)
			(xy 330.479536 -101.432737) (xy 330.438341 -101.468432) (xy 330.392487 -101.497901) (xy 330.342905 -101.520544)
			(xy 330.290605 -101.5359) (xy 330.236652 -101.543657) (xy 330.209398 -101.54412) (xy 330.182027 -101.543675)
			(xy 330.127846 -101.535855) (xy 330.075342 -101.520362) (xy 330.025595 -101.497515) (xy 329.97963 -101.467784)
			(xy 329.9587 -101.45014) (xy 329.958446 -101.449886) (xy 329.951352 -101.444311) (xy 329.934441 -101.438058)
			(xy 329.925426 -101.437694) (xy 329.85837 -101.437694) (xy 329.849352 -101.438038) (xy 329.832435 -101.444295)
			(xy 329.82535 -101.449886) (xy 329.82535 -101.45014) (xy 329.825096 -101.45014) (xy 329.804182 -101.467801)
			(xy 329.758203 -101.497508) (xy 329.708451 -101.520339) (xy 329.655947 -101.535826) (xy 329.601768 -101.543649)
			(xy 329.574398 -101.54412) (xy 329.547148 -101.54361) (xy 329.493202 -101.535853) (xy 329.440909 -101.520498)
			(xy 329.391334 -101.497858) (xy 329.345485 -101.468392) (xy 329.304297 -101.432702) (xy 329.268606 -101.391513)
			(xy 329.239141 -101.345664) (xy 329.216501 -101.296089) (xy 329.201146 -101.243796) (xy 329.19339 -101.18985)
			(xy 318.007429 -101.18985) (xy 317.788585 -101.579172) (xy 319.970656 -101.579172) (xy 319.974727 -101.52355)
			(xy 319.986853 -101.469113) (xy 320.006776 -101.417022) (xy 320.034072 -101.368387) (xy 320.068158 -101.324244)
			(xy 320.108307 -101.285535) (xy 320.153665 -101.253084) (xy 320.203265 -101.227583) (xy 320.256049 -101.209576)
			(xy 320.310892 -101.199446) (xy 320.366626 -101.197409) (xy 320.422063 -101.203509) (xy 320.47602 -101.217615)
			(xy 320.527349 -101.239427) (xy 320.574955 -101.268481) (xy 320.617823 -101.304156) (xy 320.65504 -101.345693)
			(xy 320.685813 -101.392206) (xy 320.709485 -101.442703) (xy 320.725553 -101.49611) (xy 320.733673 -101.551286)
			(xy 320.734182 -101.579172) (xy 320.733673 -101.607058) (xy 320.725553 -101.662234) (xy 320.709485 -101.715641)
			(xy 320.685813 -101.766138) (xy 320.65504 -101.812651) (xy 320.617823 -101.854188) (xy 320.597905 -101.870764)
			(xy 325.439022 -101.870764) (xy 325.443093 -101.815142) (xy 325.455219 -101.760705) (xy 325.475142 -101.708614)
			(xy 325.502438 -101.659979) (xy 325.536524 -101.615836) (xy 325.576673 -101.577127) (xy 325.622031 -101.544676)
			(xy 325.671631 -101.519175) (xy 325.724415 -101.501168) (xy 325.779258 -101.491038) (xy 325.834992 -101.489001)
			(xy 325.890429 -101.495101) (xy 325.944386 -101.509207) (xy 325.995715 -101.531019) (xy 326.043321 -101.560073)
			(xy 326.086189 -101.595748) (xy 326.123406 -101.637285) (xy 326.154179 -101.683798) (xy 326.177851 -101.734295)
			(xy 326.193919 -101.787702) (xy 326.202039 -101.842878) (xy 326.202548 -101.870764) (xy 326.202039 -101.89865)
			(xy 326.193919 -101.953826) (xy 326.177851 -102.007233) (xy 326.154179 -102.05773) (xy 326.123406 -102.104243)
			(xy 326.099924 -102.130451) (xy 328.743052 -102.130451) (xy 328.743052 -102.075949) (xy 328.750808 -102.022001)
			(xy 328.766162 -101.969707) (xy 328.788801 -101.920129) (xy 328.818265 -101.874277) (xy 328.853954 -101.833086)
			(xy 328.895142 -101.797392) (xy 328.94099 -101.767922) (xy 328.990565 -101.745277) (xy 329.042858 -101.729917)
			(xy 329.096805 -101.722155) (xy 329.124056 -101.721666) (xy 329.151426 -101.722142) (xy 329.205605 -101.729955)
			(xy 329.258109 -101.745441) (xy 329.307856 -101.768281) (xy 329.353823 -101.798005) (xy 329.374754 -101.815646)
			(xy 329.375008 -101.8159) (xy 329.382088 -101.821496) (xy 329.39901 -101.827737) (xy 329.408028 -101.828092)
			(xy 329.475084 -101.828092) (xy 329.4841 -101.827729) (xy 329.501017 -101.821486) (xy 329.508104 -101.8159)
			(xy 329.508104 -101.815646) (xy 329.508358 -101.815646) (xy 329.529301 -101.79802) (xy 329.57527 -101.768305)
			(xy 329.625015 -101.745466) (xy 329.677513 -101.729972) (xy 329.731687 -101.722141) (xy 329.759056 -101.721666)
			(xy 329.786309 -101.722178) (xy 329.840261 -101.72993) (xy 329.892561 -101.745281) (xy 329.942143 -101.767919)
			(xy 329.987998 -101.797384) (xy 330.029194 -101.833075) (xy 330.06489 -101.874266) (xy 330.09436 -101.920118)
			(xy 330.117004 -101.969698) (xy 330.132361 -102.021996) (xy 330.140119 -102.075947) (xy 330.140119 -102.130453)
			(xy 330.132361 -102.184404) (xy 330.117004 -102.236702) (xy 330.09436 -102.286282) (xy 330.06489 -102.332134)
			(xy 330.029194 -102.373325) (xy 329.987998 -102.409016) (xy 329.942143 -102.438481) (xy 329.892561 -102.461119)
			(xy 329.840261 -102.47647) (xy 329.786309 -102.484222) (xy 329.759056 -102.484682) (xy 329.731687 -102.484187)
			(xy 329.677509 -102.476377) (xy 329.625006 -102.460895) (xy 329.575258 -102.438059) (xy 329.52929 -102.408341)
			(xy 329.508358 -102.390702) (xy 329.508104 -102.390448) (xy 329.501025 -102.384851) (xy 329.484102 -102.378612)
			(xy 329.475084 -102.378256) (xy 329.408028 -102.378256) (xy 329.399011 -102.378614) (xy 329.382093 -102.38486)
			(xy 329.375008 -102.390448) (xy 329.375008 -102.390702) (xy 329.374754 -102.390702) (xy 329.353813 -102.40833)
			(xy 329.307842 -102.438043) (xy 329.258097 -102.460881) (xy 329.205599 -102.476375) (xy 329.151425 -102.484206)
			(xy 329.124056 -102.484682) (xy 329.096805 -102.484245) (xy 329.042858 -102.476483) (xy 328.990565 -102.461123)
			(xy 328.94099 -102.438478) (xy 328.895142 -102.409008) (xy 328.853954 -102.373314) (xy 328.818265 -102.332123)
			(xy 328.788801 -102.286271) (xy 328.766162 -102.236693) (xy 328.750808 -102.184399) (xy 328.743052 -102.130451)
			(xy 326.099924 -102.130451) (xy 326.086189 -102.14578) (xy 326.043321 -102.181455) (xy 325.995715 -102.210509)
			(xy 325.944386 -102.232321) (xy 325.890429 -102.246427) (xy 325.834992 -102.252527) (xy 325.779258 -102.25049)
			(xy 325.724415 -102.24036) (xy 325.671631 -102.222353) (xy 325.622031 -102.196852) (xy 325.576673 -102.164401)
			(xy 325.536524 -102.125692) (xy 325.502438 -102.081549) (xy 325.475142 -102.032914) (xy 325.455219 -101.980823)
			(xy 325.443093 -101.926386) (xy 325.439022 -101.870764) (xy 320.597905 -101.870764) (xy 320.574955 -101.889863)
			(xy 320.527349 -101.918917) (xy 320.47602 -101.940729) (xy 320.422063 -101.954835) (xy 320.366626 -101.960935)
			(xy 320.310892 -101.958898) (xy 320.256049 -101.948768) (xy 320.203265 -101.930761) (xy 320.153665 -101.90526)
			(xy 320.108307 -101.872809) (xy 320.068158 -101.8341) (xy 320.034072 -101.789957) (xy 320.006776 -101.741322)
			(xy 319.986853 -101.689231) (xy 319.974727 -101.634794) (xy 319.970656 -101.579172) (xy 317.788585 -101.579172)
			(xy 316.911647 -103.13924) (xy 321.707 -103.13924) (xy 321.711071 -103.083618) (xy 321.723197 -103.029181)
			(xy 321.74312 -102.97709) (xy 321.770416 -102.928455) (xy 321.804502 -102.884312) (xy 321.844651 -102.845603)
			(xy 321.890009 -102.813152) (xy 321.939609 -102.787651) (xy 321.992393 -102.769644) (xy 322.047236 -102.759514)
			(xy 322.10297 -102.757477) (xy 322.158407 -102.763577) (xy 322.212364 -102.777683) (xy 322.263693 -102.799495)
			(xy 322.311299 -102.828549) (xy 322.354167 -102.864224) (xy 322.391384 -102.905761) (xy 322.422157 -102.952274)
			(xy 322.445829 -103.002771) (xy 322.461897 -103.056178) (xy 322.470017 -103.111354) (xy 322.470526 -103.13924)
			(xy 322.470017 -103.167126) (xy 322.461897 -103.222302) (xy 322.445829 -103.275709) (xy 322.422157 -103.326206)
			(xy 322.391384 -103.372719) (xy 322.354167 -103.414256) (xy 322.311299 -103.449931) (xy 322.263693 -103.478985)
			(xy 322.212364 -103.500797) (xy 322.158407 -103.514903) (xy 322.10297 -103.521003) (xy 322.047236 -103.518966)
			(xy 321.992393 -103.508836) (xy 321.939609 -103.490829) (xy 321.890009 -103.465328) (xy 321.844651 -103.432877)
			(xy 321.804502 -103.394168) (xy 321.770416 -103.350025) (xy 321.74312 -103.30139) (xy 321.723197 -103.249299)
			(xy 321.711071 -103.194862) (xy 321.707 -103.13924) (xy 316.911647 -103.13924) (xy 316.048415 -104.674924)
			(xy 320.759326 -104.674924) (xy 320.763397 -104.619302) (xy 320.775523 -104.564865) (xy 320.795446 -104.512774)
			(xy 320.822742 -104.464139) (xy 320.856828 -104.419996) (xy 320.896977 -104.381287) (xy 320.942335 -104.348836)
			(xy 320.991935 -104.323335) (xy 321.044719 -104.305328) (xy 321.099562 -104.295198) (xy 321.155296 -104.293161)
			(xy 321.210733 -104.299261) (xy 321.26469 -104.313367) (xy 321.316019 -104.335179) (xy 321.363625 -104.364233)
			(xy 321.406493 -104.399908) (xy 321.44371 -104.441445) (xy 321.474483 -104.487958) (xy 321.498155 -104.538455)
			(xy 321.514223 -104.591862) (xy 321.522343 -104.647038) (xy 321.522852 -104.674924) (xy 321.522343 -104.70281)
			(xy 321.514223 -104.757986) (xy 321.498155 -104.811393) (xy 321.474483 -104.86189) (xy 321.44371 -104.908403)
			(xy 321.406493 -104.94994) (xy 321.363625 -104.985615) (xy 321.316019 -105.014669) (xy 321.26469 -105.036481)
			(xy 321.210733 -105.050587) (xy 321.155296 -105.056687) (xy 321.099562 -105.05465) (xy 321.044719 -105.04452)
			(xy 320.991935 -105.026513) (xy 320.942335 -105.001012) (xy 320.896977 -104.968561) (xy 320.856828 -104.929852)
			(xy 320.822742 -104.885709) (xy 320.795446 -104.837074) (xy 320.775523 -104.784983) (xy 320.763397 -104.730546)
			(xy 320.759326 -104.674924) (xy 316.048415 -104.674924) (xy 315.110368 -106.343704) (xy 315.108566 -106.347315)
			(xy 315.10602 -106.354974) (xy 315.105288 -106.358944) (xy 314.999493 -107.210352) (xy 317.942722 -107.210352)
			(xy 317.943237 -107.181613) (xy 317.951865 -107.124786) (xy 317.968918 -107.069896) (xy 317.994011 -107.018185)
			(xy 318.026576 -106.970822) (xy 318.045846 -106.949494) (xy 318.05245 -106.942636) (xy 318.059562 -106.924602)
			(xy 318.059562 -106.835702) (xy 318.05245 -106.817668) (xy 318.045846 -106.81081) (xy 318.026527 -106.789525)
			(xy 317.993961 -106.742156) (xy 317.968871 -106.690438) (xy 317.951823 -106.63554) (xy 317.943204 -106.578707)
			(xy 317.94321 -106.521223) (xy 317.951839 -106.464391) (xy 317.968896 -106.409497) (xy 317.993996 -106.357783)
			(xy 318.026571 -106.31042) (xy 318.045846 -106.289094) (xy 318.05245 -106.282236) (xy 318.059562 -106.264202)
			(xy 318.059562 -106.175302) (xy 318.05245 -106.157268) (xy 318.045846 -106.15041) (xy 318.026554 -106.129101)
			(xy 317.99399 -106.081735) (xy 317.968902 -106.030018) (xy 317.951856 -105.975123) (xy 317.943239 -105.918292)
			(xy 317.942722 -105.889552) (xy 317.943208 -105.862301) (xy 317.950964 -105.808353) (xy 317.966319 -105.756058)
			(xy 317.988961 -105.706481) (xy 318.018427 -105.660631) (xy 318.054118 -105.61944) (xy 318.095309 -105.583749)
			(xy 318.141159 -105.554283) (xy 318.190736 -105.531641) (xy 318.243031 -105.516286) (xy 318.296979 -105.50853)
			(xy 318.351481 -105.50853) (xy 318.405429 -105.516286) (xy 318.457724 -105.531641) (xy 318.507301 -105.554283)
			(xy 318.553151 -105.583749) (xy 318.594342 -105.61944) (xy 318.630033 -105.660631) (xy 318.659499 -105.706481)
			(xy 318.682141 -105.756058) (xy 318.697496 -105.808353) (xy 318.705252 -105.862301) (xy 318.705738 -105.889552)
			(xy 318.705236 -105.918292) (xy 318.696606 -105.975119) (xy 318.679551 -106.03001) (xy 318.654455 -106.081721)
			(xy 318.621886 -106.129083) (xy 318.602614 -106.15041) (xy 318.59601 -106.157268) (xy 318.588898 -106.175302)
			(xy 318.588898 -106.264202) (xy 318.59601 -106.282236) (xy 318.602614 -106.289094) (xy 318.621836 -106.310463)
			(xy 318.654399 -106.357819) (xy 318.679491 -106.409524) (xy 318.696543 -106.464408) (xy 318.705169 -106.521229)
			(xy 318.705174 -106.578701) (xy 318.696558 -106.635523) (xy 318.679517 -106.69041) (xy 318.654434 -106.74212)
			(xy 318.62188 -106.789482) (xy 318.602614 -106.81081) (xy 318.59601 -106.817668) (xy 318.588898 -106.835702)
			(xy 318.588898 -106.924602) (xy 318.59601 -106.942636) (xy 318.602614 -106.949494) (xy 318.621901 -106.970807)
			(xy 318.654467 -107.018172) (xy 318.67389 -107.058206) (xy 321.773804 -107.058206) (xy 321.77433 -107.029467)
			(xy 321.782952 -106.97264) (xy 321.800001 -106.917749) (xy 321.825093 -106.866037) (xy 321.857657 -106.818675)
			(xy 321.876928 -106.797348) (xy 321.883532 -106.79049) (xy 321.890644 -106.772456) (xy 321.890644 -106.683556)
			(xy 321.883532 -106.665522) (xy 321.876928 -106.658664) (xy 321.857663 -106.637332) (xy 321.825097 -106.589971)
			(xy 321.800005 -106.53826) (xy 321.782954 -106.48337) (xy 321.774331 -106.426543) (xy 321.77433 -106.369066)
			(xy 321.782952 -106.312239) (xy 321.800002 -106.257348) (xy 321.825093 -106.205637) (xy 321.857657 -106.158275)
			(xy 321.876928 -106.136948) (xy 321.883532 -106.13009) (xy 321.890644 -106.112056) (xy 321.890644 -106.023156)
			(xy 321.883532 -106.005122) (xy 321.876928 -105.998264) (xy 321.857659 -105.976936) (xy 321.825092 -105.929574)
			(xy 321.8 -105.877863) (xy 321.782949 -105.822972) (xy 321.774325 -105.766145) (xy 321.773804 -105.737406)
			(xy 321.77429 -105.710155) (xy 321.782046 -105.656207) (xy 321.797401 -105.603912) (xy 321.820043 -105.554335)
			(xy 321.849509 -105.508485) (xy 321.8852 -105.467294) (xy 321.926391 -105.431603) (xy 321.972241 -105.402137)
			(xy 322.021818 -105.379495) (xy 322.074113 -105.36414) (xy 322.128061 -105.356384) (xy 322.182563 -105.356384)
			(xy 322.236511 -105.36414) (xy 322.288806 -105.379495) (xy 322.338383 -105.402137) (xy 322.384233 -105.431603)
			(xy 322.425424 -105.467294) (xy 322.461115 -105.508485) (xy 322.490581 -105.554335) (xy 322.513223 -105.603912)
			(xy 322.528578 -105.656207) (xy 322.536334 -105.710155) (xy 322.53682 -105.737406) (xy 322.536295 -105.766145)
			(xy 322.527672 -105.822972) (xy 322.510622 -105.877862) (xy 322.485531 -105.929574) (xy 322.452966 -105.976937)
			(xy 322.433696 -105.998264) (xy 322.427092 -106.005122) (xy 322.41998 -106.023156) (xy 322.41998 -106.112056)
			(xy 322.427092 -106.13009) (xy 322.433696 -106.136948) (xy 322.452972 -106.15827) (xy 322.485535 -106.205634)
			(xy 322.510625 -106.257347) (xy 322.527674 -106.312238) (xy 322.536295 -106.369065) (xy 322.536295 -106.426543)
			(xy 322.527672 -106.483371) (xy 322.510622 -106.538262) (xy 322.485531 -106.589974) (xy 322.452966 -106.637337)
			(xy 322.433696 -106.658664) (xy 322.427092 -106.665522) (xy 322.41998 -106.683556) (xy 322.41998 -106.772456)
			(xy 322.427092 -106.79049) (xy 322.433696 -106.797348) (xy 322.452958 -106.818683) (xy 322.485528 -106.866041)
			(xy 322.510623 -106.917751) (xy 322.527676 -106.972641) (xy 322.536299 -107.029467) (xy 322.53682 -107.058206)
			(xy 322.536334 -107.085457) (xy 322.528578 -107.139405) (xy 322.513223 -107.1917) (xy 322.490581 -107.241277)
			(xy 322.461115 -107.287127) (xy 322.425424 -107.328318) (xy 322.384233 -107.364009) (xy 322.338383 -107.393475)
			(xy 322.288806 -107.416117) (xy 322.236511 -107.431472) (xy 322.182563 -107.439228) (xy 322.128061 -107.439228)
			(xy 322.074113 -107.431472) (xy 322.021818 -107.416117) (xy 321.972241 -107.393475) (xy 321.926391 -107.364009)
			(xy 321.8852 -107.328318) (xy 321.849509 -107.287127) (xy 321.820043 -107.241277) (xy 321.797401 -107.1917)
			(xy 321.782046 -107.139405) (xy 321.77429 -107.085457) (xy 321.773804 -107.058206) (xy 318.67389 -107.058206)
			(xy 318.679557 -107.069887) (xy 318.696604 -107.124781) (xy 318.705221 -107.181612) (xy 318.705738 -107.210352)
			(xy 318.705252 -107.237603) (xy 318.697496 -107.291551) (xy 318.682141 -107.343846) (xy 318.659499 -107.393423)
			(xy 318.630033 -107.439273) (xy 318.594342 -107.480464) (xy 318.553151 -107.516155) (xy 318.507301 -107.545621)
			(xy 318.457724 -107.568263) (xy 318.405429 -107.583618) (xy 318.351481 -107.591374) (xy 318.296979 -107.591374)
			(xy 318.243031 -107.583618) (xy 318.190736 -107.568263) (xy 318.141159 -107.545621) (xy 318.095309 -107.516155)
			(xy 318.054118 -107.480464) (xy 318.018427 -107.439273) (xy 317.988961 -107.393423) (xy 317.966319 -107.343846)
			(xy 317.950964 -107.291551) (xy 317.943208 -107.237603) (xy 317.942722 -107.210352) (xy 314.999493 -107.210352)
			(xy 314.854277 -108.379006) (xy 322.662804 -108.379006) (xy 322.66333 -108.350267) (xy 322.671952 -108.29344)
			(xy 322.689001 -108.238549) (xy 322.714093 -108.186837) (xy 322.746657 -108.139475) (xy 322.765928 -108.118148)
			(xy 322.772532 -108.11129) (xy 322.779644 -108.093256) (xy 322.779644 -108.004356) (xy 322.772532 -107.986322)
			(xy 322.765928 -107.979464) (xy 322.746663 -107.958132) (xy 322.714097 -107.910771) (xy 322.689005 -107.85906)
			(xy 322.671954 -107.80417) (xy 322.663331 -107.747343) (xy 322.66333 -107.689866) (xy 322.671952 -107.633039)
			(xy 322.689002 -107.578148) (xy 322.714093 -107.526437) (xy 322.746657 -107.479075) (xy 322.765928 -107.457748)
			(xy 322.772532 -107.45089) (xy 322.779644 -107.432856) (xy 322.779644 -107.343956) (xy 322.772532 -107.325922)
			(xy 322.765928 -107.319064) (xy 322.746663 -107.297732) (xy 322.714097 -107.250371) (xy 322.689005 -107.19866)
			(xy 322.671954 -107.14377) (xy 322.663331 -107.086943) (xy 322.66333 -107.029466) (xy 322.671952 -106.972639)
			(xy 322.689002 -106.917748) (xy 322.714093 -106.866037) (xy 322.746657 -106.818675) (xy 322.765928 -106.797348)
			(xy 322.772532 -106.79049) (xy 322.779644 -106.772456) (xy 322.779644 -106.683556) (xy 322.772532 -106.665522)
			(xy 322.765928 -106.658664) (xy 322.746663 -106.637332) (xy 322.714097 -106.589971) (xy 322.689005 -106.53826)
			(xy 322.671954 -106.48337) (xy 322.663331 -106.426543) (xy 322.66333 -106.369066) (xy 322.671952 -106.312239)
			(xy 322.689002 -106.257348) (xy 322.714093 -106.205637) (xy 322.746657 -106.158275) (xy 322.765928 -106.136948)
			(xy 322.772532 -106.13009) (xy 322.779644 -106.112056) (xy 322.779644 -106.023156) (xy 322.772532 -106.005122)
			(xy 322.765928 -105.998264) (xy 322.746663 -105.976932) (xy 322.714097 -105.929571) (xy 322.689005 -105.87786)
			(xy 322.671954 -105.82297) (xy 322.663331 -105.766143) (xy 322.66333 -105.708666) (xy 322.671952 -105.651839)
			(xy 322.689002 -105.596948) (xy 322.714093 -105.545237) (xy 322.746657 -105.497875) (xy 322.765928 -105.476548)
			(xy 322.772532 -105.46969) (xy 322.779644 -105.451656) (xy 322.779644 -105.362756) (xy 322.772532 -105.344722)
			(xy 322.765928 -105.337864) (xy 322.746663 -105.316532) (xy 322.714097 -105.269171) (xy 322.689005 -105.21746)
			(xy 322.671954 -105.16257) (xy 322.663331 -105.105743) (xy 322.66333 -105.048266) (xy 322.671952 -104.991439)
			(xy 322.689002 -104.936548) (xy 322.714093 -104.884837) (xy 322.746657 -104.837475) (xy 322.765928 -104.816148)
			(xy 322.772532 -104.80929) (xy 322.779644 -104.791256) (xy 322.779644 -104.702356) (xy 322.772532 -104.684322)
			(xy 322.765928 -104.677464) (xy 322.746663 -104.656132) (xy 322.714097 -104.608771) (xy 322.689005 -104.55706)
			(xy 322.671954 -104.50217) (xy 322.663331 -104.445343) (xy 322.66333 -104.387866) (xy 322.671952 -104.331039)
			(xy 322.689002 -104.276148) (xy 322.714093 -104.224437) (xy 322.746657 -104.177075) (xy 322.765928 -104.155748)
			(xy 322.772532 -104.14889) (xy 322.779644 -104.130856) (xy 322.779644 -104.041956) (xy 322.772532 -104.023922)
			(xy 322.765928 -104.017064) (xy 322.746663 -103.995732) (xy 322.714097 -103.948371) (xy 322.689005 -103.89666)
			(xy 322.671954 -103.84177) (xy 322.663331 -103.784943) (xy 322.66333 -103.727466) (xy 322.671952 -103.670639)
			(xy 322.689002 -103.615748) (xy 322.714093 -103.564037) (xy 322.746657 -103.516675) (xy 322.765928 -103.495348)
			(xy 322.772532 -103.48849) (xy 322.779644 -103.470456) (xy 322.779644 -103.381556) (xy 322.772532 -103.363522)
			(xy 322.765928 -103.356664) (xy 322.746659 -103.335336) (xy 322.714092 -103.287974) (xy 322.689 -103.236263)
			(xy 322.671949 -103.181372) (xy 322.663325 -103.124545) (xy 322.662804 -103.095806) (xy 322.663245 -103.068599)
			(xy 322.67097 -103.014735) (xy 322.686276 -102.962517) (xy 322.708854 -102.913007) (xy 322.738244 -102.867212)
			(xy 322.773848 -102.826063) (xy 322.814943 -102.790395) (xy 322.837556 -102.775258) (xy 322.845938 -102.769924)
			(xy 322.857114 -102.753668) (xy 322.875402 -102.674674) (xy 322.87721 -102.665045) (xy 322.874213 -102.645704)
			(xy 322.86956 -102.637082) (xy 322.869306 -102.637082) (xy 322.869306 -102.636574) (xy 322.856101 -102.614063)
			(xy 322.835245 -102.566221) (xy 322.821095 -102.515987) (xy 322.813911 -102.464294) (xy 322.813426 -102.4382)
			(xy 322.813912 -102.410949) (xy 322.821668 -102.357001) (xy 322.837023 -102.304706) (xy 322.859665 -102.255129)
			(xy 322.889131 -102.209279) (xy 322.924822 -102.168088) (xy 322.966013 -102.132397) (xy 323.011863 -102.102931)
			(xy 323.06144 -102.080289) (xy 323.113735 -102.064934) (xy 323.167683 -102.057178) (xy 323.222185 -102.057178)
			(xy 323.276133 -102.064934) (xy 323.328428 -102.080289) (xy 323.378005 -102.102931) (xy 323.423855 -102.132397)
			(xy 323.465046 -102.168088) (xy 323.500737 -102.209279) (xy 323.530203 -102.255129) (xy 323.552845 -102.304706)
			(xy 323.5682 -102.357001) (xy 323.575956 -102.410949) (xy 323.576442 -102.4382) (xy 323.575984 -102.465407)
			(xy 323.56826 -102.519269) (xy 323.552955 -102.571485) (xy 323.530379 -102.620994) (xy 323.500993 -102.666789)
			(xy 323.465392 -102.70794) (xy 323.424301 -102.743609) (xy 323.40169 -102.758748) (xy 323.393308 -102.764082)
			(xy 323.382132 -102.780338) (xy 323.363844 -102.859332) (xy 323.36204 -102.868962) (xy 323.365036 -102.888302)
			(xy 323.369686 -102.896924) (xy 323.36994 -102.896924) (xy 323.36994 -102.897432) (xy 323.383152 -102.919939)
			(xy 323.404005 -102.967783) (xy 323.418153 -103.018018) (xy 323.425335 -103.069712) (xy 323.42582 -103.095806)
			(xy 323.425295 -103.124545) (xy 323.416672 -103.181372) (xy 323.399622 -103.236262) (xy 323.374531 -103.287974)
			(xy 323.341966 -103.335337) (xy 323.322696 -103.356664) (xy 323.316092 -103.363522) (xy 323.30898 -103.381556)
			(xy 323.30898 -103.470456) (xy 323.316092 -103.48849) (xy 323.322696 -103.495348) (xy 323.341972 -103.51667)
			(xy 323.374535 -103.564034) (xy 323.399625 -103.615747) (xy 323.416674 -103.670638) (xy 323.425295 -103.727465)
			(xy 323.425295 -103.784943) (xy 323.416672 -103.841771) (xy 323.399622 -103.896662) (xy 323.374531 -103.948374)
			(xy 323.341966 -103.995737) (xy 323.322696 -104.017064) (xy 323.31707 -104.022906) (xy 328.065892 -104.022906)
			(xy 328.066366 -103.996592) (xy 328.0736 -103.944464) (xy 328.087918 -103.893822) (xy 328.109049 -103.845623)
			(xy 328.136594 -103.800779) (xy 328.170031 -103.760139) (xy 328.189082 -103.741982) (xy 328.196491 -103.734467)
			(xy 328.205012 -103.715182) (xy 328.205592 -103.704644) (xy 328.205592 -103.629968) (xy 328.205042 -103.619421)
			(xy 328.196522 -103.600125) (xy 328.189082 -103.59263) (xy 328.170045 -103.574456) (xy 328.136586 -103.53383)
			(xy 328.109025 -103.488994) (xy 328.087884 -103.440796) (xy 328.073563 -103.390152) (xy 328.066333 -103.338021)
			(xy 328.065892 -103.311706) (xy 328.066361 -103.284453) (xy 328.074117 -103.230503) (xy 328.089472 -103.178205)
			(xy 328.112114 -103.128625) (xy 328.141582 -103.082772) (xy 328.177275 -103.041579) (xy 328.218467 -103.005885)
			(xy 328.264319 -102.976417) (xy 328.313899 -102.953774) (xy 328.366197 -102.938418) (xy 328.420147 -102.930661)
			(xy 328.4474 -102.930198) (xy 328.475065 -102.930711) (xy 328.529814 -102.938711) (xy 328.582836 -102.954527)
			(xy 328.633019 -102.97783) (xy 328.679315 -103.008131) (xy 328.720753 -103.044796) (xy 328.756466 -103.087057)
			(xy 328.771504 -103.110284) (xy 328.77813 -103.11997) (xy 328.797999 -103.132408) (xy 328.809604 -103.13416)
			(xy 328.889614 -103.142034) (xy 328.901253 -103.142672) (xy 328.923091 -103.134588) (xy 328.931524 -103.12654)
			(xy 328.931778 -103.126286) (xy 328.949884 -103.107731) (xy 328.990211 -103.07515) (xy 329.03458 -103.048334)
			(xy 329.082173 -103.027777) (xy 329.132113 -103.013858) (xy 329.183478 -103.006834) (xy 329.2094 -103.006398)
			(xy 329.236653 -103.006855) (xy 329.290605 -103.014612) (xy 329.342903 -103.029969) (xy 329.392483 -103.052612)
			(xy 329.438337 -103.08208) (xy 329.47953 -103.117775) (xy 329.515223 -103.158968) (xy 329.544691 -103.204822)
			(xy 329.567333 -103.254403) (xy 329.582689 -103.306701) (xy 329.590445 -103.360653) (xy 329.590908 -103.387906)
			(xy 329.590443 -103.415276) (xy 329.582625 -103.469455) (xy 329.567135 -103.521958) (xy 329.544293 -103.571705)
			(xy 329.514569 -103.617672) (xy 329.496928 -103.638604) (xy 329.496674 -103.638858) (xy 329.491096 -103.64595)
			(xy 329.484845 -103.662863) (xy 329.484482 -103.671878) (xy 329.484482 -103.685654) (xy 340.692671 -103.685654)
			(xy 340.692671 -103.631146) (xy 340.700429 -103.577194) (xy 340.715787 -103.524895) (xy 340.738431 -103.475315)
			(xy 340.767901 -103.429462) (xy 340.803598 -103.38827) (xy 340.844794 -103.352577) (xy 340.89065 -103.323112)
			(xy 340.940233 -103.300473) (xy 340.992533 -103.285121) (xy 341.046486 -103.277369) (xy 341.07374 -103.276908)
			(xy 341.100055 -103.277346) (xy 341.152185 -103.284587) (xy 341.202828 -103.298911) (xy 341.251027 -103.320049)
			(xy 341.29587 -103.347601) (xy 341.336508 -103.381044) (xy 341.354664 -103.400098) (xy 341.362197 -103.407485)
			(xy 341.381469 -103.416018) (xy 341.392002 -103.416608) (xy 341.466678 -103.416608) (xy 341.477227 -103.416078)
			(xy 341.496523 -103.407543) (xy 341.504016 -103.400098) (xy 341.523836 -103.37931) (xy 341.568608 -103.343335)
			(xy 341.618266 -103.314475) (xy 341.671688 -103.293382) (xy 341.727667 -103.280533) (xy 341.78494 -103.276218)
			(xy 341.842213 -103.280533) (xy 341.898192 -103.293382) (xy 341.951614 -103.314475) (xy 342.001272 -103.343335)
			(xy 342.046044 -103.37931) (xy 342.065864 -103.400098) (xy 342.073397 -103.407485) (xy 342.092669 -103.416018)
			(xy 342.103202 -103.416608) (xy 342.177878 -103.416608) (xy 342.188427 -103.416078) (xy 342.207723 -103.407543)
			(xy 342.215216 -103.400098) (xy 342.23337 -103.381041) (xy 342.274 -103.347584) (xy 342.318841 -103.320026)
			(xy 342.367042 -103.298887) (xy 342.41769 -103.28457) (xy 342.469824 -103.277346) (xy 342.49614 -103.276908)
			(xy 342.523391 -103.277365) (xy 342.577336 -103.285126) (xy 342.629628 -103.300485) (xy 342.679203 -103.32313)
			(xy 342.72505 -103.352598) (xy 342.766237 -103.388291) (xy 342.801926 -103.429482) (xy 342.83139 -103.475333)
			(xy 342.854029 -103.524909) (xy 342.856834 -103.534464) (xy 360.553252 -103.534464) (xy 360.557323 -103.478842)
			(xy 360.569449 -103.424405) (xy 360.589372 -103.372314) (xy 360.616668 -103.323679) (xy 360.650754 -103.279536)
			(xy 360.690903 -103.240827) (xy 360.736261 -103.208376) (xy 360.785861 -103.182875) (xy 360.838645 -103.164868)
			(xy 360.893488 -103.154738) (xy 360.949222 -103.152701) (xy 361.004659 -103.158801) (xy 361.058616 -103.172907)
			(xy 361.0816 -103.182674) (xy 370.004338 -103.182674) (xy 370.008409 -103.127052) (xy 370.020535 -103.072615)
			(xy 370.040458 -103.020524) (xy 370.067754 -102.971889) (xy 370.10184 -102.927746) (xy 370.141989 -102.889037)
			(xy 370.187347 -102.856586) (xy 370.236947 -102.831085) (xy 370.289731 -102.813078) (xy 370.344574 -102.802948)
			(xy 370.400308 -102.800911) (xy 370.455745 -102.807011) (xy 370.509702 -102.821117) (xy 370.561031 -102.842929)
			(xy 370.608637 -102.871983) (xy 370.651505 -102.907658) (xy 370.688722 -102.949195) (xy 370.719495 -102.995708)
			(xy 370.743167 -103.046205) (xy 370.759235 -103.099612) (xy 370.767355 -103.154788) (xy 370.767864 -103.182674)
			(xy 370.767355 -103.21056) (xy 370.759235 -103.265736) (xy 370.743167 -103.319143) (xy 370.719495 -103.36964)
			(xy 370.688722 -103.416153) (xy 370.651505 -103.45769) (xy 370.608637 -103.493365) (xy 370.561031 -103.522419)
			(xy 370.509702 -103.544231) (xy 370.455745 -103.558337) (xy 370.400308 -103.564437) (xy 370.344574 -103.5624)
			(xy 370.289731 -103.55227) (xy 370.236947 -103.534263) (xy 370.187347 -103.508762) (xy 370.141989 -103.476311)
			(xy 370.10184 -103.437602) (xy 370.067754 -103.393459) (xy 370.040458 -103.344824) (xy 370.020535 -103.292733)
			(xy 370.008409 -103.238296) (xy 370.004338 -103.182674) (xy 361.0816 -103.182674) (xy 361.109945 -103.194719)
			(xy 361.157551 -103.223773) (xy 361.200419 -103.259448) (xy 361.237636 -103.300985) (xy 361.268409 -103.347498)
			(xy 361.292081 -103.397995) (xy 361.308149 -103.451402) (xy 361.316269 -103.506578) (xy 361.316778 -103.534464)
			(xy 361.316269 -103.56235) (xy 361.308149 -103.617526) (xy 361.292081 -103.670933) (xy 361.268409 -103.72143)
			(xy 361.237636 -103.767943) (xy 361.200419 -103.80948) (xy 361.157551 -103.845155) (xy 361.148475 -103.850694)
			(xy 372.568468 -103.850694) (xy 372.572539 -103.795072) (xy 372.584665 -103.740635) (xy 372.604588 -103.688544)
			(xy 372.631884 -103.639909) (xy 372.66597 -103.595766) (xy 372.706119 -103.557057) (xy 372.751477 -103.524606)
			(xy 372.801077 -103.499105) (xy 372.853861 -103.481098) (xy 372.908704 -103.470968) (xy 372.964438 -103.468931)
			(xy 373.019875 -103.475031) (xy 373.073832 -103.489137) (xy 373.125161 -103.510949) (xy 373.172767 -103.540003)
			(xy 373.215635 -103.575678) (xy 373.252852 -103.617215) (xy 373.283625 -103.663728) (xy 373.307297 -103.714225)
			(xy 373.323365 -103.767632) (xy 373.331485 -103.822808) (xy 373.331994 -103.850694) (xy 373.331485 -103.87858)
			(xy 373.323365 -103.933756) (xy 373.307297 -103.987163) (xy 373.283625 -104.03766) (xy 373.252852 -104.084173)
			(xy 373.215635 -104.12571) (xy 373.172767 -104.161385) (xy 373.125161 -104.190439) (xy 373.073832 -104.212251)
			(xy 373.019875 -104.226357) (xy 372.964438 -104.232457) (xy 372.908704 -104.23042) (xy 372.853861 -104.22029)
			(xy 372.801077 -104.202283) (xy 372.751477 -104.176782) (xy 372.706119 -104.144331) (xy 372.66597 -104.105622)
			(xy 372.631884 -104.061479) (xy 372.604588 -104.012844) (xy 372.584665 -103.960753) (xy 372.572539 -103.906316)
			(xy 372.568468 -103.850694) (xy 361.148475 -103.850694) (xy 361.109945 -103.874209) (xy 361.058616 -103.896021)
			(xy 361.004659 -103.910127) (xy 360.949222 -103.916227) (xy 360.893488 -103.91419) (xy 360.838645 -103.90406)
			(xy 360.785861 -103.886053) (xy 360.736261 -103.860552) (xy 360.690903 -103.828101) (xy 360.650754 -103.789392)
			(xy 360.616668 -103.745249) (xy 360.589372 -103.696614) (xy 360.569449 -103.644523) (xy 360.557323 -103.590086)
			(xy 360.553252 -103.534464) (xy 342.856834 -103.534464) (xy 342.869383 -103.577203) (xy 342.877138 -103.631149)
			(xy 342.877138 -103.685651) (xy 342.869383 -103.739597) (xy 342.854029 -103.791891) (xy 342.83139 -103.841467)
			(xy 342.801926 -103.887318) (xy 342.766237 -103.928509) (xy 342.72505 -103.964202) (xy 342.679203 -103.99367)
			(xy 342.629628 -104.016315) (xy 342.577336 -104.031674) (xy 342.523391 -104.039435) (xy 342.49614 -104.039924)
			(xy 342.469825 -104.039489) (xy 342.417695 -104.032246) (xy 342.367052 -104.01792) (xy 342.318854 -103.996782)
			(xy 342.274011 -103.969231) (xy 342.233372 -103.935787) (xy 342.215216 -103.916734) (xy 342.207686 -103.909342)
			(xy 342.188413 -103.900811) (xy 342.177878 -103.900224) (xy 342.103202 -103.900224) (xy 342.09265 -103.900734)
			(xy 342.073354 -103.909282) (xy 342.065864 -103.916734) (xy 342.046044 -103.937522) (xy 342.001272 -103.973497)
			(xy 341.951614 -104.002357) (xy 341.898192 -104.02345) (xy 341.842213 -104.036299) (xy 341.78494 -104.040614)
			(xy 341.727667 -104.036299) (xy 341.671688 -104.02345) (xy 341.618266 -104.002357) (xy 341.568608 -103.973497)
			(xy 341.523836 -103.937522) (xy 341.504016 -103.916734) (xy 341.496486 -103.909342) (xy 341.477213 -103.900811)
			(xy 341.466678 -103.900224) (xy 341.392002 -103.900224) (xy 341.38145 -103.900734) (xy 341.362154 -103.909282)
			(xy 341.354664 -103.916734) (xy 341.336526 -103.935806) (xy 341.295891 -103.969261) (xy 341.251047 -103.996817)
			(xy 341.202843 -104.017952) (xy 341.152193 -104.032266) (xy 341.100057 -104.039487) (xy 341.07374 -104.039924)
			(xy 341.046486 -104.039431) (xy 340.992533 -104.031679) (xy 340.940233 -104.016327) (xy 340.89065 -103.993688)
			(xy 340.844794 -103.964223) (xy 340.803598 -103.92853) (xy 340.767901 -103.887338) (xy 340.738431 -103.841485)
			(xy 340.715787 -103.791905) (xy 340.700429 -103.739606) (xy 340.692671 -103.685654) (xy 329.484482 -103.685654)
			(xy 329.484482 -103.738934) (xy 329.484826 -103.747952) (xy 329.491083 -103.764869) (xy 329.496674 -103.771954)
			(xy 329.496928 -103.771954) (xy 329.496928 -103.772208) (xy 329.514589 -103.793123) (xy 329.544296 -103.839101)
			(xy 329.567128 -103.888853) (xy 329.582614 -103.941357) (xy 329.590437 -103.995536) (xy 329.590908 -104.022906)
			(xy 329.590428 -104.050157) (xy 329.58267 -104.104105) (xy 329.579588 -104.1146) (xy 353.090224 -104.1146)
			(xy 353.094295 -104.058978) (xy 353.106421 -104.004541) (xy 353.126344 -103.95245) (xy 353.15364 -103.903815)
			(xy 353.187726 -103.859672) (xy 353.227875 -103.820963) (xy 353.273233 -103.788512) (xy 353.322833 -103.763011)
			(xy 353.375617 -103.745004) (xy 353.43046 -103.734874) (xy 353.486194 -103.732837) (xy 353.541631 -103.738937)
			(xy 353.595588 -103.753043) (xy 353.646917 -103.774855) (xy 353.694523 -103.803909) (xy 353.737391 -103.839584)
			(xy 353.774608 -103.881121) (xy 353.805381 -103.927634) (xy 353.829053 -103.978131) (xy 353.845121 -104.031538)
			(xy 353.853241 -104.086714) (xy 353.85375 -104.1146) (xy 353.853241 -104.142486) (xy 353.845121 -104.197662)
			(xy 353.829053 -104.251069) (xy 353.805381 -104.301566) (xy 353.774608 -104.348079) (xy 353.737391 -104.389616)
			(xy 353.722051 -104.402382) (xy 357.210358 -104.402382) (xy 357.214429 -104.34676) (xy 357.226555 -104.292323)
			(xy 357.246478 -104.240232) (xy 357.273774 -104.191597) (xy 357.30786 -104.147454) (xy 357.348009 -104.108745)
			(xy 357.393367 -104.076294) (xy 357.442967 -104.050793) (xy 357.495751 -104.032786) (xy 357.550594 -104.022656)
			(xy 357.606328 -104.020619) (xy 357.661765 -104.026719) (xy 357.715722 -104.040825) (xy 357.767051 -104.062637)
			(xy 357.814657 -104.091691) (xy 357.857525 -104.127366) (xy 357.894742 -104.168903) (xy 357.925515 -104.215416)
			(xy 357.949187 -104.265913) (xy 357.965255 -104.31932) (xy 357.973375 -104.374496) (xy 357.973884 -104.402382)
			(xy 357.973375 -104.430268) (xy 357.965255 -104.485444) (xy 357.949187 -104.538851) (xy 357.925515 -104.589348)
			(xy 357.894742 -104.635861) (xy 357.857525 -104.677398) (xy 357.814657 -104.713073) (xy 357.767051 -104.742127)
			(xy 357.715722 -104.763939) (xy 357.690901 -104.770428) (xy 374.327926 -104.770428) (xy 374.331997 -104.714806)
			(xy 374.344123 -104.660369) (xy 374.364046 -104.608278) (xy 374.391342 -104.559643) (xy 374.425428 -104.5155)
			(xy 374.465577 -104.476791) (xy 374.510935 -104.44434) (xy 374.560535 -104.418839) (xy 374.613319 -104.400832)
			(xy 374.668162 -104.390702) (xy 374.723896 -104.388665) (xy 374.779333 -104.394765) (xy 374.83329 -104.408871)
			(xy 374.884619 -104.430683) (xy 374.932225 -104.459737) (xy 374.975093 -104.495412) (xy 375.01231 -104.536949)
			(xy 375.043083 -104.583462) (xy 375.066755 -104.633959) (xy 375.082823 -104.687366) (xy 375.090943 -104.742542)
			(xy 375.091452 -104.770428) (xy 375.090943 -104.798314) (xy 375.082823 -104.85349) (xy 375.066755 -104.906897)
			(xy 375.043083 -104.957394) (xy 375.01231 -105.003907) (xy 374.975093 -105.045444) (xy 374.932225 -105.081119)
			(xy 374.884619 -105.110173) (xy 374.83329 -105.131985) (xy 374.779333 -105.146091) (xy 374.723896 -105.152191)
			(xy 374.668162 -105.150154) (xy 374.613319 -105.140024) (xy 374.560535 -105.122017) (xy 374.510935 -105.096516)
			(xy 374.465577 -105.064065) (xy 374.425428 -105.025356) (xy 374.391342 -104.981213) (xy 374.364046 -104.932578)
			(xy 374.344123 -104.880487) (xy 374.331997 -104.82605) (xy 374.327926 -104.770428) (xy 357.690901 -104.770428)
			(xy 357.661765 -104.778045) (xy 357.606328 -104.784145) (xy 357.550594 -104.782108) (xy 357.495751 -104.771978)
			(xy 357.442967 -104.753971) (xy 357.393367 -104.72847) (xy 357.348009 -104.696019) (xy 357.30786 -104.65731)
			(xy 357.273774 -104.613167) (xy 357.246478 -104.564532) (xy 357.226555 -104.512441) (xy 357.214429 -104.458004)
			(xy 357.210358 -104.402382) (xy 353.722051 -104.402382) (xy 353.694523 -104.425291) (xy 353.646917 -104.454345)
			(xy 353.595588 -104.476157) (xy 353.541631 -104.490263) (xy 353.486194 -104.496363) (xy 353.43046 -104.494326)
			(xy 353.375617 -104.484196) (xy 353.322833 -104.466189) (xy 353.273233 -104.440688) (xy 353.227875 -104.408237)
			(xy 353.187726 -104.369528) (xy 353.15364 -104.325385) (xy 353.126344 -104.27675) (xy 353.106421 -104.224659)
			(xy 353.094295 -104.170222) (xy 353.090224 -104.1146) (xy 329.579588 -104.1146) (xy 329.567315 -104.1564)
			(xy 329.544673 -104.205977) (xy 329.515206 -104.251828) (xy 329.479514 -104.293018) (xy 329.438323 -104.328709)
			(xy 329.392472 -104.358176) (xy 329.342895 -104.380817) (xy 329.290599 -104.396172) (xy 329.236651 -104.403928)
			(xy 329.2094 -104.404414) (xy 329.180481 -104.403928) (xy 329.123307 -104.395197) (xy 329.068106 -104.377935)
			(xy 329.016144 -104.352537) (xy 328.968611 -104.319586) (xy 328.926598 -104.279837) (xy 328.90841 -104.257348)
			(xy 328.900798 -104.248546) (xy 328.879901 -104.238362) (xy 328.868278 -104.23779) (xy 328.788522 -104.23779)
			(xy 328.776894 -104.23836) (xy 328.755985 -104.248527) (xy 328.74839 -104.257348) (xy 328.730217 -104.279846)
			(xy 328.688192 -104.319578) (xy 328.640653 -104.352514) (xy 328.588688 -104.3779) (xy 328.533488 -104.395153)
			(xy 328.476317 -104.40388) (xy 328.4474 -104.404414) (xy 328.420149 -104.403922) (xy 328.366202 -104.396166)
			(xy 328.313908 -104.380811) (xy 328.264331 -104.35817) (xy 328.218481 -104.328705) (xy 328.177291 -104.293014)
			(xy 328.141599 -104.251824) (xy 328.112133 -104.205975) (xy 328.089491 -104.156398) (xy 328.074135 -104.104104)
			(xy 328.066378 -104.050157) (xy 328.065892 -104.022906) (xy 323.31707 -104.022906) (xy 323.316092 -104.023922)
			(xy 323.30898 -104.041956) (xy 323.30898 -104.130856) (xy 323.316092 -104.14889) (xy 323.322696 -104.155748)
			(xy 323.341972 -104.17707) (xy 323.374535 -104.224434) (xy 323.399625 -104.276147) (xy 323.416674 -104.331038)
			(xy 323.425295 -104.387865) (xy 323.425295 -104.445343) (xy 323.416672 -104.502171) (xy 323.399622 -104.557062)
			(xy 323.374531 -104.608774) (xy 323.341966 -104.656137) (xy 323.322696 -104.677464) (xy 323.316092 -104.684322)
			(xy 323.30898 -104.702356) (xy 323.30898 -104.791256) (xy 323.316092 -104.80929) (xy 323.322696 -104.816148)
			(xy 323.341972 -104.83747) (xy 323.374535 -104.884834) (xy 323.399625 -104.936547) (xy 323.416674 -104.991438)
			(xy 323.425295 -105.048265) (xy 323.425295 -105.08445) (xy 327.943972 -105.08445) (xy 327.943972 -105.02995)
			(xy 327.951728 -104.976003) (xy 327.967082 -104.92371) (xy 327.989721 -104.874134) (xy 328.019185 -104.828284)
			(xy 328.054874 -104.787094) (xy 328.096062 -104.751402) (xy 328.141909 -104.721934) (xy 328.191484 -104.699291)
			(xy 328.243776 -104.683934) (xy 328.297722 -104.676174) (xy 328.324972 -104.675686) (xy 328.352341 -104.676172)
			(xy 328.40652 -104.683985) (xy 328.459022 -104.69947) (xy 328.50877 -104.722307) (xy 328.554737 -104.752027)
			(xy 328.57567 -104.769666) (xy 328.575924 -104.76992) (xy 328.582998 -104.775525) (xy 328.599924 -104.78176)
			(xy 328.608944 -104.782112) (xy 328.676 -104.782112) (xy 328.685017 -104.781752) (xy 328.701933 -104.775506)
			(xy 328.70902 -104.76992) (xy 328.70902 -104.769666) (xy 328.709274 -104.769666) (xy 328.730207 -104.752025)
			(xy 328.776175 -104.722301) (xy 328.825921 -104.699455) (xy 328.878423 -104.683959) (xy 328.932601 -104.67613)
			(xy 328.987343 -104.67613) (xy 329.041521 -104.683959) (xy 329.094023 -104.699455) (xy 329.143769 -104.722301)
			(xy 329.189737 -104.752025) (xy 329.21067 -104.769666) (xy 329.210924 -104.76992) (xy 329.217998 -104.775525)
			(xy 329.234924 -104.78176) (xy 329.243944 -104.782112) (xy 329.311 -104.782112) (xy 329.320017 -104.781752)
			(xy 329.336933 -104.775506) (xy 329.34402 -104.76992) (xy 329.34402 -104.769666) (xy 329.344274 -104.769666)
			(xy 329.365207 -104.752025) (xy 329.411175 -104.722301) (xy 329.460921 -104.699455) (xy 329.513423 -104.683959)
			(xy 329.567601 -104.67613) (xy 329.622343 -104.67613) (xy 329.676521 -104.683959) (xy 329.729023 -104.699455)
			(xy 329.778769 -104.722301) (xy 329.824737 -104.752025) (xy 329.84567 -104.769666) (xy 329.845924 -104.76992)
			(xy 329.852998 -104.775525) (xy 329.869924 -104.78176) (xy 329.878944 -104.782112) (xy 329.946 -104.782112)
			(xy 329.955017 -104.781752) (xy 329.971933 -104.775506) (xy 329.97902 -104.76992) (xy 329.97902 -104.769666)
			(xy 329.979274 -104.769666) (xy 330.000201 -104.75202) (xy 330.046176 -104.722311) (xy 330.095924 -104.699477)
			(xy 330.148426 -104.683987) (xy 330.202603 -104.67616) (xy 330.229972 -104.675686) (xy 330.257226 -104.676159)
			(xy 330.311179 -104.683913) (xy 330.363479 -104.699266) (xy 330.413062 -104.721907) (xy 330.458918 -104.751374)
			(xy 330.500113 -104.787067) (xy 330.535809 -104.82826) (xy 330.56528 -104.874113) (xy 330.587924 -104.923695)
			(xy 330.603281 -104.975994) (xy 330.611039 -105.029946) (xy 330.611039 -105.084454) (xy 330.603281 -105.138406)
			(xy 330.587924 -105.190705) (xy 330.56528 -105.240287) (xy 330.535809 -105.28614) (xy 330.500113 -105.327333)
			(xy 330.458918 -105.363026) (xy 330.413062 -105.392493) (xy 330.363479 -105.415134) (xy 330.311179 -105.430487)
			(xy 330.257226 -105.438241) (xy 330.229972 -105.438702) (xy 330.202601 -105.438252) (xy 330.148421 -105.43043)
			(xy 330.095918 -105.414937) (xy 330.046172 -105.392092) (xy 330.000205 -105.362365) (xy 329.979274 -105.344722)
			(xy 329.97902 -105.344468) (xy 329.971935 -105.33888) (xy 329.955017 -105.332635) (xy 329.946 -105.332276)
			(xy 329.878944 -105.332276) (xy 329.86993 -105.332659) (xy 329.853013 -105.338889) (xy 329.845924 -105.344468)
			(xy 329.84567 -105.344722) (xy 329.824737 -105.362363) (xy 329.778769 -105.392087) (xy 329.729023 -105.414933)
			(xy 329.676521 -105.430429) (xy 329.622343 -105.438258) (xy 329.567601 -105.438258) (xy 329.513423 -105.430429)
			(xy 329.460921 -105.414933) (xy 329.411175 -105.392087) (xy 329.365207 -105.362363) (xy 329.344274 -105.344722)
			(xy 329.34402 -105.344468) (xy 329.336935 -105.33888) (xy 329.320017 -105.332635) (xy 329.311 -105.332276)
			(xy 329.243944 -105.332276) (xy 329.23493 -105.332659) (xy 329.218013 -105.338889) (xy 329.210924 -105.344468)
			(xy 329.210924 -105.344722) (xy 329.21067 -105.344722) (xy 329.189737 -105.362363) (xy 329.143769 -105.392087)
			(xy 329.094023 -105.414933) (xy 329.041521 -105.430429) (xy 328.987343 -105.438258) (xy 328.932601 -105.438258)
			(xy 328.878423 -105.430429) (xy 328.825921 -105.414933) (xy 328.776175 -105.392087) (xy 328.730207 -105.362363)
			(xy 328.709274 -105.344722) (xy 328.70902 -105.344468) (xy 328.701935 -105.33888) (xy 328.685017 -105.332635)
			(xy 328.676 -105.332276) (xy 328.608944 -105.332276) (xy 328.59993 -105.332659) (xy 328.583013 -105.338889)
			(xy 328.575924 -105.344468) (xy 328.575924 -105.344722) (xy 328.57567 -105.344722) (xy 328.554725 -105.362345)
			(xy 328.508756 -105.392059) (xy 328.459011 -105.414897) (xy 328.406514 -105.430392) (xy 328.35234 -105.438225)
			(xy 328.324972 -105.438702) (xy 328.297722 -105.438226) (xy 328.243776 -105.430466) (xy 328.191484 -105.415109)
			(xy 328.141909 -105.392466) (xy 328.096062 -105.362998) (xy 328.054874 -105.327306) (xy 328.019185 -105.286116)
			(xy 327.989721 -105.240266) (xy 327.967082 -105.19069) (xy 327.951728 -105.138397) (xy 327.943972 -105.08445)
			(xy 323.425295 -105.08445) (xy 323.425295 -105.105743) (xy 323.416672 -105.162571) (xy 323.399622 -105.217462)
			(xy 323.374531 -105.269174) (xy 323.341966 -105.316537) (xy 323.322696 -105.337864) (xy 323.316092 -105.344722)
			(xy 323.30898 -105.362756) (xy 323.30898 -105.451656) (xy 323.316092 -105.46969) (xy 323.322696 -105.476548)
			(xy 323.341972 -105.49787) (xy 323.374535 -105.545234) (xy 323.399625 -105.596947) (xy 323.416674 -105.651838)
			(xy 323.425295 -105.708665) (xy 323.425295 -105.766143) (xy 323.416672 -105.822971) (xy 323.399622 -105.877862)
			(xy 323.374531 -105.929574) (xy 323.341966 -105.976937) (xy 323.322696 -105.998264) (xy 323.316092 -106.005122)
			(xy 323.30898 -106.023156) (xy 323.30898 -106.024446) (xy 351.948826 -106.024446) (xy 351.948826 -105.969954)
			(xy 351.95658 -105.916018) (xy 351.971931 -105.863734) (xy 351.994566 -105.814166) (xy 352.024023 -105.768324)
			(xy 352.059705 -105.72714) (xy 352.100884 -105.691453) (xy 352.146722 -105.66199) (xy 352.196287 -105.639348)
			(xy 352.248569 -105.623991) (xy 352.302505 -105.61623) (xy 352.32975 -105.61574) (xy 352.358741 -105.616318)
			(xy 352.416053 -105.625104) (xy 352.471378 -105.642453) (xy 352.523446 -105.667964) (xy 352.571059 -105.701053)
			(xy 352.613123 -105.740959) (xy 352.648673 -105.786764) (xy 352.663252 -105.811828) (xy 352.670612 -105.824015)
			(xy 352.690738 -105.844128) (xy 352.71564 -105.857892) (xy 352.743378 -105.864234) (xy 352.771787 -105.86266)
			(xy 352.798654 -105.853292) (xy 352.821883 -105.836861) (xy 352.831146 -105.826052) (xy 352.849353 -105.804165)
			(xy 352.891198 -105.765563) (xy 352.93831 -105.733602) (xy 352.989647 -105.708991) (xy 353.044068 -105.692276)
			(xy 353.100369 -105.683827) (xy 353.128834 -105.683304) (xy 353.156085 -105.683768) (xy 353.21003 -105.691529)
			(xy 353.262323 -105.706887) (xy 353.311897 -105.729531) (xy 353.357745 -105.758999) (xy 353.398932 -105.794692)
			(xy 353.434621 -105.835883) (xy 353.464085 -105.881733) (xy 353.486725 -105.931309) (xy 353.502078 -105.983603)
			(xy 353.509834 -106.037549) (xy 353.509834 -106.081576) (xy 359.182922 -106.081576) (xy 359.186993 -106.025954)
			(xy 359.199119 -105.971517) (xy 359.219042 -105.919426) (xy 359.246338 -105.870791) (xy 359.280424 -105.826648)
			(xy 359.320573 -105.787939) (xy 359.365931 -105.755488) (xy 359.415531 -105.729987) (xy 359.468315 -105.71198)
			(xy 359.523158 -105.70185) (xy 359.578892 -105.699813) (xy 359.634329 -105.705913) (xy 359.688286 -105.720019)
			(xy 359.739615 -105.741831) (xy 359.787221 -105.770885) (xy 359.830089 -105.80656) (xy 359.867306 -105.848097)
			(xy 359.879104 -105.86593) (xy 372.880634 -105.86593) (xy 372.884705 -105.810308) (xy 372.896831 -105.755871)
			(xy 372.916754 -105.70378) (xy 372.94405 -105.655145) (xy 372.978136 -105.611002) (xy 373.018285 -105.572293)
			(xy 373.063643 -105.539842) (xy 373.113243 -105.514341) (xy 373.166027 -105.496334) (xy 373.22087 -105.486204)
			(xy 373.276604 -105.484167) (xy 373.332041 -105.490267) (xy 373.385998 -105.504373) (xy 373.437327 -105.526185)
			(xy 373.484933 -105.555239) (xy 373.527801 -105.590914) (xy 373.565018 -105.632451) (xy 373.595791 -105.678964)
			(xy 373.619463 -105.729461) (xy 373.635531 -105.782868) (xy 373.643651 -105.838044) (xy 373.64416 -105.86593)
			(xy 373.643651 -105.893816) (xy 373.635531 -105.948992) (xy 373.619463 -106.002399) (xy 373.595791 -106.052896)
			(xy 373.565018 -106.099409) (xy 373.527801 -106.140946) (xy 373.484933 -106.176621) (xy 373.437327 -106.205675)
			(xy 373.385998 -106.227487) (xy 373.332041 -106.241593) (xy 373.276604 -106.247693) (xy 373.22087 -106.245656)
			(xy 373.166027 -106.235526) (xy 373.113243 -106.217519) (xy 373.063643 -106.192018) (xy 373.018285 -106.159567)
			(xy 372.978136 -106.120858) (xy 372.94405 -106.076715) (xy 372.916754 -106.02808) (xy 372.896831 -105.975989)
			(xy 372.884705 -105.921552) (xy 372.880634 -105.86593) (xy 359.879104 -105.86593) (xy 359.898079 -105.89461)
			(xy 359.921751 -105.945107) (xy 359.937819 -105.998514) (xy 359.945939 -106.05369) (xy 359.946448 -106.081576)
			(xy 359.945939 -106.109462) (xy 359.937819 -106.164638) (xy 359.921751 -106.218045) (xy 359.898079 -106.268542)
			(xy 359.867306 -106.315055) (xy 359.830089 -106.356592) (xy 359.787221 -106.392267) (xy 359.739615 -106.421321)
			(xy 359.688286 -106.443133) (xy 359.634329 -106.457239) (xy 359.578892 -106.463339) (xy 359.523158 -106.461302)
			(xy 359.468315 -106.451172) (xy 359.415531 -106.433165) (xy 359.365931 -106.407664) (xy 359.320573 -106.375213)
			(xy 359.280424 -106.336504) (xy 359.246338 -106.292361) (xy 359.219042 -106.243726) (xy 359.199119 -106.191635)
			(xy 359.186993 -106.137198) (xy 359.182922 -106.081576) (xy 353.509834 -106.081576) (xy 353.509834 -106.092051)
			(xy 353.502078 -106.145997) (xy 353.486725 -106.198291) (xy 353.464085 -106.247867) (xy 353.434621 -106.293717)
			(xy 353.398932 -106.334908) (xy 353.357745 -106.370601) (xy 353.311897 -106.400069) (xy 353.262323 -106.422713)
			(xy 353.21003 -106.438071) (xy 353.156085 -106.445832) (xy 353.128834 -106.44632) (xy 353.099842 -106.445776)
			(xy 353.042527 -106.436985) (xy 352.9872 -106.419633) (xy 352.935132 -106.394116) (xy 352.887519 -106.361021)
			(xy 352.845456 -106.32111) (xy 352.809909 -106.275299) (xy 352.795332 -106.250232) (xy 352.787995 -106.238032)
			(xy 352.767862 -106.217925) (xy 352.742954 -106.204166) (xy 352.715215 -106.197827) (xy 352.686804 -106.199403)
			(xy 352.659935 -106.208771) (xy 352.636703 -106.2252) (xy 352.627438 -106.236008) (xy 352.609175 -106.257846)
			(xy 352.567343 -106.296453) (xy 352.520242 -106.328421) (xy 352.468917 -106.353041) (xy 352.414505 -106.369766)
			(xy 352.358212 -106.378226) (xy 352.32975 -106.378756) (xy 352.302505 -106.37817) (xy 352.248569 -106.370409)
			(xy 352.196287 -106.355052) (xy 352.146722 -106.332411) (xy 352.100884 -106.302947) (xy 352.059705 -106.26726)
			(xy 352.024023 -106.226076) (xy 351.994566 -106.180234) (xy 351.971931 -106.130666) (xy 351.95658 -106.078382)
			(xy 351.948826 -106.024446) (xy 323.30898 -106.024446) (xy 323.30898 -106.112056) (xy 323.316092 -106.13009)
			(xy 323.322696 -106.136948) (xy 323.341972 -106.15827) (xy 323.374535 -106.205634) (xy 323.399625 -106.257347)
			(xy 323.416674 -106.312238) (xy 323.425295 -106.369065) (xy 323.425295 -106.426543) (xy 323.416672 -106.483371)
			(xy 323.399622 -106.538262) (xy 323.374531 -106.589974) (xy 323.341966 -106.637337) (xy 323.322696 -106.658664)
			(xy 323.316092 -106.665522) (xy 323.30898 -106.683556) (xy 323.30898 -106.772456) (xy 323.316092 -106.79049)
			(xy 323.322696 -106.797348) (xy 323.327305 -106.802446) (xy 340.620928 -106.802446) (xy 340.620928 -106.747954)
			(xy 340.628682 -106.694017) (xy 340.644033 -106.641733) (xy 340.666668 -106.592165) (xy 340.696127 -106.546323)
			(xy 340.731809 -106.505139) (xy 340.772989 -106.469452) (xy 340.818828 -106.439989) (xy 340.868393 -106.417348)
			(xy 340.920676 -106.401991) (xy 340.974612 -106.394231) (xy 341.001858 -106.393742) (xy 341.028174 -106.394157)
			(xy 341.080305 -106.401401) (xy 341.130949 -106.415729) (xy 341.179149 -106.436871) (xy 341.223991 -106.464427)
			(xy 341.264627 -106.497876) (xy 341.282782 -106.516932) (xy 341.290317 -106.524318) (xy 341.309587 -106.532854)
			(xy 341.32012 -106.533442) (xy 341.394796 -106.533442) (xy 341.405345 -106.532912) (xy 341.42464 -106.524376)
			(xy 341.432134 -106.516932) (xy 341.451954 -106.496144) (xy 341.496726 -106.460169) (xy 341.546384 -106.431309)
			(xy 341.599806 -106.410216) (xy 341.655785 -106.397367) (xy 341.713058 -106.393052) (xy 341.770331 -106.397367)
			(xy 341.82631 -106.410216) (xy 341.879732 -106.431309) (xy 341.92939 -106.460169) (xy 341.974162 -106.496144)
			(xy 341.993982 -106.516932) (xy 342.001517 -106.524318) (xy 342.020787 -106.532854) (xy 342.03132 -106.533442)
			(xy 342.105996 -106.533442) (xy 342.116545 -106.532912) (xy 342.13584 -106.524376) (xy 342.143334 -106.516932)
			(xy 342.161486 -106.497873) (xy 342.202116 -106.464415) (xy 342.246957 -106.436856) (xy 342.295158 -106.415718)
			(xy 342.345807 -106.401402) (xy 342.397942 -106.394179) (xy 342.424258 -106.393742) (xy 342.451516 -106.394102)
			(xy 342.505479 -106.401855) (xy 342.557789 -106.41721) (xy 342.607381 -106.439853) (xy 342.653245 -106.469324)
			(xy 342.694448 -106.505022) (xy 342.730151 -106.546221) (xy 342.759627 -106.592082) (xy 342.782276 -106.641672)
			(xy 342.797636 -106.69398) (xy 342.805395 -106.747942) (xy 342.805395 -106.802458) (xy 342.797636 -106.85642)
			(xy 342.786938 -106.892852) (xy 348.895414 -106.892852) (xy 348.899485 -106.83723) (xy 348.911611 -106.782793)
			(xy 348.931534 -106.730702) (xy 348.95883 -106.682067) (xy 348.992916 -106.637924) (xy 349.033065 -106.599215)
			(xy 349.078423 -106.566764) (xy 349.128023 -106.541263) (xy 349.180807 -106.523256) (xy 349.23565 -106.513126)
			(xy 349.291384 -106.511089) (xy 349.346821 -106.517189) (xy 349.400778 -106.531295) (xy 349.452107 -106.553107)
			(xy 349.499713 -106.582161) (xy 349.542581 -106.617836) (xy 349.579798 -106.659373) (xy 349.610571 -106.705886)
			(xy 349.634243 -106.756383) (xy 349.650311 -106.80979) (xy 349.658431 -106.864966) (xy 349.65894 -106.892852)
			(xy 349.658431 -106.920738) (xy 349.650311 -106.975914) (xy 349.634243 -107.029321) (xy 349.610571 -107.079818)
			(xy 349.607393 -107.084622) (xy 352.533966 -107.084622) (xy 352.534452 -107.057371) (xy 352.542208 -107.003423)
			(xy 352.557563 -106.951128) (xy 352.580205 -106.901551) (xy 352.609671 -106.855701) (xy 352.645362 -106.81451)
			(xy 352.686553 -106.778819) (xy 352.732403 -106.749353) (xy 352.78198 -106.726711) (xy 352.834275 -106.711356)
			(xy 352.888223 -106.7036) (xy 352.942725 -106.7036) (xy 352.996673 -106.711356) (xy 353.048968 -106.726711)
			(xy 353.098545 -106.749353) (xy 353.144395 -106.778819) (xy 353.185586 -106.81451) (xy 353.221277 -106.855701)
			(xy 353.250743 -106.901551) (xy 353.273385 -106.951128) (xy 353.28874 -107.003423) (xy 353.288911 -107.004612)
			(xy 359.199178 -107.004612) (xy 359.203249 -106.94899) (xy 359.215375 -106.894553) (xy 359.235298 -106.842462)
			(xy 359.262594 -106.793827) (xy 359.29668 -106.749684) (xy 359.336829 -106.710975) (xy 359.382187 -106.678524)
			(xy 359.431787 -106.653023) (xy 359.484571 -106.635016) (xy 359.539414 -106.624886) (xy 359.595148 -106.622849)
			(xy 359.650585 -106.628949) (xy 359.704542 -106.643055) (xy 359.755871 -106.664867) (xy 359.803477 -106.693921)
			(xy 359.846345 -106.729596) (xy 359.883562 -106.771133) (xy 359.914335 -106.817646) (xy 359.938007 -106.868143)
			(xy 359.954075 -106.92155) (xy 359.962195 -106.976726) (xy 359.962704 -107.004612) (xy 359.962195 -107.032498)
			(xy 359.954075 -107.087674) (xy 359.938007 -107.141081) (xy 359.914335 -107.191578) (xy 359.883562 -107.238091)
			(xy 359.846345 -107.279628) (xy 359.803477 -107.315303) (xy 359.755871 -107.344357) (xy 359.704542 -107.366169)
			(xy 359.650585 -107.380275) (xy 359.595148 -107.386375) (xy 359.539414 -107.384338) (xy 359.484571 -107.374208)
			(xy 359.431787 -107.356201) (xy 359.382187 -107.3307) (xy 359.336829 -107.298249) (xy 359.29668 -107.25954)
			(xy 359.262594 -107.215397) (xy 359.235298 -107.166762) (xy 359.215375 -107.114671) (xy 359.203249 -107.060234)
			(xy 359.199178 -107.004612) (xy 353.288911 -107.004612) (xy 353.296496 -107.057371) (xy 353.296982 -107.084622)
			(xy 353.296399 -107.113443) (xy 353.28772 -107.170427) (xy 353.270564 -107.225456) (xy 353.245321 -107.277276)
			(xy 353.212566 -107.324707) (xy 353.173045 -107.366667) (xy 353.150678 -107.38485) (xy 353.140129 -107.393712)
			(xy 353.123807 -107.415893) (xy 353.114002 -107.441629) (xy 353.111428 -107.469048) (xy 353.116271 -107.496158)
			(xy 353.12818 -107.52099) (xy 353.146289 -107.541738) (xy 353.157536 -107.549696) (xy 353.179741 -107.564939)
			(xy 353.220077 -107.600626) (xy 353.254996 -107.64163) (xy 353.283805 -107.687134) (xy 353.305931 -107.736237)
			(xy 353.320934 -107.787963) (xy 353.328517 -107.841283) (xy 353.328986 -107.868212) (xy 353.3285 -107.895463)
			(xy 353.327817 -107.900216) (xy 353.48545 -107.900216) (xy 353.485936 -107.872965) (xy 353.493692 -107.819017)
			(xy 353.509047 -107.766722) (xy 353.531689 -107.717145) (xy 353.561155 -107.671295) (xy 353.596846 -107.630104)
			(xy 353.638037 -107.594413) (xy 353.683887 -107.564947) (xy 353.733464 -107.542305) (xy 353.785759 -107.52695)
			(xy 353.839707 -107.519194) (xy 353.894209 -107.519194) (xy 353.948157 -107.52695) (xy 354.000452 -107.542305)
			(xy 354.050029 -107.564947) (xy 354.095879 -107.594413) (xy 354.116677 -107.612434) (xy 372.040656 -107.612434)
			(xy 372.044727 -107.556812) (xy 372.056853 -107.502375) (xy 372.076776 -107.450284) (xy 372.104072 -107.401649)
			(xy 372.138158 -107.357506) (xy 372.178307 -107.318797) (xy 372.223665 -107.286346) (xy 372.273265 -107.260845)
			(xy 372.326049 -107.242838) (xy 372.380892 -107.232708) (xy 372.436626 -107.230671) (xy 372.492063 -107.236771)
			(xy 372.54602 -107.250877) (xy 372.597349 -107.272689) (xy 372.644955 -107.301743) (xy 372.687823 -107.337418)
			(xy 372.72504 -107.378955) (xy 372.755813 -107.425468) (xy 372.779485 -107.475965) (xy 372.795553 -107.529372)
			(xy 372.803673 -107.584548) (xy 372.804182 -107.612434) (xy 372.803673 -107.64032) (xy 372.795553 -107.695496)
			(xy 372.779485 -107.748903) (xy 372.755813 -107.7994) (xy 372.72504 -107.845913) (xy 372.687823 -107.88745)
			(xy 372.644955 -107.923125) (xy 372.597349 -107.952179) (xy 372.54602 -107.973991) (xy 372.492063 -107.988097)
			(xy 372.436626 -107.994197) (xy 372.380892 -107.99216) (xy 372.326049 -107.98203) (xy 372.273265 -107.964023)
			(xy 372.223665 -107.938522) (xy 372.178307 -107.906071) (xy 372.138158 -107.867362) (xy 372.104072 -107.823219)
			(xy 372.076776 -107.774584) (xy 372.056853 -107.722493) (xy 372.044727 -107.668056) (xy 372.040656 -107.612434)
			(xy 354.116677 -107.612434) (xy 354.13707 -107.630104) (xy 354.172761 -107.671295) (xy 354.202227 -107.717145)
			(xy 354.224869 -107.766722) (xy 354.240224 -107.819017) (xy 354.24798 -107.872965) (xy 354.248466 -107.900216)
			(xy 354.247923 -107.928663) (xy 354.239485 -107.984929) (xy 354.222783 -108.039316) (xy 354.198188 -108.09062)
			(xy 354.166245 -108.137701) (xy 354.127663 -108.179516) (xy 354.083299 -108.215136) (xy 354.058982 -108.229908)
			(xy 354.047044 -108.236766) (xy 354.033582 -108.260388) (xy 354.034598 -108.36275) (xy 354.035083 -108.371609)
			(xy 354.041257 -108.388222) (xy 354.052739 -108.401723) (xy 354.060252 -108.406438) (xy 354.060506 -108.406438)
			(xy 354.08554 -108.421021) (xy 354.131307 -108.456539) (xy 354.171178 -108.498568) (xy 354.204235 -108.546144)
			(xy 354.229717 -108.598171) (xy 354.247038 -108.653454) (xy 354.255801 -108.71072) (xy 354.25634 -108.739686)
			(xy 354.255884 -108.767139) (xy 354.247996 -108.821475) (xy 354.23663 -108.859828) (xy 372.147844 -108.859828)
			(xy 372.151915 -108.804206) (xy 372.164041 -108.749769) (xy 372.183964 -108.697678) (xy 372.21126 -108.649043)
			(xy 372.245346 -108.6049) (xy 372.285495 -108.566191) (xy 372.330853 -108.53374) (xy 372.380453 -108.508239)
			(xy 372.433237 -108.490232) (xy 372.48808 -108.480102) (xy 372.543814 -108.478065) (xy 372.599251 -108.484165)
			(xy 372.653208 -108.498271) (xy 372.704537 -108.520083) (xy 372.752143 -108.549137) (xy 372.795011 -108.584812)
			(xy 372.832228 -108.626349) (xy 372.863001 -108.672862) (xy 372.886673 -108.723359) (xy 372.902741 -108.776766)
			(xy 372.910861 -108.831942) (xy 372.91137 -108.859828) (xy 372.910861 -108.887714) (xy 372.902741 -108.94289)
			(xy 372.886673 -108.996297) (xy 372.863001 -109.046794) (xy 372.832228 -109.093307) (xy 372.795011 -109.134844)
			(xy 372.752143 -109.170519) (xy 372.704537 -109.199573) (xy 372.653208 -109.221385) (xy 372.599251 -109.235491)
			(xy 372.543814 -109.241591) (xy 372.48808 -109.239554) (xy 372.433237 -109.229424) (xy 372.380453 -109.211417)
			(xy 372.330853 -109.185916) (xy 372.285495 -109.153465) (xy 372.245346 -109.114756) (xy 372.21126 -109.070613)
			(xy 372.183964 -109.021978) (xy 372.164041 -108.969887) (xy 372.151915 -108.91545) (xy 372.147844 -108.859828)
			(xy 354.23663 -108.859828) (xy 354.232395 -108.874117) (xy 354.209405 -108.923978) (xy 354.1795 -108.970024)
			(xy 354.143299 -109.011306) (xy 354.122736 -109.0295) (xy 354.122482 -109.029754) (xy 354.114082 -109.037669)
			(xy 354.104967 -109.058851) (xy 354.104956 -109.070394) (xy 354.10902 -109.162088) (xy 354.120196 -109.182408)
			(xy 354.129594 -109.189266) (xy 354.150381 -109.204676) (xy 354.187972 -109.240236) (xy 354.220414 -109.280548)
			(xy 354.239173 -109.311694) (xy 364.215678 -109.311694) (xy 364.219749 -109.256072) (xy 364.231875 -109.201635)
			(xy 364.251798 -109.149544) (xy 364.279094 -109.100909) (xy 364.31318 -109.056766) (xy 364.353329 -109.018057)
			(xy 364.398687 -108.985606) (xy 364.448287 -108.960105) (xy 364.501071 -108.942098) (xy 364.555914 -108.931968)
			(xy 364.611648 -108.929931) (xy 364.667085 -108.936031) (xy 364.721042 -108.950137) (xy 364.772371 -108.971949)
			(xy 364.819977 -109.001003) (xy 364.862845 -109.036678) (xy 364.900062 -109.078215) (xy 364.930835 -109.124728)
			(xy 364.954507 -109.175225) (xy 364.970575 -109.228632) (xy 364.978695 -109.283808) (xy 364.979204 -109.311694)
			(xy 364.978695 -109.33958) (xy 364.970575 -109.394756) (xy 364.954507 -109.448163) (xy 364.930835 -109.49866)
			(xy 364.900062 -109.545173) (xy 364.862845 -109.58671) (xy 364.819977 -109.622385) (xy 364.772371 -109.651439)
			(xy 364.721042 -109.673251) (xy 364.667085 -109.687357) (xy 364.611648 -109.693457) (xy 364.555914 -109.69142)
			(xy 364.501071 -109.68129) (xy 364.448287 -109.663283) (xy 364.398687 -109.637782) (xy 364.353329 -109.605331)
			(xy 364.31318 -109.566622) (xy 364.279094 -109.522479) (xy 364.251798 -109.473844) (xy 364.231875 -109.421753)
			(xy 364.219749 -109.367316) (xy 364.215678 -109.311694) (xy 354.239173 -109.311694) (xy 354.247111 -109.324874)
			(xy 354.267575 -109.372401) (xy 354.28143 -109.422257) (xy 354.288421 -109.473527) (xy 354.288852 -109.4994)
			(xy 354.288366 -109.526651) (xy 354.28061 -109.580599) (xy 354.265255 -109.632894) (xy 354.242613 -109.682471)
			(xy 354.213147 -109.728321) (xy 354.177456 -109.769512) (xy 354.136265 -109.805203) (xy 354.090415 -109.834669)
			(xy 354.040838 -109.857311) (xy 353.988543 -109.872666) (xy 353.934595 -109.880422) (xy 353.880093 -109.880422)
			(xy 353.826145 -109.872666) (xy 353.77385 -109.857311) (xy 353.724273 -109.834669) (xy 353.678423 -109.805203)
			(xy 353.637232 -109.769512) (xy 353.601541 -109.728321) (xy 353.572075 -109.682471) (xy 353.549433 -109.632894)
			(xy 353.534078 -109.580599) (xy 353.526322 -109.526651) (xy 353.525836 -109.4994) (xy 353.52636 -109.47195)
			(xy 353.534235 -109.417617) (xy 353.549823 -109.364976) (xy 353.572801 -109.315116) (xy 353.602693 -109.269067)
			(xy 353.638882 -109.227783) (xy 353.65944 -109.209586) (xy 353.659694 -109.209332) (xy 353.66805 -109.201378)
			(xy 353.677191 -109.180226) (xy 353.67722 -109.168692) (xy 353.673156 -109.076998) (xy 353.66198 -109.056678)
			(xy 353.652582 -109.04982) (xy 353.631831 -109.034364) (xy 353.59424 -108.998812) (xy 353.561796 -108.958507)
			(xy 353.535094 -108.914189) (xy 353.514624 -108.86667) (xy 353.500762 -108.816821) (xy 353.493761 -108.765556)
			(xy 353.493324 -108.739686) (xy 353.493873 -108.711239) (xy 353.502311 -108.654974) (xy 353.519012 -108.600587)
			(xy 353.543607 -108.549283) (xy 353.575548 -108.502202) (xy 353.614129 -108.460387) (xy 353.658492 -108.424766)
			(xy 353.682808 -108.409994) (xy 353.694746 -108.403136) (xy 353.708208 -108.379514) (xy 353.707192 -108.277152)
			(xy 353.70671 -108.268293) (xy 353.700535 -108.251679) (xy 353.689052 -108.238179) (xy 353.681538 -108.233464)
			(xy 353.681284 -108.233464) (xy 353.656249 -108.218883) (xy 353.610482 -108.183365) (xy 353.570611 -108.141335)
			(xy 353.537555 -108.093758) (xy 353.512074 -108.041731) (xy 353.494752 -107.986448) (xy 353.485989 -107.929182)
			(xy 353.48545 -107.900216) (xy 353.327817 -107.900216) (xy 353.320744 -107.949411) (xy 353.305389 -108.001706)
			(xy 353.282747 -108.051283) (xy 353.253281 -108.097133) (xy 353.21759 -108.138324) (xy 353.176399 -108.174015)
			(xy 353.130549 -108.203481) (xy 353.080972 -108.226123) (xy 353.028677 -108.241478) (xy 352.974729 -108.249234)
			(xy 352.920227 -108.249234) (xy 352.866279 -108.241478) (xy 352.813984 -108.226123) (xy 352.764407 -108.203481)
			(xy 352.718557 -108.174015) (xy 352.677366 -108.138324) (xy 352.641675 -108.097133) (xy 352.612209 -108.051283)
			(xy 352.589567 -108.001706) (xy 352.574212 -107.949411) (xy 352.566456 -107.895463) (xy 352.56597 -107.868212)
			(xy 352.566486 -107.839389) (xy 352.575176 -107.7824) (xy 352.592344 -107.727369) (xy 352.6176 -107.675549)
			(xy 352.650368 -107.62812) (xy 352.689901 -107.586164) (xy 352.712274 -107.567984) (xy 352.722781 -107.559078)
			(xy 352.739095 -107.536905) (xy 352.748896 -107.511181) (xy 352.751473 -107.483774) (xy 352.746639 -107.456673)
			(xy 352.734745 -107.431848) (xy 352.716653 -107.411099) (xy 352.705416 -107.403138) (xy 352.683192 -107.387921)
			(xy 352.642854 -107.352231) (xy 352.607934 -107.311224) (xy 352.579127 -107.265715) (xy 352.557004 -107.216607)
			(xy 352.542006 -107.164877) (xy 352.53443 -107.111552) (xy 352.533966 -107.084622) (xy 349.607393 -107.084622)
			(xy 349.579798 -107.126331) (xy 349.542581 -107.167868) (xy 349.499713 -107.203543) (xy 349.452107 -107.232597)
			(xy 349.400778 -107.254409) (xy 349.346821 -107.268515) (xy 349.291384 -107.274615) (xy 349.23565 -107.272578)
			(xy 349.180807 -107.262448) (xy 349.128023 -107.244441) (xy 349.078423 -107.21894) (xy 349.033065 -107.186489)
			(xy 348.992916 -107.14778) (xy 348.95883 -107.103637) (xy 348.931534 -107.055002) (xy 348.911611 -107.002911)
			(xy 348.899485 -106.948474) (xy 348.895414 -106.892852) (xy 342.786938 -106.892852) (xy 342.782276 -106.908728)
			(xy 342.759627 -106.958318) (xy 342.730151 -107.004179) (xy 342.694448 -107.045378) (xy 342.653245 -107.081076)
			(xy 342.607381 -107.110547) (xy 342.557789 -107.13319) (xy 342.505479 -107.148545) (xy 342.451516 -107.156298)
			(xy 342.424258 -107.156758) (xy 342.397942 -107.156332) (xy 342.345812 -107.149091) (xy 342.295168 -107.134764)
			(xy 342.246968 -107.113624) (xy 342.202126 -107.08607) (xy 342.161489 -107.052623) (xy 342.143334 -107.033568)
			(xy 342.135793 -107.026189) (xy 342.116528 -107.017649) (xy 342.105996 -107.017058) (xy 342.03132 -107.017058)
			(xy 342.020772 -107.017597) (xy 342.001477 -107.026127) (xy 341.993982 -107.033568) (xy 341.974162 -107.054356)
			(xy 341.92939 -107.090331) (xy 341.879732 -107.119191) (xy 341.82631 -107.140284) (xy 341.770331 -107.153133)
			(xy 341.713058 -107.157448) (xy 341.655785 -107.153133) (xy 341.599806 -107.140284) (xy 341.546384 -107.119191)
			(xy 341.496726 -107.090331) (xy 341.451954 -107.054356) (xy 341.432134 -107.033568) (xy 341.424593 -107.026189)
			(xy 341.405328 -107.017649) (xy 341.394796 -107.017058) (xy 341.32012 -107.017058) (xy 341.309572 -107.017597)
			(xy 341.290277 -107.026127) (xy 341.282782 -107.033568) (xy 341.264622 -107.052619) (xy 341.223994 -107.086078)
			(xy 341.179155 -107.113638) (xy 341.130955 -107.134778) (xy 341.080308 -107.149095) (xy 341.028174 -107.15632)
			(xy 341.001858 -107.156758) (xy 340.974612 -107.156169) (xy 340.920676 -107.148409) (xy 340.868393 -107.133052)
			(xy 340.818828 -107.110411) (xy 340.772989 -107.080948) (xy 340.731809 -107.045261) (xy 340.696127 -107.004077)
			(xy 340.666668 -106.958235) (xy 340.644033 -106.908667) (xy 340.628682 -106.856383) (xy 340.620928 -106.802446)
			(xy 323.327305 -106.802446) (xy 323.341972 -106.81867) (xy 323.374535 -106.866034) (xy 323.399625 -106.917747)
			(xy 323.416674 -106.972638) (xy 323.425295 -107.029465) (xy 323.425295 -107.086943) (xy 323.416672 -107.143771)
			(xy 323.399622 -107.198662) (xy 323.374531 -107.250374) (xy 323.341966 -107.297737) (xy 323.322696 -107.319064)
			(xy 323.316092 -107.325922) (xy 323.30898 -107.343956) (xy 323.30898 -107.432856) (xy 323.316092 -107.45089)
			(xy 323.322696 -107.457748) (xy 323.341972 -107.47907) (xy 323.374535 -107.526434) (xy 323.399625 -107.578147)
			(xy 323.416674 -107.633038) (xy 323.425295 -107.689865) (xy 323.425295 -107.740249) (xy 327.884296 -107.740249)
			(xy 327.884296 -107.685751) (xy 327.892052 -107.631807) (xy 327.907405 -107.579517) (xy 327.930044 -107.529943)
			(xy 327.959507 -107.484096) (xy 327.995195 -107.442908) (xy 328.036381 -107.407218) (xy 328.082227 -107.377753)
			(xy 328.1318 -107.355112) (xy 328.18409 -107.339756) (xy 328.238033 -107.331997) (xy 328.265282 -107.33151)
			(xy 328.292652 -107.331984) (xy 328.346831 -107.3398) (xy 328.399334 -107.355287) (xy 328.449081 -107.378127)
			(xy 328.495048 -107.40785) (xy 328.51598 -107.42549) (xy 328.516234 -107.425744) (xy 328.523331 -107.431314)
			(xy 328.54024 -107.43757) (xy 328.549254 -107.437936) (xy 328.61631 -107.437936) (xy 328.625326 -107.437576)
			(xy 328.642243 -107.43133) (xy 328.64933 -107.425744) (xy 328.64933 -107.42549) (xy 328.649584 -107.42549)
			(xy 328.670517 -107.407849) (xy 328.716485 -107.378125) (xy 328.766231 -107.355279) (xy 328.818733 -107.339783)
			(xy 328.872911 -107.331954) (xy 328.927653 -107.331954) (xy 328.981831 -107.339783) (xy 329.034333 -107.355279)
			(xy 329.084079 -107.378125) (xy 329.130047 -107.407849) (xy 329.15098 -107.42549) (xy 329.151234 -107.425744)
			(xy 329.158331 -107.431314) (xy 329.17524 -107.43757) (xy 329.184254 -107.437936) (xy 329.25131 -107.437936)
			(xy 329.260326 -107.437576) (xy 329.277243 -107.43133) (xy 329.28433 -107.425744) (xy 329.28433 -107.42549)
			(xy 329.284584 -107.42549) (xy 329.305517 -107.407849) (xy 329.351485 -107.378125) (xy 329.401231 -107.355279)
			(xy 329.453733 -107.339783) (xy 329.507911 -107.331954) (xy 329.562653 -107.331954) (xy 329.616831 -107.339783)
			(xy 329.669333 -107.355279) (xy 329.719079 -107.378125) (xy 329.765047 -107.407849) (xy 329.78598 -107.42549)
			(xy 329.786234 -107.425744) (xy 329.793331 -107.431314) (xy 329.81024 -107.43757) (xy 329.819254 -107.437936)
			(xy 329.88631 -107.437936) (xy 329.895326 -107.437576) (xy 329.912243 -107.43133) (xy 329.91933 -107.425744)
			(xy 329.91933 -107.42549) (xy 329.919584 -107.42549) (xy 329.94051 -107.407843) (xy 329.986485 -107.378133)
			(xy 330.036234 -107.355299) (xy 330.088736 -107.339809) (xy 330.142912 -107.331983) (xy 330.170282 -107.33151)
			(xy 330.197537 -107.331936) (xy 330.251492 -107.339691) (xy 330.303795 -107.355046) (xy 330.35338 -107.377689)
			(xy 330.399237 -107.407158) (xy 330.440434 -107.442853) (xy 330.476132 -107.484048) (xy 330.505603 -107.529904)
			(xy 330.528248 -107.579488) (xy 330.543605 -107.63179) (xy 330.551363 -107.685745) (xy 330.551363 -107.740255)
			(xy 330.543605 -107.79421) (xy 330.528248 -107.846512) (xy 330.505603 -107.896096) (xy 330.476132 -107.941952)
			(xy 330.440434 -107.983147) (xy 330.399237 -108.018842) (xy 330.35338 -108.048311) (xy 330.303795 -108.070954)
			(xy 330.251492 -108.086309) (xy 330.197537 -108.094064) (xy 330.170282 -108.094526) (xy 330.142911 -108.094089)
			(xy 330.088729 -108.086267) (xy 330.036225 -108.070772) (xy 329.986479 -108.047923) (xy 329.940514 -108.018191)
			(xy 329.919584 -108.000546) (xy 329.91933 -108.000292) (xy 329.91224 -107.994711) (xy 329.895326 -107.988461)
			(xy 329.88631 -107.9881) (xy 329.819254 -107.9881) (xy 329.81024 -107.988483) (xy 329.793323 -107.994713)
			(xy 329.786234 -108.000292) (xy 329.78598 -108.000546) (xy 329.765047 -108.018187) (xy 329.719079 -108.047911)
			(xy 329.669333 -108.070757) (xy 329.616831 -108.086253) (xy 329.562653 -108.094082) (xy 329.507911 -108.094082)
			(xy 329.453733 -108.086253) (xy 329.401231 -108.070757) (xy 329.351485 -108.047911) (xy 329.305517 -108.018187)
			(xy 329.284584 -108.000546) (xy 329.28433 -108.000292) (xy 329.27724 -107.994711) (xy 329.260326 -107.988461)
			(xy 329.25131 -107.9881) (xy 329.184254 -107.9881) (xy 329.17524 -107.988483) (xy 329.158323 -107.994713)
			(xy 329.151234 -108.000292) (xy 329.151234 -108.000546) (xy 329.15098 -108.000546) (xy 329.130047 -108.018187)
			(xy 329.084079 -108.047911) (xy 329.034333 -108.070757) (xy 328.981831 -108.086253) (xy 328.927653 -108.094082)
			(xy 328.872911 -108.094082) (xy 328.818733 -108.086253) (xy 328.766231 -108.070757) (xy 328.716485 -108.047911)
			(xy 328.670517 -108.018187) (xy 328.649584 -108.000546) (xy 328.64933 -108.000292) (xy 328.64224 -107.994711)
			(xy 328.625326 -107.988461) (xy 328.61631 -107.9881) (xy 328.549254 -107.9881) (xy 328.54024 -107.988483)
			(xy 328.523323 -107.994713) (xy 328.516234 -108.000292) (xy 328.516234 -108.000546) (xy 328.51598 -108.000546)
			(xy 328.495022 -108.018153) (xy 328.449057 -108.047871) (xy 328.399316 -108.070714) (xy 328.346821 -108.086213)
			(xy 328.29265 -108.094048) (xy 328.265282 -108.094526) (xy 328.238033 -108.094003) (xy 328.18409 -108.086244)
			(xy 328.1318 -108.070888) (xy 328.082227 -108.048247) (xy 328.036381 -108.018782) (xy 327.995195 -107.983092)
			(xy 327.959507 -107.941904) (xy 327.930044 -107.896057) (xy 327.907405 -107.846483) (xy 327.892052 -107.794193)
			(xy 327.884296 -107.740249) (xy 323.425295 -107.740249) (xy 323.425295 -107.747343) (xy 323.416672 -107.804171)
			(xy 323.399622 -107.859062) (xy 323.374531 -107.910774) (xy 323.341966 -107.958137) (xy 323.322696 -107.979464)
			(xy 323.316092 -107.986322) (xy 323.30898 -108.004356) (xy 323.30898 -108.093256) (xy 323.316092 -108.11129)
			(xy 323.322696 -108.118148) (xy 323.341958 -108.139483) (xy 323.374528 -108.186841) (xy 323.399623 -108.238551)
			(xy 323.416676 -108.293441) (xy 323.425299 -108.350267) (xy 323.42582 -108.379006) (xy 323.425334 -108.406257)
			(xy 323.417578 -108.460205) (xy 323.402223 -108.5125) (xy 323.379581 -108.562077) (xy 323.374807 -108.569506)
			(xy 339.061044 -108.569506) (xy 339.061503 -108.542135) (xy 339.069321 -108.487956) (xy 339.084811 -108.435452)
			(xy 339.107655 -108.385705) (xy 339.137381 -108.339739) (xy 339.155024 -108.318808) (xy 339.155278 -108.318554)
			(xy 339.160857 -108.311463) (xy 339.167106 -108.294549) (xy 339.16747 -108.285534) (xy 339.16747 -108.218478)
			(xy 339.16713 -108.209459) (xy 339.160871 -108.192542) (xy 339.155278 -108.185458) (xy 339.155024 -108.185458)
			(xy 339.155024 -108.185204) (xy 339.137377 -108.164278) (xy 339.107666 -108.118304) (xy 339.084831 -108.068555)
			(xy 339.069342 -108.016053) (xy 339.061516 -107.961876) (xy 339.061044 -107.934506) (xy 339.06153 -107.907255)
			(xy 339.069286 -107.853307) (xy 339.084641 -107.801012) (xy 339.107283 -107.751435) (xy 339.136749 -107.705585)
			(xy 339.17244 -107.664394) (xy 339.213631 -107.628703) (xy 339.259481 -107.599237) (xy 339.309058 -107.576595)
			(xy 339.361353 -107.56124) (xy 339.415301 -107.553484) (xy 339.469803 -107.553484) (xy 339.523751 -107.56124)
			(xy 339.576046 -107.576595) (xy 339.625623 -107.599237) (xy 339.671473 -107.628703) (xy 339.712664 -107.664394)
			(xy 339.748355 -107.705585) (xy 339.777821 -107.751435) (xy 339.800463 -107.801012) (xy 339.814452 -107.848654)
			(xy 345.240608 -107.848654) (xy 345.244679 -107.793032) (xy 345.256805 -107.738595) (xy 345.276728 -107.686504)
			(xy 345.304024 -107.637869) (xy 345.33811 -107.593726) (xy 345.378259 -107.555017) (xy 345.423617 -107.522566)
			(xy 345.473217 -107.497065) (xy 345.526001 -107.479058) (xy 345.580844 -107.468928) (xy 345.636578 -107.466891)
			(xy 345.692015 -107.472991) (xy 345.745972 -107.487097) (xy 345.797301 -107.508909) (xy 345.844907 -107.537963)
			(xy 345.887775 -107.573638) (xy 345.924992 -107.615175) (xy 345.955765 -107.661688) (xy 345.979437 -107.712185)
			(xy 345.995505 -107.765592) (xy 346.003625 -107.820768) (xy 346.004134 -107.848654) (xy 346.003625 -107.87654)
			(xy 346.002496 -107.884214) (xy 348.911416 -107.884214) (xy 348.915487 -107.828592) (xy 348.927613 -107.774155)
			(xy 348.947536 -107.722064) (xy 348.974832 -107.673429) (xy 349.008918 -107.629286) (xy 349.049067 -107.590577)
			(xy 349.094425 -107.558126) (xy 349.144025 -107.532625) (xy 349.196809 -107.514618) (xy 349.251652 -107.504488)
			(xy 349.307386 -107.502451) (xy 349.362823 -107.508551) (xy 349.41678 -107.522657) (xy 349.468109 -107.544469)
			(xy 349.515715 -107.573523) (xy 349.558583 -107.609198) (xy 349.5958 -107.650735) (xy 349.626573 -107.697248)
			(xy 349.650245 -107.747745) (xy 349.666313 -107.801152) (xy 349.674433 -107.856328) (xy 349.674942 -107.884214)
			(xy 349.674433 -107.9121) (xy 349.666313 -107.967276) (xy 349.650245 -108.020683) (xy 349.626573 -108.07118)
			(xy 349.5958 -108.117693) (xy 349.558583 -108.15923) (xy 349.515715 -108.194905) (xy 349.468109 -108.223959)
			(xy 349.41678 -108.245771) (xy 349.362823 -108.259877) (xy 349.307386 -108.265977) (xy 349.251652 -108.26394)
			(xy 349.196809 -108.25381) (xy 349.144025 -108.235803) (xy 349.094425 -108.210302) (xy 349.049067 -108.177851)
			(xy 349.008918 -108.139142) (xy 348.974832 -108.094999) (xy 348.947536 -108.046364) (xy 348.927613 -107.994273)
			(xy 348.915487 -107.939836) (xy 348.911416 -107.884214) (xy 346.002496 -107.884214) (xy 345.995505 -107.931716)
			(xy 345.979437 -107.985123) (xy 345.955765 -108.03562) (xy 345.924992 -108.082133) (xy 345.887775 -108.12367)
			(xy 345.844907 -108.159345) (xy 345.797301 -108.188399) (xy 345.745972 -108.210211) (xy 345.692015 -108.224317)
			(xy 345.636578 -108.230417) (xy 345.580844 -108.22838) (xy 345.526001 -108.21825) (xy 345.473217 -108.200243)
			(xy 345.423617 -108.174742) (xy 345.378259 -108.142291) (xy 345.33811 -108.103582) (xy 345.304024 -108.059439)
			(xy 345.276728 -108.010804) (xy 345.256805 -107.958713) (xy 345.244679 -107.904276) (xy 345.240608 -107.848654)
			(xy 339.814452 -107.848654) (xy 339.815818 -107.853307) (xy 339.823574 -107.907255) (xy 339.82406 -107.934506)
			(xy 339.823607 -107.961877) (xy 339.815788 -108.016057) (xy 339.800296 -108.068561) (xy 339.777451 -108.118307)
			(xy 339.747723 -108.164273) (xy 339.73008 -108.185204) (xy 339.729826 -108.185458) (xy 339.724242 -108.192546)
			(xy 339.717996 -108.209462) (xy 339.717634 -108.218478) (xy 339.717634 -108.285534) (xy 339.717967 -108.294553)
			(xy 339.724231 -108.311471) (xy 339.729826 -108.318554) (xy 339.73008 -108.318554) (xy 339.73008 -108.318808)
			(xy 339.747733 -108.339729) (xy 339.777444 -108.385704) (xy 339.800277 -108.435455) (xy 339.815765 -108.487958)
			(xy 339.823589 -108.542136) (xy 339.82406 -108.569506) (xy 339.823574 -108.596757) (xy 339.815818 -108.650705)
			(xy 339.800463 -108.703) (xy 339.777821 -108.752577) (xy 339.748355 -108.798427) (xy 339.712664 -108.839618)
			(xy 339.671473 -108.875309) (xy 339.625623 -108.904775) (xy 339.576046 -108.927417) (xy 339.523751 -108.942772)
			(xy 339.469803 -108.950528) (xy 339.415301 -108.950528) (xy 339.361353 -108.942772) (xy 339.309058 -108.927417)
			(xy 339.259481 -108.904775) (xy 339.213631 -108.875309) (xy 339.17244 -108.839618) (xy 339.136749 -108.798427)
			(xy 339.107283 -108.752577) (xy 339.084641 -108.703) (xy 339.069286 -108.650705) (xy 339.06153 -108.596757)
			(xy 339.061044 -108.569506) (xy 323.374807 -108.569506) (xy 323.350115 -108.607927) (xy 323.314424 -108.649118)
			(xy 323.273233 -108.684809) (xy 323.227383 -108.714275) (xy 323.177806 -108.736917) (xy 323.125511 -108.752272)
			(xy 323.071563 -108.760028) (xy 323.017061 -108.760028) (xy 322.963113 -108.752272) (xy 322.910818 -108.736917)
			(xy 322.861241 -108.714275) (xy 322.815391 -108.684809) (xy 322.7742 -108.649118) (xy 322.738509 -108.607927)
			(xy 322.709043 -108.562077) (xy 322.686401 -108.5125) (xy 322.671046 -108.460205) (xy 322.66329 -108.406257)
			(xy 322.662804 -108.379006) (xy 314.854277 -108.379006) (xy 314.714679 -109.502448) (xy 341.614504 -109.502448)
			(xy 341.618575 -109.446826) (xy 341.630701 -109.392389) (xy 341.650624 -109.340298) (xy 341.67792 -109.291663)
			(xy 341.712006 -109.24752) (xy 341.752155 -109.208811) (xy 341.797513 -109.17636) (xy 341.847113 -109.150859)
			(xy 341.899897 -109.132852) (xy 341.95474 -109.122722) (xy 342.010474 -109.120685) (xy 342.065911 -109.126785)
			(xy 342.119868 -109.140891) (xy 342.171197 -109.162703) (xy 342.218803 -109.191757) (xy 342.261671 -109.227432)
			(xy 342.298888 -109.268969) (xy 342.329661 -109.315482) (xy 342.353333 -109.365979) (xy 342.369401 -109.419386)
			(xy 342.377521 -109.474562) (xy 342.37803 -109.502448) (xy 342.377521 -109.530334) (xy 342.369401 -109.58551)
			(xy 342.353333 -109.638917) (xy 342.329661 -109.689414) (xy 342.298888 -109.735927) (xy 342.261671 -109.777464)
			(xy 342.249688 -109.787436) (xy 348.959932 -109.787436) (xy 348.960418 -109.760185) (xy 348.968174 -109.706237)
			(xy 348.983529 -109.653942) (xy 349.006171 -109.604365) (xy 349.035637 -109.558515) (xy 349.071328 -109.517324)
			(xy 349.112519 -109.481633) (xy 349.158369 -109.452167) (xy 349.207946 -109.429525) (xy 349.260241 -109.41417)
			(xy 349.314189 -109.406414) (xy 349.368691 -109.406414) (xy 349.422639 -109.41417) (xy 349.474934 -109.429525)
			(xy 349.524511 -109.452167) (xy 349.570361 -109.481633) (xy 349.611552 -109.517324) (xy 349.647243 -109.558515)
			(xy 349.676709 -109.604365) (xy 349.699351 -109.653942) (xy 349.714706 -109.706237) (xy 349.722462 -109.760185)
			(xy 349.722948 -109.787436) (xy 349.722475 -109.815341) (xy 349.714327 -109.870555) (xy 349.698225 -109.923993)
			(xy 349.674513 -109.974516) (xy 349.650378 -110.010956) (xy 371.610126 -110.010956) (xy 371.614197 -109.955334)
			(xy 371.626323 -109.900897) (xy 371.646246 -109.848806) (xy 371.673542 -109.800171) (xy 371.707628 -109.756028)
			(xy 371.747777 -109.717319) (xy 371.793135 -109.684868) (xy 371.842735 -109.659367) (xy 371.895519 -109.64136)
			(xy 371.950362 -109.63123) (xy 372.006096 -109.629193) (xy 372.061533 -109.635293) (xy 372.11549 -109.649399)
			(xy 372.166819 -109.671211) (xy 372.214425 -109.700265) (xy 372.257293 -109.73594) (xy 372.29451 -109.777477)
			(xy 372.325283 -109.82399) (xy 372.348955 -109.874487) (xy 372.365023 -109.927894) (xy 372.373143 -109.98307)
			(xy 372.373652 -110.010956) (xy 372.373647 -110.01121) (xy 373.347232 -110.01121) (xy 373.351303 -109.955588)
			(xy 373.363429 -109.901151) (xy 373.383352 -109.84906) (xy 373.410648 -109.800425) (xy 373.444734 -109.756282)
			(xy 373.484883 -109.717573) (xy 373.530241 -109.685122) (xy 373.579841 -109.659621) (xy 373.632625 -109.641614)
			(xy 373.687468 -109.631484) (xy 373.743202 -109.629447) (xy 373.798639 -109.635547) (xy 373.852596 -109.649653)
			(xy 373.903925 -109.671465) (xy 373.951531 -109.700519) (xy 373.994399 -109.736194) (xy 374.031616 -109.777731)
			(xy 374.062389 -109.824244) (xy 374.086061 -109.874741) (xy 374.102129 -109.928148) (xy 374.110249 -109.983324)
			(xy 374.110758 -110.01121) (xy 374.110249 -110.039096) (xy 374.102129 -110.094272) (xy 374.086061 -110.147679)
			(xy 374.062389 -110.198176) (xy 374.031616 -110.244689) (xy 373.994399 -110.286226) (xy 373.951531 -110.321901)
			(xy 373.903925 -110.350955) (xy 373.852596 -110.372767) (xy 373.798639 -110.386873) (xy 373.743202 -110.392973)
			(xy 373.687468 -110.390936) (xy 373.632625 -110.380806) (xy 373.579841 -110.362799) (xy 373.530241 -110.337298)
			(xy 373.484883 -110.304847) (xy 373.444734 -110.266138) (xy 373.410648 -110.221995) (xy 373.383352 -110.17336)
			(xy 373.363429 -110.121269) (xy 373.351303 -110.066832) (xy 373.347232 -110.01121) (xy 372.373647 -110.01121)
			(xy 372.373143 -110.038842) (xy 372.365023 -110.094018) (xy 372.348955 -110.147425) (xy 372.325283 -110.197922)
			(xy 372.29451 -110.244435) (xy 372.257293 -110.285972) (xy 372.214425 -110.321647) (xy 372.166819 -110.350701)
			(xy 372.11549 -110.372513) (xy 372.061533 -110.386619) (xy 372.006096 -110.392719) (xy 371.950362 -110.390682)
			(xy 371.895519 -110.380552) (xy 371.842735 -110.362545) (xy 371.793135 -110.337044) (xy 371.747777 -110.304593)
			(xy 371.707628 -110.265884) (xy 371.673542 -110.221741) (xy 371.646246 -110.173106) (xy 371.626323 -110.121015)
			(xy 371.614197 -110.066578) (xy 371.610126 -110.010956) (xy 349.650378 -110.010956) (xy 349.643695 -110.021047)
			(xy 349.606429 -110.062594) (xy 349.58528 -110.080806) (xy 349.57639 -110.088172) (xy 349.566738 -110.109)
			(xy 349.568008 -110.211108) (xy 349.578168 -110.231682) (xy 349.587312 -110.238794) (xy 349.609606 -110.257002)
			(xy 349.64901 -110.298958) (xy 349.681665 -110.346357) (xy 349.706829 -110.398124) (xy 349.72393 -110.453084)
			(xy 349.732582 -110.509989) (xy 349.733108 -110.538768) (xy 349.732622 -110.566019) (xy 349.724866 -110.619967)
			(xy 349.709511 -110.672262) (xy 349.686869 -110.721839) (xy 349.657403 -110.767689) (xy 349.621712 -110.80888)
			(xy 349.580521 -110.844571) (xy 349.534671 -110.874037) (xy 349.485094 -110.896679) (xy 349.432799 -110.912034)
			(xy 349.378851 -110.91979) (xy 349.324349 -110.91979) (xy 349.270401 -110.912034) (xy 349.218106 -110.896679)
			(xy 349.168529 -110.874037) (xy 349.122679 -110.844571) (xy 349.081488 -110.80888) (xy 349.045797 -110.767689)
			(xy 349.016331 -110.721839) (xy 348.993689 -110.672262) (xy 348.978334 -110.619967) (xy 348.970578 -110.566019)
			(xy 348.970092 -110.538768) (xy 348.970553 -110.510862) (xy 348.978702 -110.455648) (xy 348.994805 -110.402209)
			(xy 349.018519 -110.351685) (xy 349.04934 -110.305154) (xy 349.086609 -110.263608) (xy 349.10776 -110.245398)
			(xy 349.11665 -110.238032) (xy 349.126302 -110.217204) (xy 349.125032 -110.115096) (xy 349.114872 -110.094522)
			(xy 349.105728 -110.08741) (xy 349.083444 -110.06919) (xy 349.044037 -110.027237) (xy 349.01138 -109.979841)
			(xy 348.986215 -109.928076) (xy 348.969111 -109.873119) (xy 348.960459 -109.816215) (xy 348.959932 -109.787436)
			(xy 342.249688 -109.787436) (xy 342.218803 -109.813139) (xy 342.171197 -109.842193) (xy 342.119868 -109.864005)
			(xy 342.065911 -109.878111) (xy 342.010474 -109.884211) (xy 341.95474 -109.882174) (xy 341.899897 -109.872044)
			(xy 341.847113 -109.854037) (xy 341.797513 -109.828536) (xy 341.752155 -109.796085) (xy 341.712006 -109.757376)
			(xy 341.67792 -109.713233) (xy 341.650624 -109.664598) (xy 341.630701 -109.612507) (xy 341.618575 -109.55807)
			(xy 341.614504 -109.502448) (xy 314.714679 -109.502448) (xy 314.575618 -110.621572) (xy 322.761102 -110.621572)
			(xy 322.76155 -110.595257) (xy 322.768789 -110.543128) (xy 322.783112 -110.492485) (xy 322.804248 -110.444286)
			(xy 322.831797 -110.399443) (xy 322.865239 -110.358804) (xy 322.884292 -110.340648) (xy 322.891717 -110.333147)
			(xy 322.900228 -110.313851) (xy 322.900802 -110.30331) (xy 322.900802 -110.228634) (xy 322.900267 -110.218085)
			(xy 322.891736 -110.19879) (xy 322.884292 -110.191296) (xy 322.86524 -110.173137) (xy 322.831783 -110.132508)
			(xy 322.804224 -110.087668) (xy 322.783085 -110.039468) (xy 322.768767 -109.988821) (xy 322.761541 -109.936688)
			(xy 322.761102 -109.910372) (xy 322.761588 -109.883121) (xy 322.769344 -109.829173) (xy 322.784699 -109.776878)
			(xy 322.807341 -109.727301) (xy 322.836807 -109.681451) (xy 322.872498 -109.64026) (xy 322.913689 -109.604569)
			(xy 322.959539 -109.575103) (xy 323.009116 -109.552461) (xy 323.061411 -109.537106) (xy 323.115359 -109.52935)
			(xy 323.169861 -109.52935) (xy 323.223809 -109.537106) (xy 323.276104 -109.552461) (xy 323.325681 -109.575103)
			(xy 323.371531 -109.604569) (xy 323.412722 -109.64026) (xy 323.448413 -109.681451) (xy 323.477879 -109.727301)
			(xy 323.500521 -109.776878) (xy 323.515876 -109.829173) (xy 323.523632 -109.883121) (xy 323.524118 -109.910372)
			(xy 323.523693 -109.936687) (xy 323.516449 -109.988817) (xy 323.502121 -110.039461) (xy 323.48098 -110.087659)
			(xy 323.453427 -110.132502) (xy 323.419982 -110.17314) (xy 323.400928 -110.191296) (xy 323.39353 -110.198821)
			(xy 323.385003 -110.218098) (xy 323.384418 -110.228634) (xy 323.384418 -110.30331) (xy 323.384923 -110.313863)
			(xy 323.393475 -110.333158) (xy 323.400928 -110.340648) (xy 323.420005 -110.358782) (xy 323.453459 -110.399417)
			(xy 323.481015 -110.444262) (xy 323.502149 -110.492467) (xy 323.516462 -110.543118) (xy 323.523682 -110.595255)
			(xy 323.524118 -110.621572) (xy 323.523632 -110.648823) (xy 323.515876 -110.702771) (xy 323.500521 -110.755066)
			(xy 323.477879 -110.804643) (xy 323.448413 -110.850493) (xy 323.412722 -110.891684) (xy 323.371531 -110.927375)
			(xy 323.325681 -110.956841) (xy 323.276104 -110.979483) (xy 323.223809 -110.994838) (xy 323.169861 -111.002594)
			(xy 323.115359 -111.002594) (xy 323.061411 -110.994838) (xy 323.009116 -110.979483) (xy 322.959539 -110.956841)
			(xy 322.913689 -110.927375) (xy 322.872498 -110.891684) (xy 322.836807 -110.850493) (xy 322.807341 -110.804643)
			(xy 322.784699 -110.755066) (xy 322.769344 -110.702771) (xy 322.761588 -110.648823) (xy 322.761102 -110.621572)
			(xy 314.575618 -110.621572) (xy 314.556902 -110.772194) (xy 314.367336 -112.297972) (xy 325.26986 -112.297972)
			(xy 325.27029 -112.271657) (xy 325.277529 -112.219526) (xy 325.291855 -112.168881) (xy 325.312994 -112.120682)
			(xy 325.340548 -112.07584) (xy 325.373994 -112.035203) (xy 325.39305 -112.017048) (xy 325.400469 -112.009541)
			(xy 325.408985 -111.99025) (xy 325.40956 -111.97971) (xy 325.40956 -111.905034) (xy 325.409038 -111.894483)
			(xy 325.400499 -111.875187) (xy 325.39305 -111.867696) (xy 325.37399 -111.849545) (xy 325.340535 -111.808913)
			(xy 325.312978 -111.764072) (xy 325.291841 -111.71587) (xy 325.277524 -111.665222) (xy 325.270299 -111.613088)
			(xy 325.26986 -111.586772) (xy 325.270346 -111.559521) (xy 325.278102 -111.505573) (xy 325.293457 -111.453278)
			(xy 325.316099 -111.403701) (xy 325.345565 -111.357851) (xy 325.381256 -111.31666) (xy 325.422447 -111.280969)
			(xy 325.468297 -111.251503) (xy 325.517874 -111.228861) (xy 325.570169 -111.213506) (xy 325.624117 -111.20575)
			(xy 325.678619 -111.20575) (xy 325.732567 -111.213506) (xy 325.784862 -111.228861) (xy 325.834439 -111.251503)
			(xy 325.880289 -111.280969) (xy 325.92148 -111.31666) (xy 325.957171 -111.357851) (xy 325.986637 -111.403701)
			(xy 326.009279 -111.453278) (xy 326.024634 -111.505573) (xy 326.03239 -111.559521) (xy 326.032876 -111.586772)
			(xy 326.032464 -111.613088) (xy 326.025219 -111.665219) (xy 326.01089 -111.715863) (xy 325.989747 -111.764062)
			(xy 325.962191 -111.808904) (xy 325.928742 -111.849541) (xy 325.909686 -111.867696) (xy 325.902282 -111.875215)
			(xy 325.893759 -111.894497) (xy 325.893176 -111.905034) (xy 325.893176 -111.97971) (xy 325.893693 -111.990261)
			(xy 325.902238 -112.009556) (xy 325.909686 -112.017048) (xy 325.928755 -112.03519) (xy 325.962212 -112.075822)
			(xy 325.989769 -112.120665) (xy 326.010905 -112.168869) (xy 326.025219 -112.219519) (xy 326.03244 -112.271655)
			(xy 326.032876 -112.297972) (xy 327.30186 -112.297972) (xy 327.30229 -112.271657) (xy 327.309529 -112.219526)
			(xy 327.323855 -112.168881) (xy 327.344994 -112.120682) (xy 327.372548 -112.07584) (xy 327.405994 -112.035203)
			(xy 327.42505 -112.017048) (xy 327.432469 -112.009541) (xy 327.440985 -111.99025) (xy 327.44156 -111.97971)
			(xy 327.44156 -111.905034) (xy 327.441038 -111.894483) (xy 327.432499 -111.875187) (xy 327.42505 -111.867696)
			(xy 327.40599 -111.849545) (xy 327.372535 -111.808913) (xy 327.344978 -111.764072) (xy 327.323841 -111.71587)
			(xy 327.309524 -111.665222) (xy 327.302299 -111.613088) (xy 327.30186 -111.586772) (xy 327.302346 -111.559521)
			(xy 327.310102 -111.505573) (xy 327.325457 -111.453278) (xy 327.348099 -111.403701) (xy 327.377565 -111.357851)
			(xy 327.413256 -111.31666) (xy 327.454447 -111.280969) (xy 327.500297 -111.251503) (xy 327.549874 -111.228861)
			(xy 327.602169 -111.213506) (xy 327.656117 -111.20575) (xy 327.710619 -111.20575) (xy 327.764567 -111.213506)
			(xy 327.816862 -111.228861) (xy 327.866439 -111.251503) (xy 327.912289 -111.280969) (xy 327.95348 -111.31666)
			(xy 327.989171 -111.357851) (xy 328.018637 -111.403701) (xy 328.041279 -111.453278) (xy 328.056634 -111.505573)
			(xy 328.06439 -111.559521) (xy 328.064876 -111.586772) (xy 328.064464 -111.613088) (xy 328.057219 -111.665219)
			(xy 328.04289 -111.715863) (xy 328.021747 -111.764062) (xy 327.994191 -111.808904) (xy 327.960742 -111.849541)
			(xy 327.941686 -111.867696) (xy 327.934282 -111.875215) (xy 327.925759 -111.894497) (xy 327.925176 -111.905034)
			(xy 327.925176 -111.97971) (xy 327.925693 -111.990261) (xy 327.934238 -112.009556) (xy 327.941686 -112.017048)
			(xy 327.960755 -112.03519) (xy 327.962752 -112.037615) (xy 329.756103 -112.037615) (xy 329.760416 -111.980345)
			(xy 329.773262 -111.924368) (xy 329.79435 -111.870948) (xy 329.823205 -111.821291) (xy 329.859175 -111.776519)
			(xy 329.87996 -111.756698) (xy 329.887358 -111.749174) (xy 329.895886 -111.729896) (xy 329.89647 -111.71936)
			(xy 329.89647 -111.644684) (xy 329.895972 -111.63413) (xy 329.887416 -111.614835) (xy 329.87996 -111.607346)
			(xy 329.860878 -111.589218) (xy 329.827424 -111.548581) (xy 329.79987 -111.503735) (xy 329.778736 -111.455529)
			(xy 329.764425 -111.404877) (xy 329.757206 -111.35274) (xy 329.75677 -111.326422) (xy 329.757256 -111.299171)
			(xy 329.765012 -111.245223) (xy 329.780367 -111.192928) (xy 329.803009 -111.143351) (xy 329.832475 -111.097501)
			(xy 329.868166 -111.05631) (xy 329.909357 -111.020619) (xy 329.955207 -110.991153) (xy 330.004784 -110.968511)
			(xy 330.057079 -110.953156) (xy 330.111027 -110.9454) (xy 330.165529 -110.9454) (xy 330.219477 -110.953156)
			(xy 330.271772 -110.968511) (xy 330.321349 -110.991153) (xy 330.367199 -111.020619) (xy 330.40839 -111.05631)
			(xy 330.444081 -111.097501) (xy 330.473547 -111.143351) (xy 330.496189 -111.192928) (xy 330.511544 -111.245223)
			(xy 330.5193 -111.299171) (xy 330.519786 -111.326422) (xy 330.519338 -111.352737) (xy 330.5121 -111.404866)
			(xy 330.497777 -111.455509) (xy 330.476641 -111.503708) (xy 330.449091 -111.548551) (xy 330.415649 -111.58919)
			(xy 330.396596 -111.607346) (xy 330.389172 -111.614848) (xy 330.380661 -111.634143) (xy 330.380086 -111.644684)
			(xy 330.380086 -111.71936) (xy 330.380627 -111.729908) (xy 330.389154 -111.749203) (xy 330.396596 -111.756698)
			(xy 330.417407 -111.776495) (xy 330.453384 -111.82127) (xy 330.482245 -111.870931) (xy 330.503337 -111.924356)
			(xy 330.516186 -111.980339) (xy 330.520499 -112.037615) (xy 332.294318 -112.037615) (xy 332.298631 -111.980344)
			(xy 332.311478 -111.924367) (xy 332.332567 -111.870947) (xy 332.361424 -111.82129) (xy 332.397396 -111.776518)
			(xy 332.418182 -111.756698) (xy 332.425584 -111.749177) (xy 332.434109 -111.729897) (xy 332.434692 -111.71936)
			(xy 332.434692 -111.644684) (xy 332.434188 -111.634131) (xy 332.425635 -111.614836) (xy 332.418182 -111.607346)
			(xy 332.399104 -111.589213) (xy 332.365649 -111.548578) (xy 332.338094 -111.503733) (xy 332.316959 -111.455528)
			(xy 332.302647 -111.404877) (xy 332.295428 -111.352739) (xy 332.294992 -111.326422) (xy 332.295478 -111.299171)
			(xy 332.303234 -111.245223) (xy 332.318589 -111.192928) (xy 332.341231 -111.143351) (xy 332.370697 -111.097501)
			(xy 332.406388 -111.05631) (xy 332.447579 -111.020619) (xy 332.493429 -110.991153) (xy 332.543006 -110.968511)
			(xy 332.595301 -110.953156) (xy 332.649249 -110.9454) (xy 332.703751 -110.9454) (xy 332.757699 -110.953156)
			(xy 332.809994 -110.968511) (xy 332.859571 -110.991153) (xy 332.905421 -111.020619) (xy 332.946612 -111.05631)
			(xy 332.982303 -111.097501) (xy 333.011769 -111.143351) (xy 333.034411 -111.192928) (xy 333.049766 -111.245223)
			(xy 333.057522 -111.299171) (xy 333.058008 -111.326422) (xy 333.057553 -111.352736) (xy 333.050315 -111.404865)
			(xy 333.035993 -111.455508) (xy 333.014859 -111.503707) (xy 332.987311 -111.54855) (xy 332.95387 -111.58919)
			(xy 332.934818 -111.607346) (xy 332.927397 -111.614851) (xy 332.918883 -111.634144) (xy 332.918308 -111.644684)
			(xy 332.918308 -111.71936) (xy 332.918843 -111.729909) (xy 332.927374 -111.749205) (xy 332.934818 -111.756698)
			(xy 332.955628 -111.776496) (xy 332.991603 -111.821272) (xy 333.020462 -111.870933) (xy 333.041553 -111.924357)
			(xy 333.054401 -111.98034) (xy 333.055424 -111.993923) (xy 336.497253 -111.993923) (xy 336.501565 -111.936653)
			(xy 336.514411 -111.880675) (xy 336.535502 -111.827255) (xy 336.564359 -111.777599) (xy 336.600333 -111.732829)
			(xy 336.62112 -111.71301) (xy 336.628522 -111.705489) (xy 336.637046 -111.686208) (xy 336.63763 -111.675672)
			(xy 336.63763 -111.600996) (xy 336.637108 -111.590446) (xy 336.628567 -111.571151) (xy 336.62112 -111.563658)
			(xy 336.600364 -111.543805) (xy 336.564385 -111.499039) (xy 336.535522 -111.449386) (xy 336.514425 -111.395969)
			(xy 336.501572 -111.339993) (xy 336.497253 -111.282723) (xy 336.501565 -111.225453) (xy 336.514411 -111.169475)
			(xy 336.535502 -111.116055) (xy 336.564359 -111.066399) (xy 336.600333 -111.021629) (xy 336.62112 -111.00181)
			(xy 336.628522 -110.994289) (xy 336.637046 -110.975008) (xy 336.63763 -110.964472) (xy 336.63763 -110.889796)
			(xy 336.637108 -110.879246) (xy 336.628567 -110.859951) (xy 336.62112 -110.852458) (xy 336.602055 -110.834312)
			(xy 336.568598 -110.793681) (xy 336.54104 -110.748839) (xy 336.519903 -110.700636) (xy 336.505588 -110.649986)
			(xy 336.498366 -110.597851) (xy 336.49793 -110.571534) (xy 336.498387 -110.54428) (xy 336.50614 -110.490327)
			(xy 336.521494 -110.438027) (xy 336.544135 -110.388444) (xy 336.573603 -110.342589) (xy 336.609298 -110.301395)
			(xy 336.650492 -110.265701) (xy 336.696348 -110.236233) (xy 336.745931 -110.213593) (xy 336.798231 -110.19824)
			(xy 336.852184 -110.190487) (xy 336.879438 -110.190026) (xy 336.905753 -110.19046) (xy 336.957884 -110.1977)
			(xy 337.008527 -110.212025) (xy 337.056726 -110.233164) (xy 337.101569 -110.260717) (xy 337.142207 -110.294161)
			(xy 337.160362 -110.313216) (xy 337.167894 -110.320605) (xy 337.187166 -110.329136) (xy 337.1977 -110.329726)
			(xy 337.272376 -110.329726) (xy 337.282925 -110.32919) (xy 337.30222 -110.320659) (xy 337.309714 -110.313216)
			(xy 337.327873 -110.294164) (xy 337.368502 -110.260706) (xy 337.413341 -110.233146) (xy 337.461541 -110.212007)
			(xy 337.512188 -110.197689) (xy 337.564322 -110.190464) (xy 337.590638 -110.190026) (xy 337.617892 -110.190443)
			(xy 337.671844 -110.198205) (xy 337.724142 -110.213567) (xy 337.773721 -110.236215) (xy 337.813342 -110.261683)
			(xy 339.114448 -110.261683) (xy 339.114448 -110.209717) (xy 339.122577 -110.158392) (xy 339.138635 -110.108969)
			(xy 339.162226 -110.062667) (xy 339.192769 -110.020626) (xy 339.229514 -109.98388) (xy 339.271554 -109.953334)
			(xy 339.317854 -109.929741) (xy 339.367276 -109.913681) (xy 339.418601 -109.905549) (xy 339.444584 -109.905038)
			(xy 339.47123 -109.905495) (xy 339.523833 -109.914032) (xy 339.574384 -109.930903) (xy 339.62157 -109.955671)
			(xy 339.664168 -109.987694) (xy 339.701072 -110.026139) (xy 339.716618 -110.047786) (xy 339.724982 -110.059072)
			(xy 339.746655 -110.076927) (xy 339.772369 -110.08821) (xy 339.800184 -110.092068) (xy 339.827999 -110.08821)
			(xy 339.853713 -110.076927) (xy 339.875386 -110.059072) (xy 339.88375 -110.047786) (xy 339.899313 -110.026158)
			(xy 339.936232 -109.987742) (xy 339.978833 -109.955743) (xy 340.026014 -109.930989) (xy 340.076553 -109.91412)
			(xy 340.129144 -109.905574) (xy 340.155784 -109.905038) (xy 340.181778 -109.905428) (xy 340.233125 -109.913558)
			(xy 340.282569 -109.929622) (xy 340.328891 -109.953222) (xy 340.37095 -109.983778) (xy 340.407712 -110.020538)
			(xy 340.43827 -110.062596) (xy 340.461872 -110.108916) (xy 340.477938 -110.158359) (xy 340.486071 -110.209706)
			(xy 340.486071 -110.261694) (xy 340.477938 -110.313041) (xy 340.461872 -110.362484) (xy 340.43827 -110.408804)
			(xy 340.407712 -110.450862) (xy 340.37095 -110.487622) (xy 340.332365 -110.515654) (xy 343.028014 -110.515654)
			(xy 343.032085 -110.460032) (xy 343.044211 -110.405595) (xy 343.064134 -110.353504) (xy 343.09143 -110.304869)
			(xy 343.125516 -110.260726) (xy 343.165665 -110.222017) (xy 343.211023 -110.189566) (xy 343.260623 -110.164065)
			(xy 343.313407 -110.146058) (xy 343.36825 -110.135928) (xy 343.423984 -110.133891) (xy 343.479421 -110.139991)
			(xy 343.533378 -110.154097) (xy 343.584707 -110.175909) (xy 343.632313 -110.204963) (xy 343.675181 -110.240638)
			(xy 343.712398 -110.282175) (xy 343.743171 -110.328688) (xy 343.766843 -110.379185) (xy 343.782911 -110.432592)
			(xy 343.791031 -110.487768) (xy 343.79154 -110.515654) (xy 343.791031 -110.54354) (xy 343.782911 -110.598716)
			(xy 343.766843 -110.652123) (xy 343.743171 -110.70262) (xy 343.712398 -110.749133) (xy 343.675181 -110.79067)
			(xy 343.632313 -110.826345) (xy 343.584707 -110.855399) (xy 343.533378 -110.877211) (xy 343.479421 -110.891317)
			(xy 343.423984 -110.897417) (xy 343.36825 -110.89538) (xy 343.313407 -110.88525) (xy 343.260623 -110.867243)
			(xy 343.211023 -110.841742) (xy 343.165665 -110.809291) (xy 343.125516 -110.770582) (xy 343.09143 -110.726439)
			(xy 343.064134 -110.677804) (xy 343.044211 -110.625713) (xy 343.032085 -110.571276) (xy 343.028014 -110.515654)
			(xy 340.332365 -110.515654) (xy 340.328891 -110.518178) (xy 340.282569 -110.541778) (xy 340.233125 -110.557842)
			(xy 340.181778 -110.565972) (xy 340.155784 -110.566454) (xy 340.12914 -110.56595) (xy 340.076539 -110.557423)
			(xy 340.025989 -110.540562) (xy 339.978802 -110.515803) (xy 339.936203 -110.483788) (xy 339.899297 -110.44535)
			(xy 339.88375 -110.423706) (xy 339.875386 -110.41242) (xy 339.853713 -110.394565) (xy 339.827999 -110.383282)
			(xy 339.800184 -110.379424) (xy 339.772369 -110.383282) (xy 339.746655 -110.394565) (xy 339.724982 -110.41242)
			(xy 339.716618 -110.423706) (xy 339.701011 -110.4453) (xy 339.664101 -110.483718) (xy 339.621509 -110.515721)
			(xy 339.574337 -110.540481) (xy 339.523805 -110.557357) (xy 339.471222 -110.565912) (xy 339.444584 -110.566454)
			(xy 339.418601 -110.565851) (xy 339.367276 -110.557719) (xy 339.317854 -110.541659) (xy 339.271554 -110.518066)
			(xy 339.229514 -110.48752) (xy 339.192769 -110.450774) (xy 339.162226 -110.408733) (xy 339.138635 -110.362431)
			(xy 339.122577 -110.313008) (xy 339.114448 -110.261683) (xy 337.813342 -110.261683) (xy 337.819573 -110.265688)
			(xy 337.860764 -110.301387) (xy 337.896455 -110.342584) (xy 337.92592 -110.388442) (xy 337.948558 -110.438026)
			(xy 337.96391 -110.490327) (xy 337.971663 -110.54428) (xy 337.972146 -110.571534) (xy 337.971718 -110.59785)
			(xy 337.964478 -110.64998) (xy 337.950152 -110.700625) (xy 337.929012 -110.748824) (xy 337.901458 -110.793666)
			(xy 337.868012 -110.834303) (xy 337.848956 -110.852458) (xy 337.841579 -110.860001) (xy 337.833039 -110.879264)
			(xy 337.832446 -110.889796) (xy 337.832446 -110.964472) (xy 337.832963 -110.975023) (xy 337.841505 -110.994319)
			(xy 337.848956 -111.00181) (xy 337.869776 -111.021597) (xy 337.905747 -111.066376) (xy 337.934603 -111.116039)
			(xy 337.9527 -111.161885) (xy 339.114423 -111.161885) (xy 339.114423 -111.109915) (xy 339.122553 -111.058586)
			(xy 339.138612 -111.00916) (xy 339.162205 -110.962855) (xy 339.192751 -110.92081) (xy 339.229498 -110.884061)
			(xy 339.271541 -110.853513) (xy 339.317845 -110.829918) (xy 339.36727 -110.813857) (xy 339.418599 -110.805725)
			(xy 339.444584 -110.805214) (xy 339.471229 -110.805681) (xy 339.523832 -110.814218) (xy 339.574382 -110.831088)
			(xy 339.621568 -110.855854) (xy 339.664166 -110.887874) (xy 339.701071 -110.926316) (xy 339.716618 -110.947962)
			(xy 339.724982 -110.959248) (xy 339.746655 -110.977103) (xy 339.772369 -110.988386) (xy 339.800184 -110.992244)
			(xy 339.827999 -110.988386) (xy 339.853713 -110.977103) (xy 339.875386 -110.959248) (xy 339.88375 -110.947962)
			(xy 339.899306 -110.926329) (xy 339.936227 -110.887914) (xy 339.97883 -110.855916) (xy 340.026012 -110.831163)
			(xy 340.076552 -110.814296) (xy 340.129144 -110.80575) (xy 340.155784 -110.805214) (xy 340.181776 -110.805652)
			(xy 340.23312 -110.813782) (xy 340.28256 -110.829844) (xy 340.328878 -110.853442) (xy 340.370935 -110.883996)
			(xy 340.407693 -110.920753) (xy 340.438249 -110.962808) (xy 340.46185 -111.009126) (xy 340.477914 -111.058565)
			(xy 340.486047 -111.109908) (xy 340.486047 -111.161892) (xy 340.477914 -111.213235) (xy 340.46185 -111.262674)
			(xy 340.438249 -111.308992) (xy 340.407693 -111.351047) (xy 340.370935 -111.387804) (xy 340.328878 -111.418358)
			(xy 340.28256 -111.441956) (xy 340.23312 -111.458018) (xy 340.181776 -111.466148) (xy 340.155784 -111.46663)
			(xy 340.129139 -111.466136) (xy 340.076537 -111.457609) (xy 340.025987 -111.440746) (xy 339.9788 -111.415985)
			(xy 339.936201 -111.383968) (xy 339.899296 -111.345527) (xy 339.88375 -111.323882) (xy 339.875386 -111.312596)
			(xy 339.853713 -111.294741) (xy 339.827999 -111.283458) (xy 339.800184 -111.2796) (xy 339.772369 -111.283458)
			(xy 339.746655 -111.294741) (xy 339.724982 -111.312596) (xy 339.716618 -111.323882) (xy 339.701033 -111.345493)
			(xy 339.664116 -111.383906) (xy 339.621519 -111.415905) (xy 339.574343 -111.440661) (xy 339.523808 -111.457534)
			(xy 339.471222 -111.466088) (xy 339.444584 -111.46663) (xy 339.418599 -111.466075) (xy 339.36727 -111.457943)
			(xy 339.317845 -111.441882) (xy 339.271541 -111.418287) (xy 339.229498 -111.387739) (xy 339.192751 -111.35099)
			(xy 339.162205 -111.308945) (xy 339.138612 -111.26264) (xy 339.122553 -111.213214) (xy 339.114423 -111.161885)
			(xy 337.9527 -111.161885) (xy 337.955692 -111.169465) (xy 337.968537 -111.225448) (xy 337.972849 -111.282723)
			(xy 337.96853 -111.339998) (xy 337.955678 -111.395979) (xy 337.934583 -111.449403) (xy 337.905721 -111.499063)
			(xy 337.869745 -111.543837) (xy 337.848956 -111.563658) (xy 337.841579 -111.571201) (xy 337.833039 -111.590464)
			(xy 337.832446 -111.600996) (xy 337.832446 -111.675672) (xy 337.832963 -111.686223) (xy 337.841505 -111.705519)
			(xy 337.848956 -111.71301) (xy 337.869776 -111.732797) (xy 337.905747 -111.777576) (xy 337.934603 -111.827239)
			(xy 337.955692 -111.880665) (xy 337.968537 -111.936648) (xy 337.972849 -111.993923) (xy 337.96853 -112.051198)
			(xy 337.9661 -112.061783) (xy 339.114446 -112.061783) (xy 339.114446 -112.009817) (xy 339.122575 -111.958491)
			(xy 339.138633 -111.909069) (xy 339.162224 -111.862766) (xy 339.192768 -111.820725) (xy 339.229512 -111.783978)
			(xy 339.271553 -111.753432) (xy 339.317854 -111.729839) (xy 339.367275 -111.713779) (xy 339.418601 -111.705647)
			(xy 339.444584 -111.705136) (xy 339.47123 -111.705594) (xy 339.523833 -111.714131) (xy 339.574384 -111.731002)
			(xy 339.62157 -111.75577) (xy 339.664168 -111.787792) (xy 339.701072 -111.826237) (xy 339.716618 -111.847884)
			(xy 339.724982 -111.85917) (xy 339.746655 -111.877025) (xy 339.772369 -111.888308) (xy 339.800184 -111.892166)
			(xy 339.827999 -111.888308) (xy 339.853713 -111.877025) (xy 339.875386 -111.85917) (xy 339.88375 -111.847884)
			(xy 339.899312 -111.826256) (xy 339.936231 -111.78784) (xy 339.978832 -111.755841) (xy 340.026013 -111.731087)
			(xy 340.076553 -111.714218) (xy 340.129144 -111.705672) (xy 340.155784 -111.705136) (xy 340.181778 -111.70553)
			(xy 340.233125 -111.71366) (xy 340.282568 -111.729723) (xy 340.32889 -111.753323) (xy 340.370949 -111.783879)
			(xy 340.372724 -111.785654) (xy 341.657684 -111.785654) (xy 341.661755 -111.730032) (xy 341.673881 -111.675595)
			(xy 341.693804 -111.623504) (xy 341.7211 -111.574869) (xy 341.755186 -111.530726) (xy 341.795335 -111.492017)
			(xy 341.840693 -111.459566) (xy 341.890293 -111.434065) (xy 341.943077 -111.416058) (xy 341.99792 -111.405928)
			(xy 342.053654 -111.403891) (xy 342.109091 -111.409991) (xy 342.163048 -111.424097) (xy 342.214377 -111.445909)
			(xy 342.261983 -111.474963) (xy 342.304851 -111.510638) (xy 342.342068 -111.552175) (xy 342.372841 -111.598688)
			(xy 342.396513 -111.649185) (xy 342.412581 -111.702592) (xy 342.418002 -111.739426) (xy 359.765344 -111.739426)
			(xy 359.769415 -111.683804) (xy 359.781541 -111.629367) (xy 359.801464 -111.577276) (xy 359.82876 -111.528641)
			(xy 359.862846 -111.484498) (xy 359.902995 -111.445789) (xy 359.948353 -111.413338) (xy 359.997953 -111.387837)
			(xy 360.050737 -111.36983) (xy 360.10558 -111.3597) (xy 360.161314 -111.357663) (xy 360.216751 -111.363763)
			(xy 360.270708 -111.377869) (xy 360.322037 -111.399681) (xy 360.369643 -111.428735) (xy 360.412511 -111.46441)
			(xy 360.449728 -111.505947) (xy 360.480501 -111.55246) (xy 360.504173 -111.602957) (xy 360.520241 -111.656364)
			(xy 360.528361 -111.71154) (xy 360.52887 -111.739426) (xy 360.528361 -111.767312) (xy 360.520241 -111.822488)
			(xy 360.504173 -111.875895) (xy 360.480501 -111.926392) (xy 360.449728 -111.972905) (xy 360.412511 -112.014442)
			(xy 360.369643 -112.050117) (xy 360.322037 -112.079171) (xy 360.270708 -112.100983) (xy 360.216751 -112.115089)
			(xy 360.161314 -112.121189) (xy 360.10558 -112.119152) (xy 360.050737 -112.109022) (xy 359.997953 -112.091015)
			(xy 359.948353 -112.065514) (xy 359.902995 -112.033063) (xy 359.862846 -111.994354) (xy 359.82876 -111.950211)
			(xy 359.801464 -111.901576) (xy 359.781541 -111.849485) (xy 359.769415 -111.795048) (xy 359.765344 -111.739426)
			(xy 342.418002 -111.739426) (xy 342.420701 -111.757768) (xy 342.42121 -111.785654) (xy 342.420701 -111.81354)
			(xy 342.412581 -111.868716) (xy 342.396513 -111.922123) (xy 342.372841 -111.97262) (xy 342.342068 -112.019133)
			(xy 342.304851 -112.06067) (xy 342.261983 -112.096345) (xy 342.214377 -112.125399) (xy 342.163048 -112.147211)
			(xy 342.109091 -112.161317) (xy 342.053654 -112.167417) (xy 341.99792 -112.16538) (xy 341.943077 -112.15525)
			(xy 341.890293 -112.137243) (xy 341.840693 -112.111742) (xy 341.795335 -112.079291) (xy 341.755186 -112.040582)
			(xy 341.7211 -111.996439) (xy 341.693804 -111.947804) (xy 341.673881 -111.895713) (xy 341.661755 -111.841276)
			(xy 341.657684 -111.785654) (xy 340.372724 -111.785654) (xy 340.40771 -111.820639) (xy 340.438268 -111.862697)
			(xy 340.461871 -111.909017) (xy 340.477936 -111.95846) (xy 340.486069 -112.009806) (xy 340.486069 -112.061794)
			(xy 340.477936 -112.11314) (xy 340.461871 -112.162583) (xy 340.438268 -112.208903) (xy 340.40771 -112.250961)
			(xy 340.370949 -112.287721) (xy 340.358237 -112.296956) (xy 343.094816 -112.296956) (xy 343.098887 -112.241334)
			(xy 343.111013 -112.186897) (xy 343.130936 -112.134806) (xy 343.158232 -112.086171) (xy 343.192318 -112.042028)
			(xy 343.232467 -112.003319) (xy 343.277825 -111.970868) (xy 343.327425 -111.945367) (xy 343.380209 -111.92736)
			(xy 343.435052 -111.91723) (xy 343.490786 -111.915193) (xy 343.546223 -111.921293) (xy 343.60018 -111.935399)
			(xy 343.651509 -111.957211) (xy 343.699115 -111.986265) (xy 343.741983 -112.02194) (xy 343.7792 -112.063477)
			(xy 343.809973 -112.10999) (xy 343.833645 -112.160487) (xy 343.849713 -112.213894) (xy 343.857833 -112.26907)
			(xy 343.858342 -112.296956) (xy 343.857833 -112.324842) (xy 343.849713 -112.380018) (xy 343.833645 -112.433425)
			(xy 343.809973 -112.483922) (xy 343.7792 -112.530435) (xy 343.770599 -112.540034) (xy 362.1057 -112.540034)
			(xy 362.109771 -112.484412) (xy 362.121897 -112.429975) (xy 362.14182 -112.377884) (xy 362.169116 -112.329249)
			(xy 362.203202 -112.285106) (xy 362.243351 -112.246397) (xy 362.288709 -112.213946) (xy 362.338309 -112.188445)
			(xy 362.391093 -112.170438) (xy 362.445936 -112.160308) (xy 362.50167 -112.158271) (xy 362.557107 -112.164371)
			(xy 362.611064 -112.178477) (xy 362.662393 -112.200289) (xy 362.709999 -112.229343) (xy 362.752867 -112.265018)
			(xy 362.790084 -112.306555) (xy 362.820857 -112.353068) (xy 362.844529 -112.403565) (xy 362.849823 -112.421162)
			(xy 364.10722 -112.421162) (xy 364.111291 -112.36554) (xy 364.123417 -112.311103) (xy 364.14334 -112.259012)
			(xy 364.170636 -112.210377) (xy 364.204722 -112.166234) (xy 364.244871 -112.127525) (xy 364.290229 -112.095074)
			(xy 364.339829 -112.069573) (xy 364.392613 -112.051566) (xy 364.447456 -112.041436) (xy 364.50319 -112.039399)
			(xy 364.558627 -112.045499) (xy 364.612584 -112.059605) (xy 364.663913 -112.081417) (xy 364.711519 -112.110471)
			(xy 364.754387 -112.146146) (xy 364.791604 -112.187683) (xy 364.822377 -112.234196) (xy 364.846049 -112.284693)
			(xy 364.862117 -112.3381) (xy 364.870237 -112.393276) (xy 364.870746 -112.421162) (xy 364.870237 -112.449048)
			(xy 364.862117 -112.504224) (xy 364.846049 -112.557631) (xy 364.822377 -112.608128) (xy 364.791604 -112.654641)
			(xy 364.754387 -112.696178) (xy 364.711519 -112.731853) (xy 364.663913 -112.760907) (xy 364.612584 -112.782719)
			(xy 364.558627 -112.796825) (xy 364.50319 -112.802925) (xy 364.447456 -112.800888) (xy 364.392613 -112.790758)
			(xy 364.339829 -112.772751) (xy 364.290229 -112.74725) (xy 364.244871 -112.714799) (xy 364.204722 -112.67609)
			(xy 364.170636 -112.631947) (xy 364.14334 -112.583312) (xy 364.123417 -112.531221) (xy 364.111291 -112.476784)
			(xy 364.10722 -112.421162) (xy 362.849823 -112.421162) (xy 362.860597 -112.456972) (xy 362.868717 -112.512148)
			(xy 362.869226 -112.540034) (xy 362.868717 -112.56792) (xy 362.860597 -112.623096) (xy 362.844529 -112.676503)
			(xy 362.820857 -112.727) (xy 362.790084 -112.773513) (xy 362.752867 -112.81505) (xy 362.709999 -112.850725)
			(xy 362.662393 -112.879779) (xy 362.611064 -112.901591) (xy 362.557107 -112.915697) (xy 362.50167 -112.921797)
			(xy 362.445936 -112.91976) (xy 362.391093 -112.90963) (xy 362.338309 -112.891623) (xy 362.288709 -112.866122)
			(xy 362.243351 -112.833671) (xy 362.203202 -112.794962) (xy 362.169116 -112.750819) (xy 362.14182 -112.702184)
			(xy 362.121897 -112.650093) (xy 362.109771 -112.595656) (xy 362.1057 -112.540034) (xy 343.770599 -112.540034)
			(xy 343.741983 -112.571972) (xy 343.699115 -112.607647) (xy 343.651509 -112.636701) (xy 343.60018 -112.658513)
			(xy 343.546223 -112.672619) (xy 343.490786 -112.678719) (xy 343.435052 -112.676682) (xy 343.380209 -112.666552)
			(xy 343.327425 -112.648545) (xy 343.277825 -112.623044) (xy 343.232467 -112.590593) (xy 343.192318 -112.551884)
			(xy 343.158232 -112.507741) (xy 343.130936 -112.459106) (xy 343.111013 -112.407015) (xy 343.098887 -112.352578)
			(xy 343.094816 -112.296956) (xy 340.358237 -112.296956) (xy 340.32889 -112.318277) (xy 340.282568 -112.341877)
			(xy 340.233125 -112.35794) (xy 340.181778 -112.36607) (xy 340.155784 -112.366552) (xy 340.12914 -112.366049)
			(xy 340.076538 -112.357522) (xy 340.025989 -112.34066) (xy 339.978802 -112.315901) (xy 339.936203 -112.283887)
			(xy 339.899297 -112.245448) (xy 339.88375 -112.223804) (xy 339.875386 -112.212518) (xy 339.853713 -112.194663)
			(xy 339.827999 -112.18338) (xy 339.800184 -112.179522) (xy 339.772369 -112.18338) (xy 339.746655 -112.194663)
			(xy 339.724982 -112.212518) (xy 339.716618 -112.223804) (xy 339.70101 -112.245398) (xy 339.664101 -112.283816)
			(xy 339.621509 -112.315819) (xy 339.574337 -112.340579) (xy 339.523805 -112.357455) (xy 339.471221 -112.36601)
			(xy 339.444584 -112.366552) (xy 339.418601 -112.365953) (xy 339.367275 -112.357821) (xy 339.317854 -112.341761)
			(xy 339.271553 -112.318168) (xy 339.229512 -112.287622) (xy 339.192768 -112.250875) (xy 339.162224 -112.208834)
			(xy 339.138633 -112.162531) (xy 339.122575 -112.113109) (xy 339.114446 -112.061783) (xy 337.9661 -112.061783)
			(xy 337.955678 -112.107179) (xy 337.934583 -112.160603) (xy 337.905721 -112.210263) (xy 337.869745 -112.255037)
			(xy 337.848956 -112.274858) (xy 337.841579 -112.282401) (xy 337.833039 -112.301664) (xy 337.832446 -112.312196)
			(xy 337.832446 -112.386872) (xy 337.832963 -112.397423) (xy 337.841505 -112.416719) (xy 337.848956 -112.42421)
			(xy 337.86802 -112.442357) (xy 337.901474 -112.48299) (xy 337.929031 -112.527832) (xy 337.950167 -112.576034)
			(xy 337.964483 -112.626683) (xy 337.971708 -112.678818) (xy 337.972146 -112.705134) (xy 337.971654 -112.732384)
			(xy 337.963894 -112.78633) (xy 337.948536 -112.838622) (xy 337.925894 -112.888197) (xy 337.896428 -112.934045)
			(xy 337.872387 -112.961789) (xy 339.114368 -112.961789) (xy 339.114368 -112.909811) (xy 339.122498 -112.858473)
			(xy 339.13856 -112.809038) (xy 339.162157 -112.762725) (xy 339.192708 -112.720674) (xy 339.229461 -112.683919)
			(xy 339.271512 -112.653365) (xy 339.317824 -112.629766) (xy 339.367257 -112.613702) (xy 339.418595 -112.605569)
			(xy 339.444584 -112.605058) (xy 339.47123 -112.605507) (xy 339.523835 -112.614044) (xy 339.574386 -112.630917)
			(xy 339.621572 -112.655686) (xy 339.66417 -112.68771) (xy 339.701073 -112.726158) (xy 339.716618 -112.747806)
			(xy 339.724982 -112.759092) (xy 339.746655 -112.776947) (xy 339.772369 -112.78823) (xy 339.800184 -112.792088)
			(xy 339.827999 -112.78823) (xy 339.853713 -112.776947) (xy 339.875386 -112.759092) (xy 339.88375 -112.747806)
			(xy 339.899289 -112.726161) (xy 339.936216 -112.687749) (xy 339.978822 -112.655755) (xy 340.026008 -112.631004)
			(xy 340.07655 -112.614139) (xy 340.129143 -112.605594) (xy 340.155784 -112.605058) (xy 340.181771 -112.605608)
			(xy 340.233107 -112.613736) (xy 340.282538 -112.629795) (xy 340.328849 -112.65339) (xy 340.370898 -112.683939)
			(xy 340.407651 -112.72069) (xy 340.438202 -112.762737) (xy 340.461798 -112.809047) (xy 340.47786 -112.858478)
			(xy 340.485991 -112.909813) (xy 340.485991 -112.961787) (xy 340.47786 -113.013122) (xy 340.461798 -113.062553)
			(xy 340.438202 -113.108863) (xy 340.407651 -113.15091) (xy 340.370898 -113.187661) (xy 340.328849 -113.21821)
			(xy 340.282538 -113.241805) (xy 340.233107 -113.257864) (xy 340.181771 -113.265992) (xy 340.155784 -113.266474)
			(xy 340.12914 -113.265961) (xy 340.07654 -113.257435) (xy 340.025991 -113.240575) (xy 339.978804 -113.215817)
			(xy 339.936205 -113.183805) (xy 339.899297 -113.145369) (xy 339.88375 -113.123726) (xy 339.875386 -113.11244)
			(xy 339.853713 -113.094585) (xy 339.827999 -113.083302) (xy 339.800184 -113.079444) (xy 339.772369 -113.083302)
			(xy 339.746655 -113.094585) (xy 339.724982 -113.11244) (xy 339.716618 -113.123726) (xy 339.701017 -113.145325)
			(xy 339.664105 -113.183741) (xy 339.621512 -113.215743) (xy 339.574339 -113.240502) (xy 339.523806 -113.257377)
			(xy 339.471222 -113.265932) (xy 339.444584 -113.266474) (xy 339.418595 -113.266031) (xy 339.367257 -113.257898)
			(xy 339.317824 -113.241834) (xy 339.271512 -113.218235) (xy 339.229461 -113.187681) (xy 339.192708 -113.150926)
			(xy 339.162157 -113.108875) (xy 339.13856 -113.062562) (xy 339.122498 -113.013127) (xy 339.114368 -112.961789)
			(xy 337.872387 -112.961789) (xy 337.860737 -112.975234) (xy 337.819549 -113.010925) (xy 337.773701 -113.040392)
			(xy 337.724126 -113.063035) (xy 337.671834 -113.078393) (xy 337.617888 -113.086154) (xy 337.590638 -113.086642)
			(xy 337.564322 -113.086234) (xy 337.51219 -113.07899) (xy 337.461545 -113.06466) (xy 337.413346 -113.043517)
			(xy 337.368504 -113.015959) (xy 337.327868 -112.982509) (xy 337.309714 -112.963452) (xy 337.302182 -112.956062)
			(xy 337.28291 -112.947529) (xy 337.272376 -112.946942) (xy 337.1977 -112.946942) (xy 337.187147 -112.947445)
			(xy 337.167851 -112.955997) (xy 337.160362 -112.963452) (xy 337.142228 -112.982529) (xy 337.101593 -113.015982)
			(xy 337.056747 -113.043537) (xy 337.008543 -113.064671) (xy 336.957892 -113.078985) (xy 336.905755 -113.086205)
			(xy 336.879438 -113.086642) (xy 336.852188 -113.086109) (xy 336.798241 -113.078359) (xy 336.745946 -113.063009)
			(xy 336.696369 -113.040373) (xy 336.650517 -113.010913) (xy 336.609325 -112.975226) (xy 336.573631 -112.934041)
			(xy 336.544161 -112.888195) (xy 336.521516 -112.838621) (xy 336.506157 -112.786329) (xy 336.498396 -112.732384)
			(xy 336.49793 -112.705134) (xy 336.498344 -112.678818) (xy 336.505588 -112.626687) (xy 336.519917 -112.576043)
			(xy 336.54106 -112.527844) (xy 336.568616 -112.483002) (xy 336.602064 -112.442365) (xy 336.62112 -112.42421)
			(xy 336.628522 -112.416689) (xy 336.637046 -112.397408) (xy 336.63763 -112.386872) (xy 336.63763 -112.312196)
			(xy 336.637108 -112.301646) (xy 336.628567 -112.282351) (xy 336.62112 -112.274858) (xy 336.600364 -112.255005)
			(xy 336.564385 -112.210239) (xy 336.535522 -112.160586) (xy 336.514425 -112.107169) (xy 336.501572 -112.051193)
			(xy 336.497253 -111.993923) (xy 333.055424 -111.993923) (xy 333.058714 -112.037615) (xy 333.054396 -112.09489)
			(xy 333.041544 -112.150871) (xy 333.020449 -112.204294) (xy 332.991586 -112.253953) (xy 332.955607 -112.298726)
			(xy 332.934818 -112.318546) (xy 332.927397 -112.326051) (xy 332.918883 -112.345344) (xy 332.918308 -112.355884)
			(xy 332.918308 -112.43056) (xy 332.918843 -112.441109) (xy 332.927374 -112.460405) (xy 332.934818 -112.467898)
			(xy 332.953869 -112.486058) (xy 332.987326 -112.526687) (xy 333.014885 -112.571527) (xy 333.036024 -112.619726)
			(xy 333.050343 -112.670373) (xy 333.057569 -112.722506) (xy 333.058008 -112.748822) (xy 333.057522 -112.776073)
			(xy 333.049766 -112.830021) (xy 333.034411 -112.882316) (xy 333.011769 -112.931893) (xy 332.982303 -112.977743)
			(xy 332.946612 -113.018934) (xy 332.905421 -113.054625) (xy 332.859571 -113.084091) (xy 332.809994 -113.106733)
			(xy 332.757699 -113.122088) (xy 332.703751 -113.129844) (xy 332.649249 -113.129844) (xy 332.595301 -113.122088)
			(xy 332.543006 -113.106733) (xy 332.493429 -113.084091) (xy 332.447579 -113.054625) (xy 332.406388 -113.018934)
			(xy 332.370697 -112.977743) (xy 332.341231 -112.931893) (xy 332.318589 -112.882316) (xy 332.303234 -112.830021)
			(xy 332.295478 -112.776073) (xy 332.294992 -112.748822) (xy 332.295477 -112.722509) (xy 332.302708 -112.670381)
			(xy 332.317024 -112.619739) (xy 332.338153 -112.57154) (xy 332.365696 -112.526696) (xy 332.399132 -112.486055)
			(xy 332.418182 -112.467898) (xy 332.425584 -112.460377) (xy 332.434109 -112.441097) (xy 332.434692 -112.43056)
			(xy 332.434692 -112.355884) (xy 332.434188 -112.345331) (xy 332.425635 -112.326036) (xy 332.418182 -112.318546)
			(xy 332.397416 -112.298704) (xy 332.361441 -112.253935) (xy 332.33258 -112.20428) (xy 332.311487 -112.150861)
			(xy 332.298636 -112.094885) (xy 332.294318 -112.037615) (xy 330.520499 -112.037615) (xy 330.516181 -112.094891)
			(xy 330.503328 -112.150872) (xy 330.482232 -112.204296) (xy 330.453367 -112.253954) (xy 330.417387 -112.298727)
			(xy 330.396596 -112.318546) (xy 330.389172 -112.326048) (xy 330.380661 -112.345343) (xy 330.380086 -112.355884)
			(xy 330.380086 -112.43056) (xy 330.380627 -112.441108) (xy 330.389154 -112.460403) (xy 330.396596 -112.467898)
			(xy 330.415643 -112.486062) (xy 330.449101 -112.52669) (xy 330.476661 -112.571528) (xy 330.497801 -112.619728)
			(xy 330.51212 -112.670374) (xy 330.519347 -112.722506) (xy 330.519786 -112.748822) (xy 330.5193 -112.776073)
			(xy 330.511544 -112.830021) (xy 330.496189 -112.882316) (xy 330.473547 -112.931893) (xy 330.444081 -112.977743)
			(xy 330.40839 -113.018934) (xy 330.367199 -113.054625) (xy 330.321349 -113.084091) (xy 330.271772 -113.106733)
			(xy 330.219477 -113.122088) (xy 330.165529 -113.129844) (xy 330.111027 -113.129844) (xy 330.057079 -113.122088)
			(xy 330.004784 -113.106733) (xy 329.955207 -113.084091) (xy 329.909357 -113.054625) (xy 329.868166 -113.018934)
			(xy 329.832475 -112.977743) (xy 329.803009 -112.931893) (xy 329.780367 -112.882316) (xy 329.765012 -112.830021)
			(xy 329.757256 -112.776073) (xy 329.75677 -112.748822) (xy 329.757262 -112.722509) (xy 329.764493 -112.670382)
			(xy 329.778808 -112.61974) (xy 329.799936 -112.571541) (xy 329.827477 -112.526697) (xy 329.860911 -112.486056)
			(xy 329.87996 -112.467898) (xy 329.887358 -112.460374) (xy 329.895886 -112.441096) (xy 329.89647 -112.43056)
			(xy 329.89647 -112.355884) (xy 329.895972 -112.34533) (xy 329.887416 -112.326035) (xy 329.87996 -112.318546)
			(xy 329.859195 -112.298703) (xy 329.823222 -112.253933) (xy 329.794363 -112.204279) (xy 329.773271 -112.15086)
			(xy 329.760421 -112.094884) (xy 329.756103 -112.037615) (xy 327.962752 -112.037615) (xy 327.994212 -112.075822)
			(xy 328.021769 -112.120665) (xy 328.042905 -112.168869) (xy 328.057219 -112.219519) (xy 328.06444 -112.271655)
			(xy 328.064876 -112.297972) (xy 328.06439 -112.325223) (xy 328.056634 -112.379171) (xy 328.041279 -112.431466)
			(xy 328.018637 -112.481043) (xy 327.989171 -112.526893) (xy 327.95348 -112.568084) (xy 327.912289 -112.603775)
			(xy 327.866439 -112.633241) (xy 327.816862 -112.655883) (xy 327.764567 -112.671238) (xy 327.710619 -112.678994)
			(xy 327.656117 -112.678994) (xy 327.602169 -112.671238) (xy 327.549874 -112.655883) (xy 327.500297 -112.633241)
			(xy 327.454447 -112.603775) (xy 327.413256 -112.568084) (xy 327.377565 -112.526893) (xy 327.348099 -112.481043)
			(xy 327.325457 -112.431466) (xy 327.310102 -112.379171) (xy 327.302346 -112.325223) (xy 327.30186 -112.297972)
			(xy 326.032876 -112.297972) (xy 326.03239 -112.325223) (xy 326.024634 -112.379171) (xy 326.009279 -112.431466)
			(xy 325.986637 -112.481043) (xy 325.957171 -112.526893) (xy 325.92148 -112.568084) (xy 325.880289 -112.603775)
			(xy 325.834439 -112.633241) (xy 325.784862 -112.655883) (xy 325.732567 -112.671238) (xy 325.678619 -112.678994)
			(xy 325.624117 -112.678994) (xy 325.570169 -112.671238) (xy 325.517874 -112.655883) (xy 325.468297 -112.633241)
			(xy 325.422447 -112.603775) (xy 325.381256 -112.568084) (xy 325.345565 -112.526893) (xy 325.316099 -112.481043)
			(xy 325.293457 -112.431466) (xy 325.278102 -112.379171) (xy 325.270346 -112.325223) (xy 325.26986 -112.297972)
			(xy 314.367336 -112.297972) (xy 314.14536 -114.084612) (xy 321.649282 -114.084612) (xy 321.649288 -114.03011)
			(xy 321.65705 -113.976164) (xy 321.672411 -113.923871) (xy 321.695057 -113.874297) (xy 321.724528 -113.82845)
			(xy 321.760223 -113.787264) (xy 321.801417 -113.751578) (xy 321.84727 -113.722117) (xy 321.896849 -113.699481)
			(xy 321.949145 -113.684132) (xy 322.003093 -113.676382) (xy 322.030344 -113.675922) (xy 322.064564 -113.676721)
			(xy 322.131897 -113.688991) (xy 322.164202 -113.700306) (xy 322.172392 -113.702978) (xy 322.189602 -113.703321)
			(xy 322.205949 -113.697929) (xy 322.21297 -113.69294) (xy 322.291964 -113.632488) (xy 322.302378 -113.608358)
			(xy 322.301108 -113.595404) (xy 322.29933 -113.558574) (xy 322.299731 -113.531319) (xy 322.307492 -113.477364)
			(xy 322.322854 -113.425062) (xy 322.345502 -113.375479) (xy 322.374976 -113.329624) (xy 322.410676 -113.288431)
			(xy 322.451876 -113.252738) (xy 322.497736 -113.223271) (xy 322.547322 -113.200631) (xy 322.599626 -113.185279)
			(xy 322.653583 -113.177526) (xy 322.680838 -113.177066) (xy 322.709754 -113.177604) (xy 322.766926 -113.186326)
			(xy 322.822125 -113.203578) (xy 322.874088 -113.228966) (xy 322.921622 -113.261907) (xy 322.963638 -113.301647)
			(xy 322.981828 -113.324132) (xy 322.989427 -113.332947) (xy 323.010334 -113.343125) (xy 323.02196 -113.34369)
			(xy 323.101716 -113.34369) (xy 323.113348 -113.343149) (xy 323.134258 -113.332962) (xy 323.141848 -113.324132)
			(xy 323.160076 -113.30168) (xy 323.202087 -113.261941) (xy 323.249614 -113.228998) (xy 323.301568 -113.203604)
			(xy 323.35676 -113.186341) (xy 323.413924 -113.177605) (xy 323.442838 -113.177066) (xy 323.470089 -113.177542)
			(xy 323.524036 -113.185303) (xy 323.576329 -113.200662) (xy 323.625905 -113.223306) (xy 323.671754 -113.252774)
			(xy 323.712943 -113.288466) (xy 323.748634 -113.329656) (xy 323.7781 -113.375506) (xy 323.800742 -113.425082)
			(xy 323.816099 -113.477376) (xy 323.823858 -113.531323) (xy 323.824346 -113.558574) (xy 323.824161 -113.568734)
			(xy 343.089736 -113.568734) (xy 343.093807 -113.513112) (xy 343.105933 -113.458675) (xy 343.125856 -113.406584)
			(xy 343.153152 -113.357949) (xy 343.187238 -113.313806) (xy 343.227387 -113.275097) (xy 343.272745 -113.242646)
			(xy 343.322345 -113.217145) (xy 343.375129 -113.199138) (xy 343.429972 -113.189008) (xy 343.485706 -113.186971)
			(xy 343.541143 -113.193071) (xy 343.5951 -113.207177) (xy 343.646429 -113.228989) (xy 343.694035 -113.258043)
			(xy 343.736903 -113.293718) (xy 343.77412 -113.335255) (xy 343.804893 -113.381768) (xy 343.828565 -113.432265)
			(xy 343.844633 -113.485672) (xy 343.852753 -113.540848) (xy 343.853262 -113.568734) (xy 343.852753 -113.59662)
			(xy 343.844633 -113.651796) (xy 343.828565 -113.705203) (xy 343.804893 -113.7557) (xy 343.77412 -113.802213)
			(xy 343.736903 -113.84375) (xy 343.694035 -113.879425) (xy 343.662901 -113.898426) (xy 359.753406 -113.898426)
			(xy 359.757477 -113.842804) (xy 359.769603 -113.788367) (xy 359.789526 -113.736276) (xy 359.816822 -113.687641)
			(xy 359.850908 -113.643498) (xy 359.891057 -113.604789) (xy 359.936415 -113.572338) (xy 359.986015 -113.546837)
			(xy 360.038799 -113.52883) (xy 360.093642 -113.5187) (xy 360.149376 -113.516663) (xy 360.204813 -113.522763)
			(xy 360.25877 -113.536869) (xy 360.310099 -113.558681) (xy 360.357705 -113.587735) (xy 360.400573 -113.62341)
			(xy 360.43779 -113.664947) (xy 360.468563 -113.71146) (xy 360.492235 -113.761957) (xy 360.508303 -113.815364)
			(xy 360.516423 -113.87054) (xy 360.516932 -113.898426) (xy 360.516423 -113.926312) (xy 360.508303 -113.981488)
			(xy 360.492235 -114.034895) (xy 360.468563 -114.085392) (xy 360.43779 -114.131905) (xy 360.400573 -114.173442)
			(xy 360.357705 -114.209117) (xy 360.310099 -114.238171) (xy 360.25877 -114.259983) (xy 360.204813 -114.274089)
			(xy 360.149376 -114.280189) (xy 360.093642 -114.278152) (xy 360.038799 -114.268022) (xy 359.986015 -114.250015)
			(xy 359.936415 -114.224514) (xy 359.891057 -114.192063) (xy 359.850908 -114.153354) (xy 359.816822 -114.109211)
			(xy 359.789526 -114.060576) (xy 359.769603 -114.008485) (xy 359.757477 -113.954048) (xy 359.753406 -113.898426)
			(xy 343.662901 -113.898426) (xy 343.646429 -113.908479) (xy 343.5951 -113.930291) (xy 343.541143 -113.944397)
			(xy 343.485706 -113.950497) (xy 343.429972 -113.94846) (xy 343.375129 -113.93833) (xy 343.322345 -113.920323)
			(xy 343.272745 -113.894822) (xy 343.227387 -113.862371) (xy 343.187238 -113.823662) (xy 343.153152 -113.779519)
			(xy 343.125856 -113.730884) (xy 343.105933 -113.678793) (xy 343.093807 -113.624356) (xy 343.089736 -113.568734)
			(xy 323.824161 -113.568734) (xy 323.823808 -113.58812) (xy 323.814708 -113.646506) (xy 323.796706 -113.702788)
			(xy 323.770234 -113.755618) (xy 323.735926 -113.80373) (xy 323.694604 -113.84597) (xy 323.647258 -113.881327)
			(xy 323.6214 -113.895632) (xy 323.611313 -113.901734) (xy 323.597673 -113.920928) (xy 323.595238 -113.932462)
			(xy 323.580506 -114.025172) (xy 323.587872 -114.048032) (xy 323.596254 -114.056414) (xy 323.603701 -114.064122)
			(xy 323.617806 -114.080261) (xy 323.624448 -114.088672) (xy 323.632032 -114.097503) (xy 323.652951 -114.107671)
			(xy 323.66458 -114.10823) (xy 323.744336 -114.10823) (xy 323.755972 -114.107722) (xy 323.776883 -114.097513)
			(xy 323.784468 -114.088672) (xy 323.80267 -114.066198) (xy 323.844688 -114.026463) (xy 323.892221 -113.993524)
			(xy 323.94418 -113.968134) (xy 323.999375 -113.950876) (xy 324.056543 -113.942143) (xy 324.085458 -113.941606)
			(xy 324.112714 -113.942038) (xy 324.166671 -113.94979) (xy 324.218976 -113.965143) (xy 324.268564 -113.987784)
			(xy 324.314424 -114.017252) (xy 324.327376 -114.028474) (xy 337.205064 -114.028474) (xy 337.209135 -113.972852)
			(xy 337.221261 -113.918415) (xy 337.241184 -113.866324) (xy 337.26848 -113.817689) (xy 337.302566 -113.773546)
			(xy 337.342715 -113.734837) (xy 337.388073 -113.702386) (xy 337.437673 -113.676885) (xy 337.490457 -113.658878)
			(xy 337.5453 -113.648748) (xy 337.601034 -113.646711) (xy 337.656471 -113.652811) (xy 337.710428 -113.666917)
			(xy 337.761757 -113.688729) (xy 337.809363 -113.717783) (xy 337.852231 -113.753458) (xy 337.889448 -113.794995)
			(xy 337.920221 -113.841508) (xy 337.943893 -113.892005) (xy 337.959961 -113.945412) (xy 337.968081 -114.000588)
			(xy 337.96859 -114.028474) (xy 337.968081 -114.05636) (xy 337.959961 -114.111536) (xy 337.943893 -114.164943)
			(xy 337.920221 -114.21544) (xy 337.889448 -114.261953) (xy 337.852231 -114.30349) (xy 337.809363 -114.339165)
			(xy 337.761757 -114.368219) (xy 337.710428 -114.390031) (xy 337.656471 -114.404137) (xy 337.601034 -114.410237)
			(xy 337.5453 -114.4082) (xy 337.490457 -114.39807) (xy 337.437673 -114.380063) (xy 337.388073 -114.354562)
			(xy 337.342715 -114.322111) (xy 337.302566 -114.283402) (xy 337.26848 -114.239259) (xy 337.241184 -114.190624)
			(xy 337.221261 -114.138533) (xy 337.209135 -114.084096) (xy 337.205064 -114.028474) (xy 324.327376 -114.028474)
			(xy 324.355623 -114.052947) (xy 324.391322 -114.094143) (xy 324.420795 -114.14) (xy 324.443442 -114.189584)
			(xy 324.458801 -114.241888) (xy 324.466559 -114.295844) (xy 324.466559 -114.350356) (xy 324.458801 -114.404312)
			(xy 324.443442 -114.456616) (xy 324.420795 -114.5062) (xy 324.391322 -114.552057) (xy 324.355623 -114.593253)
			(xy 324.314424 -114.628948) (xy 324.268564 -114.658416) (xy 324.218976 -114.681057) (xy 324.166671 -114.69641)
			(xy 324.112714 -114.704162) (xy 324.085458 -114.704622) (xy 324.056541 -114.704091) (xy 323.999369 -114.695369)
			(xy 323.944169 -114.678115) (xy 323.892207 -114.652726) (xy 323.844673 -114.619783) (xy 323.802657 -114.580042)
			(xy 323.784468 -114.557556) (xy 323.776872 -114.548737) (xy 323.755963 -114.538562) (xy 323.744336 -114.537998)
			(xy 323.66458 -114.537998) (xy 323.652949 -114.538541) (xy 323.632039 -114.548727) (xy 323.624448 -114.557556)
			(xy 323.606219 -114.580007) (xy 323.564208 -114.619747) (xy 323.516682 -114.652691) (xy 323.464728 -114.678085)
			(xy 323.409536 -114.695348) (xy 323.352372 -114.704084) (xy 323.323458 -114.704622) (xy 323.296206 -114.704161)
			(xy 323.242258 -114.696399) (xy 323.189964 -114.68104) (xy 323.140388 -114.658395) (xy 323.094538 -114.628925)
			(xy 323.053349 -114.593231) (xy 323.017658 -114.552039) (xy 322.988192 -114.506188) (xy 322.965551 -114.45661)
			(xy 322.950195 -114.404314) (xy 322.942437 -114.350366) (xy 322.94195 -114.323114) (xy 322.942428 -114.293565)
			(xy 322.951532 -114.235174) (xy 322.969541 -114.178888) (xy 322.996022 -114.126056) (xy 323.030341 -114.077944)
			(xy 323.071675 -114.035707) (xy 323.119032 -114.000356) (xy 323.144896 -113.986056) (xy 323.154987 -113.979959)
			(xy 323.168625 -113.960762) (xy 323.171058 -113.949226) (xy 323.18579 -113.856516) (xy 323.178424 -113.833656)
			(xy 323.170042 -113.825274) (xy 323.162595 -113.817567) (xy 323.14849 -113.801427) (xy 323.141848 -113.793016)
			(xy 323.134225 -113.784226) (xy 323.113336 -113.774036) (xy 323.101716 -113.773458) (xy 323.02196 -113.773458)
			(xy 323.010324 -113.773968) (xy 322.989413 -113.784175) (xy 322.981828 -113.793016) (xy 322.963625 -113.815489)
			(xy 322.921607 -113.855225) (xy 322.874075 -113.888164) (xy 322.822116 -113.913554) (xy 322.766921 -113.930813)
			(xy 322.709753 -113.939545) (xy 322.680838 -113.940082) (xy 322.646618 -113.939287) (xy 322.579285 -113.927015)
			(xy 322.54698 -113.915698) (xy 322.538794 -113.913011) (xy 322.521581 -113.912674) (xy 322.505233 -113.918072)
			(xy 322.498212 -113.923064) (xy 322.419218 -113.983516) (xy 322.408804 -114.007646) (xy 322.410074 -114.0206)
			(xy 322.411852 -114.05743) (xy 322.411313 -114.084681) (xy 322.403552 -114.138627) (xy 322.388193 -114.19092)
			(xy 322.365548 -114.240495) (xy 322.336078 -114.286342) (xy 322.300383 -114.327529) (xy 322.259191 -114.363217)
			(xy 322.213338 -114.392679) (xy 322.16376 -114.415315) (xy 322.111464 -114.430666) (xy 322.057516 -114.438417)
			(xy 322.003014 -114.438412) (xy 321.949068 -114.430651) (xy 321.896775 -114.415291) (xy 321.847201 -114.392645)
			(xy 321.801354 -114.363175) (xy 321.760167 -114.32748) (xy 321.72448 -114.286287) (xy 321.695019 -114.240434)
			(xy 321.672383 -114.190855) (xy 321.657033 -114.13856) (xy 321.649282 -114.084612) (xy 314.14536 -114.084612)
			(xy 313.981829 -115.400836) (xy 319.460624 -115.400836) (xy 319.464695 -115.345214) (xy 319.476821 -115.290777)
			(xy 319.496744 -115.238686) (xy 319.52404 -115.190051) (xy 319.558126 -115.145908) (xy 319.598275 -115.107199)
			(xy 319.643633 -115.074748) (xy 319.693233 -115.049247) (xy 319.746017 -115.03124) (xy 319.80086 -115.02111)
			(xy 319.856594 -115.019073) (xy 319.912031 -115.025173) (xy 319.965988 -115.039279) (xy 320.017317 -115.061091)
			(xy 320.064923 -115.090145) (xy 320.107791 -115.12582) (xy 320.145008 -115.167357) (xy 320.175781 -115.21387)
			(xy 320.199453 -115.264367) (xy 320.215521 -115.317774) (xy 320.223259 -115.370356) (xy 321.561204 -115.370356)
			(xy 321.565275 -115.314734) (xy 321.577401 -115.260297) (xy 321.597324 -115.208206) (xy 321.62462 -115.159571)
			(xy 321.658706 -115.115428) (xy 321.698855 -115.076719) (xy 321.744213 -115.044268) (xy 321.793813 -115.018767)
			(xy 321.846597 -115.00076) (xy 321.90144 -114.99063) (xy 321.957174 -114.988593) (xy 322.012611 -114.994693)
			(xy 322.066568 -115.008799) (xy 322.07162 -115.010946) (xy 338.819742 -115.010946) (xy 338.823813 -114.955324)
			(xy 338.835939 -114.900887) (xy 338.855862 -114.848796) (xy 338.883158 -114.800161) (xy 338.917244 -114.756018)
			(xy 338.957393 -114.717309) (xy 339.002751 -114.684858) (xy 339.052351 -114.659357) (xy 339.105135 -114.64135)
			(xy 339.159978 -114.63122) (xy 339.215712 -114.629183) (xy 339.271149 -114.635283) (xy 339.325106 -114.649389)
			(xy 339.376435 -114.671201) (xy 339.424041 -114.700255) (xy 339.466909 -114.73593) (xy 339.504126 -114.777467)
			(xy 339.534899 -114.82398) (xy 339.558571 -114.874477) (xy 339.574639 -114.927884) (xy 339.582759 -114.98306)
			(xy 339.583268 -115.010946) (xy 339.582759 -115.038832) (xy 339.579835 -115.058698) (xy 340.186262 -115.058698)
			(xy 340.190333 -115.003076) (xy 340.202459 -114.948639) (xy 340.222382 -114.896548) (xy 340.249678 -114.847913)
			(xy 340.283764 -114.80377) (xy 340.323913 -114.765061) (xy 340.369271 -114.73261) (xy 340.418871 -114.707109)
			(xy 340.471655 -114.689102) (xy 340.526498 -114.678972) (xy 340.582232 -114.676935) (xy 340.637669 -114.683035)
			(xy 340.691626 -114.697141) (xy 340.742955 -114.718953) (xy 340.790561 -114.748007) (xy 340.833429 -114.783682)
			(xy 340.870646 -114.825219) (xy 340.901419 -114.871732) (xy 340.925091 -114.922229) (xy 340.941159 -114.975636)
			(xy 340.943328 -114.990372) (xy 341.564974 -114.990372) (xy 341.569045 -114.93475) (xy 341.581171 -114.880313)
			(xy 341.601094 -114.828222) (xy 341.62839 -114.779587) (xy 341.662476 -114.735444) (xy 341.702625 -114.696735)
			(xy 341.747983 -114.664284) (xy 341.797583 -114.638783) (xy 341.850367 -114.620776) (xy 341.90521 -114.610646)
			(xy 341.960944 -114.608609) (xy 342.016381 -114.614709) (xy 342.070338 -114.628815) (xy 342.121667 -114.650627)
			(xy 342.169273 -114.679681) (xy 342.212141 -114.715356) (xy 342.249358 -114.756893) (xy 342.280131 -114.803406)
			(xy 342.303803 -114.853903) (xy 342.319871 -114.90731) (xy 342.327721 -114.960654) (xy 343.091768 -114.960654)
			(xy 343.095839 -114.905032) (xy 343.107965 -114.850595) (xy 343.127888 -114.798504) (xy 343.155184 -114.749869)
			(xy 343.18927 -114.705726) (xy 343.229419 -114.667017) (xy 343.274777 -114.634566) (xy 343.324377 -114.609065)
			(xy 343.377161 -114.591058) (xy 343.432004 -114.580928) (xy 343.487738 -114.578891) (xy 343.543175 -114.584991)
			(xy 343.597132 -114.599097) (xy 343.648461 -114.620909) (xy 343.696067 -114.649963) (xy 343.738935 -114.685638)
			(xy 343.776152 -114.727175) (xy 343.806925 -114.773688) (xy 343.830597 -114.824185) (xy 343.846665 -114.877592)
			(xy 343.854785 -114.932768) (xy 343.855294 -114.960654) (xy 343.854785 -114.98854) (xy 343.846665 -115.043716)
			(xy 343.830597 -115.097123) (xy 343.806925 -115.14762) (xy 343.776152 -115.194133) (xy 343.738935 -115.23567)
			(xy 343.696067 -115.271345) (xy 343.648461 -115.300399) (xy 343.597132 -115.322211) (xy 343.543175 -115.336317)
			(xy 343.487738 -115.342417) (xy 343.432004 -115.34038) (xy 343.377161 -115.33025) (xy 343.324377 -115.312243)
			(xy 343.274777 -115.286742) (xy 343.229419 -115.254291) (xy 343.18927 -115.215582) (xy 343.155184 -115.171439)
			(xy 343.127888 -115.122804) (xy 343.107965 -115.070713) (xy 343.095839 -115.016276) (xy 343.091768 -114.960654)
			(xy 342.327721 -114.960654) (xy 342.327991 -114.962486) (xy 342.3285 -114.990372) (xy 342.327991 -115.018258)
			(xy 342.319871 -115.073434) (xy 342.303803 -115.126841) (xy 342.280131 -115.177338) (xy 342.249358 -115.223851)
			(xy 342.212141 -115.265388) (xy 342.169273 -115.301063) (xy 342.121667 -115.330117) (xy 342.070338 -115.351929)
			(xy 342.016381 -115.366035) (xy 341.960944 -115.372135) (xy 341.90521 -115.370098) (xy 341.850367 -115.359968)
			(xy 341.797583 -115.341961) (xy 341.747983 -115.31646) (xy 341.702625 -115.284009) (xy 341.662476 -115.2453)
			(xy 341.62839 -115.201157) (xy 341.601094 -115.152522) (xy 341.581171 -115.100431) (xy 341.569045 -115.045994)
			(xy 341.564974 -114.990372) (xy 340.943328 -114.990372) (xy 340.949279 -115.030812) (xy 340.949788 -115.058698)
			(xy 340.949279 -115.086584) (xy 340.941159 -115.14176) (xy 340.925091 -115.195167) (xy 340.901419 -115.245664)
			(xy 340.870646 -115.292177) (xy 340.833429 -115.333714) (xy 340.790561 -115.369389) (xy 340.742955 -115.398443)
			(xy 340.691626 -115.420255) (xy 340.637669 -115.434361) (xy 340.582232 -115.440461) (xy 340.526498 -115.438424)
			(xy 340.471655 -115.428294) (xy 340.418871 -115.410287) (xy 340.369271 -115.384786) (xy 340.323913 -115.352335)
			(xy 340.283764 -115.313626) (xy 340.249678 -115.269483) (xy 340.222382 -115.220848) (xy 340.202459 -115.168757)
			(xy 340.190333 -115.11432) (xy 340.186262 -115.058698) (xy 339.579835 -115.058698) (xy 339.574639 -115.094008)
			(xy 339.558571 -115.147415) (xy 339.534899 -115.197912) (xy 339.504126 -115.244425) (xy 339.466909 -115.285962)
			(xy 339.424041 -115.321637) (xy 339.376435 -115.350691) (xy 339.325106 -115.372503) (xy 339.271149 -115.386609)
			(xy 339.215712 -115.392709) (xy 339.159978 -115.390672) (xy 339.105135 -115.380542) (xy 339.052351 -115.362535)
			(xy 339.002751 -115.337034) (xy 338.957393 -115.304583) (xy 338.917244 -115.265874) (xy 338.883158 -115.221731)
			(xy 338.855862 -115.173096) (xy 338.835939 -115.121005) (xy 338.823813 -115.066568) (xy 338.819742 -115.010946)
			(xy 322.07162 -115.010946) (xy 322.117897 -115.030611) (xy 322.165503 -115.059665) (xy 322.208371 -115.09534)
			(xy 322.245588 -115.136877) (xy 322.276361 -115.18339) (xy 322.300033 -115.233887) (xy 322.316101 -115.287294)
			(xy 322.324221 -115.34247) (xy 322.32473 -115.370356) (xy 322.324221 -115.398242) (xy 322.316101 -115.453418)
			(xy 322.300033 -115.506825) (xy 322.276361 -115.557322) (xy 322.245588 -115.603835) (xy 322.208371 -115.645372)
			(xy 322.165503 -115.681047) (xy 322.117897 -115.710101) (xy 322.066568 -115.731913) (xy 322.012611 -115.746019)
			(xy 321.957174 -115.752119) (xy 321.90144 -115.750082) (xy 321.846597 -115.739952) (xy 321.793813 -115.721945)
			(xy 321.744213 -115.696444) (xy 321.698855 -115.663993) (xy 321.658706 -115.625284) (xy 321.62462 -115.581141)
			(xy 321.597324 -115.532506) (xy 321.577401 -115.480415) (xy 321.565275 -115.425978) (xy 321.561204 -115.370356)
			(xy 320.223259 -115.370356) (xy 320.223641 -115.37295) (xy 320.22415 -115.400836) (xy 320.223641 -115.428722)
			(xy 320.215521 -115.483898) (xy 320.199453 -115.537305) (xy 320.175781 -115.587802) (xy 320.145008 -115.634315)
			(xy 320.107791 -115.675852) (xy 320.064923 -115.711527) (xy 320.017317 -115.740581) (xy 319.965988 -115.762393)
			(xy 319.912031 -115.776499) (xy 319.856594 -115.782599) (xy 319.80086 -115.780562) (xy 319.746017 -115.770432)
			(xy 319.693233 -115.752425) (xy 319.643633 -115.726924) (xy 319.598275 -115.694473) (xy 319.558126 -115.655764)
			(xy 319.52404 -115.611621) (xy 319.496744 -115.562986) (xy 319.476821 -115.510895) (xy 319.464695 -115.456458)
			(xy 319.460624 -115.400836) (xy 313.981829 -115.400836) (xy 313.928181 -115.832636) (xy 325.17918 -115.832636)
			(xy 325.183251 -115.777014) (xy 325.195377 -115.722577) (xy 325.2153 -115.670486) (xy 325.242596 -115.621851)
			(xy 325.276682 -115.577708) (xy 325.316831 -115.538999) (xy 325.362189 -115.506548) (xy 325.411789 -115.481047)
			(xy 325.464573 -115.46304) (xy 325.519416 -115.45291) (xy 325.57515 -115.450873) (xy 325.630587 -115.456973)
			(xy 325.684544 -115.471079) (xy 325.735873 -115.492891) (xy 325.783479 -115.521945) (xy 325.826347 -115.55762)
			(xy 325.863564 -115.599157) (xy 325.894337 -115.64567) (xy 325.918009 -115.696167) (xy 325.934077 -115.749574)
			(xy 325.942197 -115.80475) (xy 325.942706 -115.832636) (xy 325.942197 -115.860522) (xy 325.934077 -115.915698)
			(xy 325.918009 -115.969105) (xy 325.894337 -116.019602) (xy 325.863564 -116.066115) (xy 325.826347 -116.107652)
			(xy 325.783479 -116.143327) (xy 325.735873 -116.172381) (xy 325.684544 -116.194193) (xy 325.630587 -116.208299)
			(xy 325.57515 -116.214399) (xy 325.519416 -116.212362) (xy 325.464573 -116.202232) (xy 325.411789 -116.184225)
			(xy 325.362189 -116.158724) (xy 325.316831 -116.126273) (xy 325.276682 -116.087564) (xy 325.242596 -116.043421)
			(xy 325.2153 -115.994786) (xy 325.195377 -115.942695) (xy 325.183251 -115.888258) (xy 325.17918 -115.832636)
			(xy 313.928181 -115.832636) (xy 313.824168 -116.66982) (xy 321.573142 -116.66982) (xy 321.577213 -116.614198)
			(xy 321.589339 -116.559761) (xy 321.609262 -116.50767) (xy 321.636558 -116.459035) (xy 321.670644 -116.414892)
			(xy 321.710793 -116.376183) (xy 321.756151 -116.343732) (xy 321.805751 -116.318231) (xy 321.858535 -116.300224)
			(xy 321.913378 -116.290094) (xy 321.969112 -116.288057) (xy 322.024549 -116.294157) (xy 322.078506 -116.308263)
			(xy 322.129835 -116.330075) (xy 322.177441 -116.359129) (xy 322.220309 -116.394804) (xy 322.257526 -116.436341)
			(xy 322.288299 -116.482854) (xy 322.311971 -116.533351) (xy 322.328039 -116.586758) (xy 322.334282 -116.62918)
			(xy 337.337906 -116.62918) (xy 337.341977 -116.573558) (xy 337.354103 -116.519121) (xy 337.374026 -116.46703)
			(xy 337.401322 -116.418395) (xy 337.435408 -116.374252) (xy 337.475557 -116.335543) (xy 337.520915 -116.303092)
			(xy 337.570515 -116.277591) (xy 337.623299 -116.259584) (xy 337.678142 -116.249454) (xy 337.733876 -116.247417)
			(xy 337.789313 -116.253517) (xy 337.84327 -116.267623) (xy 337.894599 -116.289435) (xy 337.942205 -116.318489)
			(xy 337.985073 -116.354164) (xy 338.02229 -116.395701) (xy 338.053063 -116.442214) (xy 338.076735 -116.492711)
			(xy 338.092803 -116.546118) (xy 338.100923 -116.601294) (xy 338.101432 -116.62918) (xy 338.100923 -116.657066)
			(xy 338.092803 -116.712242) (xy 338.076735 -116.765649) (xy 338.053063 -116.816146) (xy 338.02229 -116.862659)
			(xy 337.985073 -116.904196) (xy 337.942205 -116.939871) (xy 337.894599 -116.968925) (xy 337.84327 -116.990737)
			(xy 337.789313 -117.004843) (xy 337.733876 -117.010943) (xy 337.678142 -117.008906) (xy 337.623299 -116.998776)
			(xy 337.570515 -116.980769) (xy 337.520915 -116.955268) (xy 337.475557 -116.922817) (xy 337.435408 -116.884108)
			(xy 337.401322 -116.839965) (xy 337.374026 -116.79133) (xy 337.354103 -116.739239) (xy 337.341977 -116.684802)
			(xy 337.337906 -116.62918) (xy 322.334282 -116.62918) (xy 322.336159 -116.641934) (xy 322.336668 -116.66982)
			(xy 322.336159 -116.697706) (xy 322.328039 -116.752882) (xy 322.311971 -116.806289) (xy 322.288299 -116.856786)
			(xy 322.257526 -116.903299) (xy 322.220309 -116.944836) (xy 322.177441 -116.980511) (xy 322.129835 -117.009565)
			(xy 322.078506 -117.031377) (xy 322.024549 -117.045483) (xy 321.969112 -117.051583) (xy 321.913378 -117.049546)
			(xy 321.858535 -117.039416) (xy 321.805751 -117.021409) (xy 321.756151 -116.995908) (xy 321.710793 -116.963457)
			(xy 321.670644 -116.924748) (xy 321.636558 -116.880605) (xy 321.609262 -116.83197) (xy 321.589339 -116.779879)
			(xy 321.577213 -116.725442) (xy 321.573142 -116.66982) (xy 313.824168 -116.66982) (xy 313.734636 -117.390446)
			(xy 322.942518 -117.390446) (xy 322.942518 -117.335954) (xy 322.950273 -117.282015) (xy 322.965624 -117.229729)
			(xy 322.98826 -117.18016) (xy 323.017719 -117.134317) (xy 323.053402 -117.093132) (xy 323.094583 -117.057444)
			(xy 323.140423 -117.02798) (xy 323.18999 -117.005339) (xy 323.242274 -116.989982) (xy 323.296212 -116.982221)
			(xy 323.323458 -116.981732) (xy 323.352374 -116.982268) (xy 323.409545 -116.990992) (xy 323.464744 -117.008245)
			(xy 323.516706 -117.033634) (xy 323.564241 -117.066575) (xy 323.606258 -117.106313) (xy 323.624448 -117.128798)
			(xy 323.632044 -117.137617) (xy 323.652953 -117.147794) (xy 323.66458 -117.148356) (xy 323.744336 -117.148356)
			(xy 323.755971 -117.147839) (xy 323.776881 -117.137636) (xy 323.784468 -117.128798) (xy 323.802677 -117.106329)
			(xy 323.844693 -117.066593) (xy 323.892224 -117.033653) (xy 323.944182 -117.008262) (xy 323.999376 -116.991002)
			(xy 324.056543 -116.982269) (xy 324.085458 -116.981732) (xy 324.112716 -116.982112) (xy 324.166677 -116.989865)
			(xy 324.218985 -117.005219) (xy 324.268576 -117.027862) (xy 324.314439 -117.057332) (xy 324.355641 -117.093029)
			(xy 324.363966 -117.102636) (xy 325.17918 -117.102636) (xy 325.183251 -117.047014) (xy 325.195377 -116.992577)
			(xy 325.2153 -116.940486) (xy 325.242596 -116.891851) (xy 325.276682 -116.847708) (xy 325.316831 -116.808999)
			(xy 325.362189 -116.776548) (xy 325.411789 -116.751047) (xy 325.464573 -116.73304) (xy 325.519416 -116.72291)
			(xy 325.57515 -116.720873) (xy 325.630587 -116.726973) (xy 325.684544 -116.741079) (xy 325.735873 -116.762891)
			(xy 325.783479 -116.791945) (xy 325.826347 -116.82762) (xy 325.863564 -116.869157) (xy 325.894337 -116.91567)
			(xy 325.918009 -116.966167) (xy 325.934077 -117.019574) (xy 325.942197 -117.07475) (xy 325.942706 -117.102636)
			(xy 325.942197 -117.130522) (xy 325.934077 -117.185698) (xy 325.918009 -117.239105) (xy 325.913756 -117.248178)
			(xy 339.938866 -117.248178) (xy 339.942937 -117.192556) (xy 339.955063 -117.138119) (xy 339.974986 -117.086028)
			(xy 340.002282 -117.037393) (xy 340.036368 -116.99325) (xy 340.076517 -116.954541) (xy 340.121875 -116.92209)
			(xy 340.171475 -116.896589) (xy 340.224259 -116.878582) (xy 340.279102 -116.868452) (xy 340.334836 -116.866415)
			(xy 340.390273 -116.872515) (xy 340.44423 -116.886621) (xy 340.495559 -116.908433) (xy 340.543165 -116.937487)
			(xy 340.586033 -116.973162) (xy 340.62325 -117.014699) (xy 340.654023 -117.061212) (xy 340.677695 -117.111709)
			(xy 340.693763 -117.165116) (xy 340.701883 -117.220292) (xy 340.702392 -117.248178) (xy 340.954866 -117.248178)
			(xy 340.958937 -117.192556) (xy 340.971063 -117.138119) (xy 340.990986 -117.086028) (xy 341.018282 -117.037393)
			(xy 341.052368 -116.99325) (xy 341.092517 -116.954541) (xy 341.137875 -116.92209) (xy 341.187475 -116.896589)
			(xy 341.240259 -116.878582) (xy 341.295102 -116.868452) (xy 341.350836 -116.866415) (xy 341.406273 -116.872515)
			(xy 341.46023 -116.886621) (xy 341.511559 -116.908433) (xy 341.559165 -116.937487) (xy 341.602033 -116.973162)
			(xy 341.63925 -117.014699) (xy 341.670023 -117.061212) (xy 341.693695 -117.111709) (xy 341.709763 -117.165116)
			(xy 341.717883 -117.220292) (xy 341.718392 -117.248178) (xy 341.970866 -117.248178) (xy 341.974937 -117.192556)
			(xy 341.987063 -117.138119) (xy 342.006986 -117.086028) (xy 342.034282 -117.037393) (xy 342.068368 -116.99325)
			(xy 342.108517 -116.954541) (xy 342.153875 -116.92209) (xy 342.203475 -116.896589) (xy 342.256259 -116.878582)
			(xy 342.311102 -116.868452) (xy 342.366836 -116.866415) (xy 342.422273 -116.872515) (xy 342.47623 -116.886621)
			(xy 342.527559 -116.908433) (xy 342.575165 -116.937487) (xy 342.618033 -116.973162) (xy 342.627305 -116.98351)
			(xy 356.001572 -116.98351) (xy 356.005643 -116.927888) (xy 356.017769 -116.873451) (xy 356.037692 -116.82136)
			(xy 356.064988 -116.772725) (xy 356.099074 -116.728582) (xy 356.139223 -116.689873) (xy 356.184581 -116.657422)
			(xy 356.234181 -116.631921) (xy 356.286965 -116.613914) (xy 356.341808 -116.603784) (xy 356.397542 -116.601747)
			(xy 356.452979 -116.607847) (xy 356.506936 -116.621953) (xy 356.558265 -116.643765) (xy 356.604703 -116.672106)
			(xy 361.16895 -116.672106) (xy 361.169407 -116.644735) (xy 361.177225 -116.590555) (xy 361.192716 -116.538052)
			(xy 361.21556 -116.488305) (xy 361.245287 -116.442339) (xy 361.26293 -116.421408) (xy 361.263184 -116.421154)
			(xy 361.268752 -116.414055) (xy 361.27501 -116.397148) (xy 361.275376 -116.388134) (xy 361.275376 -116.321078)
			(xy 361.275035 -116.312059) (xy 361.268777 -116.295142) (xy 361.263184 -116.288058) (xy 361.26293 -116.288058)
			(xy 361.26293 -116.287804) (xy 361.245295 -116.266867) (xy 361.21557 -116.2209) (xy 361.192724 -116.171154)
			(xy 361.177227 -116.118653) (xy 361.169398 -116.064475) (xy 361.169397 -116.009734) (xy 361.177225 -115.955556)
			(xy 361.192721 -115.903054) (xy 361.215565 -115.853308) (xy 361.24529 -115.807341) (xy 361.26293 -115.786408)
			(xy 361.263184 -115.786154) (xy 361.268752 -115.779055) (xy 361.27501 -115.762148) (xy 361.275376 -115.753134)
			(xy 361.275376 -115.686078) (xy 361.275035 -115.677059) (xy 361.268777 -115.660142) (xy 361.263184 -115.653058)
			(xy 361.26293 -115.653058) (xy 361.26293 -115.652804) (xy 361.245284 -115.631877) (xy 361.215572 -115.585904)
			(xy 361.192737 -115.536155) (xy 361.177248 -115.483653) (xy 361.169422 -115.429476) (xy 361.16895 -115.402106)
			(xy 361.169483 -115.374857) (xy 361.177238 -115.320913) (xy 361.19259 -115.268622) (xy 361.215227 -115.219047)
			(xy 361.244689 -115.173199) (xy 361.280376 -115.13201) (xy 361.32156 -115.096318) (xy 361.367405 -115.06685)
			(xy 361.416977 -115.044207) (xy 361.469266 -115.028848) (xy 361.523209 -115.021087) (xy 361.550458 -115.020598)
			(xy 361.577827 -115.021089) (xy 361.632005 -115.028901) (xy 361.684508 -115.044384) (xy 361.734255 -115.06722)
			(xy 361.780223 -115.096939) (xy 361.801156 -115.114578) (xy 361.80141 -115.114832) (xy 361.808487 -115.120432)
			(xy 361.825411 -115.12667) (xy 361.83443 -115.127024) (xy 361.901486 -115.127024) (xy 361.910502 -115.126655)
			(xy 361.927418 -115.120415) (xy 361.934506 -115.114832) (xy 361.934506 -115.114578) (xy 361.93476 -115.114578)
			(xy 361.955694 -115.096941) (xy 362.001666 -115.067229) (xy 362.051413 -115.044393) (xy 362.103914 -115.028902)
			(xy 362.158089 -115.021073) (xy 362.185458 -115.020598) (xy 362.21271 -115.021094) (xy 362.26666 -115.028846)
			(xy 362.318958 -115.044197) (xy 362.368538 -115.066835) (xy 362.414392 -115.096299) (xy 362.455585 -115.131989)
			(xy 362.491279 -115.173179) (xy 362.520748 -115.21903) (xy 362.543391 -115.268608) (xy 362.558747 -115.320905)
			(xy 362.566503 -115.374854) (xy 362.566966 -115.402106) (xy 362.566512 -115.429477) (xy 362.558692 -115.483657)
			(xy 362.543201 -115.53616) (xy 362.520356 -115.585907) (xy 362.490629 -115.631873) (xy 362.472986 -115.652804)
			(xy 362.472732 -115.653058) (xy 362.467149 -115.660147) (xy 362.460902 -115.677062) (xy 362.46054 -115.686078)
			(xy 362.46054 -115.753134) (xy 362.460872 -115.762154) (xy 362.467136 -115.779071) (xy 362.472732 -115.786154)
			(xy 362.472986 -115.786154) (xy 362.472986 -115.786408) (xy 362.490632 -115.807336) (xy 362.520356 -115.853305)
			(xy 362.5432 -115.903052) (xy 362.558695 -115.955555) (xy 362.566523 -116.009734) (xy 362.566522 -116.064475)
			(xy 362.558693 -116.118654) (xy 362.543197 -116.171156) (xy 362.520351 -116.220903) (xy 362.490627 -116.266871)
			(xy 362.472986 -116.287804) (xy 362.472732 -116.288058) (xy 362.467149 -116.295147) (xy 362.460902 -116.312062)
			(xy 362.46054 -116.321078) (xy 362.46054 -116.388134) (xy 362.460872 -116.397154) (xy 362.467136 -116.414071)
			(xy 362.472732 -116.421154) (xy 362.472986 -116.421154) (xy 362.472986 -116.421408) (xy 362.49064 -116.442328)
			(xy 362.52035 -116.488304) (xy 362.543183 -116.538054) (xy 362.558671 -116.590558) (xy 362.566495 -116.644736)
			(xy 362.566966 -116.672106) (xy 362.566828 -116.680234) (xy 363.451138 -116.680234) (xy 363.455209 -116.624612)
			(xy 363.467335 -116.570175) (xy 363.487258 -116.518084) (xy 363.514554 -116.469449) (xy 363.54864 -116.425306)
			(xy 363.588789 -116.386597) (xy 363.634147 -116.354146) (xy 363.683747 -116.328645) (xy 363.736531 -116.310638)
			(xy 363.791374 -116.300508) (xy 363.847108 -116.298471) (xy 363.902545 -116.304571) (xy 363.956502 -116.318677)
			(xy 364.007831 -116.340489) (xy 364.055437 -116.369543) (xy 364.098305 -116.405218) (xy 364.135522 -116.446755)
			(xy 364.166295 -116.493268) (xy 364.189967 -116.543765) (xy 364.206035 -116.597172) (xy 364.214155 -116.652348)
			(xy 364.214664 -116.680234) (xy 364.214155 -116.70812) (xy 364.206035 -116.763296) (xy 364.189967 -116.816703)
			(xy 364.166295 -116.8672) (xy 364.135522 -116.913713) (xy 364.098305 -116.95525) (xy 364.055437 -116.990925)
			(xy 364.007831 -117.019979) (xy 363.956502 -117.041791) (xy 363.902545 -117.055897) (xy 363.847108 -117.061997)
			(xy 363.791374 -117.05996) (xy 363.736531 -117.04983) (xy 363.683747 -117.031823) (xy 363.634147 -117.006322)
			(xy 363.588789 -116.973871) (xy 363.54864 -116.935162) (xy 363.514554 -116.891019) (xy 363.487258 -116.842384)
			(xy 363.467335 -116.790293) (xy 363.455209 -116.735856) (xy 363.451138 -116.680234) (xy 362.566828 -116.680234)
			(xy 362.566514 -116.698663) (xy 362.559145 -116.751262) (xy 362.54455 -116.802331) (xy 362.5342 -116.826792)
			(xy 362.529851 -116.83816) (xy 362.531199 -116.862434) (xy 362.53674 -116.873274) (xy 362.578142 -116.944394)
			(xy 362.584859 -116.954477) (xy 362.605279 -116.967461) (xy 362.617258 -116.969286) (xy 362.64524 -116.972462)
			(xy 362.699904 -116.985999) (xy 362.751984 -117.007426) (xy 362.800347 -117.036278) (xy 362.843942 -117.071927)
			(xy 362.881822 -117.113598) (xy 362.913164 -117.160386) (xy 362.937286 -117.211274) (xy 362.953663 -117.265155)
			(xy 362.959105 -117.301772) (xy 364.598202 -117.301772) (xy 364.602273 -117.24615) (xy 364.614399 -117.191713)
			(xy 364.634322 -117.139622) (xy 364.661618 -117.090987) (xy 364.695704 -117.046844) (xy 364.735853 -117.008135)
			(xy 364.781211 -116.975684) (xy 364.830811 -116.950183) (xy 364.883595 -116.932176) (xy 364.938438 -116.922046)
			(xy 364.994172 -116.920009) (xy 365.049609 -116.926109) (xy 365.103566 -116.940215) (xy 365.154895 -116.962027)
			(xy 365.202501 -116.991081) (xy 365.245369 -117.026756) (xy 365.282586 -117.068293) (xy 365.313359 -117.114806)
			(xy 365.337031 -117.165303) (xy 365.353099 -117.21871) (xy 365.359118 -117.259608) (xy 365.477552 -117.259608)
			(xy 365.47801 -117.232237) (xy 365.485828 -117.178057) (xy 365.501318 -117.125554) (xy 365.524162 -117.075807)
			(xy 365.553889 -117.029841) (xy 365.571532 -117.00891) (xy 365.571786 -117.008656) (xy 365.577354 -117.001556)
			(xy 365.583612 -116.98465) (xy 365.583978 -116.975636) (xy 365.583978 -116.90858) (xy 365.583635 -116.899562)
			(xy 365.577378 -116.882644) (xy 365.571786 -116.87556) (xy 365.571532 -116.87556) (xy 365.571532 -116.875306)
			(xy 365.553899 -116.854367) (xy 365.524173 -116.8084) (xy 365.501327 -116.758655) (xy 365.48583 -116.706154)
			(xy 365.478001 -116.651976) (xy 365.478 -116.597236) (xy 365.485828 -116.543058) (xy 365.501323 -116.490556)
			(xy 365.524168 -116.44081) (xy 365.553892 -116.394843) (xy 365.571532 -116.37391) (xy 365.571786 -116.373656)
			(xy 365.577354 -116.366556) (xy 365.583612 -116.34965) (xy 365.583978 -116.340636) (xy 365.583978 -116.27358)
			(xy 365.583635 -116.264562) (xy 365.577378 -116.247644) (xy 365.571786 -116.24056) (xy 365.571532 -116.24056)
			(xy 365.571532 -116.240306) (xy 365.553887 -116.219378) (xy 365.524175 -116.173405) (xy 365.50134 -116.123656)
			(xy 365.48585 -116.071154) (xy 365.478024 -116.016978) (xy 365.477552 -115.989608) (xy 365.478085 -115.962359)
			(xy 365.485839 -115.908415) (xy 365.501192 -115.856123) (xy 365.523829 -115.806549) (xy 365.553291 -115.7607)
			(xy 365.588977 -115.719511) (xy 365.630162 -115.683819) (xy 365.676007 -115.654352) (xy 365.725578 -115.631708)
			(xy 365.777868 -115.61635) (xy 365.831811 -115.608589) (xy 365.85906 -115.6081) (xy 365.886429 -115.60859)
			(xy 365.940607 -115.616402) (xy 365.99311 -115.631885) (xy 366.042858 -115.654722) (xy 366.088825 -115.684441)
			(xy 366.109758 -115.70208) (xy 366.110012 -115.702334) (xy 366.117088 -115.707936) (xy 366.134013 -115.714172)
			(xy 366.143032 -115.714526) (xy 366.210088 -115.714526) (xy 366.219104 -115.714158) (xy 366.23602 -115.707917)
			(xy 366.243108 -115.702334) (xy 366.243108 -115.70208) (xy 366.243362 -115.70208) (xy 366.264295 -115.684442)
			(xy 366.310268 -115.654731) (xy 366.360015 -115.631895) (xy 366.412516 -115.616404) (xy 366.466691 -115.608575)
			(xy 366.49406 -115.6081) (xy 366.521312 -115.608593) (xy 366.575263 -115.616344) (xy 366.62756 -115.631696)
			(xy 366.677141 -115.654334) (xy 366.722995 -115.683799) (xy 366.764188 -115.719489) (xy 366.799882 -115.76068)
			(xy 366.829351 -115.806531) (xy 366.851993 -115.85611) (xy 366.867349 -115.908406) (xy 366.875105 -115.962356)
			(xy 366.875568 -115.989608) (xy 366.875114 -116.016979) (xy 366.867295 -116.071159) (xy 366.851803 -116.123662)
			(xy 366.828959 -116.173409) (xy 366.799231 -116.219375) (xy 366.781588 -116.240306) (xy 366.781334 -116.24056)
			(xy 366.77575 -116.247648) (xy 366.769504 -116.264564) (xy 366.769142 -116.27358) (xy 366.769142 -116.340636)
			(xy 366.769473 -116.349656) (xy 366.775737 -116.366573) (xy 366.781334 -116.373656) (xy 366.781588 -116.373656)
			(xy 366.781588 -116.37391) (xy 366.799236 -116.394837) (xy 366.828959 -116.440806) (xy 366.851803 -116.490553)
			(xy 366.867298 -116.543056) (xy 366.875126 -116.597235) (xy 366.875125 -116.651977) (xy 366.867296 -116.706156)
			(xy 366.851799 -116.758658) (xy 366.828953 -116.808405) (xy 366.799229 -116.854373) (xy 366.781588 -116.875306)
			(xy 366.781334 -116.87556) (xy 366.77575 -116.882648) (xy 366.769504 -116.899564) (xy 366.769142 -116.90858)
			(xy 366.769142 -116.975636) (xy 366.769473 -116.984656) (xy 366.775737 -117.001573) (xy 366.781334 -117.008656)
			(xy 366.781588 -117.008656) (xy 366.781588 -117.00891) (xy 366.799243 -117.029829) (xy 366.828953 -117.075805)
			(xy 366.851786 -117.125556) (xy 366.867273 -117.17806) (xy 366.875097 -117.232238) (xy 366.875568 -117.259608)
			(xy 366.875152 -117.286863) (xy 366.867393 -117.340818) (xy 366.852034 -117.393119) (xy 366.829387 -117.442702)
			(xy 366.799915 -117.488557) (xy 366.764216 -117.52975) (xy 366.723018 -117.565444) (xy 366.677159 -117.594911)
			(xy 366.627574 -117.617551) (xy 366.575271 -117.632903) (xy 366.521315 -117.640655) (xy 366.49406 -117.641116)
			(xy 366.46669 -117.640635) (xy 366.412511 -117.632824) (xy 366.360007 -117.61734) (xy 366.31026 -117.594501)
			(xy 366.264293 -117.564777) (xy 366.243362 -117.547136) (xy 366.243108 -117.546882) (xy 366.236025 -117.541291)
			(xy 366.219105 -117.535047) (xy 366.210088 -117.53469) (xy 366.143032 -117.53469) (xy 366.134017 -117.535064)
			(xy 366.1171 -117.5413) (xy 366.110012 -117.546882) (xy 366.110012 -117.547136) (xy 366.109758 -117.547136)
			(xy 366.08882 -117.564767) (xy 366.042848 -117.594479) (xy 365.993102 -117.617316) (xy 365.940603 -117.632809)
			(xy 365.886429 -117.64064) (xy 365.85906 -117.641116) (xy 365.831808 -117.640659) (xy 365.77786 -117.632898)
			(xy 365.725565 -117.617538) (xy 365.675988 -117.594893) (xy 365.630138 -117.565423) (xy 365.588949 -117.529729)
			(xy 365.553258 -117.488536) (xy 365.523792 -117.442684) (xy 365.501151 -117.393105) (xy 365.485796 -117.340809)
			(xy 365.478038 -117.28686) (xy 365.477552 -117.259608) (xy 365.359118 -117.259608) (xy 365.361219 -117.273886)
			(xy 365.361728 -117.301772) (xy 365.361219 -117.329658) (xy 365.353099 -117.384834) (xy 365.337031 -117.438241)
			(xy 365.313359 -117.488738) (xy 365.282586 -117.535251) (xy 365.245369 -117.576788) (xy 365.202501 -117.612463)
			(xy 365.154895 -117.641517) (xy 365.103566 -117.663329) (xy 365.049609 -117.677435) (xy 364.994172 -117.683535)
			(xy 364.938438 -117.681498) (xy 364.883595 -117.671368) (xy 364.830811 -117.653361) (xy 364.781211 -117.62786)
			(xy 364.735853 -117.595409) (xy 364.695704 -117.5567) (xy 364.661618 -117.512557) (xy 364.634322 -117.463922)
			(xy 364.614399 -117.411831) (xy 364.602273 -117.357394) (xy 364.598202 -117.301772) (xy 362.959105 -117.301772)
			(xy 362.961941 -117.320858) (xy 362.962444 -117.349016) (xy 362.961958 -117.376267) (xy 362.954202 -117.430215)
			(xy 362.938847 -117.48251) (xy 362.916205 -117.532087) (xy 362.886739 -117.577937) (xy 362.851048 -117.619128)
			(xy 362.809857 -117.654819) (xy 362.764007 -117.684285) (xy 362.71443 -117.706927) (xy 362.662135 -117.722282)
			(xy 362.608187 -117.730038) (xy 362.553685 -117.730038) (xy 362.499737 -117.722282) (xy 362.447442 -117.706927)
			(xy 362.397865 -117.684285) (xy 362.352015 -117.654819) (xy 362.310824 -117.619128) (xy 362.275133 -117.577937)
			(xy 362.245667 -117.532087) (xy 362.223025 -117.48251) (xy 362.20767 -117.430215) (xy 362.199914 -117.376267)
			(xy 362.199428 -117.349016) (xy 362.199888 -117.32246) (xy 362.207254 -117.26986) (xy 362.221846 -117.218791)
			(xy 362.232194 -117.19433) (xy 362.236529 -117.182958) (xy 362.235191 -117.158688) (xy 362.229654 -117.147848)
			(xy 362.188252 -117.076728) (xy 362.181509 -117.066666) (xy 362.161107 -117.053675) (xy 362.149136 -117.051836)
			(xy 362.119662 -117.048454) (xy 362.062193 -117.033737) (xy 362.007697 -117.010298) (xy 361.957487 -116.978703)
			(xy 361.93476 -116.959634) (xy 361.934506 -116.95938) (xy 361.927424 -116.953788) (xy 361.910504 -116.947545)
			(xy 361.901486 -116.947188) (xy 361.83443 -116.947188) (xy 361.825415 -116.947562) (xy 361.808498 -116.953798)
			(xy 361.80141 -116.95938) (xy 361.80141 -116.959634) (xy 361.801156 -116.959634) (xy 361.780218 -116.977266)
			(xy 361.734246 -117.006977) (xy 361.6845 -117.029814) (xy 361.632001 -117.045307) (xy 361.577827 -117.053138)
			(xy 361.550458 -117.053614) (xy 361.523206 -117.053161) (xy 361.469257 -117.045399) (xy 361.416962 -117.030039)
			(xy 361.367385 -117.007393) (xy 361.321536 -116.977923) (xy 361.280346 -116.942229) (xy 361.244655 -116.901036)
			(xy 361.215189 -116.855183) (xy 361.192548 -116.805604) (xy 361.177193 -116.753307) (xy 361.169436 -116.699358)
			(xy 361.16895 -116.672106) (xy 356.604703 -116.672106) (xy 356.605871 -116.672819) (xy 356.648739 -116.708494)
			(xy 356.685956 -116.750031) (xy 356.716729 -116.796544) (xy 356.740401 -116.847041) (xy 356.756469 -116.900448)
			(xy 356.764589 -116.955624) (xy 356.765098 -116.98351) (xy 356.764589 -117.011396) (xy 356.756469 -117.066572)
			(xy 356.740401 -117.119979) (xy 356.716729 -117.170476) (xy 356.685956 -117.216989) (xy 356.648739 -117.258526)
			(xy 356.605871 -117.294201) (xy 356.558265 -117.323255) (xy 356.54845 -117.327426) (xy 357.987344 -117.327426)
			(xy 357.991415 -117.271804) (xy 358.003541 -117.217367) (xy 358.023464 -117.165276) (xy 358.05076 -117.116641)
			(xy 358.084846 -117.072498) (xy 358.124995 -117.033789) (xy 358.170353 -117.001338) (xy 358.219953 -116.975837)
			(xy 358.272737 -116.95783) (xy 358.32758 -116.9477) (xy 358.383314 -116.945663) (xy 358.438751 -116.951763)
			(xy 358.492708 -116.965869) (xy 358.544037 -116.987681) (xy 358.591643 -117.016735) (xy 358.634511 -117.05241)
			(xy 358.671728 -117.093947) (xy 358.702501 -117.14046) (xy 358.726173 -117.190957) (xy 358.729022 -117.200426)
			(xy 360.019344 -117.200426) (xy 360.023415 -117.144804) (xy 360.035541 -117.090367) (xy 360.055464 -117.038276)
			(xy 360.08276 -116.989641) (xy 360.116846 -116.945498) (xy 360.156995 -116.906789) (xy 360.202353 -116.874338)
			(xy 360.251953 -116.848837) (xy 360.304737 -116.83083) (xy 360.35958 -116.8207) (xy 360.415314 -116.818663)
			(xy 360.470751 -116.824763) (xy 360.524708 -116.838869) (xy 360.576037 -116.860681) (xy 360.623643 -116.889735)
			(xy 360.666511 -116.92541) (xy 360.703728 -116.966947) (xy 360.734501 -117.01346) (xy 360.758173 -117.063957)
			(xy 360.774241 -117.117364) (xy 360.782361 -117.17254) (xy 360.78287 -117.200426) (xy 360.782361 -117.228312)
			(xy 360.774241 -117.283488) (xy 360.758173 -117.336895) (xy 360.734501 -117.387392) (xy 360.703728 -117.433905)
			(xy 360.666511 -117.475442) (xy 360.623643 -117.511117) (xy 360.576037 -117.540171) (xy 360.524708 -117.561983)
			(xy 360.470751 -117.576089) (xy 360.415314 -117.582189) (xy 360.35958 -117.580152) (xy 360.304737 -117.570022)
			(xy 360.251953 -117.552015) (xy 360.202353 -117.526514) (xy 360.156995 -117.494063) (xy 360.116846 -117.455354)
			(xy 360.08276 -117.411211) (xy 360.055464 -117.362576) (xy 360.035541 -117.310485) (xy 360.023415 -117.256048)
			(xy 360.019344 -117.200426) (xy 358.729022 -117.200426) (xy 358.742241 -117.244364) (xy 358.750361 -117.29954)
			(xy 358.75087 -117.327426) (xy 358.750361 -117.355312) (xy 358.742241 -117.410488) (xy 358.726173 -117.463895)
			(xy 358.702501 -117.514392) (xy 358.671728 -117.560905) (xy 358.634511 -117.602442) (xy 358.591643 -117.638117)
			(xy 358.544037 -117.667171) (xy 358.492708 -117.688983) (xy 358.438751 -117.703089) (xy 358.383314 -117.709189)
			(xy 358.32758 -117.707152) (xy 358.272737 -117.697022) (xy 358.219953 -117.679015) (xy 358.170353 -117.653514)
			(xy 358.124995 -117.621063) (xy 358.084846 -117.582354) (xy 358.05076 -117.538211) (xy 358.023464 -117.489576)
			(xy 358.003541 -117.437485) (xy 357.991415 -117.383048) (xy 357.987344 -117.327426) (xy 356.54845 -117.327426)
			(xy 356.506936 -117.345067) (xy 356.452979 -117.359173) (xy 356.397542 -117.365273) (xy 356.341808 -117.363236)
			(xy 356.286965 -117.353106) (xy 356.234181 -117.335099) (xy 356.184581 -117.309598) (xy 356.139223 -117.277147)
			(xy 356.099074 -117.238438) (xy 356.064988 -117.194295) (xy 356.037692 -117.14566) (xy 356.017769 -117.093569)
			(xy 356.005643 -117.039132) (xy 356.001572 -116.98351) (xy 342.627305 -116.98351) (xy 342.65525 -117.014699)
			(xy 342.686023 -117.061212) (xy 342.709695 -117.111709) (xy 342.725763 -117.165116) (xy 342.733883 -117.220292)
			(xy 342.734392 -117.248178) (xy 342.733883 -117.276064) (xy 342.725763 -117.33124) (xy 342.709695 -117.384647)
			(xy 342.686023 -117.435144) (xy 342.65525 -117.481657) (xy 342.618033 -117.523194) (xy 342.575165 -117.558869)
			(xy 342.527559 -117.587923) (xy 342.47623 -117.609735) (xy 342.422273 -117.623841) (xy 342.366836 -117.629941)
			(xy 342.311102 -117.627904) (xy 342.256259 -117.617774) (xy 342.203475 -117.599767) (xy 342.153875 -117.574266)
			(xy 342.108517 -117.541815) (xy 342.068368 -117.503106) (xy 342.034282 -117.458963) (xy 342.006986 -117.410328)
			(xy 341.987063 -117.358237) (xy 341.974937 -117.3038) (xy 341.970866 -117.248178) (xy 341.718392 -117.248178)
			(xy 341.717883 -117.276064) (xy 341.709763 -117.33124) (xy 341.693695 -117.384647) (xy 341.670023 -117.435144)
			(xy 341.63925 -117.481657) (xy 341.602033 -117.523194) (xy 341.559165 -117.558869) (xy 341.511559 -117.587923)
			(xy 341.46023 -117.609735) (xy 341.406273 -117.623841) (xy 341.350836 -117.629941) (xy 341.295102 -117.627904)
			(xy 341.240259 -117.617774) (xy 341.187475 -117.599767) (xy 341.137875 -117.574266) (xy 341.092517 -117.541815)
			(xy 341.052368 -117.503106) (xy 341.018282 -117.458963) (xy 340.990986 -117.410328) (xy 340.971063 -117.358237)
			(xy 340.958937 -117.3038) (xy 340.954866 -117.248178) (xy 340.702392 -117.248178) (xy 340.701883 -117.276064)
			(xy 340.693763 -117.33124) (xy 340.677695 -117.384647) (xy 340.654023 -117.435144) (xy 340.62325 -117.481657)
			(xy 340.586033 -117.523194) (xy 340.543165 -117.558869) (xy 340.495559 -117.587923) (xy 340.44423 -117.609735)
			(xy 340.390273 -117.623841) (xy 340.334836 -117.629941) (xy 340.279102 -117.627904) (xy 340.224259 -117.617774)
			(xy 340.171475 -117.599767) (xy 340.121875 -117.574266) (xy 340.076517 -117.541815) (xy 340.036368 -117.503106)
			(xy 340.002282 -117.458963) (xy 339.974986 -117.410328) (xy 339.955063 -117.358237) (xy 339.942937 -117.3038)
			(xy 339.938866 -117.248178) (xy 325.913756 -117.248178) (xy 325.894337 -117.289602) (xy 325.863564 -117.336115)
			(xy 325.826347 -117.377652) (xy 325.783479 -117.413327) (xy 325.735873 -117.442381) (xy 325.684544 -117.464193)
			(xy 325.630587 -117.478299) (xy 325.57515 -117.484399) (xy 325.519416 -117.482362) (xy 325.464573 -117.472232)
			(xy 325.411789 -117.454225) (xy 325.362189 -117.428724) (xy 325.316831 -117.396273) (xy 325.276682 -117.357564)
			(xy 325.242596 -117.313421) (xy 325.2153 -117.264786) (xy 325.195377 -117.212695) (xy 325.183251 -117.158258)
			(xy 325.17918 -117.102636) (xy 324.363966 -117.102636) (xy 324.391343 -117.134227) (xy 324.420818 -117.180087)
			(xy 324.443466 -117.229675) (xy 324.458826 -117.281982) (xy 324.466585 -117.335942) (xy 324.466585 -117.390458)
			(xy 324.458826 -117.444418) (xy 324.443466 -117.496725) (xy 324.420818 -117.546313) (xy 324.391343 -117.592173)
			(xy 324.355641 -117.633371) (xy 324.314439 -117.669068) (xy 324.268576 -117.698538) (xy 324.218985 -117.721181)
			(xy 324.166677 -117.736535) (xy 324.112716 -117.744288) (xy 324.085458 -117.744748) (xy 324.056542 -117.744208)
			(xy 323.999371 -117.735486) (xy 323.944171 -117.718234) (xy 323.892209 -117.692847) (xy 323.844675 -117.659906)
			(xy 323.802658 -117.620167) (xy 323.784468 -117.597682) (xy 323.776868 -117.588867) (xy 323.755962 -117.578688)
			(xy 323.744336 -117.578124) (xy 323.66458 -117.578124) (xy 323.652947 -117.578657) (xy 323.632037 -117.588849)
			(xy 323.624448 -117.597682) (xy 323.606225 -117.620139) (xy 323.564213 -117.659876) (xy 323.516685 -117.692819)
			(xy 323.464729 -117.718212) (xy 323.409537 -117.735474) (xy 323.352372 -117.74421) (xy 323.323458 -117.744748)
			(xy 323.296212 -117.744179) (xy 323.242274 -117.736418) (xy 323.18999 -117.721061) (xy 323.140423 -117.69842)
			(xy 323.094583 -117.668956) (xy 323.053402 -117.633268) (xy 323.017719 -117.592083) (xy 322.98826 -117.54624)
			(xy 322.965624 -117.496671) (xy 322.950273 -117.444385) (xy 322.942518 -117.390446) (xy 313.734636 -117.390446)
			(xy 313.651138 -118.062502) (xy 313.650884 -118.066566) (xy 313.649614 -118.093236) (xy 313.649614 -118.095522)
			(xy 313.647328 -118.150132) (xy 313.647873 -118.159151) (xy 313.654522 -118.175936) (xy 313.660282 -118.182898)
			(xy 313.693048 -118.219982) (xy 313.694572 -118.221252) (xy 313.696604 -118.223284) (xy 313.703645 -118.229714)
			(xy 313.721134 -118.237273) (xy 313.73064 -118.238016) (xy 313.732418 -118.238016) (xy 313.762376 -118.23852)
			(xy 313.821776 -118.246367) (xy 313.879644 -118.261897) (xy 313.934991 -118.284847) (xy 313.986869 -118.314822)
			(xy 314.034393 -118.351311) (xy 314.076749 -118.393689) (xy 314.113212 -118.441232) (xy 314.128594 -118.467886)
			(xy 329.682346 -118.467886) (xy 329.686417 -118.412264) (xy 329.698543 -118.357827) (xy 329.718466 -118.305736)
			(xy 329.745762 -118.257101) (xy 329.779848 -118.212958) (xy 329.819997 -118.174249) (xy 329.865355 -118.141798)
			(xy 329.914955 -118.116297) (xy 329.967739 -118.09829) (xy 330.022582 -118.08816) (xy 330.078316 -118.086123)
			(xy 330.133753 -118.092223) (xy 330.18771 -118.106329) (xy 330.239039 -118.128141) (xy 330.286645 -118.157195)
			(xy 330.329513 -118.19287) (xy 330.36673 -118.234407) (xy 330.397503 -118.28092) (xy 330.421175 -118.331417)
			(xy 330.437243 -118.384824) (xy 330.445363 -118.44) (xy 330.445872 -118.467886) (xy 330.445363 -118.495772)
			(xy 330.437243 -118.550948) (xy 330.421175 -118.604355) (xy 330.397503 -118.654852) (xy 330.36673 -118.701365)
			(xy 330.329513 -118.742902) (xy 330.308679 -118.76024) (xy 334.764378 -118.76024) (xy 334.768449 -118.704618)
			(xy 334.780575 -118.650181) (xy 334.800498 -118.59809) (xy 334.827794 -118.549455) (xy 334.86188 -118.505312)
			(xy 334.902029 -118.466603) (xy 334.947387 -118.434152) (xy 334.996987 -118.408651) (xy 335.049771 -118.390644)
			(xy 335.104614 -118.380514) (xy 335.160348 -118.378477) (xy 335.215785 -118.384577) (xy 335.269742 -118.398683)
			(xy 335.321071 -118.420495) (xy 335.368677 -118.449549) (xy 335.411545 -118.485224) (xy 335.448762 -118.526761)
			(xy 335.479535 -118.573274) (xy 335.503207 -118.623771) (xy 335.519275 -118.677178) (xy 335.527395 -118.732354)
			(xy 335.527904 -118.76024) (xy 335.527395 -118.788126) (xy 335.519275 -118.843302) (xy 335.503207 -118.896709)
			(xy 335.479535 -118.947206) (xy 335.448762 -118.993719) (xy 335.411545 -119.035256) (xy 335.368677 -119.070931)
			(xy 335.321071 -119.099985) (xy 335.269742 -119.121797) (xy 335.215785 -119.135903) (xy 335.160348 -119.142003)
			(xy 335.104614 -119.139966) (xy 335.049771 -119.129836) (xy 334.996987 -119.111829) (xy 334.947387 -119.086328)
			(xy 334.902029 -119.053877) (xy 334.86188 -119.015168) (xy 334.827794 -118.971025) (xy 334.800498 -118.92239)
			(xy 334.780575 -118.870299) (xy 334.768449 -118.815862) (xy 334.764378 -118.76024) (xy 330.308679 -118.76024)
			(xy 330.286645 -118.778577) (xy 330.239039 -118.807631) (xy 330.18771 -118.829443) (xy 330.133753 -118.843549)
			(xy 330.078316 -118.849649) (xy 330.022582 -118.847612) (xy 329.967739 -118.837482) (xy 329.914955 -118.819475)
			(xy 329.865355 -118.793974) (xy 329.819997 -118.761523) (xy 329.779848 -118.722814) (xy 329.745762 -118.678671)
			(xy 329.718466 -118.630036) (xy 329.698543 -118.577945) (xy 329.686417 -118.523508) (xy 329.682346 -118.467886)
			(xy 314.128594 -118.467886) (xy 314.14316 -118.493127) (xy 314.16608 -118.548486) (xy 314.181581 -118.606362)
			(xy 314.189396 -118.665766) (xy 314.189872 -118.695724) (xy 314.189872 -119.407557) (xy 326.699509 -119.407557)
			(xy 326.699509 -119.353043) (xy 326.707268 -119.299083) (xy 326.722627 -119.246777) (xy 326.745274 -119.197189)
			(xy 326.774748 -119.151329) (xy 326.810449 -119.11013) (xy 326.85165 -119.074432) (xy 326.897512 -119.044962)
			(xy 326.947101 -119.022318) (xy 326.999408 -119.006962) (xy 327.053369 -118.999207) (xy 327.080626 -118.998746)
			(xy 327.107997 -118.999186) (xy 327.162178 -119.007008) (xy 327.214682 -119.022503) (xy 327.264428 -119.045351)
			(xy 327.310394 -119.075082) (xy 327.331324 -119.092726) (xy 327.331578 -119.09298) (xy 327.33866 -119.098573)
			(xy 327.355581 -119.104814) (xy 327.364598 -119.105172) (xy 327.431654 -119.105172) (xy 327.440669 -119.104799)
			(xy 327.457587 -119.098563) (xy 327.464674 -119.09298) (xy 327.464674 -119.092726) (xy 327.464928 -119.092726)
			(xy 327.48588 -119.075111) (xy 327.531847 -119.045395) (xy 327.581589 -119.022554) (xy 327.634086 -119.007057)
			(xy 327.688258 -118.999223) (xy 327.715626 -118.998746) (xy 327.742873 -118.999326) (xy 327.796811 -119.007085)
			(xy 327.849096 -119.02244) (xy 327.898664 -119.04508) (xy 327.944506 -119.074543) (xy 327.985688 -119.11023)
			(xy 328.021372 -119.151415) (xy 328.050833 -119.197259) (xy 328.073469 -119.246828) (xy 328.088821 -119.299114)
			(xy 328.096576 -119.353053) (xy 328.096576 -119.407547) (xy 328.088821 -119.461486) (xy 328.084258 -119.477028)
			(xy 331.808072 -119.477028) (xy 331.812143 -119.421406) (xy 331.824269 -119.366969) (xy 331.844192 -119.314878)
			(xy 331.871488 -119.266243) (xy 331.905574 -119.2221) (xy 331.945723 -119.183391) (xy 331.991081 -119.15094)
			(xy 332.040681 -119.125439) (xy 332.093465 -119.107432) (xy 332.148308 -119.097302) (xy 332.204042 -119.095265)
			(xy 332.259479 -119.101365) (xy 332.313436 -119.115471) (xy 332.364765 -119.137283) (xy 332.412371 -119.166337)
			(xy 332.455239 -119.202012) (xy 332.492456 -119.243549) (xy 332.523229 -119.290062) (xy 332.546901 -119.340559)
			(xy 332.562969 -119.393966) (xy 332.571089 -119.449142) (xy 332.571598 -119.477028) (xy 332.571089 -119.504914)
			(xy 332.562969 -119.56009) (xy 332.546901 -119.613497) (xy 332.523229 -119.663994) (xy 332.492456 -119.710507)
			(xy 332.455239 -119.752044) (xy 332.426164 -119.77624) (xy 332.735934 -119.77624) (xy 332.740005 -119.720618)
			(xy 332.752131 -119.666181) (xy 332.772054 -119.61409) (xy 332.79935 -119.565455) (xy 332.833436 -119.521312)
			(xy 332.873585 -119.482603) (xy 332.918943 -119.450152) (xy 332.968543 -119.424651) (xy 333.021327 -119.406644)
			(xy 333.07617 -119.396514) (xy 333.131904 -119.394477) (xy 333.187341 -119.400577) (xy 333.241298 -119.414683)
			(xy 333.292627 -119.436495) (xy 333.340233 -119.465549) (xy 333.383101 -119.501224) (xy 333.420318 -119.542761)
			(xy 333.451091 -119.589274) (xy 333.474763 -119.639771) (xy 333.490831 -119.693178) (xy 333.494607 -119.718836)
			(xy 339.736428 -119.718836) (xy 339.740499 -119.663214) (xy 339.752625 -119.608777) (xy 339.772548 -119.556686)
			(xy 339.799844 -119.508051) (xy 339.83393 -119.463908) (xy 339.874079 -119.425199) (xy 339.919437 -119.392748)
			(xy 339.969037 -119.367247) (xy 340.021821 -119.34924) (xy 340.076664 -119.33911) (xy 340.132398 -119.337073)
			(xy 340.187835 -119.343173) (xy 340.241792 -119.357279) (xy 340.293121 -119.379091) (xy 340.340727 -119.408145)
			(xy 340.383595 -119.44382) (xy 340.420812 -119.485357) (xy 340.421519 -119.486426) (xy 357.987344 -119.486426)
			(xy 357.991415 -119.430804) (xy 358.003541 -119.376367) (xy 358.023464 -119.324276) (xy 358.05076 -119.275641)
			(xy 358.084846 -119.231498) (xy 358.124995 -119.192789) (xy 358.170353 -119.160338) (xy 358.219953 -119.134837)
			(xy 358.272737 -119.11683) (xy 358.32758 -119.1067) (xy 358.383314 -119.104663) (xy 358.438751 -119.110763)
			(xy 358.492708 -119.124869) (xy 358.544037 -119.146681) (xy 358.591643 -119.175735) (xy 358.634511 -119.21141)
			(xy 358.671728 -119.252947) (xy 358.702501 -119.29946) (xy 358.726173 -119.349957) (xy 358.727952 -119.35587)
			(xy 359.003344 -119.35587) (xy 359.007415 -119.300248) (xy 359.019541 -119.245811) (xy 359.039464 -119.19372)
			(xy 359.06676 -119.145085) (xy 359.100846 -119.100942) (xy 359.140995 -119.062233) (xy 359.186353 -119.029782)
			(xy 359.235953 -119.004281) (xy 359.288737 -118.986274) (xy 359.34358 -118.976144) (xy 359.399314 -118.974107)
			(xy 359.454751 -118.980207) (xy 359.508708 -118.994313) (xy 359.560037 -119.016125) (xy 359.607643 -119.045179)
			(xy 359.650511 -119.080854) (xy 359.687728 -119.122391) (xy 359.718501 -119.168904) (xy 359.742173 -119.219401)
			(xy 359.758241 -119.272808) (xy 359.766361 -119.327984) (xy 359.76687 -119.35587) (xy 360.019344 -119.35587)
			(xy 360.023415 -119.300248) (xy 360.035541 -119.245811) (xy 360.055464 -119.19372) (xy 360.08276 -119.145085)
			(xy 360.116846 -119.100942) (xy 360.156995 -119.062233) (xy 360.202353 -119.029782) (xy 360.251953 -119.004281)
			(xy 360.304737 -118.986274) (xy 360.35958 -118.976144) (xy 360.415314 -118.974107) (xy 360.470751 -118.980207)
			(xy 360.524708 -118.994313) (xy 360.576037 -119.016125) (xy 360.623643 -119.045179) (xy 360.666511 -119.080854)
			(xy 360.703728 -119.122391) (xy 360.734501 -119.168904) (xy 360.758173 -119.219401) (xy 360.774241 -119.272808)
			(xy 360.782361 -119.327984) (xy 360.78287 -119.35587) (xy 360.782361 -119.383756) (xy 360.781232 -119.39143)
			(xy 363.214918 -119.39143) (xy 363.218989 -119.335808) (xy 363.231115 -119.281371) (xy 363.251038 -119.22928)
			(xy 363.278334 -119.180645) (xy 363.31242 -119.136502) (xy 363.352569 -119.097793) (xy 363.397927 -119.065342)
			(xy 363.447527 -119.039841) (xy 363.500311 -119.021834) (xy 363.555154 -119.011704) (xy 363.610888 -119.009667)
			(xy 363.666325 -119.015767) (xy 363.720282 -119.029873) (xy 363.771611 -119.051685) (xy 363.819217 -119.080739)
			(xy 363.862085 -119.116414) (xy 363.899302 -119.157951) (xy 363.930075 -119.204464) (xy 363.953747 -119.254961)
			(xy 363.969815 -119.308368) (xy 363.977935 -119.363544) (xy 363.978444 -119.39143) (xy 363.977935 -119.419316)
			(xy 363.969815 -119.474492) (xy 363.953747 -119.527899) (xy 363.930075 -119.578396) (xy 363.899302 -119.624909)
			(xy 363.862085 -119.666446) (xy 363.819217 -119.702121) (xy 363.771611 -119.731175) (xy 363.720282 -119.752987)
			(xy 363.666325 -119.767093) (xy 363.610888 -119.773193) (xy 363.555154 -119.771156) (xy 363.500311 -119.761026)
			(xy 363.447527 -119.743019) (xy 363.397927 -119.717518) (xy 363.352569 -119.685067) (xy 363.31242 -119.646358)
			(xy 363.278334 -119.602215) (xy 363.251038 -119.55358) (xy 363.231115 -119.501489) (xy 363.218989 -119.447052)
			(xy 363.214918 -119.39143) (xy 360.781232 -119.39143) (xy 360.774241 -119.438932) (xy 360.758173 -119.492339)
			(xy 360.734501 -119.542836) (xy 360.703728 -119.589349) (xy 360.666511 -119.630886) (xy 360.623643 -119.666561)
			(xy 360.576037 -119.695615) (xy 360.524708 -119.717427) (xy 360.470751 -119.731533) (xy 360.415314 -119.737633)
			(xy 360.35958 -119.735596) (xy 360.304737 -119.725466) (xy 360.251953 -119.707459) (xy 360.202353 -119.681958)
			(xy 360.156995 -119.649507) (xy 360.116846 -119.610798) (xy 360.08276 -119.566655) (xy 360.055464 -119.51802)
			(xy 360.035541 -119.465929) (xy 360.023415 -119.411492) (xy 360.019344 -119.35587) (xy 359.76687 -119.35587)
			(xy 359.766361 -119.383756) (xy 359.758241 -119.438932) (xy 359.742173 -119.492339) (xy 359.718501 -119.542836)
			(xy 359.687728 -119.589349) (xy 359.650511 -119.630886) (xy 359.607643 -119.666561) (xy 359.560037 -119.695615)
			(xy 359.508708 -119.717427) (xy 359.454751 -119.731533) (xy 359.399314 -119.737633) (xy 359.34358 -119.735596)
			(xy 359.288737 -119.725466) (xy 359.235953 -119.707459) (xy 359.186353 -119.681958) (xy 359.140995 -119.649507)
			(xy 359.100846 -119.610798) (xy 359.06676 -119.566655) (xy 359.039464 -119.51802) (xy 359.019541 -119.465929)
			(xy 359.007415 -119.411492) (xy 359.003344 -119.35587) (xy 358.727952 -119.35587) (xy 358.742241 -119.403364)
			(xy 358.750361 -119.45854) (xy 358.75087 -119.486426) (xy 358.750361 -119.514312) (xy 358.742241 -119.569488)
			(xy 358.726173 -119.622895) (xy 358.702501 -119.673392) (xy 358.671728 -119.719905) (xy 358.634511 -119.761442)
			(xy 358.591643 -119.797117) (xy 358.544037 -119.826171) (xy 358.492708 -119.847983) (xy 358.438751 -119.862089)
			(xy 358.383314 -119.868189) (xy 358.32758 -119.866152) (xy 358.272737 -119.856022) (xy 358.219953 -119.838015)
			(xy 358.170353 -119.812514) (xy 358.124995 -119.780063) (xy 358.084846 -119.741354) (xy 358.05076 -119.697211)
			(xy 358.023464 -119.648576) (xy 358.003541 -119.596485) (xy 357.991415 -119.542048) (xy 357.987344 -119.486426)
			(xy 340.421519 -119.486426) (xy 340.451585 -119.53187) (xy 340.475257 -119.582367) (xy 340.491325 -119.635774)
			(xy 340.499445 -119.69095) (xy 340.499954 -119.718836) (xy 340.499445 -119.746722) (xy 340.491325 -119.801898)
			(xy 340.475257 -119.855305) (xy 340.451585 -119.905802) (xy 340.420812 -119.952315) (xy 340.383595 -119.993852)
			(xy 340.340727 -120.029527) (xy 340.293121 -120.058581) (xy 340.241792 -120.080393) (xy 340.187835 -120.094499)
			(xy 340.132398 -120.100599) (xy 340.076664 -120.098562) (xy 340.021821 -120.088432) (xy 339.969037 -120.070425)
			(xy 339.919437 -120.044924) (xy 339.874079 -120.012473) (xy 339.83393 -119.973764) (xy 339.799844 -119.929621)
			(xy 339.772548 -119.880986) (xy 339.752625 -119.828895) (xy 339.740499 -119.774458) (xy 339.736428 -119.718836)
			(xy 333.494607 -119.718836) (xy 333.498951 -119.748354) (xy 333.49946 -119.77624) (xy 333.498951 -119.804126)
			(xy 333.490831 -119.859302) (xy 333.474763 -119.912709) (xy 333.451091 -119.963206) (xy 333.420318 -120.009719)
			(xy 333.383101 -120.051256) (xy 333.340233 -120.086931) (xy 333.292627 -120.115985) (xy 333.241298 -120.137797)
			(xy 333.187341 -120.151903) (xy 333.131904 -120.158003) (xy 333.07617 -120.155966) (xy 333.021327 -120.145836)
			(xy 332.968543 -120.127829) (xy 332.918943 -120.102328) (xy 332.873585 -120.069877) (xy 332.833436 -120.031168)
			(xy 332.79935 -119.987025) (xy 332.772054 -119.93839) (xy 332.752131 -119.886299) (xy 332.740005 -119.831862)
			(xy 332.735934 -119.77624) (xy 332.426164 -119.77624) (xy 332.412371 -119.787719) (xy 332.364765 -119.816773)
			(xy 332.313436 -119.838585) (xy 332.259479 -119.852691) (xy 332.204042 -119.858791) (xy 332.148308 -119.856754)
			(xy 332.093465 -119.846624) (xy 332.040681 -119.828617) (xy 331.991081 -119.803116) (xy 331.945723 -119.770665)
			(xy 331.905574 -119.731956) (xy 331.871488 -119.687813) (xy 331.844192 -119.639178) (xy 331.824269 -119.587087)
			(xy 331.812143 -119.53265) (xy 331.808072 -119.477028) (xy 328.084258 -119.477028) (xy 328.073469 -119.513772)
			(xy 328.050833 -119.563341) (xy 328.021372 -119.609185) (xy 327.985688 -119.65037) (xy 327.944506 -119.686057)
			(xy 327.898664 -119.71552) (xy 327.849096 -119.73816) (xy 327.796811 -119.753515) (xy 327.742873 -119.761274)
			(xy 327.715626 -119.761762) (xy 327.688256 -119.76129) (xy 327.634077 -119.753475) (xy 327.581573 -119.737988)
			(xy 327.531826 -119.715147) (xy 327.48586 -119.685423) (xy 327.464928 -119.667782) (xy 327.464674 -119.667528)
			(xy 327.457577 -119.661958) (xy 327.440668 -119.655703) (xy 327.431654 -119.655336) (xy 327.364598 -119.655336)
			(xy 327.35558 -119.655684) (xy 327.338663 -119.661937) (xy 327.331578 -119.667528) (xy 327.331578 -119.667782)
			(xy 327.331324 -119.667782) (xy 327.310391 -119.685421) (xy 327.264419 -119.715133) (xy 327.214672 -119.737969)
			(xy 327.162171 -119.753461) (xy 327.107995 -119.761288) (xy 327.080626 -119.761762) (xy 327.053369 -119.761393)
			(xy 326.999408 -119.753638) (xy 326.947101 -119.738282) (xy 326.897512 -119.715638) (xy 326.85165 -119.686168)
			(xy 326.810449 -119.65047) (xy 326.774748 -119.609271) (xy 326.745274 -119.563411) (xy 326.722627 -119.513823)
			(xy 326.707268 -119.461517) (xy 326.699509 -119.407557) (xy 314.189872 -119.407557) (xy 314.189872 -119.559324)
			(xy 314.189401 -119.589291) (xy 314.181575 -119.648712) (xy 314.16606 -119.706604) (xy 314.143121 -119.761974)
			(xy 314.11315 -119.813877) (xy 314.076661 -119.861424) (xy 314.045001 -119.89308) (xy 329.76896 -119.89308)
			(xy 329.773031 -119.837458) (xy 329.785157 -119.783021) (xy 329.80508 -119.73093) (xy 329.832376 -119.682295)
			(xy 329.866462 -119.638152) (xy 329.906611 -119.599443) (xy 329.951969 -119.566992) (xy 330.001569 -119.541491)
			(xy 330.054353 -119.523484) (xy 330.109196 -119.513354) (xy 330.16493 -119.511317) (xy 330.220367 -119.517417)
			(xy 330.274324 -119.531523) (xy 330.325653 -119.553335) (xy 330.373259 -119.582389) (xy 330.416127 -119.618064)
			(xy 330.453344 -119.659601) (xy 330.484117 -119.706114) (xy 330.507789 -119.756611) (xy 330.523857 -119.810018)
			(xy 330.531977 -119.865194) (xy 330.532486 -119.89308) (xy 330.531977 -119.920966) (xy 330.523857 -119.976142)
			(xy 330.507789 -120.029549) (xy 330.484117 -120.080046) (xy 330.453344 -120.126559) (xy 330.416127 -120.168096)
			(xy 330.373259 -120.203771) (xy 330.325653 -120.232825) (xy 330.274324 -120.254637) (xy 330.220367 -120.268743)
			(xy 330.16493 -120.274843) (xy 330.109196 -120.272806) (xy 330.054353 -120.262676) (xy 330.001569 -120.244669)
			(xy 329.951969 -120.219168) (xy 329.906611 -120.186717) (xy 329.866462 -120.148008) (xy 329.832376 -120.103865)
			(xy 329.80508 -120.05523) (xy 329.785157 -120.003139) (xy 329.773031 -119.948702) (xy 329.76896 -119.89308)
			(xy 314.045001 -119.89308) (xy 314.034279 -119.903801) (xy 313.986727 -119.940284) (xy 313.93482 -119.970247)
			(xy 313.879447 -119.993179) (xy 313.821553 -120.008687) (xy 313.762131 -120.016505) (xy 313.732164 -120.017032)
			(xy 313.72027 -120.017002) (xy 313.696508 -120.015858) (xy 313.684666 -120.014746) (xy 313.672712 -120.013456)
			(xy 313.648951 -120.009772) (xy 313.637168 -120.00738) (xy 313.636914 -120.00738) (xy 313.635898 -120.007126)
			(xy 313.633866 -120.006618) (xy 313.630818 -120.00611) (xy 313.629294 -120.005602) (xy 313.62904 -120.005602)
			(xy 313.625992 -120.00484) (xy 313.623706 -120.004332) (xy 313.622944 -120.004332) (xy 313.616594 -120.004078)
			(xy 313.607323 -120.004537) (xy 313.590024 -120.011229) (xy 313.57623 -120.023629) (xy 313.567739 -120.040119)
			(xy 313.566302 -120.04929) (xy 313.539632 -120.6754) (xy 313.510267 -121.365772) (xy 315.916564 -121.365772)
			(xy 315.916564 -120.502172) (xy 315.917054 -120.472204) (xy 315.924877 -120.412782) (xy 315.94039 -120.354889)
			(xy 315.963326 -120.299516) (xy 315.993293 -120.24761) (xy 316.02978 -120.20006) (xy 316.07216 -120.15768)
			(xy 316.11971 -120.121193) (xy 316.171616 -120.091226) (xy 316.226989 -120.06829) (xy 316.284882 -120.052777)
			(xy 316.344304 -120.044954) (xy 316.40424 -120.044954) (xy 316.463662 -120.052777) (xy 316.521555 -120.06829)
			(xy 316.576928 -120.091226) (xy 316.628834 -120.121193) (xy 316.676384 -120.15768) (xy 316.718764 -120.20006)
			(xy 316.755251 -120.24761) (xy 316.785218 -120.299516) (xy 316.808154 -120.354889) (xy 316.823667 -120.412782)
			(xy 316.83149 -120.472204) (xy 316.83198 -120.502172) (xy 316.83198 -121.365772) (xy 316.83149 -121.39574)
			(xy 316.823667 -121.455162) (xy 316.808154 -121.513055) (xy 316.785218 -121.568428) (xy 316.755251 -121.620334)
			(xy 316.718764 -121.667884) (xy 316.676384 -121.710264) (xy 316.628834 -121.746751) (xy 316.576928 -121.776718)
			(xy 316.521555 -121.799654) (xy 316.463662 -121.815167) (xy 316.40424 -121.82299) (xy 316.344304 -121.82299)
			(xy 316.284882 -121.815167) (xy 316.226989 -121.799654) (xy 316.171616 -121.776718) (xy 316.11971 -121.746751)
			(xy 316.07216 -121.710264) (xy 316.02978 -121.667884) (xy 315.993293 -121.620334) (xy 315.963326 -121.568428)
			(xy 315.94039 -121.513055) (xy 315.924877 -121.455162) (xy 315.917054 -121.39574) (xy 315.916564 -121.365772)
			(xy 313.510267 -121.365772) (xy 313.490864 -121.821956) (xy 313.49099 -121.834084) (xy 313.501063 -121.856109)
			(xy 313.510168 -121.86412) (xy 313.518042 -121.868946) (xy 313.523048 -121.871415) (xy 313.533813 -121.874351)
			(xy 313.539378 -121.874788) (xy 313.5503 -121.875296) (xy 313.56046 -121.871232) (xy 313.561984 -121.87047)
			(xy 313.563254 -121.869962) (xy 313.588654 -121.860818) (xy 313.59602 -121.858532) (xy 313.607958 -121.854976)
			(xy 313.608212 -121.854976) (xy 313.609482 -121.854468) (xy 313.611768 -121.85396) (xy 313.617864 -121.852182)
			(xy 313.618118 -121.852182) (xy 313.624214 -121.850658) (xy 313.662568 -121.843038) (xy 313.673236 -121.841514)
			(xy 313.68784 -121.839738) (xy 313.717199 -121.837834) (xy 313.73191 -121.837704) (xy 313.751214 -121.837704)
			(xy 313.756294 -121.837958) (xy 313.77763 -121.83999) (xy 313.787028 -121.841006) (xy 313.816965 -121.845103)
			(xy 313.875483 -121.860163) (xy 313.931513 -121.882787) (xy 313.984081 -121.912583) (xy 314.032274 -121.949033)
			(xy 314.075255 -121.991503) (xy 314.112278 -122.039257) (xy 314.1427 -122.091465) (xy 314.165993 -122.14722)
			(xy 314.178099 -122.192034) (xy 321.650614 -122.192034) (xy 321.651097 -122.164664) (xy 321.65891 -122.110486)
			(xy 321.674395 -122.057983) (xy 321.697233 -122.008236) (xy 321.726954 -121.962268) (xy 321.744594 -121.941336)
			(xy 321.744848 -121.941082) (xy 321.750454 -121.934009) (xy 321.756688 -121.917082) (xy 321.75704 -121.908062)
			(xy 321.75704 -121.841006) (xy 321.756693 -121.831988) (xy 321.75044 -121.81507) (xy 321.744848 -121.807986)
			(xy 321.744594 -121.807986) (xy 321.744594 -121.807732) (xy 321.726988 -121.786772) (xy 321.697264 -121.740808)
			(xy 321.674419 -121.691066) (xy 321.658922 -121.638568) (xy 321.65109 -121.584394) (xy 321.651087 -121.529657)
			(xy 321.658911 -121.475482) (xy 321.674401 -121.422982) (xy 321.69724 -121.373237) (xy 321.726957 -121.327269)
			(xy 321.744594 -121.306336) (xy 321.744848 -121.306082) (xy 321.750454 -121.299009) (xy 321.756688 -121.282082)
			(xy 321.75704 -121.273062) (xy 321.75704 -121.206006) (xy 321.756693 -121.196988) (xy 321.75044 -121.18007)
			(xy 321.744848 -121.172986) (xy 321.744594 -121.172986) (xy 321.744594 -121.172732) (xy 321.726988 -121.151772)
			(xy 321.697264 -121.105808) (xy 321.674419 -121.056066) (xy 321.658922 -121.003568) (xy 321.65109 -120.949394)
			(xy 321.651087 -120.894657) (xy 321.658911 -120.840482) (xy 321.674401 -120.787982) (xy 321.69724 -120.738237)
			(xy 321.726957 -120.692269) (xy 321.744594 -120.671336) (xy 321.744848 -120.671082) (xy 321.750454 -120.664009)
			(xy 321.756688 -120.647082) (xy 321.75704 -120.638062) (xy 321.75704 -120.571006) (xy 321.756693 -120.561988)
			(xy 321.75044 -120.54507) (xy 321.744848 -120.537986) (xy 321.744594 -120.537986) (xy 321.744594 -120.537732)
			(xy 321.726956 -120.516799) (xy 321.697244 -120.470827) (xy 321.674408 -120.421079) (xy 321.658917 -120.368579)
			(xy 321.651088 -120.314403) (xy 321.650614 -120.287034) (xy 321.6511 -120.259783) (xy 321.658856 -120.205835)
			(xy 321.674211 -120.15354) (xy 321.696853 -120.103963) (xy 321.726319 -120.058113) (xy 321.76201 -120.016922)
			(xy 321.803201 -119.981231) (xy 321.849051 -119.951765) (xy 321.898628 -119.929123) (xy 321.950923 -119.913768)
			(xy 322.004871 -119.906012) (xy 322.059373 -119.906012) (xy 322.113321 -119.913768) (xy 322.165616 -119.929123)
			(xy 322.215193 -119.951765) (xy 322.261043 -119.981231) (xy 322.302234 -120.016922) (xy 322.337925 -120.058113)
			(xy 322.367391 -120.103963) (xy 322.390033 -120.15354) (xy 322.405388 -120.205835) (xy 322.413144 -120.259783)
			(xy 322.41363 -120.287034) (xy 322.413201 -120.314406) (xy 322.405377 -120.368587) (xy 322.38988 -120.421091)
			(xy 322.36703 -120.470838) (xy 322.352675 -120.493028) (xy 331.804008 -120.493028) (xy 331.808079 -120.437406)
			(xy 331.820205 -120.382969) (xy 331.840128 -120.330878) (xy 331.867424 -120.282243) (xy 331.90151 -120.2381)
			(xy 331.941659 -120.199391) (xy 331.987017 -120.16694) (xy 332.036617 -120.141439) (xy 332.089401 -120.123432)
			(xy 332.144244 -120.113302) (xy 332.199978 -120.111265) (xy 332.255415 -120.117365) (xy 332.309372 -120.131471)
			(xy 332.360701 -120.153283) (xy 332.408307 -120.182337) (xy 332.451175 -120.218012) (xy 332.488392 -120.259549)
			(xy 332.519165 -120.306062) (xy 332.542837 -120.356559) (xy 332.558905 -120.409966) (xy 332.567025 -120.465142)
			(xy 332.567534 -120.493028) (xy 332.567025 -120.520914) (xy 332.558905 -120.57609) (xy 332.542837 -120.629497)
			(xy 332.519165 -120.679994) (xy 332.488392 -120.726507) (xy 332.451175 -120.768044) (xy 332.4221 -120.79224)
			(xy 332.735934 -120.79224) (xy 332.740005 -120.736618) (xy 332.752131 -120.682181) (xy 332.772054 -120.63009)
			(xy 332.79935 -120.581455) (xy 332.833436 -120.537312) (xy 332.873585 -120.498603) (xy 332.918943 -120.466152)
			(xy 332.968543 -120.440651) (xy 333.021327 -120.422644) (xy 333.07617 -120.412514) (xy 333.131904 -120.410477)
			(xy 333.187341 -120.416577) (xy 333.241298 -120.430683) (xy 333.292627 -120.452495) (xy 333.340233 -120.481549)
			(xy 333.383101 -120.517224) (xy 333.420318 -120.558761) (xy 333.451091 -120.605274) (xy 333.474763 -120.655771)
			(xy 333.490831 -120.709178) (xy 333.498951 -120.764354) (xy 333.49946 -120.79224) (xy 334.891378 -120.79224)
			(xy 334.895449 -120.736618) (xy 334.907575 -120.682181) (xy 334.927498 -120.63009) (xy 334.954794 -120.581455)
			(xy 334.98888 -120.537312) (xy 335.029029 -120.498603) (xy 335.074387 -120.466152) (xy 335.123987 -120.440651)
			(xy 335.176771 -120.422644) (xy 335.231614 -120.412514) (xy 335.287348 -120.410477) (xy 335.342785 -120.416577)
			(xy 335.396742 -120.430683) (xy 335.448071 -120.452495) (xy 335.495677 -120.481549) (xy 335.538545 -120.517224)
			(xy 335.546679 -120.526302) (xy 338.193378 -120.526302) (xy 338.197449 -120.47068) (xy 338.209575 -120.416243)
			(xy 338.229498 -120.364152) (xy 338.256794 -120.315517) (xy 338.29088 -120.271374) (xy 338.331029 -120.232665)
			(xy 338.376387 -120.200214) (xy 338.425987 -120.174713) (xy 338.478771 -120.156706) (xy 338.533614 -120.146576)
			(xy 338.589348 -120.144539) (xy 338.644785 -120.150639) (xy 338.698742 -120.164745) (xy 338.750071 -120.186557)
			(xy 338.797677 -120.215611) (xy 338.840545 -120.251286) (xy 338.877762 -120.292823) (xy 338.908535 -120.339336)
			(xy 338.932207 -120.389833) (xy 338.948275 -120.44324) (xy 338.956395 -120.498416) (xy 338.956904 -120.526302)
			(xy 338.956395 -120.554188) (xy 338.948275 -120.609364) (xy 338.932207 -120.662771) (xy 338.908535 -120.713268)
			(xy 338.877762 -120.759781) (xy 338.840545 -120.801318) (xy 338.797677 -120.836993) (xy 338.750071 -120.866047)
			(xy 338.698742 -120.887859) (xy 338.644785 -120.901965) (xy 338.589348 -120.908065) (xy 338.533614 -120.906028)
			(xy 338.478771 -120.895898) (xy 338.425987 -120.877891) (xy 338.376387 -120.85239) (xy 338.331029 -120.819939)
			(xy 338.29088 -120.78123) (xy 338.256794 -120.737087) (xy 338.229498 -120.688452) (xy 338.209575 -120.636361)
			(xy 338.197449 -120.581924) (xy 338.193378 -120.526302) (xy 335.546679 -120.526302) (xy 335.575762 -120.558761)
			(xy 335.606535 -120.605274) (xy 335.630207 -120.655771) (xy 335.646275 -120.709178) (xy 335.654395 -120.764354)
			(xy 335.654904 -120.79224) (xy 335.654395 -120.820126) (xy 335.646275 -120.875302) (xy 335.630207 -120.928709)
			(xy 335.606535 -120.979206) (xy 335.575762 -121.025719) (xy 335.538545 -121.067256) (xy 335.495677 -121.102931)
			(xy 335.448071 -121.131985) (xy 335.396742 -121.153797) (xy 335.342785 -121.167903) (xy 335.287348 -121.174003)
			(xy 335.231614 -121.171966) (xy 335.176771 -121.161836) (xy 335.123987 -121.143829) (xy 335.074387 -121.118328)
			(xy 335.029029 -121.085877) (xy 334.98888 -121.047168) (xy 334.954794 -121.003025) (xy 334.927498 -120.95439)
			(xy 334.907575 -120.902299) (xy 334.895449 -120.847862) (xy 334.891378 -120.79224) (xy 333.49946 -120.79224)
			(xy 333.498951 -120.820126) (xy 333.490831 -120.875302) (xy 333.474763 -120.928709) (xy 333.451091 -120.979206)
			(xy 333.420318 -121.025719) (xy 333.383101 -121.067256) (xy 333.340233 -121.102931) (xy 333.292627 -121.131985)
			(xy 333.241298 -121.153797) (xy 333.187341 -121.167903) (xy 333.131904 -121.174003) (xy 333.07617 -121.171966)
			(xy 333.021327 -121.161836) (xy 332.968543 -121.143829) (xy 332.918943 -121.118328) (xy 332.873585 -121.085877)
			(xy 332.833436 -121.047168) (xy 332.79935 -121.003025) (xy 332.772054 -120.95439) (xy 332.752131 -120.902299)
			(xy 332.740005 -120.847862) (xy 332.735934 -120.79224) (xy 332.4221 -120.79224) (xy 332.408307 -120.803719)
			(xy 332.360701 -120.832773) (xy 332.309372 -120.854585) (xy 332.255415 -120.868691) (xy 332.199978 -120.874791)
			(xy 332.144244 -120.872754) (xy 332.089401 -120.862624) (xy 332.036617 -120.844617) (xy 331.987017 -120.819116)
			(xy 331.941659 -120.786665) (xy 331.90151 -120.747956) (xy 331.867424 -120.703813) (xy 331.840128 -120.655178)
			(xy 331.820205 -120.603087) (xy 331.808079 -120.54865) (xy 331.804008 -120.493028) (xy 322.352675 -120.493028)
			(xy 322.337296 -120.516802) (xy 322.31965 -120.537732) (xy 322.319396 -120.537986) (xy 322.313809 -120.545072)
			(xy 322.307563 -120.561989) (xy 322.307204 -120.571006) (xy 322.307204 -120.638062) (xy 322.307579 -120.647077)
			(xy 322.313814 -120.663994) (xy 322.319396 -120.671082) (xy 322.31965 -120.671082) (xy 322.31965 -120.671336)
			(xy 322.337325 -120.692241) (xy 322.36705 -120.738213) (xy 322.389895 -120.787964) (xy 322.40539 -120.84047)
			(xy 322.413215 -120.894653) (xy 322.413212 -120.949398) (xy 322.405379 -121.00358) (xy 322.389877 -121.056084)
			(xy 322.367025 -121.105832) (xy 322.337294 -121.1518) (xy 322.31965 -121.172732) (xy 322.319396 -121.172986)
			(xy 322.313809 -121.180072) (xy 322.307563 -121.196989) (xy 322.307493 -121.198756) (xy 322.685317 -121.198756)
			(xy 322.685317 -121.144244) (xy 322.693075 -121.090287) (xy 322.708433 -121.037983) (xy 322.731079 -120.988397)
			(xy 322.76055 -120.942539) (xy 322.796249 -120.901342) (xy 322.837447 -120.865644) (xy 322.883306 -120.836174)
			(xy 322.932892 -120.81353) (xy 322.985196 -120.798173) (xy 323.039154 -120.790416) (xy 323.06641 -120.789954)
			(xy 323.093781 -120.790401) (xy 323.147962 -120.798221) (xy 323.200465 -120.813714) (xy 323.250212 -120.836561)
			(xy 323.296177 -120.86629) (xy 323.317108 -120.883934) (xy 323.317362 -120.884188) (xy 323.324456 -120.889763)
			(xy 323.341367 -120.896017) (xy 323.350382 -120.89638) (xy 323.417438 -120.89638) (xy 323.426457 -120.896045)
			(xy 323.443374 -120.889783) (xy 323.450458 -120.884188) (xy 323.450458 -120.883934) (xy 323.450712 -120.883934)
			(xy 323.471671 -120.866328) (xy 323.517636 -120.83661) (xy 323.567376 -120.813767) (xy 323.619871 -120.798268)
			(xy 323.674043 -120.790432) (xy 323.70141 -120.789954) (xy 323.728658 -120.790517) (xy 323.782599 -120.798274)
			(xy 323.834888 -120.813628) (xy 323.884458 -120.836268) (xy 323.930303 -120.865731) (xy 323.971488 -120.901419)
			(xy 324.007175 -120.942605) (xy 324.036637 -120.98845) (xy 324.059275 -121.038022) (xy 324.074628 -121.090311)
			(xy 324.082384 -121.144252) (xy 324.082384 -121.198748) (xy 324.074628 -121.252689) (xy 324.059275 -121.304978)
			(xy 324.036637 -121.35455) (xy 324.007175 -121.400395) (xy 323.971488 -121.441581) (xy 323.930303 -121.477269)
			(xy 323.884458 -121.506732) (xy 323.834888 -121.529372) (xy 323.782599 -121.544726) (xy 323.728658 -121.552483)
			(xy 323.70141 -121.55297) (xy 323.67404 -121.552505) (xy 323.61986 -121.544688) (xy 323.567357 -121.529199)
			(xy 323.51761 -121.506357) (xy 323.471643 -121.476632) (xy 323.450712 -121.45899) (xy 323.450458 -121.458736)
			(xy 323.443364 -121.45316) (xy 323.426453 -121.446909) (xy 323.417438 -121.446544) (xy 323.350382 -121.446544)
			(xy 323.341363 -121.446883) (xy 323.324446 -121.453142) (xy 323.317362 -121.458736) (xy 323.317362 -121.45899)
			(xy 323.317108 -121.45899) (xy 323.296182 -121.476637) (xy 323.250208 -121.506348) (xy 323.200459 -121.529183)
			(xy 323.147957 -121.544672) (xy 323.09378 -121.552497) (xy 323.06641 -121.55297) (xy 323.039154 -121.552584)
			(xy 322.985197 -121.544827) (xy 322.932892 -121.52947) (xy 322.883306 -121.506826) (xy 322.837447 -121.477356)
			(xy 322.796249 -121.441658) (xy 322.76055 -121.400461) (xy 322.731079 -121.354603) (xy 322.708433 -121.305017)
			(xy 322.693075 -121.252713) (xy 322.685317 -121.198756) (xy 322.307493 -121.198756) (xy 322.307204 -121.206006)
			(xy 322.307204 -121.273062) (xy 322.307579 -121.282077) (xy 322.313814 -121.298994) (xy 322.319396 -121.306082)
			(xy 322.31965 -121.306082) (xy 322.31965 -121.306336) (xy 322.337325 -121.327241) (xy 322.36705 -121.373213)
			(xy 322.389895 -121.422964) (xy 322.40539 -121.47547) (xy 322.413215 -121.529653) (xy 322.413212 -121.584398)
			(xy 322.405968 -121.634504) (xy 324.20433 -121.634504) (xy 324.204791 -121.607134) (xy 324.212609 -121.552954)
			(xy 324.228099 -121.50045) (xy 324.250942 -121.450704) (xy 324.280668 -121.404737) (xy 324.29831 -121.383806)
			(xy 324.298564 -121.383552) (xy 324.304143 -121.37646) (xy 324.310392 -121.359547) (xy 324.310756 -121.350532)
			(xy 324.310756 -121.283476) (xy 324.31042 -121.274457) (xy 324.304159 -121.257539) (xy 324.298564 -121.250456)
			(xy 324.29831 -121.250456) (xy 324.29831 -121.250202) (xy 324.28066 -121.229279) (xy 324.250949 -121.183304)
			(xy 324.228115 -121.133554) (xy 324.212627 -121.081051) (xy 324.204802 -121.026874) (xy 324.20433 -120.999504)
			(xy 324.204759 -120.97225) (xy 324.212517 -120.918295) (xy 324.227874 -120.865995) (xy 324.250519 -120.816412)
			(xy 324.27999 -120.770557) (xy 324.315687 -120.729363) (xy 324.356884 -120.69367) (xy 324.402742 -120.664203)
			(xy 324.452326 -120.641562) (xy 324.504629 -120.626209) (xy 324.558583 -120.618457) (xy 324.585838 -120.617996)
			(xy 324.61496 -120.618546) (xy 324.672531 -120.627378) (xy 324.72809 -120.64486) (xy 324.780344 -120.670586)
			(xy 324.82808 -120.703959) (xy 324.870186 -120.744201) (xy 324.905684 -120.790378) (xy 324.933748 -120.841415)
			(xy 324.953726 -120.896126) (xy 324.95998 -120.924574) (xy 324.962266 -120.936258) (xy 324.976744 -120.955054)
			(xy 325.060818 -120.99544) (xy 325.071632 -121.000003) (xy 325.095071 -120.999743) (xy 325.105776 -120.994932)
			(xy 325.106284 -120.994932) (xy 325.13334 -120.981644) (xy 325.190617 -120.962868) (xy 325.250136 -120.953351)
			(xy 325.280274 -120.952768) (xy 325.307525 -120.953279) (xy 325.361473 -120.961032) (xy 325.413769 -120.976384)
			(xy 325.463347 -120.999021) (xy 325.509199 -121.028485) (xy 325.550391 -121.064173) (xy 325.586085 -121.105361)
			(xy 325.615555 -121.151209) (xy 325.638199 -121.200785) (xy 325.649355 -121.238772) (xy 329.7842 -121.238772)
			(xy 329.788271 -121.18315) (xy 329.800397 -121.128713) (xy 329.82032 -121.076622) (xy 329.847616 -121.027987)
			(xy 329.881702 -120.983844) (xy 329.921851 -120.945135) (xy 329.967209 -120.912684) (xy 330.016809 -120.887183)
			(xy 330.069593 -120.869176) (xy 330.124436 -120.859046) (xy 330.18017 -120.857009) (xy 330.235607 -120.863109)
			(xy 330.289564 -120.877215) (xy 330.340893 -120.899027) (xy 330.388499 -120.928081) (xy 330.431367 -120.963756)
			(xy 330.468584 -121.005293) (xy 330.499357 -121.051806) (xy 330.523029 -121.102303) (xy 330.539097 -121.15571)
			(xy 330.547217 -121.210886) (xy 330.547726 -121.238772) (xy 330.547217 -121.266658) (xy 330.539097 -121.321834)
			(xy 330.523029 -121.375241) (xy 330.499357 -121.425738) (xy 330.468584 -121.472251) (xy 330.431367 -121.513788)
			(xy 330.388499 -121.549463) (xy 330.35362 -121.57075) (xy 361.920028 -121.57075) (xy 361.920517 -121.54338)
			(xy 361.928328 -121.489202) (xy 361.943811 -121.436699) (xy 361.966648 -121.386952) (xy 361.996369 -121.340984)
			(xy 362.014008 -121.320052) (xy 362.014262 -121.319798) (xy 362.019863 -121.312722) (xy 362.026099 -121.295797)
			(xy 362.026454 -121.286778) (xy 362.026454 -121.219722) (xy 362.026096 -121.210705) (xy 362.01985 -121.193788)
			(xy 362.014262 -121.186702) (xy 362.014008 -121.186702) (xy 362.014008 -121.186448) (xy 361.996379 -121.165508)
			(xy 361.966666 -121.119537) (xy 361.943827 -121.069792) (xy 361.928334 -121.017293) (xy 361.920503 -120.963119)
			(xy 361.920028 -120.93575) (xy 361.920514 -120.908499) (xy 361.92827 -120.854551) (xy 361.943625 -120.802256)
			(xy 361.966267 -120.752679) (xy 361.995733 -120.706829) (xy 362.031424 -120.665638) (xy 362.072615 -120.629947)
			(xy 362.118465 -120.600481) (xy 362.168042 -120.577839) (xy 362.220337 -120.562484) (xy 362.274285 -120.554728)
			(xy 362.328787 -120.554728) (xy 362.382735 -120.562484) (xy 362.43503 -120.577839) (xy 362.484607 -120.600481)
			(xy 362.530457 -120.629947) (xy 362.571648 -120.665638) (xy 362.607339 -120.706829) (xy 362.636805 -120.752679)
			(xy 362.659447 -120.802256) (xy 362.674802 -120.854551) (xy 362.682558 -120.908499) (xy 362.683044 -120.93575)
			(xy 362.682562 -120.96312) (xy 362.67475 -121.017299) (xy 362.659266 -121.069802) (xy 362.636427 -121.119549)
			(xy 362.606705 -121.165516) (xy 362.589064 -121.186448) (xy 362.58881 -121.186702) (xy 362.583218 -121.193785)
			(xy 362.576974 -121.210704) (xy 362.576618 -121.219722) (xy 362.576618 -121.286778) (xy 362.576982 -121.295794)
			(xy 362.583224 -121.312711) (xy 362.58881 -121.319798) (xy 362.589064 -121.319798) (xy 362.589064 -121.320052)
			(xy 362.606688 -121.340996) (xy 362.636404 -121.386965) (xy 362.659243 -121.436709) (xy 362.674737 -121.489208)
			(xy 362.682569 -121.543382) (xy 362.683044 -121.57075) (xy 362.682558 -121.598001) (xy 362.674802 -121.651949)
			(xy 362.659447 -121.704244) (xy 362.636805 -121.753821) (xy 362.607339 -121.799671) (xy 362.571648 -121.840862)
			(xy 362.530457 -121.876553) (xy 362.484607 -121.906019) (xy 362.43503 -121.928661) (xy 362.382735 -121.944016)
			(xy 362.328787 -121.951772) (xy 362.274285 -121.951772) (xy 362.220337 -121.944016) (xy 362.168042 -121.928661)
			(xy 362.118465 -121.906019) (xy 362.072615 -121.876553) (xy 362.031424 -121.840862) (xy 361.995733 -121.799671)
			(xy 361.966267 -121.753821) (xy 361.943625 -121.704244) (xy 361.92827 -121.651949) (xy 361.920514 -121.598001)
			(xy 361.920028 -121.57075) (xy 330.35362 -121.57075) (xy 330.340893 -121.578517) (xy 330.289564 -121.600329)
			(xy 330.235607 -121.614435) (xy 330.18017 -121.620535) (xy 330.124436 -121.618498) (xy 330.069593 -121.608368)
			(xy 330.016809 -121.590361) (xy 329.967209 -121.56486) (xy 329.921851 -121.532409) (xy 329.881702 -121.4937)
			(xy 329.847616 -121.449557) (xy 329.82032 -121.400922) (xy 329.800397 -121.348831) (xy 329.788271 -121.294394)
			(xy 329.7842 -121.238772) (xy 325.649355 -121.238772) (xy 325.653557 -121.253078) (xy 325.661317 -121.307025)
			(xy 325.661782 -121.334276) (xy 325.661306 -121.361646) (xy 325.653491 -121.415825) (xy 325.638005 -121.468328)
			(xy 325.615165 -121.518075) (xy 325.585442 -121.564042) (xy 325.567802 -121.584974) (xy 325.567548 -121.585228)
			(xy 325.561979 -121.592327) (xy 325.555723 -121.609234) (xy 325.555356 -121.618248) (xy 325.555356 -121.685304)
			(xy 325.555699 -121.694323) (xy 325.561955 -121.71124) (xy 325.567548 -121.718324) (xy 325.567802 -121.718324)
			(xy 325.567802 -121.718578) (xy 325.585445 -121.739507) (xy 325.615156 -121.785481) (xy 325.637991 -121.835229)
			(xy 325.653481 -121.88773) (xy 325.661309 -121.941907) (xy 325.661782 -121.969276) (xy 325.661322 -121.996529)
			(xy 325.653568 -122.050482) (xy 325.638214 -122.102781) (xy 325.615572 -122.152363) (xy 325.586104 -122.198218)
			(xy 325.55041 -122.239411) (xy 325.509216 -122.275105) (xy 325.481964 -122.292618) (xy 358.080308 -122.292618)
			(xy 358.084379 -122.236996) (xy 358.096505 -122.182559) (xy 358.116428 -122.130468) (xy 358.143724 -122.081833)
			(xy 358.17781 -122.03769) (xy 358.217959 -121.998981) (xy 358.263317 -121.96653) (xy 358.312917 -121.941029)
			(xy 358.365701 -121.923022) (xy 358.420544 -121.912892) (xy 358.476278 -121.910855) (xy 358.531715 -121.916955)
			(xy 358.585672 -121.931061) (xy 358.637001 -121.952873) (xy 358.684607 -121.981927) (xy 358.727475 -122.017602)
			(xy 358.764692 -122.059139) (xy 358.795465 -122.105652) (xy 358.819137 -122.156149) (xy 358.835205 -122.209556)
			(xy 358.843325 -122.264732) (xy 358.843834 -122.292618) (xy 358.843325 -122.320504) (xy 358.835205 -122.37568)
			(xy 358.819137 -122.429087) (xy 358.8 -122.46991) (xy 359.237024 -122.46991) (xy 359.241095 -122.414288)
			(xy 359.253221 -122.359851) (xy 359.273144 -122.30776) (xy 359.30044 -122.259125) (xy 359.334526 -122.214982)
			(xy 359.374675 -122.176273) (xy 359.420033 -122.143822) (xy 359.469633 -122.118321) (xy 359.522417 -122.100314)
			(xy 359.57726 -122.090184) (xy 359.632994 -122.088147) (xy 359.688431 -122.094247) (xy 359.742388 -122.108353)
			(xy 359.793717 -122.130165) (xy 359.841323 -122.159219) (xy 359.884191 -122.194894) (xy 359.921408 -122.236431)
			(xy 359.952181 -122.282944) (xy 359.975853 -122.333441) (xy 359.991921 -122.386848) (xy 360.000041 -122.442024)
			(xy 360.00055 -122.46991) (xy 360.000041 -122.497796) (xy 359.991921 -122.552972) (xy 359.975853 -122.606379)
			(xy 359.952181 -122.656876) (xy 359.921408 -122.703389) (xy 359.884191 -122.744926) (xy 359.841323 -122.780601)
			(xy 359.793717 -122.809655) (xy 359.742388 -122.831467) (xy 359.688431 -122.845573) (xy 359.632994 -122.851673)
			(xy 359.57726 -122.849636) (xy 359.522417 -122.839506) (xy 359.469633 -122.821499) (xy 359.420033 -122.795998)
			(xy 359.374675 -122.763547) (xy 359.334526 -122.724838) (xy 359.30044 -122.680695) (xy 359.273144 -122.63206)
			(xy 359.253221 -122.579969) (xy 359.241095 -122.525532) (xy 359.237024 -122.46991) (xy 358.8 -122.46991)
			(xy 358.795465 -122.479584) (xy 358.764692 -122.526097) (xy 358.727475 -122.567634) (xy 358.684607 -122.603309)
			(xy 358.637001 -122.632363) (xy 358.585672 -122.654175) (xy 358.531715 -122.668281) (xy 358.476278 -122.674381)
			(xy 358.420544 -122.672344) (xy 358.365701 -122.662214) (xy 358.312917 -122.644207) (xy 358.263317 -122.618706)
			(xy 358.217959 -122.586255) (xy 358.17781 -122.547546) (xy 358.143724 -122.503403) (xy 358.116428 -122.454768)
			(xy 358.096505 -122.402677) (xy 358.084379 -122.34824) (xy 358.080308 -122.292618) (xy 325.481964 -122.292618)
			(xy 325.463361 -122.304573) (xy 325.413779 -122.327214) (xy 325.36148 -122.342568) (xy 325.307527 -122.350322)
			(xy 325.280274 -122.350784) (xy 325.251151 -122.350239) (xy 325.193579 -122.341409) (xy 325.13802 -122.323927)
			(xy 325.085764 -122.2982) (xy 325.038028 -122.264827) (xy 324.995922 -122.224584) (xy 324.960424 -122.178406)
			(xy 324.932361 -122.127367) (xy 324.912385 -122.072655) (xy 324.906132 -122.044206) (xy 324.903846 -122.032522)
			(xy 324.889368 -122.013726) (xy 324.805294 -121.97334) (xy 324.794479 -121.968779) (xy 324.77104 -121.969034)
			(xy 324.760336 -121.973848) (xy 324.759828 -121.973848) (xy 324.732769 -121.98713) (xy 324.675494 -122.005909)
			(xy 324.615975 -122.015428) (xy 324.585838 -122.016012) (xy 324.558586 -122.015509) (xy 324.504637 -122.007758)
			(xy 324.45234 -121.992407) (xy 324.40276 -121.969769) (xy 324.356907 -121.940305) (xy 324.315714 -121.904616)
			(xy 324.28002 -121.863426) (xy 324.250551 -121.817577) (xy 324.227908 -121.767999) (xy 324.212551 -121.715704)
			(xy 324.204794 -121.661756) (xy 324.20433 -121.634504) (xy 322.405968 -121.634504) (xy 322.405379 -121.63858)
			(xy 322.389877 -121.691084) (xy 322.367025 -121.740832) (xy 322.337294 -121.7868) (xy 322.31965 -121.807732)
			(xy 322.319396 -121.807986) (xy 322.313809 -121.815072) (xy 322.307563 -121.831989) (xy 322.307204 -121.841006)
			(xy 322.307204 -121.908062) (xy 322.307579 -121.917077) (xy 322.313814 -121.933994) (xy 322.319396 -121.941082)
			(xy 322.31965 -121.941082) (xy 322.31965 -121.941336) (xy 322.337265 -121.962288) (xy 322.366982 -122.008254)
			(xy 322.389823 -122.057997) (xy 322.40532 -122.110493) (xy 322.413153 -122.164666) (xy 322.41363 -122.192034)
			(xy 322.413144 -122.219285) (xy 322.405388 -122.273233) (xy 322.390033 -122.325528) (xy 322.367391 -122.375105)
			(xy 322.337925 -122.420955) (xy 322.302234 -122.462146) (xy 322.261043 -122.497837) (xy 322.215193 -122.527303)
			(xy 322.165616 -122.549945) (xy 322.113321 -122.5653) (xy 322.059373 -122.573056) (xy 322.004871 -122.573056)
			(xy 321.950923 -122.5653) (xy 321.898628 -122.549945) (xy 321.849051 -122.527303) (xy 321.803201 -122.497837)
			(xy 321.76201 -122.462146) (xy 321.726319 -122.420955) (xy 321.696853 -122.375105) (xy 321.674211 -122.325528)
			(xy 321.658856 -122.273233) (xy 321.6511 -122.219285) (xy 321.650614 -122.192034) (xy 314.178099 -122.192034)
			(xy 314.181751 -122.205554) (xy 314.189701 -122.265454) (xy 314.190126 -122.295666) (xy 314.190126 -122.507756)
			(xy 314.189872 -122.507756) (xy 314.189872 -122.727212) (xy 314.190126 -122.727212) (xy 314.190126 -123.159266)
			(xy 314.189659 -123.189252) (xy 314.181835 -123.248712) (xy 314.166315 -123.306642) (xy 314.143367 -123.36205)
			(xy 314.141925 -123.364548) (xy 326.264298 -123.364548) (xy 326.264298 -123.310052) (xy 326.272053 -123.256109)
			(xy 326.287406 -123.20382) (xy 326.310044 -123.154247) (xy 326.339506 -123.108401) (xy 326.375192 -123.067214)
			(xy 326.416377 -123.031524) (xy 326.462221 -123.002058) (xy 326.511792 -122.979417) (xy 326.56408 -122.96406)
			(xy 326.618022 -122.9563) (xy 326.64527 -122.955812) (xy 326.67264 -122.956293) (xy 326.726818 -122.964107)
			(xy 326.779321 -122.979592) (xy 326.829068 -123.002431) (xy 326.875036 -123.032152) (xy 326.895968 -123.049792)
			(xy 326.896222 -123.050046) (xy 326.903294 -123.055653) (xy 326.920222 -123.061886) (xy 326.929242 -123.062238)
			(xy 326.996298 -123.062238) (xy 327.005314 -123.061872) (xy 327.02223 -123.055629) (xy 327.029318 -123.050046)
			(xy 327.029318 -123.049792) (xy 327.029572 -123.049792) (xy 327.050505 -123.032151) (xy 327.096473 -123.002427)
			(xy 327.146219 -122.979581) (xy 327.198721 -122.964085) (xy 327.252899 -122.956256) (xy 327.307641 -122.956256)
			(xy 327.361819 -122.964085) (xy 327.414321 -122.979581) (xy 327.464067 -123.002427) (xy 327.510035 -123.032151)
			(xy 327.530968 -123.049792) (xy 327.531222 -123.050046) (xy 327.538294 -123.055653) (xy 327.555222 -123.061886)
			(xy 327.564242 -123.062238) (xy 327.631298 -123.062238) (xy 327.640314 -123.061872) (xy 327.65723 -123.055629)
			(xy 327.664318 -123.050046) (xy 327.664318 -123.049792) (xy 327.664572 -123.049792) (xy 327.685503 -123.032151)
			(xy 327.731476 -123.00244) (xy 327.781224 -122.979604) (xy 327.833725 -122.964114) (xy 327.887901 -122.956286)
			(xy 327.91527 -122.955812) (xy 327.942526 -122.956233) (xy 327.996483 -122.963987) (xy 328.048787 -122.979341)
			(xy 328.098374 -123.001983) (xy 328.144233 -123.031452) (xy 328.185431 -123.067147) (xy 328.22113 -123.108343)
			(xy 328.250603 -123.1542) (xy 328.273248 -123.203785) (xy 328.288607 -123.256088) (xy 328.296365 -123.310044)
			(xy 328.296365 -123.364556) (xy 328.288607 -123.418512) (xy 328.273248 -123.470815) (xy 328.250603 -123.5204)
			(xy 328.22113 -123.566257) (xy 328.185431 -123.607453) (xy 328.144233 -123.643148) (xy 328.098374 -123.672617)
			(xy 328.048787 -123.695259) (xy 327.996483 -123.710613) (xy 327.942526 -123.718367) (xy 327.91527 -123.718828)
			(xy 327.887898 -123.718397) (xy 327.833717 -123.710573) (xy 327.781213 -123.695077) (xy 327.731466 -123.672227)
			(xy 327.685502 -123.642494) (xy 327.664572 -123.624848) (xy 327.664318 -123.624594) (xy 327.657231 -123.619008)
			(xy 327.640315 -123.612761) (xy 327.631298 -123.612402) (xy 327.564242 -123.612402) (xy 327.555227 -123.612779)
			(xy 327.53831 -123.619013) (xy 327.531222 -123.624594) (xy 327.530968 -123.624848) (xy 327.510035 -123.642489)
			(xy 327.464067 -123.672213) (xy 327.414321 -123.695059) (xy 327.361819 -123.710555) (xy 327.307641 -123.718384)
			(xy 327.252899 -123.718384) (xy 327.198721 -123.710555) (xy 327.146219 -123.695059) (xy 327.096473 -123.672213)
			(xy 327.050505 -123.642489) (xy 327.029572 -123.624848) (xy 327.029318 -123.624594) (xy 327.022231 -123.619008)
			(xy 327.005315 -123.612761) (xy 326.996298 -123.612402) (xy 326.929242 -123.612402) (xy 326.920227 -123.612779)
			(xy 326.90331 -123.619013) (xy 326.896222 -123.624594) (xy 326.896222 -123.624848) (xy 326.895968 -123.624848)
			(xy 326.875014 -123.642461) (xy 326.829048 -123.672178) (xy 326.779306 -123.69502) (xy 326.72681 -123.710517)
			(xy 326.672638 -123.718351) (xy 326.64527 -123.718828) (xy 326.618022 -123.7183) (xy 326.56408 -123.71054)
			(xy 326.511792 -123.695183) (xy 326.462221 -123.672542) (xy 326.416377 -123.643076) (xy 326.375192 -123.607386)
			(xy 326.339506 -123.566199) (xy 326.310044 -123.520353) (xy 326.287406 -123.47078) (xy 326.272053 -123.418491)
			(xy 326.264298 -123.364548) (xy 314.141925 -123.364548) (xy 314.113382 -123.413988) (xy 314.076874 -123.461568)
			(xy 314.034467 -123.503975) (xy 313.986887 -123.540483) (xy 313.934948 -123.570468) (xy 313.87954 -123.593416)
			(xy 313.82161 -123.608935) (xy 313.76215 -123.616759) (xy 313.732164 -123.617228) (xy 313.727084 -123.617228)
			(xy 313.719718 -123.616974) (xy 313.71921 -123.616974) (xy 313.677808 -123.613926) (xy 313.65519 -123.610936)
			(xy 313.610654 -123.601015) (xy 313.588908 -123.594114) (xy 313.568819 -123.58727) (xy 313.529895 -123.570349)
			(xy 313.511184 -123.560332) (xy 313.510168 -123.55957) (xy 313.509406 -123.559062) (xy 313.506104 -123.557538)
			(xy 313.50077 -123.554998) (xy 313.493161 -123.551924) (xy 313.476845 -123.550253) (xy 313.468766 -123.551696)
			(xy 313.448192 -123.556268) (xy 313.438286 -123.558554) (xy 313.420252 -123.571) (xy 313.41695 -123.573286)
			(xy 313.415934 -123.574302) (xy 313.36742 -124.713492) (xy 313.356669 -124.965714) (xy 315.916564 -124.965714)
			(xy 315.916564 -124.102114) (xy 315.917054 -124.072146) (xy 315.924877 -124.012724) (xy 315.94039 -123.954831)
			(xy 315.963326 -123.899458) (xy 315.993293 -123.847552) (xy 316.02978 -123.800002) (xy 316.07216 -123.757622)
			(xy 316.11971 -123.721135) (xy 316.171616 -123.691168) (xy 316.226989 -123.668232) (xy 316.284882 -123.652719)
			(xy 316.344304 -123.644896) (xy 316.40424 -123.644896) (xy 316.463662 -123.652719) (xy 316.521555 -123.668232)
			(xy 316.576928 -123.691168) (xy 316.628834 -123.721135) (xy 316.676384 -123.757622) (xy 316.718764 -123.800002)
			(xy 316.73582 -123.822229) (xy 329.642205 -123.822229) (xy 329.642208 -123.767731) (xy 329.649966 -123.713788)
			(xy 329.665323 -123.661498) (xy 329.687965 -123.611926) (xy 329.717431 -123.566081) (xy 329.753121 -123.524896)
			(xy 329.79431 -123.489209) (xy 329.840158 -123.459747) (xy 329.889732 -123.43711) (xy 329.942023 -123.421759)
			(xy 329.995967 -123.414005) (xy 330.023216 -123.41352) (xy 330.023724 -123.41352) (xy 330.034096 -123.4136)
			(xy 330.054808 -123.414744) (xy 330.065126 -123.415806) (xy 330.079675 -123.416857) (xy 330.108365 -123.411664)
			(xy 330.134422 -123.398584) (xy 330.155726 -123.378679) (xy 330.170544 -123.35357) (xy 330.177672 -123.325299)
			(xy 330.176529 -123.296165) (xy 330.172314 -123.282202) (xy 330.162954 -123.252595) (xy 330.152876 -123.191327)
			(xy 330.152248 -123.160282) (xy 330.152248 -123.160028) (xy 330.152725 -123.132772) (xy 330.160479 -123.078814)
			(xy 330.175834 -123.02651) (xy 330.198476 -122.976922) (xy 330.227945 -122.931063) (xy 330.263641 -122.889864)
			(xy 330.304837 -122.854164) (xy 330.350694 -122.824691) (xy 330.40028 -122.802045) (xy 330.452583 -122.786686)
			(xy 330.50654 -122.778927) (xy 330.561052 -122.778927) (xy 330.615009 -122.786684) (xy 330.667313 -122.802042)
			(xy 330.716899 -122.824688) (xy 330.762757 -122.85416) (xy 330.803953 -122.889858) (xy 330.83965 -122.931056)
			(xy 330.86912 -122.976915) (xy 330.891763 -123.026502) (xy 330.907119 -123.078807) (xy 330.914874 -123.132764)
			(xy 330.914872 -123.187276) (xy 330.907111 -123.241233) (xy 330.904609 -123.24975) (xy 360.21009 -123.24975)
			(xy 360.21009 -123.19525) (xy 360.217847 -123.141304) (xy 360.233201 -123.089011) (xy 360.255842 -123.039435)
			(xy 360.285307 -122.993586) (xy 360.320997 -122.952397) (xy 360.362186 -122.916707) (xy 360.408035 -122.887242)
			(xy 360.457611 -122.864601) (xy 360.509904 -122.849247) (xy 360.56385 -122.84149) (xy 360.5911 -122.841004)
			(xy 360.61813 -122.841499) (xy 360.671647 -122.849137) (xy 360.723549 -122.86426) (xy 360.772793 -122.886564)
			(xy 360.818392 -122.915602) (xy 360.85943 -122.950792) (xy 360.877612 -122.970798) (xy 360.877866 -122.971052)
			(xy 360.885307 -122.978703) (xy 360.904793 -122.987368) (xy 360.915458 -122.987816) (xy 361.003088 -122.988324)
			(xy 361.022646 -122.979688) (xy 361.030012 -122.971306) (xy 361.048173 -122.951583) (xy 361.089074 -122.916919)
			(xy 361.134429 -122.88833) (xy 361.183345 -122.866382) (xy 361.234854 -122.851506) (xy 361.287939 -122.843997)
			(xy 361.314746 -122.843544) (xy 361.342116 -122.844031) (xy 361.396294 -122.851842) (xy 361.448798 -122.867326)
			(xy 361.498545 -122.890163) (xy 361.544512 -122.919884) (xy 361.565444 -122.937524) (xy 361.565698 -122.937778)
			(xy 361.572774 -122.943379) (xy 361.589699 -122.949615) (xy 361.598718 -122.94997) (xy 361.665774 -122.94997)
			(xy 361.67479 -122.949607) (xy 361.691708 -122.943364) (xy 361.698794 -122.937778) (xy 361.698794 -122.937524)
			(xy 361.699048 -122.937524) (xy 361.719981 -122.919883) (xy 361.765949 -122.890159) (xy 361.815695 -122.867313)
			(xy 361.868197 -122.851817) (xy 361.922375 -122.843988) (xy 361.977117 -122.843988) (xy 362.031295 -122.851817)
			(xy 362.083797 -122.867313) (xy 362.133543 -122.890159) (xy 362.179511 -122.919883) (xy 362.200444 -122.937524)
			(xy 362.200698 -122.937778) (xy 362.207774 -122.943379) (xy 362.224699 -122.949615) (xy 362.233718 -122.94997)
			(xy 362.300774 -122.94997) (xy 362.30979 -122.949607) (xy 362.326708 -122.943364) (xy 362.333794 -122.937778)
			(xy 362.334302 -122.937524) (xy 362.347036 -122.92658) (xy 362.374128 -122.906738) (xy 362.388404 -122.8979)
			(xy 362.397294 -122.892566) (xy 362.409486 -122.875548) (xy 362.429806 -122.78233) (xy 362.425488 -122.761756)
			(xy 362.419646 -122.75312) (xy 362.403646 -122.729056) (xy 362.378305 -122.677124) (xy 362.36108 -122.621966)
			(xy 362.352364 -122.564842) (xy 362.351828 -122.53595) (xy 362.352314 -122.508699) (xy 362.36007 -122.454751)
			(xy 362.375425 -122.402456) (xy 362.398067 -122.352879) (xy 362.427533 -122.307029) (xy 362.463224 -122.265838)
			(xy 362.504415 -122.230147) (xy 362.550265 -122.200681) (xy 362.599842 -122.178039) (xy 362.652137 -122.162684)
			(xy 362.706085 -122.154928) (xy 362.760587 -122.154928) (xy 362.814535 -122.162684) (xy 362.86683 -122.178039)
			(xy 362.916407 -122.200681) (xy 362.962257 -122.230147) (xy 363.003448 -122.265838) (xy 363.039139 -122.307029)
			(xy 363.068605 -122.352879) (xy 363.091247 -122.402456) (xy 363.106602 -122.454751) (xy 363.114358 -122.508699)
			(xy 363.114844 -122.53595) (xy 363.114297 -122.56404) (xy 363.106078 -122.619614) (xy 363.089795 -122.673381)
			(xy 363.065801 -122.724178) (xy 363.034614 -122.770905) (xy 362.99691 -122.812552) (xy 362.953505 -122.848217)
			(xy 362.929678 -122.863102) (xy 362.920788 -122.868436) (xy 362.908596 -122.885454) (xy 362.888276 -122.978672)
			(xy 362.892594 -122.999246) (xy 362.898436 -123.007882) (xy 362.914435 -123.031947) (xy 362.939777 -123.083878)
			(xy 362.957002 -123.139036) (xy 362.965719 -123.19616) (xy 362.966254 -123.225052) (xy 362.9657 -123.252302)
			(xy 362.957951 -123.306247) (xy 362.942603 -123.35854) (xy 362.91997 -123.408117) (xy 362.890511 -123.453968)
			(xy 362.854827 -123.49516) (xy 362.813644 -123.530855) (xy 362.7678 -123.560325) (xy 362.718228 -123.58297)
			(xy 362.665939 -123.598331) (xy 362.611995 -123.606093) (xy 362.584746 -123.60656) (xy 362.557376 -123.606077)
			(xy 362.503198 -123.598265) (xy 362.450694 -123.58278) (xy 362.400947 -123.559942) (xy 362.35498 -123.53022)
			(xy 362.334048 -123.51258) (xy 362.333794 -123.512326) (xy 362.32672 -123.506722) (xy 362.309793 -123.500488)
			(xy 362.300774 -123.500134) (xy 362.233718 -123.500134) (xy 362.224701 -123.500492) (xy 362.207784 -123.506738)
			(xy 362.200698 -123.512326) (xy 362.200444 -123.51258) (xy 362.179511 -123.530221) (xy 362.133543 -123.559945)
			(xy 362.083797 -123.582791) (xy 362.031295 -123.598287) (xy 361.977117 -123.606116) (xy 361.922375 -123.606116)
			(xy 361.868197 -123.598287) (xy 361.815695 -123.582791) (xy 361.765949 -123.559945) (xy 361.719981 -123.530221)
			(xy 361.699048 -123.51258) (xy 361.698794 -123.512326) (xy 361.69172 -123.506722) (xy 361.674793 -123.500488)
			(xy 361.665774 -123.500134) (xy 361.598718 -123.500134) (xy 361.589701 -123.500492) (xy 361.572784 -123.506738)
			(xy 361.565698 -123.512326) (xy 361.565698 -123.51258) (xy 361.565444 -123.51258) (xy 361.544504 -123.530209)
			(xy 361.498533 -123.559923) (xy 361.448788 -123.582761) (xy 361.396289 -123.598255) (xy 361.342115 -123.606085)
			(xy 361.314746 -123.60656) (xy 361.287716 -123.60608) (xy 361.234199 -123.598436) (xy 361.182298 -123.583308)
			(xy 361.133054 -123.561001) (xy 361.087456 -123.531962) (xy 361.046417 -123.496772) (xy 361.028234 -123.476766)
			(xy 361.02798 -123.476512) (xy 361.020512 -123.468892) (xy 361.001047 -123.460207) (xy 360.990388 -123.459748)
			(xy 360.902758 -123.45924) (xy 360.8832 -123.467876) (xy 360.875834 -123.476258) (xy 360.857663 -123.495971)
			(xy 360.816763 -123.530634) (xy 360.771409 -123.559222) (xy 360.722496 -123.581172) (xy 360.67099 -123.596051)
			(xy 360.617906 -123.603564) (xy 360.5911 -123.60402) (xy 360.56385 -123.60351) (xy 360.509904 -123.595753)
			(xy 360.457611 -123.580399) (xy 360.408035 -123.557758) (xy 360.362186 -123.528293) (xy 360.320997 -123.492603)
			(xy 360.285307 -123.451414) (xy 360.255842 -123.405565) (xy 360.233201 -123.355989) (xy 360.217847 -123.303696)
			(xy 360.21009 -123.24975) (xy 330.904609 -123.24975) (xy 330.891749 -123.293535) (xy 330.869101 -123.34312)
			(xy 330.839626 -123.388976) (xy 330.803925 -123.43017) (xy 330.762725 -123.465864) (xy 330.716863 -123.495332)
			(xy 330.667275 -123.517972) (xy 330.61497 -123.533324) (xy 330.561012 -123.541076) (xy 330.533756 -123.541536)
			(xy 330.533248 -123.541536) (xy 330.522876 -123.541459) (xy 330.502164 -123.540313) (xy 330.491846 -123.53925)
			(xy 330.477298 -123.538232) (xy 330.448617 -123.543429) (xy 330.422569 -123.556508) (xy 330.40127 -123.576406)
			(xy 330.386452 -123.601506) (xy 330.379319 -123.629767) (xy 330.380451 -123.658893) (xy 330.384658 -123.672854)
			(xy 330.39401 -123.702463) (xy 330.404093 -123.763729) (xy 330.404724 -123.794774) (xy 330.404724 -123.795028)
			(xy 330.404192 -123.822277) (xy 330.396432 -123.87622) (xy 330.381074 -123.928509) (xy 330.358432 -123.978081)
			(xy 330.328965 -124.023925) (xy 330.293273 -124.06511) (xy 330.252084 -124.100796) (xy 330.206235 -124.130257)
			(xy 330.15666 -124.152893) (xy 330.104369 -124.168243) (xy 330.050425 -124.175996) (xy 329.995927 -124.175992)
			(xy 329.941984 -124.168233) (xy 329.889695 -124.152876) (xy 329.840123 -124.130234) (xy 329.794278 -124.100767)
			(xy 329.753093 -124.065076) (xy 329.717407 -124.023887) (xy 329.687945 -123.978039) (xy 329.665309 -123.928464)
			(xy 329.649958 -123.876173) (xy 329.642205 -123.822229) (xy 316.73582 -123.822229) (xy 316.755251 -123.847552)
			(xy 316.785218 -123.899458) (xy 316.808154 -123.954831) (xy 316.823667 -124.012724) (xy 316.83149 -124.072146)
			(xy 316.83198 -124.102114) (xy 316.83198 -124.215144) (xy 326.806558 -124.215144) (xy 326.810629 -124.159522)
			(xy 326.822755 -124.105085) (xy 326.842678 -124.052994) (xy 326.869974 -124.004359) (xy 326.90406 -123.960216)
			(xy 326.944209 -123.921507) (xy 326.989567 -123.889056) (xy 327.039167 -123.863555) (xy 327.091951 -123.845548)
			(xy 327.146794 -123.835418) (xy 327.202528 -123.833381) (xy 327.257965 -123.839481) (xy 327.311922 -123.853587)
			(xy 327.363251 -123.875399) (xy 327.410857 -123.904453) (xy 327.453725 -123.940128) (xy 327.490942 -123.981665)
			(xy 327.521715 -124.028178) (xy 327.545387 -124.078675) (xy 327.561455 -124.132082) (xy 327.569575 -124.187258)
			(xy 327.570084 -124.215144) (xy 327.569575 -124.24303) (xy 327.561455 -124.298206) (xy 327.545387 -124.351613)
			(xy 327.521715 -124.40211) (xy 327.490942 -124.448623) (xy 327.453725 -124.49016) (xy 327.410857 -124.525835)
			(xy 327.363251 -124.554889) (xy 327.311922 -124.576701) (xy 327.257965 -124.590807) (xy 327.202528 -124.596907)
			(xy 327.146794 -124.59487) (xy 327.091951 -124.58474) (xy 327.039167 -124.566733) (xy 326.989567 -124.541232)
			(xy 326.944209 -124.508781) (xy 326.90406 -124.470072) (xy 326.869974 -124.425929) (xy 326.842678 -124.377294)
			(xy 326.822755 -124.325203) (xy 326.810629 -124.270766) (xy 326.806558 -124.215144) (xy 316.83198 -124.215144)
			(xy 316.83198 -124.965714) (xy 316.83149 -124.995682) (xy 316.823667 -125.055104) (xy 316.808154 -125.112997)
			(xy 316.785218 -125.16837) (xy 316.755251 -125.220276) (xy 316.718764 -125.267826) (xy 316.676384 -125.310206)
			(xy 316.628834 -125.346693) (xy 316.576928 -125.37666) (xy 316.521555 -125.399596) (xy 316.463662 -125.415109)
			(xy 316.40424 -125.422932) (xy 316.344304 -125.422932) (xy 316.284882 -125.415109) (xy 316.226989 -125.399596)
			(xy 316.171616 -125.37666) (xy 316.11971 -125.346693) (xy 316.07216 -125.310206) (xy 316.02978 -125.267826)
			(xy 315.993293 -125.220276) (xy 315.963326 -125.16837) (xy 315.94039 -125.112997) (xy 315.924877 -125.055104)
			(xy 315.917054 -124.995682) (xy 315.916564 -124.965714) (xy 313.356669 -124.965714) (xy 313.317205 -125.891544)
			(xy 327.375012 -125.891544) (xy 327.375438 -125.865229) (xy 327.382681 -125.813098) (xy 327.397008 -125.762454)
			(xy 327.418148 -125.714256) (xy 327.445702 -125.669413) (xy 327.479147 -125.628775) (xy 327.498202 -125.61062)
			(xy 327.505597 -125.603093) (xy 327.514125 -125.583817) (xy 327.514712 -125.573282) (xy 327.514712 -125.498606)
			(xy 327.51419 -125.488056) (xy 327.505649 -125.46876) (xy 327.498202 -125.461268) (xy 327.479138 -125.443121)
			(xy 327.445682 -125.402489) (xy 327.418124 -125.357647) (xy 327.396987 -125.309445) (xy 327.382671 -125.258796)
			(xy 327.375449 -125.206661) (xy 327.375012 -125.180344) (xy 327.375498 -125.153093) (xy 327.383254 -125.099145)
			(xy 327.398609 -125.04685) (xy 327.421251 -124.997273) (xy 327.450717 -124.951423) (xy 327.486408 -124.910232)
			(xy 327.527599 -124.874541) (xy 327.573449 -124.845075) (xy 327.623026 -124.822433) (xy 327.675321 -124.807078)
			(xy 327.729269 -124.799322) (xy 327.783771 -124.799322) (xy 327.837719 -124.807078) (xy 327.890014 -124.822433)
			(xy 327.939591 -124.845075) (xy 327.985441 -124.874541) (xy 328.026632 -124.910232) (xy 328.062323 -124.951423)
			(xy 328.070038 -124.963428) (xy 356.973122 -124.963428) (xy 356.977193 -124.907806) (xy 356.989319 -124.853369)
			(xy 357.009242 -124.801278) (xy 357.036538 -124.752643) (xy 357.070624 -124.7085) (xy 357.110773 -124.669791)
			(xy 357.156131 -124.63734) (xy 357.205731 -124.611839) (xy 357.258515 -124.593832) (xy 357.313358 -124.583702)
			(xy 357.369092 -124.581665) (xy 357.424529 -124.587765) (xy 357.478486 -124.601871) (xy 357.529815 -124.623683)
			(xy 357.577421 -124.652737) (xy 357.620289 -124.688412) (xy 357.657506 -124.729949) (xy 357.688279 -124.776462)
			(xy 357.711951 -124.826959) (xy 357.728019 -124.880366) (xy 357.736139 -124.935542) (xy 357.736648 -124.963428)
			(xy 357.736139 -124.991314) (xy 357.729552 -125.036072) (xy 359.186224 -125.036072) (xy 359.190295 -124.98045)
			(xy 359.202421 -124.926013) (xy 359.222344 -124.873922) (xy 359.24964 -124.825287) (xy 359.283726 -124.781144)
			(xy 359.323875 -124.742435) (xy 359.369233 -124.709984) (xy 359.418833 -124.684483) (xy 359.471617 -124.666476)
			(xy 359.52646 -124.656346) (xy 359.582194 -124.654309) (xy 359.637631 -124.660409) (xy 359.691588 -124.674515)
			(xy 359.742917 -124.696327) (xy 359.790523 -124.725381) (xy 359.833391 -124.761056) (xy 359.870608 -124.802593)
			(xy 359.901381 -124.849106) (xy 359.925053 -124.899603) (xy 359.941121 -124.95301) (xy 359.949241 -125.008186)
			(xy 359.94975 -125.036072) (xy 359.949241 -125.063958) (xy 359.941121 -125.119134) (xy 359.925053 -125.172541)
			(xy 359.901381 -125.223038) (xy 359.870608 -125.269551) (xy 359.833391 -125.311088) (xy 359.790523 -125.346763)
			(xy 359.742917 -125.375817) (xy 359.691588 -125.397629) (xy 359.669682 -125.403356) (xy 363.844332 -125.403356)
			(xy 363.844823 -125.375987) (xy 363.852634 -125.321808) (xy 363.868116 -125.269305) (xy 363.890953 -125.219558)
			(xy 363.920673 -125.17359) (xy 363.938312 -125.152658) (xy 363.938566 -125.152404) (xy 363.944165 -125.145326)
			(xy 363.950402 -125.128402) (xy 363.950758 -125.119384) (xy 363.950758 -125.052328) (xy 363.950397 -125.043311)
			(xy 363.944153 -125.026394) (xy 363.938566 -125.019308) (xy 363.938312 -125.019308) (xy 363.938312 -125.019054)
			(xy 363.920687 -124.998111) (xy 363.890972 -124.952141) (xy 363.868134 -124.902397) (xy 363.852639 -124.849898)
			(xy 363.844808 -124.795724) (xy 363.844332 -124.768356) (xy 363.844818 -124.741105) (xy 363.852574 -124.687157)
			(xy 363.867929 -124.634862) (xy 363.890571 -124.585285) (xy 363.920037 -124.539435) (xy 363.955728 -124.498244)
			(xy 363.996919 -124.462553) (xy 364.042769 -124.433087) (xy 364.092346 -124.410445) (xy 364.144641 -124.39509)
			(xy 364.198589 -124.387334) (xy 364.253091 -124.387334) (xy 364.307039 -124.39509) (xy 364.359334 -124.410445)
			(xy 364.408911 -124.433087) (xy 364.454761 -124.462553) (xy 364.495952 -124.498244) (xy 364.531643 -124.539435)
			(xy 364.561109 -124.585285) (xy 364.583751 -124.634862) (xy 364.599106 -124.687157) (xy 364.606862 -124.741105)
			(xy 364.607348 -124.768356) (xy 364.606869 -124.795726) (xy 364.599056 -124.849905) (xy 364.583571 -124.902408)
			(xy 364.560732 -124.952156) (xy 364.531009 -124.998122) (xy 364.513368 -125.019054) (xy 364.513114 -125.019308)
			(xy 364.507519 -125.026389) (xy 364.501277 -125.04331) (xy 364.500922 -125.052328) (xy 364.500922 -125.119384)
			(xy 364.501282 -125.128401) (xy 364.507527 -125.145318) (xy 364.513114 -125.152404) (xy 364.513368 -125.152404)
			(xy 364.513368 -125.152658) (xy 364.530996 -125.173599) (xy 364.560711 -125.219569) (xy 364.583549 -125.269314)
			(xy 364.599043 -125.321813) (xy 364.606873 -125.375987) (xy 364.607348 -125.403356) (xy 364.606862 -125.430607)
			(xy 364.599106 -125.484555) (xy 364.583751 -125.53685) (xy 364.561109 -125.586427) (xy 364.531643 -125.632277)
			(xy 364.495952 -125.673468) (xy 364.454761 -125.709159) (xy 364.408911 -125.738625) (xy 364.359334 -125.761267)
			(xy 364.307039 -125.776622) (xy 364.253091 -125.784378) (xy 364.198589 -125.784378) (xy 364.144641 -125.776622)
			(xy 364.092346 -125.761267) (xy 364.042769 -125.738625) (xy 363.996919 -125.709159) (xy 363.955728 -125.673468)
			(xy 363.920037 -125.632277) (xy 363.890571 -125.586427) (xy 363.867929 -125.53685) (xy 363.852574 -125.484555)
			(xy 363.844818 -125.430607) (xy 363.844332 -125.403356) (xy 359.669682 -125.403356) (xy 359.637631 -125.411735)
			(xy 359.582194 -125.417835) (xy 359.52646 -125.415798) (xy 359.471617 -125.405668) (xy 359.418833 -125.387661)
			(xy 359.369233 -125.36216) (xy 359.323875 -125.329709) (xy 359.283726 -125.291) (xy 359.24964 -125.246857)
			(xy 359.222344 -125.198222) (xy 359.202421 -125.146131) (xy 359.190295 -125.091694) (xy 359.186224 -125.036072)
			(xy 357.729552 -125.036072) (xy 357.728019 -125.04649) (xy 357.711951 -125.099897) (xy 357.688279 -125.150394)
			(xy 357.657506 -125.196907) (xy 357.620289 -125.238444) (xy 357.577421 -125.274119) (xy 357.529815 -125.303173)
			(xy 357.478486 -125.324985) (xy 357.424529 -125.339091) (xy 357.369092 -125.345191) (xy 357.313358 -125.343154)
			(xy 357.258515 -125.333024) (xy 357.205731 -125.315017) (xy 357.156131 -125.289516) (xy 357.110773 -125.257065)
			(xy 357.070624 -125.218356) (xy 357.036538 -125.174213) (xy 357.009242 -125.125578) (xy 356.989319 -125.073487)
			(xy 356.977193 -125.01905) (xy 356.973122 -124.963428) (xy 328.070038 -124.963428) (xy 328.091789 -124.997273)
			(xy 328.114431 -125.04685) (xy 328.129786 -125.099145) (xy 328.137542 -125.153093) (xy 328.138028 -125.180344)
			(xy 328.137581 -125.206659) (xy 328.130341 -125.258788) (xy 328.116017 -125.30943) (xy 328.094881 -125.357629)
			(xy 328.067331 -125.402472) (xy 328.03389 -125.443111) (xy 328.014838 -125.461268) (xy 328.007454 -125.468805)
			(xy 327.998919 -125.488073) (xy 327.998328 -125.498606) (xy 327.998328 -125.573282) (xy 327.998845 -125.583833)
			(xy 328.007388 -125.603129) (xy 328.014838 -125.61062) (xy 328.033903 -125.628765) (xy 328.067358 -125.669398)
			(xy 328.094915 -125.714241) (xy 328.116052 -125.762443) (xy 328.130367 -125.813092) (xy 328.13759 -125.865227)
			(xy 328.138028 -125.891544) (xy 328.137542 -125.918795) (xy 328.129786 -125.972743) (xy 328.127823 -125.979428)
			(xy 356.973122 -125.979428) (xy 356.977193 -125.923806) (xy 356.989319 -125.869369) (xy 357.009242 -125.817278)
			(xy 357.036538 -125.768643) (xy 357.070624 -125.7245) (xy 357.110773 -125.685791) (xy 357.156131 -125.65334)
			(xy 357.205731 -125.627839) (xy 357.258515 -125.609832) (xy 357.313358 -125.599702) (xy 357.369092 -125.597665)
			(xy 357.424529 -125.603765) (xy 357.478486 -125.617871) (xy 357.529815 -125.639683) (xy 357.577421 -125.668737)
			(xy 357.620289 -125.704412) (xy 357.657506 -125.745949) (xy 357.688279 -125.792462) (xy 357.711951 -125.842959)
			(xy 357.727562 -125.894846) (xy 359.386884 -125.894846) (xy 359.390955 -125.839224) (xy 359.403081 -125.784787)
			(xy 359.423004 -125.732696) (xy 359.4503 -125.684061) (xy 359.484386 -125.639918) (xy 359.524535 -125.601209)
			(xy 359.569893 -125.568758) (xy 359.619493 -125.543257) (xy 359.672277 -125.52525) (xy 359.72712 -125.51512)
			(xy 359.782854 -125.513083) (xy 359.838291 -125.519183) (xy 359.892248 -125.533289) (xy 359.943577 -125.555101)
			(xy 359.991183 -125.584155) (xy 360.034051 -125.61983) (xy 360.071268 -125.661367) (xy 360.102041 -125.70788)
			(xy 360.125713 -125.758377) (xy 360.141781 -125.811784) (xy 360.147949 -125.853698) (xy 364.784894 -125.853698)
			(xy 364.78536 -125.826328) (xy 364.793178 -125.772149) (xy 364.808667 -125.719646) (xy 364.831509 -125.669899)
			(xy 364.861233 -125.623932) (xy 364.878874 -125.603) (xy 364.879128 -125.602746) (xy 364.884705 -125.595653)
			(xy 364.890956 -125.578741) (xy 364.89132 -125.569726) (xy 364.89132 -125.50267) (xy 364.890973 -125.493652)
			(xy 364.884718 -125.476735) (xy 364.879128 -125.46965) (xy 364.878874 -125.46965) (xy 364.878874 -125.469396)
			(xy 364.861216 -125.44848) (xy 364.831507 -125.402502) (xy 364.808676 -125.352751) (xy 364.793189 -125.300247)
			(xy 364.785366 -125.246068) (xy 364.784894 -125.218698) (xy 364.78538 -125.191447) (xy 364.793136 -125.137499)
			(xy 364.808491 -125.085204) (xy 364.831133 -125.035627) (xy 364.860599 -124.989777) (xy 364.89629 -124.948586)
			(xy 364.937481 -124.912895) (xy 364.983331 -124.883429) (xy 365.032908 -124.860787) (xy 365.085203 -124.845432)
			(xy 365.139151 -124.837676) (xy 365.193653 -124.837676) (xy 365.247601 -124.845432) (xy 365.299896 -124.860787)
			(xy 365.349473 -124.883429) (xy 365.395323 -124.912895) (xy 365.436514 -124.948586) (xy 365.472205 -124.989777)
			(xy 365.501671 -125.035627) (xy 365.524313 -125.085204) (xy 365.539668 -125.137499) (xy 365.547424 -125.191447)
			(xy 365.54791 -125.218698) (xy 365.54744 -125.246068) (xy 365.539623 -125.300247) (xy 365.524135 -125.35275)
			(xy 365.501294 -125.402497) (xy 365.471571 -125.448464) (xy 365.45393 -125.469396) (xy 365.453676 -125.46965)
			(xy 365.448102 -125.476745) (xy 365.441848 -125.493655) (xy 365.441484 -125.50267) (xy 365.441484 -125.569726)
			(xy 365.441832 -125.578744) (xy 365.448086 -125.59566) (xy 365.453676 -125.602746) (xy 365.45393 -125.602746)
			(xy 365.45393 -125.603) (xy 365.471587 -125.623917) (xy 365.501295 -125.669895) (xy 365.524127 -125.719646)
			(xy 365.539614 -125.77215) (xy 365.547438 -125.826328) (xy 365.54791 -125.853698) (xy 365.547424 -125.880949)
			(xy 365.539668 -125.934897) (xy 365.524313 -125.987192) (xy 365.501671 -126.036769) (xy 365.472205 -126.082619)
			(xy 365.436514 -126.12381) (xy 365.395323 -126.159501) (xy 365.349473 -126.188967) (xy 365.299896 -126.211609)
			(xy 365.247601 -126.226964) (xy 365.193653 -126.23472) (xy 365.139151 -126.23472) (xy 365.085203 -126.226964)
			(xy 365.032908 -126.211609) (xy 364.983331 -126.188967) (xy 364.937481 -126.159501) (xy 364.89629 -126.12381)
			(xy 364.860599 -126.082619) (xy 364.831133 -126.036769) (xy 364.808491 -125.987192) (xy 364.793136 -125.934897)
			(xy 364.78538 -125.880949) (xy 364.784894 -125.853698) (xy 360.147949 -125.853698) (xy 360.149901 -125.86696)
			(xy 360.15041 -125.894846) (xy 360.149901 -125.922732) (xy 360.141781 -125.977908) (xy 360.125713 -126.031315)
			(xy 360.102041 -126.081812) (xy 360.071268 -126.128325) (xy 360.034051 -126.169862) (xy 359.991183 -126.205537)
			(xy 359.943577 -126.234591) (xy 359.892248 -126.256403) (xy 359.838291 -126.270509) (xy 359.782854 -126.276609)
			(xy 359.72712 -126.274572) (xy 359.672277 -126.264442) (xy 359.619493 -126.246435) (xy 359.569893 -126.220934)
			(xy 359.524535 -126.188483) (xy 359.484386 -126.149774) (xy 359.4503 -126.105631) (xy 359.423004 -126.056996)
			(xy 359.403081 -126.004905) (xy 359.390955 -125.950468) (xy 359.386884 -125.894846) (xy 357.727562 -125.894846)
			(xy 357.728019 -125.896366) (xy 357.736139 -125.951542) (xy 357.736648 -125.979428) (xy 357.736139 -126.007314)
			(xy 357.728019 -126.06249) (xy 357.711951 -126.115897) (xy 357.688279 -126.166394) (xy 357.657506 -126.212907)
			(xy 357.620289 -126.254444) (xy 357.577421 -126.290119) (xy 357.529815 -126.319173) (xy 357.478486 -126.340985)
			(xy 357.424529 -126.355091) (xy 357.369092 -126.361191) (xy 357.313358 -126.359154) (xy 357.258515 -126.349024)
			(xy 357.205731 -126.331017) (xy 357.156131 -126.305516) (xy 357.110773 -126.273065) (xy 357.070624 -126.234356)
			(xy 357.036538 -126.190213) (xy 357.009242 -126.141578) (xy 356.989319 -126.089487) (xy 356.977193 -126.03505)
			(xy 356.973122 -125.979428) (xy 328.127823 -125.979428) (xy 328.114431 -126.025038) (xy 328.091789 -126.074615)
			(xy 328.062323 -126.120465) (xy 328.026632 -126.161656) (xy 327.985441 -126.197347) (xy 327.939591 -126.226813)
			(xy 327.890014 -126.249455) (xy 327.837719 -126.26481) (xy 327.783771 -126.272566) (xy 327.729269 -126.272566)
			(xy 327.675321 -126.26481) (xy 327.623026 -126.249455) (xy 327.573449 -126.226813) (xy 327.527599 -126.197347)
			(xy 327.486408 -126.161656) (xy 327.450717 -126.120465) (xy 327.421251 -126.074615) (xy 327.398609 -126.025038)
			(xy 327.383254 -125.972743) (xy 327.375498 -125.918795) (xy 327.375012 -125.891544) (xy 313.317205 -125.891544)
			(xy 313.289976 -126.530354) (xy 365.993426 -126.530354) (xy 365.993968 -126.50269) (xy 366.001961 -126.447942)
			(xy 366.017771 -126.39492) (xy 366.041069 -126.344736) (xy 366.071366 -126.298439) (xy 366.108028 -126.257001)
			(xy 366.150286 -126.221287) (xy 366.173512 -126.20625) (xy 366.183163 -126.199581) (xy 366.195622 -126.179744)
			(xy 366.197388 -126.16815) (xy 366.205262 -126.08814) (xy 366.205858 -126.076503) (xy 366.197802 -126.054668)
			(xy 366.189768 -126.04623) (xy 366.189514 -126.045976) (xy 366.170942 -126.027886) (xy 366.138362 -125.987557)
			(xy 366.111547 -125.943184) (xy 366.090993 -125.895587) (xy 366.077078 -125.845645) (xy 366.070059 -125.794277)
			(xy 366.069626 -125.768354) (xy 366.070035 -125.7411) (xy 366.077799 -125.687148) (xy 366.093161 -125.63485)
			(xy 366.11581 -125.58527) (xy 366.145285 -125.539418) (xy 366.180984 -125.498228) (xy 366.222182 -125.462537)
			(xy 366.26804 -125.433072) (xy 366.317625 -125.410433) (xy 366.369926 -125.395082) (xy 366.42388 -125.387329)
			(xy 366.451134 -125.386846) (xy 366.478505 -125.387281) (xy 366.532686 -125.395105) (xy 366.58519 -125.4106)
			(xy 366.634937 -125.433449) (xy 366.680902 -125.463181) (xy 366.701832 -125.480826) (xy 366.702086 -125.48108)
			(xy 366.709166 -125.486676) (xy 366.726088 -125.492915) (xy 366.735106 -125.493272) (xy 366.802162 -125.493272)
			(xy 366.811178 -125.492903) (xy 366.828095 -125.486664) (xy 366.835182 -125.48108) (xy 366.835182 -125.480826)
			(xy 366.835436 -125.480826) (xy 366.856385 -125.463207) (xy 366.902353 -125.433492) (xy 366.952096 -125.410651)
			(xy 367.004593 -125.395156) (xy 367.058766 -125.387322) (xy 367.086134 -125.386846) (xy 367.113384 -125.387346)
			(xy 367.167329 -125.395106) (xy 367.21962 -125.410463) (xy 367.269195 -125.433105) (xy 367.315043 -125.46257)
			(xy 367.356231 -125.49826) (xy 367.391922 -125.539448) (xy 367.421389 -125.585295) (xy 367.444033 -125.634868)
			(xy 367.459391 -125.687159) (xy 367.467153 -125.741104) (xy 367.467642 -125.768354) (xy 367.467113 -125.797271)
			(xy 367.458389 -125.854442) (xy 367.441135 -125.909642) (xy 367.415745 -125.961604) (xy 367.382803 -126.009138)
			(xy 367.343062 -126.051155) (xy 367.320576 -126.069344) (xy 367.311755 -126.076938) (xy 367.30158 -126.097849)
			(xy 367.301018 -126.109476) (xy 367.301018 -126.189232) (xy 367.301547 -126.200865) (xy 367.311742 -126.221775)
			(xy 367.320576 -126.229364) (xy 367.343037 -126.247581) (xy 367.382775 -126.289595) (xy 367.415717 -126.337124)
			(xy 367.44111 -126.38908) (xy 367.45837 -126.444274) (xy 367.467104 -126.501439) (xy 367.467642 -126.530354)
			(xy 367.467102 -126.557604) (xy 367.459352 -126.611551) (xy 367.447251 -126.652782) (xy 367.738914 -126.652782)
			(xy 367.739366 -126.625411) (xy 367.747187 -126.571231) (xy 367.762679 -126.518728) (xy 367.785524 -126.468981)
			(xy 367.815251 -126.423015) (xy 367.832894 -126.402084) (xy 367.833148 -126.40183) (xy 367.838734 -126.394743)
			(xy 367.84498 -126.377826) (xy 367.84534 -126.36881) (xy 367.84534 -126.301754) (xy 367.84497 -126.292738)
			(xy 367.838733 -126.27582) (xy 367.833148 -126.268734) (xy 367.832894 -126.268734) (xy 367.832894 -126.26848)
			(xy 367.815237 -126.247561) (xy 367.785515 -126.20159) (xy 367.762673 -126.151841) (xy 367.74718 -126.099337)
			(xy 367.739354 -126.045158) (xy 367.739355 -125.990415) (xy 367.747186 -125.936236) (xy 367.762683 -125.883733)
			(xy 367.785529 -125.833986) (xy 367.815253 -125.788017) (xy 367.832894 -125.767084) (xy 367.833148 -125.76683)
			(xy 367.838734 -125.759743) (xy 367.84498 -125.742826) (xy 367.84534 -125.73381) (xy 367.84534 -125.666754)
			(xy 367.84497 -125.657738) (xy 367.838733 -125.64082) (xy 367.833148 -125.633734) (xy 367.832894 -125.633734)
			(xy 367.832894 -125.63348) (xy 367.815237 -125.612561) (xy 367.785515 -125.56659) (xy 367.762673 -125.516841)
			(xy 367.74718 -125.464337) (xy 367.739354 -125.410158) (xy 367.739355 -125.355415) (xy 367.747186 -125.301236)
			(xy 367.762683 -125.248733) (xy 367.785529 -125.198986) (xy 367.815253 -125.153017) (xy 367.832894 -125.132084)
			(xy 367.833148 -125.13183) (xy 367.838734 -125.124743) (xy 367.84498 -125.107826) (xy 367.84534 -125.09881)
			(xy 367.84534 -125.031754) (xy 367.84497 -125.022738) (xy 367.838733 -125.00582) (xy 367.833148 -124.998734)
			(xy 367.832894 -124.998734) (xy 367.832894 -124.99848) (xy 367.815278 -124.977529) (xy 367.785563 -124.931562)
			(xy 367.762723 -124.881819) (xy 367.747226 -124.829322) (xy 367.739392 -124.77515) (xy 367.738914 -124.747782)
			(xy 367.7394 -124.720531) (xy 367.747156 -124.666583) (xy 367.762511 -124.614288) (xy 367.785153 -124.564711)
			(xy 367.814619 -124.518861) (xy 367.85031 -124.47767) (xy 367.891501 -124.441979) (xy 367.937351 -124.412513)
			(xy 367.986928 -124.389871) (xy 368.039223 -124.374516) (xy 368.093171 -124.36676) (xy 368.147673 -124.36676)
			(xy 368.201621 -124.374516) (xy 368.253916 -124.389871) (xy 368.303493 -124.412513) (xy 368.349343 -124.441979)
			(xy 368.390534 -124.47767) (xy 368.426225 -124.518861) (xy 368.455691 -124.564711) (xy 368.478333 -124.614288)
			(xy 368.493688 -124.666583) (xy 368.501444 -124.720531) (xy 368.50193 -124.747782) (xy 368.50147 -124.775153)
			(xy 368.493654 -124.829333) (xy 368.478164 -124.881837) (xy 368.45532 -124.931583) (xy 368.425593 -124.977549)
			(xy 368.40795 -124.99848) (xy 368.407696 -124.998734) (xy 368.40213 -125.005835) (xy 368.395871 -125.022741)
			(xy 368.395504 -125.031754) (xy 368.395504 -125.09881) (xy 368.395855 -125.107827) (xy 368.402107 -125.124744)
			(xy 368.407696 -125.13183) (xy 368.40795 -125.13183) (xy 368.40795 -125.132084) (xy 368.425574 -125.153031)
			(xy 368.455301 -125.198995) (xy 368.478149 -125.248739) (xy 368.493648 -125.301239) (xy 368.501479 -125.355416)
			(xy 368.50148 -125.410156) (xy 368.493654 -125.464334) (xy 368.478159 -125.516835) (xy 368.455314 -125.566581)
			(xy 368.42559 -125.612548) (xy 368.40795 -125.63348) (xy 368.407696 -125.633734) (xy 368.40213 -125.640835)
			(xy 368.395871 -125.657741) (xy 368.395504 -125.666754) (xy 368.395504 -125.73381) (xy 368.395855 -125.742827)
			(xy 368.402107 -125.759744) (xy 368.407696 -125.76683) (xy 368.40795 -125.76683) (xy 368.40795 -125.767084)
			(xy 368.425574 -125.788031) (xy 368.455301 -125.833995) (xy 368.478149 -125.883739) (xy 368.493648 -125.936239)
			(xy 368.501479 -125.990416) (xy 368.50148 -126.045156) (xy 368.493654 -126.099334) (xy 368.478159 -126.151835)
			(xy 368.455314 -126.201581) (xy 368.42559 -126.247548) (xy 368.40795 -126.26848) (xy 368.407696 -126.268734)
			(xy 368.40213 -126.275835) (xy 368.395871 -126.292741) (xy 368.395504 -126.301754) (xy 368.395504 -126.36881)
			(xy 368.395855 -126.377827) (xy 368.402107 -126.394744) (xy 368.407696 -126.40183) (xy 368.40795 -126.40183)
			(xy 368.40795 -126.402084) (xy 368.425587 -126.423018) (xy 368.455301 -126.468989) (xy 368.478138 -126.518736)
			(xy 368.493629 -126.571237) (xy 368.501457 -126.625413) (xy 368.50193 -126.652782) (xy 368.501444 -126.680033)
			(xy 368.493688 -126.733981) (xy 368.478333 -126.786276) (xy 368.455691 -126.835853) (xy 368.426225 -126.881703)
			(xy 368.390534 -126.922894) (xy 368.349343 -126.958585) (xy 368.303493 -126.988051) (xy 368.253916 -127.010693)
			(xy 368.201621 -127.026048) (xy 368.147673 -127.033804) (xy 368.093171 -127.033804) (xy 368.039223 -127.026048)
			(xy 367.986928 -127.010693) (xy 367.937351 -126.988051) (xy 367.891501 -126.958585) (xy 367.85031 -126.922894)
			(xy 367.814619 -126.881703) (xy 367.785153 -126.835853) (xy 367.762511 -126.786276) (xy 367.747156 -126.733981)
			(xy 367.7394 -126.680033) (xy 367.738914 -126.652782) (xy 367.447251 -126.652782) (xy 367.444004 -126.663845)
			(xy 367.421369 -126.713423) (xy 367.391909 -126.759274) (xy 367.356223 -126.800467) (xy 367.315038 -126.836161)
			(xy 367.269193 -126.865631) (xy 367.21962 -126.888276) (xy 367.167329 -126.903635) (xy 367.113384 -126.911396)
			(xy 367.086134 -126.911862) (xy 367.059818 -126.911451) (xy 367.007687 -126.904206) (xy 366.957042 -126.889877)
			(xy 366.908843 -126.868734) (xy 366.864001 -126.841177) (xy 366.823365 -126.807728) (xy 366.80521 -126.788672)
			(xy 366.797677 -126.781283) (xy 366.778406 -126.772749) (xy 366.767872 -126.772162) (xy 366.693196 -126.772162)
			(xy 366.682646 -126.772687) (xy 366.663352 -126.781226) (xy 366.655858 -126.788672) (xy 366.63771 -126.807736)
			(xy 366.59708 -126.841193) (xy 366.552238 -126.868752) (xy 366.504035 -126.889889) (xy 366.453386 -126.904204)
			(xy 366.401251 -126.911426) (xy 366.374934 -126.911862) (xy 366.34768 -126.911413) (xy 366.293726 -126.903659)
			(xy 366.241425 -126.888305) (xy 366.191842 -126.865663) (xy 366.145987 -126.836195) (xy 366.104792 -126.800499)
			(xy 366.069098 -126.759304) (xy 366.039631 -126.713447) (xy 366.01699 -126.663864) (xy 366.001638 -126.611562)
			(xy 365.993886 -126.557608) (xy 365.993426 -126.530354) (xy 313.289976 -126.530354) (xy 313.26777 -127.051308)
			(xy 359.044238 -127.051308) (xy 359.048309 -126.995686) (xy 359.060435 -126.941249) (xy 359.080358 -126.889158)
			(xy 359.107654 -126.840523) (xy 359.14174 -126.79638) (xy 359.181889 -126.757671) (xy 359.227247 -126.72522)
			(xy 359.276847 -126.699719) (xy 359.329631 -126.681712) (xy 359.384474 -126.671582) (xy 359.440208 -126.669545)
			(xy 359.495645 -126.675645) (xy 359.549602 -126.689751) (xy 359.600931 -126.711563) (xy 359.648537 -126.740617)
			(xy 359.691405 -126.776292) (xy 359.728622 -126.817829) (xy 359.759395 -126.864342) (xy 359.783067 -126.914839)
			(xy 359.799135 -126.968246) (xy 359.807255 -127.023422) (xy 359.807764 -127.051308) (xy 359.807255 -127.079194)
			(xy 359.799135 -127.13437) (xy 359.783067 -127.187777) (xy 359.759395 -127.238274) (xy 359.728622 -127.284787)
			(xy 359.691405 -127.326324) (xy 359.648537 -127.361999) (xy 359.600931 -127.391053) (xy 359.549602 -127.412865)
			(xy 359.495645 -127.426971) (xy 359.440208 -127.433071) (xy 359.384474 -127.431034) (xy 359.329631 -127.420904)
			(xy 359.276847 -127.402897) (xy 359.227247 -127.377396) (xy 359.181889 -127.344945) (xy 359.14174 -127.306236)
			(xy 359.107654 -127.262093) (xy 359.080358 -127.213458) (xy 359.060435 -127.161367) (xy 359.048309 -127.10693)
			(xy 359.044238 -127.051308) (xy 313.26777 -127.051308) (xy 313.216558 -128.252747) (xy 358.028528 -128.252747)
			(xy 358.028528 -128.198253) (xy 358.036283 -128.144313) (xy 358.051636 -128.092025) (xy 358.074274 -128.042455)
			(xy 358.103736 -127.996611) (xy 358.139422 -127.955426) (xy 358.180606 -127.919739) (xy 358.22645 -127.890277)
			(xy 358.27602 -127.867638) (xy 358.328307 -127.852285) (xy 358.382247 -127.844529) (xy 358.409494 -127.844042)
			(xy 358.436865 -127.844501) (xy 358.491044 -127.852319) (xy 358.543548 -127.867809) (xy 358.593295 -127.890653)
			(xy 358.639261 -127.92038) (xy 358.660192 -127.938022) (xy 358.660446 -127.938276) (xy 358.667537 -127.943855)
			(xy 358.684451 -127.950104) (xy 358.693466 -127.950468) (xy 358.760522 -127.950468) (xy 358.769541 -127.950129)
			(xy 358.786458 -127.94387) (xy 358.793542 -127.938276) (xy 358.793542 -127.938022) (xy 358.793796 -127.938022)
			(xy 358.814729 -127.920381) (xy 358.860697 -127.890657) (xy 358.910443 -127.867811) (xy 358.962945 -127.852315)
			(xy 359.017123 -127.844486) (xy 359.071865 -127.844486) (xy 359.126043 -127.852315) (xy 359.178545 -127.867811)
			(xy 359.228291 -127.890657) (xy 359.274259 -127.920381) (xy 359.295192 -127.938022) (xy 359.295446 -127.938276)
			(xy 359.302537 -127.943855) (xy 359.319451 -127.950104) (xy 359.328466 -127.950468) (xy 359.395522 -127.950468)
			(xy 359.404541 -127.950129) (xy 359.421458 -127.94387) (xy 359.428542 -127.938276) (xy 359.428542 -127.938022)
			(xy 359.428796 -127.938022) (xy 359.449722 -127.920375) (xy 359.495696 -127.890663) (xy 359.545445 -127.867829)
			(xy 359.597947 -127.85234) (xy 359.652124 -127.844514) (xy 359.679494 -127.844042) (xy 359.706751 -127.844405)
			(xy 359.760709 -127.852162) (xy 359.813015 -127.867519) (xy 359.862602 -127.890165) (xy 359.908462 -127.919636)
			(xy 359.949661 -127.955335) (xy 359.98536 -127.996533) (xy 360.014833 -128.042392) (xy 360.037478 -128.091979)
			(xy 360.052837 -128.144285) (xy 360.060595 -128.198243) (xy 360.060595 -128.252757) (xy 360.052837 -128.306715)
			(xy 360.037478 -128.359021) (xy 360.014833 -128.408608) (xy 359.98536 -128.454467) (xy 359.949661 -128.495665)
			(xy 359.908462 -128.531364) (xy 359.862602 -128.560835) (xy 359.813015 -128.583481) (xy 359.760709 -128.598838)
			(xy 359.706751 -128.606595) (xy 359.679494 -128.607058) (xy 359.652123 -128.606606) (xy 359.597943 -128.598786)
			(xy 359.545439 -128.583294) (xy 359.495693 -128.560449) (xy 359.449727 -128.530721) (xy 359.428796 -128.513078)
			(xy 359.428542 -128.512824) (xy 359.421454 -128.50724) (xy 359.404538 -128.500994) (xy 359.395522 -128.500632)
			(xy 359.328466 -128.500632) (xy 359.319447 -128.500966) (xy 359.302529 -128.507229) (xy 359.295446 -128.512824)
			(xy 359.295192 -128.513078) (xy 359.274259 -128.530719) (xy 359.228291 -128.560443) (xy 359.178545 -128.583289)
			(xy 359.126043 -128.598785) (xy 359.071865 -128.606614) (xy 359.017123 -128.606614) (xy 358.962945 -128.598785)
			(xy 358.910443 -128.583289) (xy 358.860697 -128.560443) (xy 358.814729 -128.530719) (xy 358.793796 -128.513078)
			(xy 358.793542 -128.512824) (xy 358.786454 -128.50724) (xy 358.769538 -128.500994) (xy 358.760522 -128.500632)
			(xy 358.693466 -128.500632) (xy 358.684447 -128.500966) (xy 358.667529 -128.507229) (xy 358.660446 -128.512824)
			(xy 358.660446 -128.513078) (xy 358.660192 -128.513078) (xy 358.639271 -128.530731) (xy 358.593295 -128.560441)
			(xy 358.543545 -128.583275) (xy 358.491042 -128.598763) (xy 358.436864 -128.606587) (xy 358.409494 -128.607058)
			(xy 358.382247 -128.606471) (xy 358.328307 -128.598715) (xy 358.27602 -128.583362) (xy 358.22645 -128.560723)
			(xy 358.180606 -128.531261) (xy 358.139422 -128.495574) (xy 358.103736 -128.454389) (xy 358.074274 -128.408545)
			(xy 358.051636 -128.358975) (xy 358.036283 -128.306687) (xy 358.028528 -128.252747) (xy 313.216558 -128.252747)
			(xy 313.180874 -129.089912) (xy 350.987104 -129.089912) (xy 350.991175 -129.03429) (xy 351.003301 -128.979853)
			(xy 351.023224 -128.927762) (xy 351.05052 -128.879127) (xy 351.084606 -128.834984) (xy 351.124755 -128.796275)
			(xy 351.170113 -128.763824) (xy 351.219713 -128.738323) (xy 351.272497 -128.720316) (xy 351.32734 -128.710186)
			(xy 351.383074 -128.708149) (xy 351.438511 -128.714249) (xy 351.492468 -128.728355) (xy 351.543797 -128.750167)
			(xy 351.591403 -128.779221) (xy 351.634271 -128.814896) (xy 351.671488 -128.856433) (xy 351.702261 -128.902946)
			(xy 351.725933 -128.953443) (xy 351.738563 -128.995424) (xy 353.680268 -128.995424) (xy 353.680754 -128.968173)
			(xy 353.68851 -128.914225) (xy 353.703865 -128.86193) (xy 353.726507 -128.812353) (xy 353.755973 -128.766503)
			(xy 353.791664 -128.725312) (xy 353.832855 -128.689621) (xy 353.878705 -128.660155) (xy 353.928282 -128.637513)
			(xy 353.980577 -128.622158) (xy 354.034525 -128.614402) (xy 354.089027 -128.614402) (xy 354.142975 -128.622158)
			(xy 354.19527 -128.637513) (xy 354.244847 -128.660155) (xy 354.290697 -128.689621) (xy 354.331888 -128.725312)
			(xy 354.367579 -128.766503) (xy 354.397045 -128.812353) (xy 354.419687 -128.86193) (xy 354.435042 -128.914225)
			(xy 354.442798 -128.968173) (xy 354.443284 -128.995424) (xy 354.442716 -129.02523) (xy 354.433422 -129.084112)
			(xy 354.415081 -129.140832) (xy 354.388139 -129.194007) (xy 354.353252 -129.242344) (xy 354.311269 -129.284664)
			(xy 354.287582 -129.302764) (xy 354.276455 -129.31143) (xy 354.25915 -129.333688) (xy 354.248595 -129.359833)
			(xy 354.245596 -129.387867) (xy 354.250383 -129.415652) (xy 354.262589 -129.441068) (xy 354.281284 -129.462173)
			(xy 354.292916 -129.47015) (xy 354.315638 -129.485287) (xy 354.356946 -129.520983) (xy 354.392746 -129.562203)
			(xy 354.422305 -129.608104) (xy 354.44502 -129.657749) (xy 354.460429 -129.710125) (xy 354.468215 -129.764162)
			(xy 354.468684 -129.79146) (xy 354.468198 -129.818711) (xy 354.460442 -129.872659) (xy 354.445087 -129.924954)
			(xy 354.422445 -129.974531) (xy 354.392979 -130.020381) (xy 354.357288 -130.061572) (xy 354.316097 -130.097263)
			(xy 354.270247 -130.126729) (xy 354.22067 -130.149371) (xy 354.168375 -130.164726) (xy 354.114427 -130.172482)
			(xy 354.059925 -130.172482) (xy 354.005977 -130.164726) (xy 353.953682 -130.149371) (xy 353.904105 -130.126729)
			(xy 353.858255 -130.097263) (xy 353.817064 -130.061572) (xy 353.781373 -130.020381) (xy 353.751907 -129.974531)
			(xy 353.729265 -129.924954) (xy 353.71391 -129.872659) (xy 353.706154 -129.818711) (xy 353.705668 -129.79146)
			(xy 353.706203 -129.761653) (xy 353.715501 -129.702768) (xy 353.733847 -129.646047) (xy 353.760795 -129.592871)
			(xy 353.795689 -129.544535) (xy 353.837679 -129.502218) (xy 353.86137 -129.48412) (xy 353.872506 -129.475469)
			(xy 353.889803 -129.453204) (xy 353.900351 -129.427058) (xy 353.903345 -129.399023) (xy 353.898558 -129.371239)
			(xy 353.886355 -129.345823) (xy 353.867666 -129.324714) (xy 353.856036 -129.316734) (xy 353.833296 -129.301624)
			(xy 353.79199 -129.265921) (xy 353.756194 -129.224696) (xy 353.726638 -129.17879) (xy 353.703925 -129.129141)
			(xy 353.688519 -129.076762) (xy 353.680736 -129.022723) (xy 353.680268 -128.995424) (xy 351.738563 -128.995424)
			(xy 351.742001 -129.00685) (xy 351.750121 -129.062026) (xy 351.75063 -129.089912) (xy 351.750121 -129.117798)
			(xy 351.742001 -129.172974) (xy 351.725933 -129.226381) (xy 351.702261 -129.276878) (xy 351.671488 -129.323391)
			(xy 351.634271 -129.364928) (xy 351.591403 -129.400603) (xy 351.543797 -129.429657) (xy 351.492468 -129.451469)
			(xy 351.438511 -129.465575) (xy 351.383074 -129.471675) (xy 351.32734 -129.469638) (xy 351.272497 -129.459508)
			(xy 351.219713 -129.441501) (xy 351.170113 -129.416) (xy 351.124755 -129.383549) (xy 351.084606 -129.34484)
			(xy 351.05052 -129.300697) (xy 351.023224 -129.252062) (xy 351.003301 -129.199971) (xy 350.991175 -129.145534)
			(xy 350.987104 -129.089912) (xy 313.180874 -129.089912) (xy 313.172094 -129.295906) (xy 313.172878 -129.306)
			(xy 313.181337 -129.324376) (xy 313.196253 -129.338041) (xy 313.205622 -129.34188) (xy 313.208416 -129.342642)
			(xy 313.230922 -129.349826) (xy 313.274102 -129.368999) (xy 313.314581 -129.393362) (xy 313.333384 -129.407666)
			(xy 313.356956 -129.426847) (xy 313.398304 -129.47138) (xy 313.41568 -129.496312) (xy 313.417751 -129.49927)
			(xy 313.422596 -129.504624) (xy 313.425332 -129.50698) (xy 313.442858 -129.521712) (xy 313.453449 -129.525437)
			(xy 313.475852 -129.524399) (xy 313.486038 -129.51968) (xy 313.489086 -129.517648) (xy 313.516516 -129.501054)
			(xy 313.575033 -129.474868) (xy 313.636633 -129.457109) (xy 313.70011 -129.448124) (xy 313.732164 -129.447544)
			(xy 313.762124 -129.448031) (xy 313.821532 -129.455845) (xy 313.879412 -129.471343) (xy 313.934775 -129.49426)
			(xy 313.986675 -129.524206) (xy 314.034224 -129.560667) (xy 314.076609 -129.603021) (xy 314.113106 -129.650543)
			(xy 314.14309 -129.702421) (xy 314.166048 -129.757768) (xy 314.181589 -129.815637) (xy 314.189447 -129.875039)
			(xy 314.189872 -129.904998) (xy 314.189872 -130.769106) (xy 314.189382 -130.79908) (xy 314.18156 -130.858515)
			(xy 314.166049 -130.916421) (xy 314.143116 -130.971808) (xy 314.113151 -131.023729) (xy 314.076669 -131.071297)
			(xy 314.034292 -131.113699) (xy 313.986744 -131.150208) (xy 313.93484 -131.180201) (xy 313.879465 -131.203166)
			(xy 313.838684 -131.214114) (xy 351.13036 -131.214114) (xy 351.134431 -131.158492) (xy 351.146557 -131.104055)
			(xy 351.16648 -131.051964) (xy 351.193776 -131.003329) (xy 351.227862 -130.959186) (xy 351.268011 -130.920477)
			(xy 351.313369 -130.888026) (xy 351.362969 -130.862525) (xy 351.415753 -130.844518) (xy 351.470596 -130.834388)
			(xy 351.52633 -130.832351) (xy 351.581767 -130.838451) (xy 351.635724 -130.852557) (xy 351.687053 -130.874369)
			(xy 351.734659 -130.903423) (xy 351.777527 -130.939098) (xy 351.814744 -130.980635) (xy 351.845517 -131.027148)
			(xy 351.869189 -131.077645) (xy 351.885257 -131.131052) (xy 351.893377 -131.186228) (xy 351.893886 -131.214114)
			(xy 351.893377 -131.242) (xy 351.885257 -131.297176) (xy 351.869189 -131.350583) (xy 351.845517 -131.40108)
			(xy 351.815032 -131.447157) (xy 358.013409 -131.447157) (xy 358.013409 -131.392643) (xy 358.021167 -131.338685)
			(xy 358.036525 -131.28638) (xy 358.059171 -131.236794) (xy 358.088644 -131.190935) (xy 358.124342 -131.149737)
			(xy 358.165541 -131.114039) (xy 358.211401 -131.084567) (xy 358.260988 -131.061923) (xy 358.313293 -131.046565)
			(xy 358.367251 -131.038808) (xy 358.394508 -131.038346) (xy 358.421879 -131.038796) (xy 358.476059 -131.046616)
			(xy 358.528563 -131.062108) (xy 358.57831 -131.084954) (xy 358.624275 -131.114683) (xy 358.645206 -131.132326)
			(xy 358.64546 -131.13258) (xy 358.652547 -131.138165) (xy 358.669464 -131.144411) (xy 358.67848 -131.144772)
			(xy 358.745536 -131.144772) (xy 358.754555 -131.144438) (xy 358.771472 -131.138175) (xy 358.778556 -131.13258)
			(xy 358.778556 -131.132326) (xy 358.77881 -131.132326) (xy 358.799743 -131.114685) (xy 358.845711 -131.084961)
			(xy 358.895457 -131.062115) (xy 358.947959 -131.046619) (xy 359.002137 -131.03879) (xy 359.056879 -131.03879)
			(xy 359.111057 -131.046619) (xy 359.163559 -131.062115) (xy 359.213305 -131.084961) (xy 359.259273 -131.114685)
			(xy 359.280206 -131.132326) (xy 359.28046 -131.13258) (xy 359.287547 -131.138165) (xy 359.304464 -131.144411)
			(xy 359.31348 -131.144772) (xy 359.380536 -131.144772) (xy 359.389555 -131.144438) (xy 359.406472 -131.138175)
			(xy 359.413556 -131.13258) (xy 359.413556 -131.132326) (xy 359.41381 -131.132326) (xy 359.434731 -131.114673)
			(xy 359.480706 -131.084962) (xy 359.530457 -131.062129) (xy 359.58296 -131.046641) (xy 359.637138 -131.038817)
			(xy 359.664508 -131.038346) (xy 359.691756 -131.038925) (xy 359.745696 -131.046681) (xy 359.797983 -131.062035)
			(xy 359.847553 -131.084674) (xy 359.893397 -131.114137) (xy 359.934582 -131.149824) (xy 359.970268 -131.191009)
			(xy 359.99973 -131.236854) (xy 360.022368 -131.286424) (xy 360.037721 -131.338712) (xy 360.045476 -131.392652)
			(xy 360.045476 -131.447148) (xy 360.037721 -131.501088) (xy 360.022368 -131.553376) (xy 359.99973 -131.602946)
			(xy 359.970268 -131.648791) (xy 359.934582 -131.689976) (xy 359.893397 -131.725663) (xy 359.847553 -131.755126)
			(xy 359.797983 -131.777765) (xy 359.745696 -131.793119) (xy 359.691756 -131.800875) (xy 359.664508 -131.801362)
			(xy 359.637137 -131.800901) (xy 359.582958 -131.793083) (xy 359.530454 -131.777593) (xy 359.480708 -131.75475)
			(xy 359.434741 -131.725024) (xy 359.41381 -131.707382) (xy 359.413556 -131.707128) (xy 359.406464 -131.70155)
			(xy 359.389551 -131.6953) (xy 359.380536 -131.694936) (xy 359.31348 -131.694936) (xy 359.304461 -131.695276)
			(xy 359.287544 -131.701534) (xy 359.28046 -131.707128) (xy 359.280206 -131.707382) (xy 359.259273 -131.725023)
			(xy 359.213305 -131.754747) (xy 359.163559 -131.777593) (xy 359.111057 -131.793089) (xy 359.056879 -131.800918)
			(xy 359.002137 -131.800918) (xy 358.947959 -131.793089) (xy 358.895457 -131.777593) (xy 358.845711 -131.754747)
			(xy 358.799743 -131.725023) (xy 358.77881 -131.707382) (xy 358.778556 -131.707128) (xy 358.771464 -131.70155)
			(xy 358.754551 -131.6953) (xy 358.745536 -131.694936) (xy 358.67848 -131.694936) (xy 358.669461 -131.695276)
			(xy 358.652544 -131.701534) (xy 358.64546 -131.707128) (xy 358.64546 -131.707382) (xy 358.645206 -131.707382)
			(xy 358.62428 -131.725029) (xy 358.578306 -131.75474) (xy 358.528557 -131.777575) (xy 358.476055 -131.793064)
			(xy 358.421878 -131.80089) (xy 358.394508 -131.801362) (xy 358.367251 -131.800992) (xy 358.313293 -131.793235)
			(xy 358.260988 -131.777877) (xy 358.211401 -131.755233) (xy 358.165541 -131.725761) (xy 358.124342 -131.690063)
			(xy 358.088644 -131.648865) (xy 358.059171 -131.603006) (xy 358.036525 -131.55342) (xy 358.021167 -131.501115)
			(xy 358.013409 -131.447157) (xy 351.815032 -131.447157) (xy 351.814744 -131.447593) (xy 351.777527 -131.48913)
			(xy 351.734659 -131.524805) (xy 351.687053 -131.553859) (xy 351.635724 -131.575671) (xy 351.581767 -131.589777)
			(xy 351.52633 -131.595877) (xy 351.470596 -131.59384) (xy 351.415753 -131.58371) (xy 351.362969 -131.565703)
			(xy 351.313369 -131.540202) (xy 351.268011 -131.507751) (xy 351.227862 -131.469042) (xy 351.193776 -131.424899)
			(xy 351.16648 -131.376264) (xy 351.146557 -131.324173) (xy 351.134431 -131.269736) (xy 351.13036 -131.214114)
			(xy 313.838684 -131.214114) (xy 313.821568 -131.218709) (xy 313.762137 -131.226565) (xy 313.732164 -131.227068)
			(xy 313.702519 -131.226587) (xy 313.643728 -131.2189) (xy 313.586426 -131.203671) (xy 313.531576 -131.181158)
			(xy 313.505596 -131.16687) (xy 313.497214 -131.162527) (xy 313.478549 -131.159778) (xy 313.469274 -131.161536)
			(xy 313.438794 -131.168394) (xy 313.429814 -131.170847) (xy 313.414319 -131.181139) (xy 313.408568 -131.18846)
			(xy 313.391942 -131.210897) (xy 313.353207 -131.251121) (xy 313.309025 -131.285272) (xy 313.260338 -131.31262)
			(xy 313.208185 -131.332581) (xy 313.15368 -131.344731) (xy 313.125866 -131.34721) (xy 313.125358 -131.34721)
			(xy 313.110118 -131.34848) (xy 313.083448 -131.376166) (xy 313.032223 -132.575808) (xy 315.916564 -132.575808)
			(xy 315.916564 -131.712208) (xy 315.917054 -131.68224) (xy 315.924877 -131.622818) (xy 315.94039 -131.564925)
			(xy 315.963326 -131.509552) (xy 315.993293 -131.457646) (xy 316.02978 -131.410096) (xy 316.07216 -131.367716)
			(xy 316.11971 -131.331229) (xy 316.171616 -131.301262) (xy 316.226989 -131.278326) (xy 316.284882 -131.262813)
			(xy 316.344304 -131.25499) (xy 316.40424 -131.25499) (xy 316.463662 -131.262813) (xy 316.521555 -131.278326)
			(xy 316.576928 -131.301262) (xy 316.628834 -131.331229) (xy 316.676384 -131.367716) (xy 316.718764 -131.410096)
			(xy 316.755251 -131.457646) (xy 316.785218 -131.509552) (xy 316.808154 -131.564925) (xy 316.823667 -131.622818)
			(xy 316.83149 -131.68224) (xy 316.83198 -131.712208) (xy 316.83198 -132.575808) (xy 316.83149 -132.605776)
			(xy 316.823667 -132.665198) (xy 316.808154 -132.723091) (xy 316.785218 -132.778464) (xy 316.755251 -132.83037)
			(xy 316.718764 -132.87792) (xy 316.676384 -132.9203) (xy 316.628834 -132.956787) (xy 316.576928 -132.986754)
			(xy 316.521555 -133.00969) (xy 316.463662 -133.025203) (xy 316.40424 -133.033026) (xy 316.344304 -133.033026)
			(xy 316.284882 -133.025203) (xy 316.226989 -133.00969) (xy 316.171616 -132.986754) (xy 316.11971 -132.956787)
			(xy 316.07216 -132.9203) (xy 316.02978 -132.87792) (xy 315.993293 -132.83037) (xy 315.963326 -132.778464)
			(xy 315.94039 -132.723091) (xy 315.924877 -132.665198) (xy 315.917054 -132.605776) (xy 315.916564 -132.575808)
			(xy 313.032223 -132.575808) (xy 312.955641 -134.369302) (xy 313.274456 -134.369302) (xy 313.274456 -133.505702)
			(xy 313.274946 -133.475734) (xy 313.282769 -133.416312) (xy 313.298282 -133.358419) (xy 313.321218 -133.303046)
			(xy 313.351185 -133.25114) (xy 313.387672 -133.20359) (xy 313.430052 -133.16121) (xy 313.477602 -133.124723)
			(xy 313.529508 -133.094756) (xy 313.584881 -133.07182) (xy 313.642774 -133.056307) (xy 313.702196 -133.048484)
			(xy 313.762132 -133.048484) (xy 313.821554 -133.056307) (xy 313.879447 -133.07182) (xy 313.93482 -133.094756)
			(xy 313.986726 -133.124723) (xy 314.034276 -133.16121) (xy 314.076656 -133.20359) (xy 314.113143 -133.25114)
			(xy 314.14311 -133.303046) (xy 314.166046 -133.358419) (xy 314.181559 -133.416312) (xy 314.189382 -133.475734)
			(xy 314.189872 -133.505702) (xy 314.189872 -134.369302) (xy 314.189382 -134.39927) (xy 314.181559 -134.458692)
			(xy 314.166046 -134.516585) (xy 314.14311 -134.571958) (xy 314.113143 -134.623864) (xy 314.076656 -134.671414)
			(xy 314.034276 -134.713794) (xy 313.986726 -134.750281) (xy 313.93482 -134.780248) (xy 313.879447 -134.803184)
			(xy 313.821554 -134.818697) (xy 313.762132 -134.82652) (xy 313.702196 -134.82652) (xy 313.642774 -134.818697)
			(xy 313.584881 -134.803184) (xy 313.529508 -134.780248) (xy 313.477602 -134.750281) (xy 313.430052 -134.713794)
			(xy 313.387672 -134.671414) (xy 313.351185 -134.623864) (xy 313.321218 -134.571958) (xy 313.298282 -134.516585)
			(xy 313.282769 -134.458692) (xy 313.274946 -134.39927) (xy 313.274456 -134.369302) (xy 312.955641 -134.369302)
			(xy 312.89498 -135.789924) (xy 312.89498 -136.17575) (xy 315.916564 -136.17575) (xy 315.916564 -135.31215)
			(xy 315.917054 -135.282182) (xy 315.924877 -135.22276) (xy 315.94039 -135.164867) (xy 315.963326 -135.109494)
			(xy 315.993293 -135.057588) (xy 316.02978 -135.010038) (xy 316.07216 -134.967658) (xy 316.11971 -134.931171)
			(xy 316.171616 -134.901204) (xy 316.226989 -134.878268) (xy 316.284882 -134.862755) (xy 316.344304 -134.854932)
			(xy 316.40424 -134.854932) (xy 316.463662 -134.862755) (xy 316.521555 -134.878268) (xy 316.576928 -134.901204)
			(xy 316.628834 -134.931171) (xy 316.676384 -134.967658) (xy 316.718764 -135.010038) (xy 316.755251 -135.057588)
			(xy 316.785218 -135.109494) (xy 316.808154 -135.164867) (xy 316.823667 -135.22276) (xy 316.83149 -135.282182)
			(xy 316.83198 -135.31215) (xy 316.83198 -136.17575) (xy 316.83149 -136.205718) (xy 316.823667 -136.26514)
			(xy 316.808154 -136.323033) (xy 316.785218 -136.378406) (xy 316.755251 -136.430312) (xy 316.718764 -136.477862)
			(xy 316.676384 -136.520242) (xy 316.628834 -136.556729) (xy 316.576928 -136.586696) (xy 316.521555 -136.609632)
			(xy 316.463662 -136.625145) (xy 316.40424 -136.632968) (xy 316.344304 -136.632968) (xy 316.284882 -136.625145)
			(xy 316.226989 -136.609632) (xy 316.171616 -136.586696) (xy 316.11971 -136.556729) (xy 316.07216 -136.520242)
			(xy 316.02978 -136.477862) (xy 315.993293 -136.430312) (xy 315.963326 -136.378406) (xy 315.94039 -136.323033)
			(xy 315.924877 -136.26514) (xy 315.917054 -136.205718) (xy 315.916564 -136.17575) (xy 312.89498 -136.17575)
			(xy 312.89498 -136.524492) (xy 312.89498 -136.527286) (xy 312.895757 -136.535151) (xy 312.901459 -136.549884)
			(xy 312.906156 -136.556242) (xy 312.915808 -136.56564) (xy 312.973212 -136.60755) (xy 312.97372 -136.608058)
			(xy 312.98261 -136.614662) (xy 312.985907 -136.616869) (xy 312.993053 -136.620317) (xy 312.996834 -136.62152)
			(xy 313.026552 -136.62152) (xy 313.031124 -136.62025) (xy 313.05757 -136.612903) (xy 313.111885 -136.604993)
			(xy 313.139328 -136.604502) (xy 313.14644 -136.604502) (xy 313.17337 -136.605449) (xy 313.226573 -136.613988)
			(xy 313.278046 -136.629928) (xy 313.326763 -136.652954) (xy 313.371755 -136.682606) (xy 313.412126 -136.718295)
			(xy 313.447073 -136.75931) (xy 313.475901 -136.804834) (xy 313.498035 -136.853963) (xy 313.513035 -136.905717)
			(xy 313.520603 -136.959068) (xy 313.52109 -136.98601) (xy 313.520626 -137.013262) (xy 313.512868 -137.067211)
			(xy 313.497511 -137.119506) (xy 313.474867 -137.169084) (xy 313.445399 -137.214935) (xy 313.409705 -137.256125)
			(xy 313.368512 -137.291816) (xy 313.32266 -137.321281) (xy 313.27308 -137.34392) (xy 313.220783 -137.359274)
			(xy 313.166834 -137.367028) (xy 313.139582 -137.367518) (xy 313.139328 -137.367518) (xy 313.110759 -137.366961)
			(xy 313.054262 -137.358416) (xy 313.026806 -137.3505) (xy 313.026552 -137.3505) (xy 313.015378 -137.347677)
			(xy 312.992631 -137.351242) (xy 312.982864 -137.357358) (xy 312.967878 -137.36828) (xy 312.915808 -137.40638)
			(xy 312.906664 -137.415016) (xy 312.901691 -137.421469) (xy 312.895733 -137.436622) (xy 312.89498 -137.444734)
			(xy 312.89498 -139.281154) (xy 312.895464 -139.29149) (xy 312.903584 -139.3105) (xy 312.910728 -139.317984)
			(xy 312.912506 -139.319762) (xy 312.93308 -139.33932) (xy 312.94024 -139.345598) (xy 312.957861 -139.35278)
			(xy 312.96737 -139.35329) (xy 312.967878 -139.35329) (xy 312.998227 -139.354042) (xy 313.058113 -139.363978)
			(xy 313.11567 -139.38327) (xy 313.169448 -139.411431) (xy 313.218089 -139.447751) (xy 313.239658 -139.469114)
			(xy 313.24677 -139.47648) (xy 313.27344 -139.48791) (xy 313.27818 -139.489776) (xy 313.28816 -139.491814)
			(xy 313.293252 -139.491974) (xy 313.347608 -139.491974) (xy 313.352705 -139.491861) (xy 313.36269 -139.489812)
			(xy 313.36742 -139.48791) (xy 313.39409 -139.47648) (xy 313.401202 -139.469114) (xy 313.419232 -139.451133)
			(xy 313.459234 -139.419625) (xy 313.503072 -139.393719) (xy 313.549967 -139.373876) (xy 313.599086 -139.360448)
			(xy 313.649554 -139.353675) (xy 313.675014 -139.35329) (xy 313.702265 -139.353777) (xy 313.756211 -139.361535)
			(xy 313.808505 -139.376891) (xy 313.85808 -139.399533) (xy 313.903929 -139.429) (xy 313.945118 -139.464692)
			(xy 313.980808 -139.505882) (xy 314.010273 -139.551732) (xy 314.032914 -139.601309) (xy 314.048268 -139.653602)
			(xy 314.056024 -139.707549) (xy 314.056024 -139.71651) (xy 314.991748 -139.71651) (xy 314.995819 -139.660888)
			(xy 315.007945 -139.606451) (xy 315.027868 -139.55436) (xy 315.055164 -139.505725) (xy 315.08925 -139.461582)
			(xy 315.129399 -139.422873) (xy 315.174757 -139.390422) (xy 315.224357 -139.364921) (xy 315.277141 -139.346914)
			(xy 315.331984 -139.336784) (xy 315.387718 -139.334747) (xy 315.443155 -139.340847) (xy 315.497112 -139.354953)
			(xy 315.548441 -139.376765) (xy 315.596047 -139.405819) (xy 315.638915 -139.441494) (xy 315.676132 -139.483031)
			(xy 315.706905 -139.529544) (xy 315.730577 -139.580041) (xy 315.746645 -139.633448) (xy 315.754765 -139.688624)
			(xy 315.755274 -139.71651) (xy 315.754765 -139.744396) (xy 315.746645 -139.799572) (xy 315.730577 -139.852979)
			(xy 315.706905 -139.903476) (xy 315.676132 -139.949989) (xy 315.638915 -139.991526) (xy 315.596047 -140.027201)
			(xy 315.548441 -140.056255) (xy 315.497112 -140.078067) (xy 315.443155 -140.092173) (xy 315.387718 -140.098273)
			(xy 315.331984 -140.096236) (xy 315.277141 -140.086106) (xy 315.224357 -140.068099) (xy 315.174757 -140.042598)
			(xy 315.129399 -140.010147) (xy 315.08925 -139.971438) (xy 315.055164 -139.927295) (xy 315.027868 -139.87866)
			(xy 315.007945 -139.826569) (xy 314.995819 -139.772132) (xy 314.991748 -139.71651) (xy 314.056024 -139.71651)
			(xy 314.056024 -139.762051) (xy 314.048268 -139.815998) (xy 314.032914 -139.868291) (xy 314.010273 -139.917868)
			(xy 313.980808 -139.963718) (xy 313.945118 -140.004908) (xy 313.903929 -140.0406) (xy 313.85808 -140.070067)
			(xy 313.808505 -140.092709) (xy 313.756211 -140.108065) (xy 313.702265 -140.115823) (xy 313.675014 -140.116306)
			(xy 313.649555 -140.115885) (xy 313.599088 -140.109115) (xy 313.54997 -140.095694) (xy 313.503074 -140.075861)
			(xy 313.459231 -140.049966) (xy 313.419221 -140.018472) (xy 313.401202 -140.000482) (xy 313.39409 -139.993116)
			(xy 313.36742 -139.981686) (xy 313.362681 -139.979815) (xy 313.352701 -139.977766) (xy 313.347608 -139.977622)
			(xy 313.293252 -139.977622) (xy 313.288156 -139.977739) (xy 313.278174 -139.979795) (xy 313.27344 -139.981686)
			(xy 313.24677 -139.993116) (xy 313.239658 -140.000482) (xy 313.218386 -140.021567) (xy 313.170477 -140.057508)
			(xy 313.117539 -140.085518) (xy 313.060874 -140.10491) (xy 313.001874 -140.115207) (xy 312.971942 -140.116306)
			(xy 312.965592 -140.116306) (xy 312.959496 -140.116306) (xy 312.948066 -140.116306) (xy 312.944002 -140.120116)
			(xy 312.910982 -140.151612) (xy 312.90387 -140.15974) (xy 312.900141 -140.165531) (xy 312.895634 -140.178538)
			(xy 312.89498 -140.185394) (xy 312.89498 -140.487654) (xy 317.90208 -140.487654) (xy 317.906151 -140.432032)
			(xy 317.918277 -140.377595) (xy 317.9382 -140.325504) (xy 317.965496 -140.276869) (xy 317.999582 -140.232726)
			(xy 318.039731 -140.194017) (xy 318.085089 -140.161566) (xy 318.134689 -140.136065) (xy 318.187473 -140.118058)
			(xy 318.242316 -140.107928) (xy 318.29805 -140.105891) (xy 318.353487 -140.111991) (xy 318.407444 -140.126097)
			(xy 318.458773 -140.147909) (xy 318.506379 -140.176963) (xy 318.549247 -140.212638) (xy 318.586464 -140.254175)
			(xy 318.617237 -140.300688) (xy 318.640909 -140.351185) (xy 318.656977 -140.404592) (xy 318.665097 -140.459768)
			(xy 318.665606 -140.487654) (xy 318.665097 -140.51554) (xy 318.656977 -140.570716) (xy 318.640909 -140.624123)
			(xy 318.617237 -140.67462) (xy 318.586464 -140.721133) (xy 318.549247 -140.76267) (xy 318.506379 -140.798345)
			(xy 318.458773 -140.827399) (xy 318.407444 -140.849211) (xy 318.353487 -140.863317) (xy 318.29805 -140.869417)
			(xy 318.242316 -140.86738) (xy 318.187473 -140.85725) (xy 318.134689 -140.839243) (xy 318.085089 -140.813742)
			(xy 318.039731 -140.781291) (xy 317.999582 -140.742582) (xy 317.965496 -140.698439) (xy 317.9382 -140.649804)
			(xy 317.918277 -140.597713) (xy 317.906151 -140.543276) (xy 317.90208 -140.487654) (xy 312.89498 -140.487654)
			(xy 312.89498 -140.798042) (xy 312.894651 -140.835963) (xy 312.888945 -140.91159) (xy 312.877515 -140.986566)
			(xy 312.869326 -141.023594) (xy 312.783474 -141.393164) (xy 312.62828 -142.060676) (xy 312.627772 -142.065756)
			(xy 312.567469 -143.479266) (xy 313.274456 -143.479266) (xy 313.274456 -142.615666) (xy 313.274946 -142.585698)
			(xy 313.282769 -142.526276) (xy 313.298282 -142.468383) (xy 313.321218 -142.41301) (xy 313.351185 -142.361104)
			(xy 313.387672 -142.313554) (xy 313.430052 -142.271174) (xy 313.477602 -142.234687) (xy 313.529508 -142.20472)
			(xy 313.584881 -142.181784) (xy 313.642774 -142.166271) (xy 313.702196 -142.158448) (xy 313.762132 -142.158448)
			(xy 313.821554 -142.166271) (xy 313.879447 -142.181784) (xy 313.93482 -142.20472) (xy 313.986726 -142.234687)
			(xy 314.034276 -142.271174) (xy 314.076656 -142.313554) (xy 314.113143 -142.361104) (xy 314.14311 -142.41301)
			(xy 314.166046 -142.468383) (xy 314.181559 -142.526276) (xy 314.189382 -142.585698) (xy 314.189872 -142.615666)
			(xy 314.189872 -143.479266) (xy 314.189382 -143.509234) (xy 314.181559 -143.568656) (xy 314.166046 -143.626549)
			(xy 314.14311 -143.681922) (xy 314.113143 -143.733828) (xy 314.076656 -143.781378) (xy 314.034276 -143.823758)
			(xy 313.986726 -143.860245) (xy 313.93482 -143.890212) (xy 313.879447 -143.913148) (xy 313.821554 -143.928661)
			(xy 313.762132 -143.936484) (xy 313.702196 -143.936484) (xy 313.642774 -143.928661) (xy 313.584881 -143.913148)
			(xy 313.529508 -143.890212) (xy 313.477602 -143.860245) (xy 313.430052 -143.823758) (xy 313.387672 -143.781378)
			(xy 313.351185 -143.733828) (xy 313.321218 -143.681922) (xy 313.298282 -143.626549) (xy 313.282769 -143.568656)
			(xy 313.274946 -143.509234) (xy 313.274456 -143.479266) (xy 312.567469 -143.479266) (xy 312.490402 -145.285714)
			(xy 315.916564 -145.285714) (xy 315.916564 -144.422114) (xy 315.917054 -144.392146) (xy 315.924877 -144.332724)
			(xy 315.94039 -144.274831) (xy 315.963326 -144.219458) (xy 315.993293 -144.167552) (xy 316.02978 -144.120002)
			(xy 316.07216 -144.077622) (xy 316.11971 -144.041135) (xy 316.171616 -144.011168) (xy 316.226989 -143.988232)
			(xy 316.284882 -143.972719) (xy 316.344304 -143.964896) (xy 316.40424 -143.964896) (xy 316.463662 -143.972719)
			(xy 316.521555 -143.988232) (xy 316.576928 -144.011168) (xy 316.628834 -144.041135) (xy 316.676384 -144.077622)
			(xy 316.718764 -144.120002) (xy 316.755251 -144.167552) (xy 316.785218 -144.219458) (xy 316.808154 -144.274831)
			(xy 316.823667 -144.332724) (xy 316.83149 -144.392146) (xy 316.83198 -144.422114) (xy 316.83198 -145.285714)
			(xy 316.83149 -145.315682) (xy 316.823667 -145.375104) (xy 316.808154 -145.432997) (xy 316.785218 -145.48837)
			(xy 316.755251 -145.540276) (xy 316.718764 -145.587826) (xy 316.676384 -145.630206) (xy 316.628834 -145.666693)
			(xy 316.576928 -145.69666) (xy 316.521555 -145.719596) (xy 316.463662 -145.735109) (xy 316.40424 -145.742932)
			(xy 316.344304 -145.742932) (xy 316.284882 -145.735109) (xy 316.226989 -145.719596) (xy 316.171616 -145.69666)
			(xy 316.11971 -145.666693) (xy 316.07216 -145.630206) (xy 316.02978 -145.587826) (xy 315.993293 -145.540276)
			(xy 315.963326 -145.48837) (xy 315.94039 -145.432997) (xy 315.924877 -145.375104) (xy 315.917054 -145.315682)
			(xy 315.916564 -145.285714) (xy 312.490402 -145.285714) (xy 312.462672 -145.9357) (xy 312.446924 -146.302984)
			(xy 312.44667 -146.30908) (xy 312.44667 -146.309588) (xy 312.444384 -146.342354) (xy 312.383761 -147.079208)
			(xy 313.274456 -147.079208) (xy 313.274456 -146.215608) (xy 313.274946 -146.18564) (xy 313.282769 -146.126218)
			(xy 313.298282 -146.068325) (xy 313.321218 -146.012952) (xy 313.351185 -145.961046) (xy 313.387672 -145.913496)
			(xy 313.430052 -145.871116) (xy 313.477602 -145.834629) (xy 313.529508 -145.804662) (xy 313.584881 -145.781726)
			(xy 313.642774 -145.766213) (xy 313.702196 -145.75839) (xy 313.762132 -145.75839) (xy 313.821554 -145.766213)
			(xy 313.879447 -145.781726) (xy 313.93482 -145.804662) (xy 313.986726 -145.834629) (xy 314.034276 -145.871116)
			(xy 314.076656 -145.913496) (xy 314.113143 -145.961046) (xy 314.14311 -146.012952) (xy 314.166046 -146.068325)
			(xy 314.181559 -146.126218) (xy 314.189382 -146.18564) (xy 314.189872 -146.215608) (xy 314.189872 -147.079208)
			(xy 314.189382 -147.109176) (xy 314.181559 -147.168598) (xy 314.166046 -147.226491) (xy 314.14311 -147.281864)
			(xy 314.113143 -147.33377) (xy 314.076656 -147.38132) (xy 314.034276 -147.4237) (xy 313.986726 -147.460187)
			(xy 313.93482 -147.490154) (xy 313.879447 -147.51309) (xy 313.821554 -147.528603) (xy 313.762132 -147.536426)
			(xy 313.702196 -147.536426) (xy 313.642774 -147.528603) (xy 313.584881 -147.51309) (xy 313.529508 -147.490154)
			(xy 313.477602 -147.460187) (xy 313.430052 -147.4237) (xy 313.387672 -147.38132) (xy 313.351185 -147.33377)
			(xy 313.321218 -147.281864) (xy 313.298282 -147.226491) (xy 313.282769 -147.168598) (xy 313.274946 -147.109176)
			(xy 313.274456 -147.079208) (xy 312.383761 -147.079208) (xy 312.235118 -148.88591) (xy 315.916564 -148.88591)
			(xy 315.916564 -148.02231) (xy 315.917054 -147.992342) (xy 315.924877 -147.93292) (xy 315.94039 -147.875027)
			(xy 315.963326 -147.819654) (xy 315.993293 -147.767748) (xy 316.02978 -147.720198) (xy 316.07216 -147.677818)
			(xy 316.11971 -147.641331) (xy 316.171616 -147.611364) (xy 316.226989 -147.588428) (xy 316.284882 -147.572915)
			(xy 316.344304 -147.565092) (xy 316.40424 -147.565092) (xy 316.463662 -147.572915) (xy 316.521555 -147.588428)
			(xy 316.576928 -147.611364) (xy 316.628834 -147.641331) (xy 316.676384 -147.677818) (xy 316.718764 -147.720198)
			(xy 316.755251 -147.767748) (xy 316.785218 -147.819654) (xy 316.808154 -147.875027) (xy 316.823667 -147.93292)
			(xy 316.83149 -147.992342) (xy 316.83198 -148.02231) (xy 316.83198 -148.88591) (xy 316.83149 -148.915878)
			(xy 316.823667 -148.9753) (xy 316.808154 -149.033193) (xy 316.785218 -149.088566) (xy 316.755251 -149.140472)
			(xy 316.718764 -149.188022) (xy 316.676384 -149.230402) (xy 316.628834 -149.266889) (xy 316.576928 -149.296856)
			(xy 316.521555 -149.319792) (xy 316.463662 -149.335305) (xy 316.40424 -149.343128) (xy 316.344304 -149.343128)
			(xy 316.284882 -149.335305) (xy 316.226989 -149.319792) (xy 316.171616 -149.296856) (xy 316.11971 -149.266889)
			(xy 316.07216 -149.230402) (xy 316.02978 -149.188022) (xy 315.993293 -149.140472) (xy 315.963326 -149.088566)
			(xy 315.94039 -149.033193) (xy 315.924877 -148.9753) (xy 315.917054 -148.915878) (xy 315.916564 -148.88591)
			(xy 312.235118 -148.88591) (xy 312.087582 -150.67915) (xy 313.274456 -150.67915) (xy 313.274456 -149.81555)
			(xy 313.274946 -149.785582) (xy 313.282769 -149.72616) (xy 313.298282 -149.668267) (xy 313.321218 -149.612894)
			(xy 313.351185 -149.560988) (xy 313.387672 -149.513438) (xy 313.430052 -149.471058) (xy 313.477602 -149.434571)
			(xy 313.529508 -149.404604) (xy 313.584881 -149.381668) (xy 313.642774 -149.366155) (xy 313.702196 -149.358332)
			(xy 313.762132 -149.358332) (xy 313.821554 -149.366155) (xy 313.879447 -149.381668) (xy 313.93482 -149.404604)
			(xy 313.986726 -149.434571) (xy 314.034276 -149.471058) (xy 314.076656 -149.513438) (xy 314.113143 -149.560988)
			(xy 314.14311 -149.612894) (xy 314.166046 -149.668267) (xy 314.181559 -149.72616) (xy 314.189382 -149.785582)
			(xy 314.189872 -149.81555) (xy 314.189872 -150.67915) (xy 314.189382 -150.709118) (xy 314.181559 -150.76854)
			(xy 314.166046 -150.826433) (xy 314.14311 -150.881806) (xy 314.113143 -150.933712) (xy 314.076656 -150.981262)
			(xy 314.034276 -151.023642) (xy 313.986726 -151.060129) (xy 313.93482 -151.090096) (xy 313.879447 -151.113032)
			(xy 313.821554 -151.128545) (xy 313.762132 -151.136368) (xy 313.702196 -151.136368) (xy 313.642774 -151.128545)
			(xy 313.584881 -151.113032) (xy 313.529508 -151.090096) (xy 313.477602 -151.060129) (xy 313.430052 -151.023642)
			(xy 313.387672 -150.981262) (xy 313.351185 -150.933712) (xy 313.321218 -150.881806) (xy 313.298282 -150.826433)
			(xy 313.282769 -150.76854) (xy 313.274946 -150.709118) (xy 313.274456 -150.67915) (xy 312.087582 -150.67915)
			(xy 311.938939 -152.485852) (xy 315.916564 -152.485852) (xy 315.916564 -151.622252) (xy 315.917054 -151.592284)
			(xy 315.924877 -151.532862) (xy 315.94039 -151.474969) (xy 315.963326 -151.419596) (xy 315.993293 -151.36769)
			(xy 316.02978 -151.32014) (xy 316.07216 -151.27776) (xy 316.11971 -151.241273) (xy 316.171616 -151.211306)
			(xy 316.226989 -151.18837) (xy 316.284882 -151.172857) (xy 316.344304 -151.165034) (xy 316.40424 -151.165034)
			(xy 316.463662 -151.172857) (xy 316.521555 -151.18837) (xy 316.576928 -151.211306) (xy 316.628834 -151.241273)
			(xy 316.676384 -151.27776) (xy 316.718764 -151.32014) (xy 316.755251 -151.36769) (xy 316.785218 -151.419596)
			(xy 316.808154 -151.474969) (xy 316.823667 -151.532862) (xy 316.83149 -151.592284) (xy 316.83198 -151.622252)
			(xy 316.83198 -152.485852) (xy 316.83149 -152.51582) (xy 316.823667 -152.575242) (xy 316.808154 -152.633135)
			(xy 316.785218 -152.688508) (xy 316.755251 -152.740414) (xy 316.718764 -152.787964) (xy 316.676384 -152.830344)
			(xy 316.628834 -152.866831) (xy 316.576928 -152.896798) (xy 316.521555 -152.919734) (xy 316.463662 -152.935247)
			(xy 316.40424 -152.94307) (xy 316.344304 -152.94307) (xy 316.284882 -152.935247) (xy 316.226989 -152.919734)
			(xy 316.171616 -152.896798) (xy 316.11971 -152.866831) (xy 316.07216 -152.830344) (xy 316.02978 -152.787964)
			(xy 315.993293 -152.740414) (xy 315.963326 -152.688508) (xy 315.94039 -152.633135) (xy 315.924877 -152.575242)
			(xy 315.917054 -152.51582) (xy 315.916564 -152.485852) (xy 311.938939 -152.485852) (xy 311.818528 -153.9494)
			(xy 311.813194 -153.99893) (xy 311.776015 -154.279346) (xy 313.274456 -154.279346) (xy 313.274456 -153.415746)
			(xy 313.274946 -153.385778) (xy 313.282769 -153.326356) (xy 313.298282 -153.268463) (xy 313.321218 -153.21309)
			(xy 313.351185 -153.161184) (xy 313.387672 -153.113634) (xy 313.430052 -153.071254) (xy 313.477602 -153.034767)
			(xy 313.529508 -153.0048) (xy 313.584881 -152.981864) (xy 313.642774 -152.966351) (xy 313.702196 -152.958528)
			(xy 313.762132 -152.958528) (xy 313.821554 -152.966351) (xy 313.879447 -152.981864) (xy 313.93482 -153.0048)
			(xy 313.986726 -153.034767) (xy 314.034276 -153.071254) (xy 314.076656 -153.113634) (xy 314.113143 -153.161184)
			(xy 314.14311 -153.21309) (xy 314.166046 -153.268463) (xy 314.181559 -153.326356) (xy 314.189382 -153.385778)
			(xy 314.189872 -153.415746) (xy 314.189872 -154.279346) (xy 314.189382 -154.309314) (xy 314.181559 -154.368736)
			(xy 314.166046 -154.426629) (xy 314.14311 -154.482002) (xy 314.113143 -154.533908) (xy 314.076656 -154.581458)
			(xy 314.034276 -154.623838) (xy 313.986726 -154.660325) (xy 313.93482 -154.690292) (xy 313.879447 -154.713228)
			(xy 313.821554 -154.728741) (xy 313.762132 -154.736564) (xy 313.702196 -154.736564) (xy 313.642774 -154.728741)
			(xy 313.584881 -154.713228) (xy 313.529508 -154.690292) (xy 313.477602 -154.660325) (xy 313.430052 -154.623838)
			(xy 313.387672 -154.581458) (xy 313.351185 -154.533908) (xy 313.321218 -154.482002) (xy 313.298282 -154.426629)
			(xy 313.282769 -154.368736) (xy 313.274946 -154.309314) (xy 313.274456 -154.279346) (xy 311.776015 -154.279346)
			(xy 311.741058 -154.542998) (xy 311.69229 -154.91206) (xy 311.692036 -154.9146) (xy 311.594071 -156.085794)
			(xy 315.916564 -156.085794) (xy 315.916564 -155.222194) (xy 315.917054 -155.192226) (xy 315.924877 -155.132804)
			(xy 315.94039 -155.074911) (xy 315.963326 -155.019538) (xy 315.993293 -154.967632) (xy 316.02978 -154.920082)
			(xy 316.07216 -154.877702) (xy 316.11971 -154.841215) (xy 316.171616 -154.811248) (xy 316.226989 -154.788312)
			(xy 316.284882 -154.772799) (xy 316.344304 -154.764976) (xy 316.40424 -154.764976) (xy 316.463662 -154.772799)
			(xy 316.521555 -154.788312) (xy 316.576928 -154.811248) (xy 316.628834 -154.841215) (xy 316.676384 -154.877702)
			(xy 316.718764 -154.920082) (xy 316.755251 -154.967632) (xy 316.785218 -155.019538) (xy 316.808154 -155.074911)
			(xy 316.823667 -155.132804) (xy 316.83149 -155.192226) (xy 316.83198 -155.222194) (xy 316.83198 -156.085794)
			(xy 316.83149 -156.115762) (xy 316.823667 -156.175184) (xy 316.808154 -156.233077) (xy 316.785218 -156.28845)
			(xy 316.755251 -156.340356) (xy 316.718764 -156.387906) (xy 316.676384 -156.430286) (xy 316.628834 -156.466773)
			(xy 316.576928 -156.49674) (xy 316.521555 -156.519676) (xy 316.463662 -156.535189) (xy 316.40424 -156.543012)
			(xy 316.344304 -156.543012) (xy 316.284882 -156.535189) (xy 316.226989 -156.519676) (xy 316.171616 -156.49674)
			(xy 316.11971 -156.466773) (xy 316.07216 -156.430286) (xy 316.02978 -156.387906) (xy 315.993293 -156.340356)
			(xy 315.963326 -156.28845) (xy 315.94039 -156.233077) (xy 315.924877 -156.175184) (xy 315.917054 -156.115762)
			(xy 315.916564 -156.085794) (xy 311.594071 -156.085794) (xy 311.465214 -157.626304) (xy 311.465214 -157.627066)
			(xy 311.463944 -157.644084) (xy 311.46369 -157.645354) (xy 311.461404 -157.672278) (xy 311.461404 -157.67304)
			(xy 311.460896 -157.676088) (xy 311.452514 -157.7213) (xy 311.452514 -157.721554) (xy 310.972454 -160.33496)
			(xy 310.971946 -160.3375) (xy 310.96204 -160.412684) (xy 310.858662 -161.189924) (xy 310.858662 -161.190432)
			(xy 310.854598 -161.218626) (xy 310.854598 -161.219134) (xy 310.851042 -161.2392) (xy 310.821211 -161.401506)
			(xy 312.89752 -161.401506) (xy 312.89752 -160.461452) (xy 312.897917 -160.437478) (xy 312.905423 -160.390122)
			(xy 312.920257 -160.344526) (xy 312.942053 -160.301819) (xy 312.970272 -160.263055) (xy 312.986928 -160.245806)
			(xy 313.710574 -159.522414) (xy 313.717946 -159.514289) (xy 313.725595 -159.493756) (xy 313.725306 -159.48279)
			(xy 313.719718 -159.405828) (xy 313.718413 -159.394932) (xy 313.707879 -159.375708) (xy 313.699398 -159.368744)
			(xy 313.699144 -159.368744) (xy 313.675595 -159.350656) (xy 313.633939 -159.308341) (xy 313.599341 -159.260083)
			(xy 313.572635 -159.207049) (xy 313.554467 -159.150518) (xy 313.545274 -159.091855) (xy 313.544712 -159.062166)
			(xy 313.545248 -159.033447) (xy 313.553856 -158.976659) (xy 313.570887 -158.921805) (xy 313.595955 -158.870128)
			(xy 313.628493 -158.822796) (xy 313.667765 -158.780883) (xy 313.69 -158.7627) (xy 313.690254 -158.762446)
			(xy 313.697175 -158.756347) (xy 313.706517 -158.740458) (xy 313.709646 -158.722294) (xy 313.708288 -158.71317)
			(xy 313.688476 -158.610554) (xy 313.66968 -158.589472) (xy 313.656218 -158.585408) (xy 313.655964 -158.585408)
			(xy 313.630006 -158.577244) (xy 313.580542 -158.554566) (xy 313.534805 -158.525087) (xy 313.493722 -158.489406)
			(xy 313.458128 -158.448248) (xy 313.428746 -158.402448) (xy 313.406173 -158.352936) (xy 313.390867 -158.300718)
			(xy 313.38314 -158.246855) (xy 313.38266 -158.219648) (xy 313.383146 -158.192397) (xy 313.390902 -158.138449)
			(xy 313.406257 -158.086154) (xy 313.428899 -158.036577) (xy 313.458365 -157.990727) (xy 313.494056 -157.949536)
			(xy 313.535247 -157.913845) (xy 313.581097 -157.884379) (xy 313.630674 -157.861737) (xy 313.682969 -157.846382)
			(xy 313.736917 -157.838626) (xy 313.791419 -157.838626) (xy 313.845367 -157.846382) (xy 313.897662 -157.861737)
			(xy 313.947239 -157.884379) (xy 313.993089 -157.913845) (xy 314.03428 -157.949536) (xy 314.069971 -157.990727)
			(xy 314.099437 -158.036577) (xy 314.122079 -158.086154) (xy 314.137434 -158.138449) (xy 314.14519 -158.192397)
			(xy 314.145676 -158.219648) (xy 314.145117 -158.248365) (xy 314.136509 -158.305151) (xy 314.119481 -158.360003)
			(xy 314.094417 -158.41168) (xy 314.061884 -158.459012) (xy 314.02262 -158.500929) (xy 314.000388 -158.519114)
			(xy 314.000134 -158.519368) (xy 313.993203 -158.525457) (xy 313.983865 -158.541351) (xy 313.98074 -158.559519)
			(xy 313.9821 -158.568644) (xy 314.001912 -158.67126) (xy 314.020708 -158.692342) (xy 314.03417 -158.696406)
			(xy 314.034678 -158.696406) (xy 314.06402 -158.70572) (xy 314.119467 -158.732464) (xy 314.169898 -158.767764)
			(xy 314.214006 -158.810706) (xy 314.232798 -158.83509) (xy 314.232798 -158.835344) (xy 314.239784 -158.843796)
			(xy 314.258999 -158.854322) (xy 314.269882 -158.855664) (xy 314.346844 -158.861252) (xy 314.357809 -158.861537)
			(xy 314.378345 -158.853892) (xy 314.386468 -158.84652) (xy 314.664852 -158.567882) (xy 314.682121 -158.551205)
			(xy 314.720937 -158.522957) (xy 314.763694 -158.501129) (xy 314.80934 -158.486258) (xy 314.856749 -158.47871)
			(xy 314.880752 -158.47822) (xy 318.076834 -158.47822) (xy 318.086908 -158.477834) (xy 318.105507 -158.470088)
			(xy 318.112902 -158.463234) (xy 323.204078 -153.372312) (xy 323.210902 -153.364899) (xy 323.218632 -153.34631)
			(xy 323.219064 -153.336244) (xy 323.219064 -138.72845) (xy 323.219476 -138.704477) (xy 323.22698 -138.657122)
			(xy 323.241812 -138.611527) (xy 323.263604 -138.56882) (xy 323.291818 -138.530054) (xy 323.308472 -138.512804)
			(xy 330.328524 -131.492752) (xy 330.345836 -131.476175) (xy 330.384611 -131.448005) (xy 330.427307 -131.426233)
			(xy 330.472878 -131.411392) (xy 330.520207 -131.403845) (xy 330.54417 -131.403344) (xy 335.809082 -131.403344)
			(xy 335.833053 -131.403805) (xy 335.880406 -131.411298) (xy 335.925999 -131.426118) (xy 335.968708 -131.4479)
			(xy 336.007476 -131.476103) (xy 336.024728 -131.492752) (xy 336.466942 -131.934966) (xy 336.483631 -131.952225)
			(xy 336.511885 -131.991042) (xy 336.533718 -132.0338) (xy 336.548591 -132.079448) (xy 336.556139 -132.126861)
			(xy 336.556604 -132.150866) (xy 336.556604 -133.308598) (xy 336.556153 -133.332603) (xy 336.548605 -133.380017)
			(xy 336.533728 -133.425665) (xy 336.524502 -133.443726) (xy 359.422954 -133.443726) (xy 359.423421 -133.417412)
			(xy 359.430654 -133.365283) (xy 359.444972 -133.314639) (xy 359.466104 -133.26644) (xy 359.493651 -133.221596)
			(xy 359.527091 -133.180958) (xy 359.546144 -133.162802) (xy 359.553538 -133.155274) (xy 359.562069 -133.135999)
			(xy 359.562654 -133.125464) (xy 359.562654 -133.050788) (xy 359.562158 -133.040234) (xy 359.553601 -133.020938)
			(xy 359.546144 -133.01345) (xy 359.527061 -132.995323) (xy 359.493608 -132.954686) (xy 359.466054 -132.909839)
			(xy 359.444921 -132.861633) (xy 359.430609 -132.810981) (xy 359.42339 -132.758844) (xy 359.422954 -132.732526)
			(xy 359.42344 -132.705275) (xy 359.431196 -132.651327) (xy 359.446551 -132.599032) (xy 359.469193 -132.549455)
			(xy 359.498659 -132.503605) (xy 359.53435 -132.462414) (xy 359.575541 -132.426723) (xy 359.621391 -132.397257)
			(xy 359.670968 -132.374615) (xy 359.723263 -132.35926) (xy 359.777211 -132.351504) (xy 359.831713 -132.351504)
			(xy 359.885661 -132.35926) (xy 359.937956 -132.374615) (xy 359.987533 -132.397257) (xy 360.033383 -132.426723)
			(xy 360.074574 -132.462414) (xy 360.110265 -132.503605) (xy 360.139731 -132.549455) (xy 360.162373 -132.599032)
			(xy 360.177728 -132.651327) (xy 360.185484 -132.705275) (xy 360.18597 -132.732526) (xy 360.185529 -132.758841)
			(xy 360.17829 -132.810971) (xy 360.163967 -132.861615) (xy 360.142829 -132.909814) (xy 360.115278 -132.954657)
			(xy 360.081834 -132.995295) (xy 360.06278 -133.01345) (xy 360.055351 -133.020948) (xy 360.046843 -133.040246)
			(xy 360.04627 -133.050788) (xy 360.04627 -133.125464) (xy 360.046814 -133.136012) (xy 360.05534 -133.155307)
			(xy 360.06278 -133.162802) (xy 360.081826 -133.180968) (xy 360.115285 -133.221595) (xy 360.142845 -133.266433)
			(xy 360.163986 -133.314632) (xy 360.178305 -133.365278) (xy 360.185531 -133.41741) (xy 360.18597 -133.443726)
			(xy 360.185484 -133.470977) (xy 360.177728 -133.524925) (xy 360.162373 -133.57722) (xy 360.139731 -133.626797)
			(xy 360.110265 -133.672647) (xy 360.074574 -133.713838) (xy 360.033383 -133.749529) (xy 359.987533 -133.778995)
			(xy 359.937956 -133.801637) (xy 359.885661 -133.816992) (xy 359.831713 -133.824748) (xy 359.777211 -133.824748)
			(xy 359.723263 -133.816992) (xy 359.670968 -133.801637) (xy 359.621391 -133.778995) (xy 359.575541 -133.749529)
			(xy 359.53435 -133.713838) (xy 359.498659 -133.672647) (xy 359.469193 -133.626797) (xy 359.446551 -133.57722)
			(xy 359.431196 -133.524925) (xy 359.42344 -133.470977) (xy 359.422954 -133.443726) (xy 336.524502 -133.443726)
			(xy 336.511887 -133.46842) (xy 336.483622 -133.507229) (xy 336.466942 -133.524498) (xy 335.949036 -134.042404)
			(xy 354.476048 -134.042404) (xy 354.480119 -133.986782) (xy 354.492245 -133.932345) (xy 354.512168 -133.880254)
			(xy 354.539464 -133.831619) (xy 354.57355 -133.787476) (xy 354.613699 -133.748767) (xy 354.659057 -133.716316)
			(xy 354.708657 -133.690815) (xy 354.761441 -133.672808) (xy 354.816284 -133.662678) (xy 354.872018 -133.660641)
			(xy 354.927455 -133.666741) (xy 354.981412 -133.680847) (xy 355.032741 -133.702659) (xy 355.080347 -133.731713)
			(xy 355.123215 -133.767388) (xy 355.160432 -133.808925) (xy 355.191205 -133.855438) (xy 355.214877 -133.905935)
			(xy 355.230945 -133.959342) (xy 355.239065 -134.014518) (xy 355.239574 -134.042404) (xy 355.239065 -134.07029)
			(xy 355.230945 -134.125466) (xy 355.214877 -134.178873) (xy 355.191205 -134.22937) (xy 355.160432 -134.275883)
			(xy 355.123215 -134.31742) (xy 355.080347 -134.353095) (xy 355.032741 -134.382149) (xy 354.981412 -134.403961)
			(xy 354.927455 -134.418067) (xy 354.872018 -134.424167) (xy 354.816284 -134.42213) (xy 354.761441 -134.412)
			(xy 354.708657 -134.393993) (xy 354.659057 -134.368492) (xy 354.613699 -134.336041) (xy 354.57355 -134.297332)
			(xy 354.539464 -134.253189) (xy 354.512168 -134.204554) (xy 354.492245 -134.152463) (xy 354.480119 -134.098026)
			(xy 354.476048 -134.042404) (xy 335.949036 -134.042404) (xy 335.515966 -134.475474) (xy 335.498698 -134.492154)
			(xy 335.459883 -134.520407) (xy 335.417127 -134.542241) (xy 335.371481 -134.557117) (xy 335.32407 -134.564669)
			(xy 335.300066 -134.565136) (xy 331.522324 -134.565136) (xy 331.512255 -134.565565) (xy 331.493657 -134.573282)
			(xy 331.486256 -134.580122) (xy 330.9243 -135.142051) (xy 357.66197 -135.142051) (xy 357.66197 -135.087549)
			(xy 357.669726 -135.033603) (xy 357.68508 -134.981309) (xy 357.707719 -134.931733) (xy 357.737184 -134.885883)
			(xy 357.772873 -134.844693) (xy 357.814061 -134.809) (xy 357.859908 -134.779533) (xy 357.909483 -134.756889)
			(xy 357.961776 -134.741532) (xy 358.015721 -134.733772) (xy 358.042972 -134.733284) (xy 358.07189 -134.73379)
			(xy 358.129063 -134.742517) (xy 358.184263 -134.759776) (xy 358.236226 -134.785169) (xy 358.283759 -134.818117)
			(xy 358.325774 -134.857862) (xy 358.343962 -134.88035) (xy 358.351755 -134.889337) (xy 358.37322 -134.899526)
			(xy 358.38511 -134.899908) (xy 358.478582 -134.897876) (xy 358.499918 -134.8867) (xy 358.506776 -134.876794)
			(xy 358.522175 -134.855885) (xy 358.557753 -134.818058) (xy 358.598132 -134.785406) (xy 358.642566 -134.758531)
			(xy 358.690235 -134.737931) (xy 358.740256 -134.723985) (xy 358.791707 -134.716952) (xy 358.817672 -134.71652)
			(xy 358.845042 -134.716998) (xy 358.899221 -134.724812) (xy 358.951724 -134.740298) (xy 359.001471 -134.763137)
			(xy 359.047438 -134.79286) (xy 359.06837 -134.8105) (xy 359.068624 -134.810754) (xy 359.075695 -134.816363)
			(xy 359.092624 -134.822595) (xy 359.101644 -134.822946) (xy 359.1687 -134.822946) (xy 359.177718 -134.822601)
			(xy 359.194636 -134.816346) (xy 359.20172 -134.810754) (xy 359.20172 -134.8105) (xy 359.201974 -134.8105)
			(xy 359.222907 -134.792859) (xy 359.268875 -134.763135) (xy 359.318621 -134.740289) (xy 359.371123 -134.724793)
			(xy 359.425301 -134.716964) (xy 359.480043 -134.716964) (xy 359.534221 -134.724793) (xy 359.586723 -134.740289)
			(xy 359.636469 -134.763135) (xy 359.682437 -134.792859) (xy 359.70337 -134.8105) (xy 359.703624 -134.810754)
			(xy 359.710695 -134.816363) (xy 359.727624 -134.822595) (xy 359.736644 -134.822946) (xy 359.8037 -134.822946)
			(xy 359.812718 -134.822601) (xy 359.829636 -134.816346) (xy 359.83672 -134.810754) (xy 359.837228 -134.8105)
			(xy 359.849966 -134.79956) (xy 359.877055 -134.779716) (xy 359.89133 -134.770876) (xy 359.90022 -134.765542)
			(xy 359.912412 -134.748524) (xy 359.932732 -134.655306) (xy 359.928414 -134.634732) (xy 359.922572 -134.626096)
			(xy 359.906565 -134.602037) (xy 359.881225 -134.550103) (xy 359.864001 -134.494944) (xy 359.855288 -134.437819)
			(xy 359.854754 -134.408926) (xy 359.85524 -134.381675) (xy 359.862996 -134.327727) (xy 359.878351 -134.275432)
			(xy 359.900993 -134.225855) (xy 359.930459 -134.180005) (xy 359.96615 -134.138814) (xy 360.007341 -134.103123)
			(xy 360.053191 -134.073657) (xy 360.102768 -134.051015) (xy 360.155063 -134.03566) (xy 360.209011 -134.027904)
			(xy 360.263513 -134.027904) (xy 360.317461 -134.03566) (xy 360.369756 -134.051015) (xy 360.419333 -134.073657)
			(xy 360.465183 -134.103123) (xy 360.506374 -134.138814) (xy 360.542065 -134.180005) (xy 360.571531 -134.225855)
			(xy 360.594173 -134.275432) (xy 360.609528 -134.327727) (xy 360.617284 -134.381675) (xy 360.61777 -134.408926)
			(xy 360.617319 -134.437019) (xy 360.609086 -134.492599) (xy 360.592789 -134.546371) (xy 360.56878 -134.597169)
			(xy 360.537578 -134.643895) (xy 360.499859 -134.685539) (xy 360.456438 -134.721198) (xy 360.432604 -134.736078)
			(xy 360.423714 -134.741412) (xy 360.411522 -134.75843) (xy 360.391202 -134.851648) (xy 360.39552 -134.872222)
			(xy 360.401362 -134.880858) (xy 360.417342 -134.904935) (xy 360.44269 -134.956861) (xy 360.459922 -135.012015)
			(xy 360.468643 -135.069137) (xy 360.46918 -135.098028) (xy 360.468748 -135.125281) (xy 360.460987 -135.179232)
			(xy 360.445627 -135.23153) (xy 360.422981 -135.281109) (xy 360.393509 -135.326961) (xy 360.357812 -135.368151)
			(xy 360.316616 -135.403842) (xy 360.27076 -135.433307) (xy 360.221177 -135.455947) (xy 360.168878 -135.471299)
			(xy 360.114925 -135.479052) (xy 360.087672 -135.479536) (xy 360.0603 -135.479102) (xy 360.006119 -135.471279)
			(xy 359.953615 -135.455783) (xy 359.903869 -135.432934) (xy 359.857904 -135.403201) (xy 359.836974 -135.385556)
			(xy 359.83672 -135.385302) (xy 359.829632 -135.379718) (xy 359.812716 -135.37347) (xy 359.8037 -135.37311)
			(xy 359.736644 -135.37311) (xy 359.727629 -135.373486) (xy 359.710712 -135.37972) (xy 359.703624 -135.385302)
			(xy 359.703624 -135.385556) (xy 359.70337 -135.385556) (xy 359.682437 -135.403197) (xy 359.636469 -135.432921)
			(xy 359.586723 -135.455767) (xy 359.534221 -135.471263) (xy 359.480043 -135.479092) (xy 359.425301 -135.479092)
			(xy 359.371123 -135.471263) (xy 359.318621 -135.455767) (xy 359.268875 -135.432921) (xy 359.222907 -135.403197)
			(xy 359.201974 -135.385556) (xy 359.20172 -135.385302) (xy 359.194632 -135.379718) (xy 359.177716 -135.37347)
			(xy 359.1687 -135.37311) (xy 359.101644 -135.37311) (xy 359.092629 -135.373486) (xy 359.075712 -135.37972)
			(xy 359.068624 -135.385302) (xy 359.068624 -135.385556) (xy 359.06837 -135.385556) (xy 359.047417 -135.403169)
			(xy 359.00145 -135.432886) (xy 358.951708 -135.455728) (xy 358.899212 -135.471225) (xy 358.84504 -135.479059)
			(xy 358.817672 -135.479536) (xy 358.788756 -135.47899) (xy 358.731585 -135.47027) (xy 358.676386 -135.453019)
			(xy 358.624423 -135.427633) (xy 358.576889 -135.394693) (xy 358.534872 -135.354954) (xy 358.516682 -135.33247)
			(xy 358.508866 -135.323507) (xy 358.487419 -135.313305) (xy 358.475534 -135.312912) (xy 358.382062 -135.314944)
			(xy 358.360726 -135.32612) (xy 358.353868 -135.336026) (xy 358.338447 -135.356919) (xy 358.302873 -135.394745)
			(xy 358.262497 -135.427398) (xy 358.218066 -135.454275) (xy 358.170402 -135.474878) (xy 358.120383 -135.488827)
			(xy 358.068936 -135.495865) (xy 358.042972 -135.4963) (xy 358.015721 -135.495828) (xy 357.961776 -135.488068)
			(xy 357.909483 -135.472711) (xy 357.859908 -135.450067) (xy 357.814061 -135.4206) (xy 357.772873 -135.384907)
			(xy 357.737184 -135.343717) (xy 357.707719 -135.297867) (xy 357.68508 -135.248291) (xy 357.669726 -135.195997)
			(xy 357.66197 -135.142051) (xy 330.9243 -135.142051) (xy 330.376731 -135.689594) (xy 355.583234 -135.689594)
			(xy 355.587305 -135.633972) (xy 355.599431 -135.579535) (xy 355.619354 -135.527444) (xy 355.64665 -135.478809)
			(xy 355.680736 -135.434666) (xy 355.720885 -135.395957) (xy 355.766243 -135.363506) (xy 355.815843 -135.338005)
			(xy 355.868627 -135.319998) (xy 355.92347 -135.309868) (xy 355.979204 -135.307831) (xy 356.034641 -135.313931)
			(xy 356.088598 -135.328037) (xy 356.139927 -135.349849) (xy 356.187533 -135.378903) (xy 356.230401 -135.414578)
			(xy 356.267618 -135.456115) (xy 356.298391 -135.502628) (xy 356.322063 -135.553125) (xy 356.338131 -135.606532)
			(xy 356.346251 -135.661708) (xy 356.34676 -135.689594) (xy 356.346251 -135.71748) (xy 356.338131 -135.772656)
			(xy 356.322063 -135.826063) (xy 356.302926 -135.866886) (xy 356.73995 -135.866886) (xy 356.744021 -135.811264)
			(xy 356.756147 -135.756827) (xy 356.77607 -135.704736) (xy 356.803366 -135.656101) (xy 356.837452 -135.611958)
			(xy 356.877601 -135.573249) (xy 356.922959 -135.540798) (xy 356.972559 -135.515297) (xy 357.025343 -135.49729)
			(xy 357.080186 -135.48716) (xy 357.13592 -135.485123) (xy 357.191357 -135.491223) (xy 357.245314 -135.505329)
			(xy 357.296643 -135.527141) (xy 357.344249 -135.556195) (xy 357.387117 -135.59187) (xy 357.424334 -135.633407)
			(xy 357.455107 -135.67992) (xy 357.478779 -135.730417) (xy 357.494847 -135.783824) (xy 357.502967 -135.839)
			(xy 357.503476 -135.866886) (xy 357.502967 -135.894772) (xy 357.494847 -135.949948) (xy 357.478779 -136.003355)
			(xy 357.455107 -136.053852) (xy 357.424334 -136.100365) (xy 357.387117 -136.141902) (xy 357.344249 -136.177577)
			(xy 357.296643 -136.206631) (xy 357.245314 -136.228443) (xy 357.191357 -136.242549) (xy 357.13592 -136.248649)
			(xy 357.080186 -136.246612) (xy 357.025343 -136.236482) (xy 356.972559 -136.218475) (xy 356.922959 -136.192974)
			(xy 356.877601 -136.160523) (xy 356.837452 -136.121814) (xy 356.803366 -136.077671) (xy 356.77607 -136.029036)
			(xy 356.756147 -135.976945) (xy 356.744021 -135.922508) (xy 356.73995 -135.866886) (xy 356.302926 -135.866886)
			(xy 356.298391 -135.87656) (xy 356.267618 -135.923073) (xy 356.230401 -135.96461) (xy 356.187533 -136.000285)
			(xy 356.139927 -136.029339) (xy 356.088598 -136.051151) (xy 356.034641 -136.065257) (xy 355.979204 -136.071357)
			(xy 355.92347 -136.06932) (xy 355.868627 -136.05919) (xy 355.815843 -136.041183) (xy 355.766243 -136.015682)
			(xy 355.720885 -135.983231) (xy 355.680736 -135.944522) (xy 355.64665 -135.900379) (xy 355.619354 -135.851744)
			(xy 355.599431 -135.799653) (xy 355.587305 -135.745216) (xy 355.583234 -135.689594) (xy 330.376731 -135.689594)
			(xy 328.617952 -137.44829) (xy 356.645208 -137.44829) (xy 356.649279 -137.392668) (xy 356.661405 -137.338231)
			(xy 356.681328 -137.28614) (xy 356.708624 -137.237505) (xy 356.74271 -137.193362) (xy 356.782859 -137.154653)
			(xy 356.828217 -137.122202) (xy 356.877817 -137.096701) (xy 356.930601 -137.078694) (xy 356.985444 -137.068564)
			(xy 357.041178 -137.066527) (xy 357.096615 -137.072627) (xy 357.150572 -137.086733) (xy 357.201901 -137.108545)
			(xy 357.249507 -137.137599) (xy 357.292375 -137.173274) (xy 357.329592 -137.214811) (xy 357.360365 -137.261324)
			(xy 357.3674 -137.276332) (xy 361.347258 -137.276332) (xy 361.347662 -137.250016) (xy 361.354907 -137.197884)
			(xy 361.369237 -137.147239) (xy 361.390382 -137.09904) (xy 361.41794 -137.054198) (xy 361.451391 -137.013562)
			(xy 361.470448 -136.995408) (xy 361.47784 -136.987878) (xy 361.486372 -136.968605) (xy 361.486958 -136.95807)
			(xy 361.486958 -136.883394) (xy 361.486458 -136.872841) (xy 361.477904 -136.853545) (xy 361.470448 -136.846056)
			(xy 361.451368 -136.827925) (xy 361.417915 -136.787289) (xy 361.390361 -136.742443) (xy 361.369227 -136.694238)
			(xy 361.354914 -136.643586) (xy 361.347694 -136.591449) (xy 361.347258 -136.565132) (xy 361.347744 -136.537881)
			(xy 361.3555 -136.483933) (xy 361.370855 -136.431638) (xy 361.393497 -136.382061) (xy 361.422963 -136.336211)
			(xy 361.458654 -136.29502) (xy 361.499845 -136.259329) (xy 361.545695 -136.229863) (xy 361.595272 -136.207221)
			(xy 361.647567 -136.191866) (xy 361.701515 -136.18411) (xy 361.756017 -136.18411) (xy 361.809965 -136.191866)
			(xy 361.86226 -136.207221) (xy 361.911837 -136.229863) (xy 361.957687 -136.259329) (xy 361.998878 -136.29502)
			(xy 362.034569 -136.336211) (xy 362.064035 -136.382061) (xy 362.086677 -136.431638) (xy 362.102032 -136.483933)
			(xy 362.109788 -136.537881) (xy 362.110274 -136.565132) (xy 362.109836 -136.591447) (xy 362.102596 -136.643577)
			(xy 362.088272 -136.694221) (xy 362.067134 -136.74242) (xy 362.039582 -136.787263) (xy 362.006138 -136.827901)
			(xy 361.987084 -136.846056) (xy 361.979697 -136.85359) (xy 361.971165 -136.872861) (xy 361.970574 -136.883394)
			(xy 361.970574 -136.95807) (xy 361.971114 -136.968618) (xy 361.979642 -136.987913) (xy 361.987084 -136.995408)
			(xy 362.006133 -137.01357) (xy 362.039592 -137.054198) (xy 362.067152 -137.099037) (xy 362.088292 -137.147236)
			(xy 362.10261 -137.197883) (xy 362.109835 -137.250016) (xy 362.110274 -137.276332) (xy 362.109788 -137.303583)
			(xy 362.102032 -137.357531) (xy 362.086677 -137.409826) (xy 362.064035 -137.459403) (xy 362.034569 -137.505253)
			(xy 361.998878 -137.546444) (xy 361.957687 -137.582135) (xy 361.911837 -137.611601) (xy 361.86226 -137.634243)
			(xy 361.809965 -137.649598) (xy 361.756017 -137.657354) (xy 361.701515 -137.657354) (xy 361.647567 -137.649598)
			(xy 361.595272 -137.634243) (xy 361.545695 -137.611601) (xy 361.499845 -137.582135) (xy 361.458654 -137.546444)
			(xy 361.422963 -137.505253) (xy 361.393497 -137.459403) (xy 361.370855 -137.409826) (xy 361.3555 -137.357531)
			(xy 361.347744 -137.303583) (xy 361.347258 -137.276332) (xy 357.3674 -137.276332) (xy 357.384037 -137.311821)
			(xy 357.400105 -137.365228) (xy 357.408225 -137.420404) (xy 357.408734 -137.44829) (xy 357.408225 -137.476176)
			(xy 357.400105 -137.531352) (xy 357.384037 -137.584759) (xy 357.360365 -137.635256) (xy 357.329592 -137.681769)
			(xy 357.292375 -137.723306) (xy 357.288328 -137.726674) (xy 362.28782 -137.726674) (xy 362.288266 -137.699303)
			(xy 362.296088 -137.645123) (xy 362.311581 -137.592619) (xy 362.334428 -137.542873) (xy 362.364157 -137.496907)
			(xy 362.3818 -137.475976) (xy 362.382054 -137.475722) (xy 362.387644 -137.468638) (xy 362.393887 -137.451719)
			(xy 362.394246 -137.442702) (xy 362.394246 -137.375646) (xy 362.393879 -137.36663) (xy 362.38764 -137.349712)
			(xy 362.382054 -137.342626) (xy 362.3818 -137.342626) (xy 362.3818 -137.342372) (xy 362.364181 -137.321424)
			(xy 362.334466 -137.275455) (xy 362.311626 -137.225712) (xy 362.296131 -137.173215) (xy 362.288297 -137.119042)
			(xy 362.28782 -137.091674) (xy 362.288306 -137.064423) (xy 362.296062 -137.010475) (xy 362.311417 -136.95818)
			(xy 362.334059 -136.908603) (xy 362.363525 -136.862753) (xy 362.399216 -136.821562) (xy 362.440407 -136.785871)
			(xy 362.486257 -136.756405) (xy 362.535834 -136.733763) (xy 362.588129 -136.718408) (xy 362.642077 -136.710652)
			(xy 362.696579 -136.710652) (xy 362.750527 -136.718408) (xy 362.802822 -136.733763) (xy 362.852399 -136.756405)
			(xy 362.898249 -136.785871) (xy 362.93944 -136.821562) (xy 362.975131 -136.862753) (xy 363.004597 -136.908603)
			(xy 363.027239 -136.95818) (xy 363.042594 -137.010475) (xy 363.05035 -137.064423) (xy 363.050836 -137.091674)
			(xy 363.05037 -137.119044) (xy 363.042555 -137.173224) (xy 363.027066 -137.225728) (xy 363.004224 -137.275475)
			(xy 362.974498 -137.321441) (xy 362.956856 -137.342372) (xy 362.956602 -137.342626) (xy 362.95104 -137.34973)
			(xy 362.944779 -137.366633) (xy 362.94441 -137.375646) (xy 362.94441 -137.442702) (xy 362.944764 -137.451719)
			(xy 362.951013 -137.468636) (xy 362.956602 -137.475722) (xy 362.956856 -137.475722) (xy 362.956856 -137.475976)
			(xy 362.97449 -137.496912) (xy 363.004205 -137.542883) (xy 363.027042 -137.592629) (xy 363.042534 -137.64513)
			(xy 363.050362 -137.699305) (xy 363.050836 -137.726674) (xy 363.05035 -137.753925) (xy 363.042594 -137.807873)
			(xy 363.027239 -137.860168) (xy 363.004597 -137.909745) (xy 362.975131 -137.955595) (xy 362.93944 -137.996786)
			(xy 362.898249 -138.032477) (xy 362.852399 -138.061943) (xy 362.802822 -138.084585) (xy 362.750527 -138.09994)
			(xy 362.696579 -138.107696) (xy 362.642077 -138.107696) (xy 362.588129 -138.09994) (xy 362.535834 -138.084585)
			(xy 362.486257 -138.061943) (xy 362.440407 -138.032477) (xy 362.399216 -137.996786) (xy 362.363525 -137.955595)
			(xy 362.334059 -137.909745) (xy 362.311417 -137.860168) (xy 362.296062 -137.807873) (xy 362.288306 -137.753925)
			(xy 362.28782 -137.726674) (xy 357.288328 -137.726674) (xy 357.249507 -137.758981) (xy 357.201901 -137.788035)
			(xy 357.150572 -137.809847) (xy 357.096615 -137.823953) (xy 357.041178 -137.830053) (xy 356.985444 -137.828016)
			(xy 356.930601 -137.817886) (xy 356.877817 -137.799879) (xy 356.828217 -137.774378) (xy 356.782859 -137.741927)
			(xy 356.74271 -137.703218) (xy 356.708624 -137.659075) (xy 356.681328 -137.61044) (xy 356.661405 -137.558349)
			(xy 356.649279 -137.503912) (xy 356.645208 -137.44829) (xy 328.617952 -137.44829) (xy 327.705795 -138.360404)
			(xy 354.476048 -138.360404) (xy 354.480119 -138.304782) (xy 354.492245 -138.250345) (xy 354.512168 -138.198254)
			(xy 354.539464 -138.149619) (xy 354.57355 -138.105476) (xy 354.613699 -138.066767) (xy 354.659057 -138.034316)
			(xy 354.708657 -138.008815) (xy 354.761441 -137.990808) (xy 354.816284 -137.980678) (xy 354.872018 -137.978641)
			(xy 354.927455 -137.984741) (xy 354.981412 -137.998847) (xy 355.032741 -138.020659) (xy 355.080347 -138.049713)
			(xy 355.123215 -138.085388) (xy 355.160432 -138.126925) (xy 355.191205 -138.173438) (xy 355.214877 -138.223935)
			(xy 355.230945 -138.277342) (xy 355.239065 -138.332518) (xy 355.239574 -138.360404) (xy 355.239065 -138.38829)
			(xy 355.236852 -138.40333) (xy 363.496352 -138.40333) (xy 363.496863 -138.375665) (xy 363.50486 -138.320914)
			(xy 363.520675 -138.267892) (xy 363.543977 -138.217707) (xy 363.574279 -138.171411) (xy 363.610946 -138.129973)
			(xy 363.65321 -138.094262) (xy 363.676438 -138.079226) (xy 363.686103 -138.072575) (xy 363.698554 -138.052724)
			(xy 363.700314 -138.041126) (xy 363.708188 -137.961116) (xy 363.708791 -137.949479) (xy 363.700729 -137.927644)
			(xy 363.692694 -137.919206) (xy 363.69244 -137.918952) (xy 363.673861 -137.900869) (xy 363.641281 -137.860538)
			(xy 363.614466 -137.816165) (xy 363.593913 -137.768567) (xy 363.58 -137.718622) (xy 363.572983 -137.667253)
			(xy 363.572552 -137.64133) (xy 363.573106 -137.614081) (xy 363.580857 -137.560138) (xy 363.596207 -137.507847)
			(xy 363.618841 -137.458273) (xy 363.648301 -137.412424) (xy 363.683985 -137.371235) (xy 363.725168 -137.335543)
			(xy 363.771011 -137.306075) (xy 363.820582 -137.283431) (xy 363.87287 -137.268072) (xy 363.926811 -137.260311)
			(xy 363.95406 -137.259822) (xy 363.98143 -137.260306) (xy 364.035608 -137.268119) (xy 364.088111 -137.283603)
			(xy 364.137858 -137.306441) (xy 364.183826 -137.336162) (xy 364.204758 -137.353802) (xy 364.205012 -137.354056)
			(xy 364.212086 -137.35966) (xy 364.229013 -137.365895) (xy 364.238032 -137.366248) (xy 364.305088 -137.366248)
			(xy 364.314106 -137.365896) (xy 364.331023 -137.359646) (xy 364.338108 -137.354056) (xy 364.338108 -137.353802)
			(xy 364.338362 -137.353802) (xy 364.359298 -137.336168) (xy 364.40527 -137.306455) (xy 364.455016 -137.283618)
			(xy 364.507516 -137.268126) (xy 364.561691 -137.260297) (xy 364.58906 -137.259822) (xy 364.616313 -137.260293)
			(xy 364.670265 -137.268045) (xy 364.722565 -137.283397) (xy 364.772147 -137.306037) (xy 364.818002 -137.335504)
			(xy 364.859196 -137.371197) (xy 364.89489 -137.41239) (xy 364.924358 -137.458244) (xy 364.946999 -137.507826)
			(xy 364.962353 -137.560125) (xy 364.970107 -137.614077) (xy 364.970568 -137.64133) (xy 364.970012 -137.670246)
			(xy 364.961292 -137.727416) (xy 364.944043 -137.782614) (xy 364.918658 -137.834576) (xy 364.885721 -137.882111)
			(xy 364.845985 -137.924129) (xy 364.823502 -137.94232) (xy 364.814696 -137.949929) (xy 364.804512 -137.970828)
			(xy 364.803944 -137.982452) (xy 364.803944 -138.062208) (xy 364.804478 -138.073841) (xy 364.814669 -138.094751)
			(xy 364.823502 -138.10234) (xy 364.846005 -138.120508) (xy 364.885739 -138.162533) (xy 364.918676 -138.210072)
			(xy 364.944061 -138.262038) (xy 364.961312 -138.31724) (xy 364.970036 -138.374413) (xy 364.970568 -138.40333)
			(xy 364.970173 -138.430585) (xy 364.962411 -138.484541) (xy 364.950305 -138.525758) (xy 365.24184 -138.525758)
			(xy 365.24233 -138.498389) (xy 365.250141 -138.44421) (xy 365.265624 -138.391707) (xy 365.28846 -138.34196)
			(xy 365.318181 -138.295992) (xy 365.33582 -138.27506) (xy 365.336074 -138.274806) (xy 365.341673 -138.267728)
			(xy 365.34791 -138.250804) (xy 365.348266 -138.241786) (xy 365.348266 -138.17473) (xy 365.347902 -138.165714)
			(xy 365.34166 -138.148796) (xy 365.336074 -138.14171) (xy 365.33582 -138.14171) (xy 365.33582 -138.141456)
			(xy 365.318138 -138.120556) (xy 365.288416 -138.074583) (xy 365.265573 -138.024831) (xy 365.250081 -137.972324)
			(xy 365.242256 -137.918141) (xy 365.242261 -137.863396) (xy 365.250094 -137.809214) (xy 365.265596 -137.75671)
			(xy 365.288446 -137.706962) (xy 365.318177 -137.660993) (xy 365.33582 -137.64006) (xy 365.336074 -137.639806)
			(xy 365.341673 -137.632728) (xy 365.34791 -137.615804) (xy 365.348266 -137.606786) (xy 365.348266 -137.53973)
			(xy 365.347902 -137.530714) (xy 365.34166 -137.513796) (xy 365.336074 -137.50671) (xy 365.33582 -137.50671)
			(xy 365.33582 -137.506456) (xy 365.318138 -137.485556) (xy 365.288416 -137.439583) (xy 365.265573 -137.389831)
			(xy 365.250081 -137.337324) (xy 365.242256 -137.283141) (xy 365.242261 -137.228396) (xy 365.250094 -137.174214)
			(xy 365.265596 -137.12171) (xy 365.288446 -137.071962) (xy 365.318177 -137.025993) (xy 365.33582 -137.00506)
			(xy 365.336074 -137.004806) (xy 365.341673 -136.997728) (xy 365.34791 -136.980804) (xy 365.348266 -136.971786)
			(xy 365.348266 -136.90473) (xy 365.347902 -136.895714) (xy 365.34166 -136.878796) (xy 365.336074 -136.87171)
			(xy 365.33582 -136.87171) (xy 365.33582 -136.871456) (xy 365.318197 -136.850511) (xy 365.288482 -136.804542)
			(xy 365.265643 -136.754798) (xy 365.250148 -136.7023) (xy 365.242316 -136.648126) (xy 365.24184 -136.620758)
			(xy 365.242326 -136.593507) (xy 365.250082 -136.539559) (xy 365.265437 -136.487264) (xy 365.288079 -136.437687)
			(xy 365.317545 -136.391837) (xy 365.353236 -136.350646) (xy 365.394427 -136.314955) (xy 365.440277 -136.285489)
			(xy 365.489854 -136.262847) (xy 365.542149 -136.247492) (xy 365.596097 -136.239736) (xy 365.650599 -136.239736)
			(xy 365.704547 -136.247492) (xy 365.756842 -136.262847) (xy 365.806419 -136.285489) (xy 365.852269 -136.314955)
			(xy 365.89346 -136.350646) (xy 365.929151 -136.391837) (xy 365.958617 -136.437687) (xy 365.981259 -136.487264)
			(xy 365.996614 -136.539559) (xy 366.00437 -136.593507) (xy 366.004856 -136.620758) (xy 366.004376 -136.648128)
			(xy 365.996563 -136.702307) (xy 365.981078 -136.75481) (xy 365.958239 -136.804557) (xy 365.928517 -136.850524)
			(xy 365.910876 -136.871456) (xy 365.910622 -136.87171) (xy 365.905016 -136.878783) (xy 365.898783 -136.89571)
			(xy 365.89843 -136.90473) (xy 365.89843 -136.971786) (xy 365.898787 -136.980803) (xy 365.905034 -136.99772)
			(xy 365.910622 -137.004806) (xy 365.910876 -137.004806) (xy 365.910876 -137.00506) (xy 365.928475 -137.026026)
			(xy 365.958202 -137.071988) (xy 365.981049 -137.121729) (xy 365.996549 -137.174226) (xy 366.004381 -137.2284)
			(xy 366.004386 -137.283137) (xy 365.996562 -137.337312) (xy 365.981072 -137.389812) (xy 365.958232 -137.439556)
			(xy 365.928514 -137.485523) (xy 365.910876 -137.506456) (xy 365.910622 -137.50671) (xy 365.905016 -137.513783)
			(xy 365.898783 -137.53071) (xy 365.89843 -137.53973) (xy 365.89843 -137.606786) (xy 365.898787 -137.615803)
			(xy 365.905034 -137.63272) (xy 365.910622 -137.639806) (xy 365.910876 -137.639806) (xy 365.910876 -137.64006)
			(xy 365.928475 -137.661026) (xy 365.958202 -137.706988) (xy 365.981049 -137.756729) (xy 365.996549 -137.809226)
			(xy 366.004381 -137.8634) (xy 366.004386 -137.918137) (xy 365.996562 -137.972312) (xy 365.981072 -138.024812)
			(xy 365.958232 -138.074556) (xy 365.928514 -138.120523) (xy 365.910876 -138.141456) (xy 365.910622 -138.14171)
			(xy 365.905016 -138.148783) (xy 365.898783 -138.16571) (xy 365.89843 -138.17473) (xy 365.89843 -138.241786)
			(xy 365.898787 -138.250803) (xy 365.905034 -138.26772) (xy 365.910622 -138.274806) (xy 365.910876 -138.274806)
			(xy 365.910876 -138.27506) (xy 365.928506 -138.295999) (xy 365.95822 -138.34197) (xy 365.981058 -138.391715)
			(xy 365.996551 -138.444215) (xy 366.004381 -138.498389) (xy 366.004856 -138.525758) (xy 366.004277 -138.554944)
			(xy 365.995383 -138.612636) (xy 365.977812 -138.668301) (xy 365.951974 -138.720644) (xy 365.918469 -138.768444)
			(xy 365.87808 -138.810588) (xy 365.85525 -138.82878) (xy 365.846159 -138.836456) (xy 365.835688 -138.857787)
			(xy 365.835184 -138.869674) (xy 365.835946 -138.950954) (xy 365.836649 -138.962668) (xy 365.847243 -138.983581)
			(xy 365.856266 -138.991086) (xy 365.856774 -138.991594) (xy 365.88065 -139.010644) (xy 365.880904 -139.010898)
			(xy 365.887985 -139.016492) (xy 365.904906 -139.022734) (xy 365.913924 -139.02309) (xy 365.98098 -139.02309)
			(xy 365.989996 -139.022726) (xy 366.006913 -139.016484) (xy 366.014 -139.010898) (xy 366.014 -139.010644)
			(xy 366.014254 -139.010644) (xy 366.035187 -138.993003) (xy 366.081155 -138.963279) (xy 366.130901 -138.940433)
			(xy 366.183403 -138.924937) (xy 366.237581 -138.917108) (xy 366.292323 -138.917108) (xy 366.346501 -138.924937)
			(xy 366.399003 -138.940433) (xy 366.448749 -138.963279) (xy 366.494717 -138.993003) (xy 366.51565 -139.010644)
			(xy 366.515904 -139.010898) (xy 366.522985 -139.016492) (xy 366.539906 -139.022734) (xy 366.548924 -139.02309)
			(xy 366.61598 -139.02309) (xy 366.624996 -139.022726) (xy 366.641913 -139.016484) (xy 366.649 -139.010898)
			(xy 366.649 -139.010644) (xy 366.649254 -139.010644) (xy 366.670187 -138.993003) (xy 366.716155 -138.963279)
			(xy 366.765901 -138.940433) (xy 366.818403 -138.924937) (xy 366.872581 -138.917108) (xy 366.927323 -138.917108)
			(xy 366.981501 -138.924937) (xy 367.034003 -138.940433) (xy 367.083749 -138.963279) (xy 367.129717 -138.993003)
			(xy 367.15065 -139.010644) (xy 367.150904 -139.010898) (xy 367.157985 -139.016492) (xy 367.174906 -139.022734)
			(xy 367.183924 -139.02309) (xy 367.25098 -139.02309) (xy 367.259996 -139.022726) (xy 367.276913 -139.016484)
			(xy 367.284 -139.010898) (xy 367.284 -139.010644) (xy 367.284254 -139.010644) (xy 367.305198 -138.99302)
			(xy 367.351167 -138.963304) (xy 367.400911 -138.940465) (xy 367.45341 -138.92497) (xy 367.507584 -138.917139)
			(xy 367.534952 -138.916664) (xy 367.562205 -138.91718) (xy 367.616157 -138.924931) (xy 367.668457 -138.940282)
			(xy 367.71804 -138.96292) (xy 367.763895 -138.992384) (xy 367.805091 -139.028075) (xy 367.840787 -139.069266)
			(xy 367.870257 -139.115118) (xy 367.892902 -139.164698) (xy 367.908259 -139.216996) (xy 367.916017 -139.270947)
			(xy 367.916017 -139.325453) (xy 367.908259 -139.379404) (xy 367.892902 -139.431702) (xy 367.870257 -139.481282)
			(xy 367.840787 -139.527134) (xy 367.805091 -139.568325) (xy 367.763895 -139.604016) (xy 367.71804 -139.63348)
			(xy 367.668457 -139.656118) (xy 367.616157 -139.671469) (xy 367.562205 -139.67922) (xy 367.534952 -139.67968)
			(xy 367.507583 -139.679188) (xy 367.453404 -139.671377) (xy 367.400901 -139.655895) (xy 367.351154 -139.633058)
			(xy 367.305186 -139.603339) (xy 367.284254 -139.5857) (xy 367.284 -139.585446) (xy 367.276922 -139.579847)
			(xy 367.259999 -139.573609) (xy 367.25098 -139.573254) (xy 367.183924 -139.573254) (xy 367.174907 -139.573611)
			(xy 367.157989 -139.579857) (xy 367.150904 -139.585446) (xy 367.150904 -139.5857) (xy 367.15065 -139.5857)
			(xy 367.129717 -139.603341) (xy 367.083749 -139.633065) (xy 367.034003 -139.655911) (xy 366.981501 -139.671407)
			(xy 366.927323 -139.679236) (xy 366.872581 -139.679236) (xy 366.818403 -139.671407) (xy 366.765901 -139.655911)
			(xy 366.716155 -139.633065) (xy 366.670187 -139.603341) (xy 366.649254 -139.5857) (xy 366.649 -139.585446)
			(xy 366.641922 -139.579847) (xy 366.624999 -139.573609) (xy 366.61598 -139.573254) (xy 366.548924 -139.573254)
			(xy 366.539907 -139.573611) (xy 366.522989 -139.579857) (xy 366.515904 -139.585446) (xy 366.515904 -139.5857)
			(xy 366.51565 -139.5857) (xy 366.494717 -139.603341) (xy 366.448749 -139.633065) (xy 366.399003 -139.655911)
			(xy 366.346501 -139.671407) (xy 366.292323 -139.679236) (xy 366.237581 -139.679236) (xy 366.183403 -139.671407)
			(xy 366.130901 -139.655911) (xy 366.081155 -139.633065) (xy 366.035187 -139.603341) (xy 366.014254 -139.5857)
			(xy 366.014 -139.585446) (xy 366.006922 -139.579847) (xy 365.989999 -139.573609) (xy 365.98098 -139.573254)
			(xy 365.913924 -139.573254) (xy 365.904907 -139.573611) (xy 365.887989 -139.579857) (xy 365.880904 -139.585446)
			(xy 365.880904 -139.5857) (xy 365.88065 -139.5857) (xy 365.85971 -139.603329) (xy 365.813739 -139.633042)
			(xy 365.763994 -139.65588) (xy 365.711495 -139.671374) (xy 365.657321 -139.679205) (xy 365.629952 -139.67968)
			(xy 365.602698 -139.679267) (xy 365.548747 -139.671503) (xy 365.496449 -139.65614) (xy 365.446869 -139.633492)
			(xy 365.401018 -139.604018) (xy 365.359828 -139.568319) (xy 365.324137 -139.527121) (xy 365.294672 -139.481264)
			(xy 365.272033 -139.43168) (xy 365.256681 -139.379379) (xy 365.248928 -139.325426) (xy 365.248444 -139.298172)
			(xy 365.248973 -139.268984) (xy 365.257877 -139.21129) (xy 365.275458 -139.155623) (xy 365.301306 -139.103281)
			(xy 365.334819 -139.055482) (xy 365.375216 -139.013341) (xy 365.39805 -138.99515) (xy 365.407128 -138.98746)
			(xy 365.417605 -138.96614) (xy 365.418116 -138.954256) (xy 365.417354 -138.872976) (xy 365.416635 -138.861264)
			(xy 365.406052 -138.840351) (xy 365.397034 -138.832844) (xy 365.397034 -138.83259) (xy 365.396526 -138.83259)
			(xy 365.372936 -138.814499) (xy 365.331183 -138.772183) (xy 365.296507 -138.723897) (xy 365.269751 -138.670812)
			(xy 365.251562 -138.614216) (xy 365.242384 -138.555482) (xy 365.24184 -138.525758) (xy 364.950305 -138.525758)
			(xy 364.947049 -138.536843) (xy 364.9244 -138.586426) (xy 364.894925 -138.63228) (xy 364.859224 -138.673474)
			(xy 364.818024 -138.709167) (xy 364.772164 -138.738634) (xy 364.722577 -138.761273) (xy 364.670272 -138.776626)
			(xy 364.616316 -138.784378) (xy 364.58906 -138.784838) (xy 364.562744 -138.784417) (xy 364.510613 -138.777175)
			(xy 364.459969 -138.762849) (xy 364.411769 -138.741708) (xy 364.366927 -138.714152) (xy 364.32629 -138.680704)
			(xy 364.308136 -138.661648) (xy 364.300596 -138.654267) (xy 364.28133 -138.645729) (xy 364.270798 -138.645138)
			(xy 364.196122 -138.645138) (xy 364.18557 -138.645654) (xy 364.166274 -138.654197) (xy 364.158784 -138.661648)
			(xy 364.140639 -138.680713) (xy 364.100006 -138.714168) (xy 364.055163 -138.741724) (xy 364.00696 -138.762861)
			(xy 363.956312 -138.777176) (xy 363.904177 -138.7844) (xy 363.87786 -138.784838) (xy 363.850609 -138.784359)
			(xy 363.796663 -138.776598) (xy 363.74437 -138.76124) (xy 363.694794 -138.738596) (xy 363.648946 -138.709128)
			(xy 363.607757 -138.673436) (xy 363.572066 -138.632246) (xy 363.542599 -138.586397) (xy 363.519957 -138.536821)
			(xy 363.5046 -138.484527) (xy 363.49684 -138.430581) (xy 363.496352 -138.40333) (xy 355.236852 -138.40333)
			(xy 355.230945 -138.443466) (xy 355.214877 -138.496873) (xy 355.191205 -138.54737) (xy 355.160432 -138.593883)
			(xy 355.123215 -138.63542) (xy 355.080347 -138.671095) (xy 355.032741 -138.700149) (xy 354.981412 -138.721961)
			(xy 354.927455 -138.736067) (xy 354.872018 -138.742167) (xy 354.816284 -138.74013) (xy 354.761441 -138.73)
			(xy 354.708657 -138.711993) (xy 354.659057 -138.686492) (xy 354.613699 -138.654041) (xy 354.57355 -138.615332)
			(xy 354.539464 -138.571189) (xy 354.512168 -138.522554) (xy 354.492245 -138.470463) (xy 354.480119 -138.416026)
			(xy 354.476048 -138.360404) (xy 327.705795 -138.360404) (xy 327.241715 -138.824462) (xy 356.661972 -138.824462)
			(xy 356.666043 -138.76884) (xy 356.678169 -138.714403) (xy 356.698092 -138.662312) (xy 356.725388 -138.613677)
			(xy 356.759474 -138.569534) (xy 356.799623 -138.530825) (xy 356.844981 -138.498374) (xy 356.894581 -138.472873)
			(xy 356.947365 -138.454866) (xy 357.002208 -138.444736) (xy 357.057942 -138.442699) (xy 357.113379 -138.448799)
			(xy 357.167336 -138.462905) (xy 357.218665 -138.484717) (xy 357.266271 -138.513771) (xy 357.309139 -138.549446)
			(xy 357.346356 -138.590983) (xy 357.377129 -138.637496) (xy 357.400801 -138.687993) (xy 357.416869 -138.7414)
			(xy 357.424989 -138.796576) (xy 357.425498 -138.824462) (xy 357.424989 -138.852348) (xy 357.416869 -138.907524)
			(xy 357.400801 -138.960931) (xy 357.377129 -139.011428) (xy 357.346356 -139.057941) (xy 357.309139 -139.099478)
			(xy 357.266271 -139.135153) (xy 357.218665 -139.164207) (xy 357.167336 -139.186019) (xy 357.113379 -139.200125)
			(xy 357.057942 -139.206225) (xy 357.002208 -139.204188) (xy 356.947365 -139.194058) (xy 356.894581 -139.176051)
			(xy 356.844981 -139.15055) (xy 356.799623 -139.118099) (xy 356.759474 -139.07939) (xy 356.725388 -139.035247)
			(xy 356.698092 -138.986612) (xy 356.678169 -138.934521) (xy 356.666043 -138.880084) (xy 356.661972 -138.824462)
			(xy 327.241715 -138.824462) (xy 326.383663 -139.682474) (xy 337.716366 -139.682474) (xy 337.720437 -139.626852)
			(xy 337.732563 -139.572415) (xy 337.752486 -139.520324) (xy 337.779782 -139.471689) (xy 337.813868 -139.427546)
			(xy 337.854017 -139.388837) (xy 337.899375 -139.356386) (xy 337.948975 -139.330885) (xy 338.001759 -139.312878)
			(xy 338.056602 -139.302748) (xy 338.112336 -139.300711) (xy 338.167773 -139.306811) (xy 338.22173 -139.320917)
			(xy 338.273059 -139.342729) (xy 338.320665 -139.371783) (xy 338.326218 -139.376404) (xy 354.476048 -139.376404)
			(xy 354.480119 -139.320782) (xy 354.492245 -139.266345) (xy 354.512168 -139.214254) (xy 354.539464 -139.165619)
			(xy 354.57355 -139.121476) (xy 354.613699 -139.082767) (xy 354.659057 -139.050316) (xy 354.708657 -139.024815)
			(xy 354.761441 -139.006808) (xy 354.816284 -138.996678) (xy 354.872018 -138.994641) (xy 354.927455 -139.000741)
			(xy 354.981412 -139.014847) (xy 355.032741 -139.036659) (xy 355.080347 -139.065713) (xy 355.123215 -139.101388)
			(xy 355.160432 -139.142925) (xy 355.191205 -139.189438) (xy 355.214877 -139.239935) (xy 355.230945 -139.293342)
			(xy 355.239065 -139.348518) (xy 355.239574 -139.376404) (xy 355.239065 -139.40429) (xy 355.230945 -139.459466)
			(xy 355.214877 -139.512873) (xy 355.191205 -139.56337) (xy 355.160432 -139.609883) (xy 355.123215 -139.65142)
			(xy 355.080347 -139.687095) (xy 355.032741 -139.716149) (xy 354.981412 -139.737961) (xy 354.927455 -139.752067)
			(xy 354.872018 -139.758167) (xy 354.816284 -139.75613) (xy 354.761441 -139.746) (xy 354.708657 -139.727993)
			(xy 354.659057 -139.702492) (xy 354.613699 -139.670041) (xy 354.57355 -139.631332) (xy 354.539464 -139.587189)
			(xy 354.512168 -139.538554) (xy 354.492245 -139.486463) (xy 354.480119 -139.432026) (xy 354.476048 -139.376404)
			(xy 338.326218 -139.376404) (xy 338.363533 -139.407458) (xy 338.40075 -139.448995) (xy 338.431523 -139.495508)
			(xy 338.455195 -139.546005) (xy 338.471263 -139.599412) (xy 338.479383 -139.654588) (xy 338.479892 -139.682474)
			(xy 338.479383 -139.71036) (xy 338.471263 -139.765536) (xy 338.455195 -139.818943) (xy 338.431523 -139.86944)
			(xy 338.40075 -139.915953) (xy 338.363533 -139.95749) (xy 338.320665 -139.993165) (xy 338.273059 -140.022219)
			(xy 338.22173 -140.044031) (xy 338.167773 -140.058137) (xy 338.112336 -140.064237) (xy 338.056602 -140.0622)
			(xy 338.001759 -140.05207) (xy 337.948975 -140.034063) (xy 337.899375 -140.008562) (xy 337.854017 -139.976111)
			(xy 337.813868 -139.937402) (xy 337.779782 -139.893259) (xy 337.752486 -139.844624) (xy 337.732563 -139.792533)
			(xy 337.720437 -139.738096) (xy 337.716366 -139.682474) (xy 326.383663 -139.682474) (xy 326.104758 -139.961366)
			(xy 326.097993 -139.968818) (xy 326.090275 -139.987382) (xy 326.089772 -139.997434) (xy 326.089772 -140.392404)
			(xy 356.667814 -140.392404) (xy 356.671885 -140.336782) (xy 356.684011 -140.282345) (xy 356.703934 -140.230254)
			(xy 356.73123 -140.181619) (xy 356.765316 -140.137476) (xy 356.805465 -140.098767) (xy 356.850823 -140.066316)
			(xy 356.900423 -140.040815) (xy 356.953207 -140.022808) (xy 357.00805 -140.012678) (xy 357.063784 -140.010641)
			(xy 357.119221 -140.016741) (xy 357.173178 -140.030847) (xy 357.224507 -140.052659) (xy 357.272113 -140.081713)
			(xy 357.314981 -140.117388) (xy 357.352198 -140.158925) (xy 357.382971 -140.205438) (xy 357.406643 -140.255935)
			(xy 357.422711 -140.309342) (xy 357.430831 -140.364518) (xy 357.43134 -140.392404) (xy 357.430831 -140.42029)
			(xy 357.422711 -140.475466) (xy 357.406643 -140.528873) (xy 357.382971 -140.57937) (xy 357.352198 -140.625883)
			(xy 357.314981 -140.66742) (xy 357.272113 -140.703095) (xy 357.224507 -140.732149) (xy 357.173178 -140.753961)
			(xy 357.119221 -140.768067) (xy 357.063784 -140.774167) (xy 357.00805 -140.77213) (xy 356.953207 -140.762)
			(xy 356.900423 -140.743993) (xy 356.850823 -140.718492) (xy 356.805465 -140.686041) (xy 356.765316 -140.647332)
			(xy 356.73123 -140.603189) (xy 356.703934 -140.554554) (xy 356.684011 -140.502463) (xy 356.671885 -140.448026)
			(xy 356.667814 -140.392404) (xy 326.089772 -140.392404) (xy 326.089772 -140.814552) (xy 351.041206 -140.814552)
			(xy 351.045277 -140.75893) (xy 351.057403 -140.704493) (xy 351.077326 -140.652402) (xy 351.104622 -140.603767)
			(xy 351.138708 -140.559624) (xy 351.178857 -140.520915) (xy 351.224215 -140.488464) (xy 351.273815 -140.462963)
			(xy 351.326599 -140.444956) (xy 351.381442 -140.434826) (xy 351.437176 -140.432789) (xy 351.492613 -140.438889)
			(xy 351.54657 -140.452995) (xy 351.597899 -140.474807) (xy 351.645505 -140.503861) (xy 351.688373 -140.539536)
			(xy 351.72559 -140.581073) (xy 351.756363 -140.627586) (xy 351.780035 -140.678083) (xy 351.796103 -140.73149)
			(xy 351.804223 -140.786666) (xy 351.804732 -140.814552) (xy 351.804223 -140.842438) (xy 351.796103 -140.897614)
			(xy 351.780035 -140.951021) (xy 351.756363 -141.001518) (xy 351.72559 -141.048031) (xy 351.688373 -141.089568)
			(xy 351.645505 -141.125243) (xy 351.597899 -141.154297) (xy 351.54657 -141.176109) (xy 351.492613 -141.190215)
			(xy 351.437176 -141.196315) (xy 351.381442 -141.194278) (xy 351.326599 -141.184148) (xy 351.273815 -141.166141)
			(xy 351.224215 -141.14064) (xy 351.178857 -141.108189) (xy 351.138708 -141.06948) (xy 351.104622 -141.025337)
			(xy 351.077326 -140.976702) (xy 351.057403 -140.924611) (xy 351.045277 -140.870174) (xy 351.041206 -140.814552)
			(xy 326.089772 -140.814552) (xy 326.089772 -141.424152) (xy 336.674204 -141.424152) (xy 336.678275 -141.36853)
			(xy 336.690401 -141.314093) (xy 336.710324 -141.262002) (xy 336.73762 -141.213367) (xy 336.771706 -141.169224)
			(xy 336.811855 -141.130515) (xy 336.857213 -141.098064) (xy 336.906813 -141.072563) (xy 336.959597 -141.054556)
			(xy 337.01444 -141.044426) (xy 337.070174 -141.042389) (xy 337.125611 -141.048489) (xy 337.179568 -141.062595)
			(xy 337.230897 -141.084407) (xy 337.278503 -141.113461) (xy 337.321371 -141.149136) (xy 337.358588 -141.190673)
			(xy 337.389361 -141.237186) (xy 337.409018 -141.279118) (xy 354.101652 -141.279118) (xy 354.105723 -141.223496)
			(xy 354.117849 -141.169059) (xy 354.137772 -141.116968) (xy 354.165068 -141.068333) (xy 354.199154 -141.02419)
			(xy 354.239303 -140.985481) (xy 354.284661 -140.95303) (xy 354.334261 -140.927529) (xy 354.387045 -140.909522)
			(xy 354.441888 -140.899392) (xy 354.497622 -140.897355) (xy 354.553059 -140.903455) (xy 354.607016 -140.917561)
			(xy 354.658345 -140.939373) (xy 354.705951 -140.968427) (xy 354.748819 -141.004102) (xy 354.786036 -141.045639)
			(xy 354.786639 -141.046551) (xy 359.055154 -141.046551) (xy 359.055154 -140.992049) (xy 359.06291 -140.938101)
			(xy 359.078264 -140.885806) (xy 359.100904 -140.836228) (xy 359.130368 -140.790377) (xy 359.166058 -140.749185)
			(xy 359.207246 -140.713491) (xy 359.253095 -140.684022) (xy 359.30267 -140.661377) (xy 359.354964 -140.646018)
			(xy 359.408911 -140.638256) (xy 359.436162 -140.637768) (xy 359.462477 -140.638204) (xy 359.514606 -140.645447)
			(xy 359.565249 -140.659773) (xy 359.613448 -140.680911) (xy 359.658291 -140.708462) (xy 359.69893 -140.741905)
			(xy 359.717086 -140.760958) (xy 359.724617 -140.768349) (xy 359.74389 -140.776881) (xy 359.754424 -140.777468)
			(xy 359.8291 -140.777468) (xy 359.839653 -140.776962) (xy 359.858948 -140.768412) (xy 359.866438 -140.760958)
			(xy 359.884574 -140.741883) (xy 359.925209 -140.708429) (xy 359.970053 -140.680874) (xy 360.018258 -140.659739)
			(xy 360.068908 -140.645426) (xy 360.121045 -140.638205) (xy 360.147362 -140.637768) (xy 360.174615 -140.638277)
			(xy 360.228567 -140.646029) (xy 360.280866 -140.661381) (xy 360.330447 -140.684019) (xy 360.376302 -140.713485)
			(xy 360.417497 -140.749176) (xy 360.453193 -140.790367) (xy 360.482662 -140.836219) (xy 360.505306 -140.885799)
			(xy 360.520663 -140.938096) (xy 360.528421 -140.992047) (xy 360.528421 -141.046553) (xy 360.520663 -141.100504)
			(xy 360.505306 -141.152801) (xy 360.482662 -141.202381) (xy 360.453193 -141.248233) (xy 360.417497 -141.289424)
			(xy 360.376302 -141.325115) (xy 360.330447 -141.354581) (xy 360.280866 -141.377219) (xy 360.228567 -141.392571)
			(xy 360.174615 -141.400323) (xy 360.147362 -141.400784) (xy 360.121047 -141.400347) (xy 360.068917 -141.393107)
			(xy 360.018273 -141.378782) (xy 359.970074 -141.357644) (xy 359.925232 -141.330092) (xy 359.884594 -141.296648)
			(xy 359.866438 -141.277594) (xy 359.858905 -141.270206) (xy 359.839634 -141.261674) (xy 359.8291 -141.261084)
			(xy 359.754424 -141.261084) (xy 359.743875 -141.261618) (xy 359.72458 -141.27015) (xy 359.717086 -141.277594)
			(xy 359.698929 -141.296648) (xy 359.6583 -141.330106) (xy 359.61346 -141.357665) (xy 359.565259 -141.378804)
			(xy 359.514612 -141.393121) (xy 359.462478 -141.400346) (xy 359.436162 -141.400784) (xy 359.408911 -141.400344)
			(xy 359.354964 -141.392582) (xy 359.30267 -141.377223) (xy 359.253095 -141.354578) (xy 359.207246 -141.325109)
			(xy 359.166058 -141.289415) (xy 359.130368 -141.248223) (xy 359.100904 -141.202372) (xy 359.078264 -141.152794)
			(xy 359.06291 -141.100499) (xy 359.055154 -141.046551) (xy 354.786639 -141.046551) (xy 354.816809 -141.092152)
			(xy 354.840481 -141.142649) (xy 354.856549 -141.196056) (xy 354.864669 -141.251232) (xy 354.865178 -141.279118)
			(xy 354.864669 -141.307004) (xy 354.856549 -141.36218) (xy 354.840481 -141.415587) (xy 354.816809 -141.466084)
			(xy 354.786036 -141.512597) (xy 354.748819 -141.554134) (xy 354.705951 -141.589809) (xy 354.658345 -141.618863)
			(xy 354.607016 -141.640675) (xy 354.553059 -141.654781) (xy 354.497622 -141.660881) (xy 354.441888 -141.658844)
			(xy 354.387045 -141.648714) (xy 354.334261 -141.630707) (xy 354.284661 -141.605206) (xy 354.239303 -141.572755)
			(xy 354.199154 -141.534046) (xy 354.165068 -141.489903) (xy 354.137772 -141.441268) (xy 354.117849 -141.389177)
			(xy 354.105723 -141.33474) (xy 354.101652 -141.279118) (xy 337.409018 -141.279118) (xy 337.413033 -141.287683)
			(xy 337.429101 -141.34109) (xy 337.437221 -141.396266) (xy 337.43773 -141.424152) (xy 337.437221 -141.452038)
			(xy 337.429101 -141.507214) (xy 337.413033 -141.560621) (xy 337.389361 -141.611118) (xy 337.358588 -141.657631)
			(xy 337.321371 -141.699168) (xy 337.278503 -141.734843) (xy 337.230897 -141.763897) (xy 337.179568 -141.785709)
			(xy 337.125611 -141.799815) (xy 337.070174 -141.805915) (xy 337.01444 -141.803878) (xy 336.959597 -141.793748)
			(xy 336.906813 -141.775741) (xy 336.857213 -141.75024) (xy 336.811855 -141.717789) (xy 336.771706 -141.67908)
			(xy 336.73762 -141.634937) (xy 336.710324 -141.586302) (xy 336.690401 -141.534211) (xy 336.678275 -141.479774)
			(xy 336.674204 -141.424152) (xy 326.089772 -141.424152) (xy 326.089772 -141.859) (xy 334.643982 -141.859)
			(xy 334.648053 -141.803378) (xy 334.660179 -141.748941) (xy 334.680102 -141.69685) (xy 334.707398 -141.648215)
			(xy 334.741484 -141.604072) (xy 334.781633 -141.565363) (xy 334.826991 -141.532912) (xy 334.876591 -141.507411)
			(xy 334.929375 -141.489404) (xy 334.984218 -141.479274) (xy 335.039952 -141.477237) (xy 335.095389 -141.483337)
			(xy 335.149346 -141.497443) (xy 335.200675 -141.519255) (xy 335.248281 -141.548309) (xy 335.291149 -141.583984)
			(xy 335.328366 -141.625521) (xy 335.359139 -141.672034) (xy 335.382811 -141.722531) (xy 335.398879 -141.775938)
			(xy 335.406999 -141.831114) (xy 335.407508 -141.859) (xy 335.406999 -141.886886) (xy 335.400076 -141.93393)
			(xy 349.735392 -141.93393) (xy 349.739463 -141.878308) (xy 349.751589 -141.823871) (xy 349.771512 -141.77178)
			(xy 349.798808 -141.723145) (xy 349.832894 -141.679002) (xy 349.873043 -141.640293) (xy 349.918401 -141.607842)
			(xy 349.968001 -141.582341) (xy 350.020785 -141.564334) (xy 350.075628 -141.554204) (xy 350.131362 -141.552167)
			(xy 350.186799 -141.558267) (xy 350.240756 -141.572373) (xy 350.292085 -141.594185) (xy 350.339691 -141.623239)
			(xy 350.382559 -141.658914) (xy 350.419776 -141.700451) (xy 350.450549 -141.746964) (xy 350.474221 -141.797461)
			(xy 350.490289 -141.850868) (xy 350.498409 -141.906044) (xy 350.498918 -141.93393) (xy 350.498409 -141.961816)
			(xy 350.490289 -142.016992) (xy 350.474221 -142.070399) (xy 350.450549 -142.120896) (xy 350.419776 -142.167409)
			(xy 350.382559 -142.208946) (xy 350.339691 -142.244621) (xy 350.292085 -142.273675) (xy 350.240756 -142.295487)
			(xy 350.186799 -142.309593) (xy 350.131362 -142.315693) (xy 350.075628 -142.313656) (xy 350.020785 -142.303526)
			(xy 349.968001 -142.285519) (xy 349.918401 -142.260018) (xy 349.873043 -142.227567) (xy 349.832894 -142.188858)
			(xy 349.798808 -142.144715) (xy 349.771512 -142.09608) (xy 349.751589 -142.043989) (xy 349.739463 -141.989552)
			(xy 349.735392 -141.93393) (xy 335.400076 -141.93393) (xy 335.398879 -141.942062) (xy 335.382811 -141.995469)
			(xy 335.359139 -142.045966) (xy 335.328366 -142.092479) (xy 335.291149 -142.134016) (xy 335.248281 -142.169691)
			(xy 335.200675 -142.198745) (xy 335.149346 -142.220557) (xy 335.095389 -142.234663) (xy 335.039952 -142.240763)
			(xy 334.984218 -142.238726) (xy 334.929375 -142.228596) (xy 334.876591 -142.210589) (xy 334.826991 -142.185088)
			(xy 334.781633 -142.152637) (xy 334.741484 -142.113928) (xy 334.707398 -142.069785) (xy 334.680102 -142.02115)
			(xy 334.660179 -141.969059) (xy 334.648053 -141.914622) (xy 334.643982 -141.859) (xy 326.089772 -141.859)
			(xy 326.089772 -142.875) (xy 334.643982 -142.875) (xy 334.648053 -142.819378) (xy 334.660179 -142.764941)
			(xy 334.680102 -142.71285) (xy 334.707398 -142.664215) (xy 334.741484 -142.620072) (xy 334.781633 -142.581363)
			(xy 334.826991 -142.548912) (xy 334.876591 -142.523411) (xy 334.929375 -142.505404) (xy 334.984218 -142.495274)
			(xy 335.039952 -142.493237) (xy 335.095389 -142.499337) (xy 335.149346 -142.513443) (xy 335.200675 -142.535255)
			(xy 335.248281 -142.564309) (xy 335.291149 -142.599984) (xy 335.328366 -142.641521) (xy 335.359139 -142.688034)
			(xy 335.382811 -142.738531) (xy 335.398879 -142.791938) (xy 335.406999 -142.847114) (xy 335.407508 -142.875)
			(xy 336.675982 -142.875) (xy 336.680053 -142.819378) (xy 336.692179 -142.764941) (xy 336.712102 -142.71285)
			(xy 336.739398 -142.664215) (xy 336.773484 -142.620072) (xy 336.813633 -142.581363) (xy 336.858991 -142.548912)
			(xy 336.908591 -142.523411) (xy 336.961375 -142.505404) (xy 337.016218 -142.495274) (xy 337.071952 -142.493237)
			(xy 337.127389 -142.499337) (xy 337.181346 -142.513443) (xy 337.232675 -142.535255) (xy 337.280281 -142.564309)
			(xy 337.323149 -142.599984) (xy 337.360366 -142.641521) (xy 337.391139 -142.688034) (xy 337.414811 -142.738531)
			(xy 337.430879 -142.791938) (xy 337.438999 -142.847114) (xy 337.439508 -142.875) (xy 339.469982 -142.875)
			(xy 339.474053 -142.819378) (xy 339.486179 -142.764941) (xy 339.506102 -142.71285) (xy 339.533398 -142.664215)
			(xy 339.567484 -142.620072) (xy 339.607633 -142.581363) (xy 339.652991 -142.548912) (xy 339.702591 -142.523411)
			(xy 339.755375 -142.505404) (xy 339.810218 -142.495274) (xy 339.865952 -142.493237) (xy 339.872886 -142.494)
			(xy 352.866196 -142.494) (xy 352.870267 -142.438378) (xy 352.882393 -142.383941) (xy 352.902316 -142.33185)
			(xy 352.929612 -142.283215) (xy 352.963698 -142.239072) (xy 353.003847 -142.200363) (xy 353.049205 -142.167912)
			(xy 353.098805 -142.142411) (xy 353.151589 -142.124404) (xy 353.206432 -142.114274) (xy 353.262166 -142.112237)
			(xy 353.317603 -142.118337) (xy 353.37156 -142.132443) (xy 353.422889 -142.154255) (xy 353.470495 -142.183309)
			(xy 353.513363 -142.218984) (xy 353.55058 -142.260521) (xy 353.581353 -142.307034) (xy 353.605025 -142.357531)
			(xy 353.621093 -142.410938) (xy 353.629213 -142.466114) (xy 353.629722 -142.494) (xy 353.629213 -142.521886)
			(xy 353.621093 -142.577062) (xy 353.605025 -142.630469) (xy 353.581353 -142.680966) (xy 353.55058 -142.727479)
			(xy 353.513363 -142.769016) (xy 353.470495 -142.804691) (xy 353.422889 -142.833745) (xy 353.37156 -142.855557)
			(xy 353.317603 -142.869663) (xy 353.262166 -142.875763) (xy 353.206432 -142.873726) (xy 353.151589 -142.863596)
			(xy 353.098805 -142.845589) (xy 353.049205 -142.820088) (xy 353.003847 -142.787637) (xy 352.963698 -142.748928)
			(xy 352.929612 -142.704785) (xy 352.902316 -142.65615) (xy 352.882393 -142.604059) (xy 352.870267 -142.549622)
			(xy 352.866196 -142.494) (xy 339.872886 -142.494) (xy 339.921389 -142.499337) (xy 339.975346 -142.513443)
			(xy 340.026675 -142.535255) (xy 340.074281 -142.564309) (xy 340.117149 -142.599984) (xy 340.154366 -142.641521)
			(xy 340.185139 -142.688034) (xy 340.208811 -142.738531) (xy 340.224879 -142.791938) (xy 340.232999 -142.847114)
			(xy 340.233508 -142.875) (xy 340.232999 -142.902886) (xy 340.224879 -142.958062) (xy 340.208811 -143.011469)
			(xy 340.185139 -143.061966) (xy 340.154366 -143.108479) (xy 340.117149 -143.150016) (xy 340.074281 -143.185691)
			(xy 340.026675 -143.214745) (xy 339.975346 -143.236557) (xy 339.921389 -143.250663) (xy 339.865952 -143.256763)
			(xy 339.810218 -143.254726) (xy 339.755375 -143.244596) (xy 339.702591 -143.226589) (xy 339.652991 -143.201088)
			(xy 339.607633 -143.168637) (xy 339.567484 -143.129928) (xy 339.533398 -143.085785) (xy 339.506102 -143.03715)
			(xy 339.486179 -142.985059) (xy 339.474053 -142.930622) (xy 339.469982 -142.875) (xy 337.439508 -142.875)
			(xy 337.438999 -142.902886) (xy 337.430879 -142.958062) (xy 337.414811 -143.011469) (xy 337.391139 -143.061966)
			(xy 337.360366 -143.108479) (xy 337.323149 -143.150016) (xy 337.280281 -143.185691) (xy 337.232675 -143.214745)
			(xy 337.181346 -143.236557) (xy 337.127389 -143.250663) (xy 337.071952 -143.256763) (xy 337.016218 -143.254726)
			(xy 336.961375 -143.244596) (xy 336.908591 -143.226589) (xy 336.858991 -143.201088) (xy 336.813633 -143.168637)
			(xy 336.773484 -143.129928) (xy 336.739398 -143.085785) (xy 336.712102 -143.03715) (xy 336.692179 -142.985059)
			(xy 336.680053 -142.930622) (xy 336.675982 -142.875) (xy 335.407508 -142.875) (xy 335.406999 -142.902886)
			(xy 335.398879 -142.958062) (xy 335.382811 -143.011469) (xy 335.359139 -143.061966) (xy 335.328366 -143.108479)
			(xy 335.291149 -143.150016) (xy 335.248281 -143.185691) (xy 335.200675 -143.214745) (xy 335.149346 -143.236557)
			(xy 335.095389 -143.250663) (xy 335.039952 -143.256763) (xy 334.984218 -143.254726) (xy 334.929375 -143.244596)
			(xy 334.876591 -143.226589) (xy 334.826991 -143.201088) (xy 334.781633 -143.168637) (xy 334.741484 -143.129928)
			(xy 334.707398 -143.085785) (xy 334.680102 -143.03715) (xy 334.660179 -142.985059) (xy 334.648053 -142.930622)
			(xy 334.643982 -142.875) (xy 326.089772 -142.875) (xy 326.089772 -144.43329) (xy 330.02601 -144.43329)
			(xy 330.026471 -144.407257) (xy 330.03356 -144.355674) (xy 330.047592 -144.305534) (xy 330.068307 -144.257765)
			(xy 330.095319 -144.213253) (xy 330.128129 -144.172824) (xy 330.166128 -144.137228) (xy 330.20861 -144.107125)
			(xy 330.231496 -144.094708) (xy 330.243753 -144.087739) (xy 330.264199 -144.068341) (xy 330.278569 -144.044097)
			(xy 330.285772 -144.01685) (xy 330.28526 -143.988672) (xy 330.277072 -143.961705) (xy 330.261831 -143.937999)
			(xy 330.251562 -143.928338) (xy 330.231547 -143.910136) (xy 330.196348 -143.869052) (xy 330.167304 -143.82341)
			(xy 330.144997 -143.774123) (xy 330.129873 -143.72218) (xy 330.122237 -143.668622) (xy 330.121768 -143.641572)
			(xy 330.122254 -143.614321) (xy 330.13001 -143.560373) (xy 330.145365 -143.508078) (xy 330.168007 -143.458501)
			(xy 330.197473 -143.412651) (xy 330.233164 -143.37146) (xy 330.274355 -143.335769) (xy 330.320205 -143.306303)
			(xy 330.369782 -143.283661) (xy 330.422077 -143.268306) (xy 330.476025 -143.26055) (xy 330.530527 -143.26055)
			(xy 330.584475 -143.268306) (xy 330.63677 -143.283661) (xy 330.686347 -143.306303) (xy 330.732197 -143.335769)
			(xy 330.773388 -143.37146) (xy 330.781626 -143.380968) (xy 341.689434 -143.380968) (xy 341.693505 -143.325346)
			(xy 341.705631 -143.270909) (xy 341.725554 -143.218818) (xy 341.75285 -143.170183) (xy 341.786936 -143.12604)
			(xy 341.827085 -143.087331) (xy 341.872443 -143.05488) (xy 341.922043 -143.029379) (xy 341.974827 -143.011372)
			(xy 342.02967 -143.001242) (xy 342.085404 -142.999205) (xy 342.140841 -143.005305) (xy 342.194798 -143.019411)
			(xy 342.246127 -143.041223) (xy 342.293733 -143.070277) (xy 342.336601 -143.105952) (xy 342.373818 -143.147489)
			(xy 342.404591 -143.194002) (xy 342.428263 -143.244499) (xy 342.4305 -143.251936) (xy 349.735392 -143.251936)
			(xy 349.739463 -143.196314) (xy 349.751589 -143.141877) (xy 349.771512 -143.089786) (xy 349.798808 -143.041151)
			(xy 349.832894 -142.997008) (xy 349.873043 -142.958299) (xy 349.918401 -142.925848) (xy 349.968001 -142.900347)
			(xy 350.020785 -142.88234) (xy 350.075628 -142.87221) (xy 350.131362 -142.870173) (xy 350.186799 -142.876273)
			(xy 350.240756 -142.890379) (xy 350.292085 -142.912191) (xy 350.339691 -142.941245) (xy 350.382559 -142.97692)
			(xy 350.419776 -143.018457) (xy 350.450549 -143.06497) (xy 350.456916 -143.078551) (xy 359.055154 -143.078551)
			(xy 359.055154 -143.024049) (xy 359.06291 -142.970101) (xy 359.078264 -142.917806) (xy 359.100904 -142.868228)
			(xy 359.130368 -142.822377) (xy 359.166058 -142.781185) (xy 359.207246 -142.745491) (xy 359.253095 -142.716022)
			(xy 359.30267 -142.693377) (xy 359.354964 -142.678018) (xy 359.408911 -142.670256) (xy 359.436162 -142.669768)
			(xy 359.462477 -142.670204) (xy 359.514606 -142.677447) (xy 359.565249 -142.691773) (xy 359.613448 -142.712911)
			(xy 359.658291 -142.740462) (xy 359.69893 -142.773905) (xy 359.717086 -142.792958) (xy 359.724617 -142.800349)
			(xy 359.74389 -142.808881) (xy 359.754424 -142.809468) (xy 359.8291 -142.809468) (xy 359.839653 -142.808962)
			(xy 359.858948 -142.800412) (xy 359.866438 -142.792958) (xy 359.884574 -142.773883) (xy 359.925209 -142.740429)
			(xy 359.970053 -142.712874) (xy 360.018258 -142.691739) (xy 360.068908 -142.677426) (xy 360.121045 -142.670205)
			(xy 360.147362 -142.669768) (xy 360.174615 -142.670277) (xy 360.228567 -142.678029) (xy 360.280866 -142.693381)
			(xy 360.330447 -142.716019) (xy 360.376302 -142.745485) (xy 360.417497 -142.781176) (xy 360.453193 -142.822367)
			(xy 360.482662 -142.868219) (xy 360.505306 -142.917799) (xy 360.520663 -142.970096) (xy 360.528421 -143.024047)
			(xy 360.528421 -143.078553) (xy 360.520663 -143.132504) (xy 360.505306 -143.184801) (xy 360.482662 -143.234381)
			(xy 360.453193 -143.280233) (xy 360.417497 -143.321424) (xy 360.376302 -143.357115) (xy 360.330447 -143.386581)
			(xy 360.280866 -143.409219) (xy 360.228567 -143.424571) (xy 360.174615 -143.432323) (xy 360.147362 -143.432784)
			(xy 360.121047 -143.432347) (xy 360.068917 -143.425107) (xy 360.018273 -143.410782) (xy 359.970074 -143.389644)
			(xy 359.925232 -143.362092) (xy 359.884594 -143.328648) (xy 359.866438 -143.309594) (xy 359.858905 -143.302206)
			(xy 359.839634 -143.293674) (xy 359.8291 -143.293084) (xy 359.754424 -143.293084) (xy 359.743875 -143.293618)
			(xy 359.72458 -143.30215) (xy 359.717086 -143.309594) (xy 359.698929 -143.328648) (xy 359.6583 -143.362106)
			(xy 359.61346 -143.389665) (xy 359.565259 -143.410804) (xy 359.514612 -143.425121) (xy 359.462478 -143.432346)
			(xy 359.436162 -143.432784) (xy 359.408911 -143.432344) (xy 359.354964 -143.424582) (xy 359.30267 -143.409223)
			(xy 359.253095 -143.386578) (xy 359.207246 -143.357109) (xy 359.166058 -143.321415) (xy 359.130368 -143.280223)
			(xy 359.100904 -143.234372) (xy 359.078264 -143.184794) (xy 359.06291 -143.132499) (xy 359.055154 -143.078551)
			(xy 350.456916 -143.078551) (xy 350.474221 -143.115467) (xy 350.490289 -143.168874) (xy 350.498409 -143.22405)
			(xy 350.498918 -143.251936) (xy 350.498409 -143.279822) (xy 350.490289 -143.334998) (xy 350.474221 -143.388405)
			(xy 350.450549 -143.438902) (xy 350.419776 -143.485415) (xy 350.397748 -143.51) (xy 352.866196 -143.51)
			(xy 352.870267 -143.454378) (xy 352.882393 -143.399941) (xy 352.902316 -143.34785) (xy 352.929612 -143.299215)
			(xy 352.963698 -143.255072) (xy 353.003847 -143.216363) (xy 353.049205 -143.183912) (xy 353.098805 -143.158411)
			(xy 353.151589 -143.140404) (xy 353.206432 -143.130274) (xy 353.262166 -143.128237) (xy 353.317603 -143.134337)
			(xy 353.37156 -143.148443) (xy 353.422889 -143.170255) (xy 353.470495 -143.199309) (xy 353.513363 -143.234984)
			(xy 353.55058 -143.276521) (xy 353.581353 -143.323034) (xy 353.605025 -143.373531) (xy 353.621093 -143.426938)
			(xy 353.629213 -143.482114) (xy 353.629722 -143.51) (xy 353.629213 -143.537886) (xy 353.621093 -143.593062)
			(xy 353.605025 -143.646469) (xy 353.581353 -143.696966) (xy 353.55058 -143.743479) (xy 353.513363 -143.785016)
			(xy 353.470495 -143.820691) (xy 353.422889 -143.849745) (xy 353.37156 -143.871557) (xy 353.317603 -143.885663)
			(xy 353.262166 -143.891763) (xy 353.206432 -143.889726) (xy 353.151589 -143.879596) (xy 353.098805 -143.861589)
			(xy 353.049205 -143.836088) (xy 353.003847 -143.803637) (xy 352.963698 -143.764928) (xy 352.929612 -143.720785)
			(xy 352.902316 -143.67215) (xy 352.882393 -143.620059) (xy 352.870267 -143.565622) (xy 352.866196 -143.51)
			(xy 350.397748 -143.51) (xy 350.382559 -143.526952) (xy 350.339691 -143.562627) (xy 350.292085 -143.591681)
			(xy 350.240756 -143.613493) (xy 350.186799 -143.627599) (xy 350.131362 -143.633699) (xy 350.075628 -143.631662)
			(xy 350.020785 -143.621532) (xy 349.968001 -143.603525) (xy 349.918401 -143.578024) (xy 349.873043 -143.545573)
			(xy 349.832894 -143.506864) (xy 349.798808 -143.462721) (xy 349.771512 -143.414086) (xy 349.751589 -143.361995)
			(xy 349.739463 -143.307558) (xy 349.735392 -143.251936) (xy 342.4305 -143.251936) (xy 342.444331 -143.297906)
			(xy 342.452451 -143.353082) (xy 342.45296 -143.380968) (xy 342.452451 -143.408854) (xy 342.444331 -143.46403)
			(xy 342.428263 -143.517437) (xy 342.404591 -143.567934) (xy 342.373818 -143.614447) (xy 342.336601 -143.655984)
			(xy 342.293733 -143.691659) (xy 342.246127 -143.720713) (xy 342.194798 -143.742525) (xy 342.140841 -143.756631)
			(xy 342.085404 -143.762731) (xy 342.02967 -143.760694) (xy 341.974827 -143.750564) (xy 341.922043 -143.732557)
			(xy 341.872443 -143.707056) (xy 341.827085 -143.674605) (xy 341.786936 -143.635896) (xy 341.75285 -143.591753)
			(xy 341.725554 -143.543118) (xy 341.705631 -143.491027) (xy 341.693505 -143.43659) (xy 341.689434 -143.380968)
			(xy 330.781626 -143.380968) (xy 330.809079 -143.412651) (xy 330.838545 -143.458501) (xy 330.861187 -143.508078)
			(xy 330.876542 -143.560373) (xy 330.884298 -143.614321) (xy 330.884784 -143.641572) (xy 330.884295 -143.667605)
			(xy 330.877211 -143.719186) (xy 330.863183 -143.769326) (xy 330.842473 -143.817095) (xy 330.815465 -143.861607)
			(xy 330.782658 -143.902036) (xy 330.744662 -143.937633) (xy 330.702182 -143.967736) (xy 330.679298 -143.980154)
			(xy 330.66699 -143.98704) (xy 330.64654 -144.006455) (xy 330.632171 -144.030716) (xy 330.624973 -144.057979)
			(xy 330.625495 -144.086171) (xy 330.633697 -144.113149) (xy 330.648955 -144.136862) (xy 330.659232 -144.146524)
			(xy 330.679227 -144.164747) (xy 330.714428 -144.205826) (xy 330.741349 -144.248124) (xy 336.662266 -144.248124)
			(xy 336.666337 -144.192502) (xy 336.678463 -144.138065) (xy 336.698386 -144.085974) (xy 336.725682 -144.037339)
			(xy 336.759768 -143.993196) (xy 336.799917 -143.954487) (xy 336.845275 -143.922036) (xy 336.894875 -143.896535)
			(xy 336.947659 -143.878528) (xy 337.002502 -143.868398) (xy 337.058236 -143.866361) (xy 337.113673 -143.872461)
			(xy 337.16763 -143.886567) (xy 337.218959 -143.908379) (xy 337.266565 -143.937433) (xy 337.301418 -143.966438)
			(xy 367.764314 -143.966438) (xy 367.764725 -143.940462) (xy 367.771775 -143.88899) (xy 367.785751 -143.838952)
			(xy 367.806392 -143.791277) (xy 367.833317 -143.746846) (xy 367.866026 -143.706483) (xy 367.903914 -143.670936)
			(xy 367.924842 -143.655542) (xy 367.934333 -143.64791) (xy 367.945478 -143.626298) (xy 367.946178 -143.61414)
			(xy 367.946178 -143.531336) (xy 367.945487 -143.519174) (xy 367.934347 -143.497553) (xy 367.924842 -143.489934)
			(xy 367.903923 -143.474532) (xy 367.866046 -143.438979) (xy 367.833346 -143.398614) (xy 367.806428 -143.354184)
			(xy 367.785789 -143.306512) (xy 367.771812 -143.256479) (xy 367.764756 -143.205012) (xy 367.764314 -143.179038)
			(xy 367.764823 -143.150299) (xy 367.773453 -143.093472) (xy 367.790508 -143.038582) (xy 367.815602 -142.98687)
			(xy 367.848168 -142.939508) (xy 367.867438 -142.91818) (xy 367.874042 -142.911322) (xy 367.881154 -142.893288)
			(xy 367.881154 -142.804388) (xy 367.874042 -142.786354) (xy 367.867438 -142.779496) (xy 367.848204 -142.758137)
			(xy 367.815637 -142.71078) (xy 367.790542 -142.659074) (xy 367.773488 -142.604188) (xy 367.764862 -142.547365)
			(xy 367.764858 -142.489891) (xy 367.773476 -142.433066) (xy 367.790522 -142.378178) (xy 367.815609 -142.326468)
			(xy 367.848169 -142.279106) (xy 367.867438 -142.25778) (xy 367.874042 -142.250922) (xy 367.881154 -142.232888)
			(xy 367.881154 -142.143988) (xy 367.874042 -142.125954) (xy 367.867438 -142.119096) (xy 367.848204 -142.097737)
			(xy 367.815637 -142.05038) (xy 367.790542 -141.998674) (xy 367.773488 -141.943788) (xy 367.764862 -141.886965)
			(xy 367.764858 -141.829491) (xy 367.773476 -141.772666) (xy 367.790522 -141.717778) (xy 367.815609 -141.666068)
			(xy 367.848169 -141.618706) (xy 367.867438 -141.59738) (xy 367.874042 -141.590522) (xy 367.881154 -141.572488)
			(xy 367.881154 -141.483588) (xy 367.874042 -141.465554) (xy 367.867438 -141.458696) (xy 367.848204 -141.437337)
			(xy 367.815637 -141.38998) (xy 367.790542 -141.338274) (xy 367.773488 -141.283388) (xy 367.764862 -141.226565)
			(xy 367.764858 -141.169091) (xy 367.773476 -141.112266) (xy 367.790522 -141.057378) (xy 367.815609 -141.005668)
			(xy 367.848169 -140.958306) (xy 367.867438 -140.93698) (xy 367.874042 -140.930122) (xy 367.881154 -140.912088)
			(xy 367.881154 -140.823188) (xy 367.874042 -140.805154) (xy 367.867438 -140.798296) (xy 367.848185 -140.776953)
			(xy 367.815617 -140.729596) (xy 367.790521 -140.677888) (xy 367.773466 -140.623001) (xy 367.764838 -140.566176)
			(xy 367.764314 -140.537438) (xy 367.7648 -140.510187) (xy 367.772556 -140.456239) (xy 367.787911 -140.403944)
			(xy 367.810553 -140.354367) (xy 367.840019 -140.308517) (xy 367.87571 -140.267326) (xy 367.916901 -140.231635)
			(xy 367.962751 -140.202169) (xy 368.012328 -140.179527) (xy 368.064623 -140.164172) (xy 368.118571 -140.156416)
			(xy 368.173073 -140.156416) (xy 368.227021 -140.164172) (xy 368.279316 -140.179527) (xy 368.328893 -140.202169)
			(xy 368.374743 -140.231635) (xy 368.415934 -140.267326) (xy 368.451625 -140.308517) (xy 368.481091 -140.354367)
			(xy 368.503733 -140.403944) (xy 368.519088 -140.456239) (xy 368.526844 -140.510187) (xy 368.52733 -140.537438)
			(xy 368.526821 -140.566177) (xy 368.518194 -140.623005) (xy 368.50114 -140.677896) (xy 368.476045 -140.729607)
			(xy 368.443478 -140.776969) (xy 368.424206 -140.798296) (xy 368.417602 -140.805154) (xy 368.41049 -140.823188)
			(xy 368.41049 -140.912088) (xy 368.417602 -140.930122) (xy 368.424206 -140.93698) (xy 368.443513 -140.958275)
			(xy 368.476075 -141.005644) (xy 368.501162 -141.057361) (xy 368.518208 -141.112256) (xy 368.526826 -141.169087)
			(xy 368.526822 -141.226568) (xy 368.518195 -141.283398) (xy 368.501142 -141.338291) (xy 368.476047 -141.390004)
			(xy 368.443478 -141.437368) (xy 368.424206 -141.458696) (xy 368.417602 -141.465554) (xy 368.41049 -141.483588)
			(xy 368.41049 -141.572488) (xy 368.417602 -141.590522) (xy 368.424206 -141.59738) (xy 368.443513 -141.618675)
			(xy 368.476075 -141.666044) (xy 368.501162 -141.717761) (xy 368.518208 -141.772656) (xy 368.526826 -141.829487)
			(xy 368.526822 -141.886968) (xy 368.518195 -141.943798) (xy 368.501142 -141.998691) (xy 368.476047 -142.050404)
			(xy 368.443478 -142.097768) (xy 368.424206 -142.119096) (xy 368.417602 -142.125954) (xy 368.41049 -142.143988)
			(xy 368.41049 -142.232888) (xy 368.417602 -142.250922) (xy 368.424206 -142.25778) (xy 368.443513 -142.279075)
			(xy 368.476075 -142.326444) (xy 368.501162 -142.378161) (xy 368.518208 -142.433056) (xy 368.526826 -142.489887)
			(xy 368.526822 -142.547368) (xy 368.518195 -142.604198) (xy 368.501142 -142.659091) (xy 368.476047 -142.710804)
			(xy 368.443478 -142.758168) (xy 368.424206 -142.779496) (xy 368.417602 -142.786354) (xy 368.41049 -142.804388)
			(xy 368.41049 -142.893288) (xy 368.417602 -142.911322) (xy 368.424206 -142.91818) (xy 368.443485 -142.9395)
			(xy 368.476052 -142.986863) (xy 368.501144 -143.038576) (xy 368.518192 -143.093469) (xy 368.526811 -143.150298)
			(xy 368.52733 -143.179038) (xy 368.526925 -143.205015) (xy 368.519876 -143.256488) (xy 368.505902 -143.306526)
			(xy 368.48526 -143.354203) (xy 368.458334 -143.398634) (xy 368.425622 -143.438996) (xy 368.387731 -143.474541)
			(xy 368.366802 -143.489934) (xy 368.35733 -143.497587) (xy 368.346173 -143.519183) (xy 368.345466 -143.531336)
			(xy 368.345466 -143.61414) (xy 368.346155 -143.626303) (xy 368.357295 -143.647925) (xy 368.366802 -143.655542)
			(xy 368.38772 -143.670946) (xy 368.425594 -143.7065) (xy 368.458293 -143.746865) (xy 368.485211 -143.791295)
			(xy 368.50585 -143.838967) (xy 368.519828 -143.888998) (xy 368.526887 -143.940464) (xy 368.52733 -143.966438)
			(xy 368.526844 -143.993689) (xy 368.519088 -144.047637) (xy 368.503733 -144.099932) (xy 368.481091 -144.149509)
			(xy 368.451625 -144.195359) (xy 368.415934 -144.23655) (xy 368.374743 -144.272241) (xy 368.328893 -144.301707)
			(xy 368.279316 -144.324349) (xy 368.227021 -144.339704) (xy 368.173073 -144.34746) (xy 368.118571 -144.34746)
			(xy 368.064623 -144.339704) (xy 368.012328 -144.324349) (xy 367.962751 -144.301707) (xy 367.916901 -144.272241)
			(xy 367.87571 -144.23655) (xy 367.840019 -144.195359) (xy 367.810553 -144.149509) (xy 367.787911 -144.099932)
			(xy 367.772556 -144.047637) (xy 367.7648 -143.993689) (xy 367.764314 -143.966438) (xy 337.301418 -143.966438)
			(xy 337.309433 -143.973108) (xy 337.34665 -144.014645) (xy 337.377423 -144.061158) (xy 337.401095 -144.111655)
			(xy 337.417163 -144.165062) (xy 337.425283 -144.220238) (xy 337.425792 -144.248124) (xy 337.425283 -144.27601)
			(xy 337.417163 -144.331186) (xy 337.401095 -144.384593) (xy 337.398985 -144.389094) (xy 339.797388 -144.389094)
			(xy 339.801459 -144.333472) (xy 339.813585 -144.279035) (xy 339.833508 -144.226944) (xy 339.860804 -144.178309)
			(xy 339.89489 -144.134166) (xy 339.935039 -144.095457) (xy 339.980397 -144.063006) (xy 340.029997 -144.037505)
			(xy 340.082781 -144.019498) (xy 340.137624 -144.009368) (xy 340.193358 -144.007331) (xy 340.248795 -144.013431)
			(xy 340.302752 -144.027537) (xy 340.354081 -144.049349) (xy 340.401687 -144.078403) (xy 340.444555 -144.114078)
			(xy 340.481772 -144.155615) (xy 340.512545 -144.202128) (xy 340.536217 -144.252625) (xy 340.552285 -144.306032)
			(xy 340.560405 -144.361208) (xy 340.560914 -144.389094) (xy 340.560405 -144.41698) (xy 340.552285 -144.472156)
			(xy 340.536217 -144.525563) (xy 340.512545 -144.57606) (xy 340.481772 -144.622573) (xy 340.444555 -144.66411)
			(xy 340.401687 -144.699785) (xy 340.363478 -144.723104) (xy 349.735392 -144.723104) (xy 349.739463 -144.667482)
			(xy 349.751589 -144.613045) (xy 349.771512 -144.560954) (xy 349.798808 -144.512319) (xy 349.832894 -144.468176)
			(xy 349.873043 -144.429467) (xy 349.918401 -144.397016) (xy 349.968001 -144.371515) (xy 350.020785 -144.353508)
			(xy 350.075628 -144.343378) (xy 350.131362 -144.341341) (xy 350.186799 -144.347441) (xy 350.240756 -144.361547)
			(xy 350.292085 -144.383359) (xy 350.339691 -144.412413) (xy 350.382559 -144.448088) (xy 350.419776 -144.489625)
			(xy 350.443842 -144.526) (xy 352.866196 -144.526) (xy 352.870267 -144.470378) (xy 352.882393 -144.415941)
			(xy 352.902316 -144.36385) (xy 352.929612 -144.315215) (xy 352.963698 -144.271072) (xy 353.003847 -144.232363)
			(xy 353.049205 -144.199912) (xy 353.098805 -144.174411) (xy 353.151589 -144.156404) (xy 353.206432 -144.146274)
			(xy 353.262166 -144.144237) (xy 353.317603 -144.150337) (xy 353.37156 -144.164443) (xy 353.422889 -144.186255)
			(xy 353.470495 -144.215309) (xy 353.513363 -144.250984) (xy 353.55058 -144.292521) (xy 353.581353 -144.339034)
			(xy 353.605025 -144.389531) (xy 353.621093 -144.442938) (xy 353.629213 -144.498114) (xy 353.629722 -144.526)
			(xy 353.629213 -144.553886) (xy 353.621093 -144.609062) (xy 353.605025 -144.662469) (xy 353.581353 -144.712966)
			(xy 353.55058 -144.759479) (xy 353.513363 -144.801016) (xy 353.470495 -144.836691) (xy 353.422889 -144.865745)
			(xy 353.37156 -144.887557) (xy 353.317603 -144.901663) (xy 353.262166 -144.907763) (xy 353.206432 -144.905726)
			(xy 353.151589 -144.895596) (xy 353.098805 -144.877589) (xy 353.049205 -144.852088) (xy 353.003847 -144.819637)
			(xy 352.963698 -144.780928) (xy 352.929612 -144.736785) (xy 352.902316 -144.68815) (xy 352.882393 -144.636059)
			(xy 352.870267 -144.581622) (xy 352.866196 -144.526) (xy 350.443842 -144.526) (xy 350.450549 -144.536138)
			(xy 350.474221 -144.586635) (xy 350.490289 -144.640042) (xy 350.498409 -144.695218) (xy 350.498918 -144.723104)
			(xy 350.498409 -144.75099) (xy 350.490289 -144.806166) (xy 350.474221 -144.859573) (xy 350.450549 -144.91007)
			(xy 350.419776 -144.956583) (xy 350.382559 -144.99812) (xy 350.339691 -145.033795) (xy 350.292085 -145.062849)
			(xy 350.240756 -145.084661) (xy 350.186799 -145.098767) (xy 350.131362 -145.104867) (xy 350.075628 -145.10283)
			(xy 350.020785 -145.0927) (xy 349.968001 -145.074693) (xy 349.918401 -145.049192) (xy 349.873043 -145.016741)
			(xy 349.832894 -144.978032) (xy 349.798808 -144.933889) (xy 349.771512 -144.885254) (xy 349.751589 -144.833163)
			(xy 349.739463 -144.778726) (xy 349.735392 -144.723104) (xy 340.363478 -144.723104) (xy 340.354081 -144.728839)
			(xy 340.302752 -144.750651) (xy 340.248795 -144.764757) (xy 340.193358 -144.770857) (xy 340.137624 -144.76882)
			(xy 340.082781 -144.75869) (xy 340.029997 -144.740683) (xy 339.980397 -144.715182) (xy 339.935039 -144.682731)
			(xy 339.89489 -144.644022) (xy 339.860804 -144.599879) (xy 339.833508 -144.551244) (xy 339.813585 -144.499153)
			(xy 339.801459 -144.444716) (xy 339.797388 -144.389094) (xy 337.398985 -144.389094) (xy 337.377423 -144.43509)
			(xy 337.34665 -144.481603) (xy 337.309433 -144.52314) (xy 337.266565 -144.558815) (xy 337.218959 -144.587869)
			(xy 337.16763 -144.609681) (xy 337.113673 -144.623787) (xy 337.058236 -144.629887) (xy 337.002502 -144.62785)
			(xy 336.947659 -144.61772) (xy 336.894875 -144.599713) (xy 336.845275 -144.574212) (xy 336.799917 -144.541761)
			(xy 336.759768 -144.503052) (xy 336.725682 -144.458909) (xy 336.698386 -144.410274) (xy 336.678463 -144.358183)
			(xy 336.666337 -144.303746) (xy 336.662266 -144.248124) (xy 330.741349 -144.248124) (xy 330.743475 -144.251464)
			(xy 330.765786 -144.300746) (xy 330.780913 -144.352686) (xy 330.788554 -144.406241) (xy 330.789026 -144.43329)
			(xy 330.78854 -144.460541) (xy 330.780784 -144.514489) (xy 330.765429 -144.566784) (xy 330.742787 -144.616361)
			(xy 330.713321 -144.662211) (xy 330.67763 -144.703402) (xy 330.636439 -144.739093) (xy 330.590589 -144.768559)
			(xy 330.541012 -144.791201) (xy 330.488717 -144.806556) (xy 330.434769 -144.814312) (xy 330.380267 -144.814312)
			(xy 330.326319 -144.806556) (xy 330.274024 -144.791201) (xy 330.224447 -144.768559) (xy 330.178597 -144.739093)
			(xy 330.137406 -144.703402) (xy 330.101715 -144.662211) (xy 330.072249 -144.616361) (xy 330.049607 -144.566784)
			(xy 330.034252 -144.514489) (xy 330.026496 -144.460541) (xy 330.02601 -144.43329) (xy 326.089772 -144.43329)
			(xy 326.089772 -145.923) (xy 334.643982 -145.923) (xy 334.648053 -145.867378) (xy 334.660179 -145.812941)
			(xy 334.680102 -145.76085) (xy 334.707398 -145.712215) (xy 334.741484 -145.668072) (xy 334.781633 -145.629363)
			(xy 334.826991 -145.596912) (xy 334.876591 -145.571411) (xy 334.929375 -145.553404) (xy 334.984218 -145.543274)
			(xy 335.039952 -145.541237) (xy 335.095389 -145.547337) (xy 335.149346 -145.561443) (xy 335.200675 -145.583255)
			(xy 335.248281 -145.612309) (xy 335.2694 -145.629884) (xy 336.686904 -145.629884) (xy 336.690975 -145.574262)
			(xy 336.703101 -145.519825) (xy 336.723024 -145.467734) (xy 336.75032 -145.419099) (xy 336.784406 -145.374956)
			(xy 336.824555 -145.336247) (xy 336.869913 -145.303796) (xy 336.919513 -145.278295) (xy 336.972297 -145.260288)
			(xy 337.02714 -145.250158) (xy 337.082874 -145.248121) (xy 337.138311 -145.254221) (xy 337.192268 -145.268327)
			(xy 337.19493 -145.269458) (xy 351.054414 -145.269458) (xy 351.058485 -145.213836) (xy 351.070611 -145.159399)
			(xy 351.090534 -145.107308) (xy 351.11783 -145.058673) (xy 351.151916 -145.01453) (xy 351.192065 -144.975821)
			(xy 351.237423 -144.94337) (xy 351.287023 -144.917869) (xy 351.339807 -144.899862) (xy 351.39465 -144.889732)
			(xy 351.450384 -144.887695) (xy 351.505821 -144.893795) (xy 351.559778 -144.907901) (xy 351.611107 -144.929713)
			(xy 351.658713 -144.958767) (xy 351.701581 -144.994442) (xy 351.738798 -145.035979) (xy 351.769571 -145.082492)
			(xy 351.782725 -145.110551) (xy 359.055154 -145.110551) (xy 359.055154 -145.056049) (xy 359.06291 -145.002101)
			(xy 359.078264 -144.949806) (xy 359.100904 -144.900228) (xy 359.130368 -144.854377) (xy 359.166058 -144.813185)
			(xy 359.207246 -144.777491) (xy 359.253095 -144.748022) (xy 359.30267 -144.725377) (xy 359.354964 -144.710018)
			(xy 359.408911 -144.702256) (xy 359.436162 -144.701768) (xy 359.462477 -144.702204) (xy 359.514606 -144.709447)
			(xy 359.565249 -144.723773) (xy 359.613448 -144.744911) (xy 359.658291 -144.772462) (xy 359.69893 -144.805905)
			(xy 359.717086 -144.824958) (xy 359.724617 -144.832349) (xy 359.74389 -144.840881) (xy 359.754424 -144.841468)
			(xy 359.8291 -144.841468) (xy 359.839653 -144.840962) (xy 359.858948 -144.832412) (xy 359.866438 -144.824958)
			(xy 359.884574 -144.805883) (xy 359.925209 -144.772429) (xy 359.970053 -144.744874) (xy 360.018258 -144.723739)
			(xy 360.068908 -144.709426) (xy 360.121045 -144.702205) (xy 360.147362 -144.701768) (xy 360.174615 -144.702277)
			(xy 360.228567 -144.710029) (xy 360.280866 -144.725381) (xy 360.330447 -144.748019) (xy 360.376302 -144.777485)
			(xy 360.417497 -144.813176) (xy 360.453193 -144.854367) (xy 360.482662 -144.900219) (xy 360.505306 -144.949799)
			(xy 360.506611 -144.954244) (xy 366.239044 -144.954244) (xy 366.239619 -144.926996) (xy 366.247368 -144.873054)
			(xy 366.262715 -144.820764) (xy 366.285348 -144.77119) (xy 366.314805 -144.725342) (xy 366.350487 -144.684152)
			(xy 366.391668 -144.64846) (xy 366.437509 -144.618992) (xy 366.487078 -144.596348) (xy 366.539364 -144.580988)
			(xy 366.593304 -144.573226) (xy 366.620552 -144.572736) (xy 366.649326 -144.573259) (xy 366.706221 -144.581909)
			(xy 366.761172 -144.599005) (xy 366.812932 -144.624159) (xy 366.860328 -144.656801) (xy 366.881664 -144.676114)
			(xy 366.889538 -144.68348) (xy 366.90935 -144.690592) (xy 367.005616 -144.683226) (xy 367.024412 -144.67332)
			(xy 367.031016 -144.664938) (xy 367.049197 -144.642716) (xy 367.091141 -144.603508) (xy 367.138486 -144.571026)
			(xy 367.190162 -144.546004) (xy 367.245004 -144.529006) (xy 367.301774 -144.520416) (xy 367.330482 -144.519904)
			(xy 367.357735 -144.520372) (xy 367.411686 -144.528127) (xy 367.463985 -144.543481) (xy 367.513566 -144.566123)
			(xy 367.559419 -144.59559) (xy 367.600613 -144.631283) (xy 367.636307 -144.672476) (xy 367.665775 -144.718329)
			(xy 367.688417 -144.76791) (xy 367.703772 -144.820208) (xy 367.711527 -144.874159) (xy 367.71199 -144.901412)
			(xy 367.711543 -144.928315) (xy 367.703969 -144.981586) (xy 367.688988 -145.033265) (xy 367.666895 -145.082327)
			(xy 367.63813 -145.127799) (xy 367.603263 -145.16878) (xy 367.562985 -145.204457) (xy 367.540794 -145.219674)
			(xy 367.529872 -145.226786) (xy 367.517934 -145.249646) (xy 367.519966 -145.361914) (xy 367.53292 -145.384266)
			(xy 367.544096 -145.391124) (xy 367.567696 -145.406048) (xy 367.610649 -145.441726) (xy 367.647942 -145.483283)
			(xy 367.67878 -145.529833) (xy 367.702504 -145.58038) (xy 367.718606 -145.633846) (xy 367.726744 -145.689087)
			(xy 367.72723 -145.717006) (xy 367.726776 -145.744) (xy 367.719169 -145.797448) (xy 367.704107 -145.849292)
			(xy 367.681891 -145.898496) (xy 367.652965 -145.94408) (xy 367.63579 -145.96491) (xy 367.628678 -145.973038)
			(xy 367.622582 -145.993612) (xy 367.633504 -146.078956) (xy 367.635295 -146.089496) (xy 367.646338 -146.107781)
			(xy 367.65484 -146.114262) (xy 367.676045 -146.12965) (xy 367.714499 -146.165231) (xy 367.74772 -146.205741)
			(xy 367.775082 -146.250419) (xy 367.79607 -146.298421) (xy 367.810288 -146.348845) (xy 367.817469 -146.400741)
			(xy 367.817908 -146.426936) (xy 367.817422 -146.454187) (xy 367.809666 -146.508135) (xy 367.794311 -146.56043)
			(xy 367.771669 -146.610007) (xy 367.742203 -146.655857) (xy 367.706512 -146.697048) (xy 367.665321 -146.732739)
			(xy 367.619471 -146.762205) (xy 367.569894 -146.784847) (xy 367.517599 -146.800202) (xy 367.463651 -146.807958)
			(xy 367.409149 -146.807958) (xy 367.355201 -146.800202) (xy 367.302906 -146.784847) (xy 367.253329 -146.762205)
			(xy 367.207479 -146.732739) (xy 367.166288 -146.697048) (xy 367.130597 -146.655857) (xy 367.101131 -146.610007)
			(xy 367.078489 -146.56043) (xy 367.063134 -146.508135) (xy 367.055378 -146.454187) (xy 367.054892 -146.426936)
			(xy 367.055365 -146.399943) (xy 367.062967 -146.346495) (xy 367.078024 -146.294651) (xy 367.100235 -146.245447)
			(xy 367.129158 -146.199862) (xy 367.146332 -146.179032) (xy 367.153444 -146.170904) (xy 367.15954 -146.15033)
			(xy 367.148618 -146.064986) (xy 367.146848 -146.054441) (xy 367.135789 -146.036159) (xy 367.127282 -146.02968)
			(xy 367.102981 -146.012068) (xy 367.059722 -145.970472) (xy 367.041176 -145.946876) (xy 367.035334 -145.939002)
			(xy 367.017808 -145.928588) (xy 366.927384 -145.91538) (xy 366.90808 -145.920206) (xy 366.900206 -145.926048)
			(xy 366.899952 -145.926048) (xy 366.87521 -145.943554) (xy 366.821357 -145.971357) (xy 366.763784 -145.990292)
			(xy 366.703941 -145.999884) (xy 366.673638 -146.00047) (xy 366.646384 -146.000009) (xy 366.592431 -145.992256)
			(xy 366.540131 -145.976903) (xy 366.490549 -145.954262) (xy 366.444693 -145.924795) (xy 366.403499 -145.889101)
			(xy 366.367805 -145.847907) (xy 366.338338 -145.802051) (xy 366.315697 -145.752469) (xy 366.300344 -145.700169)
			(xy 366.292591 -145.646216) (xy 366.29213 -145.618962) (xy 366.292566 -145.592928) (xy 366.299657 -145.541345)
			(xy 366.31369 -145.491203) (xy 366.334403 -145.443433) (xy 366.361413 -145.398918) (xy 366.377474 -145.378424)
			(xy 366.383214 -145.370666) (xy 366.388956 -145.352256) (xy 366.38865 -145.34261) (xy 366.3823 -145.262854)
			(xy 366.373664 -145.245074) (xy 366.366298 -145.238724) (xy 366.346658 -145.220536) (xy 366.312132 -145.179632)
			(xy 366.28366 -145.134305) (xy 366.261801 -145.085445) (xy 366.246983 -145.034009) (xy 366.239498 -144.981008)
			(xy 366.239044 -144.954244) (xy 360.506611 -144.954244) (xy 360.520663 -145.002096) (xy 360.528421 -145.056047)
			(xy 360.528421 -145.110553) (xy 360.520663 -145.164504) (xy 360.505306 -145.216801) (xy 360.482662 -145.266381)
			(xy 360.453193 -145.312233) (xy 360.417497 -145.353424) (xy 360.376302 -145.389115) (xy 360.330447 -145.418581)
			(xy 360.280866 -145.441219) (xy 360.228567 -145.456571) (xy 360.174615 -145.464323) (xy 360.147362 -145.464784)
			(xy 360.121047 -145.464347) (xy 360.068917 -145.457107) (xy 360.018273 -145.442782) (xy 359.970074 -145.421644)
			(xy 359.925232 -145.394092) (xy 359.884594 -145.360648) (xy 359.866438 -145.341594) (xy 359.858905 -145.334206)
			(xy 359.839634 -145.325674) (xy 359.8291 -145.325084) (xy 359.754424 -145.325084) (xy 359.743875 -145.325618)
			(xy 359.72458 -145.33415) (xy 359.717086 -145.341594) (xy 359.698929 -145.360648) (xy 359.6583 -145.394106)
			(xy 359.61346 -145.421665) (xy 359.565259 -145.442804) (xy 359.514612 -145.457121) (xy 359.462478 -145.464346)
			(xy 359.436162 -145.464784) (xy 359.408911 -145.464344) (xy 359.354964 -145.456582) (xy 359.30267 -145.441223)
			(xy 359.253095 -145.418578) (xy 359.207246 -145.389109) (xy 359.166058 -145.353415) (xy 359.130368 -145.312223)
			(xy 359.100904 -145.266372) (xy 359.078264 -145.216794) (xy 359.06291 -145.164499) (xy 359.055154 -145.110551)
			(xy 351.782725 -145.110551) (xy 351.793243 -145.132989) (xy 351.809311 -145.186396) (xy 351.817431 -145.241572)
			(xy 351.81794 -145.269458) (xy 351.817431 -145.297344) (xy 351.809311 -145.35252) (xy 351.793243 -145.405927)
			(xy 351.769571 -145.456424) (xy 351.738798 -145.502937) (xy 351.701581 -145.544474) (xy 351.658713 -145.580149)
			(xy 351.611107 -145.609203) (xy 351.559778 -145.631015) (xy 351.505821 -145.645121) (xy 351.450384 -145.651221)
			(xy 351.39465 -145.649184) (xy 351.339807 -145.639054) (xy 351.287023 -145.621047) (xy 351.237423 -145.595546)
			(xy 351.192065 -145.563095) (xy 351.151916 -145.524386) (xy 351.11783 -145.480243) (xy 351.090534 -145.431608)
			(xy 351.070611 -145.379517) (xy 351.058485 -145.32508) (xy 351.054414 -145.269458) (xy 337.19493 -145.269458)
			(xy 337.243597 -145.290139) (xy 337.291203 -145.319193) (xy 337.334071 -145.354868) (xy 337.371288 -145.396405)
			(xy 337.402061 -145.442918) (xy 337.425733 -145.493415) (xy 337.441801 -145.546822) (xy 337.449921 -145.601998)
			(xy 337.45043 -145.629884) (xy 337.449921 -145.65777) (xy 337.441801 -145.712946) (xy 337.425733 -145.766353)
			(xy 337.402061 -145.81685) (xy 337.371288 -145.863363) (xy 337.334071 -145.9049) (xy 337.291203 -145.940575)
			(xy 337.243597 -145.969629) (xy 337.192268 -145.991441) (xy 337.138311 -146.005547) (xy 337.082874 -146.011647)
			(xy 337.02714 -146.00961) (xy 336.972297 -145.99948) (xy 336.919513 -145.981473) (xy 336.869913 -145.955972)
			(xy 336.824555 -145.923521) (xy 336.784406 -145.884812) (xy 336.75032 -145.840669) (xy 336.723024 -145.792034)
			(xy 336.703101 -145.739943) (xy 336.690975 -145.685506) (xy 336.686904 -145.629884) (xy 335.2694 -145.629884)
			(xy 335.291149 -145.647984) (xy 335.328366 -145.689521) (xy 335.359139 -145.736034) (xy 335.382811 -145.786531)
			(xy 335.398879 -145.839938) (xy 335.406999 -145.895114) (xy 335.407508 -145.923) (xy 335.406999 -145.950886)
			(xy 335.398879 -146.006062) (xy 335.382811 -146.059469) (xy 335.359139 -146.109966) (xy 335.328366 -146.156479)
			(xy 335.291149 -146.198016) (xy 335.248281 -146.233691) (xy 335.200675 -146.262745) (xy 335.149346 -146.284557)
			(xy 335.095389 -146.298663) (xy 335.039952 -146.304763) (xy 334.984218 -146.302726) (xy 334.929375 -146.292596)
			(xy 334.876591 -146.274589) (xy 334.826991 -146.249088) (xy 334.781633 -146.216637) (xy 334.741484 -146.177928)
			(xy 334.707398 -146.133785) (xy 334.680102 -146.08515) (xy 334.660179 -146.033059) (xy 334.648053 -145.978622)
			(xy 334.643982 -145.923) (xy 326.089772 -145.923) (xy 326.089772 -146.50212) (xy 341.637364 -146.50212)
			(xy 341.641435 -146.446498) (xy 341.653561 -146.392061) (xy 341.673484 -146.33997) (xy 341.70078 -146.291335)
			(xy 341.734866 -146.247192) (xy 341.775015 -146.208483) (xy 341.820373 -146.176032) (xy 341.869973 -146.150531)
			(xy 341.922757 -146.132524) (xy 341.9776 -146.122394) (xy 342.033334 -146.120357) (xy 342.088771 -146.126457)
			(xy 342.142728 -146.140563) (xy 342.194057 -146.162375) (xy 342.241663 -146.191429) (xy 342.284531 -146.227104)
			(xy 342.321748 -146.268641) (xy 342.352521 -146.315154) (xy 342.376193 -146.365651) (xy 342.392261 -146.419058)
			(xy 342.400381 -146.474234) (xy 342.40089 -146.50212) (xy 342.400381 -146.530006) (xy 342.392261 -146.585182)
			(xy 342.376193 -146.638589) (xy 342.352521 -146.689086) (xy 342.321748 -146.735599) (xy 342.284531 -146.777136)
			(xy 342.241663 -146.812811) (xy 342.194057 -146.841865) (xy 342.142728 -146.863677) (xy 342.088771 -146.877783)
			(xy 342.033334 -146.883883) (xy 341.9776 -146.881846) (xy 341.922757 -146.871716) (xy 341.869973 -146.853709)
			(xy 341.820373 -146.828208) (xy 341.775015 -146.795757) (xy 341.734866 -146.757048) (xy 341.70078 -146.712905)
			(xy 341.673484 -146.66427) (xy 341.653561 -146.612179) (xy 341.641435 -146.557742) (xy 341.637364 -146.50212)
			(xy 326.089772 -146.50212) (xy 326.089772 -146.939) (xy 334.643982 -146.939) (xy 334.648053 -146.883378)
			(xy 334.660179 -146.828941) (xy 334.680102 -146.77685) (xy 334.707398 -146.728215) (xy 334.741484 -146.684072)
			(xy 334.781633 -146.645363) (xy 334.826991 -146.612912) (xy 334.876591 -146.587411) (xy 334.929375 -146.569404)
			(xy 334.984218 -146.559274) (xy 335.039952 -146.557237) (xy 335.095389 -146.563337) (xy 335.149346 -146.577443)
			(xy 335.200675 -146.599255) (xy 335.248281 -146.628309) (xy 335.291149 -146.663984) (xy 335.328366 -146.705521)
			(xy 335.359139 -146.752034) (xy 335.382811 -146.802531) (xy 335.398879 -146.855938) (xy 335.406999 -146.911114)
			(xy 335.407508 -146.939) (xy 336.675982 -146.939) (xy 336.680053 -146.883378) (xy 336.692179 -146.828941)
			(xy 336.712102 -146.77685) (xy 336.739398 -146.728215) (xy 336.773484 -146.684072) (xy 336.813633 -146.645363)
			(xy 336.858991 -146.612912) (xy 336.908591 -146.587411) (xy 336.961375 -146.569404) (xy 337.016218 -146.559274)
			(xy 337.071952 -146.557237) (xy 337.127389 -146.563337) (xy 337.181346 -146.577443) (xy 337.232675 -146.599255)
			(xy 337.280281 -146.628309) (xy 337.323149 -146.663984) (xy 337.360366 -146.705521) (xy 337.391139 -146.752034)
			(xy 337.414811 -146.802531) (xy 337.430879 -146.855938) (xy 337.438999 -146.911114) (xy 337.439508 -146.939)
			(xy 337.438999 -146.966886) (xy 337.430879 -147.022062) (xy 337.414811 -147.075469) (xy 337.391139 -147.125966)
			(xy 337.373845 -147.152106) (xy 340.499444 -147.152106) (xy 340.503515 -147.096484) (xy 340.515641 -147.042047)
			(xy 340.535564 -146.989956) (xy 340.56286 -146.941321) (xy 340.596946 -146.897178) (xy 340.637095 -146.858469)
			(xy 340.682453 -146.826018) (xy 340.732053 -146.800517) (xy 340.784837 -146.78251) (xy 340.83968 -146.77238)
			(xy 340.895414 -146.770343) (xy 340.950851 -146.776443) (xy 341.004808 -146.790549) (xy 341.056137 -146.812361)
			(xy 341.103743 -146.841415) (xy 341.146611 -146.87709) (xy 341.180462 -146.91487) (xy 367.916204 -146.91487)
			(xy 367.920275 -146.859248) (xy 367.932401 -146.804811) (xy 367.952324 -146.75272) (xy 367.97962 -146.704085)
			(xy 368.013706 -146.659942) (xy 368.053855 -146.621233) (xy 368.099213 -146.588782) (xy 368.148813 -146.563281)
			(xy 368.201597 -146.545274) (xy 368.25644 -146.535144) (xy 368.312174 -146.533107) (xy 368.367611 -146.539207)
			(xy 368.421568 -146.553313) (xy 368.472897 -146.575125) (xy 368.520503 -146.604179) (xy 368.563371 -146.639854)
			(xy 368.600588 -146.681391) (xy 368.631361 -146.727904) (xy 368.655033 -146.778401) (xy 368.671101 -146.831808)
			(xy 368.679221 -146.886984) (xy 368.67973 -146.91487) (xy 368.679221 -146.942756) (xy 368.671101 -146.997932)
			(xy 368.655033 -147.051339) (xy 368.649827 -147.062444) (xy 369.294408 -147.062444) (xy 369.298479 -147.006822)
			(xy 369.310605 -146.952385) (xy 369.330528 -146.900294) (xy 369.357824 -146.851659) (xy 369.39191 -146.807516)
			(xy 369.432059 -146.768807) (xy 369.477417 -146.736356) (xy 369.527017 -146.710855) (xy 369.579801 -146.692848)
			(xy 369.634644 -146.682718) (xy 369.690378 -146.680681) (xy 369.745815 -146.686781) (xy 369.799772 -146.700887)
			(xy 369.851101 -146.722699) (xy 369.898707 -146.751753) (xy 369.941575 -146.787428) (xy 369.978792 -146.828965)
			(xy 370.009565 -146.875478) (xy 370.033237 -146.925975) (xy 370.049305 -146.979382) (xy 370.057425 -147.034558)
			(xy 370.057934 -147.062444) (xy 370.057425 -147.09033) (xy 370.049305 -147.145506) (xy 370.033237 -147.198913)
			(xy 370.009565 -147.24941) (xy 369.978792 -147.295923) (xy 369.941575 -147.33746) (xy 369.898707 -147.373135)
			(xy 369.851101 -147.402189) (xy 369.799772 -147.424001) (xy 369.745815 -147.438107) (xy 369.690378 -147.444207)
			(xy 369.634644 -147.44217) (xy 369.579801 -147.43204) (xy 369.527017 -147.414033) (xy 369.477417 -147.388532)
			(xy 369.432059 -147.356081) (xy 369.39191 -147.317372) (xy 369.357824 -147.273229) (xy 369.330528 -147.224594)
			(xy 369.310605 -147.172503) (xy 369.298479 -147.118066) (xy 369.294408 -147.062444) (xy 368.649827 -147.062444)
			(xy 368.631361 -147.101836) (xy 368.600588 -147.148349) (xy 368.563371 -147.189886) (xy 368.520503 -147.225561)
			(xy 368.472897 -147.254615) (xy 368.421568 -147.276427) (xy 368.367611 -147.290533) (xy 368.312174 -147.296633)
			(xy 368.25644 -147.294596) (xy 368.201597 -147.284466) (xy 368.148813 -147.266459) (xy 368.099213 -147.240958)
			(xy 368.053855 -147.208507) (xy 368.013706 -147.169798) (xy 367.97962 -147.125655) (xy 367.952324 -147.07702)
			(xy 367.932401 -147.024929) (xy 367.920275 -146.970492) (xy 367.916204 -146.91487) (xy 341.180462 -146.91487)
			(xy 341.183828 -146.918627) (xy 341.214601 -146.96514) (xy 341.238273 -147.015637) (xy 341.254341 -147.069044)
			(xy 341.262461 -147.12422) (xy 341.26297 -147.152106) (xy 341.262461 -147.179992) (xy 341.254341 -147.235168)
			(xy 341.238273 -147.288575) (xy 341.214601 -147.339072) (xy 341.183828 -147.385585) (xy 341.146611 -147.427122)
			(xy 341.103743 -147.462797) (xy 341.056137 -147.491851) (xy 341.004808 -147.513663) (xy 340.950851 -147.527769)
			(xy 340.895414 -147.533869) (xy 340.83968 -147.531832) (xy 340.784837 -147.521702) (xy 340.732053 -147.503695)
			(xy 340.682453 -147.478194) (xy 340.637095 -147.445743) (xy 340.596946 -147.407034) (xy 340.56286 -147.362891)
			(xy 340.535564 -147.314256) (xy 340.515641 -147.262165) (xy 340.503515 -147.207728) (xy 340.499444 -147.152106)
			(xy 337.373845 -147.152106) (xy 337.360366 -147.172479) (xy 337.323149 -147.214016) (xy 337.280281 -147.249691)
			(xy 337.232675 -147.278745) (xy 337.181346 -147.300557) (xy 337.127389 -147.314663) (xy 337.071952 -147.320763)
			(xy 337.016218 -147.318726) (xy 336.961375 -147.308596) (xy 336.908591 -147.290589) (xy 336.858991 -147.265088)
			(xy 336.813633 -147.232637) (xy 336.773484 -147.193928) (xy 336.739398 -147.149785) (xy 336.712102 -147.10115)
			(xy 336.692179 -147.049059) (xy 336.680053 -146.994622) (xy 336.675982 -146.939) (xy 335.407508 -146.939)
			(xy 335.406999 -146.966886) (xy 335.398879 -147.022062) (xy 335.382811 -147.075469) (xy 335.359139 -147.125966)
			(xy 335.328366 -147.172479) (xy 335.291149 -147.214016) (xy 335.248281 -147.249691) (xy 335.200675 -147.278745)
			(xy 335.149346 -147.300557) (xy 335.095389 -147.314663) (xy 335.039952 -147.320763) (xy 334.984218 -147.318726)
			(xy 334.929375 -147.308596) (xy 334.876591 -147.290589) (xy 334.826991 -147.265088) (xy 334.781633 -147.232637)
			(xy 334.741484 -147.193928) (xy 334.707398 -147.149785) (xy 334.680102 -147.10115) (xy 334.660179 -147.049059)
			(xy 334.648053 -146.994622) (xy 334.643982 -146.939) (xy 326.089772 -146.939) (xy 326.089772 -147.802092)
			(xy 341.637364 -147.802092) (xy 341.641435 -147.74647) (xy 341.653561 -147.692033) (xy 341.673484 -147.639942)
			(xy 341.70078 -147.591307) (xy 341.734866 -147.547164) (xy 341.775015 -147.508455) (xy 341.820373 -147.476004)
			(xy 341.869973 -147.450503) (xy 341.922757 -147.432496) (xy 341.9776 -147.422366) (xy 342.033334 -147.420329)
			(xy 342.088771 -147.426429) (xy 342.142728 -147.440535) (xy 342.194057 -147.462347) (xy 342.241663 -147.491401)
			(xy 342.284531 -147.527076) (xy 342.321748 -147.568613) (xy 342.352521 -147.615126) (xy 342.370987 -147.654518)
			(xy 350.89973 -147.654518) (xy 350.900216 -147.627267) (xy 350.907972 -147.573319) (xy 350.923327 -147.521024)
			(xy 350.945969 -147.471447) (xy 350.975435 -147.425597) (xy 351.011126 -147.384406) (xy 351.052317 -147.348715)
			(xy 351.098167 -147.319249) (xy 351.147744 -147.296607) (xy 351.200039 -147.281252) (xy 351.253987 -147.273496)
			(xy 351.308489 -147.273496) (xy 351.362437 -147.281252) (xy 351.414732 -147.296607) (xy 351.464309 -147.319249)
			(xy 351.510159 -147.348715) (xy 351.55135 -147.384406) (xy 351.587041 -147.425597) (xy 351.616507 -147.471447)
			(xy 351.639149 -147.521024) (xy 351.654504 -147.573319) (xy 351.66226 -147.627267) (xy 351.662746 -147.654518)
			(xy 352.95408 -147.654518) (xy 352.958151 -147.598896) (xy 352.970277 -147.544459) (xy 352.9902 -147.492368)
			(xy 353.017496 -147.443733) (xy 353.051582 -147.39959) (xy 353.091731 -147.360881) (xy 353.137089 -147.32843)
			(xy 353.186689 -147.302929) (xy 353.239473 -147.284922) (xy 353.294316 -147.274792) (xy 353.35005 -147.272755)
			(xy 353.405487 -147.278855) (xy 353.459444 -147.292961) (xy 353.510773 -147.314773) (xy 353.558379 -147.343827)
			(xy 353.601247 -147.379502) (xy 353.638464 -147.421039) (xy 353.669237 -147.467552) (xy 353.692909 -147.518049)
			(xy 353.708977 -147.571456) (xy 353.717097 -147.626632) (xy 353.717606 -147.654518) (xy 353.717549 -147.657656)
			(xy 359.450543 -147.657656) (xy 359.450543 -147.603144) (xy 359.458301 -147.549188) (xy 359.47366 -147.496885)
			(xy 359.496306 -147.447301) (xy 359.525779 -147.401445) (xy 359.561478 -147.360249) (xy 359.602677 -147.324555)
			(xy 359.648536 -147.295087) (xy 359.698123 -147.272446) (xy 359.750427 -147.257093) (xy 359.804384 -147.24934)
			(xy 359.83164 -147.24888) (xy 359.857955 -147.249327) (xy 359.910084 -147.256567) (xy 359.960727 -147.270891)
			(xy 360.008925 -147.292027) (xy 360.053768 -147.319576) (xy 360.094408 -147.353017) (xy 360.112564 -147.37207)
			(xy 360.120101 -147.379453) (xy 360.139369 -147.387989) (xy 360.149902 -147.38858) (xy 360.224578 -147.38858)
			(xy 360.235129 -147.388058) (xy 360.254424 -147.379519) (xy 360.261916 -147.37207) (xy 360.281736 -147.351282)
			(xy 360.326508 -147.315307) (xy 360.376166 -147.286447) (xy 360.429588 -147.265354) (xy 360.485567 -147.252505)
			(xy 360.54284 -147.24819) (xy 360.600113 -147.252505) (xy 360.656092 -147.265354) (xy 360.709514 -147.286447)
			(xy 360.759172 -147.315307) (xy 360.803944 -147.351282) (xy 360.823764 -147.37207) (xy 360.831301 -147.379453)
			(xy 360.850569 -147.387989) (xy 360.861102 -147.38858) (xy 360.935778 -147.38858) (xy 360.946329 -147.388058)
			(xy 360.965624 -147.379519) (xy 360.973116 -147.37207) (xy 360.991265 -147.353008) (xy 361.031897 -147.319553)
			(xy 361.076739 -147.291995) (xy 361.124941 -147.270858) (xy 361.175589 -147.256542) (xy 361.227724 -147.249318)
			(xy 361.25404 -147.24888) (xy 361.281288 -147.249393) (xy 361.33523 -147.257154) (xy 361.387518 -147.272512)
			(xy 361.437089 -147.295155) (xy 361.482933 -147.324621) (xy 361.524117 -147.360311) (xy 361.559803 -147.401499)
			(xy 361.589265 -147.447346) (xy 361.611902 -147.496919) (xy 361.627255 -147.549209) (xy 361.63501 -147.603151)
			(xy 361.63501 -147.657649) (xy 361.627255 -147.711591) (xy 361.611902 -147.763881) (xy 361.589265 -147.813454)
			(xy 361.559803 -147.859301) (xy 361.524117 -147.900489) (xy 361.482933 -147.936179) (xy 361.437089 -147.965645)
			(xy 361.387518 -147.988288) (xy 361.33523 -148.003646) (xy 361.281288 -148.011407) (xy 361.25404 -148.011896)
			(xy 361.227725 -148.01147) (xy 361.175594 -148.004227) (xy 361.124951 -147.9899) (xy 361.076752 -147.968759)
			(xy 361.031909 -147.941206) (xy 360.991271 -147.907761) (xy 360.973116 -147.888706) (xy 360.965589 -147.88131)
			(xy 360.946313 -147.872782) (xy 360.935778 -147.872196) (xy 360.861102 -147.872196) (xy 360.850551 -147.872714)
			(xy 360.831256 -147.881257) (xy 360.823764 -147.888706) (xy 360.803944 -147.909494) (xy 360.759172 -147.945469)
			(xy 360.709514 -147.974329) (xy 360.656092 -147.995422) (xy 360.600113 -148.008271) (xy 360.54284 -148.012586)
			(xy 360.485567 -148.008271) (xy 360.429588 -147.995422) (xy 360.376166 -147.974329) (xy 360.326508 -147.945469)
			(xy 360.281736 -147.909494) (xy 360.261916 -147.888706) (xy 360.254389 -147.88131) (xy 360.235113 -147.872782)
			(xy 360.224578 -147.872196) (xy 360.149902 -147.872196) (xy 360.139351 -147.872714) (xy 360.120056 -147.881257)
			(xy 360.112564 -147.888706) (xy 360.09442 -147.907773) (xy 360.053788 -147.941229) (xy 360.008945 -147.968786)
			(xy 359.960742 -147.989923) (xy 359.910092 -148.004237) (xy 359.857957 -148.011459) (xy 359.83164 -148.011896)
			(xy 359.804384 -148.01146) (xy 359.750427 -148.003707) (xy 359.698123 -147.988354) (xy 359.648536 -147.965713)
			(xy 359.602677 -147.936245) (xy 359.561478 -147.900551) (xy 359.525779 -147.859355) (xy 359.496306 -147.813499)
			(xy 359.47366 -147.763915) (xy 359.458301 -147.711612) (xy 359.450543 -147.657656) (xy 353.717549 -147.657656)
			(xy 353.717097 -147.682404) (xy 353.708977 -147.73758) (xy 353.692909 -147.790987) (xy 353.669237 -147.841484)
			(xy 353.638464 -147.887997) (xy 353.601247 -147.929534) (xy 353.558379 -147.965209) (xy 353.510773 -147.994263)
			(xy 353.459444 -148.016075) (xy 353.453083 -148.017738) (xy 364.277654 -148.017738) (xy 364.281725 -147.962116)
			(xy 364.293851 -147.907679) (xy 364.313774 -147.855588) (xy 364.34107 -147.806953) (xy 364.375156 -147.76281)
			(xy 364.415305 -147.724101) (xy 364.460663 -147.69165) (xy 364.510263 -147.666149) (xy 364.563047 -147.648142)
			(xy 364.61789 -147.638012) (xy 364.673624 -147.635975) (xy 364.729061 -147.642075) (xy 364.783018 -147.656181)
			(xy 364.834347 -147.677993) (xy 364.881953 -147.707047) (xy 364.923216 -147.741386) (xy 370.18163 -147.741386)
			(xy 370.185701 -147.685764) (xy 370.197827 -147.631327) (xy 370.21775 -147.579236) (xy 370.245046 -147.530601)
			(xy 370.279132 -147.486458) (xy 370.319281 -147.447749) (xy 370.364639 -147.415298) (xy 370.414239 -147.389797)
			(xy 370.467023 -147.37179) (xy 370.521866 -147.36166) (xy 370.5776 -147.359623) (xy 370.633037 -147.365723)
			(xy 370.686994 -147.379829) (xy 370.738323 -147.401641) (xy 370.785929 -147.430695) (xy 370.828797 -147.46637)
			(xy 370.866014 -147.507907) (xy 370.896787 -147.55442) (xy 370.920459 -147.604917) (xy 370.936527 -147.658324)
			(xy 370.944647 -147.7135) (xy 370.945156 -147.741386) (xy 370.944647 -147.769272) (xy 370.936527 -147.824448)
			(xy 370.920459 -147.877855) (xy 370.896787 -147.928352) (xy 370.866014 -147.974865) (xy 370.828797 -148.016402)
			(xy 370.785929 -148.052077) (xy 370.738323 -148.081131) (xy 370.686994 -148.102943) (xy 370.633037 -148.117049)
			(xy 370.5776 -148.123149) (xy 370.521866 -148.121112) (xy 370.467023 -148.110982) (xy 370.414239 -148.092975)
			(xy 370.364639 -148.067474) (xy 370.319281 -148.035023) (xy 370.279132 -147.996314) (xy 370.245046 -147.952171)
			(xy 370.21775 -147.903536) (xy 370.197827 -147.851445) (xy 370.185701 -147.797008) (xy 370.18163 -147.741386)
			(xy 364.923216 -147.741386) (xy 364.924821 -147.742722) (xy 364.962038 -147.784259) (xy 364.992811 -147.830772)
			(xy 365.016483 -147.881269) (xy 365.032551 -147.934676) (xy 365.040671 -147.989852) (xy 365.04118 -148.017738)
			(xy 365.040671 -148.045624) (xy 365.032551 -148.1008) (xy 365.016483 -148.154207) (xy 364.992811 -148.204704)
			(xy 364.962038 -148.251217) (xy 364.924821 -148.292754) (xy 364.881953 -148.328429) (xy 364.834347 -148.357483)
			(xy 364.783018 -148.379295) (xy 364.729061 -148.393401) (xy 364.673624 -148.399501) (xy 364.61789 -148.397464)
			(xy 364.563047 -148.387334) (xy 364.510263 -148.369327) (xy 364.460663 -148.343826) (xy 364.415305 -148.311375)
			(xy 364.375156 -148.272666) (xy 364.34107 -148.228523) (xy 364.313774 -148.179888) (xy 364.293851 -148.127797)
			(xy 364.281725 -148.07336) (xy 364.277654 -148.017738) (xy 353.453083 -148.017738) (xy 353.405487 -148.030181)
			(xy 353.35005 -148.036281) (xy 353.294316 -148.034244) (xy 353.239473 -148.024114) (xy 353.186689 -148.006107)
			(xy 353.137089 -147.980606) (xy 353.091731 -147.948155) (xy 353.051582 -147.909446) (xy 353.017496 -147.865303)
			(xy 352.9902 -147.816668) (xy 352.970277 -147.764577) (xy 352.958151 -147.71014) (xy 352.95408 -147.654518)
			(xy 351.662746 -147.654518) (xy 351.662331 -147.681517) (xy 351.654726 -147.734977) (xy 351.639657 -147.78683)
			(xy 351.617425 -147.836039) (xy 351.588474 -147.881621) (xy 351.553384 -147.922663) (xy 351.512855 -147.958345)
			(xy 351.490534 -147.973542) (xy 351.478774 -147.981858) (xy 351.460084 -148.003757) (xy 351.448242 -148.029999)
			(xy 351.444188 -148.058503) (xy 351.448244 -148.087006) (xy 351.460087 -148.113247) (xy 351.478778 -148.135145)
			(xy 351.490534 -148.143468) (xy 351.512908 -148.158695) (xy 351.553587 -148.194389) (xy 351.588816 -148.235471)
			(xy 351.617889 -148.281117) (xy 351.640223 -148.330412) (xy 351.655371 -148.382367) (xy 351.663029 -148.435941)
			(xy 351.663508 -148.463) (xy 351.663022 -148.490251) (xy 351.655266 -148.544199) (xy 351.639911 -148.596494)
			(xy 351.617269 -148.646071) (xy 351.587803 -148.691921) (xy 351.552112 -148.733112) (xy 351.510921 -148.768803)
			(xy 351.465071 -148.798269) (xy 351.415494 -148.820911) (xy 351.363199 -148.836266) (xy 351.309251 -148.844022)
			(xy 351.254749 -148.844022) (xy 351.200801 -148.836266) (xy 351.148506 -148.820911) (xy 351.098929 -148.798269)
			(xy 351.053079 -148.768803) (xy 351.011888 -148.733112) (xy 350.976197 -148.691921) (xy 350.946731 -148.646071)
			(xy 350.924089 -148.596494) (xy 350.908734 -148.544199) (xy 350.900978 -148.490251) (xy 350.900492 -148.463)
			(xy 350.900949 -148.436003) (xy 350.90855 -148.382546) (xy 350.923614 -148.330695) (xy 350.94584 -148.281487)
			(xy 350.974783 -148.235905) (xy 351.009866 -148.194861) (xy 351.050387 -148.159175) (xy 351.072704 -148.143976)
			(xy 351.08449 -148.135666) (xy 351.103264 -148.113794) (xy 351.115165 -148.087541) (xy 351.119242 -148.059007)
			(xy 351.115169 -148.030472) (xy 351.103272 -148.004218) (xy 351.084501 -147.982344) (xy 351.072704 -147.97405)
			(xy 351.0503 -147.958864) (xy 351.009621 -147.923164) (xy 350.974393 -147.882076) (xy 350.945322 -147.836423)
			(xy 350.922992 -147.787121) (xy 350.907852 -147.735159) (xy 350.900203 -147.681579) (xy 350.89973 -147.654518)
			(xy 342.370987 -147.654518) (xy 342.376193 -147.665623) (xy 342.392261 -147.71903) (xy 342.400381 -147.774206)
			(xy 342.40089 -147.802092) (xy 342.400381 -147.829978) (xy 342.392261 -147.885154) (xy 342.376193 -147.938561)
			(xy 342.352521 -147.989058) (xy 342.321748 -148.035571) (xy 342.284531 -148.077108) (xy 342.241663 -148.112783)
			(xy 342.194057 -148.141837) (xy 342.142728 -148.163649) (xy 342.088771 -148.177755) (xy 342.033334 -148.183855)
			(xy 341.9776 -148.181818) (xy 341.922757 -148.171688) (xy 341.869973 -148.153681) (xy 341.820373 -148.12818)
			(xy 341.775015 -148.095729) (xy 341.734866 -148.05702) (xy 341.70078 -148.012877) (xy 341.673484 -147.964242)
			(xy 341.653561 -147.912151) (xy 341.641435 -147.857714) (xy 341.637364 -147.802092) (xy 326.089772 -147.802092)
			(xy 326.089772 -148.291804) (xy 336.675982 -148.291804) (xy 336.680053 -148.236182) (xy 336.692179 -148.181745)
			(xy 336.712102 -148.129654) (xy 336.739398 -148.081019) (xy 336.773484 -148.036876) (xy 336.813633 -147.998167)
			(xy 336.858991 -147.965716) (xy 336.908591 -147.940215) (xy 336.961375 -147.922208) (xy 337.016218 -147.912078)
			(xy 337.071952 -147.910041) (xy 337.127389 -147.916141) (xy 337.181346 -147.930247) (xy 337.232675 -147.952059)
			(xy 337.280281 -147.981113) (xy 337.323149 -148.016788) (xy 337.360366 -148.058325) (xy 337.391139 -148.104838)
			(xy 337.414811 -148.155335) (xy 337.430879 -148.208742) (xy 337.438999 -148.263918) (xy 337.439508 -148.291804)
			(xy 337.438999 -148.31969) (xy 337.430879 -148.374866) (xy 337.414811 -148.428273) (xy 337.403652 -148.452078)
			(xy 349.87306 -148.452078) (xy 349.877131 -148.396456) (xy 349.889257 -148.342019) (xy 349.90918 -148.289928)
			(xy 349.936476 -148.241293) (xy 349.970562 -148.19715) (xy 350.010711 -148.158441) (xy 350.056069 -148.12599)
			(xy 350.105669 -148.100489) (xy 350.158453 -148.082482) (xy 350.213296 -148.072352) (xy 350.26903 -148.070315)
			(xy 350.324467 -148.076415) (xy 350.378424 -148.090521) (xy 350.429753 -148.112333) (xy 350.477359 -148.141387)
			(xy 350.520227 -148.177062) (xy 350.557444 -148.218599) (xy 350.588217 -148.265112) (xy 350.611889 -148.315609)
			(xy 350.627957 -148.369016) (xy 350.636077 -148.424192) (xy 350.636586 -148.452078) (xy 350.636077 -148.479964)
			(xy 350.627957 -148.53514) (xy 350.611889 -148.588547) (xy 350.588217 -148.639044) (xy 350.557444 -148.685557)
			(xy 350.520227 -148.727094) (xy 350.477359 -148.762769) (xy 350.429753 -148.791823) (xy 350.378424 -148.813635)
			(xy 350.324467 -148.827741) (xy 350.26903 -148.833841) (xy 350.213296 -148.831804) (xy 350.158453 -148.821674)
			(xy 350.105669 -148.803667) (xy 350.056069 -148.778166) (xy 350.010711 -148.745715) (xy 349.970562 -148.707006)
			(xy 349.936476 -148.662863) (xy 349.90918 -148.614228) (xy 349.889257 -148.562137) (xy 349.877131 -148.5077)
			(xy 349.87306 -148.452078) (xy 337.403652 -148.452078) (xy 337.391139 -148.47877) (xy 337.360366 -148.525283)
			(xy 337.323149 -148.56682) (xy 337.280281 -148.602495) (xy 337.232675 -148.631549) (xy 337.181346 -148.653361)
			(xy 337.127389 -148.667467) (xy 337.071952 -148.673567) (xy 337.016218 -148.67153) (xy 336.961375 -148.6614)
			(xy 336.908591 -148.643393) (xy 336.858991 -148.617892) (xy 336.813633 -148.585441) (xy 336.773484 -148.546732)
			(xy 336.739398 -148.502589) (xy 336.712102 -148.453954) (xy 336.692179 -148.401863) (xy 336.680053 -148.347426)
			(xy 336.675982 -148.291804) (xy 326.089772 -148.291804) (xy 326.089772 -148.971) (xy 334.643982 -148.971)
			(xy 334.648053 -148.915378) (xy 334.660179 -148.860941) (xy 334.680102 -148.80885) (xy 334.707398 -148.760215)
			(xy 334.741484 -148.716072) (xy 334.781633 -148.677363) (xy 334.826991 -148.644912) (xy 334.876591 -148.619411)
			(xy 334.929375 -148.601404) (xy 334.984218 -148.591274) (xy 335.039952 -148.589237) (xy 335.095389 -148.595337)
			(xy 335.149346 -148.609443) (xy 335.200675 -148.631255) (xy 335.248281 -148.660309) (xy 335.291149 -148.695984)
			(xy 335.328366 -148.737521) (xy 335.359139 -148.784034) (xy 335.382811 -148.834531) (xy 335.395823 -148.877782)
			(xy 340.11057 -148.877782) (xy 340.114641 -148.82216) (xy 340.126767 -148.767723) (xy 340.14669 -148.715632)
			(xy 340.173986 -148.666997) (xy 340.208072 -148.622854) (xy 340.248221 -148.584145) (xy 340.293579 -148.551694)
			(xy 340.343179 -148.526193) (xy 340.395963 -148.508186) (xy 340.450806 -148.498056) (xy 340.50654 -148.496019)
			(xy 340.561977 -148.502119) (xy 340.615934 -148.516225) (xy 340.667263 -148.538037) (xy 340.714869 -148.567091)
			(xy 340.757737 -148.602766) (xy 340.794954 -148.644303) (xy 340.825727 -148.690816) (xy 340.849399 -148.741313)
			(xy 340.865467 -148.79472) (xy 340.873587 -148.849896) (xy 340.874096 -148.877782) (xy 340.873587 -148.905668)
			(xy 340.865467 -148.960844) (xy 340.849399 -149.014251) (xy 340.825727 -149.064748) (xy 340.794954 -149.111261)
			(xy 340.757737 -149.152798) (xy 340.714869 -149.188473) (xy 340.667263 -149.217527) (xy 340.615934 -149.239339)
			(xy 340.561977 -149.253445) (xy 340.50654 -149.259545) (xy 340.450806 -149.257508) (xy 340.395963 -149.247378)
			(xy 340.343179 -149.229371) (xy 340.293579 -149.20387) (xy 340.248221 -149.171419) (xy 340.208072 -149.13271)
			(xy 340.173986 -149.088567) (xy 340.14669 -149.039932) (xy 340.126767 -148.987841) (xy 340.114641 -148.933404)
			(xy 340.11057 -148.877782) (xy 335.395823 -148.877782) (xy 335.398879 -148.887938) (xy 335.406999 -148.943114)
			(xy 335.407508 -148.971) (xy 335.406999 -148.998886) (xy 335.398879 -149.054062) (xy 335.382811 -149.107469)
			(xy 335.359139 -149.157966) (xy 335.328366 -149.204479) (xy 335.291149 -149.246016) (xy 335.248281 -149.281691)
			(xy 335.200675 -149.310745) (xy 335.149346 -149.332557) (xy 335.095389 -149.346663) (xy 335.039952 -149.352763)
			(xy 334.984218 -149.350726) (xy 334.929375 -149.340596) (xy 334.876591 -149.322589) (xy 334.826991 -149.297088)
			(xy 334.781633 -149.264637) (xy 334.741484 -149.225928) (xy 334.707398 -149.181785) (xy 334.680102 -149.13315)
			(xy 334.660179 -149.081059) (xy 334.648053 -149.026622) (xy 334.643982 -148.971) (xy 326.089772 -148.971)
			(xy 326.089772 -149.987) (xy 334.643982 -149.987) (xy 334.648053 -149.931378) (xy 334.660179 -149.876941)
			(xy 334.680102 -149.82485) (xy 334.707398 -149.776215) (xy 334.741484 -149.732072) (xy 334.781633 -149.693363)
			(xy 334.826991 -149.660912) (xy 334.876591 -149.635411) (xy 334.929375 -149.617404) (xy 334.984218 -149.607274)
			(xy 335.039952 -149.605237) (xy 335.095389 -149.611337) (xy 335.149346 -149.625443) (xy 335.200675 -149.647255)
			(xy 335.248281 -149.676309) (xy 335.291149 -149.711984) (xy 335.328366 -149.753521) (xy 335.359139 -149.800034)
			(xy 335.382811 -149.850531) (xy 335.398879 -149.903938) (xy 335.406999 -149.959114) (xy 335.407313 -149.976332)
			(xy 340.739982 -149.976332) (xy 340.744053 -149.92071) (xy 340.756179 -149.866273) (xy 340.776102 -149.814182)
			(xy 340.803398 -149.765547) (xy 340.837484 -149.721404) (xy 340.877633 -149.682695) (xy 340.922991 -149.650244)
			(xy 340.972591 -149.624743) (xy 341.025375 -149.606736) (xy 341.080218 -149.596606) (xy 341.135952 -149.594569)
			(xy 341.191389 -149.600669) (xy 341.245346 -149.614775) (xy 341.296675 -149.636587) (xy 341.344281 -149.665641)
			(xy 341.387149 -149.701316) (xy 341.424366 -149.742853) (xy 341.455139 -149.789366) (xy 341.478811 -149.839863)
			(xy 341.494879 -149.89327) (xy 341.502999 -149.948446) (xy 341.503355 -149.96795) (xy 351.007932 -149.96795)
			(xy 351.012003 -149.912328) (xy 351.024129 -149.857891) (xy 351.044052 -149.8058) (xy 351.071348 -149.757165)
			(xy 351.105434 -149.713022) (xy 351.145583 -149.674313) (xy 351.190941 -149.641862) (xy 351.240541 -149.616361)
			(xy 351.293325 -149.598354) (xy 351.348168 -149.588224) (xy 351.403902 -149.586187) (xy 351.459339 -149.592287)
			(xy 351.513296 -149.606393) (xy 351.564625 -149.628205) (xy 351.612231 -149.657259) (xy 351.655099 -149.692934)
			(xy 351.692316 -149.734471) (xy 351.723089 -149.780984) (xy 351.746761 -149.831481) (xy 351.762829 -149.884888)
			(xy 351.770949 -149.940064) (xy 351.771458 -149.96795) (xy 351.770949 -149.995836) (xy 351.762829 -150.051012)
			(xy 351.746761 -150.104419) (xy 351.723089 -150.154916) (xy 351.696004 -150.195854) (xy 359.450565 -150.195854)
			(xy 359.450565 -150.141346) (xy 359.458323 -150.087393) (xy 359.473681 -150.035093) (xy 359.496326 -149.985512)
			(xy 359.525797 -149.939658) (xy 359.561494 -149.898465) (xy 359.60269 -149.862773) (xy 359.648547 -149.833307)
			(xy 359.698131 -149.810667) (xy 359.750432 -149.795315) (xy 359.804386 -149.787563) (xy 359.83164 -149.787102)
			(xy 359.857955 -149.787542) (xy 359.910085 -149.794782) (xy 359.960728 -149.809107) (xy 360.008927 -149.830244)
			(xy 360.05377 -149.857795) (xy 360.094408 -149.891238) (xy 360.112564 -149.910292) (xy 360.120098 -149.917679)
			(xy 360.139369 -149.926212) (xy 360.149902 -149.926802) (xy 360.224578 -149.926802) (xy 360.235128 -149.926274)
			(xy 360.254423 -149.917738) (xy 360.261916 -149.910292) (xy 360.281736 -149.889504) (xy 360.326508 -149.853529)
			(xy 360.376166 -149.824669) (xy 360.429588 -149.803576) (xy 360.485567 -149.790727) (xy 360.54284 -149.786412)
			(xy 360.600113 -149.790727) (xy 360.656092 -149.803576) (xy 360.709514 -149.824669) (xy 360.759172 -149.853529)
			(xy 360.803944 -149.889504) (xy 360.823764 -149.910292) (xy 360.831298 -149.917679) (xy 360.850569 -149.926212)
			(xy 360.861102 -149.926802) (xy 360.935778 -149.926802) (xy 360.946328 -149.926274) (xy 360.965623 -149.917738)
			(xy 360.973116 -149.910292) (xy 360.991269 -149.891234) (xy 361.0319 -149.857778) (xy 361.07674 -149.830219)
			(xy 361.124942 -149.809081) (xy 361.175589 -149.794764) (xy 361.227724 -149.78754) (xy 361.25404 -149.787102)
			(xy 361.28129 -149.787571) (xy 361.335235 -149.795332) (xy 361.387526 -149.810691) (xy 361.4371 -149.833335)
			(xy 361.482946 -149.862803) (xy 361.524133 -149.898495) (xy 361.559821 -149.939686) (xy 361.589284 -149.985535)
			(xy 361.611923 -150.035111) (xy 361.627277 -150.087404) (xy 361.6311 -150.114) (xy 363.091982 -150.114)
			(xy 363.096053 -150.058378) (xy 363.108179 -150.003941) (xy 363.128102 -149.95185) (xy 363.155398 -149.903215)
			(xy 363.189484 -149.859072) (xy 363.229633 -149.820363) (xy 363.274991 -149.787912) (xy 363.324591 -149.762411)
			(xy 363.377375 -149.744404) (xy 363.432218 -149.734274) (xy 363.487952 -149.732237) (xy 363.543389 -149.738337)
			(xy 363.597346 -149.752443) (xy 363.648675 -149.774255) (xy 363.696281 -149.803309) (xy 363.739149 -149.838984)
			(xy 363.776366 -149.880521) (xy 363.807139 -149.927034) (xy 363.830811 -149.977531) (xy 363.846879 -150.030938)
			(xy 363.851664 -150.063454) (xy 364.138208 -150.063454) (xy 364.142279 -150.007832) (xy 364.154405 -149.953395)
			(xy 364.174328 -149.901304) (xy 364.201624 -149.852669) (xy 364.23571 -149.808526) (xy 364.275859 -149.769817)
			(xy 364.321217 -149.737366) (xy 364.370817 -149.711865) (xy 364.423601 -149.693858) (xy 364.478444 -149.683728)
			(xy 364.534178 -149.681691) (xy 364.589615 -149.687791) (xy 364.643572 -149.701897) (xy 364.694901 -149.723709)
			(xy 364.742507 -149.752763) (xy 364.785375 -149.788438) (xy 364.822592 -149.829975) (xy 364.853365 -149.876488)
			(xy 364.877037 -149.926985) (xy 364.893105 -149.980392) (xy 364.901225 -150.035568) (xy 364.901734 -150.063454)
			(xy 364.901225 -150.09134) (xy 364.893105 -150.146516) (xy 364.877037 -150.199923) (xy 364.853365 -150.25042)
			(xy 364.822592 -150.296933) (xy 364.785375 -150.33847) (xy 364.742507 -150.374145) (xy 364.694901 -150.403199)
			(xy 364.643572 -150.425011) (xy 364.589615 -150.439117) (xy 364.534178 -150.445217) (xy 364.478444 -150.44318)
			(xy 364.423601 -150.43305) (xy 364.370817 -150.415043) (xy 364.321217 -150.389542) (xy 364.275859 -150.357091)
			(xy 364.23571 -150.318382) (xy 364.201624 -150.274239) (xy 364.174328 -150.225604) (xy 364.154405 -150.173513)
			(xy 364.142279 -150.119076) (xy 364.138208 -150.063454) (xy 363.851664 -150.063454) (xy 363.854999 -150.086114)
			(xy 363.855508 -150.114) (xy 363.854999 -150.141886) (xy 363.846879 -150.197062) (xy 363.830811 -150.250469)
			(xy 363.807139 -150.300966) (xy 363.776366 -150.347479) (xy 363.739149 -150.389016) (xy 363.696281 -150.424691)
			(xy 363.648675 -150.453745) (xy 363.597346 -150.475557) (xy 363.543389 -150.489663) (xy 363.487952 -150.495763)
			(xy 363.432218 -150.493726) (xy 363.377375 -150.483596) (xy 363.324591 -150.465589) (xy 363.274991 -150.440088)
			(xy 363.229633 -150.407637) (xy 363.189484 -150.368928) (xy 363.155398 -150.324785) (xy 363.128102 -150.27615)
			(xy 363.108179 -150.224059) (xy 363.096053 -150.169622) (xy 363.091982 -150.114) (xy 361.6311 -150.114)
			(xy 361.635032 -150.14135) (xy 361.635032 -150.19585) (xy 361.627277 -150.249796) (xy 361.611923 -150.302089)
			(xy 361.589284 -150.351665) (xy 361.559821 -150.397514) (xy 361.524133 -150.438705) (xy 361.482946 -150.474397)
			(xy 361.4371 -150.503865) (xy 361.387526 -150.526509) (xy 361.335235 -150.541868) (xy 361.28129 -150.549629)
			(xy 361.25404 -150.550118) (xy 361.227725 -150.549685) (xy 361.175595 -150.542442) (xy 361.124952 -150.528116)
			(xy 361.076753 -150.506977) (xy 361.031911 -150.479425) (xy 360.991272 -150.445982) (xy 360.973116 -150.426928)
			(xy 360.965587 -150.419535) (xy 360.946313 -150.411005) (xy 360.935778 -150.410418) (xy 360.861102 -150.410418)
			(xy 360.85055 -150.410929) (xy 360.831255 -150.419477) (xy 360.823764 -150.426928) (xy 360.803944 -150.447716)
			(xy 360.759172 -150.483691) (xy 360.709514 -150.512551) (xy 360.656092 -150.533644) (xy 360.600113 -150.546493)
			(xy 360.54284 -150.550808) (xy 360.485567 -150.546493) (xy 360.429588 -150.533644) (xy 360.376166 -150.512551)
			(xy 360.326508 -150.483691) (xy 360.281736 -150.447716) (xy 360.261916 -150.426928) (xy 360.254387 -150.419535)
			(xy 360.235113 -150.411005) (xy 360.224578 -150.410418) (xy 360.149902 -150.410418) (xy 360.13935 -150.410929)
			(xy 360.120055 -150.419477) (xy 360.112564 -150.426928) (xy 360.094424 -150.445999) (xy 360.053791 -150.479454)
			(xy 360.008947 -150.50701) (xy 359.960743 -150.528146) (xy 359.910093 -150.54246) (xy 359.857957 -150.549681)
			(xy 359.83164 -150.550118) (xy 359.804386 -150.549637) (xy 359.750432 -150.541885) (xy 359.698131 -150.526533)
			(xy 359.648547 -150.503893) (xy 359.60269 -150.474427) (xy 359.561494 -150.438735) (xy 359.525797 -150.397542)
			(xy 359.496326 -150.351688) (xy 359.473681 -150.302107) (xy 359.458323 -150.249807) (xy 359.450565 -150.195854)
			(xy 351.696004 -150.195854) (xy 351.692316 -150.201429) (xy 351.655099 -150.242966) (xy 351.612231 -150.278641)
			(xy 351.564625 -150.307695) (xy 351.513296 -150.329507) (xy 351.459339 -150.343613) (xy 351.403902 -150.349713)
			(xy 351.348168 -150.347676) (xy 351.293325 -150.337546) (xy 351.240541 -150.319539) (xy 351.190941 -150.294038)
			(xy 351.145583 -150.261587) (xy 351.105434 -150.222878) (xy 351.071348 -150.178735) (xy 351.044052 -150.1301)
			(xy 351.024129 -150.078009) (xy 351.012003 -150.023572) (xy 351.007932 -149.96795) (xy 341.503355 -149.96795)
			(xy 341.503508 -149.976332) (xy 341.502999 -150.004218) (xy 341.494879 -150.059394) (xy 341.478811 -150.112801)
			(xy 341.455139 -150.163298) (xy 341.424366 -150.209811) (xy 341.387149 -150.251348) (xy 341.344281 -150.287023)
			(xy 341.296675 -150.316077) (xy 341.245346 -150.337889) (xy 341.191389 -150.351995) (xy 341.135952 -150.358095)
			(xy 341.080218 -150.356058) (xy 341.025375 -150.345928) (xy 340.972591 -150.327921) (xy 340.922991 -150.30242)
			(xy 340.877633 -150.269969) (xy 340.837484 -150.23126) (xy 340.803398 -150.187117) (xy 340.776102 -150.138482)
			(xy 340.756179 -150.086391) (xy 340.744053 -150.031954) (xy 340.739982 -149.976332) (xy 335.407313 -149.976332)
			(xy 335.407508 -149.987) (xy 335.406999 -150.014886) (xy 335.398879 -150.070062) (xy 335.382811 -150.123469)
			(xy 335.359139 -150.173966) (xy 335.328366 -150.220479) (xy 335.291149 -150.262016) (xy 335.248281 -150.297691)
			(xy 335.200675 -150.326745) (xy 335.149346 -150.348557) (xy 335.095389 -150.362663) (xy 335.039952 -150.368763)
			(xy 334.984218 -150.366726) (xy 334.929375 -150.356596) (xy 334.876591 -150.338589) (xy 334.826991 -150.313088)
			(xy 334.781633 -150.280637) (xy 334.741484 -150.241928) (xy 334.707398 -150.197785) (xy 334.680102 -150.14915)
			(xy 334.660179 -150.097059) (xy 334.648053 -150.042622) (xy 334.643982 -149.987) (xy 326.089772 -149.987)
			(xy 326.089772 -151.003) (xy 336.675982 -151.003) (xy 336.680053 -150.947378) (xy 336.692179 -150.892941)
			(xy 336.712102 -150.84085) (xy 336.739398 -150.792215) (xy 336.773484 -150.748072) (xy 336.813633 -150.709363)
			(xy 336.858991 -150.676912) (xy 336.908591 -150.651411) (xy 336.961375 -150.633404) (xy 337.016218 -150.623274)
			(xy 337.071952 -150.621237) (xy 337.127389 -150.627337) (xy 337.181346 -150.641443) (xy 337.232675 -150.663255)
			(xy 337.280281 -150.692309) (xy 337.323149 -150.727984) (xy 337.360366 -150.769521) (xy 337.391139 -150.816034)
			(xy 337.414811 -150.866531) (xy 337.430879 -150.919938) (xy 337.438999 -150.975114) (xy 337.439508 -151.003)
			(xy 338.707982 -151.003) (xy 338.712053 -150.947378) (xy 338.724179 -150.892941) (xy 338.744102 -150.84085)
			(xy 338.771398 -150.792215) (xy 338.805484 -150.748072) (xy 338.845633 -150.709363) (xy 338.890991 -150.676912)
			(xy 338.940591 -150.651411) (xy 338.993375 -150.633404) (xy 339.048218 -150.623274) (xy 339.103952 -150.621237)
			(xy 339.159389 -150.627337) (xy 339.213346 -150.641443) (xy 339.264675 -150.663255) (xy 339.312281 -150.692309)
			(xy 339.355149 -150.727984) (xy 339.392366 -150.769521) (xy 339.423139 -150.816034) (xy 339.446811 -150.866531)
			(xy 339.462879 -150.919938) (xy 339.470999 -150.975114) (xy 339.471508 -151.003) (xy 339.470999 -151.030886)
			(xy 339.462879 -151.086062) (xy 339.446811 -151.139469) (xy 339.423139 -151.189966) (xy 339.392366 -151.236479)
			(xy 339.355149 -151.278016) (xy 339.312281 -151.313691) (xy 339.264675 -151.342745) (xy 339.213346 -151.364557)
			(xy 339.159389 -151.378663) (xy 339.103952 -151.384763) (xy 339.048218 -151.382726) (xy 338.993375 -151.372596)
			(xy 338.940591 -151.354589) (xy 338.890991 -151.329088) (xy 338.845633 -151.296637) (xy 338.805484 -151.257928)
			(xy 338.771398 -151.213785) (xy 338.744102 -151.16515) (xy 338.724179 -151.113059) (xy 338.712053 -151.058622)
			(xy 338.707982 -151.003) (xy 337.439508 -151.003) (xy 337.438999 -151.030886) (xy 337.430879 -151.086062)
			(xy 337.414811 -151.139469) (xy 337.391139 -151.189966) (xy 337.360366 -151.236479) (xy 337.323149 -151.278016)
			(xy 337.280281 -151.313691) (xy 337.232675 -151.342745) (xy 337.181346 -151.364557) (xy 337.127389 -151.378663)
			(xy 337.071952 -151.384763) (xy 337.016218 -151.382726) (xy 336.961375 -151.372596) (xy 336.908591 -151.354589)
			(xy 336.858991 -151.329088) (xy 336.813633 -151.296637) (xy 336.773484 -151.257928) (xy 336.739398 -151.213785)
			(xy 336.712102 -151.16515) (xy 336.692179 -151.113059) (xy 336.680053 -151.058622) (xy 336.675982 -151.003)
			(xy 326.089772 -151.003) (xy 326.089772 -152.007316) (xy 334.726024 -152.007316) (xy 334.730095 -151.951694)
			(xy 334.742221 -151.897257) (xy 334.762144 -151.845166) (xy 334.78944 -151.796531) (xy 334.823526 -151.752388)
			(xy 334.863675 -151.713679) (xy 334.909033 -151.681228) (xy 334.958633 -151.655727) (xy 335.011417 -151.63772)
			(xy 335.06626 -151.62759) (xy 335.121994 -151.625553) (xy 335.177431 -151.631653) (xy 335.231388 -151.645759)
			(xy 335.282717 -151.667571) (xy 335.288368 -151.67102) (xy 364.093758 -151.67102) (xy 364.097829 -151.615398)
			(xy 364.109955 -151.560961) (xy 364.129878 -151.50887) (xy 364.157174 -151.460235) (xy 364.19126 -151.416092)
			(xy 364.231409 -151.377383) (xy 364.276767 -151.344932) (xy 364.326367 -151.319431) (xy 364.379151 -151.301424)
			(xy 364.433994 -151.291294) (xy 364.489728 -151.289257) (xy 364.545165 -151.295357) (xy 364.599122 -151.309463)
			(xy 364.650451 -151.331275) (xy 364.698057 -151.360329) (xy 364.740925 -151.396004) (xy 364.778142 -151.437541)
			(xy 364.808915 -151.484054) (xy 364.832587 -151.534551) (xy 364.848655 -151.587958) (xy 364.856775 -151.643134)
			(xy 364.857284 -151.67102) (xy 364.856811 -151.696928) (xy 365.109758 -151.696928) (xy 365.113829 -151.641306)
			(xy 365.125955 -151.586869) (xy 365.145878 -151.534778) (xy 365.173174 -151.486143) (xy 365.20726 -151.442)
			(xy 365.247409 -151.403291) (xy 365.292767 -151.37084) (xy 365.342367 -151.345339) (xy 365.395151 -151.327332)
			(xy 365.449994 -151.317202) (xy 365.505728 -151.315165) (xy 365.561165 -151.321265) (xy 365.615122 -151.335371)
			(xy 365.666451 -151.357183) (xy 365.714057 -151.386237) (xy 365.738533 -151.406606) (xy 366.336832 -151.406606)
			(xy 366.340903 -151.350984) (xy 366.353029 -151.296547) (xy 366.372952 -151.244456) (xy 366.400248 -151.195821)
			(xy 366.434334 -151.151678) (xy 366.474483 -151.112969) (xy 366.519841 -151.080518) (xy 366.569441 -151.055017)
			(xy 366.622225 -151.03701) (xy 366.677068 -151.02688) (xy 366.732802 -151.024843) (xy 366.788239 -151.030943)
			(xy 366.842196 -151.045049) (xy 366.893525 -151.066861) (xy 366.941131 -151.095915) (xy 366.983999 -151.13159)
			(xy 367.021216 -151.173127) (xy 367.051989 -151.21964) (xy 367.075661 -151.270137) (xy 367.091729 -151.323544)
			(xy 367.099849 -151.37872) (xy 367.100358 -151.406606) (xy 367.099849 -151.434492) (xy 367.091729 -151.489668)
			(xy 367.075661 -151.543075) (xy 367.057119 -151.582628) (xy 367.662458 -151.582628) (xy 367.666529 -151.527006)
			(xy 367.678655 -151.472569) (xy 367.698578 -151.420478) (xy 367.725874 -151.371843) (xy 367.75996 -151.3277)
			(xy 367.800109 -151.288991) (xy 367.845467 -151.25654) (xy 367.895067 -151.231039) (xy 367.947851 -151.213032)
			(xy 368.002694 -151.202902) (xy 368.058428 -151.200865) (xy 368.113865 -151.206965) (xy 368.167822 -151.221071)
			(xy 368.219151 -151.242883) (xy 368.266757 -151.271937) (xy 368.309625 -151.307612) (xy 368.346842 -151.349149)
			(xy 368.377615 -151.395662) (xy 368.401287 -151.446159) (xy 368.417355 -151.499566) (xy 368.425475 -151.554742)
			(xy 368.425738 -151.569166) (xy 369.173758 -151.569166) (xy 369.177829 -151.513544) (xy 369.189955 -151.459107)
			(xy 369.209878 -151.407016) (xy 369.237174 -151.358381) (xy 369.27126 -151.314238) (xy 369.311409 -151.275529)
			(xy 369.356767 -151.243078) (xy 369.406367 -151.217577) (xy 369.459151 -151.19957) (xy 369.513994 -151.18944)
			(xy 369.569728 -151.187403) (xy 369.625165 -151.193503) (xy 369.679122 -151.207609) (xy 369.730451 -151.229421)
			(xy 369.778057 -151.258475) (xy 369.820925 -151.29415) (xy 369.858142 -151.335687) (xy 369.888915 -151.3822)
			(xy 369.912587 -151.432697) (xy 369.928655 -151.486104) (xy 369.936775 -151.54128) (xy 369.937284 -151.569166)
			(xy 369.936775 -151.597052) (xy 369.928655 -151.652228) (xy 369.912587 -151.705635) (xy 369.888915 -151.756132)
			(xy 369.858142 -151.802645) (xy 369.820925 -151.844182) (xy 369.778057 -151.879857) (xy 369.730451 -151.908911)
			(xy 369.679122 -151.930723) (xy 369.625165 -151.944829) (xy 369.569728 -151.950929) (xy 369.513994 -151.948892)
			(xy 369.459151 -151.938762) (xy 369.406367 -151.920755) (xy 369.356767 -151.895254) (xy 369.311409 -151.862803)
			(xy 369.27126 -151.824094) (xy 369.237174 -151.779951) (xy 369.209878 -151.731316) (xy 369.189955 -151.679225)
			(xy 369.177829 -151.624788) (xy 369.173758 -151.569166) (xy 368.425738 -151.569166) (xy 368.425984 -151.582628)
			(xy 368.425475 -151.610514) (xy 368.417355 -151.66569) (xy 368.401287 -151.719097) (xy 368.377615 -151.769594)
			(xy 368.346842 -151.816107) (xy 368.309625 -151.857644) (xy 368.266757 -151.893319) (xy 368.219151 -151.922373)
			(xy 368.167822 -151.944185) (xy 368.113865 -151.958291) (xy 368.058428 -151.964391) (xy 368.002694 -151.962354)
			(xy 367.947851 -151.952224) (xy 367.895067 -151.934217) (xy 367.845467 -151.908716) (xy 367.800109 -151.876265)
			(xy 367.75996 -151.837556) (xy 367.725874 -151.793413) (xy 367.698578 -151.744778) (xy 367.678655 -151.692687)
			(xy 367.666529 -151.63825) (xy 367.662458 -151.582628) (xy 367.057119 -151.582628) (xy 367.051989 -151.593572)
			(xy 367.021216 -151.640085) (xy 366.983999 -151.681622) (xy 366.941131 -151.717297) (xy 366.893525 -151.746351)
			(xy 366.842196 -151.768163) (xy 366.788239 -151.782269) (xy 366.732802 -151.788369) (xy 366.677068 -151.786332)
			(xy 366.622225 -151.776202) (xy 366.569441 -151.758195) (xy 366.519841 -151.732694) (xy 366.474483 -151.700243)
			(xy 366.434334 -151.661534) (xy 366.400248 -151.617391) (xy 366.372952 -151.568756) (xy 366.353029 -151.516665)
			(xy 366.340903 -151.462228) (xy 366.336832 -151.406606) (xy 365.738533 -151.406606) (xy 365.756925 -151.421912)
			(xy 365.794142 -151.463449) (xy 365.824915 -151.509962) (xy 365.848587 -151.560459) (xy 365.864655 -151.613866)
			(xy 365.872775 -151.669042) (xy 365.873284 -151.696928) (xy 365.872775 -151.724814) (xy 365.864655 -151.77999)
			(xy 365.848587 -151.833397) (xy 365.824915 -151.883894) (xy 365.794142 -151.930407) (xy 365.756925 -151.971944)
			(xy 365.714057 -152.007619) (xy 365.666451 -152.036673) (xy 365.615122 -152.058485) (xy 365.561165 -152.072591)
			(xy 365.505728 -152.078691) (xy 365.449994 -152.076654) (xy 365.395151 -152.066524) (xy 365.342367 -152.048517)
			(xy 365.292767 -152.023016) (xy 365.247409 -151.990565) (xy 365.20726 -151.951856) (xy 365.173174 -151.907713)
			(xy 365.145878 -151.859078) (xy 365.125955 -151.806987) (xy 365.113829 -151.75255) (xy 365.109758 -151.696928)
			(xy 364.856811 -151.696928) (xy 364.856775 -151.698906) (xy 364.848655 -151.754082) (xy 364.832587 -151.807489)
			(xy 364.808915 -151.857986) (xy 364.778142 -151.904499) (xy 364.740925 -151.946036) (xy 364.698057 -151.981711)
			(xy 364.650451 -152.010765) (xy 364.599122 -152.032577) (xy 364.545165 -152.046683) (xy 364.489728 -152.052783)
			(xy 364.433994 -152.050746) (xy 364.379151 -152.040616) (xy 364.326367 -152.022609) (xy 364.276767 -151.997108)
			(xy 364.231409 -151.964657) (xy 364.19126 -151.925948) (xy 364.157174 -151.881805) (xy 364.129878 -151.83317)
			(xy 364.109955 -151.781079) (xy 364.097829 -151.726642) (xy 364.093758 -151.67102) (xy 335.288368 -151.67102)
			(xy 335.330323 -151.696625) (xy 335.373191 -151.7323) (xy 335.410408 -151.773837) (xy 335.441181 -151.82035)
			(xy 335.464853 -151.870847) (xy 335.480921 -151.924254) (xy 335.489041 -151.97943) (xy 335.48955 -152.007316)
			(xy 335.489041 -152.035202) (xy 335.480921 -152.090378) (xy 335.464853 -152.143785) (xy 335.441181 -152.194282)
			(xy 335.410408 -152.240795) (xy 335.373191 -152.282332) (xy 335.330323 -152.318007) (xy 335.282717 -152.347061)
			(xy 335.231388 -152.368873) (xy 335.177431 -152.382979) (xy 335.121994 -152.389079) (xy 335.06626 -152.387042)
			(xy 335.011417 -152.376912) (xy 334.958633 -152.358905) (xy 334.909033 -152.333404) (xy 334.863675 -152.300953)
			(xy 334.823526 -152.262244) (xy 334.78944 -152.218101) (xy 334.762144 -152.169466) (xy 334.742221 -152.117375)
			(xy 334.730095 -152.062938) (xy 334.726024 -152.007316) (xy 326.089772 -152.007316) (xy 326.089772 -152.705054)
			(xy 341.103964 -152.705054) (xy 341.108035 -152.649432) (xy 341.120161 -152.594995) (xy 341.140084 -152.542904)
			(xy 341.16738 -152.494269) (xy 341.201466 -152.450126) (xy 341.241615 -152.411417) (xy 341.286973 -152.378966)
			(xy 341.336573 -152.353465) (xy 341.389357 -152.335458) (xy 341.4442 -152.325328) (xy 341.499934 -152.323291)
			(xy 341.555371 -152.329391) (xy 341.609328 -152.343497) (xy 341.660657 -152.365309) (xy 341.708263 -152.394363)
			(xy 341.751131 -152.430038) (xy 341.788348 -152.471575) (xy 341.819121 -152.518088) (xy 341.842793 -152.568585)
			(xy 341.858861 -152.621992) (xy 341.866981 -152.677168) (xy 341.86749 -152.705054) (xy 341.866981 -152.73294)
			(xy 341.858861 -152.788116) (xy 341.842793 -152.841523) (xy 341.819121 -152.89202) (xy 341.788348 -152.938533)
			(xy 341.751131 -152.98007) (xy 341.708263 -153.015745) (xy 341.660657 -153.044799) (xy 341.609328 -153.066611)
			(xy 341.555371 -153.080717) (xy 341.499934 -153.086817) (xy 341.4442 -153.08478) (xy 341.389357 -153.07465)
			(xy 341.336573 -153.056643) (xy 341.286973 -153.031142) (xy 341.241615 -152.998691) (xy 341.201466 -152.959982)
			(xy 341.16738 -152.915839) (xy 341.140084 -152.867204) (xy 341.120161 -152.815113) (xy 341.108035 -152.760676)
			(xy 341.103964 -152.705054) (xy 326.089772 -152.705054) (xy 326.089772 -153.67) (xy 334.643982 -153.67)
			(xy 334.648053 -153.614378) (xy 334.660179 -153.559941) (xy 334.680102 -153.50785) (xy 334.707398 -153.459215)
			(xy 334.741484 -153.415072) (xy 334.781633 -153.376363) (xy 334.826991 -153.343912) (xy 334.876591 -153.318411)
			(xy 334.929375 -153.300404) (xy 334.984218 -153.290274) (xy 335.039952 -153.288237) (xy 335.095389 -153.294337)
			(xy 335.149346 -153.308443) (xy 335.200675 -153.330255) (xy 335.248281 -153.359309) (xy 335.291149 -153.394984)
			(xy 335.328366 -153.436521) (xy 335.359139 -153.483034) (xy 335.382811 -153.533531) (xy 335.398879 -153.586938)
			(xy 335.406999 -153.642114) (xy 335.407508 -153.67) (xy 336.675982 -153.67) (xy 336.680053 -153.614378)
			(xy 336.692179 -153.559941) (xy 336.712102 -153.50785) (xy 336.739398 -153.459215) (xy 336.773484 -153.415072)
			(xy 336.813633 -153.376363) (xy 336.858991 -153.343912) (xy 336.908591 -153.318411) (xy 336.961375 -153.300404)
			(xy 337.016218 -153.290274) (xy 337.071952 -153.288237) (xy 337.127389 -153.294337) (xy 337.181346 -153.308443)
			(xy 337.232675 -153.330255) (xy 337.280281 -153.359309) (xy 337.323149 -153.394984) (xy 337.360366 -153.436521)
			(xy 337.391139 -153.483034) (xy 337.414811 -153.533531) (xy 337.430879 -153.586938) (xy 337.438999 -153.642114)
			(xy 337.439508 -153.67) (xy 337.438999 -153.697886) (xy 337.432076 -153.74493) (xy 349.735392 -153.74493)
			(xy 349.739463 -153.689308) (xy 349.751589 -153.634871) (xy 349.771512 -153.58278) (xy 349.798808 -153.534145)
			(xy 349.832894 -153.490002) (xy 349.873043 -153.451293) (xy 349.918401 -153.418842) (xy 349.968001 -153.393341)
			(xy 350.020785 -153.375334) (xy 350.075628 -153.365204) (xy 350.131362 -153.363167) (xy 350.186799 -153.369267)
			(xy 350.240756 -153.383373) (xy 350.292085 -153.405185) (xy 350.339691 -153.434239) (xy 350.382559 -153.469914)
			(xy 350.419776 -153.511451) (xy 350.450549 -153.557964) (xy 350.474221 -153.608461) (xy 350.490289 -153.661868)
			(xy 350.498409 -153.717044) (xy 350.498918 -153.74493) (xy 350.498409 -153.772816) (xy 350.496981 -153.782522)
			(xy 363.077758 -153.782522) (xy 363.081829 -153.7269) (xy 363.093955 -153.672463) (xy 363.113878 -153.620372)
			(xy 363.141174 -153.571737) (xy 363.17526 -153.527594) (xy 363.215409 -153.488885) (xy 363.260767 -153.456434)
			(xy 363.310367 -153.430933) (xy 363.363151 -153.412926) (xy 363.417994 -153.402796) (xy 363.473728 -153.400759)
			(xy 363.529165 -153.406859) (xy 363.583122 -153.420965) (xy 363.634451 -153.442777) (xy 363.682057 -153.471831)
			(xy 363.724925 -153.507506) (xy 363.762142 -153.549043) (xy 363.792915 -153.595556) (xy 363.816587 -153.646053)
			(xy 363.832655 -153.69946) (xy 363.840775 -153.754636) (xy 363.841284 -153.782522) (xy 364.093758 -153.782522)
			(xy 364.097829 -153.7269) (xy 364.109955 -153.672463) (xy 364.129878 -153.620372) (xy 364.157174 -153.571737)
			(xy 364.19126 -153.527594) (xy 364.231409 -153.488885) (xy 364.276767 -153.456434) (xy 364.326367 -153.430933)
			(xy 364.379151 -153.412926) (xy 364.433994 -153.402796) (xy 364.489728 -153.400759) (xy 364.545165 -153.406859)
			(xy 364.599122 -153.420965) (xy 364.650451 -153.442777) (xy 364.698057 -153.471831) (xy 364.740925 -153.507506)
			(xy 364.778142 -153.549043) (xy 364.808915 -153.595556) (xy 364.832587 -153.646053) (xy 364.848655 -153.69946)
			(xy 364.856775 -153.754636) (xy 364.857284 -153.782522) (xy 364.856775 -153.810408) (xy 364.853627 -153.831798)
			(xy 365.109758 -153.831798) (xy 365.113829 -153.776176) (xy 365.125955 -153.721739) (xy 365.145878 -153.669648)
			(xy 365.173174 -153.621013) (xy 365.20726 -153.57687) (xy 365.247409 -153.538161) (xy 365.292767 -153.50571)
			(xy 365.342367 -153.480209) (xy 365.395151 -153.462202) (xy 365.449994 -153.452072) (xy 365.505728 -153.450035)
			(xy 365.561165 -153.456135) (xy 365.615122 -153.470241) (xy 365.666451 -153.492053) (xy 365.714057 -153.521107)
			(xy 365.756925 -153.556782) (xy 365.794142 -153.598319) (xy 365.824915 -153.644832) (xy 365.848587 -153.695329)
			(xy 365.864655 -153.748736) (xy 365.869627 -153.782522) (xy 368.157758 -153.782522) (xy 368.161829 -153.7269)
			(xy 368.173955 -153.672463) (xy 368.193878 -153.620372) (xy 368.221174 -153.571737) (xy 368.25526 -153.527594)
			(xy 368.295409 -153.488885) (xy 368.340767 -153.456434) (xy 368.390367 -153.430933) (xy 368.443151 -153.412926)
			(xy 368.497994 -153.402796) (xy 368.553728 -153.400759) (xy 368.609165 -153.406859) (xy 368.663122 -153.420965)
			(xy 368.714451 -153.442777) (xy 368.762057 -153.471831) (xy 368.804925 -153.507506) (xy 368.842142 -153.549043)
			(xy 368.872915 -153.595556) (xy 368.896587 -153.646053) (xy 368.912655 -153.69946) (xy 368.920775 -153.754636)
			(xy 368.921284 -153.782522) (xy 370.189758 -153.782522) (xy 370.193829 -153.7269) (xy 370.205955 -153.672463)
			(xy 370.225878 -153.620372) (xy 370.253174 -153.571737) (xy 370.28726 -153.527594) (xy 370.327409 -153.488885)
			(xy 370.372767 -153.456434) (xy 370.422367 -153.430933) (xy 370.475151 -153.412926) (xy 370.529994 -153.402796)
			(xy 370.585728 -153.400759) (xy 370.641165 -153.406859) (xy 370.695122 -153.420965) (xy 370.746451 -153.442777)
			(xy 370.794057 -153.471831) (xy 370.836925 -153.507506) (xy 370.874142 -153.549043) (xy 370.904915 -153.595556)
			(xy 370.928587 -153.646053) (xy 370.944655 -153.69946) (xy 370.952775 -153.754636) (xy 370.953284 -153.782522)
			(xy 370.952775 -153.810408) (xy 370.944655 -153.865584) (xy 370.928587 -153.918991) (xy 370.904915 -153.969488)
			(xy 370.874142 -154.016001) (xy 370.836925 -154.057538) (xy 370.794057 -154.093213) (xy 370.746451 -154.122267)
			(xy 370.695122 -154.144079) (xy 370.641165 -154.158185) (xy 370.585728 -154.164285) (xy 370.529994 -154.162248)
			(xy 370.475151 -154.152118) (xy 370.422367 -154.134111) (xy 370.372767 -154.10861) (xy 370.327409 -154.076159)
			(xy 370.28726 -154.03745) (xy 370.253174 -153.993307) (xy 370.225878 -153.944672) (xy 370.205955 -153.892581)
			(xy 370.193829 -153.838144) (xy 370.189758 -153.782522) (xy 368.921284 -153.782522) (xy 368.920775 -153.810408)
			(xy 368.912655 -153.865584) (xy 368.896587 -153.918991) (xy 368.872915 -153.969488) (xy 368.842142 -154.016001)
			(xy 368.804925 -154.057538) (xy 368.762057 -154.093213) (xy 368.714451 -154.122267) (xy 368.663122 -154.144079)
			(xy 368.609165 -154.158185) (xy 368.553728 -154.164285) (xy 368.497994 -154.162248) (xy 368.443151 -154.152118)
			(xy 368.390367 -154.134111) (xy 368.340767 -154.10861) (xy 368.295409 -154.076159) (xy 368.25526 -154.03745)
			(xy 368.221174 -153.993307) (xy 368.193878 -153.944672) (xy 368.173955 -153.892581) (xy 368.161829 -153.838144)
			(xy 368.157758 -153.782522) (xy 365.869627 -153.782522) (xy 365.872775 -153.803912) (xy 365.873284 -153.831798)
			(xy 365.872775 -153.859684) (xy 365.864655 -153.91486) (xy 365.848587 -153.968267) (xy 365.824915 -154.018764)
			(xy 365.794142 -154.065277) (xy 365.756925 -154.106814) (xy 365.714057 -154.142489) (xy 365.666451 -154.171543)
			(xy 365.615122 -154.193355) (xy 365.561165 -154.207461) (xy 365.505728 -154.213561) (xy 365.449994 -154.211524)
			(xy 365.395151 -154.201394) (xy 365.342367 -154.183387) (xy 365.292767 -154.157886) (xy 365.247409 -154.125435)
			(xy 365.20726 -154.086726) (xy 365.173174 -154.042583) (xy 365.145878 -153.993948) (xy 365.125955 -153.941857)
			(xy 365.113829 -153.88742) (xy 365.109758 -153.831798) (xy 364.853627 -153.831798) (xy 364.848655 -153.865584)
			(xy 364.832587 -153.918991) (xy 364.808915 -153.969488) (xy 364.778142 -154.016001) (xy 364.740925 -154.057538)
			(xy 364.698057 -154.093213) (xy 364.650451 -154.122267) (xy 364.599122 -154.144079) (xy 364.545165 -154.158185)
			(xy 364.489728 -154.164285) (xy 364.433994 -154.162248) (xy 364.379151 -154.152118) (xy 364.326367 -154.134111)
			(xy 364.276767 -154.10861) (xy 364.231409 -154.076159) (xy 364.19126 -154.03745) (xy 364.157174 -153.993307)
			(xy 364.129878 -153.944672) (xy 364.109955 -153.892581) (xy 364.097829 -153.838144) (xy 364.093758 -153.782522)
			(xy 363.841284 -153.782522) (xy 363.840775 -153.810408) (xy 363.832655 -153.865584) (xy 363.816587 -153.918991)
			(xy 363.792915 -153.969488) (xy 363.762142 -154.016001) (xy 363.724925 -154.057538) (xy 363.682057 -154.093213)
			(xy 363.634451 -154.122267) (xy 363.583122 -154.144079) (xy 363.529165 -154.158185) (xy 363.473728 -154.164285)
			(xy 363.417994 -154.162248) (xy 363.363151 -154.152118) (xy 363.310367 -154.134111) (xy 363.260767 -154.10861)
			(xy 363.215409 -154.076159) (xy 363.17526 -154.03745) (xy 363.141174 -153.993307) (xy 363.113878 -153.944672)
			(xy 363.093955 -153.892581) (xy 363.081829 -153.838144) (xy 363.077758 -153.782522) (xy 350.496981 -153.782522)
			(xy 350.490289 -153.827992) (xy 350.474221 -153.881399) (xy 350.450549 -153.931896) (xy 350.419776 -153.978409)
			(xy 350.382559 -154.019946) (xy 350.339691 -154.055621) (xy 350.292085 -154.084675) (xy 350.240756 -154.106487)
			(xy 350.186799 -154.120593) (xy 350.131362 -154.126693) (xy 350.075628 -154.124656) (xy 350.020785 -154.114526)
			(xy 349.968001 -154.096519) (xy 349.918401 -154.071018) (xy 349.873043 -154.038567) (xy 349.832894 -153.999858)
			(xy 349.798808 -153.955715) (xy 349.771512 -153.90708) (xy 349.751589 -153.854989) (xy 349.739463 -153.800552)
			(xy 349.735392 -153.74493) (xy 337.432076 -153.74493) (xy 337.430879 -153.753062) (xy 337.414811 -153.806469)
			(xy 337.391139 -153.856966) (xy 337.360366 -153.903479) (xy 337.323149 -153.945016) (xy 337.280281 -153.980691)
			(xy 337.232675 -154.009745) (xy 337.181346 -154.031557) (xy 337.127389 -154.045663) (xy 337.071952 -154.051763)
			(xy 337.016218 -154.049726) (xy 336.961375 -154.039596) (xy 336.908591 -154.021589) (xy 336.858991 -153.996088)
			(xy 336.813633 -153.963637) (xy 336.773484 -153.924928) (xy 336.739398 -153.880785) (xy 336.712102 -153.83215)
			(xy 336.692179 -153.780059) (xy 336.680053 -153.725622) (xy 336.675982 -153.67) (xy 335.407508 -153.67)
			(xy 335.406999 -153.697886) (xy 335.398879 -153.753062) (xy 335.382811 -153.806469) (xy 335.359139 -153.856966)
			(xy 335.328366 -153.903479) (xy 335.291149 -153.945016) (xy 335.248281 -153.980691) (xy 335.200675 -154.009745)
			(xy 335.149346 -154.031557) (xy 335.095389 -154.045663) (xy 335.039952 -154.051763) (xy 334.984218 -154.049726)
			(xy 334.929375 -154.039596) (xy 334.876591 -154.021589) (xy 334.826991 -153.996088) (xy 334.781633 -153.963637)
			(xy 334.741484 -153.924928) (xy 334.707398 -153.880785) (xy 334.680102 -153.83215) (xy 334.660179 -153.780059)
			(xy 334.648053 -153.725622) (xy 334.643982 -153.67) (xy 326.089772 -153.67) (xy 326.089772 -154.156156)
			(xy 341.026748 -154.156156) (xy 341.030819 -154.100534) (xy 341.042945 -154.046097) (xy 341.062868 -153.994006)
			(xy 341.090164 -153.945371) (xy 341.12425 -153.901228) (xy 341.164399 -153.862519) (xy 341.209757 -153.830068)
			(xy 341.259357 -153.804567) (xy 341.312141 -153.78656) (xy 341.366984 -153.77643) (xy 341.422718 -153.774393)
			(xy 341.478155 -153.780493) (xy 341.532112 -153.794599) (xy 341.583441 -153.816411) (xy 341.631047 -153.845465)
			(xy 341.673915 -153.88114) (xy 341.711132 -153.922677) (xy 341.741905 -153.96919) (xy 341.765577 -154.019687)
			(xy 341.781645 -154.073094) (xy 341.789765 -154.12827) (xy 341.790274 -154.156156) (xy 341.789765 -154.184042)
			(xy 341.781645 -154.239218) (xy 341.765577 -154.292625) (xy 341.759776 -154.305) (xy 352.866196 -154.305)
			(xy 352.870267 -154.249378) (xy 352.882393 -154.194941) (xy 352.902316 -154.14285) (xy 352.929612 -154.094215)
			(xy 352.963698 -154.050072) (xy 353.003847 -154.011363) (xy 353.049205 -153.978912) (xy 353.098805 -153.953411)
			(xy 353.151589 -153.935404) (xy 353.206432 -153.925274) (xy 353.262166 -153.923237) (xy 353.317603 -153.929337)
			(xy 353.37156 -153.943443) (xy 353.422889 -153.965255) (xy 353.470495 -153.994309) (xy 353.513363 -154.029984)
			(xy 353.55058 -154.071521) (xy 353.581353 -154.118034) (xy 353.605025 -154.168531) (xy 353.621093 -154.221938)
			(xy 353.629213 -154.277114) (xy 353.629722 -154.305) (xy 353.629213 -154.332886) (xy 353.621093 -154.388062)
			(xy 353.605025 -154.441469) (xy 353.581353 -154.491966) (xy 353.55058 -154.538479) (xy 353.513363 -154.580016)
			(xy 353.470495 -154.615691) (xy 353.422889 -154.644745) (xy 353.37156 -154.666557) (xy 353.317603 -154.680663)
			(xy 353.262166 -154.686763) (xy 353.206432 -154.684726) (xy 353.151589 -154.674596) (xy 353.098805 -154.656589)
			(xy 353.049205 -154.631088) (xy 353.003847 -154.598637) (xy 352.963698 -154.559928) (xy 352.929612 -154.515785)
			(xy 352.902316 -154.46715) (xy 352.882393 -154.415059) (xy 352.870267 -154.360622) (xy 352.866196 -154.305)
			(xy 341.759776 -154.305) (xy 341.741905 -154.343122) (xy 341.711132 -154.389635) (xy 341.673915 -154.431172)
			(xy 341.631047 -154.466847) (xy 341.583441 -154.495901) (xy 341.532112 -154.517713) (xy 341.478155 -154.531819)
			(xy 341.422718 -154.537919) (xy 341.366984 -154.535882) (xy 341.312141 -154.525752) (xy 341.259357 -154.507745)
			(xy 341.209757 -154.482244) (xy 341.164399 -154.449793) (xy 341.12425 -154.411084) (xy 341.090164 -154.366941)
			(xy 341.062868 -154.318306) (xy 341.042945 -154.266215) (xy 341.030819 -154.211778) (xy 341.026748 -154.156156)
			(xy 326.089772 -154.156156) (xy 326.089772 -154.686) (xy 334.643982 -154.686) (xy 334.648053 -154.630378)
			(xy 334.660179 -154.575941) (xy 334.680102 -154.52385) (xy 334.707398 -154.475215) (xy 334.741484 -154.431072)
			(xy 334.781633 -154.392363) (xy 334.826991 -154.359912) (xy 334.876591 -154.334411) (xy 334.929375 -154.316404)
			(xy 334.984218 -154.306274) (xy 335.039952 -154.304237) (xy 335.095389 -154.310337) (xy 335.149346 -154.324443)
			(xy 335.200675 -154.346255) (xy 335.248281 -154.375309) (xy 335.291149 -154.410984) (xy 335.328366 -154.452521)
			(xy 335.359139 -154.499034) (xy 335.382811 -154.549531) (xy 335.398879 -154.602938) (xy 335.406999 -154.658114)
			(xy 335.407508 -154.686) (xy 336.675982 -154.686) (xy 336.680053 -154.630378) (xy 336.692179 -154.575941)
			(xy 336.712102 -154.52385) (xy 336.739398 -154.475215) (xy 336.773484 -154.431072) (xy 336.813633 -154.392363)
			(xy 336.858991 -154.359912) (xy 336.908591 -154.334411) (xy 336.961375 -154.316404) (xy 337.016218 -154.306274)
			(xy 337.071952 -154.304237) (xy 337.127389 -154.310337) (xy 337.181346 -154.324443) (xy 337.232675 -154.346255)
			(xy 337.280281 -154.375309) (xy 337.323149 -154.410984) (xy 337.360366 -154.452521) (xy 337.391139 -154.499034)
			(xy 337.414811 -154.549531) (xy 337.430879 -154.602938) (xy 337.438999 -154.658114) (xy 337.439508 -154.686)
			(xy 339.469982 -154.686) (xy 339.474053 -154.630378) (xy 339.486179 -154.575941) (xy 339.506102 -154.52385)
			(xy 339.533398 -154.475215) (xy 339.567484 -154.431072) (xy 339.607633 -154.392363) (xy 339.652991 -154.359912)
			(xy 339.702591 -154.334411) (xy 339.755375 -154.316404) (xy 339.810218 -154.306274) (xy 339.865952 -154.304237)
			(xy 339.921389 -154.310337) (xy 339.975346 -154.324443) (xy 340.026675 -154.346255) (xy 340.074281 -154.375309)
			(xy 340.117149 -154.410984) (xy 340.154366 -154.452521) (xy 340.185139 -154.499034) (xy 340.208811 -154.549531)
			(xy 340.224879 -154.602938) (xy 340.232999 -154.658114) (xy 340.233508 -154.686) (xy 340.232999 -154.713886)
			(xy 340.224879 -154.769062) (xy 340.208811 -154.822469) (xy 340.185139 -154.872966) (xy 340.154366 -154.919479)
			(xy 340.117149 -154.961016) (xy 340.074281 -154.996691) (xy 340.026675 -155.025745) (xy 339.975346 -155.047557)
			(xy 339.921389 -155.061663) (xy 339.865952 -155.067763) (xy 339.810218 -155.065726) (xy 339.755375 -155.055596)
			(xy 339.702591 -155.037589) (xy 339.652991 -155.012088) (xy 339.607633 -154.979637) (xy 339.567484 -154.940928)
			(xy 339.533398 -154.896785) (xy 339.506102 -154.84815) (xy 339.486179 -154.796059) (xy 339.474053 -154.741622)
			(xy 339.469982 -154.686) (xy 337.439508 -154.686) (xy 337.438999 -154.713886) (xy 337.430879 -154.769062)
			(xy 337.414811 -154.822469) (xy 337.391139 -154.872966) (xy 337.360366 -154.919479) (xy 337.323149 -154.961016)
			(xy 337.280281 -154.996691) (xy 337.232675 -155.025745) (xy 337.181346 -155.047557) (xy 337.127389 -155.061663)
			(xy 337.071952 -155.067763) (xy 337.016218 -155.065726) (xy 336.961375 -155.055596) (xy 336.908591 -155.037589)
			(xy 336.858991 -155.012088) (xy 336.813633 -154.979637) (xy 336.773484 -154.940928) (xy 336.739398 -154.896785)
			(xy 336.712102 -154.84815) (xy 336.692179 -154.796059) (xy 336.680053 -154.741622) (xy 336.675982 -154.686)
			(xy 335.407508 -154.686) (xy 335.406999 -154.713886) (xy 335.398879 -154.769062) (xy 335.382811 -154.822469)
			(xy 335.359139 -154.872966) (xy 335.328366 -154.919479) (xy 335.291149 -154.961016) (xy 335.248281 -154.996691)
			(xy 335.200675 -155.025745) (xy 335.149346 -155.047557) (xy 335.095389 -155.061663) (xy 335.039952 -155.067763)
			(xy 334.984218 -155.065726) (xy 334.929375 -155.055596) (xy 334.876591 -155.037589) (xy 334.826991 -155.012088)
			(xy 334.781633 -154.979637) (xy 334.741484 -154.940928) (xy 334.707398 -154.896785) (xy 334.680102 -154.84815)
			(xy 334.660179 -154.796059) (xy 334.648053 -154.741622) (xy 334.643982 -154.686) (xy 326.089772 -154.686)
			(xy 326.089772 -155.242768) (xy 341.689434 -155.242768) (xy 341.693505 -155.187146) (xy 341.705631 -155.132709)
			(xy 341.725554 -155.080618) (xy 341.75285 -155.031983) (xy 341.786936 -154.98784) (xy 341.827085 -154.949131)
			(xy 341.872443 -154.91668) (xy 341.922043 -154.891179) (xy 341.974827 -154.873172) (xy 342.02967 -154.863042)
			(xy 342.085404 -154.861005) (xy 342.140841 -154.867105) (xy 342.194798 -154.881211) (xy 342.246127 -154.903023)
			(xy 342.293733 -154.932077) (xy 342.336601 -154.967752) (xy 342.373818 -155.009289) (xy 342.404591 -155.055802)
			(xy 342.407935 -155.062936) (xy 349.735392 -155.062936) (xy 349.739463 -155.007314) (xy 349.751589 -154.952877)
			(xy 349.771512 -154.900786) (xy 349.798808 -154.852151) (xy 349.832894 -154.808008) (xy 349.873043 -154.769299)
			(xy 349.918401 -154.736848) (xy 349.968001 -154.711347) (xy 350.020785 -154.69334) (xy 350.075628 -154.68321)
			(xy 350.131362 -154.681173) (xy 350.186799 -154.687273) (xy 350.240756 -154.701379) (xy 350.292085 -154.723191)
			(xy 350.339691 -154.752245) (xy 350.382559 -154.78792) (xy 350.419776 -154.829457) (xy 350.450549 -154.87597)
			(xy 350.474221 -154.926467) (xy 350.490289 -154.979874) (xy 350.498409 -155.03505) (xy 350.498918 -155.062936)
			(xy 350.498409 -155.090822) (xy 350.490289 -155.145998) (xy 350.474221 -155.199405) (xy 350.450549 -155.249902)
			(xy 350.419776 -155.296415) (xy 350.397748 -155.321) (xy 352.866196 -155.321) (xy 352.870267 -155.265378)
			(xy 352.882393 -155.210941) (xy 352.902316 -155.15885) (xy 352.929612 -155.110215) (xy 352.963698 -155.066072)
			(xy 353.003847 -155.027363) (xy 353.049205 -154.994912) (xy 353.098805 -154.969411) (xy 353.151589 -154.951404)
			(xy 353.206432 -154.941274) (xy 353.262166 -154.939237) (xy 353.317603 -154.945337) (xy 353.37156 -154.959443)
			(xy 353.422889 -154.981255) (xy 353.470495 -155.010309) (xy 353.513363 -155.045984) (xy 353.55058 -155.087521)
			(xy 353.581353 -155.134034) (xy 353.605025 -155.184531) (xy 353.6133 -155.212034) (xy 355.569264 -155.212034)
			(xy 355.573335 -155.156412) (xy 355.585461 -155.101975) (xy 355.605384 -155.049884) (xy 355.63268 -155.001249)
			(xy 355.666766 -154.957106) (xy 355.706915 -154.918397) (xy 355.752273 -154.885946) (xy 355.801873 -154.860445)
			(xy 355.854657 -154.842438) (xy 355.9095 -154.832308) (xy 355.965234 -154.830271) (xy 356.020671 -154.836371)
			(xy 356.074628 -154.850477) (xy 356.125957 -154.872289) (xy 356.173563 -154.901343) (xy 356.216431 -154.937018)
			(xy 356.253648 -154.978555) (xy 356.284421 -155.025068) (xy 356.308093 -155.075565) (xy 356.309184 -155.079192)
			(xy 358.16997 -155.079192) (xy 358.174041 -155.02357) (xy 358.186167 -154.969133) (xy 358.20609 -154.917042)
			(xy 358.233386 -154.868407) (xy 358.267472 -154.824264) (xy 358.307621 -154.785555) (xy 358.352979 -154.753104)
			(xy 358.402579 -154.727603) (xy 358.455363 -154.709596) (xy 358.510206 -154.699466) (xy 358.56594 -154.697429)
			(xy 358.621377 -154.703529) (xy 358.675334 -154.717635) (xy 358.726663 -154.739447) (xy 358.774269 -154.768501)
			(xy 358.817137 -154.804176) (xy 358.854354 -154.845713) (xy 358.885127 -154.892226) (xy 358.908799 -154.942723)
			(xy 358.924867 -154.99613) (xy 358.932987 -155.051306) (xy 358.933496 -155.079192) (xy 358.933431 -155.082748)
			(xy 359.49382 -155.082748) (xy 359.494246 -155.056433) (xy 359.501489 -155.004302) (xy 359.515815 -154.953658)
			(xy 359.536956 -154.905459) (xy 359.564509 -154.860617) (xy 359.597955 -154.819979) (xy 359.61701 -154.801824)
			(xy 359.624405 -154.794297) (xy 359.632933 -154.775021) (xy 359.63352 -154.764486) (xy 359.63352 -154.68981)
			(xy 359.632993 -154.67926) (xy 359.624456 -154.659965) (xy 359.61701 -154.652472) (xy 359.59795 -154.634321)
			(xy 359.564493 -154.593691) (xy 359.536934 -154.548849) (xy 359.515796 -154.500648) (xy 359.50148 -154.449999)
			(xy 359.494257 -154.397864) (xy 359.49382 -154.371548) (xy 359.4943 -154.344295) (xy 359.502051 -154.290343)
			(xy 359.517403 -154.238044) (xy 359.540042 -154.188462) (xy 359.569507 -154.142607) (xy 359.605199 -154.101414)
			(xy 359.646391 -154.065719) (xy 359.692245 -154.036251) (xy 359.741825 -154.01361) (xy 359.794124 -153.998255)
			(xy 359.848075 -153.990501) (xy 359.875328 -153.99004) (xy 359.901643 -153.990476) (xy 359.953774 -153.997715)
			(xy 360.004417 -154.01204) (xy 360.052617 -154.033178) (xy 360.097459 -154.06073) (xy 360.138097 -154.094175)
			(xy 360.156252 -154.11323) (xy 360.163762 -154.120646) (xy 360.18305 -154.129165) (xy 360.19359 -154.12974)
			(xy 360.268266 -154.12974) (xy 360.278813 -154.129194) (xy 360.298108 -154.12067) (xy 360.305604 -154.11323)
			(xy 360.325424 -154.092442) (xy 360.370196 -154.056467) (xy 360.419854 -154.027607) (xy 360.473276 -154.006514)
			(xy 360.529255 -153.993665) (xy 360.586528 -153.98935) (xy 360.643801 -153.993665) (xy 360.69978 -154.006514)
			(xy 360.753202 -154.027607) (xy 360.80286 -154.056467) (xy 360.847632 -154.092442) (xy 360.867452 -154.11323)
			(xy 360.874962 -154.120646) (xy 360.89425 -154.129165) (xy 360.90479 -154.12974) (xy 360.979466 -154.12974)
			(xy 360.990013 -154.129194) (xy 361.009308 -154.12067) (xy 361.016804 -154.11323) (xy 361.036624 -154.092442)
			(xy 361.081396 -154.056467) (xy 361.131054 -154.027607) (xy 361.184476 -154.006514) (xy 361.240455 -153.993665)
			(xy 361.297728 -153.98935) (xy 361.355001 -153.993665) (xy 361.41098 -154.006514) (xy 361.464402 -154.027607)
			(xy 361.51406 -154.056467) (xy 361.558832 -154.092442) (xy 361.578652 -154.11323) (xy 361.586162 -154.120646)
			(xy 361.60545 -154.129165) (xy 361.61599 -154.12974) (xy 361.690666 -154.12974) (xy 361.701213 -154.129194)
			(xy 361.720508 -154.12067) (xy 361.728004 -154.11323) (xy 361.746171 -154.094185) (xy 361.786797 -154.060726)
			(xy 361.831635 -154.033165) (xy 361.879834 -154.012024) (xy 361.93048 -153.997705) (xy 361.982612 -153.990479)
			(xy 362.008928 -153.99004) (xy 362.036184 -153.990429) (xy 362.09014 -153.998191) (xy 362.142442 -154.013553)
			(xy 362.192026 -154.036202) (xy 362.237881 -154.065678) (xy 362.279075 -154.101379) (xy 362.314768 -154.14258)
			(xy 362.344234 -154.188441) (xy 362.366874 -154.238029) (xy 362.382225 -154.290334) (xy 362.389976 -154.344292)
			(xy 362.390436 -154.371548) (xy 362.389989 -154.397863) (xy 362.382748 -154.449991) (xy 362.368424 -154.500634)
			(xy 362.347288 -154.548833) (xy 362.319739 -154.593676) (xy 362.286298 -154.634315) (xy 362.267246 -154.652472)
			(xy 362.259862 -154.660008) (xy 362.251326 -154.679277) (xy 362.250736 -154.68981) (xy 362.250736 -154.764486)
			(xy 362.251248 -154.775038) (xy 362.259794 -154.794334) (xy 362.267246 -154.801824) (xy 362.286315 -154.819966)
			(xy 362.319769 -154.8606) (xy 362.347325 -154.905443) (xy 362.368461 -154.953646) (xy 362.382776 -155.004296)
			(xy 362.389998 -155.056431) (xy 362.390436 -155.082748) (xy 362.389967 -155.109999) (xy 362.382205 -155.163946)
			(xy 362.366845 -155.216239) (xy 362.3442 -155.265815) (xy 362.314731 -155.311664) (xy 362.279038 -155.352853)
			(xy 362.237848 -155.388543) (xy 362.191997 -155.41801) (xy 362.142421 -155.440652) (xy 362.090126 -155.456009)
			(xy 362.036179 -155.463768) (xy 362.008928 -155.464256) (xy 361.982612 -155.463851) (xy 361.93048 -155.456605)
			(xy 361.879836 -155.442275) (xy 361.831636 -155.421131) (xy 361.786795 -155.393573) (xy 361.746158 -155.360123)
			(xy 361.728004 -155.341066) (xy 361.720474 -155.333674) (xy 361.701201 -155.325142) (xy 361.690666 -155.324556)
			(xy 361.61599 -155.324556) (xy 361.60544 -155.325079) (xy 361.586146 -155.33362) (xy 361.578652 -155.341066)
			(xy 361.558832 -155.361854) (xy 361.51406 -155.397829) (xy 361.464402 -155.426689) (xy 361.41098 -155.447782)
			(xy 361.355001 -155.460631) (xy 361.297728 -155.464946) (xy 361.240455 -155.460631) (xy 361.184476 -155.447782)
			(xy 361.131054 -155.426689) (xy 361.081396 -155.397829) (xy 361.036624 -155.361854) (xy 361.016804 -155.341066)
			(xy 361.009274 -155.333674) (xy 360.990001 -155.325142) (xy 360.979466 -155.324556) (xy 360.90479 -155.324556)
			(xy 360.89424 -155.325079) (xy 360.874946 -155.33362) (xy 360.867452 -155.341066) (xy 360.847632 -155.361854)
			(xy 360.80286 -155.397829) (xy 360.753202 -155.426689) (xy 360.69978 -155.447782) (xy 360.643801 -155.460631)
			(xy 360.586528 -155.464946) (xy 360.529255 -155.460631) (xy 360.473276 -155.447782) (xy 360.419854 -155.426689)
			(xy 360.370196 -155.397829) (xy 360.325424 -155.361854) (xy 360.305604 -155.341066) (xy 360.298074 -155.333674)
			(xy 360.278801 -155.325142) (xy 360.268266 -155.324556) (xy 360.19359 -155.324556) (xy 360.18304 -155.325079)
			(xy 360.163746 -155.33362) (xy 360.156252 -155.341066) (xy 360.138126 -155.36015) (xy 360.097488 -155.393602)
			(xy 360.052641 -155.421156) (xy 360.004435 -155.442289) (xy 359.953783 -155.456601) (xy 359.901646 -155.46382)
			(xy 359.875328 -155.464256) (xy 359.84808 -155.463696) (xy 359.794137 -155.455944) (xy 359.741847 -155.440595)
			(xy 359.692273 -155.417961) (xy 359.646425 -155.388502) (xy 359.605235 -155.352818) (xy 359.569544 -155.311636)
			(xy 359.540076 -155.265794) (xy 359.517431 -155.216225) (xy 359.502072 -155.163937) (xy 359.49431 -155.109996)
			(xy 359.49382 -155.082748) (xy 358.933431 -155.082748) (xy 358.932987 -155.107078) (xy 358.924867 -155.162254)
			(xy 358.908799 -155.215661) (xy 358.885127 -155.266158) (xy 358.854354 -155.312671) (xy 358.817137 -155.354208)
			(xy 358.774269 -155.389883) (xy 358.726663 -155.418937) (xy 358.675334 -155.440749) (xy 358.621377 -155.454855)
			(xy 358.56594 -155.460955) (xy 358.510206 -155.458918) (xy 358.455363 -155.448788) (xy 358.402579 -155.430781)
			(xy 358.352979 -155.40528) (xy 358.307621 -155.372829) (xy 358.267472 -155.33412) (xy 358.233386 -155.289977)
			(xy 358.20609 -155.241342) (xy 358.186167 -155.189251) (xy 358.174041 -155.134814) (xy 358.16997 -155.079192)
			(xy 356.309184 -155.079192) (xy 356.324161 -155.128972) (xy 356.332281 -155.184148) (xy 356.33279 -155.212034)
			(xy 356.332281 -155.23992) (xy 356.324161 -155.295096) (xy 356.308093 -155.348503) (xy 356.284421 -155.399)
			(xy 356.253648 -155.445513) (xy 356.216431 -155.48705) (xy 356.173563 -155.522725) (xy 356.125957 -155.551779)
			(xy 356.074628 -155.573591) (xy 356.020671 -155.587697) (xy 355.965234 -155.593797) (xy 355.9095 -155.59176)
			(xy 355.854657 -155.58163) (xy 355.801873 -155.563623) (xy 355.752273 -155.538122) (xy 355.706915 -155.505671)
			(xy 355.666766 -155.466962) (xy 355.63268 -155.422819) (xy 355.605384 -155.374184) (xy 355.585461 -155.322093)
			(xy 355.573335 -155.267656) (xy 355.569264 -155.212034) (xy 353.6133 -155.212034) (xy 353.621093 -155.237938)
			(xy 353.629213 -155.293114) (xy 353.629722 -155.321) (xy 353.629213 -155.348886) (xy 353.621093 -155.404062)
			(xy 353.605025 -155.457469) (xy 353.581353 -155.507966) (xy 353.55058 -155.554479) (xy 353.513363 -155.596016)
			(xy 353.470495 -155.631691) (xy 353.422889 -155.660745) (xy 353.37156 -155.682557) (xy 353.317603 -155.696663)
			(xy 353.262166 -155.702763) (xy 353.206432 -155.700726) (xy 353.151589 -155.690596) (xy 353.098805 -155.672589)
			(xy 353.049205 -155.647088) (xy 353.003847 -155.614637) (xy 352.963698 -155.575928) (xy 352.929612 -155.531785)
			(xy 352.902316 -155.48315) (xy 352.882393 -155.431059) (xy 352.870267 -155.376622) (xy 352.866196 -155.321)
			(xy 350.397748 -155.321) (xy 350.382559 -155.337952) (xy 350.339691 -155.373627) (xy 350.292085 -155.402681)
			(xy 350.240756 -155.424493) (xy 350.186799 -155.438599) (xy 350.131362 -155.444699) (xy 350.075628 -155.442662)
			(xy 350.020785 -155.432532) (xy 349.968001 -155.414525) (xy 349.918401 -155.389024) (xy 349.873043 -155.356573)
			(xy 349.832894 -155.317864) (xy 349.798808 -155.273721) (xy 349.771512 -155.225086) (xy 349.751589 -155.172995)
			(xy 349.739463 -155.118558) (xy 349.735392 -155.062936) (xy 342.407935 -155.062936) (xy 342.428263 -155.106299)
			(xy 342.444331 -155.159706) (xy 342.452451 -155.214882) (xy 342.45296 -155.242768) (xy 342.452451 -155.270654)
			(xy 342.444331 -155.32583) (xy 342.428263 -155.379237) (xy 342.404591 -155.429734) (xy 342.373818 -155.476247)
			(xy 342.336601 -155.517784) (xy 342.293733 -155.553459) (xy 342.246127 -155.582513) (xy 342.194798 -155.604325)
			(xy 342.140841 -155.618431) (xy 342.085404 -155.624531) (xy 342.02967 -155.622494) (xy 341.974827 -155.612364)
			(xy 341.922043 -155.594357) (xy 341.872443 -155.568856) (xy 341.827085 -155.536405) (xy 341.786936 -155.497696)
			(xy 341.75285 -155.453553) (xy 341.725554 -155.404918) (xy 341.705631 -155.352827) (xy 341.693505 -155.29839)
			(xy 341.689434 -155.242768) (xy 326.089772 -155.242768) (xy 326.089772 -155.469082) (xy 326.089307 -155.493053)
			(xy 326.081814 -155.540405) (xy 326.066994 -155.585999) (xy 326.045214 -155.628707) (xy 326.017012 -155.667476)
			(xy 326.000364 -155.684728) (xy 325.983092 -155.702) (xy 336.675982 -155.702) (xy 336.680053 -155.646378)
			(xy 336.692179 -155.591941) (xy 336.712102 -155.53985) (xy 336.739398 -155.491215) (xy 336.773484 -155.447072)
			(xy 336.813633 -155.408363) (xy 336.858991 -155.375912) (xy 336.908591 -155.350411) (xy 336.961375 -155.332404)
			(xy 337.016218 -155.322274) (xy 337.071952 -155.320237) (xy 337.127389 -155.326337) (xy 337.181346 -155.340443)
			(xy 337.232675 -155.362255) (xy 337.280281 -155.391309) (xy 337.323149 -155.426984) (xy 337.360366 -155.468521)
			(xy 337.391139 -155.515034) (xy 337.414811 -155.565531) (xy 337.430879 -155.618938) (xy 337.438999 -155.674114)
			(xy 337.439508 -155.702) (xy 337.438999 -155.729886) (xy 337.430879 -155.785062) (xy 337.414811 -155.838469)
			(xy 337.391139 -155.888966) (xy 337.360366 -155.935479) (xy 337.323149 -155.977016) (xy 337.280281 -156.012691)
			(xy 337.232675 -156.041745) (xy 337.181346 -156.063557) (xy 337.127389 -156.077663) (xy 337.071952 -156.083763)
			(xy 337.016218 -156.081726) (xy 336.961375 -156.071596) (xy 336.908591 -156.053589) (xy 336.858991 -156.028088)
			(xy 336.813633 -155.995637) (xy 336.773484 -155.956928) (xy 336.739398 -155.912785) (xy 336.712102 -155.86415)
			(xy 336.692179 -155.812059) (xy 336.680053 -155.757622) (xy 336.675982 -155.702) (xy 325.983092 -155.702)
			(xy 325.352156 -156.332936) (xy 338.256878 -156.332936) (xy 338.260949 -156.277314) (xy 338.273075 -156.222877)
			(xy 338.292998 -156.170786) (xy 338.320294 -156.122151) (xy 338.35438 -156.078008) (xy 338.394529 -156.039299)
			(xy 338.439887 -156.006848) (xy 338.489487 -155.981347) (xy 338.542271 -155.96334) (xy 338.597114 -155.95321)
			(xy 338.652848 -155.951173) (xy 338.708285 -155.957273) (xy 338.762242 -155.971379) (xy 338.813571 -155.993191)
			(xy 338.861177 -156.022245) (xy 338.904045 -156.05792) (xy 338.941262 -156.099457) (xy 338.972035 -156.14597)
			(xy 338.995707 -156.196467) (xy 338.996798 -156.200094) (xy 339.797388 -156.200094) (xy 339.801459 -156.144472)
			(xy 339.813585 -156.090035) (xy 339.833508 -156.037944) (xy 339.860804 -155.989309) (xy 339.89489 -155.945166)
			(xy 339.935039 -155.906457) (xy 339.980397 -155.874006) (xy 340.029997 -155.848505) (xy 340.082781 -155.830498)
			(xy 340.137624 -155.820368) (xy 340.193358 -155.818331) (xy 340.248795 -155.824431) (xy 340.302752 -155.838537)
			(xy 340.354081 -155.860349) (xy 340.401687 -155.889403) (xy 340.444555 -155.925078) (xy 340.481772 -155.966615)
			(xy 340.512545 -156.013128) (xy 340.536217 -156.063625) (xy 340.552285 -156.117032) (xy 340.560405 -156.172208)
			(xy 340.560914 -156.200094) (xy 340.560405 -156.22798) (xy 340.552285 -156.283156) (xy 340.536217 -156.336563)
			(xy 340.512545 -156.38706) (xy 340.481772 -156.433573) (xy 340.444555 -156.47511) (xy 340.401687 -156.510785)
			(xy 340.363478 -156.534104) (xy 349.735392 -156.534104) (xy 349.739463 -156.478482) (xy 349.751589 -156.424045)
			(xy 349.771512 -156.371954) (xy 349.798808 -156.323319) (xy 349.832894 -156.279176) (xy 349.873043 -156.240467)
			(xy 349.918401 -156.208016) (xy 349.968001 -156.182515) (xy 350.020785 -156.164508) (xy 350.075628 -156.154378)
			(xy 350.131362 -156.152341) (xy 350.186799 -156.158441) (xy 350.240756 -156.172547) (xy 350.292085 -156.194359)
			(xy 350.339691 -156.223413) (xy 350.382559 -156.259088) (xy 350.419776 -156.300625) (xy 350.443842 -156.337)
			(xy 352.866196 -156.337) (xy 352.870267 -156.281378) (xy 352.882393 -156.226941) (xy 352.902316 -156.17485)
			(xy 352.929612 -156.126215) (xy 352.963698 -156.082072) (xy 353.003847 -156.043363) (xy 353.049205 -156.010912)
			(xy 353.098805 -155.985411) (xy 353.151589 -155.967404) (xy 353.206432 -155.957274) (xy 353.262166 -155.955237)
			(xy 353.317603 -155.961337) (xy 353.37156 -155.975443) (xy 353.422889 -155.997255) (xy 353.470495 -156.026309)
			(xy 353.513363 -156.061984) (xy 353.55058 -156.103521) (xy 353.581353 -156.150034) (xy 353.605025 -156.200531)
			(xy 353.621093 -156.253938) (xy 353.629213 -156.309114) (xy 353.629722 -156.337) (xy 353.629213 -156.364886)
			(xy 353.621093 -156.420062) (xy 353.605025 -156.473469) (xy 353.581353 -156.523966) (xy 353.55058 -156.570479)
			(xy 353.513363 -156.612016) (xy 353.470495 -156.647691) (xy 353.422889 -156.676745) (xy 353.38259 -156.69387)
			(xy 357.187498 -156.69387) (xy 357.191569 -156.638248) (xy 357.203695 -156.583811) (xy 357.223618 -156.53172)
			(xy 357.250914 -156.483085) (xy 357.285 -156.438942) (xy 357.325149 -156.400233) (xy 357.370507 -156.367782)
			(xy 357.420107 -156.342281) (xy 357.472891 -156.324274) (xy 357.527734 -156.314144) (xy 357.583468 -156.312107)
			(xy 357.638905 -156.318207) (xy 357.692862 -156.332313) (xy 357.744191 -156.354125) (xy 357.791797 -156.383179)
			(xy 357.834665 -156.418854) (xy 357.871882 -156.460391) (xy 357.902655 -156.506904) (xy 357.926327 -156.557401)
			(xy 357.942395 -156.610808) (xy 357.950515 -156.665984) (xy 357.951024 -156.69387) (xy 357.950515 -156.721756)
			(xy 357.942395 -156.776932) (xy 357.926327 -156.830339) (xy 357.902655 -156.880836) (xy 357.871882 -156.927349)
			(xy 357.834665 -156.968886) (xy 357.791797 -157.004561) (xy 357.744191 -157.033615) (xy 357.692862 -157.055427)
			(xy 357.638905 -157.069533) (xy 357.583468 -157.075633) (xy 357.527734 -157.073596) (xy 357.472891 -157.063466)
			(xy 357.420107 -157.045459) (xy 357.370507 -157.019958) (xy 357.325149 -156.987507) (xy 357.285 -156.948798)
			(xy 357.250914 -156.904655) (xy 357.223618 -156.85602) (xy 357.203695 -156.803929) (xy 357.191569 -156.749492)
			(xy 357.187498 -156.69387) (xy 353.38259 -156.69387) (xy 353.37156 -156.698557) (xy 353.317603 -156.712663)
			(xy 353.262166 -156.718763) (xy 353.206432 -156.716726) (xy 353.151589 -156.706596) (xy 353.098805 -156.688589)
			(xy 353.049205 -156.663088) (xy 353.003847 -156.630637) (xy 352.963698 -156.591928) (xy 352.929612 -156.547785)
			(xy 352.902316 -156.49915) (xy 352.882393 -156.447059) (xy 352.870267 -156.392622) (xy 352.866196 -156.337)
			(xy 350.443842 -156.337) (xy 350.450549 -156.347138) (xy 350.474221 -156.397635) (xy 350.490289 -156.451042)
			(xy 350.498409 -156.506218) (xy 350.498918 -156.534104) (xy 350.498409 -156.56199) (xy 350.490289 -156.617166)
			(xy 350.474221 -156.670573) (xy 350.450549 -156.72107) (xy 350.419776 -156.767583) (xy 350.382559 -156.80912)
			(xy 350.339691 -156.844795) (xy 350.292085 -156.873849) (xy 350.240756 -156.895661) (xy 350.186799 -156.909767)
			(xy 350.131362 -156.915867) (xy 350.075628 -156.91383) (xy 350.020785 -156.9037) (xy 349.968001 -156.885693)
			(xy 349.918401 -156.860192) (xy 349.873043 -156.827741) (xy 349.832894 -156.789032) (xy 349.798808 -156.744889)
			(xy 349.771512 -156.696254) (xy 349.751589 -156.644163) (xy 349.739463 -156.589726) (xy 349.735392 -156.534104)
			(xy 340.363478 -156.534104) (xy 340.354081 -156.539839) (xy 340.302752 -156.561651) (xy 340.248795 -156.575757)
			(xy 340.193358 -156.581857) (xy 340.137624 -156.57982) (xy 340.082781 -156.56969) (xy 340.029997 -156.551683)
			(xy 339.980397 -156.526182) (xy 339.935039 -156.493731) (xy 339.89489 -156.455022) (xy 339.860804 -156.410879)
			(xy 339.833508 -156.362244) (xy 339.813585 -156.310153) (xy 339.801459 -156.255716) (xy 339.797388 -156.200094)
			(xy 338.996798 -156.200094) (xy 339.011775 -156.249874) (xy 339.019895 -156.30505) (xy 339.020404 -156.332936)
			(xy 339.019895 -156.360822) (xy 339.011775 -156.415998) (xy 338.995707 -156.469405) (xy 338.972035 -156.519902)
			(xy 338.941262 -156.566415) (xy 338.904045 -156.607952) (xy 338.861177 -156.643627) (xy 338.813571 -156.672681)
			(xy 338.762242 -156.694493) (xy 338.708285 -156.708599) (xy 338.652848 -156.714699) (xy 338.597114 -156.712662)
			(xy 338.542271 -156.702532) (xy 338.489487 -156.684525) (xy 338.439887 -156.659024) (xy 338.394529 -156.626573)
			(xy 338.35438 -156.587864) (xy 338.320294 -156.543721) (xy 338.292998 -156.495086) (xy 338.273075 -156.442995)
			(xy 338.260949 -156.388558) (xy 338.256878 -156.332936) (xy 325.352156 -156.332936) (xy 324.437502 -157.24759)
			(xy 341.166702 -157.24759) (xy 341.170773 -157.191968) (xy 341.182899 -157.137531) (xy 341.202822 -157.08544)
			(xy 341.230118 -157.036805) (xy 341.264204 -156.992662) (xy 341.304353 -156.953953) (xy 341.349711 -156.921502)
			(xy 341.399311 -156.896001) (xy 341.452095 -156.877994) (xy 341.506938 -156.867864) (xy 341.562672 -156.865827)
			(xy 341.618109 -156.871927) (xy 341.672066 -156.886033) (xy 341.723395 -156.907845) (xy 341.771001 -156.936899)
			(xy 341.813869 -156.972574) (xy 341.851086 -157.014111) (xy 341.881859 -157.060624) (xy 341.891157 -157.080458)
			(xy 351.054414 -157.080458) (xy 351.058485 -157.024836) (xy 351.070611 -156.970399) (xy 351.090534 -156.918308)
			(xy 351.11783 -156.869673) (xy 351.151916 -156.82553) (xy 351.192065 -156.786821) (xy 351.237423 -156.75437)
			(xy 351.287023 -156.728869) (xy 351.339807 -156.710862) (xy 351.39465 -156.700732) (xy 351.450384 -156.698695)
			(xy 351.505821 -156.704795) (xy 351.559778 -156.718901) (xy 351.611107 -156.740713) (xy 351.658713 -156.769767)
			(xy 351.701581 -156.805442) (xy 351.738798 -156.846979) (xy 351.769571 -156.893492) (xy 351.793243 -156.943989)
			(xy 351.809311 -156.997396) (xy 351.817431 -157.052572) (xy 351.81794 -157.080458) (xy 351.817431 -157.108344)
			(xy 351.809311 -157.16352) (xy 351.793243 -157.216927) (xy 351.769571 -157.267424) (xy 351.738798 -157.313937)
			(xy 351.701581 -157.355474) (xy 351.658713 -157.391149) (xy 351.611107 -157.420203) (xy 351.559778 -157.442015)
			(xy 351.505821 -157.456121) (xy 351.450384 -157.462221) (xy 351.39465 -157.460184) (xy 351.339807 -157.450054)
			(xy 351.287023 -157.432047) (xy 351.237423 -157.406546) (xy 351.192065 -157.374095) (xy 351.151916 -157.335386)
			(xy 351.11783 -157.291243) (xy 351.090534 -157.242608) (xy 351.070611 -157.190517) (xy 351.058485 -157.13608)
			(xy 351.054414 -157.080458) (xy 341.891157 -157.080458) (xy 341.905531 -157.111121) (xy 341.921599 -157.164528)
			(xy 341.929719 -157.219704) (xy 341.930228 -157.24759) (xy 341.929719 -157.275476) (xy 341.921599 -157.330652)
			(xy 341.905531 -157.384059) (xy 341.881859 -157.434556) (xy 341.851086 -157.481069) (xy 341.813869 -157.522606)
			(xy 341.771001 -157.558281) (xy 341.723395 -157.587335) (xy 341.672066 -157.609147) (xy 341.618109 -157.623253)
			(xy 341.562672 -157.629353) (xy 341.506938 -157.627316) (xy 341.452095 -157.617186) (xy 341.399311 -157.599179)
			(xy 341.349711 -157.573678) (xy 341.304353 -157.541227) (xy 341.264204 -157.502518) (xy 341.230118 -157.458375)
			(xy 341.202822 -157.40974) (xy 341.182899 -157.357649) (xy 341.170773 -157.303212) (xy 341.166702 -157.24759)
			(xy 324.437502 -157.24759) (xy 323.951092 -157.734) (xy 334.643982 -157.734) (xy 334.648053 -157.678378)
			(xy 334.660179 -157.623941) (xy 334.680102 -157.57185) (xy 334.707398 -157.523215) (xy 334.741484 -157.479072)
			(xy 334.781633 -157.440363) (xy 334.826991 -157.407912) (xy 334.876591 -157.382411) (xy 334.929375 -157.364404)
			(xy 334.984218 -157.354274) (xy 335.039952 -157.352237) (xy 335.095389 -157.358337) (xy 335.149346 -157.372443)
			(xy 335.200675 -157.394255) (xy 335.248281 -157.423309) (xy 335.291149 -157.458984) (xy 335.328366 -157.500521)
			(xy 335.359139 -157.547034) (xy 335.382811 -157.597531) (xy 335.398879 -157.650938) (xy 335.406999 -157.706114)
			(xy 335.407508 -157.734) (xy 336.676492 -157.734) (xy 336.676978 -157.706749) (xy 336.684734 -157.652801)
			(xy 336.700089 -157.600506) (xy 336.722731 -157.550929) (xy 336.752197 -157.505079) (xy 336.787888 -157.463888)
			(xy 336.829079 -157.428197) (xy 336.874929 -157.398731) (xy 336.924506 -157.376089) (xy 336.976801 -157.360734)
			(xy 337.030749 -157.352978) (xy 337.085251 -157.352978) (xy 337.139199 -157.360734) (xy 337.191494 -157.376089)
			(xy 337.241071 -157.398731) (xy 337.286921 -157.428197) (xy 337.328112 -157.463888) (xy 337.363803 -157.505079)
			(xy 337.393269 -157.550929) (xy 337.415911 -157.600506) (xy 337.431266 -157.652801) (xy 337.439022 -157.706749)
			(xy 337.439508 -157.734) (xy 337.43902 -157.762071) (xy 337.43078 -157.817605) (xy 337.414492 -157.871333)
			(xy 337.390509 -157.922094) (xy 337.359348 -157.968794) (xy 337.32168 -158.010425) (xy 337.300316 -158.02864)
			(xy 337.291426 -158.036006) (xy 337.28286 -158.05404) (xy 338.84311 -158.05404) (xy 338.847181 -157.998418)
			(xy 338.859307 -157.943981) (xy 338.87923 -157.89189) (xy 338.906526 -157.843255) (xy 338.940612 -157.799112)
			(xy 338.980761 -157.760403) (xy 339.026119 -157.727952) (xy 339.075719 -157.702451) (xy 339.128503 -157.684444)
			(xy 339.183346 -157.674314) (xy 339.23908 -157.672277) (xy 339.294517 -157.678377) (xy 339.348474 -157.692483)
			(xy 339.399803 -157.714295) (xy 339.447409 -157.743349) (xy 339.490277 -157.779024) (xy 339.520714 -157.812994)
			(xy 354.950266 -157.812994) (xy 354.954337 -157.757372) (xy 354.966463 -157.702935) (xy 354.986386 -157.650844)
			(xy 355.013682 -157.602209) (xy 355.047768 -157.558066) (xy 355.087917 -157.519357) (xy 355.133275 -157.486906)
			(xy 355.182875 -157.461405) (xy 355.235659 -157.443398) (xy 355.290502 -157.433268) (xy 355.346236 -157.431231)
			(xy 355.401673 -157.437331) (xy 355.45563 -157.451437) (xy 355.506959 -157.473249) (xy 355.554565 -157.502303)
			(xy 355.597433 -157.537978) (xy 355.63465 -157.579515) (xy 355.665423 -157.626028) (xy 355.675673 -157.647894)
			(xy 359.313988 -157.647894) (xy 359.314524 -157.621251) (xy 359.323048 -157.568653) (xy 359.339905 -157.518105)
			(xy 359.364658 -157.470919) (xy 359.396665 -157.428318) (xy 359.435096 -157.391409) (xy 359.456736 -157.37586)
			(xy 359.468026 -157.367502) (xy 359.485877 -157.345826) (xy 359.497157 -157.320111) (xy 359.501013 -157.292297)
			(xy 359.497155 -157.264483) (xy 359.485874 -157.238768) (xy 359.468021 -157.217094) (xy 359.456736 -157.208728)
			(xy 359.435134 -157.193132) (xy 359.396719 -157.156218) (xy 359.364719 -157.113623) (xy 359.339961 -157.066449)
			(xy 359.323086 -157.015916) (xy 359.31453 -156.963332) (xy 359.313988 -156.936694) (xy 359.314498 -156.910707)
			(xy 359.322628 -156.859372) (xy 359.338689 -156.809942) (xy 359.362285 -156.763632) (xy 359.392835 -156.721584)
			(xy 359.429586 -156.684833) (xy 359.471634 -156.654283) (xy 359.517944 -156.630687) (xy 359.567374 -156.614626)
			(xy 359.618709 -156.606496) (xy 359.670683 -156.606496) (xy 359.722018 -156.614626) (xy 359.771448 -156.630687)
			(xy 359.817758 -156.654283) (xy 359.859806 -156.684833) (xy 359.896557 -156.721584) (xy 359.927107 -156.763632)
			(xy 359.950703 -156.809942) (xy 359.966764 -156.859372) (xy 359.974894 -156.910707) (xy 359.975404 -156.936694)
			(xy 359.974862 -156.963336) (xy 359.96634 -157.015935) (xy 359.949485 -157.066483) (xy 359.924733 -157.113669)
			(xy 359.892726 -157.15627) (xy 359.854296 -157.193179) (xy 359.832656 -157.208728) (xy 359.821379 -157.217101)
			(xy 359.803529 -157.238774) (xy 359.79225 -157.264486) (xy 359.788392 -157.292297) (xy 359.792248 -157.320108)
			(xy 359.803525 -157.34582) (xy 359.821374 -157.367494) (xy 359.832656 -157.37586) (xy 359.854251 -157.391466)
			(xy 359.892666 -157.428378) (xy 359.924667 -157.47097) (xy 359.949427 -157.518142) (xy 359.966303 -157.568674)
			(xy 359.974861 -157.621257) (xy 359.975404 -157.647894) (xy 360.21391 -157.647894) (xy 360.214437 -157.621251)
			(xy 360.222961 -157.568652) (xy 360.239819 -157.518103) (xy 360.264574 -157.470917) (xy 360.296583 -157.428317)
			(xy 360.335017 -157.391408) (xy 360.356658 -157.37586) (xy 360.367946 -157.3675) (xy 360.385793 -157.345824)
			(xy 360.39707 -157.320109) (xy 360.400926 -157.292297) (xy 360.397068 -157.264484) (xy 360.38579 -157.23877)
			(xy 360.367941 -157.217095) (xy 360.356658 -157.208728) (xy 360.335061 -157.193125) (xy 360.296645 -157.156214)
			(xy 360.264643 -157.11362) (xy 360.239884 -157.066447) (xy 360.223009 -157.015915) (xy 360.214452 -156.963332)
			(xy 360.21391 -156.936694) (xy 360.21442 -156.910707) (xy 360.22255 -156.859372) (xy 360.238611 -156.809942)
			(xy 360.262207 -156.763632) (xy 360.292757 -156.721584) (xy 360.329508 -156.684833) (xy 360.371556 -156.654283)
			(xy 360.417866 -156.630687) (xy 360.467296 -156.614626) (xy 360.518631 -156.606496) (xy 360.570605 -156.606496)
			(xy 360.62194 -156.614626) (xy 360.67137 -156.630687) (xy 360.71768 -156.654283) (xy 360.759728 -156.684833)
			(xy 360.796479 -156.721584) (xy 360.827029 -156.763632) (xy 360.850625 -156.809942) (xy 360.866686 -156.859372)
			(xy 360.874816 -156.910707) (xy 360.875326 -156.936694) (xy 360.874817 -156.963338) (xy 360.866294 -157.01594)
			(xy 360.849434 -157.06649) (xy 360.824675 -157.113677) (xy 360.792661 -157.156276) (xy 360.754222 -157.193182)
			(xy 360.732578 -157.208728) (xy 360.721299 -157.2171) (xy 360.703445 -157.238772) (xy 360.692163 -157.264484)
			(xy 360.688305 -157.292297) (xy 360.692161 -157.320109) (xy 360.703441 -157.345823) (xy 360.721294 -157.367495)
			(xy 360.732578 -157.37586) (xy 360.754178 -157.391459) (xy 360.792592 -157.428373) (xy 360.824592 -157.470967)
			(xy 360.84935 -157.518141) (xy 360.866226 -157.568673) (xy 360.874783 -157.621256) (xy 360.875326 -157.647894)
			(xy 361.113832 -157.647894) (xy 361.11435 -157.62125) (xy 361.122874 -157.56865) (xy 361.139734 -157.518101)
			(xy 361.16449 -157.470914) (xy 361.196502 -157.428315) (xy 361.234937 -157.391407) (xy 361.25658 -157.37586)
			(xy 361.267875 -157.367505) (xy 361.285736 -157.345832) (xy 361.297022 -157.320115) (xy 361.300881 -157.292297)
			(xy 361.29702 -157.264479) (xy 361.285732 -157.238762) (xy 361.26787 -157.217091) (xy 361.25658 -157.208728)
			(xy 361.234987 -157.193119) (xy 361.19657 -157.156209) (xy 361.164567 -157.113617) (xy 361.139808 -157.066446)
			(xy 361.122931 -157.015915) (xy 361.114374 -156.963331) (xy 361.113832 -156.936694) (xy 361.114342 -156.910707)
			(xy 361.122472 -156.859372) (xy 361.138533 -156.809942) (xy 361.162129 -156.763632) (xy 361.192679 -156.721584)
			(xy 361.22943 -156.684833) (xy 361.271478 -156.654283) (xy 361.317788 -156.630687) (xy 361.367218 -156.614626)
			(xy 361.418553 -156.606496) (xy 361.470527 -156.606496) (xy 361.521862 -156.614626) (xy 361.571292 -156.630687)
			(xy 361.617602 -156.654283) (xy 361.65965 -156.684833) (xy 361.696401 -156.721584) (xy 361.726951 -156.763632)
			(xy 361.750547 -156.809942) (xy 361.766608 -156.859372) (xy 361.774738 -156.910707) (xy 361.775248 -156.936694)
			(xy 361.77473 -156.963338) (xy 361.766207 -157.015938) (xy 361.749348 -157.066488) (xy 361.724592 -157.113675)
			(xy 361.69258 -157.156274) (xy 361.654143 -157.193181) (xy 361.6325 -157.208728) (xy 361.621219 -157.217099)
			(xy 361.603362 -157.23877) (xy 361.592077 -157.264483) (xy 361.588218 -157.292297) (xy 361.592075 -157.320111)
			(xy 361.603358 -157.345825) (xy 361.621214 -157.367496) (xy 361.6325 -157.37586) (xy 361.654083 -157.391483)
			(xy 361.692501 -157.428389) (xy 361.724506 -157.470977) (xy 361.749267 -157.518147) (xy 361.766146 -157.568676)
			(xy 361.774705 -157.621257) (xy 361.775248 -157.647894) (xy 362.014008 -157.647894) (xy 362.014536 -157.621251)
			(xy 362.02306 -157.568652) (xy 362.039918 -157.518103) (xy 362.064672 -157.470917) (xy 362.096682 -157.428317)
			(xy 362.135115 -157.391408) (xy 362.156756 -157.37586) (xy 362.168044 -157.367501) (xy 362.185892 -157.345824)
			(xy 362.197169 -157.320109) (xy 362.201024 -157.292297) (xy 362.197167 -157.264484) (xy 362.185888 -157.23877)
			(xy 362.168039 -157.217095) (xy 362.156756 -157.208728) (xy 362.135158 -157.193126) (xy 362.096742 -157.156214)
			(xy 362.064741 -157.113621) (xy 362.039982 -157.066448) (xy 362.023107 -157.015916) (xy 362.01455 -156.963332)
			(xy 362.014008 -156.936694) (xy 362.014518 -156.910707) (xy 362.022648 -156.859372) (xy 362.038709 -156.809942)
			(xy 362.062305 -156.763632) (xy 362.092855 -156.721584) (xy 362.129606 -156.684833) (xy 362.171654 -156.654283)
			(xy 362.217964 -156.630687) (xy 362.267394 -156.614626) (xy 362.318729 -156.606496) (xy 362.370703 -156.606496)
			(xy 362.422038 -156.614626) (xy 362.471468 -156.630687) (xy 362.517778 -156.654283) (xy 362.559826 -156.684833)
			(xy 362.596577 -156.721584) (xy 362.627127 -156.763632) (xy 362.650723 -156.809942) (xy 362.666784 -156.859372)
			(xy 362.674914 -156.910707) (xy 362.675424 -156.936694) (xy 362.674916 -156.963338) (xy 362.666392 -157.01594)
			(xy 362.649532 -157.06649) (xy 362.624774 -157.113677) (xy 362.59276 -157.156276) (xy 362.55432 -157.193182)
			(xy 362.532676 -157.208728) (xy 362.521397 -157.2171) (xy 362.503544 -157.238772) (xy 362.492262 -157.264484)
			(xy 362.488404 -157.292297) (xy 362.49226 -157.320109) (xy 362.50354 -157.345822) (xy 362.521392 -157.367495)
			(xy 362.532676 -157.37586) (xy 362.554275 -157.39146) (xy 362.592689 -157.428374) (xy 362.624689 -157.470968)
			(xy 362.649448 -157.518141) (xy 362.666324 -157.568673) (xy 362.674881 -157.621256) (xy 362.675383 -157.645862)
			(xy 363.629448 -157.645862) (xy 363.629875 -157.619546) (xy 363.637116 -157.567416) (xy 363.651442 -157.516771)
			(xy 363.672582 -157.468572) (xy 363.700136 -157.42373) (xy 363.733582 -157.383093) (xy 363.752638 -157.364938)
			(xy 363.760016 -157.357396) (xy 363.768556 -157.338132) (xy 363.769148 -157.3276) (xy 363.769148 -157.252924)
			(xy 363.768605 -157.242376) (xy 363.760078 -157.223082) (xy 363.752638 -157.215586) (xy 363.733571 -157.197442)
			(xy 363.700117 -157.156809) (xy 363.672561 -157.111965) (xy 363.651425 -157.063763) (xy 363.63711 -157.013114)
			(xy 363.629886 -156.960979) (xy 363.629448 -156.934662) (xy 363.629934 -156.907411) (xy 363.63769 -156.853463)
			(xy 363.653045 -156.801168) (xy 363.675687 -156.751591) (xy 363.705153 -156.705741) (xy 363.740844 -156.66455)
			(xy 363.782035 -156.628859) (xy 363.827885 -156.599393) (xy 363.877462 -156.576751) (xy 363.929757 -156.561396)
			(xy 363.983705 -156.55364) (xy 364.038207 -156.55364) (xy 364.092155 -156.561396) (xy 364.14445 -156.576751)
			(xy 364.194027 -156.599393) (xy 364.239877 -156.628859) (xy 364.258622 -156.645101) (xy 365.614017 -156.645101)
			(xy 365.618332 -156.587828) (xy 365.631182 -156.531849) (xy 365.652276 -156.478427) (xy 365.681137 -156.428769)
			(xy 365.717113 -156.383997) (xy 365.737902 -156.364178) (xy 365.745315 -156.356667) (xy 365.753833 -156.337379)
			(xy 365.754412 -156.32684) (xy 365.754412 -156.252164) (xy 365.753858 -156.241617) (xy 365.74534 -156.222322)
			(xy 365.737902 -156.214826) (xy 365.718866 -156.19665) (xy 365.685407 -156.156025) (xy 365.657846 -156.111189)
			(xy 365.636704 -156.062992) (xy 365.622382 -156.012348) (xy 365.615153 -155.960217) (xy 365.614712 -155.933902)
			(xy 365.615198 -155.906651) (xy 365.622954 -155.852703) (xy 365.638309 -155.800408) (xy 365.660951 -155.750831)
			(xy 365.690417 -155.704981) (xy 365.726108 -155.66379) (xy 365.767299 -155.628099) (xy 365.813149 -155.598633)
			(xy 365.862726 -155.575991) (xy 365.915021 -155.560636) (xy 365.968969 -155.55288) (xy 366.023471 -155.55288)
			(xy 366.077419 -155.560636) (xy 366.129714 -155.575991) (xy 366.179291 -155.598633) (xy 366.225141 -155.628099)
			(xy 366.266332 -155.66379) (xy 366.302023 -155.704981) (xy 366.331489 -155.750831) (xy 366.354131 -155.800408)
			(xy 366.369486 -155.852703) (xy 366.377242 -155.906651) (xy 366.377728 -155.933902) (xy 366.377253 -155.960216)
			(xy 366.370018 -156.012343) (xy 366.3557 -156.062986) (xy 366.334569 -156.111184) (xy 366.307025 -156.156028)
			(xy 366.273588 -156.196669) (xy 366.254538 -156.214826) (xy 366.247129 -156.222341) (xy 366.238608 -156.241626)
			(xy 366.238028 -156.252164) (xy 366.238028 -156.32684) (xy 366.238568 -156.337389) (xy 366.247095 -156.356685)
			(xy 366.254538 -156.364178) (xy 366.275327 -156.383996) (xy 366.3113 -156.42877) (xy 366.340158 -156.478428)
			(xy 366.36125 -156.53185) (xy 366.374098 -156.587829) (xy 366.378413 -156.645101) (xy 366.374098 -156.702374)
			(xy 366.372962 -156.707322) (xy 368.679825 -156.707322) (xy 368.684137 -156.650052) (xy 368.696983 -156.594076)
			(xy 368.718071 -156.540656) (xy 368.746926 -156.491) (xy 368.782897 -156.446228) (xy 368.803682 -156.426408)
			(xy 368.811079 -156.418883) (xy 368.819607 -156.399606) (xy 368.820192 -156.38907) (xy 368.820192 -156.314394)
			(xy 368.819682 -156.303842) (xy 368.811133 -156.284547) (xy 368.803682 -156.277056) (xy 368.784609 -156.258918)
			(xy 368.751154 -156.218284) (xy 368.723598 -156.17344) (xy 368.702462 -156.125236) (xy 368.688149 -156.074586)
			(xy 368.680928 -156.022449) (xy 368.680492 -155.996132) (xy 368.680978 -155.968881) (xy 368.688734 -155.914933)
			(xy 368.704089 -155.862638) (xy 368.726731 -155.813061) (xy 368.756197 -155.767211) (xy 368.791888 -155.72602)
			(xy 368.833079 -155.690329) (xy 368.878929 -155.660863) (xy 368.928506 -155.638221) (xy 368.980801 -155.622866)
			(xy 369.034749 -155.61511) (xy 369.089251 -155.61511) (xy 369.143199 -155.622866) (xy 369.195494 -155.638221)
			(xy 369.245071 -155.660863) (xy 369.290921 -155.690329) (xy 369.332112 -155.72602) (xy 369.367803 -155.767211)
			(xy 369.397269 -155.813061) (xy 369.419911 -155.862638) (xy 369.435266 -155.914933) (xy 369.443022 -155.968881)
			(xy 369.443508 -155.996132) (xy 369.443059 -156.022447) (xy 369.43582 -156.074576) (xy 369.421497 -156.125219)
			(xy 369.400361 -156.173418) (xy 369.372812 -156.218261) (xy 369.339371 -156.2589) (xy 369.320318 -156.277056)
			(xy 369.312936 -156.284594) (xy 369.3044 -156.303862) (xy 369.303808 -156.314394) (xy 369.303808 -156.38907)
			(xy 369.304337 -156.39962) (xy 369.312872 -156.418915) (xy 369.320318 -156.426408) (xy 369.341138 -156.446196)
			(xy 369.377113 -156.490973) (xy 369.405971 -156.540635) (xy 369.427062 -156.594062) (xy 369.439909 -156.650045)
			(xy 369.444222 -156.707322) (xy 369.439903 -156.764598) (xy 369.427049 -156.82058) (xy 369.405952 -156.874004)
			(xy 369.377088 -156.923663) (xy 369.341108 -156.968436) (xy 369.320318 -156.988256) (xy 369.312936 -156.995794)
			(xy 369.3044 -157.015062) (xy 369.303808 -157.025594) (xy 369.303808 -157.10027) (xy 369.304337 -157.11082)
			(xy 369.312872 -157.130115) (xy 369.320318 -157.137608) (xy 369.339374 -157.155763) (xy 369.37283 -157.196393)
			(xy 369.400389 -157.241234) (xy 369.421527 -157.289435) (xy 369.435844 -157.340082) (xy 369.443069 -157.392216)
			(xy 369.443508 -157.418532) (xy 369.443022 -157.445783) (xy 369.435266 -157.499731) (xy 369.419911 -157.552026)
			(xy 369.397269 -157.601603) (xy 369.367803 -157.647453) (xy 369.332112 -157.688644) (xy 369.290921 -157.724335)
			(xy 369.245071 -157.753801) (xy 369.195494 -157.776443) (xy 369.143199 -157.791798) (xy 369.089251 -157.799554)
			(xy 369.034749 -157.799554) (xy 368.980801 -157.791798) (xy 368.928506 -157.776443) (xy 368.878929 -157.753801)
			(xy 368.833079 -157.724335) (xy 368.791888 -157.688644) (xy 368.756197 -157.647453) (xy 368.726731 -157.601603)
			(xy 368.704089 -157.552026) (xy 368.688734 -157.499731) (xy 368.680978 -157.445783) (xy 368.680492 -157.418532)
			(xy 368.680917 -157.392217) (xy 368.688161 -157.340086) (xy 368.702488 -157.289443) (xy 368.723629 -157.241244)
			(xy 368.751182 -157.196402) (xy 368.784627 -157.155764) (xy 368.803682 -157.137608) (xy 368.811079 -157.130083)
			(xy 368.819607 -157.110806) (xy 368.820192 -157.10027) (xy 368.820192 -157.025594) (xy 368.819682 -157.015042)
			(xy 368.811133 -156.995747) (xy 368.803682 -156.988256) (xy 368.782926 -156.968404) (xy 368.746951 -156.923636)
			(xy 368.71809 -156.873983) (xy 368.696996 -156.820566) (xy 368.684144 -156.764591) (xy 368.679825 -156.707322)
			(xy 366.372962 -156.707322) (xy 366.361249 -156.758353) (xy 366.340157 -156.811774) (xy 366.311299 -156.861432)
			(xy 366.275325 -156.906205) (xy 366.254538 -156.926026) (xy 366.247129 -156.933541) (xy 366.238608 -156.952826)
			(xy 366.238028 -156.963364) (xy 366.238028 -157.03804) (xy 366.238568 -157.048589) (xy 366.247095 -157.067885)
			(xy 366.254538 -157.075378) (xy 366.273583 -157.093544) (xy 366.30704 -157.134172) (xy 366.334599 -157.179011)
			(xy 366.355739 -157.227209) (xy 366.370059 -157.277854) (xy 366.377287 -157.329987) (xy 366.377728 -157.356302)
			(xy 366.377242 -157.383553) (xy 366.369486 -157.437501) (xy 366.354131 -157.489796) (xy 366.331489 -157.539373)
			(xy 366.302023 -157.585223) (xy 366.266332 -157.626414) (xy 366.225141 -157.662105) (xy 366.179291 -157.691571)
			(xy 366.129714 -157.714213) (xy 366.077419 -157.729568) (xy 366.023471 -157.737324) (xy 365.968969 -157.737324)
			(xy 365.915021 -157.729568) (xy 365.862726 -157.714213) (xy 365.813149 -157.691571) (xy 365.767299 -157.662105)
			(xy 365.726108 -157.626414) (xy 365.690417 -157.585223) (xy 365.660951 -157.539373) (xy 365.638309 -157.489796)
			(xy 365.622954 -157.437501) (xy 365.615198 -157.383553) (xy 365.614712 -157.356302) (xy 365.615177 -157.329988)
			(xy 365.622412 -157.277859) (xy 365.636731 -157.227216) (xy 365.657864 -157.179017) (xy 365.685411 -157.134174)
			(xy 365.71885 -157.093534) (xy 365.737902 -157.075378) (xy 365.745315 -157.067867) (xy 365.753833 -157.048579)
			(xy 365.754412 -157.03804) (xy 365.754412 -156.963364) (xy 365.753858 -156.952817) (xy 365.74534 -156.933522)
			(xy 365.737902 -156.926026) (xy 365.717115 -156.906205) (xy 365.681138 -156.861433) (xy 365.652277 -156.811776)
			(xy 365.631183 -156.758354) (xy 365.618333 -156.702374) (xy 365.614017 -156.645101) (xy 364.258622 -156.645101)
			(xy 364.281068 -156.66455) (xy 364.316759 -156.705741) (xy 364.346225 -156.751591) (xy 364.368867 -156.801168)
			(xy 364.384222 -156.853463) (xy 364.391978 -156.907411) (xy 364.392464 -156.934662) (xy 364.392049 -156.960978)
			(xy 364.384805 -157.013109) (xy 364.370477 -157.063753) (xy 364.349334 -157.111952) (xy 364.321778 -157.156794)
			(xy 364.28833 -157.197431) (xy 364.269274 -157.215586) (xy 364.261887 -157.223121) (xy 364.253352 -157.24239)
			(xy 364.252764 -157.252924) (xy 364.252764 -157.3276) (xy 364.25329 -157.33815) (xy 364.261829 -157.357444)
			(xy 364.269274 -157.364938) (xy 364.288336 -157.383087) (xy 364.321794 -157.423718) (xy 364.349352 -157.468559)
			(xy 364.37049 -157.516761) (xy 364.384805 -157.56741) (xy 364.392027 -157.619545) (xy 364.392464 -157.645862)
			(xy 364.391978 -157.673113) (xy 364.384222 -157.727061) (xy 364.368867 -157.779356) (xy 364.346225 -157.828933)
			(xy 364.316759 -157.874783) (xy 364.281068 -157.915974) (xy 364.239877 -157.951665) (xy 364.194027 -157.981131)
			(xy 364.14445 -158.003773) (xy 364.092155 -158.019128) (xy 364.038207 -158.026884) (xy 363.983705 -158.026884)
			(xy 363.929757 -158.019128) (xy 363.877462 -158.003773) (xy 363.827885 -157.981131) (xy 363.782035 -157.951665)
			(xy 363.740844 -157.915974) (xy 363.705153 -157.874783) (xy 363.675687 -157.828933) (xy 363.653045 -157.779356)
			(xy 363.63769 -157.727061) (xy 363.629934 -157.673113) (xy 363.629448 -157.645862) (xy 362.675383 -157.645862)
			(xy 362.675424 -157.647894) (xy 362.674914 -157.673881) (xy 362.666784 -157.725216) (xy 362.650723 -157.774646)
			(xy 362.627127 -157.820956) (xy 362.596577 -157.863004) (xy 362.559826 -157.899755) (xy 362.517778 -157.930305)
			(xy 362.471468 -157.953901) (xy 362.422038 -157.969962) (xy 362.370703 -157.978092) (xy 362.318729 -157.978092)
			(xy 362.267394 -157.969962) (xy 362.217964 -157.953901) (xy 362.171654 -157.930305) (xy 362.129606 -157.899755)
			(xy 362.092855 -157.863004) (xy 362.062305 -157.820956) (xy 362.038709 -157.774646) (xy 362.022648 -157.725216)
			(xy 362.014518 -157.673881) (xy 362.014008 -157.647894) (xy 361.775248 -157.647894) (xy 361.774738 -157.673881)
			(xy 361.766608 -157.725216) (xy 361.750547 -157.774646) (xy 361.726951 -157.820956) (xy 361.696401 -157.863004)
			(xy 361.65965 -157.899755) (xy 361.617602 -157.930305) (xy 361.571292 -157.953901) (xy 361.521862 -157.969962)
			(xy 361.470527 -157.978092) (xy 361.418553 -157.978092) (xy 361.367218 -157.969962) (xy 361.317788 -157.953901)
			(xy 361.271478 -157.930305) (xy 361.22943 -157.899755) (xy 361.192679 -157.863004) (xy 361.162129 -157.820956)
			(xy 361.138533 -157.774646) (xy 361.122472 -157.725216) (xy 361.114342 -157.673881) (xy 361.113832 -157.647894)
			(xy 360.875326 -157.647894) (xy 360.874816 -157.673881) (xy 360.866686 -157.725216) (xy 360.850625 -157.774646)
			(xy 360.827029 -157.820956) (xy 360.796479 -157.863004) (xy 360.759728 -157.899755) (xy 360.71768 -157.930305)
			(xy 360.67137 -157.953901) (xy 360.62194 -157.969962) (xy 360.570605 -157.978092) (xy 360.518631 -157.978092)
			(xy 360.467296 -157.969962) (xy 360.417866 -157.953901) (xy 360.371556 -157.930305) (xy 360.329508 -157.899755)
			(xy 360.292757 -157.863004) (xy 360.262207 -157.820956) (xy 360.238611 -157.774646) (xy 360.22255 -157.725216)
			(xy 360.21442 -157.673881) (xy 360.21391 -157.647894) (xy 359.975404 -157.647894) (xy 359.974894 -157.673881)
			(xy 359.966764 -157.725216) (xy 359.950703 -157.774646) (xy 359.927107 -157.820956) (xy 359.896557 -157.863004)
			(xy 359.859806 -157.899755) (xy 359.817758 -157.930305) (xy 359.771448 -157.953901) (xy 359.722018 -157.969962)
			(xy 359.670683 -157.978092) (xy 359.618709 -157.978092) (xy 359.567374 -157.969962) (xy 359.517944 -157.953901)
			(xy 359.471634 -157.930305) (xy 359.429586 -157.899755) (xy 359.392835 -157.863004) (xy 359.362285 -157.820956)
			(xy 359.338689 -157.774646) (xy 359.322628 -157.725216) (xy 359.314498 -157.673881) (xy 359.313988 -157.647894)
			(xy 355.675673 -157.647894) (xy 355.689095 -157.676525) (xy 355.705163 -157.729932) (xy 355.713283 -157.785108)
			(xy 355.713792 -157.812994) (xy 355.713283 -157.84088) (xy 355.705163 -157.896056) (xy 355.689095 -157.949463)
			(xy 355.665423 -157.99996) (xy 355.63465 -158.046473) (xy 355.62218 -158.06039) (xy 357.139746 -158.06039)
			(xy 357.143817 -158.004768) (xy 357.155943 -157.950331) (xy 357.175866 -157.89824) (xy 357.203162 -157.849605)
			(xy 357.237248 -157.805462) (xy 357.277397 -157.766753) (xy 357.322755 -157.734302) (xy 357.372355 -157.708801)
			(xy 357.425139 -157.690794) (xy 357.479982 -157.680664) (xy 357.535716 -157.678627) (xy 357.591153 -157.684727)
			(xy 357.64511 -157.698833) (xy 357.696439 -157.720645) (xy 357.744045 -157.749699) (xy 357.786913 -157.785374)
			(xy 357.82413 -157.826911) (xy 357.854903 -157.873424) (xy 357.878575 -157.923921) (xy 357.894643 -157.977328)
			(xy 357.902763 -158.032504) (xy 357.903272 -158.06039) (xy 357.902763 -158.088276) (xy 357.894643 -158.143452)
			(xy 357.878575 -158.196859) (xy 357.854903 -158.247356) (xy 357.82413 -158.293869) (xy 357.786913 -158.335406)
			(xy 357.744045 -158.371081) (xy 357.696439 -158.400135) (xy 357.64511 -158.421947) (xy 357.591153 -158.436053)
			(xy 357.535716 -158.442153) (xy 357.479982 -158.440116) (xy 357.425139 -158.429986) (xy 357.372355 -158.411979)
			(xy 357.322755 -158.386478) (xy 357.277397 -158.354027) (xy 357.237248 -158.315318) (xy 357.203162 -158.271175)
			(xy 357.175866 -158.22254) (xy 357.155943 -158.170449) (xy 357.143817 -158.116012) (xy 357.139746 -158.06039)
			(xy 355.62218 -158.06039) (xy 355.597433 -158.08801) (xy 355.554565 -158.123685) (xy 355.506959 -158.152739)
			(xy 355.45563 -158.174551) (xy 355.401673 -158.188657) (xy 355.346236 -158.194757) (xy 355.290502 -158.19272)
			(xy 355.235659 -158.18259) (xy 355.182875 -158.164583) (xy 355.133275 -158.139082) (xy 355.087917 -158.106631)
			(xy 355.047768 -158.067922) (xy 355.013682 -158.023779) (xy 354.986386 -157.975144) (xy 354.966463 -157.923053)
			(xy 354.954337 -157.868616) (xy 354.950266 -157.812994) (xy 339.520714 -157.812994) (xy 339.527494 -157.820561)
			(xy 339.558267 -157.867074) (xy 339.581939 -157.917571) (xy 339.598007 -157.970978) (xy 339.606127 -158.026154)
			(xy 339.606636 -158.05404) (xy 339.606127 -158.081926) (xy 339.598007 -158.137102) (xy 339.581939 -158.190509)
			(xy 339.558267 -158.241006) (xy 339.527494 -158.287519) (xy 339.490277 -158.329056) (xy 339.447409 -158.364731)
			(xy 339.399803 -158.393785) (xy 339.348474 -158.415597) (xy 339.299363 -158.428436) (xy 341.597994 -158.428436)
			(xy 341.602065 -158.372814) (xy 341.614191 -158.318377) (xy 341.634114 -158.266286) (xy 341.66141 -158.217651)
			(xy 341.695496 -158.173508) (xy 341.735645 -158.134799) (xy 341.781003 -158.102348) (xy 341.830603 -158.076847)
			(xy 341.883387 -158.05884) (xy 341.93823 -158.04871) (xy 341.993964 -158.046673) (xy 342.049401 -158.052773)
			(xy 342.103358 -158.066879) (xy 342.154687 -158.088691) (xy 342.202293 -158.117745) (xy 342.245161 -158.15342)
			(xy 342.282378 -158.194957) (xy 342.313151 -158.24147) (xy 342.336823 -158.291967) (xy 342.352891 -158.345374)
			(xy 342.361011 -158.40055) (xy 342.361325 -158.417768) (xy 353.080826 -158.417768) (xy 353.084897 -158.362146)
			(xy 353.097023 -158.307709) (xy 353.116946 -158.255618) (xy 353.144242 -158.206983) (xy 353.178328 -158.16284)
			(xy 353.218477 -158.124131) (xy 353.263835 -158.09168) (xy 353.313435 -158.066179) (xy 353.366219 -158.048172)
			(xy 353.421062 -158.038042) (xy 353.476796 -158.036005) (xy 353.532233 -158.042105) (xy 353.58619 -158.056211)
			(xy 353.637519 -158.078023) (xy 353.685125 -158.107077) (xy 353.727993 -158.142752) (xy 353.76521 -158.184289)
			(xy 353.795983 -158.230802) (xy 353.819655 -158.281299) (xy 353.835723 -158.334706) (xy 353.843843 -158.389882)
			(xy 353.844352 -158.417768) (xy 353.843843 -158.445654) (xy 353.835723 -158.50083) (xy 353.819655 -158.554237)
			(xy 353.795983 -158.604734) (xy 353.76521 -158.651247) (xy 353.727993 -158.692784) (xy 353.685125 -158.728459)
			(xy 353.637519 -158.757513) (xy 353.58619 -158.779325) (xy 353.532233 -158.793431) (xy 353.476796 -158.799531)
			(xy 353.421062 -158.797494) (xy 353.366219 -158.787364) (xy 353.313435 -158.769357) (xy 353.263835 -158.743856)
			(xy 353.218477 -158.711405) (xy 353.178328 -158.672696) (xy 353.144242 -158.628553) (xy 353.116946 -158.579918)
			(xy 353.097023 -158.527827) (xy 353.084897 -158.47339) (xy 353.080826 -158.417768) (xy 342.361325 -158.417768)
			(xy 342.36152 -158.428436) (xy 342.361011 -158.456322) (xy 342.352891 -158.511498) (xy 342.336823 -158.564905)
			(xy 342.313151 -158.615402) (xy 342.282378 -158.661915) (xy 342.245161 -158.703452) (xy 342.202293 -158.739127)
			(xy 342.154687 -158.768181) (xy 342.103358 -158.789993) (xy 342.049401 -158.804099) (xy 341.993964 -158.810199)
			(xy 341.93823 -158.808162) (xy 341.883387 -158.798032) (xy 341.830603 -158.780025) (xy 341.781003 -158.754524)
			(xy 341.735645 -158.722073) (xy 341.695496 -158.683364) (xy 341.66141 -158.639221) (xy 341.634114 -158.590586)
			(xy 341.614191 -158.538495) (xy 341.602065 -158.484058) (xy 341.597994 -158.428436) (xy 339.299363 -158.428436)
			(xy 339.294517 -158.429703) (xy 339.23908 -158.435803) (xy 339.183346 -158.433766) (xy 339.128503 -158.423636)
			(xy 339.075719 -158.405629) (xy 339.026119 -158.380128) (xy 338.980761 -158.347677) (xy 338.940612 -158.308968)
			(xy 338.906526 -158.264825) (xy 338.87923 -158.21619) (xy 338.859307 -158.164099) (xy 338.847181 -158.109662)
			(xy 338.84311 -158.05404) (xy 337.28286 -158.05404) (xy 337.281774 -158.056326) (xy 337.282028 -158.146496)
			(xy 337.282705 -158.157714) (xy 337.292301 -158.178004) (xy 337.30057 -158.185612) (xy 337.322018 -158.203824)
			(xy 337.359817 -158.245502) (xy 337.391089 -158.292276) (xy 337.415158 -158.343133) (xy 337.431501 -158.396972)
			(xy 337.439766 -158.452627) (xy 337.44027 -158.48076) (xy 337.439784 -158.508011) (xy 337.432028 -158.561959)
			(xy 337.416673 -158.614254) (xy 337.394031 -158.663831) (xy 337.364565 -158.709681) (xy 337.328874 -158.750872)
			(xy 337.287683 -158.786563) (xy 337.241833 -158.816029) (xy 337.192256 -158.838671) (xy 337.139961 -158.854026)
			(xy 337.086013 -158.861782) (xy 337.031511 -158.861782) (xy 336.977563 -158.854026) (xy 336.925268 -158.838671)
			(xy 336.875691 -158.816029) (xy 336.829841 -158.786563) (xy 336.78865 -158.750872) (xy 336.752959 -158.709681)
			(xy 336.723493 -158.663831) (xy 336.700851 -158.614254) (xy 336.685496 -158.561959) (xy 336.67774 -158.508011)
			(xy 336.677254 -158.48076) (xy 336.677798 -158.452691) (xy 336.686028 -158.39716) (xy 336.702306 -158.343434)
			(xy 336.726279 -158.292673) (xy 336.75743 -158.245971) (xy 336.795087 -158.204338) (xy 336.816446 -158.18612)
			(xy 336.825336 -158.178754) (xy 336.834988 -158.158434) (xy 336.834734 -158.068264) (xy 336.834092 -158.057041)
			(xy 336.824473 -158.036751) (xy 336.816192 -158.029148) (xy 336.794786 -158.010889) (xy 336.756981 -157.969223)
			(xy 336.725702 -157.922459) (xy 336.701625 -157.871611) (xy 336.685274 -157.817779) (xy 336.677001 -157.76213)
			(xy 336.676492 -157.734) (xy 335.407508 -157.734) (xy 335.406999 -157.761886) (xy 335.398879 -157.817062)
			(xy 335.382811 -157.870469) (xy 335.359139 -157.920966) (xy 335.328366 -157.967479) (xy 335.291149 -158.009016)
			(xy 335.248281 -158.044691) (xy 335.200675 -158.073745) (xy 335.149346 -158.095557) (xy 335.095389 -158.109663)
			(xy 335.039952 -158.115763) (xy 334.984218 -158.113726) (xy 334.929375 -158.103596) (xy 334.876591 -158.085589)
			(xy 334.826991 -158.060088) (xy 334.781633 -158.027637) (xy 334.741484 -157.988928) (xy 334.707398 -157.944785)
			(xy 334.680102 -157.89615) (xy 334.660179 -157.844059) (xy 334.648053 -157.789622) (xy 334.643982 -157.734)
			(xy 323.951092 -157.734) (xy 322.935092 -158.75) (xy 334.643982 -158.75) (xy 334.648053 -158.694378)
			(xy 334.660179 -158.639941) (xy 334.680102 -158.58785) (xy 334.707398 -158.539215) (xy 334.741484 -158.495072)
			(xy 334.781633 -158.456363) (xy 334.826991 -158.423912) (xy 334.876591 -158.398411) (xy 334.929375 -158.380404)
			(xy 334.984218 -158.370274) (xy 335.039952 -158.368237) (xy 335.095389 -158.374337) (xy 335.149346 -158.388443)
			(xy 335.200675 -158.410255) (xy 335.248281 -158.439309) (xy 335.291149 -158.474984) (xy 335.328366 -158.516521)
			(xy 335.359139 -158.563034) (xy 335.382811 -158.613531) (xy 335.398879 -158.666938) (xy 335.406999 -158.722114)
			(xy 335.407508 -158.75) (xy 335.406999 -158.777886) (xy 335.398879 -158.833062) (xy 335.382811 -158.886469)
			(xy 335.359139 -158.936966) (xy 335.341845 -158.963106) (xy 340.499444 -158.963106) (xy 340.503515 -158.907484)
			(xy 340.515641 -158.853047) (xy 340.535564 -158.800956) (xy 340.56286 -158.752321) (xy 340.596946 -158.708178)
			(xy 340.637095 -158.669469) (xy 340.682453 -158.637018) (xy 340.732053 -158.611517) (xy 340.784837 -158.59351)
			(xy 340.83968 -158.58338) (xy 340.895414 -158.581343) (xy 340.950851 -158.587443) (xy 341.004808 -158.601549)
			(xy 341.056137 -158.623361) (xy 341.103743 -158.652415) (xy 341.146611 -158.68809) (xy 341.183828 -158.729627)
			(xy 341.214601 -158.77614) (xy 341.238273 -158.826637) (xy 341.238982 -158.828994) (xy 354.950266 -158.828994)
			(xy 354.954337 -158.773372) (xy 354.966463 -158.718935) (xy 354.986386 -158.666844) (xy 355.013682 -158.618209)
			(xy 355.047768 -158.574066) (xy 355.087917 -158.535357) (xy 355.133275 -158.502906) (xy 355.182875 -158.477405)
			(xy 355.235659 -158.459398) (xy 355.290502 -158.449268) (xy 355.346236 -158.447231) (xy 355.401673 -158.453331)
			(xy 355.45563 -158.467437) (xy 355.506959 -158.489249) (xy 355.554565 -158.518303) (xy 355.597433 -158.553978)
			(xy 355.63465 -158.595515) (xy 355.665423 -158.642028) (xy 355.689095 -158.692525) (xy 355.705163 -158.745932)
			(xy 355.706248 -158.753302) (xy 364.816642 -158.753302) (xy 364.820713 -158.69768) (xy 364.832839 -158.643243)
			(xy 364.852762 -158.591152) (xy 364.880058 -158.542517) (xy 364.914144 -158.498374) (xy 364.954293 -158.459665)
			(xy 364.999651 -158.427214) (xy 365.049251 -158.401713) (xy 365.102035 -158.383706) (xy 365.156878 -158.373576)
			(xy 365.212612 -158.371539) (xy 365.268049 -158.377639) (xy 365.322006 -158.391745) (xy 365.373335 -158.413557)
			(xy 365.420941 -158.442611) (xy 365.463809 -158.478286) (xy 365.501026 -158.519823) (xy 365.531799 -158.566336)
			(xy 365.555471 -158.616833) (xy 365.571539 -158.67024) (xy 365.579659 -158.725416) (xy 365.580168 -158.753302)
			(xy 365.579659 -158.781188) (xy 365.571539 -158.836364) (xy 365.555471 -158.889771) (xy 365.531799 -158.940268)
			(xy 365.501026 -158.986781) (xy 365.463809 -159.028318) (xy 365.420941 -159.063993) (xy 365.373335 -159.093047)
			(xy 365.322006 -159.114859) (xy 365.268049 -159.128965) (xy 365.212612 -159.135065) (xy 365.156878 -159.133028)
			(xy 365.102035 -159.122898) (xy 365.049251 -159.104891) (xy 364.999651 -159.07939) (xy 364.954293 -159.046939)
			(xy 364.914144 -159.00823) (xy 364.880058 -158.964087) (xy 364.852762 -158.915452) (xy 364.832839 -158.863361)
			(xy 364.820713 -158.808924) (xy 364.816642 -158.753302) (xy 355.706248 -158.753302) (xy 355.713283 -158.801108)
			(xy 355.713792 -158.828994) (xy 355.713283 -158.85688) (xy 355.705163 -158.912056) (xy 355.689095 -158.965463)
			(xy 355.665423 -159.01596) (xy 355.63465 -159.062473) (xy 355.597433 -159.10401) (xy 355.554565 -159.139685)
			(xy 355.506959 -159.168739) (xy 355.45563 -159.190551) (xy 355.401673 -159.204657) (xy 355.346236 -159.210757)
			(xy 355.290502 -159.20872) (xy 355.235659 -159.19859) (xy 355.182875 -159.180583) (xy 355.133275 -159.155082)
			(xy 355.087917 -159.122631) (xy 355.047768 -159.083922) (xy 355.013682 -159.039779) (xy 354.986386 -158.991144)
			(xy 354.966463 -158.939053) (xy 354.954337 -158.884616) (xy 354.950266 -158.828994) (xy 341.238982 -158.828994)
			(xy 341.254341 -158.880044) (xy 341.262461 -158.93522) (xy 341.26297 -158.963106) (xy 341.262461 -158.990992)
			(xy 341.254341 -159.046168) (xy 341.238273 -159.099575) (xy 341.214601 -159.150072) (xy 341.183828 -159.196585)
			(xy 341.146611 -159.238122) (xy 341.103743 -159.273797) (xy 341.056137 -159.302851) (xy 341.004808 -159.324663)
			(xy 340.950851 -159.338769) (xy 340.895414 -159.344869) (xy 340.83968 -159.342832) (xy 340.784837 -159.332702)
			(xy 340.732053 -159.314695) (xy 340.682453 -159.289194) (xy 340.637095 -159.256743) (xy 340.596946 -159.218034)
			(xy 340.56286 -159.173891) (xy 340.535564 -159.125256) (xy 340.515641 -159.073165) (xy 340.503515 -159.018728)
			(xy 340.499444 -158.963106) (xy 335.341845 -158.963106) (xy 335.328366 -158.983479) (xy 335.291149 -159.025016)
			(xy 335.248281 -159.060691) (xy 335.200675 -159.089745) (xy 335.149346 -159.111557) (xy 335.095389 -159.125663)
			(xy 335.039952 -159.131763) (xy 334.984218 -159.129726) (xy 334.929375 -159.119596) (xy 334.876591 -159.101589)
			(xy 334.826991 -159.076088) (xy 334.781633 -159.043637) (xy 334.741484 -159.004928) (xy 334.707398 -158.960785)
			(xy 334.680102 -158.91215) (xy 334.660179 -158.860059) (xy 334.648053 -158.805622) (xy 334.643982 -158.75)
			(xy 322.935092 -158.75) (xy 321.919092 -159.766) (xy 336.675982 -159.766) (xy 336.680053 -159.710378)
			(xy 336.692179 -159.655941) (xy 336.712102 -159.60385) (xy 336.739398 -159.555215) (xy 336.773484 -159.511072)
			(xy 336.813633 -159.472363) (xy 336.858991 -159.439912) (xy 336.908591 -159.414411) (xy 336.961375 -159.396404)
			(xy 337.016218 -159.386274) (xy 337.071952 -159.384237) (xy 337.127389 -159.390337) (xy 337.181346 -159.404443)
			(xy 337.232675 -159.426255) (xy 337.280281 -159.455309) (xy 337.323149 -159.490984) (xy 337.360366 -159.532521)
			(xy 337.391139 -159.579034) (xy 337.407105 -159.613092) (xy 341.637364 -159.613092) (xy 341.641435 -159.55747)
			(xy 341.653561 -159.503033) (xy 341.673484 -159.450942) (xy 341.70078 -159.402307) (xy 341.734866 -159.358164)
			(xy 341.775015 -159.319455) (xy 341.820373 -159.287004) (xy 341.869973 -159.261503) (xy 341.922757 -159.243496)
			(xy 341.9776 -159.233366) (xy 342.033334 -159.231329) (xy 342.088771 -159.237429) (xy 342.142728 -159.251535)
			(xy 342.194057 -159.273347) (xy 342.241663 -159.302401) (xy 342.284531 -159.338076) (xy 342.321748 -159.379613)
			(xy 342.352521 -159.426126) (xy 342.376193 -159.476623) (xy 342.392261 -159.53003) (xy 342.400381 -159.585206)
			(xy 342.40089 -159.613092) (xy 342.400381 -159.640978) (xy 342.392261 -159.696154) (xy 342.376193 -159.749561)
			(xy 342.352521 -159.800058) (xy 342.321748 -159.846571) (xy 342.284531 -159.888108) (xy 342.241663 -159.923783)
			(xy 342.194057 -159.952837) (xy 342.142728 -159.974649) (xy 342.088771 -159.988755) (xy 342.033334 -159.994855)
			(xy 341.9776 -159.992818) (xy 341.922757 -159.982688) (xy 341.869973 -159.964681) (xy 341.820373 -159.93918)
			(xy 341.775015 -159.906729) (xy 341.734866 -159.86802) (xy 341.70078 -159.823877) (xy 341.673484 -159.775242)
			(xy 341.653561 -159.723151) (xy 341.641435 -159.668714) (xy 341.637364 -159.613092) (xy 337.407105 -159.613092)
			(xy 337.414811 -159.629531) (xy 337.430879 -159.682938) (xy 337.438999 -159.738114) (xy 337.439508 -159.766)
			(xy 337.438999 -159.793886) (xy 337.430879 -159.849062) (xy 337.414811 -159.902469) (xy 337.391139 -159.952966)
			(xy 337.360366 -159.999479) (xy 337.323149 -160.041016) (xy 337.280281 -160.076691) (xy 337.232675 -160.105745)
			(xy 337.181346 -160.127557) (xy 337.127389 -160.141663) (xy 337.071952 -160.147763) (xy 337.016218 -160.145726)
			(xy 336.961375 -160.135596) (xy 336.908591 -160.117589) (xy 336.858991 -160.092088) (xy 336.813633 -160.059637)
			(xy 336.773484 -160.020928) (xy 336.739398 -159.976785) (xy 336.712102 -159.92815) (xy 336.692179 -159.876059)
			(xy 336.680053 -159.821622) (xy 336.675982 -159.766) (xy 321.919092 -159.766) (xy 321.422014 -160.263078)
			(xy 349.87357 -160.263078) (xy 349.874131 -160.234583) (xy 349.882581 -160.178224) (xy 349.899318 -160.123748)
			(xy 349.923971 -160.072367) (xy 349.955992 -160.025224) (xy 349.994667 -159.983368) (xy 350.016572 -159.965136)
			(xy 350.025087 -159.957504) (xy 350.034987 -159.936928) (xy 350.035622 -159.925512) (xy 350.035622 -159.846518)
			(xy 350.034972 -159.835104) (xy 350.025083 -159.814527) (xy 350.016572 -159.806894) (xy 349.994664 -159.788666)
			(xy 349.956 -159.746799) (xy 349.923983 -159.699653) (xy 349.899326 -159.648274) (xy 349.882575 -159.593802)
			(xy 349.874101 -159.537447) (xy 349.87357 -159.508952) (xy 349.874056 -159.481701) (xy 349.881812 -159.427753)
			(xy 349.897167 -159.375458) (xy 349.919809 -159.325881) (xy 349.949275 -159.280031) (xy 349.984966 -159.23884)
			(xy 350.026157 -159.203149) (xy 350.072007 -159.173683) (xy 350.121584 -159.151041) (xy 350.173879 -159.135686)
			(xy 350.227827 -159.12793) (xy 350.282329 -159.12793) (xy 350.336277 -159.135686) (xy 350.388572 -159.151041)
			(xy 350.438149 -159.173683) (xy 350.483999 -159.203149) (xy 350.52519 -159.23884) (xy 350.560881 -159.280031)
			(xy 350.590347 -159.325881) (xy 350.612989 -159.375458) (xy 350.628344 -159.427753) (xy 350.629976 -159.439102)
			(xy 357.208072 -159.439102) (xy 357.212143 -159.38348) (xy 357.224269 -159.329043) (xy 357.244192 -159.276952)
			(xy 357.271488 -159.228317) (xy 357.305574 -159.184174) (xy 357.345723 -159.145465) (xy 357.391081 -159.113014)
			(xy 357.440681 -159.087513) (xy 357.493465 -159.069506) (xy 357.548308 -159.059376) (xy 357.604042 -159.057339)
			(xy 357.659479 -159.063439) (xy 357.713436 -159.077545) (xy 357.764765 -159.099357) (xy 357.812371 -159.128411)
			(xy 357.855239 -159.164086) (xy 357.892456 -159.205623) (xy 357.923229 -159.252136) (xy 357.946901 -159.302633)
			(xy 357.962969 -159.35604) (xy 357.971089 -159.411216) (xy 357.971598 -159.439102) (xy 357.971089 -159.466988)
			(xy 357.962969 -159.522164) (xy 357.960066 -159.531812) (xy 360.41279 -159.531812) (xy 360.416861 -159.47619)
			(xy 360.428987 -159.421753) (xy 360.44891 -159.369662) (xy 360.476206 -159.321027) (xy 360.510292 -159.276884)
			(xy 360.550441 -159.238175) (xy 360.595799 -159.205724) (xy 360.645399 -159.180223) (xy 360.698183 -159.162216)
			(xy 360.753026 -159.152086) (xy 360.80876 -159.150049) (xy 360.864197 -159.156149) (xy 360.918154 -159.170255)
			(xy 360.969483 -159.192067) (xy 361.017089 -159.221121) (xy 361.059957 -159.256796) (xy 361.097174 -159.298333)
			(xy 361.127947 -159.344846) (xy 361.151619 -159.395343) (xy 361.167687 -159.44875) (xy 361.171463 -159.474408)
			(xy 362.882432 -159.474408) (xy 362.886503 -159.418786) (xy 362.898629 -159.364349) (xy 362.918552 -159.312258)
			(xy 362.945848 -159.263623) (xy 362.979934 -159.21948) (xy 363.020083 -159.180771) (xy 363.065441 -159.14832)
			(xy 363.115041 -159.122819) (xy 363.167825 -159.104812) (xy 363.222668 -159.094682) (xy 363.278402 -159.092645)
			(xy 363.333839 -159.098745) (xy 363.387796 -159.112851) (xy 363.439125 -159.134663) (xy 363.486731 -159.163717)
			(xy 363.529599 -159.199392) (xy 363.566816 -159.240929) (xy 363.597589 -159.287442) (xy 363.621261 -159.337939)
			(xy 363.637329 -159.391346) (xy 363.645449 -159.446522) (xy 363.645958 -159.474408) (xy 363.645449 -159.502294)
			(xy 363.637329 -159.55747) (xy 363.621261 -159.610877) (xy 363.597589 -159.661374) (xy 363.566816 -159.707887)
			(xy 363.529599 -159.749424) (xy 363.486731 -159.785099) (xy 363.439125 -159.814153) (xy 363.387796 -159.835965)
			(xy 363.333839 -159.850071) (xy 363.278402 -159.856171) (xy 363.222668 -159.854134) (xy 363.167825 -159.844004)
			(xy 363.115041 -159.825997) (xy 363.065441 -159.800496) (xy 363.020083 -159.768045) (xy 362.979934 -159.729336)
			(xy 362.945848 -159.685193) (xy 362.918552 -159.636558) (xy 362.898629 -159.584467) (xy 362.886503 -159.53003)
			(xy 362.882432 -159.474408) (xy 361.171463 -159.474408) (xy 361.175807 -159.503926) (xy 361.176316 -159.531812)
			(xy 361.175807 -159.559698) (xy 361.167687 -159.614874) (xy 361.151619 -159.668281) (xy 361.127947 -159.718778)
			(xy 361.097174 -159.765291) (xy 361.059957 -159.806828) (xy 361.017089 -159.842503) (xy 360.969483 -159.871557)
			(xy 360.918154 -159.893369) (xy 360.864197 -159.907475) (xy 360.80876 -159.913575) (xy 360.753026 -159.911538)
			(xy 360.698183 -159.901408) (xy 360.645399 -159.883401) (xy 360.595799 -159.8579) (xy 360.550441 -159.825449)
			(xy 360.510292 -159.78674) (xy 360.476206 -159.742597) (xy 360.44891 -159.693962) (xy 360.428987 -159.641871)
			(xy 360.416861 -159.587434) (xy 360.41279 -159.531812) (xy 357.960066 -159.531812) (xy 357.946901 -159.575571)
			(xy 357.923229 -159.626068) (xy 357.892456 -159.672581) (xy 357.855239 -159.714118) (xy 357.812371 -159.749793)
			(xy 357.764765 -159.778847) (xy 357.713436 -159.800659) (xy 357.659479 -159.814765) (xy 357.604042 -159.820865)
			(xy 357.548308 -159.818828) (xy 357.493465 -159.808698) (xy 357.440681 -159.790691) (xy 357.391081 -159.76519)
			(xy 357.345723 -159.732739) (xy 357.305574 -159.69403) (xy 357.271488 -159.649887) (xy 357.244192 -159.601252)
			(xy 357.224269 -159.549161) (xy 357.212143 -159.494724) (xy 357.208072 -159.439102) (xy 350.629976 -159.439102)
			(xy 350.6361 -159.481701) (xy 350.636586 -159.508952) (xy 350.636062 -159.537448) (xy 350.627608 -159.59381)
			(xy 350.610864 -159.648287) (xy 350.586204 -159.699668) (xy 350.554176 -159.74681) (xy 350.515492 -159.788664)
			(xy 350.493584 -159.806894) (xy 350.485064 -159.814522) (xy 350.475165 -159.8351) (xy 350.474618 -159.844994)
			(xy 354.950266 -159.844994) (xy 354.954337 -159.789372) (xy 354.966463 -159.734935) (xy 354.986386 -159.682844)
			(xy 355.013682 -159.634209) (xy 355.047768 -159.590066) (xy 355.087917 -159.551357) (xy 355.133275 -159.518906)
			(xy 355.182875 -159.493405) (xy 355.235659 -159.475398) (xy 355.290502 -159.465268) (xy 355.346236 -159.463231)
			(xy 355.401673 -159.469331) (xy 355.45563 -159.483437) (xy 355.506959 -159.505249) (xy 355.554565 -159.534303)
			(xy 355.597433 -159.569978) (xy 355.63465 -159.611515) (xy 355.665423 -159.658028) (xy 355.689095 -159.708525)
			(xy 355.705163 -159.761932) (xy 355.713283 -159.817108) (xy 355.713792 -159.844994) (xy 355.713283 -159.87288)
			(xy 355.705163 -159.928056) (xy 355.689095 -159.981463) (xy 355.665423 -160.03196) (xy 355.63465 -160.078473)
			(xy 355.597433 -160.12001) (xy 355.554565 -160.155685) (xy 355.506959 -160.184739) (xy 355.45563 -160.206551)
			(xy 355.401673 -160.220657) (xy 355.346236 -160.226757) (xy 355.290502 -160.22472) (xy 355.235659 -160.21459)
			(xy 355.182875 -160.196583) (xy 355.133275 -160.171082) (xy 355.087917 -160.138631) (xy 355.047768 -160.099922)
			(xy 355.013682 -160.055779) (xy 354.986386 -160.007144) (xy 354.966463 -159.955053) (xy 354.954337 -159.900616)
			(xy 354.950266 -159.844994) (xy 350.474618 -159.844994) (xy 350.474534 -159.846518) (xy 350.474534 -159.925512)
			(xy 350.475148 -159.936931) (xy 350.48506 -159.957509) (xy 350.493584 -159.965136) (xy 350.515497 -159.983358)
			(xy 350.554163 -160.025225) (xy 350.58618 -160.072372) (xy 350.610837 -160.123752) (xy 350.627587 -160.178225)
			(xy 350.636057 -160.234583) (xy 350.636586 -160.263078) (xy 350.6361 -160.290329) (xy 350.628344 -160.344277)
			(xy 350.612989 -160.396572) (xy 350.597046 -160.43148) (xy 351.32086 -160.43148) (xy 351.324931 -160.375858)
			(xy 351.337057 -160.321421) (xy 351.35698 -160.26933) (xy 351.384276 -160.220695) (xy 351.418362 -160.176552)
			(xy 351.458511 -160.137843) (xy 351.503869 -160.105392) (xy 351.553469 -160.079891) (xy 351.606253 -160.061884)
			(xy 351.661096 -160.051754) (xy 351.71683 -160.049717) (xy 351.772267 -160.055817) (xy 351.826224 -160.069923)
			(xy 351.877553 -160.091735) (xy 351.925159 -160.120789) (xy 351.968027 -160.156464) (xy 352.005244 -160.198001)
			(xy 352.036017 -160.244514) (xy 352.059689 -160.295011) (xy 352.075757 -160.348418) (xy 352.083877 -160.403594)
			(xy 352.084386 -160.43148) (xy 352.083877 -160.459366) (xy 352.075757 -160.514542) (xy 352.059689 -160.567949)
			(xy 352.036017 -160.618446) (xy 352.005244 -160.664959) (xy 351.968027 -160.706496) (xy 351.925159 -160.742171)
			(xy 351.877553 -160.771225) (xy 351.826224 -160.793037) (xy 351.772267 -160.807143) (xy 351.71683 -160.813243)
			(xy 351.661096 -160.811206) (xy 351.606253 -160.801076) (xy 351.553469 -160.783069) (xy 351.503869 -160.757568)
			(xy 351.458511 -160.725117) (xy 351.418362 -160.686408) (xy 351.384276 -160.642265) (xy 351.35698 -160.59363)
			(xy 351.337057 -160.541539) (xy 351.324931 -160.487102) (xy 351.32086 -160.43148) (xy 350.597046 -160.43148)
			(xy 350.590347 -160.446149) (xy 350.560881 -160.491999) (xy 350.52519 -160.53319) (xy 350.483999 -160.568881)
			(xy 350.438149 -160.598347) (xy 350.388572 -160.620989) (xy 350.336277 -160.636344) (xy 350.282329 -160.6441)
			(xy 350.227827 -160.6441) (xy 350.173879 -160.636344) (xy 350.121584 -160.620989) (xy 350.072007 -160.598347)
			(xy 350.026157 -160.568881) (xy 349.984966 -160.53319) (xy 349.949275 -160.491999) (xy 349.919809 -160.446149)
			(xy 349.897167 -160.396572) (xy 349.881812 -160.344277) (xy 349.874056 -160.290329) (xy 349.87357 -160.263078)
			(xy 321.422014 -160.263078) (xy 320.903092 -160.782) (xy 334.643982 -160.782) (xy 334.648053 -160.726378)
			(xy 334.660179 -160.671941) (xy 334.680102 -160.61985) (xy 334.707398 -160.571215) (xy 334.741484 -160.527072)
			(xy 334.781633 -160.488363) (xy 334.826991 -160.455912) (xy 334.876591 -160.430411) (xy 334.929375 -160.412404)
			(xy 334.984218 -160.402274) (xy 335.039952 -160.400237) (xy 335.095389 -160.406337) (xy 335.149346 -160.420443)
			(xy 335.200675 -160.442255) (xy 335.248281 -160.471309) (xy 335.291149 -160.506984) (xy 335.328366 -160.548521)
			(xy 335.359139 -160.595034) (xy 335.382811 -160.645531) (xy 335.395823 -160.688782) (xy 340.11057 -160.688782)
			(xy 340.114641 -160.63316) (xy 340.126767 -160.578723) (xy 340.14669 -160.526632) (xy 340.173986 -160.477997)
			(xy 340.208072 -160.433854) (xy 340.248221 -160.395145) (xy 340.293579 -160.362694) (xy 340.343179 -160.337193)
			(xy 340.395963 -160.319186) (xy 340.450806 -160.309056) (xy 340.50654 -160.307019) (xy 340.561977 -160.313119)
			(xy 340.615934 -160.327225) (xy 340.667263 -160.349037) (xy 340.714869 -160.378091) (xy 340.757737 -160.413766)
			(xy 340.794954 -160.455303) (xy 340.825727 -160.501816) (xy 340.849399 -160.552313) (xy 340.865467 -160.60572)
			(xy 340.873587 -160.660896) (xy 340.874096 -160.688782) (xy 340.873587 -160.716668) (xy 340.865467 -160.771844)
			(xy 340.849399 -160.825251) (xy 340.825727 -160.875748) (xy 340.794954 -160.922261) (xy 340.757737 -160.963798)
			(xy 340.755216 -160.965896) (xy 357.23779 -160.965896) (xy 357.241861 -160.910274) (xy 357.253987 -160.855837)
			(xy 357.27391 -160.803746) (xy 357.301206 -160.755111) (xy 357.335292 -160.710968) (xy 357.375441 -160.672259)
			(xy 357.420799 -160.639808) (xy 357.470399 -160.614307) (xy 357.523183 -160.5963) (xy 357.578026 -160.58617)
			(xy 357.63376 -160.584133) (xy 357.689197 -160.590233) (xy 357.743154 -160.604339) (xy 357.794483 -160.626151)
			(xy 357.842089 -160.655205) (xy 357.884957 -160.69088) (xy 357.922174 -160.732417) (xy 357.952947 -160.77893)
			(xy 357.976619 -160.829427) (xy 357.992687 -160.882834) (xy 358.000807 -160.93801) (xy 358.001279 -160.963864)
			(xy 358.62971 -160.963864) (xy 358.633781 -160.908242) (xy 358.645907 -160.853805) (xy 358.66583 -160.801714)
			(xy 358.693126 -160.753079) (xy 358.727212 -160.708936) (xy 358.767361 -160.670227) (xy 358.812719 -160.637776)
			(xy 358.862319 -160.612275) (xy 358.915103 -160.594268) (xy 358.969946 -160.584138) (xy 359.02568 -160.582101)
			(xy 359.081117 -160.588201) (xy 359.135074 -160.602307) (xy 359.186403 -160.624119) (xy 359.234009 -160.653173)
			(xy 359.276877 -160.688848) (xy 359.314094 -160.730385) (xy 359.344867 -160.776898) (xy 359.368539 -160.827395)
			(xy 359.384607 -160.880802) (xy 359.392727 -160.935978) (xy 359.393236 -160.963864) (xy 359.393143 -160.968944)
			(xy 359.901488 -160.968944) (xy 359.905559 -160.913322) (xy 359.917685 -160.858885) (xy 359.937608 -160.806794)
			(xy 359.964904 -160.758159) (xy 359.99899 -160.714016) (xy 360.039139 -160.675307) (xy 360.084497 -160.642856)
			(xy 360.134097 -160.617355) (xy 360.186881 -160.599348) (xy 360.241724 -160.589218) (xy 360.297458 -160.587181)
			(xy 360.352895 -160.593281) (xy 360.406852 -160.607387) (xy 360.458181 -160.629199) (xy 360.505787 -160.658253)
			(xy 360.548655 -160.693928) (xy 360.585872 -160.735465) (xy 360.616645 -160.781978) (xy 360.640317 -160.832475)
			(xy 360.656385 -160.885882) (xy 360.658778 -160.902142) (xy 361.68279 -160.902142) (xy 361.686861 -160.84652)
			(xy 361.698987 -160.792083) (xy 361.71891 -160.739992) (xy 361.746206 -160.691357) (xy 361.780292 -160.647214)
			(xy 361.820441 -160.608505) (xy 361.865799 -160.576054) (xy 361.915399 -160.550553) (xy 361.968183 -160.532546)
			(xy 362.023026 -160.522416) (xy 362.07876 -160.520379) (xy 362.134197 -160.526479) (xy 362.188154 -160.540585)
			(xy 362.239483 -160.562397) (xy 362.287089 -160.591451) (xy 362.329957 -160.627126) (xy 362.367174 -160.668663)
			(xy 362.397947 -160.715176) (xy 362.421619 -160.765673) (xy 362.437687 -160.81908) (xy 362.445807 -160.874256)
			(xy 362.446316 -160.902142) (xy 362.445807 -160.930028) (xy 362.437687 -160.985204) (xy 362.421619 -161.038611)
			(xy 362.397947 -161.089108) (xy 362.367174 -161.135621) (xy 362.329957 -161.177158) (xy 362.287089 -161.212833)
			(xy 362.239483 -161.241887) (xy 362.188154 -161.263699) (xy 362.134197 -161.277805) (xy 362.07876 -161.283905)
			(xy 362.023026 -161.281868) (xy 361.968183 -161.271738) (xy 361.915399 -161.253731) (xy 361.865799 -161.22823)
			(xy 361.820441 -161.195779) (xy 361.780292 -161.15707) (xy 361.746206 -161.112927) (xy 361.71891 -161.064292)
			(xy 361.698987 -161.012201) (xy 361.686861 -160.957764) (xy 361.68279 -160.902142) (xy 360.658778 -160.902142)
			(xy 360.664505 -160.941058) (xy 360.665014 -160.968944) (xy 360.664505 -160.99683) (xy 360.656385 -161.052006)
			(xy 360.640317 -161.105413) (xy 360.616645 -161.15591) (xy 360.585872 -161.202423) (xy 360.548655 -161.24396)
			(xy 360.505787 -161.279635) (xy 360.458181 -161.308689) (xy 360.406852 -161.330501) (xy 360.352895 -161.344607)
			(xy 360.297458 -161.350707) (xy 360.241724 -161.34867) (xy 360.186881 -161.33854) (xy 360.134097 -161.320533)
			(xy 360.084497 -161.295032) (xy 360.039139 -161.262581) (xy 359.99899 -161.223872) (xy 359.964904 -161.179729)
			(xy 359.937608 -161.131094) (xy 359.917685 -161.079003) (xy 359.905559 -161.024566) (xy 359.901488 -160.968944)
			(xy 359.393143 -160.968944) (xy 359.392727 -160.99175) (xy 359.384607 -161.046926) (xy 359.368539 -161.100333)
			(xy 359.344867 -161.15083) (xy 359.314094 -161.197343) (xy 359.276877 -161.23888) (xy 359.234009 -161.274555)
			(xy 359.186403 -161.303609) (xy 359.135074 -161.325421) (xy 359.081117 -161.339527) (xy 359.02568 -161.345627)
			(xy 358.969946 -161.34359) (xy 358.915103 -161.33346) (xy 358.862319 -161.315453) (xy 358.812719 -161.289952)
			(xy 358.767361 -161.257501) (xy 358.727212 -161.218792) (xy 358.693126 -161.174649) (xy 358.66583 -161.126014)
			(xy 358.645907 -161.073923) (xy 358.633781 -161.019486) (xy 358.62971 -160.963864) (xy 358.001279 -160.963864)
			(xy 358.001316 -160.965896) (xy 358.000807 -160.993782) (xy 357.992687 -161.048958) (xy 357.976619 -161.102365)
			(xy 357.952947 -161.152862) (xy 357.922174 -161.199375) (xy 357.884957 -161.240912) (xy 357.842089 -161.276587)
			(xy 357.794483 -161.305641) (xy 357.743154 -161.327453) (xy 357.689197 -161.341559) (xy 357.63376 -161.347659)
			(xy 357.578026 -161.345622) (xy 357.523183 -161.335492) (xy 357.470399 -161.317485) (xy 357.420799 -161.291984)
			(xy 357.375441 -161.259533) (xy 357.335292 -161.220824) (xy 357.301206 -161.176681) (xy 357.27391 -161.128046)
			(xy 357.253987 -161.075955) (xy 357.241861 -161.021518) (xy 357.23779 -160.965896) (xy 340.755216 -160.965896)
			(xy 340.714869 -160.999473) (xy 340.667263 -161.028527) (xy 340.615934 -161.050339) (xy 340.561977 -161.064445)
			(xy 340.50654 -161.070545) (xy 340.450806 -161.068508) (xy 340.395963 -161.058378) (xy 340.343179 -161.040371)
			(xy 340.293579 -161.01487) (xy 340.248221 -160.982419) (xy 340.208072 -160.94371) (xy 340.173986 -160.899567)
			(xy 340.14669 -160.850932) (xy 340.126767 -160.798841) (xy 340.114641 -160.744404) (xy 340.11057 -160.688782)
			(xy 335.395823 -160.688782) (xy 335.398879 -160.698938) (xy 335.406999 -160.754114) (xy 335.407508 -160.782)
			(xy 335.406999 -160.809886) (xy 335.398879 -160.865062) (xy 335.382811 -160.918469) (xy 335.359139 -160.968966)
			(xy 335.328366 -161.015479) (xy 335.291149 -161.057016) (xy 335.248281 -161.092691) (xy 335.200675 -161.121745)
			(xy 335.149346 -161.143557) (xy 335.095389 -161.157663) (xy 335.039952 -161.163763) (xy 334.984218 -161.161726)
			(xy 334.929375 -161.151596) (xy 334.876591 -161.133589) (xy 334.826991 -161.108088) (xy 334.781633 -161.075637)
			(xy 334.741484 -161.036928) (xy 334.707398 -160.992785) (xy 334.680102 -160.94415) (xy 334.660179 -160.892059)
			(xy 334.648053 -160.837622) (xy 334.643982 -160.782) (xy 320.903092 -160.782) (xy 319.887092 -161.798)
			(xy 334.643982 -161.798) (xy 334.648053 -161.742378) (xy 334.660179 -161.687941) (xy 334.680102 -161.63585)
			(xy 334.707398 -161.587215) (xy 334.741484 -161.543072) (xy 334.781633 -161.504363) (xy 334.826991 -161.471912)
			(xy 334.876591 -161.446411) (xy 334.929375 -161.428404) (xy 334.984218 -161.418274) (xy 335.039952 -161.416237)
			(xy 335.095389 -161.422337) (xy 335.149346 -161.436443) (xy 335.200675 -161.458255) (xy 335.248281 -161.487309)
			(xy 335.291149 -161.522984) (xy 335.328366 -161.564521) (xy 335.359139 -161.611034) (xy 335.382811 -161.661531)
			(xy 335.398879 -161.714938) (xy 335.406999 -161.770114) (xy 335.407313 -161.787332) (xy 340.739982 -161.787332)
			(xy 340.744053 -161.73171) (xy 340.756179 -161.677273) (xy 340.776102 -161.625182) (xy 340.803398 -161.576547)
			(xy 340.837484 -161.532404) (xy 340.877633 -161.493695) (xy 340.922991 -161.461244) (xy 340.972591 -161.435743)
			(xy 341.025375 -161.417736) (xy 341.080218 -161.407606) (xy 341.135952 -161.405569) (xy 341.191389 -161.411669)
			(xy 341.245346 -161.425775) (xy 341.296675 -161.447587) (xy 341.344281 -161.476641) (xy 341.387149 -161.512316)
			(xy 341.424366 -161.553853) (xy 341.455139 -161.600366) (xy 341.478811 -161.650863) (xy 341.494879 -161.70427)
			(xy 341.502999 -161.759446) (xy 341.503355 -161.77895) (xy 351.007932 -161.77895) (xy 351.012003 -161.723328)
			(xy 351.024129 -161.668891) (xy 351.044052 -161.6168) (xy 351.071348 -161.568165) (xy 351.105434 -161.524022)
			(xy 351.145583 -161.485313) (xy 351.190941 -161.452862) (xy 351.240541 -161.427361) (xy 351.293325 -161.409354)
			(xy 351.348168 -161.399224) (xy 351.403902 -161.397187) (xy 351.459339 -161.403287) (xy 351.513296 -161.417393)
			(xy 351.564625 -161.439205) (xy 351.612231 -161.468259) (xy 351.655099 -161.503934) (xy 351.692316 -161.545471)
			(xy 351.723089 -161.591984) (xy 351.746761 -161.642481) (xy 351.762829 -161.695888) (xy 351.770949 -161.751064)
			(xy 351.771458 -161.77895) (xy 351.770949 -161.806836) (xy 351.762829 -161.862012) (xy 351.746761 -161.915419)
			(xy 351.723089 -161.965916) (xy 351.692316 -162.012429) (xy 351.655099 -162.053966) (xy 351.612231 -162.089641)
			(xy 351.564625 -162.118695) (xy 351.513296 -162.140507) (xy 351.459339 -162.154613) (xy 351.403902 -162.160713)
			(xy 351.348168 -162.158676) (xy 351.293325 -162.148546) (xy 351.240541 -162.130539) (xy 351.190941 -162.105038)
			(xy 351.145583 -162.072587) (xy 351.105434 -162.033878) (xy 351.071348 -161.989735) (xy 351.044052 -161.9411)
			(xy 351.024129 -161.889009) (xy 351.012003 -161.834572) (xy 351.007932 -161.77895) (xy 341.503355 -161.77895)
			(xy 341.503508 -161.787332) (xy 341.502999 -161.815218) (xy 341.494879 -161.870394) (xy 341.478811 -161.923801)
			(xy 341.455139 -161.974298) (xy 341.424366 -162.020811) (xy 341.387149 -162.062348) (xy 341.344281 -162.098023)
			(xy 341.296675 -162.127077) (xy 341.245346 -162.148889) (xy 341.191389 -162.162995) (xy 341.135952 -162.169095)
			(xy 341.080218 -162.167058) (xy 341.025375 -162.156928) (xy 340.972591 -162.138921) (xy 340.922991 -162.11342)
			(xy 340.877633 -162.080969) (xy 340.837484 -162.04226) (xy 340.803398 -161.998117) (xy 340.776102 -161.949482)
			(xy 340.756179 -161.897391) (xy 340.744053 -161.842954) (xy 340.739982 -161.787332) (xy 335.407313 -161.787332)
			(xy 335.407508 -161.798) (xy 335.406999 -161.825886) (xy 335.398879 -161.881062) (xy 335.382811 -161.934469)
			(xy 335.359139 -161.984966) (xy 335.328366 -162.031479) (xy 335.291149 -162.073016) (xy 335.248281 -162.108691)
			(xy 335.200675 -162.137745) (xy 335.149346 -162.159557) (xy 335.095389 -162.173663) (xy 335.039952 -162.179763)
			(xy 334.984218 -162.177726) (xy 334.929375 -162.167596) (xy 334.876591 -162.149589) (xy 334.826991 -162.124088)
			(xy 334.781633 -162.091637) (xy 334.741484 -162.052928) (xy 334.707398 -162.008785) (xy 334.680102 -161.96015)
			(xy 334.660179 -161.908059) (xy 334.648053 -161.853622) (xy 334.643982 -161.798) (xy 319.887092 -161.798)
			(xy 319.662048 -162.023044) (xy 319.644748 -162.039634) (xy 319.60597 -162.067802) (xy 319.563271 -162.089572)
			(xy 319.517697 -162.10441) (xy 319.470366 -162.111954) (xy 319.446402 -162.112452) (xy 313.608466 -162.112452)
			(xy 313.584494 -162.112025) (xy 313.537139 -162.104524) (xy 313.491545 -162.089695) (xy 313.448837 -162.067907)
			(xy 313.410071 -162.039696) (xy 313.39282 -162.023044) (xy 312.986928 -161.617152) (xy 312.970335 -161.599855)
			(xy 312.942169 -161.561075) (xy 312.9204 -161.518375) (xy 312.905562 -161.472801) (xy 312.898019 -161.42547)
			(xy 312.89752 -161.401506) (xy 310.821211 -161.401506) (xy 310.561598 -162.814) (xy 334.643982 -162.814)
			(xy 334.648053 -162.758378) (xy 334.660179 -162.703941) (xy 334.680102 -162.65185) (xy 334.707398 -162.603215)
			(xy 334.741484 -162.559072) (xy 334.781633 -162.520363) (xy 334.826991 -162.487912) (xy 334.876591 -162.462411)
			(xy 334.929375 -162.444404) (xy 334.984218 -162.434274) (xy 335.039952 -162.432237) (xy 335.095389 -162.438337)
			(xy 335.149346 -162.452443) (xy 335.200675 -162.474255) (xy 335.248281 -162.503309) (xy 335.291149 -162.538984)
			(xy 335.328366 -162.580521) (xy 335.359139 -162.627034) (xy 335.382811 -162.677531) (xy 335.398879 -162.730938)
			(xy 335.406999 -162.786114) (xy 335.407508 -162.814) (xy 336.675982 -162.814) (xy 336.680053 -162.758378)
			(xy 336.692179 -162.703941) (xy 336.712102 -162.65185) (xy 336.739398 -162.603215) (xy 336.773484 -162.559072)
			(xy 336.813633 -162.520363) (xy 336.858991 -162.487912) (xy 336.908591 -162.462411) (xy 336.961375 -162.444404)
			(xy 337.016218 -162.434274) (xy 337.071952 -162.432237) (xy 337.127389 -162.438337) (xy 337.181346 -162.452443)
			(xy 337.232675 -162.474255) (xy 337.280281 -162.503309) (xy 337.323149 -162.538984) (xy 337.360366 -162.580521)
			(xy 337.391139 -162.627034) (xy 337.414811 -162.677531) (xy 337.430879 -162.730938) (xy 337.438999 -162.786114)
			(xy 337.439508 -162.814) (xy 338.707982 -162.814) (xy 338.712053 -162.758378) (xy 338.724179 -162.703941)
			(xy 338.744102 -162.65185) (xy 338.771398 -162.603215) (xy 338.805484 -162.559072) (xy 338.845633 -162.520363)
			(xy 338.890991 -162.487912) (xy 338.940591 -162.462411) (xy 338.993375 -162.444404) (xy 339.048218 -162.434274)
			(xy 339.103952 -162.432237) (xy 339.159389 -162.438337) (xy 339.213346 -162.452443) (xy 339.264675 -162.474255)
			(xy 339.312281 -162.503309) (xy 339.355149 -162.538984) (xy 339.392366 -162.580521) (xy 339.423139 -162.627034)
			(xy 339.446811 -162.677531) (xy 339.462879 -162.730938) (xy 339.470999 -162.786114) (xy 339.471508 -162.814)
			(xy 339.470999 -162.841886) (xy 339.462879 -162.897062) (xy 339.446811 -162.950469) (xy 339.423139 -163.000966)
			(xy 339.392366 -163.047479) (xy 339.355149 -163.089016) (xy 339.324243 -163.114736) (xy 364.34979 -163.114736)
			(xy 364.353861 -163.059114) (xy 364.365987 -163.004677) (xy 364.38591 -162.952586) (xy 364.413206 -162.903951)
			(xy 364.447292 -162.859808) (xy 364.487441 -162.821099) (xy 364.532799 -162.788648) (xy 364.582399 -162.763147)
			(xy 364.635183 -162.74514) (xy 364.690026 -162.73501) (xy 364.74576 -162.732973) (xy 364.801197 -162.739073)
			(xy 364.855154 -162.753179) (xy 364.906483 -162.774991) (xy 364.954089 -162.804045) (xy 364.996957 -162.83972)
			(xy 365.034174 -162.881257) (xy 365.064947 -162.92777) (xy 365.088619 -162.978267) (xy 365.104687 -163.031674)
			(xy 365.112807 -163.08685) (xy 365.113316 -163.114736) (xy 365.112807 -163.142622) (xy 365.104687 -163.197798)
			(xy 365.088619 -163.251205) (xy 365.064947 -163.301702) (xy 365.034174 -163.348215) (xy 364.996957 -163.389752)
			(xy 364.954089 -163.425427) (xy 364.906483 -163.454481) (xy 364.855154 -163.476293) (xy 364.801197 -163.490399)
			(xy 364.74576 -163.496499) (xy 364.690026 -163.494462) (xy 364.635183 -163.484332) (xy 364.582399 -163.466325)
			(xy 364.532799 -163.440824) (xy 364.487441 -163.408373) (xy 364.447292 -163.369664) (xy 364.413206 -163.325521)
			(xy 364.38591 -163.276886) (xy 364.365987 -163.224795) (xy 364.353861 -163.170358) (xy 364.34979 -163.114736)
			(xy 339.324243 -163.114736) (xy 339.312281 -163.124691) (xy 339.264675 -163.153745) (xy 339.213346 -163.175557)
			(xy 339.159389 -163.189663) (xy 339.103952 -163.195763) (xy 339.048218 -163.193726) (xy 338.993375 -163.183596)
			(xy 338.940591 -163.165589) (xy 338.890991 -163.140088) (xy 338.845633 -163.107637) (xy 338.805484 -163.068928)
			(xy 338.771398 -163.024785) (xy 338.744102 -162.97615) (xy 338.724179 -162.924059) (xy 338.712053 -162.869622)
			(xy 338.707982 -162.814) (xy 337.439508 -162.814) (xy 337.438999 -162.841886) (xy 337.430879 -162.897062)
			(xy 337.414811 -162.950469) (xy 337.391139 -163.000966) (xy 337.360366 -163.047479) (xy 337.323149 -163.089016)
			(xy 337.280281 -163.124691) (xy 337.232675 -163.153745) (xy 337.181346 -163.175557) (xy 337.127389 -163.189663)
			(xy 337.071952 -163.195763) (xy 337.016218 -163.193726) (xy 336.961375 -163.183596) (xy 336.908591 -163.165589)
			(xy 336.858991 -163.140088) (xy 336.813633 -163.107637) (xy 336.773484 -163.068928) (xy 336.739398 -163.024785)
			(xy 336.712102 -162.97615) (xy 336.692179 -162.924059) (xy 336.680053 -162.869622) (xy 336.675982 -162.814)
			(xy 335.407508 -162.814) (xy 335.406999 -162.841886) (xy 335.398879 -162.897062) (xy 335.382811 -162.950469)
			(xy 335.359139 -163.000966) (xy 335.328366 -163.047479) (xy 335.291149 -163.089016) (xy 335.248281 -163.124691)
			(xy 335.200675 -163.153745) (xy 335.149346 -163.175557) (xy 335.095389 -163.189663) (xy 335.039952 -163.195763)
			(xy 334.984218 -163.193726) (xy 334.929375 -163.183596) (xy 334.876591 -163.165589) (xy 334.826991 -163.140088)
			(xy 334.781633 -163.107637) (xy 334.741484 -163.068928) (xy 334.707398 -163.024785) (xy 334.680102 -162.97615)
			(xy 334.660179 -162.924059) (xy 334.648053 -162.869622) (xy 334.643982 -162.814) (xy 310.561598 -162.814)
			(xy 310.325188 -164.100256) (xy 336.678776 -164.100256) (xy 336.682847 -164.044634) (xy 336.694973 -163.990197)
			(xy 336.714896 -163.938106) (xy 336.742192 -163.889471) (xy 336.776278 -163.845328) (xy 336.816427 -163.806619)
			(xy 336.861785 -163.774168) (xy 336.911385 -163.748667) (xy 336.964169 -163.73066) (xy 337.019012 -163.72053)
			(xy 337.074746 -163.718493) (xy 337.130183 -163.724593) (xy 337.18414 -163.738699) (xy 337.235469 -163.760511)
			(xy 337.283075 -163.789565) (xy 337.325943 -163.82524) (xy 337.36316 -163.866777) (xy 337.393933 -163.91329)
			(xy 337.417605 -163.963787) (xy 337.433673 -164.017194) (xy 337.441793 -164.07237) (xy 337.442302 -164.100256)
			(xy 337.441793 -164.128142) (xy 337.433673 -164.183318) (xy 337.417605 -164.236725) (xy 337.393933 -164.287222)
			(xy 337.36316 -164.333735) (xy 337.325943 -164.375272) (xy 337.283075 -164.410947) (xy 337.235469 -164.440001)
			(xy 337.18414 -164.461813) (xy 337.130183 -164.475919) (xy 337.074746 -164.482019) (xy 337.019012 -164.479982)
			(xy 336.964169 -164.469852) (xy 336.911385 -164.451845) (xy 336.861785 -164.426344) (xy 336.816427 -164.393893)
			(xy 336.776278 -164.355184) (xy 336.742192 -164.311041) (xy 336.714896 -164.262406) (xy 336.694973 -164.210315)
			(xy 336.682847 -164.155878) (xy 336.678776 -164.100256) (xy 310.325188 -164.100256) (xy 310.16478 -164.973)
			(xy 334.643982 -164.973) (xy 334.648053 -164.917378) (xy 334.660179 -164.862941) (xy 334.680102 -164.81085)
			(xy 334.707398 -164.762215) (xy 334.741484 -164.718072) (xy 334.781633 -164.679363) (xy 334.826991 -164.646912)
			(xy 334.876591 -164.621411) (xy 334.929375 -164.603404) (xy 334.984218 -164.593274) (xy 335.039952 -164.591237)
			(xy 335.095389 -164.597337) (xy 335.149346 -164.611443) (xy 335.200675 -164.633255) (xy 335.248281 -164.662309)
			(xy 335.291149 -164.697984) (xy 335.328366 -164.739521) (xy 335.359139 -164.786034) (xy 335.382811 -164.836531)
			(xy 335.398879 -164.889938) (xy 335.406999 -164.945114) (xy 335.407508 -164.973) (xy 335.406999 -165.000886)
			(xy 335.400076 -165.04793) (xy 349.735392 -165.04793) (xy 349.739463 -164.992308) (xy 349.751589 -164.937871)
			(xy 349.771512 -164.88578) (xy 349.798808 -164.837145) (xy 349.832894 -164.793002) (xy 349.873043 -164.754293)
			(xy 349.918401 -164.721842) (xy 349.968001 -164.696341) (xy 350.020785 -164.678334) (xy 350.075628 -164.668204)
			(xy 350.131362 -164.666167) (xy 350.186799 -164.672267) (xy 350.240756 -164.686373) (xy 350.292085 -164.708185)
			(xy 350.339691 -164.737239) (xy 350.382559 -164.772914) (xy 350.419776 -164.814451) (xy 350.450549 -164.860964)
			(xy 350.474221 -164.911461) (xy 350.490289 -164.964868) (xy 350.498409 -165.020044) (xy 350.498918 -165.04793)
			(xy 350.498409 -165.075816) (xy 350.490289 -165.130992) (xy 350.474221 -165.184399) (xy 350.450549 -165.234896)
			(xy 350.419776 -165.281409) (xy 350.382559 -165.322946) (xy 350.339691 -165.358621) (xy 350.292085 -165.387675)
			(xy 350.240756 -165.409487) (xy 350.186799 -165.423593) (xy 350.131362 -165.429693) (xy 350.075628 -165.427656)
			(xy 350.020785 -165.417526) (xy 349.968001 -165.399519) (xy 349.918401 -165.374018) (xy 349.873043 -165.341567)
			(xy 349.832894 -165.302858) (xy 349.798808 -165.258715) (xy 349.771512 -165.21008) (xy 349.751589 -165.157989)
			(xy 349.739463 -165.103552) (xy 349.735392 -165.04793) (xy 335.400076 -165.04793) (xy 335.398879 -165.056062)
			(xy 335.382811 -165.109469) (xy 335.359139 -165.159966) (xy 335.328366 -165.206479) (xy 335.291149 -165.248016)
			(xy 335.248281 -165.283691) (xy 335.200675 -165.312745) (xy 335.149346 -165.334557) (xy 335.095389 -165.348663)
			(xy 335.039952 -165.354763) (xy 334.984218 -165.352726) (xy 334.929375 -165.342596) (xy 334.876591 -165.324589)
			(xy 334.826991 -165.299088) (xy 334.781633 -165.266637) (xy 334.741484 -165.227928) (xy 334.707398 -165.183785)
			(xy 334.680102 -165.13515) (xy 334.660179 -165.083059) (xy 334.648053 -165.028622) (xy 334.643982 -164.973)
			(xy 310.16478 -164.973) (xy 309.978042 -165.989) (xy 334.643982 -165.989) (xy 334.648053 -165.933378)
			(xy 334.660179 -165.878941) (xy 334.680102 -165.82685) (xy 334.707398 -165.778215) (xy 334.741484 -165.734072)
			(xy 334.781633 -165.695363) (xy 334.826991 -165.662912) (xy 334.876591 -165.637411) (xy 334.929375 -165.619404)
			(xy 334.984218 -165.609274) (xy 335.039952 -165.607237) (xy 335.095389 -165.613337) (xy 335.149346 -165.627443)
			(xy 335.200675 -165.649255) (xy 335.248281 -165.678309) (xy 335.291149 -165.713984) (xy 335.328366 -165.755521)
			(xy 335.359139 -165.802034) (xy 335.382811 -165.852531) (xy 335.398879 -165.905938) (xy 335.406999 -165.961114)
			(xy 335.407508 -165.989) (xy 339.469982 -165.989) (xy 339.474053 -165.933378) (xy 339.486179 -165.878941)
			(xy 339.506102 -165.82685) (xy 339.533398 -165.778215) (xy 339.567484 -165.734072) (xy 339.607633 -165.695363)
			(xy 339.652991 -165.662912) (xy 339.702591 -165.637411) (xy 339.755375 -165.619404) (xy 339.810218 -165.609274)
			(xy 339.865952 -165.607237) (xy 339.872886 -165.608) (xy 354.455982 -165.608) (xy 354.460053 -165.552378)
			(xy 354.472179 -165.497941) (xy 354.492102 -165.44585) (xy 354.519398 -165.397215) (xy 354.553484 -165.353072)
			(xy 354.593633 -165.314363) (xy 354.638991 -165.281912) (xy 354.688591 -165.256411) (xy 354.741375 -165.238404)
			(xy 354.796218 -165.228274) (xy 354.851952 -165.226237) (xy 354.907389 -165.232337) (xy 354.961346 -165.246443)
			(xy 355.012675 -165.268255) (xy 355.060281 -165.297309) (xy 355.103149 -165.332984) (xy 355.140366 -165.374521)
			(xy 355.171139 -165.421034) (xy 355.194811 -165.471531) (xy 355.210879 -165.524938) (xy 355.218999 -165.580114)
			(xy 355.219508 -165.608) (xy 355.219378 -165.615112) (xy 356.546148 -165.615112) (xy 356.550219 -165.55949)
			(xy 356.562345 -165.505053) (xy 356.582268 -165.452962) (xy 356.609564 -165.404327) (xy 356.64365 -165.360184)
			(xy 356.683799 -165.321475) (xy 356.729157 -165.289024) (xy 356.778757 -165.263523) (xy 356.831541 -165.245516)
			(xy 356.886384 -165.235386) (xy 356.942118 -165.233349) (xy 356.997555 -165.239449) (xy 357.051512 -165.253555)
			(xy 357.102841 -165.275367) (xy 357.150447 -165.304421) (xy 357.193315 -165.340096) (xy 357.230532 -165.381633)
			(xy 357.261305 -165.428146) (xy 357.284977 -165.478643) (xy 357.301045 -165.53205) (xy 357.309165 -165.587226)
			(xy 357.309674 -165.615112) (xy 357.309165 -165.642998) (xy 357.301045 -165.698174) (xy 357.284977 -165.751581)
			(xy 357.261305 -165.802078) (xy 357.230532 -165.848591) (xy 357.193315 -165.890128) (xy 357.150447 -165.925803)
			(xy 357.102841 -165.954857) (xy 357.051512 -165.976669) (xy 356.997555 -165.990775) (xy 356.942118 -165.996875)
			(xy 356.886384 -165.994838) (xy 356.831541 -165.984708) (xy 356.778757 -165.966701) (xy 356.729157 -165.9412)
			(xy 356.683799 -165.908749) (xy 356.64365 -165.87004) (xy 356.609564 -165.825897) (xy 356.582268 -165.777262)
			(xy 356.562345 -165.725171) (xy 356.550219 -165.670734) (xy 356.546148 -165.615112) (xy 355.219378 -165.615112)
			(xy 355.218999 -165.635886) (xy 355.210879 -165.691062) (xy 355.194811 -165.744469) (xy 355.171139 -165.794966)
			(xy 355.140366 -165.841479) (xy 355.103149 -165.883016) (xy 355.060281 -165.918691) (xy 355.012675 -165.947745)
			(xy 354.961346 -165.969557) (xy 354.907389 -165.983663) (xy 354.851952 -165.989763) (xy 354.796218 -165.987726)
			(xy 354.741375 -165.977596) (xy 354.688591 -165.959589) (xy 354.638991 -165.934088) (xy 354.593633 -165.901637)
			(xy 354.553484 -165.862928) (xy 354.519398 -165.818785) (xy 354.492102 -165.77015) (xy 354.472179 -165.718059)
			(xy 354.460053 -165.663622) (xy 354.455982 -165.608) (xy 339.872886 -165.608) (xy 339.921389 -165.613337)
			(xy 339.975346 -165.627443) (xy 340.026675 -165.649255) (xy 340.074281 -165.678309) (xy 340.117149 -165.713984)
			(xy 340.154366 -165.755521) (xy 340.185139 -165.802034) (xy 340.208811 -165.852531) (xy 340.224879 -165.905938)
			(xy 340.232999 -165.961114) (xy 340.233508 -165.989) (xy 340.232999 -166.016886) (xy 340.224879 -166.072062)
			(xy 340.208811 -166.125469) (xy 340.185139 -166.175966) (xy 340.154366 -166.222479) (xy 340.117149 -166.264016)
			(xy 340.074281 -166.299691) (xy 340.026675 -166.328745) (xy 339.975346 -166.350557) (xy 339.921389 -166.364663)
			(xy 339.865952 -166.370763) (xy 339.810218 -166.368726) (xy 339.755375 -166.358596) (xy 339.702591 -166.340589)
			(xy 339.652991 -166.315088) (xy 339.607633 -166.282637) (xy 339.567484 -166.243928) (xy 339.533398 -166.199785)
			(xy 339.506102 -166.15115) (xy 339.486179 -166.099059) (xy 339.474053 -166.044622) (xy 339.469982 -165.989)
			(xy 335.407508 -165.989) (xy 335.406999 -166.016886) (xy 335.398879 -166.072062) (xy 335.382811 -166.125469)
			(xy 335.359139 -166.175966) (xy 335.328366 -166.222479) (xy 335.291149 -166.264016) (xy 335.248281 -166.299691)
			(xy 335.200675 -166.328745) (xy 335.149346 -166.350557) (xy 335.095389 -166.364663) (xy 335.039952 -166.370763)
			(xy 334.984218 -166.368726) (xy 334.929375 -166.358596) (xy 334.876591 -166.340589) (xy 334.826991 -166.315088)
			(xy 334.781633 -166.282637) (xy 334.741484 -166.243928) (xy 334.707398 -166.199785) (xy 334.680102 -166.15115)
			(xy 334.660179 -166.099059) (xy 334.648053 -166.044622) (xy 334.643982 -165.989) (xy 309.978042 -165.989)
			(xy 309.885046 -166.494968) (xy 341.689434 -166.494968) (xy 341.693505 -166.439346) (xy 341.705631 -166.384909)
			(xy 341.725554 -166.332818) (xy 341.75285 -166.284183) (xy 341.786936 -166.24004) (xy 341.827085 -166.201331)
			(xy 341.872443 -166.16888) (xy 341.922043 -166.143379) (xy 341.974827 -166.125372) (xy 342.02967 -166.115242)
			(xy 342.085404 -166.113205) (xy 342.140841 -166.119305) (xy 342.194798 -166.133411) (xy 342.246127 -166.155223)
			(xy 342.293733 -166.184277) (xy 342.336601 -166.219952) (xy 342.373818 -166.261489) (xy 342.404591 -166.308002)
			(xy 342.428263 -166.358499) (xy 342.4305 -166.365936) (xy 349.735392 -166.365936) (xy 349.739463 -166.310314)
			(xy 349.751589 -166.255877) (xy 349.771512 -166.203786) (xy 349.798808 -166.155151) (xy 349.832894 -166.111008)
			(xy 349.873043 -166.072299) (xy 349.918401 -166.039848) (xy 349.968001 -166.014347) (xy 350.020785 -165.99634)
			(xy 350.075628 -165.98621) (xy 350.131362 -165.984173) (xy 350.186799 -165.990273) (xy 350.240756 -166.004379)
			(xy 350.292085 -166.026191) (xy 350.339691 -166.055245) (xy 350.382559 -166.09092) (xy 350.419776 -166.132457)
			(xy 350.450549 -166.17897) (xy 350.474221 -166.229467) (xy 350.490289 -166.282874) (xy 350.498409 -166.33805)
			(xy 350.498918 -166.365936) (xy 350.498409 -166.393822) (xy 350.490289 -166.448998) (xy 350.474221 -166.502405)
			(xy 350.450549 -166.552902) (xy 350.419776 -166.599415) (xy 350.397748 -166.624) (xy 354.455982 -166.624)
			(xy 354.460053 -166.568378) (xy 354.472179 -166.513941) (xy 354.492102 -166.46185) (xy 354.519398 -166.413215)
			(xy 354.553484 -166.369072) (xy 354.593633 -166.330363) (xy 354.638991 -166.297912) (xy 354.688591 -166.272411)
			(xy 354.741375 -166.254404) (xy 354.796218 -166.244274) (xy 354.851952 -166.242237) (xy 354.907389 -166.248337)
			(xy 354.961346 -166.262443) (xy 355.012675 -166.284255) (xy 355.060281 -166.313309) (xy 355.103149 -166.348984)
			(xy 355.140366 -166.390521) (xy 355.171139 -166.437034) (xy 355.194811 -166.487531) (xy 355.210879 -166.540938)
			(xy 355.215889 -166.574978) (xy 370.832378 -166.574978) (xy 370.836449 -166.519356) (xy 370.848575 -166.464919)
			(xy 370.868498 -166.412828) (xy 370.895794 -166.364193) (xy 370.92988 -166.32005) (xy 370.970029 -166.281341)
			(xy 371.015387 -166.24889) (xy 371.064987 -166.223389) (xy 371.117771 -166.205382) (xy 371.172614 -166.195252)
			(xy 371.228348 -166.193215) (xy 371.283785 -166.199315) (xy 371.337742 -166.213421) (xy 371.389071 -166.235233)
			(xy 371.436677 -166.264287) (xy 371.479545 -166.299962) (xy 371.516762 -166.341499) (xy 371.547535 -166.388012)
			(xy 371.571207 -166.438509) (xy 371.587275 -166.491916) (xy 371.595395 -166.547092) (xy 371.595904 -166.574978)
			(xy 371.595395 -166.602864) (xy 371.587275 -166.65804) (xy 371.571207 -166.711447) (xy 371.547535 -166.761944)
			(xy 371.516762 -166.808457) (xy 371.479545 -166.849994) (xy 371.436677 -166.885669) (xy 371.389071 -166.914723)
			(xy 371.337742 -166.936535) (xy 371.283785 -166.950641) (xy 371.228348 -166.956741) (xy 371.172614 -166.954704)
			(xy 371.117771 -166.944574) (xy 371.064987 -166.926567) (xy 371.015387 -166.901066) (xy 370.970029 -166.868615)
			(xy 370.92988 -166.829906) (xy 370.895794 -166.785763) (xy 370.868498 -166.737128) (xy 370.848575 -166.685037)
			(xy 370.836449 -166.6306) (xy 370.832378 -166.574978) (xy 355.215889 -166.574978) (xy 355.218999 -166.596114)
			(xy 355.219508 -166.624) (xy 355.218999 -166.651886) (xy 355.210879 -166.707062) (xy 355.194811 -166.760469)
			(xy 355.171139 -166.810966) (xy 355.140366 -166.857479) (xy 355.103149 -166.899016) (xy 355.060281 -166.934691)
			(xy 355.012675 -166.963745) (xy 354.961346 -166.985557) (xy 354.907389 -166.999663) (xy 354.851952 -167.005763)
			(xy 354.796218 -167.003726) (xy 354.741375 -166.993596) (xy 354.688591 -166.975589) (xy 354.638991 -166.950088)
			(xy 354.593633 -166.917637) (xy 354.553484 -166.878928) (xy 354.519398 -166.834785) (xy 354.492102 -166.78615)
			(xy 354.472179 -166.734059) (xy 354.460053 -166.679622) (xy 354.455982 -166.624) (xy 350.397748 -166.624)
			(xy 350.382559 -166.640952) (xy 350.339691 -166.676627) (xy 350.292085 -166.705681) (xy 350.240756 -166.727493)
			(xy 350.186799 -166.741599) (xy 350.131362 -166.747699) (xy 350.075628 -166.745662) (xy 350.020785 -166.735532)
			(xy 349.968001 -166.717525) (xy 349.918401 -166.692024) (xy 349.873043 -166.659573) (xy 349.832894 -166.620864)
			(xy 349.798808 -166.576721) (xy 349.771512 -166.528086) (xy 349.751589 -166.475995) (xy 349.739463 -166.421558)
			(xy 349.735392 -166.365936) (xy 342.4305 -166.365936) (xy 342.444331 -166.411906) (xy 342.452451 -166.467082)
			(xy 342.45296 -166.494968) (xy 342.452451 -166.522854) (xy 342.444331 -166.57803) (xy 342.428263 -166.631437)
			(xy 342.404591 -166.681934) (xy 342.373818 -166.728447) (xy 342.336601 -166.769984) (xy 342.293733 -166.805659)
			(xy 342.246127 -166.834713) (xy 342.194798 -166.856525) (xy 342.140841 -166.870631) (xy 342.085404 -166.876731)
			(xy 342.02967 -166.874694) (xy 341.974827 -166.864564) (xy 341.922043 -166.846557) (xy 341.872443 -166.821056)
			(xy 341.827085 -166.788605) (xy 341.786936 -166.749896) (xy 341.75285 -166.705753) (xy 341.725554 -166.657118)
			(xy 341.705631 -166.605027) (xy 341.693505 -166.55059) (xy 341.689434 -166.494968) (xy 309.885046 -166.494968)
			(xy 309.791304 -167.005) (xy 336.675982 -167.005) (xy 336.680053 -166.949378) (xy 336.692179 -166.894941)
			(xy 336.712102 -166.84285) (xy 336.739398 -166.794215) (xy 336.773484 -166.750072) (xy 336.813633 -166.711363)
			(xy 336.858991 -166.678912) (xy 336.908591 -166.653411) (xy 336.961375 -166.635404) (xy 337.016218 -166.625274)
			(xy 337.071952 -166.623237) (xy 337.127389 -166.629337) (xy 337.181346 -166.643443) (xy 337.232675 -166.665255)
			(xy 337.280281 -166.694309) (xy 337.323149 -166.729984) (xy 337.360366 -166.771521) (xy 337.391139 -166.818034)
			(xy 337.414811 -166.868531) (xy 337.430879 -166.921938) (xy 337.438999 -166.977114) (xy 337.439508 -167.005)
			(xy 337.438999 -167.032886) (xy 337.430879 -167.088062) (xy 337.414811 -167.141469) (xy 337.391139 -167.191966)
			(xy 337.360366 -167.238479) (xy 337.323149 -167.280016) (xy 337.280281 -167.315691) (xy 337.232675 -167.344745)
			(xy 337.181346 -167.366557) (xy 337.127389 -167.380663) (xy 337.071952 -167.386763) (xy 337.016218 -167.384726)
			(xy 336.961375 -167.374596) (xy 336.908591 -167.356589) (xy 336.858991 -167.331088) (xy 336.813633 -167.298637)
			(xy 336.773484 -167.259928) (xy 336.739398 -167.215785) (xy 336.712102 -167.16715) (xy 336.692179 -167.115059)
			(xy 336.680053 -167.060622) (xy 336.675982 -167.005) (xy 309.791304 -167.005) (xy 309.692846 -167.540686)
			(xy 329.554584 -167.540686) (xy 329.558655 -167.485064) (xy 329.570781 -167.430627) (xy 329.590704 -167.378536)
			(xy 329.618 -167.329901) (xy 329.652086 -167.285758) (xy 329.692235 -167.247049) (xy 329.737593 -167.214598)
			(xy 329.787193 -167.189097) (xy 329.839977 -167.17109) (xy 329.89482 -167.16096) (xy 329.950554 -167.158923)
			(xy 330.005991 -167.165023) (xy 330.059948 -167.179129) (xy 330.111277 -167.200941) (xy 330.158883 -167.229995)
			(xy 330.201751 -167.26567) (xy 330.238968 -167.307207) (xy 330.269741 -167.35372) (xy 330.293413 -167.404217)
			(xy 330.309481 -167.457624) (xy 330.317601 -167.5128) (xy 330.31811 -167.540686) (xy 330.317601 -167.568572)
			(xy 330.309481 -167.623748) (xy 330.303904 -167.642286) (xy 331.300326 -167.642286) (xy 331.304397 -167.586664)
			(xy 331.316523 -167.532227) (xy 331.336446 -167.480136) (xy 331.363742 -167.431501) (xy 331.397828 -167.387358)
			(xy 331.437977 -167.348649) (xy 331.483335 -167.316198) (xy 331.532935 -167.290697) (xy 331.585719 -167.27269)
			(xy 331.640562 -167.26256) (xy 331.696296 -167.260523) (xy 331.751733 -167.266623) (xy 331.80569 -167.280729)
			(xy 331.857019 -167.302541) (xy 331.904625 -167.331595) (xy 331.947493 -167.36727) (xy 331.98471 -167.408807)
			(xy 332.015483 -167.45532) (xy 332.037879 -167.503094) (xy 339.797388 -167.503094) (xy 339.801459 -167.447472)
			(xy 339.813585 -167.393035) (xy 339.833508 -167.340944) (xy 339.860804 -167.292309) (xy 339.89489 -167.248166)
			(xy 339.935039 -167.209457) (xy 339.980397 -167.177006) (xy 340.029997 -167.151505) (xy 340.082781 -167.133498)
			(xy 340.137624 -167.123368) (xy 340.193358 -167.121331) (xy 340.248795 -167.127431) (xy 340.302752 -167.141537)
			(xy 340.354081 -167.163349) (xy 340.366391 -167.170862) (xy 362.960156 -167.170862) (xy 362.964227 -167.11524)
			(xy 362.976353 -167.060803) (xy 362.996276 -167.008712) (xy 363.023572 -166.960077) (xy 363.057658 -166.915934)
			(xy 363.097807 -166.877225) (xy 363.143165 -166.844774) (xy 363.192765 -166.819273) (xy 363.245549 -166.801266)
			(xy 363.300392 -166.791136) (xy 363.356126 -166.789099) (xy 363.411563 -166.795199) (xy 363.46552 -166.809305)
			(xy 363.516849 -166.831117) (xy 363.564455 -166.860171) (xy 363.607323 -166.895846) (xy 363.64454 -166.937383)
			(xy 363.675313 -166.983896) (xy 363.698985 -167.034393) (xy 363.715053 -167.0878) (xy 363.723173 -167.142976)
			(xy 363.723682 -167.170862) (xy 363.723173 -167.198748) (xy 363.715053 -167.253924) (xy 363.698985 -167.307331)
			(xy 363.675313 -167.357828) (xy 363.64454 -167.404341) (xy 363.607323 -167.445878) (xy 363.564455 -167.481553)
			(xy 363.516849 -167.510607) (xy 363.46552 -167.532419) (xy 363.411563 -167.546525) (xy 363.356126 -167.552625)
			(xy 363.300392 -167.550588) (xy 363.245549 -167.540458) (xy 363.192765 -167.522451) (xy 363.143165 -167.49695)
			(xy 363.097807 -167.464499) (xy 363.057658 -167.42579) (xy 363.023572 -167.381647) (xy 362.996276 -167.333012)
			(xy 362.976353 -167.280921) (xy 362.964227 -167.226484) (xy 362.960156 -167.170862) (xy 340.366391 -167.170862)
			(xy 340.401687 -167.192403) (xy 340.444555 -167.228078) (xy 340.481772 -167.269615) (xy 340.512545 -167.316128)
			(xy 340.536217 -167.366625) (xy 340.552285 -167.420032) (xy 340.560405 -167.475208) (xy 340.560914 -167.503094)
			(xy 340.560405 -167.53098) (xy 340.552285 -167.586156) (xy 340.536217 -167.639563) (xy 340.512545 -167.69006)
			(xy 340.481772 -167.736573) (xy 340.444555 -167.77811) (xy 340.401687 -167.813785) (xy 340.363478 -167.837104)
			(xy 349.735392 -167.837104) (xy 349.739463 -167.781482) (xy 349.751589 -167.727045) (xy 349.771512 -167.674954)
			(xy 349.798808 -167.626319) (xy 349.832894 -167.582176) (xy 349.873043 -167.543467) (xy 349.918401 -167.511016)
			(xy 349.968001 -167.485515) (xy 350.020785 -167.467508) (xy 350.075628 -167.457378) (xy 350.131362 -167.455341)
			(xy 350.186799 -167.461441) (xy 350.240756 -167.475547) (xy 350.292085 -167.497359) (xy 350.339691 -167.526413)
			(xy 350.382559 -167.562088) (xy 350.419776 -167.603625) (xy 350.443842 -167.64) (xy 354.455982 -167.64)
			(xy 354.460053 -167.584378) (xy 354.472179 -167.529941) (xy 354.492102 -167.47785) (xy 354.519398 -167.429215)
			(xy 354.553484 -167.385072) (xy 354.593633 -167.346363) (xy 354.638991 -167.313912) (xy 354.688591 -167.288411)
			(xy 354.741375 -167.270404) (xy 354.796218 -167.260274) (xy 354.851952 -167.258237) (xy 354.907389 -167.264337)
			(xy 354.961346 -167.278443) (xy 355.012675 -167.300255) (xy 355.060281 -167.329309) (xy 355.103149 -167.364984)
			(xy 355.140366 -167.406521) (xy 355.171139 -167.453034) (xy 355.194811 -167.503531) (xy 355.210879 -167.556938)
			(xy 355.218999 -167.612114) (xy 355.219508 -167.64) (xy 356.487982 -167.64) (xy 356.492053 -167.584378)
			(xy 356.504179 -167.529941) (xy 356.524102 -167.47785) (xy 356.551398 -167.429215) (xy 356.585484 -167.385072)
			(xy 356.625633 -167.346363) (xy 356.670991 -167.313912) (xy 356.720591 -167.288411) (xy 356.773375 -167.270404)
			(xy 356.828218 -167.260274) (xy 356.883952 -167.258237) (xy 356.939389 -167.264337) (xy 356.993346 -167.278443)
			(xy 357.044675 -167.300255) (xy 357.092281 -167.329309) (xy 357.135149 -167.364984) (xy 357.172366 -167.406521)
			(xy 357.203139 -167.453034) (xy 357.226811 -167.503531) (xy 357.242879 -167.556938) (xy 357.250999 -167.612114)
			(xy 357.251508 -167.64) (xy 357.250999 -167.667886) (xy 357.242879 -167.723062) (xy 357.226811 -167.776469)
			(xy 357.223629 -167.783256) (xy 363.734348 -167.783256) (xy 363.738419 -167.727634) (xy 363.750545 -167.673197)
			(xy 363.770468 -167.621106) (xy 363.797764 -167.572471) (xy 363.83185 -167.528328) (xy 363.871999 -167.489619)
			(xy 363.917357 -167.457168) (xy 363.966957 -167.431667) (xy 364.019741 -167.41366) (xy 364.074584 -167.40353)
			(xy 364.130318 -167.401493) (xy 364.185755 -167.407593) (xy 364.239712 -167.421699) (xy 364.291041 -167.443511)
			(xy 364.338647 -167.472565) (xy 364.381515 -167.50824) (xy 364.418732 -167.549777) (xy 364.449505 -167.59629)
			(xy 364.473177 -167.646787) (xy 364.489245 -167.700194) (xy 364.497365 -167.75537) (xy 364.497874 -167.783256)
			(xy 364.497365 -167.811142) (xy 364.489245 -167.866318) (xy 364.473177 -167.919725) (xy 364.449505 -167.970222)
			(xy 364.418732 -168.016735) (xy 364.381515 -168.058272) (xy 364.338647 -168.093947) (xy 364.291041 -168.123001)
			(xy 364.239712 -168.144813) (xy 364.185755 -168.158919) (xy 364.130318 -168.165019) (xy 364.074584 -168.162982)
			(xy 364.019741 -168.152852) (xy 363.966957 -168.134845) (xy 363.917357 -168.109344) (xy 363.871999 -168.076893)
			(xy 363.83185 -168.038184) (xy 363.797764 -167.994041) (xy 363.770468 -167.945406) (xy 363.750545 -167.893315)
			(xy 363.738419 -167.838878) (xy 363.734348 -167.783256) (xy 357.223629 -167.783256) (xy 357.203139 -167.826966)
			(xy 357.172366 -167.873479) (xy 357.135149 -167.915016) (xy 357.092281 -167.950691) (xy 357.044675 -167.979745)
			(xy 356.993346 -168.001557) (xy 356.939389 -168.015663) (xy 356.883952 -168.021763) (xy 356.828218 -168.019726)
			(xy 356.773375 -168.009596) (xy 356.720591 -167.991589) (xy 356.670991 -167.966088) (xy 356.625633 -167.933637)
			(xy 356.585484 -167.894928) (xy 356.551398 -167.850785) (xy 356.524102 -167.80215) (xy 356.504179 -167.750059)
			(xy 356.492053 -167.695622) (xy 356.487982 -167.64) (xy 355.219508 -167.64) (xy 355.218999 -167.667886)
			(xy 355.210879 -167.723062) (xy 355.194811 -167.776469) (xy 355.171139 -167.826966) (xy 355.140366 -167.873479)
			(xy 355.103149 -167.915016) (xy 355.060281 -167.950691) (xy 355.012675 -167.979745) (xy 354.961346 -168.001557)
			(xy 354.907389 -168.015663) (xy 354.851952 -168.021763) (xy 354.796218 -168.019726) (xy 354.741375 -168.009596)
			(xy 354.688591 -167.991589) (xy 354.638991 -167.966088) (xy 354.593633 -167.933637) (xy 354.553484 -167.894928)
			(xy 354.519398 -167.850785) (xy 354.492102 -167.80215) (xy 354.472179 -167.750059) (xy 354.460053 -167.695622)
			(xy 354.455982 -167.64) (xy 350.443842 -167.64) (xy 350.450549 -167.650138) (xy 350.474221 -167.700635)
			(xy 350.490289 -167.754042) (xy 350.498409 -167.809218) (xy 350.498918 -167.837104) (xy 350.498409 -167.86499)
			(xy 350.490289 -167.920166) (xy 350.474221 -167.973573) (xy 350.450549 -168.02407) (xy 350.419776 -168.070583)
			(xy 350.382559 -168.11212) (xy 350.339691 -168.147795) (xy 350.292085 -168.176849) (xy 350.240756 -168.198661)
			(xy 350.186799 -168.212767) (xy 350.131362 -168.218867) (xy 350.075628 -168.21683) (xy 350.020785 -168.2067)
			(xy 349.968001 -168.188693) (xy 349.918401 -168.163192) (xy 349.873043 -168.130741) (xy 349.832894 -168.092032)
			(xy 349.798808 -168.047889) (xy 349.771512 -167.999254) (xy 349.751589 -167.947163) (xy 349.739463 -167.892726)
			(xy 349.735392 -167.837104) (xy 340.363478 -167.837104) (xy 340.354081 -167.842839) (xy 340.302752 -167.864651)
			(xy 340.248795 -167.878757) (xy 340.193358 -167.884857) (xy 340.137624 -167.88282) (xy 340.082781 -167.87269)
			(xy 340.029997 -167.854683) (xy 339.980397 -167.829182) (xy 339.935039 -167.796731) (xy 339.89489 -167.758022)
			(xy 339.860804 -167.713879) (xy 339.833508 -167.665244) (xy 339.813585 -167.613153) (xy 339.801459 -167.558716)
			(xy 339.797388 -167.503094) (xy 332.037879 -167.503094) (xy 332.039155 -167.505817) (xy 332.055223 -167.559224)
			(xy 332.063343 -167.6144) (xy 332.063852 -167.642286) (xy 332.063343 -167.670172) (xy 332.055223 -167.725348)
			(xy 332.039155 -167.778755) (xy 332.015483 -167.829252) (xy 331.98471 -167.875765) (xy 331.947493 -167.917302)
			(xy 331.904625 -167.952977) (xy 331.857019 -167.982031) (xy 331.80569 -168.003843) (xy 331.751733 -168.017949)
			(xy 331.696296 -168.024049) (xy 331.640562 -168.022012) (xy 331.585719 -168.011882) (xy 331.532935 -167.993875)
			(xy 331.483335 -167.968374) (xy 331.437977 -167.935923) (xy 331.397828 -167.897214) (xy 331.363742 -167.853071)
			(xy 331.336446 -167.804436) (xy 331.316523 -167.752345) (xy 331.304397 -167.697908) (xy 331.300326 -167.642286)
			(xy 330.303904 -167.642286) (xy 330.293413 -167.677155) (xy 330.269741 -167.727652) (xy 330.238968 -167.774165)
			(xy 330.201751 -167.815702) (xy 330.158883 -167.851377) (xy 330.111277 -167.880431) (xy 330.059948 -167.902243)
			(xy 330.005991 -167.916349) (xy 329.950554 -167.922449) (xy 329.89482 -167.920412) (xy 329.839977 -167.910282)
			(xy 329.787193 -167.892275) (xy 329.737593 -167.866774) (xy 329.692235 -167.834323) (xy 329.652086 -167.795614)
			(xy 329.618 -167.751471) (xy 329.590704 -167.702836) (xy 329.570781 -167.650745) (xy 329.558655 -167.596308)
			(xy 329.554584 -167.540686) (xy 309.692846 -167.540686) (xy 309.417828 -169.037) (xy 334.643982 -169.037)
			(xy 334.648053 -168.981378) (xy 334.660179 -168.926941) (xy 334.680102 -168.87485) (xy 334.707398 -168.826215)
			(xy 334.741484 -168.782072) (xy 334.781633 -168.743363) (xy 334.826991 -168.710912) (xy 334.876591 -168.685411)
			(xy 334.929375 -168.667404) (xy 334.984218 -168.657274) (xy 335.039952 -168.655237) (xy 335.095389 -168.661337)
			(xy 335.149346 -168.675443) (xy 335.200675 -168.697255) (xy 335.248281 -168.726309) (xy 335.291149 -168.761984)
			(xy 335.328366 -168.803521) (xy 335.359139 -168.850034) (xy 335.382811 -168.900531) (xy 335.398879 -168.953938)
			(xy 335.406999 -169.009114) (xy 335.407508 -169.037) (xy 335.406999 -169.064886) (xy 335.398879 -169.120062)
			(xy 335.382811 -169.173469) (xy 335.359139 -169.223966) (xy 335.328366 -169.270479) (xy 335.291149 -169.312016)
			(xy 335.248281 -169.347691) (xy 335.200675 -169.376745) (xy 335.149346 -169.398557) (xy 335.095389 -169.412663)
			(xy 335.039952 -169.418763) (xy 334.984218 -169.416726) (xy 334.929375 -169.406596) (xy 334.876591 -169.388589)
			(xy 334.826991 -169.363088) (xy 334.781633 -169.330637) (xy 334.741484 -169.291928) (xy 334.707398 -169.247785)
			(xy 334.680102 -169.19915) (xy 334.660179 -169.147059) (xy 334.648053 -169.092622) (xy 334.643982 -169.037)
			(xy 309.417828 -169.037) (xy 309.311387 -169.61612) (xy 341.637364 -169.61612) (xy 341.641435 -169.560498)
			(xy 341.653561 -169.506061) (xy 341.673484 -169.45397) (xy 341.70078 -169.405335) (xy 341.734866 -169.361192)
			(xy 341.775015 -169.322483) (xy 341.820373 -169.290032) (xy 341.869973 -169.264531) (xy 341.922757 -169.246524)
			(xy 341.9776 -169.236394) (xy 342.033334 -169.234357) (xy 342.088771 -169.240457) (xy 342.142728 -169.254563)
			(xy 342.194057 -169.276375) (xy 342.241663 -169.305429) (xy 342.284531 -169.341104) (xy 342.321748 -169.382641)
			(xy 342.352521 -169.429154) (xy 342.376193 -169.479651) (xy 342.392261 -169.533058) (xy 342.400381 -169.588234)
			(xy 342.40089 -169.61612) (xy 342.400381 -169.644006) (xy 342.392261 -169.699182) (xy 342.376193 -169.752589)
			(xy 342.352521 -169.803086) (xy 342.321748 -169.849599) (xy 342.284531 -169.891136) (xy 342.241663 -169.926811)
			(xy 342.194057 -169.955865) (xy 342.142728 -169.977677) (xy 342.088771 -169.991783) (xy 342.033334 -169.997883)
			(xy 341.9776 -169.995846) (xy 341.922757 -169.985716) (xy 341.869973 -169.967709) (xy 341.820373 -169.942208)
			(xy 341.775015 -169.909757) (xy 341.734866 -169.871048) (xy 341.70078 -169.826905) (xy 341.673484 -169.77827)
			(xy 341.653561 -169.726179) (xy 341.641435 -169.671742) (xy 341.637364 -169.61612) (xy 309.311387 -169.61612)
			(xy 309.23109 -170.053) (xy 334.643982 -170.053) (xy 334.648053 -169.997378) (xy 334.660179 -169.942941)
			(xy 334.680102 -169.89085) (xy 334.707398 -169.842215) (xy 334.741484 -169.798072) (xy 334.781633 -169.759363)
			(xy 334.826991 -169.726912) (xy 334.876591 -169.701411) (xy 334.929375 -169.683404) (xy 334.984218 -169.673274)
			(xy 335.039952 -169.671237) (xy 335.095389 -169.677337) (xy 335.149346 -169.691443) (xy 335.200675 -169.713255)
			(xy 335.248281 -169.742309) (xy 335.291149 -169.777984) (xy 335.328366 -169.819521) (xy 335.359139 -169.866034)
			(xy 335.382811 -169.916531) (xy 335.398879 -169.969938) (xy 335.406999 -170.025114) (xy 335.407508 -170.053)
			(xy 335.406999 -170.080886) (xy 335.398879 -170.136062) (xy 335.382811 -170.189469) (xy 335.359139 -170.239966)
			(xy 335.341845 -170.266106) (xy 340.499444 -170.266106) (xy 340.503515 -170.210484) (xy 340.515641 -170.156047)
			(xy 340.535564 -170.103956) (xy 340.56286 -170.055321) (xy 340.596946 -170.011178) (xy 340.637095 -169.972469)
			(xy 340.682453 -169.940018) (xy 340.732053 -169.914517) (xy 340.784837 -169.89651) (xy 340.83968 -169.88638)
			(xy 340.895414 -169.884343) (xy 340.950851 -169.890443) (xy 341.004808 -169.904549) (xy 341.056137 -169.926361)
			(xy 341.103743 -169.955415) (xy 341.146611 -169.99109) (xy 341.183828 -170.032627) (xy 341.214601 -170.07914)
			(xy 341.238273 -170.129637) (xy 341.254341 -170.183044) (xy 341.262461 -170.23822) (xy 341.26297 -170.266106)
			(xy 341.262461 -170.293992) (xy 341.254341 -170.349168) (xy 341.238273 -170.402575) (xy 341.214601 -170.453072)
			(xy 341.183828 -170.499585) (xy 341.146611 -170.541122) (xy 341.103743 -170.576797) (xy 341.056137 -170.605851)
			(xy 341.004808 -170.627663) (xy 340.950851 -170.641769) (xy 340.895414 -170.647869) (xy 340.83968 -170.645832)
			(xy 340.784837 -170.635702) (xy 340.732053 -170.617695) (xy 340.682453 -170.592194) (xy 340.637095 -170.559743)
			(xy 340.596946 -170.521034) (xy 340.56286 -170.476891) (xy 340.535564 -170.428256) (xy 340.515641 -170.376165)
			(xy 340.503515 -170.321728) (xy 340.499444 -170.266106) (xy 335.341845 -170.266106) (xy 335.328366 -170.286479)
			(xy 335.291149 -170.328016) (xy 335.248281 -170.363691) (xy 335.200675 -170.392745) (xy 335.149346 -170.414557)
			(xy 335.095389 -170.428663) (xy 335.039952 -170.434763) (xy 334.984218 -170.432726) (xy 334.929375 -170.422596)
			(xy 334.876591 -170.404589) (xy 334.826991 -170.379088) (xy 334.781633 -170.346637) (xy 334.741484 -170.307928)
			(xy 334.707398 -170.263785) (xy 334.680102 -170.21515) (xy 334.660179 -170.163059) (xy 334.648053 -170.108622)
			(xy 334.643982 -170.053) (xy 309.23109 -170.053) (xy 309.072456 -170.916092) (xy 341.637364 -170.916092)
			(xy 341.641435 -170.86047) (xy 341.653561 -170.806033) (xy 341.673484 -170.753942) (xy 341.70078 -170.705307)
			(xy 341.734866 -170.661164) (xy 341.775015 -170.622455) (xy 341.820373 -170.590004) (xy 341.869973 -170.564503)
			(xy 341.922757 -170.546496) (xy 341.9776 -170.536366) (xy 342.033334 -170.534329) (xy 342.088771 -170.540429)
			(xy 342.142728 -170.554535) (xy 342.194057 -170.576347) (xy 342.241663 -170.605401) (xy 342.284531 -170.641076)
			(xy 342.321748 -170.682613) (xy 342.352521 -170.729126) (xy 342.376193 -170.779623) (xy 342.385919 -170.811952)
			(xy 351.735388 -170.811952) (xy 351.739459 -170.75633) (xy 351.751585 -170.701893) (xy 351.771508 -170.649802)
			(xy 351.798804 -170.601167) (xy 351.83289 -170.557024) (xy 351.873039 -170.518315) (xy 351.918397 -170.485864)
			(xy 351.967997 -170.460363) (xy 352.020781 -170.442356) (xy 352.075624 -170.432226) (xy 352.131358 -170.430189)
			(xy 352.186795 -170.436289) (xy 352.240752 -170.450395) (xy 352.292081 -170.472207) (xy 352.339687 -170.501261)
			(xy 352.382555 -170.536936) (xy 352.419772 -170.578473) (xy 352.450545 -170.624986) (xy 352.474217 -170.675483)
			(xy 352.490285 -170.72889) (xy 352.498405 -170.784066) (xy 352.498914 -170.811952) (xy 352.498405 -170.839838)
			(xy 352.490285 -170.895014) (xy 352.474217 -170.948421) (xy 352.450545 -170.998918) (xy 352.419772 -171.045431)
			(xy 352.382555 -171.086968) (xy 352.339687 -171.122643) (xy 352.292081 -171.151697) (xy 352.240752 -171.173509)
			(xy 352.186795 -171.187615) (xy 352.131358 -171.193715) (xy 352.075624 -171.191678) (xy 352.020781 -171.181548)
			(xy 351.967997 -171.163541) (xy 351.918397 -171.13804) (xy 351.873039 -171.105589) (xy 351.83289 -171.06688)
			(xy 351.798804 -171.022737) (xy 351.771508 -170.974102) (xy 351.751585 -170.922011) (xy 351.739459 -170.867574)
			(xy 351.735388 -170.811952) (xy 342.385919 -170.811952) (xy 342.392261 -170.83303) (xy 342.400381 -170.888206)
			(xy 342.40089 -170.916092) (xy 342.400381 -170.943978) (xy 342.392261 -170.999154) (xy 342.376193 -171.052561)
			(xy 342.352521 -171.103058) (xy 342.321748 -171.149571) (xy 342.284531 -171.191108) (xy 342.241663 -171.226783)
			(xy 342.194057 -171.255837) (xy 342.142728 -171.277649) (xy 342.088771 -171.291755) (xy 342.033334 -171.297855)
			(xy 341.9776 -171.295818) (xy 341.922757 -171.285688) (xy 341.869973 -171.267681) (xy 341.820373 -171.24218)
			(xy 341.775015 -171.209729) (xy 341.734866 -171.17102) (xy 341.70078 -171.126877) (xy 341.673484 -171.078242)
			(xy 341.653561 -171.026151) (xy 341.641435 -170.971714) (xy 341.637364 -170.916092) (xy 309.072456 -170.916092)
			(xy 308.95299 -171.566078) (xy 349.87306 -171.566078) (xy 349.877131 -171.510456) (xy 349.889257 -171.456019)
			(xy 349.90918 -171.403928) (xy 349.936476 -171.355293) (xy 349.970562 -171.31115) (xy 350.010711 -171.272441)
			(xy 350.056069 -171.23999) (xy 350.105669 -171.214489) (xy 350.158453 -171.196482) (xy 350.213296 -171.186352)
			(xy 350.26903 -171.184315) (xy 350.324467 -171.190415) (xy 350.378424 -171.204521) (xy 350.429753 -171.226333)
			(xy 350.477359 -171.255387) (xy 350.520227 -171.291062) (xy 350.557444 -171.332599) (xy 350.588217 -171.379112)
			(xy 350.611889 -171.429609) (xy 350.627957 -171.483016) (xy 350.636077 -171.538192) (xy 350.636586 -171.566078)
			(xy 350.636387 -171.577) (xy 350.899982 -171.577) (xy 350.904053 -171.521378) (xy 350.916179 -171.466941)
			(xy 350.936102 -171.41485) (xy 350.963398 -171.366215) (xy 350.997484 -171.322072) (xy 351.037633 -171.283363)
			(xy 351.082991 -171.250912) (xy 351.132591 -171.225411) (xy 351.185375 -171.207404) (xy 351.240218 -171.197274)
			(xy 351.295952 -171.195237) (xy 351.351389 -171.201337) (xy 351.405346 -171.215443) (xy 351.456675 -171.237255)
			(xy 351.504281 -171.266309) (xy 351.547149 -171.301984) (xy 351.584366 -171.343521) (xy 351.615139 -171.390034)
			(xy 351.638811 -171.440531) (xy 351.64166 -171.45) (xy 356.360982 -171.45) (xy 356.365053 -171.394378)
			(xy 356.377179 -171.339941) (xy 356.397102 -171.28785) (xy 356.424398 -171.239215) (xy 356.458484 -171.195072)
			(xy 356.498633 -171.156363) (xy 356.543991 -171.123912) (xy 356.593591 -171.098411) (xy 356.646375 -171.080404)
			(xy 356.701218 -171.070274) (xy 356.756952 -171.068237) (xy 356.812389 -171.074337) (xy 356.866346 -171.088443)
			(xy 356.917675 -171.110255) (xy 356.965281 -171.139309) (xy 357.008149 -171.174984) (xy 357.045366 -171.216521)
			(xy 357.050611 -171.224448) (xy 361.978192 -171.224448) (xy 361.982263 -171.168826) (xy 361.994389 -171.114389)
			(xy 362.014312 -171.062298) (xy 362.041608 -171.013663) (xy 362.075694 -170.96952) (xy 362.115843 -170.930811)
			(xy 362.161201 -170.89836) (xy 362.210801 -170.872859) (xy 362.263585 -170.854852) (xy 362.318428 -170.844722)
			(xy 362.374162 -170.842685) (xy 362.429599 -170.848785) (xy 362.483556 -170.862891) (xy 362.534885 -170.884703)
			(xy 362.582491 -170.913757) (xy 362.625359 -170.949432) (xy 362.660348 -170.988482) (xy 366.984024 -170.988482)
			(xy 366.988095 -170.93286) (xy 367.000221 -170.878423) (xy 367.020144 -170.826332) (xy 367.04744 -170.777697)
			(xy 367.081526 -170.733554) (xy 367.121675 -170.694845) (xy 367.167033 -170.662394) (xy 367.216633 -170.636893)
			(xy 367.269417 -170.618886) (xy 367.32426 -170.608756) (xy 367.379994 -170.606719) (xy 367.435431 -170.612819)
			(xy 367.489388 -170.626925) (xy 367.540717 -170.648737) (xy 367.588323 -170.677791) (xy 367.631191 -170.713466)
			(xy 367.668408 -170.755003) (xy 367.699181 -170.801516) (xy 367.722853 -170.852013) (xy 367.738921 -170.90542)
			(xy 367.747041 -170.960596) (xy 367.74755 -170.988482) (xy 367.74723 -171.006008) (xy 368.280694 -171.006008)
			(xy 368.284765 -170.950386) (xy 368.296891 -170.895949) (xy 368.316814 -170.843858) (xy 368.34411 -170.795223)
			(xy 368.378196 -170.75108) (xy 368.418345 -170.712371) (xy 368.463703 -170.67992) (xy 368.513303 -170.654419)
			(xy 368.566087 -170.636412) (xy 368.62093 -170.626282) (xy 368.676664 -170.624245) (xy 368.732101 -170.630345)
			(xy 368.786058 -170.644451) (xy 368.837387 -170.666263) (xy 368.884993 -170.695317) (xy 368.927861 -170.730992)
			(xy 368.965078 -170.772529) (xy 368.995851 -170.819042) (xy 369.019523 -170.869539) (xy 369.035591 -170.922946)
			(xy 369.043711 -170.978122) (xy 369.04422 -171.006008) (xy 369.043711 -171.033894) (xy 369.035591 -171.08907)
			(xy 369.019523 -171.142477) (xy 369.016818 -171.148248) (xy 372.58447 -171.148248) (xy 372.588541 -171.092626)
			(xy 372.600667 -171.038189) (xy 372.62059 -170.986098) (xy 372.647886 -170.937463) (xy 372.681972 -170.89332)
			(xy 372.722121 -170.854611) (xy 372.767479 -170.82216) (xy 372.817079 -170.796659) (xy 372.869863 -170.778652)
			(xy 372.924706 -170.768522) (xy 372.98044 -170.766485) (xy 373.035877 -170.772585) (xy 373.089834 -170.786691)
			(xy 373.141163 -170.808503) (xy 373.188769 -170.837557) (xy 373.231637 -170.873232) (xy 373.268854 -170.914769)
			(xy 373.299627 -170.961282) (xy 373.323299 -171.011779) (xy 373.339367 -171.065186) (xy 373.347487 -171.120362)
			(xy 373.347996 -171.148248) (xy 373.347487 -171.176134) (xy 373.339367 -171.23131) (xy 373.323299 -171.284717)
			(xy 373.299627 -171.335214) (xy 373.268854 -171.381727) (xy 373.231637 -171.423264) (xy 373.188769 -171.458939)
			(xy 373.141163 -171.487993) (xy 373.089834 -171.509805) (xy 373.035877 -171.523911) (xy 372.98044 -171.530011)
			(xy 372.924706 -171.527974) (xy 372.869863 -171.517844) (xy 372.817079 -171.499837) (xy 372.767479 -171.474336)
			(xy 372.722121 -171.441885) (xy 372.681972 -171.403176) (xy 372.647886 -171.359033) (xy 372.62059 -171.310398)
			(xy 372.600667 -171.258307) (xy 372.588541 -171.20387) (xy 372.58447 -171.148248) (xy 369.016818 -171.148248)
			(xy 368.995851 -171.192974) (xy 368.965078 -171.239487) (xy 368.927861 -171.281024) (xy 368.884993 -171.316699)
			(xy 368.837387 -171.345753) (xy 368.786058 -171.367565) (xy 368.732101 -171.381671) (xy 368.676664 -171.387771)
			(xy 368.62093 -171.385734) (xy 368.566087 -171.375604) (xy 368.513303 -171.357597) (xy 368.463703 -171.332096)
			(xy 368.418345 -171.299645) (xy 368.378196 -171.260936) (xy 368.34411 -171.216793) (xy 368.316814 -171.168158)
			(xy 368.296891 -171.116067) (xy 368.284765 -171.06163) (xy 368.280694 -171.006008) (xy 367.74723 -171.006008)
			(xy 367.747041 -171.016368) (xy 367.738921 -171.071544) (xy 367.722853 -171.124951) (xy 367.699181 -171.175448)
			(xy 367.668408 -171.221961) (xy 367.631191 -171.263498) (xy 367.588323 -171.299173) (xy 367.540717 -171.328227)
			(xy 367.489388 -171.350039) (xy 367.435431 -171.364145) (xy 367.379994 -171.370245) (xy 367.32426 -171.368208)
			(xy 367.269417 -171.358078) (xy 367.216633 -171.340071) (xy 367.167033 -171.31457) (xy 367.121675 -171.282119)
			(xy 367.081526 -171.24341) (xy 367.04744 -171.199267) (xy 367.020144 -171.150632) (xy 367.000221 -171.098541)
			(xy 366.988095 -171.044104) (xy 366.984024 -170.988482) (xy 362.660348 -170.988482) (xy 362.662576 -170.990969)
			(xy 362.693349 -171.037482) (xy 362.717021 -171.087979) (xy 362.733089 -171.141386) (xy 362.741209 -171.196562)
			(xy 362.741718 -171.224448) (xy 362.741209 -171.252334) (xy 362.733089 -171.30751) (xy 362.717021 -171.360917)
			(xy 362.693349 -171.411414) (xy 362.662576 -171.457927) (xy 362.625359 -171.499464) (xy 362.582491 -171.535139)
			(xy 362.534885 -171.564193) (xy 362.483556 -171.586005) (xy 362.429599 -171.600111) (xy 362.374162 -171.606211)
			(xy 362.318428 -171.604174) (xy 362.263585 -171.594044) (xy 362.210801 -171.576037) (xy 362.161201 -171.550536)
			(xy 362.115843 -171.518085) (xy 362.075694 -171.479376) (xy 362.041608 -171.435233) (xy 362.014312 -171.386598)
			(xy 361.994389 -171.334507) (xy 361.982263 -171.28007) (xy 361.978192 -171.224448) (xy 357.050611 -171.224448)
			(xy 357.076139 -171.263034) (xy 357.099811 -171.313531) (xy 357.115879 -171.366938) (xy 357.123999 -171.422114)
			(xy 357.124508 -171.45) (xy 357.123999 -171.477886) (xy 357.115879 -171.533062) (xy 357.099811 -171.586469)
			(xy 357.076139 -171.636966) (xy 357.045366 -171.683479) (xy 357.008149 -171.725016) (xy 356.965281 -171.760691)
			(xy 356.917675 -171.789745) (xy 356.866346 -171.811557) (xy 356.812389 -171.825663) (xy 356.756952 -171.831763)
			(xy 356.701218 -171.829726) (xy 356.646375 -171.819596) (xy 356.593591 -171.801589) (xy 356.543991 -171.776088)
			(xy 356.498633 -171.743637) (xy 356.458484 -171.704928) (xy 356.424398 -171.660785) (xy 356.397102 -171.61215)
			(xy 356.377179 -171.560059) (xy 356.365053 -171.505622) (xy 356.360982 -171.45) (xy 351.64166 -171.45)
			(xy 351.654879 -171.493938) (xy 351.662999 -171.549114) (xy 351.663508 -171.577) (xy 351.662999 -171.604886)
			(xy 351.654879 -171.660062) (xy 351.638811 -171.713469) (xy 351.615139 -171.763966) (xy 351.584366 -171.810479)
			(xy 351.547149 -171.852016) (xy 351.504281 -171.887691) (xy 351.456675 -171.916745) (xy 351.405346 -171.938557)
			(xy 351.351389 -171.952663) (xy 351.295952 -171.958763) (xy 351.240218 -171.956726) (xy 351.185375 -171.946596)
			(xy 351.132591 -171.928589) (xy 351.082991 -171.903088) (xy 351.037633 -171.870637) (xy 350.997484 -171.831928)
			(xy 350.963398 -171.787785) (xy 350.936102 -171.73915) (xy 350.916179 -171.687059) (xy 350.904053 -171.632622)
			(xy 350.899982 -171.577) (xy 350.636387 -171.577) (xy 350.636077 -171.593964) (xy 350.627957 -171.64914)
			(xy 350.611889 -171.702547) (xy 350.588217 -171.753044) (xy 350.557444 -171.799557) (xy 350.520227 -171.841094)
			(xy 350.477359 -171.876769) (xy 350.429753 -171.905823) (xy 350.378424 -171.927635) (xy 350.324467 -171.941741)
			(xy 350.26903 -171.947841) (xy 350.213296 -171.945804) (xy 350.158453 -171.935674) (xy 350.105669 -171.917667)
			(xy 350.056069 -171.892166) (xy 350.010711 -171.859715) (xy 349.970562 -171.821006) (xy 349.936476 -171.776863)
			(xy 349.90918 -171.728228) (xy 349.889257 -171.676137) (xy 349.877131 -171.6217) (xy 349.87306 -171.566078)
			(xy 308.95299 -171.566078) (xy 308.796924 -172.4152) (xy 325.982582 -172.4152) (xy 325.986653 -172.359578)
			(xy 325.998779 -172.305141) (xy 326.018702 -172.25305) (xy 326.045998 -172.204415) (xy 326.080084 -172.160272)
			(xy 326.120233 -172.121563) (xy 326.165591 -172.089112) (xy 326.215191 -172.063611) (xy 326.267975 -172.045604)
			(xy 326.322818 -172.035474) (xy 326.378552 -172.033437) (xy 326.433989 -172.039537) (xy 326.487946 -172.053643)
			(xy 326.539275 -172.075455) (xy 326.586881 -172.104509) (xy 326.597622 -172.113448) (xy 327.229976 -172.113448)
			(xy 327.234047 -172.057826) (xy 327.246173 -172.003389) (xy 327.266096 -171.951298) (xy 327.293392 -171.902663)
			(xy 327.327478 -171.85852) (xy 327.367627 -171.819811) (xy 327.412985 -171.78736) (xy 327.462585 -171.761859)
			(xy 327.515369 -171.743852) (xy 327.570212 -171.733722) (xy 327.625946 -171.731685) (xy 327.681383 -171.737785)
			(xy 327.73534 -171.751891) (xy 327.786669 -171.773703) (xy 327.834275 -171.802757) (xy 327.877143 -171.838432)
			(xy 327.91436 -171.879969) (xy 327.945133 -171.926482) (xy 327.968805 -171.976979) (xy 327.984873 -172.030386)
			(xy 327.992993 -172.085562) (xy 327.993502 -172.113448) (xy 327.992993 -172.141334) (xy 327.992836 -172.142404)
			(xy 333.368648 -172.142404) (xy 333.372719 -172.086782) (xy 333.384845 -172.032345) (xy 333.404768 -171.980254)
			(xy 333.432064 -171.931619) (xy 333.46615 -171.887476) (xy 333.506299 -171.848767) (xy 333.551657 -171.816316)
			(xy 333.601257 -171.790815) (xy 333.654041 -171.772808) (xy 333.708884 -171.762678) (xy 333.764618 -171.760641)
			(xy 333.820055 -171.766741) (xy 333.874012 -171.780847) (xy 333.925341 -171.802659) (xy 333.972947 -171.831713)
			(xy 334.015815 -171.867388) (xy 334.053032 -171.908925) (xy 334.083805 -171.955438) (xy 334.107477 -172.005935)
			(xy 334.123545 -172.059342) (xy 334.127321 -172.085) (xy 334.643982 -172.085) (xy 334.648053 -172.029378)
			(xy 334.660179 -171.974941) (xy 334.680102 -171.92285) (xy 334.707398 -171.874215) (xy 334.741484 -171.830072)
			(xy 334.781633 -171.791363) (xy 334.826991 -171.758912) (xy 334.876591 -171.733411) (xy 334.929375 -171.715404)
			(xy 334.984218 -171.705274) (xy 335.039952 -171.703237) (xy 335.095389 -171.709337) (xy 335.149346 -171.723443)
			(xy 335.200675 -171.745255) (xy 335.248281 -171.774309) (xy 335.291149 -171.809984) (xy 335.328366 -171.851521)
			(xy 335.359139 -171.898034) (xy 335.382811 -171.948531) (xy 335.395823 -171.991782) (xy 340.11057 -171.991782)
			(xy 340.114641 -171.93616) (xy 340.126767 -171.881723) (xy 340.14669 -171.829632) (xy 340.173986 -171.780997)
			(xy 340.208072 -171.736854) (xy 340.248221 -171.698145) (xy 340.293579 -171.665694) (xy 340.343179 -171.640193)
			(xy 340.395963 -171.622186) (xy 340.450806 -171.612056) (xy 340.50654 -171.610019) (xy 340.561977 -171.616119)
			(xy 340.615934 -171.630225) (xy 340.667263 -171.652037) (xy 340.714869 -171.681091) (xy 340.757737 -171.716766)
			(xy 340.794954 -171.758303) (xy 340.825727 -171.804816) (xy 340.849399 -171.855313) (xy 340.865467 -171.90872)
			(xy 340.873587 -171.963896) (xy 340.874096 -171.991782) (xy 340.873587 -172.019668) (xy 340.865467 -172.074844)
			(xy 340.849399 -172.128251) (xy 340.825727 -172.178748) (xy 340.794954 -172.225261) (xy 340.757737 -172.266798)
			(xy 340.714869 -172.302473) (xy 340.667263 -172.331527) (xy 340.615934 -172.353339) (xy 340.561977 -172.367445)
			(xy 340.50654 -172.373545) (xy 340.450806 -172.371508) (xy 340.395963 -172.361378) (xy 340.343179 -172.343371)
			(xy 340.293579 -172.31787) (xy 340.248221 -172.285419) (xy 340.208072 -172.24671) (xy 340.173986 -172.202567)
			(xy 340.14669 -172.153932) (xy 340.126767 -172.101841) (xy 340.114641 -172.047404) (xy 340.11057 -171.991782)
			(xy 335.395823 -171.991782) (xy 335.398879 -172.001938) (xy 335.406999 -172.057114) (xy 335.407508 -172.085)
			(xy 335.406999 -172.112886) (xy 335.398879 -172.168062) (xy 335.382811 -172.221469) (xy 335.359139 -172.271966)
			(xy 335.328366 -172.318479) (xy 335.291149 -172.360016) (xy 335.248281 -172.395691) (xy 335.200675 -172.424745)
			(xy 335.149346 -172.446557) (xy 335.095389 -172.460663) (xy 335.039952 -172.466763) (xy 334.984218 -172.464726)
			(xy 334.929375 -172.454596) (xy 334.876591 -172.436589) (xy 334.826991 -172.411088) (xy 334.781633 -172.378637)
			(xy 334.741484 -172.339928) (xy 334.707398 -172.295785) (xy 334.680102 -172.24715) (xy 334.660179 -172.195059)
			(xy 334.648053 -172.140622) (xy 334.643982 -172.085) (xy 334.127321 -172.085) (xy 334.131665 -172.114518)
			(xy 334.132174 -172.142404) (xy 334.131665 -172.17029) (xy 334.123545 -172.225466) (xy 334.107477 -172.278873)
			(xy 334.083805 -172.32937) (xy 334.053032 -172.375883) (xy 334.015815 -172.41742) (xy 333.972947 -172.453095)
			(xy 333.925341 -172.482149) (xy 333.874012 -172.503961) (xy 333.820055 -172.518067) (xy 333.764618 -172.524167)
			(xy 333.708884 -172.52213) (xy 333.654041 -172.512) (xy 333.601257 -172.493993) (xy 333.551657 -172.468492)
			(xy 333.506299 -172.436041) (xy 333.46615 -172.397332) (xy 333.432064 -172.353189) (xy 333.404768 -172.304554)
			(xy 333.384845 -172.252463) (xy 333.372719 -172.198026) (xy 333.368648 -172.142404) (xy 327.992836 -172.142404)
			(xy 327.984873 -172.19651) (xy 327.968805 -172.249917) (xy 327.945133 -172.300414) (xy 327.91436 -172.346927)
			(xy 327.877143 -172.388464) (xy 327.834275 -172.424139) (xy 327.786669 -172.453193) (xy 327.73534 -172.475005)
			(xy 327.681383 -172.489111) (xy 327.625946 -172.495211) (xy 327.570212 -172.493174) (xy 327.515369 -172.483044)
			(xy 327.462585 -172.465037) (xy 327.412985 -172.439536) (xy 327.367627 -172.407085) (xy 327.327478 -172.368376)
			(xy 327.293392 -172.324233) (xy 327.266096 -172.275598) (xy 327.246173 -172.223507) (xy 327.234047 -172.16907)
			(xy 327.229976 -172.113448) (xy 326.597622 -172.113448) (xy 326.629749 -172.140184) (xy 326.666966 -172.181721)
			(xy 326.697739 -172.228234) (xy 326.721411 -172.278731) (xy 326.737479 -172.332138) (xy 326.745599 -172.387314)
			(xy 326.746108 -172.4152) (xy 326.745599 -172.443086) (xy 326.737479 -172.498262) (xy 326.721411 -172.551669)
			(xy 326.697739 -172.602166) (xy 326.666966 -172.648679) (xy 326.629749 -172.690216) (xy 326.586881 -172.725891)
			(xy 326.539275 -172.754945) (xy 326.487946 -172.776757) (xy 326.433989 -172.790863) (xy 326.378552 -172.796963)
			(xy 326.322818 -172.794926) (xy 326.267975 -172.784796) (xy 326.215191 -172.766789) (xy 326.165591 -172.741288)
			(xy 326.120233 -172.708837) (xy 326.080084 -172.670128) (xy 326.045998 -172.625985) (xy 326.018702 -172.57735)
			(xy 325.998779 -172.525259) (xy 325.986653 -172.470822) (xy 325.982582 -172.4152) (xy 308.796924 -172.4152)
			(xy 308.670876 -173.101) (xy 334.643982 -173.101) (xy 334.648053 -173.045378) (xy 334.660179 -172.990941)
			(xy 334.680102 -172.93885) (xy 334.707398 -172.890215) (xy 334.741484 -172.846072) (xy 334.781633 -172.807363)
			(xy 334.826991 -172.774912) (xy 334.876591 -172.749411) (xy 334.929375 -172.731404) (xy 334.984218 -172.721274)
			(xy 335.039952 -172.719237) (xy 335.095389 -172.725337) (xy 335.149346 -172.739443) (xy 335.200675 -172.761255)
			(xy 335.248281 -172.790309) (xy 335.291149 -172.825984) (xy 335.328366 -172.867521) (xy 335.359139 -172.914034)
			(xy 335.382811 -172.964531) (xy 335.398879 -173.017938) (xy 335.406999 -173.073114) (xy 335.407313 -173.090332)
			(xy 340.739982 -173.090332) (xy 340.744053 -173.03471) (xy 340.756179 -172.980273) (xy 340.776102 -172.928182)
			(xy 340.803398 -172.879547) (xy 340.837484 -172.835404) (xy 340.877633 -172.796695) (xy 340.922991 -172.764244)
			(xy 340.972591 -172.738743) (xy 341.025375 -172.720736) (xy 341.080218 -172.710606) (xy 341.135952 -172.708569)
			(xy 341.191389 -172.714669) (xy 341.245346 -172.728775) (xy 341.296675 -172.750587) (xy 341.344281 -172.779641)
			(xy 341.387149 -172.815316) (xy 341.424366 -172.856853) (xy 341.455139 -172.903366) (xy 341.478811 -172.953863)
			(xy 341.494879 -173.00727) (xy 341.502999 -173.062446) (xy 341.503355 -173.08195) (xy 351.007932 -173.08195)
			(xy 351.012003 -173.026328) (xy 351.024129 -172.971891) (xy 351.044052 -172.9198) (xy 351.071348 -172.871165)
			(xy 351.105434 -172.827022) (xy 351.145583 -172.788313) (xy 351.190941 -172.755862) (xy 351.240541 -172.730361)
			(xy 351.293325 -172.712354) (xy 351.348168 -172.702224) (xy 351.403902 -172.700187) (xy 351.459339 -172.706287)
			(xy 351.513296 -172.720393) (xy 351.564625 -172.742205) (xy 351.612231 -172.771259) (xy 351.655099 -172.806934)
			(xy 351.692316 -172.848471) (xy 351.723089 -172.894984) (xy 351.746761 -172.945481) (xy 351.755341 -172.974)
			(xy 357.757982 -172.974) (xy 357.762053 -172.918378) (xy 357.774179 -172.863941) (xy 357.794102 -172.81185)
			(xy 357.821398 -172.763215) (xy 357.855484 -172.719072) (xy 357.895633 -172.680363) (xy 357.940991 -172.647912)
			(xy 357.990591 -172.622411) (xy 358.043375 -172.604404) (xy 358.098218 -172.594274) (xy 358.153952 -172.592237)
			(xy 358.209389 -172.598337) (xy 358.263346 -172.612443) (xy 358.314675 -172.634255) (xy 358.362281 -172.663309)
			(xy 358.405149 -172.698984) (xy 358.442366 -172.740521) (xy 358.473139 -172.787034) (xy 358.496811 -172.837531)
			(xy 358.512879 -172.890938) (xy 358.520999 -172.946114) (xy 358.521508 -172.974) (xy 359.789982 -172.974)
			(xy 359.794053 -172.918378) (xy 359.806179 -172.863941) (xy 359.826102 -172.81185) (xy 359.853398 -172.763215)
			(xy 359.887484 -172.719072) (xy 359.927633 -172.680363) (xy 359.972991 -172.647912) (xy 360.022591 -172.622411)
			(xy 360.075375 -172.604404) (xy 360.130218 -172.594274) (xy 360.185952 -172.592237) (xy 360.241389 -172.598337)
			(xy 360.295346 -172.612443) (xy 360.346675 -172.634255) (xy 360.394281 -172.663309) (xy 360.437149 -172.698984)
			(xy 360.474366 -172.740521) (xy 360.505139 -172.787034) (xy 360.528811 -172.837531) (xy 360.544879 -172.890938)
			(xy 360.552999 -172.946114) (xy 360.553508 -172.974) (xy 360.553321 -172.984224) (xy 374.33612 -172.984224)
			(xy 374.336124 -172.92973) (xy 374.343882 -172.87579) (xy 374.359238 -172.823504) (xy 374.381878 -172.773936)
			(xy 374.411341 -172.728093) (xy 374.447029 -172.686911) (xy 374.488214 -172.651226) (xy 374.534058 -172.621765)
			(xy 374.583629 -172.599129) (xy 374.635916 -172.583777) (xy 374.689856 -172.576022) (xy 374.74435 -172.576022)
			(xy 374.798289 -172.583778) (xy 374.850576 -172.59913) (xy 374.900146 -172.621768) (xy 374.94599 -172.651229)
			(xy 374.987175 -172.686914) (xy 375.022862 -172.728098) (xy 375.052325 -172.77394) (xy 375.074964 -172.823509)
			(xy 375.090319 -172.875796) (xy 375.098077 -172.929735) (xy 375.098564 -172.956982) (xy 375.098459 -172.967738)
			(xy 375.097188 -172.989214) (xy 375.096024 -172.999908) (xy 375.094893 -173.013839) (xy 375.099329 -173.041422)
			(xy 375.111086 -173.066764) (xy 375.129282 -173.087963) (xy 375.15255 -173.103426) (xy 375.179142 -173.11199)
			(xy 375.20706 -173.113014) (xy 375.220738 -173.110144) (xy 375.242452 -173.105308) (xy 375.286633 -173.100087)
			(xy 375.308876 -173.09973) (xy 375.309638 -173.09973) (xy 375.336885 -173.100219) (xy 375.390825 -173.107979)
			(xy 375.443111 -173.123337) (xy 375.492679 -173.145979) (xy 375.53852 -173.175444) (xy 375.579702 -173.211134)
			(xy 375.615386 -173.25232) (xy 375.644846 -173.298166) (xy 375.667481 -173.347737) (xy 375.682832 -173.400025)
			(xy 375.690585 -173.453965) (xy 375.690583 -173.50846) (xy 375.682826 -173.5624) (xy 375.667472 -173.614687)
			(xy 375.644833 -173.664257) (xy 375.615371 -173.7101) (xy 375.579684 -173.751284) (xy 375.5385 -173.786971)
			(xy 375.492657 -173.816433) (xy 375.443087 -173.839072) (xy 375.3908 -173.854426) (xy 375.33686 -173.862183)
			(xy 375.282365 -173.862185) (xy 375.228425 -173.854432) (xy 375.176137 -173.839081) (xy 375.126566 -173.816446)
			(xy 375.08072 -173.786986) (xy 375.039534 -173.751302) (xy 375.003844 -173.71012) (xy 374.974379 -173.664279)
			(xy 374.951737 -173.614711) (xy 374.936379 -173.562425) (xy 374.928619 -173.508485) (xy 374.92813 -173.481238)
			(xy 374.928237 -173.470482) (xy 374.929507 -173.449006) (xy 374.93067 -173.438312) (xy 374.931885 -173.424387)
			(xy 374.92743 -173.396798) (xy 374.915656 -173.371454) (xy 374.897446 -173.350255) (xy 374.874167 -173.334794)
			(xy 374.847565 -173.32623) (xy 374.819638 -173.325207) (xy 374.805956 -173.328076) (xy 374.784242 -173.332913)
			(xy 374.740061 -173.338134) (xy 374.717818 -173.33849) (xy 374.717056 -173.33849) (xy 374.689809 -173.337975)
			(xy 374.63587 -173.330213) (xy 374.583585 -173.314855) (xy 374.534017 -173.292212) (xy 374.488177 -173.262746)
			(xy 374.446996 -173.227056) (xy 374.411313 -173.185869) (xy 374.381855 -173.140023) (xy 374.359221 -173.090452)
			(xy 374.343872 -173.038164) (xy 374.33612 -172.984224) (xy 360.553321 -172.984224) (xy 360.552999 -173.001886)
			(xy 360.544879 -173.057062) (xy 360.528811 -173.110469) (xy 360.505139 -173.160966) (xy 360.474366 -173.207479)
			(xy 360.437149 -173.249016) (xy 360.394281 -173.284691) (xy 360.346675 -173.313745) (xy 360.295346 -173.335557)
			(xy 360.241389 -173.349663) (xy 360.185952 -173.355763) (xy 360.130218 -173.353726) (xy 360.075375 -173.343596)
			(xy 360.022591 -173.325589) (xy 359.972991 -173.300088) (xy 359.927633 -173.267637) (xy 359.887484 -173.228928)
			(xy 359.853398 -173.184785) (xy 359.826102 -173.13615) (xy 359.806179 -173.084059) (xy 359.794053 -173.029622)
			(xy 359.789982 -172.974) (xy 358.521508 -172.974) (xy 358.520999 -173.001886) (xy 358.512879 -173.057062)
			(xy 358.496811 -173.110469) (xy 358.473139 -173.160966) (xy 358.442366 -173.207479) (xy 358.405149 -173.249016)
			(xy 358.362281 -173.284691) (xy 358.314675 -173.313745) (xy 358.263346 -173.335557) (xy 358.209389 -173.349663)
			(xy 358.153952 -173.355763) (xy 358.098218 -173.353726) (xy 358.043375 -173.343596) (xy 357.990591 -173.325589)
			(xy 357.940991 -173.300088) (xy 357.895633 -173.267637) (xy 357.855484 -173.228928) (xy 357.821398 -173.184785)
			(xy 357.794102 -173.13615) (xy 357.774179 -173.084059) (xy 357.762053 -173.029622) (xy 357.757982 -172.974)
			(xy 351.755341 -172.974) (xy 351.762829 -172.998888) (xy 351.770949 -173.054064) (xy 351.771458 -173.08195)
			(xy 351.770949 -173.109836) (xy 351.762829 -173.165012) (xy 351.746761 -173.218419) (xy 351.723089 -173.268916)
			(xy 351.692316 -173.315429) (xy 351.655099 -173.356966) (xy 351.612231 -173.392641) (xy 351.564625 -173.421695)
			(xy 351.513296 -173.443507) (xy 351.459339 -173.457613) (xy 351.403902 -173.463713) (xy 351.348168 -173.461676)
			(xy 351.293325 -173.451546) (xy 351.240541 -173.433539) (xy 351.190941 -173.408038) (xy 351.145583 -173.375587)
			(xy 351.105434 -173.336878) (xy 351.071348 -173.292735) (xy 351.044052 -173.2441) (xy 351.024129 -173.192009)
			(xy 351.012003 -173.137572) (xy 351.007932 -173.08195) (xy 341.503355 -173.08195) (xy 341.503508 -173.090332)
			(xy 341.502999 -173.118218) (xy 341.494879 -173.173394) (xy 341.478811 -173.226801) (xy 341.455139 -173.277298)
			(xy 341.424366 -173.323811) (xy 341.387149 -173.365348) (xy 341.344281 -173.401023) (xy 341.296675 -173.430077)
			(xy 341.245346 -173.451889) (xy 341.191389 -173.465995) (xy 341.135952 -173.472095) (xy 341.080218 -173.470058)
			(xy 341.025375 -173.459928) (xy 340.972591 -173.441921) (xy 340.922991 -173.41642) (xy 340.877633 -173.383969)
			(xy 340.837484 -173.34526) (xy 340.803398 -173.301117) (xy 340.776102 -173.252482) (xy 340.756179 -173.200391)
			(xy 340.744053 -173.145954) (xy 340.739982 -173.090332) (xy 335.407313 -173.090332) (xy 335.407508 -173.101)
			(xy 335.406999 -173.128886) (xy 335.398879 -173.184062) (xy 335.382811 -173.237469) (xy 335.359139 -173.287966)
			(xy 335.328366 -173.334479) (xy 335.291149 -173.376016) (xy 335.248281 -173.411691) (xy 335.200675 -173.440745)
			(xy 335.149346 -173.462557) (xy 335.095389 -173.476663) (xy 335.039952 -173.482763) (xy 334.984218 -173.480726)
			(xy 334.929375 -173.470596) (xy 334.876591 -173.452589) (xy 334.826991 -173.427088) (xy 334.781633 -173.394637)
			(xy 334.741484 -173.355928) (xy 334.707398 -173.311785) (xy 334.680102 -173.26315) (xy 334.660179 -173.211059)
			(xy 334.648053 -173.156622) (xy 334.643982 -173.101) (xy 308.670876 -173.101) (xy 308.579935 -173.595792)
			(xy 369.381276 -173.595792) (xy 369.385347 -173.54017) (xy 369.397473 -173.485733) (xy 369.417396 -173.433642)
			(xy 369.444692 -173.385007) (xy 369.478778 -173.340864) (xy 369.518927 -173.302155) (xy 369.564285 -173.269704)
			(xy 369.613885 -173.244203) (xy 369.666669 -173.226196) (xy 369.721512 -173.216066) (xy 369.777246 -173.214029)
			(xy 369.832683 -173.220129) (xy 369.88664 -173.234235) (xy 369.937969 -173.256047) (xy 369.985575 -173.285101)
			(xy 370.028443 -173.320776) (xy 370.06566 -173.362313) (xy 370.096433 -173.408826) (xy 370.120105 -173.459323)
			(xy 370.136173 -173.51273) (xy 370.144293 -173.567906) (xy 370.144802 -173.595792) (xy 370.144394 -173.618144)
			(xy 370.486176 -173.618144) (xy 370.490247 -173.562522) (xy 370.502373 -173.508085) (xy 370.522296 -173.455994)
			(xy 370.549592 -173.407359) (xy 370.583678 -173.363216) (xy 370.623827 -173.324507) (xy 370.669185 -173.292056)
			(xy 370.718785 -173.266555) (xy 370.771569 -173.248548) (xy 370.826412 -173.238418) (xy 370.882146 -173.236381)
			(xy 370.937583 -173.242481) (xy 370.99154 -173.256587) (xy 371.042869 -173.278399) (xy 371.090475 -173.307453)
			(xy 371.133343 -173.343128) (xy 371.17056 -173.384665) (xy 371.201333 -173.431178) (xy 371.225005 -173.481675)
			(xy 371.241073 -173.535082) (xy 371.249193 -173.590258) (xy 371.249702 -173.618144) (xy 371.249193 -173.64603)
			(xy 371.241073 -173.701206) (xy 371.225005 -173.754613) (xy 371.201333 -173.80511) (xy 371.17056 -173.851623)
			(xy 371.133343 -173.89316) (xy 371.090475 -173.928835) (xy 371.042869 -173.957889) (xy 370.99154 -173.979701)
			(xy 370.937583 -173.993807) (xy 370.882146 -173.999907) (xy 370.826412 -173.99787) (xy 370.771569 -173.98774)
			(xy 370.718785 -173.969733) (xy 370.669185 -173.944232) (xy 370.623827 -173.911781) (xy 370.583678 -173.873072)
			(xy 370.549592 -173.828929) (xy 370.522296 -173.780294) (xy 370.502373 -173.728203) (xy 370.490247 -173.673766)
			(xy 370.486176 -173.618144) (xy 370.144394 -173.618144) (xy 370.144293 -173.623678) (xy 370.136173 -173.678854)
			(xy 370.120105 -173.732261) (xy 370.096433 -173.782758) (xy 370.06566 -173.829271) (xy 370.028443 -173.870808)
			(xy 369.985575 -173.906483) (xy 369.937969 -173.935537) (xy 369.88664 -173.957349) (xy 369.832683 -173.971455)
			(xy 369.777246 -173.977555) (xy 369.721512 -173.975518) (xy 369.666669 -173.965388) (xy 369.613885 -173.947381)
			(xy 369.564285 -173.92188) (xy 369.518927 -173.889429) (xy 369.478778 -173.85072) (xy 369.444692 -173.806577)
			(xy 369.417396 -173.757942) (xy 369.397473 -173.705851) (xy 369.385347 -173.651414) (xy 369.381276 -173.595792)
			(xy 308.579935 -173.595792) (xy 308.484138 -174.117) (xy 334.643982 -174.117) (xy 334.648053 -174.061378)
			(xy 334.660179 -174.006941) (xy 334.680102 -173.95485) (xy 334.707398 -173.906215) (xy 334.741484 -173.862072)
			(xy 334.781633 -173.823363) (xy 334.826991 -173.790912) (xy 334.876591 -173.765411) (xy 334.929375 -173.747404)
			(xy 334.984218 -173.737274) (xy 335.039952 -173.735237) (xy 335.095389 -173.741337) (xy 335.149346 -173.755443)
			(xy 335.200675 -173.777255) (xy 335.248281 -173.806309) (xy 335.291149 -173.841984) (xy 335.328366 -173.883521)
			(xy 335.359139 -173.930034) (xy 335.382811 -173.980531) (xy 335.398879 -174.033938) (xy 335.406999 -174.089114)
			(xy 335.407508 -174.117) (xy 336.675982 -174.117) (xy 336.680053 -174.061378) (xy 336.692179 -174.006941)
			(xy 336.712102 -173.95485) (xy 336.739398 -173.906215) (xy 336.773484 -173.862072) (xy 336.813633 -173.823363)
			(xy 336.858991 -173.790912) (xy 336.908591 -173.765411) (xy 336.961375 -173.747404) (xy 337.016218 -173.737274)
			(xy 337.071952 -173.735237) (xy 337.127389 -173.741337) (xy 337.181346 -173.755443) (xy 337.232675 -173.777255)
			(xy 337.280281 -173.806309) (xy 337.323149 -173.841984) (xy 337.360366 -173.883521) (xy 337.391139 -173.930034)
			(xy 337.414811 -173.980531) (xy 337.430879 -174.033938) (xy 337.438999 -174.089114) (xy 337.439508 -174.117)
			(xy 338.707982 -174.117) (xy 338.712053 -174.061378) (xy 338.724179 -174.006941) (xy 338.744102 -173.95485)
			(xy 338.771398 -173.906215) (xy 338.805484 -173.862072) (xy 338.845633 -173.823363) (xy 338.890991 -173.790912)
			(xy 338.940591 -173.765411) (xy 338.993375 -173.747404) (xy 339.048218 -173.737274) (xy 339.103952 -173.735237)
			(xy 339.159389 -173.741337) (xy 339.213346 -173.755443) (xy 339.264675 -173.777255) (xy 339.312281 -173.806309)
			(xy 339.355149 -173.841984) (xy 339.392366 -173.883521) (xy 339.423139 -173.930034) (xy 339.446811 -173.980531)
			(xy 339.462879 -174.033938) (xy 339.470999 -174.089114) (xy 339.471508 -174.117) (xy 339.470999 -174.144886)
			(xy 339.462879 -174.200062) (xy 339.446811 -174.253469) (xy 339.423139 -174.303966) (xy 339.421977 -174.305722)
			(xy 340.053928 -174.305722) (xy 340.057999 -174.2501) (xy 340.070125 -174.195663) (xy 340.090048 -174.143572)
			(xy 340.117344 -174.094937) (xy 340.15143 -174.050794) (xy 340.191579 -174.012085) (xy 340.236937 -173.979634)
			(xy 340.286537 -173.954133) (xy 340.339321 -173.936126) (xy 340.394164 -173.925996) (xy 340.449898 -173.923959)
			(xy 340.505335 -173.930059) (xy 340.559292 -173.944165) (xy 340.610621 -173.965977) (xy 340.649984 -173.99)
			(xy 357.757982 -173.99) (xy 357.762053 -173.934378) (xy 357.774179 -173.879941) (xy 357.794102 -173.82785)
			(xy 357.821398 -173.779215) (xy 357.855484 -173.735072) (xy 357.895633 -173.696363) (xy 357.940991 -173.663912)
			(xy 357.990591 -173.638411) (xy 358.043375 -173.620404) (xy 358.098218 -173.610274) (xy 358.153952 -173.608237)
			(xy 358.209389 -173.614337) (xy 358.263346 -173.628443) (xy 358.314675 -173.650255) (xy 358.362281 -173.679309)
			(xy 358.405149 -173.714984) (xy 358.442366 -173.756521) (xy 358.473139 -173.803034) (xy 358.496811 -173.853531)
			(xy 358.512879 -173.906938) (xy 358.520999 -173.962114) (xy 358.521508 -173.99) (xy 359.789982 -173.99)
			(xy 359.794053 -173.934378) (xy 359.806179 -173.879941) (xy 359.826102 -173.82785) (xy 359.853398 -173.779215)
			(xy 359.887484 -173.735072) (xy 359.927633 -173.696363) (xy 359.972991 -173.663912) (xy 360.022591 -173.638411)
			(xy 360.075375 -173.620404) (xy 360.130218 -173.610274) (xy 360.185952 -173.608237) (xy 360.241389 -173.614337)
			(xy 360.295346 -173.628443) (xy 360.346675 -173.650255) (xy 360.394281 -173.679309) (xy 360.437149 -173.714984)
			(xy 360.474366 -173.756521) (xy 360.505139 -173.803034) (xy 360.528811 -173.853531) (xy 360.544879 -173.906938)
			(xy 360.552999 -173.962114) (xy 360.553508 -173.99) (xy 362.583982 -173.99) (xy 362.588053 -173.934378)
			(xy 362.600179 -173.879941) (xy 362.620102 -173.82785) (xy 362.647398 -173.779215) (xy 362.681484 -173.735072)
			(xy 362.721633 -173.696363) (xy 362.766991 -173.663912) (xy 362.816591 -173.638411) (xy 362.869375 -173.620404)
			(xy 362.924218 -173.610274) (xy 362.979952 -173.608237) (xy 363.035389 -173.614337) (xy 363.089346 -173.628443)
			(xy 363.140675 -173.650255) (xy 363.188281 -173.679309) (xy 363.231149 -173.714984) (xy 363.268366 -173.756521)
			(xy 363.299139 -173.803034) (xy 363.322811 -173.853531) (xy 363.338879 -173.906938) (xy 363.346999 -173.962114)
			(xy 363.347508 -173.99) (xy 363.346999 -174.017886) (xy 363.34187 -174.052738) (xy 374.195084 -174.052738)
			(xy 374.199155 -173.997116) (xy 374.211281 -173.942679) (xy 374.231204 -173.890588) (xy 374.2585 -173.841953)
			(xy 374.292586 -173.79781) (xy 374.332735 -173.759101) (xy 374.378093 -173.72665) (xy 374.427693 -173.701149)
			(xy 374.480477 -173.683142) (xy 374.53532 -173.673012) (xy 374.591054 -173.670975) (xy 374.646491 -173.677075)
			(xy 374.700448 -173.691181) (xy 374.751777 -173.712993) (xy 374.799383 -173.742047) (xy 374.842251 -173.777722)
			(xy 374.879468 -173.819259) (xy 374.910241 -173.865772) (xy 374.933913 -173.916269) (xy 374.949981 -173.969676)
			(xy 374.958101 -174.024852) (xy 374.95861 -174.052738) (xy 374.958101 -174.080624) (xy 374.949981 -174.1358)
			(xy 374.933913 -174.189207) (xy 374.910241 -174.239704) (xy 374.879468 -174.286217) (xy 374.842251 -174.327754)
			(xy 374.799383 -174.363429) (xy 374.751777 -174.392483) (xy 374.700448 -174.414295) (xy 374.646491 -174.428401)
			(xy 374.591054 -174.434501) (xy 374.53532 -174.432464) (xy 374.480477 -174.422334) (xy 374.427693 -174.404327)
			(xy 374.378093 -174.378826) (xy 374.332735 -174.346375) (xy 374.292586 -174.307666) (xy 374.2585 -174.263523)
			(xy 374.231204 -174.214888) (xy 374.211281 -174.162797) (xy 374.199155 -174.10836) (xy 374.195084 -174.052738)
			(xy 363.34187 -174.052738) (xy 363.338879 -174.073062) (xy 363.322811 -174.126469) (xy 363.299139 -174.176966)
			(xy 363.268366 -174.223479) (xy 363.231149 -174.265016) (xy 363.188281 -174.300691) (xy 363.140675 -174.329745)
			(xy 363.089346 -174.351557) (xy 363.035389 -174.365663) (xy 362.979952 -174.371763) (xy 362.924218 -174.369726)
			(xy 362.869375 -174.359596) (xy 362.816591 -174.341589) (xy 362.766991 -174.316088) (xy 362.721633 -174.283637)
			(xy 362.681484 -174.244928) (xy 362.647398 -174.200785) (xy 362.620102 -174.15215) (xy 362.600179 -174.100059)
			(xy 362.588053 -174.045622) (xy 362.583982 -173.99) (xy 360.553508 -173.99) (xy 360.552999 -174.017886)
			(xy 360.544879 -174.073062) (xy 360.528811 -174.126469) (xy 360.505139 -174.176966) (xy 360.474366 -174.223479)
			(xy 360.437149 -174.265016) (xy 360.394281 -174.300691) (xy 360.346675 -174.329745) (xy 360.295346 -174.351557)
			(xy 360.241389 -174.365663) (xy 360.185952 -174.371763) (xy 360.130218 -174.369726) (xy 360.075375 -174.359596)
			(xy 360.022591 -174.341589) (xy 359.972991 -174.316088) (xy 359.927633 -174.283637) (xy 359.887484 -174.244928)
			(xy 359.853398 -174.200785) (xy 359.826102 -174.15215) (xy 359.806179 -174.100059) (xy 359.794053 -174.045622)
			(xy 359.789982 -173.99) (xy 358.521508 -173.99) (xy 358.520999 -174.017886) (xy 358.512879 -174.073062)
			(xy 358.496811 -174.126469) (xy 358.473139 -174.176966) (xy 358.442366 -174.223479) (xy 358.405149 -174.265016)
			(xy 358.362281 -174.300691) (xy 358.314675 -174.329745) (xy 358.263346 -174.351557) (xy 358.209389 -174.365663)
			(xy 358.153952 -174.371763) (xy 358.098218 -174.369726) (xy 358.043375 -174.359596) (xy 357.990591 -174.341589)
			(xy 357.940991 -174.316088) (xy 357.895633 -174.283637) (xy 357.855484 -174.244928) (xy 357.821398 -174.200785)
			(xy 357.794102 -174.15215) (xy 357.774179 -174.100059) (xy 357.762053 -174.045622) (xy 357.757982 -173.99)
			(xy 340.649984 -173.99) (xy 340.658227 -173.995031) (xy 340.701095 -174.030706) (xy 340.738312 -174.072243)
			(xy 340.769085 -174.118756) (xy 340.792757 -174.169253) (xy 340.808825 -174.22266) (xy 340.816945 -174.277836)
			(xy 340.817454 -174.305722) (xy 340.816945 -174.333608) (xy 340.808825 -174.388784) (xy 340.792757 -174.442191)
			(xy 340.769085 -174.492688) (xy 340.758345 -174.508922) (xy 342.753948 -174.508922) (xy 342.758019 -174.4533)
			(xy 342.770145 -174.398863) (xy 342.790068 -174.346772) (xy 342.817364 -174.298137) (xy 342.85145 -174.253994)
			(xy 342.891599 -174.215285) (xy 342.936957 -174.182834) (xy 342.986557 -174.157333) (xy 343.039341 -174.139326)
			(xy 343.094184 -174.129196) (xy 343.149918 -174.127159) (xy 343.205355 -174.133259) (xy 343.259312 -174.147365)
			(xy 343.310641 -174.169177) (xy 343.358247 -174.198231) (xy 343.401115 -174.233906) (xy 343.438332 -174.275443)
			(xy 343.469105 -174.321956) (xy 343.492777 -174.372453) (xy 343.508845 -174.42586) (xy 343.516965 -174.481036)
			(xy 343.517238 -174.495968) (xy 364.803434 -174.495968) (xy 364.807505 -174.440346) (xy 364.819631 -174.385909)
			(xy 364.839554 -174.333818) (xy 364.86685 -174.285183) (xy 364.900936 -174.24104) (xy 364.941085 -174.202331)
			(xy 364.986443 -174.16988) (xy 365.036043 -174.144379) (xy 365.088827 -174.126372) (xy 365.14367 -174.116242)
			(xy 365.199404 -174.114205) (xy 365.254841 -174.120305) (xy 365.308798 -174.134411) (xy 365.360127 -174.156223)
			(xy 365.407733 -174.185277) (xy 365.450601 -174.220952) (xy 365.487818 -174.262489) (xy 365.518591 -174.309002)
			(xy 365.542263 -174.359499) (xy 365.558331 -174.412906) (xy 365.566451 -174.468082) (xy 365.56696 -174.495968)
			(xy 365.566451 -174.523854) (xy 365.558331 -174.57903) (xy 365.542263 -174.632437) (xy 365.518591 -174.682934)
			(xy 365.487818 -174.729447) (xy 365.450601 -174.770984) (xy 365.407733 -174.806659) (xy 365.360127 -174.835713)
			(xy 365.308798 -174.857525) (xy 365.254841 -174.871631) (xy 365.199404 -174.877731) (xy 365.14367 -174.875694)
			(xy 365.088827 -174.865564) (xy 365.036043 -174.847557) (xy 364.986443 -174.822056) (xy 364.941085 -174.789605)
			(xy 364.900936 -174.750896) (xy 364.86685 -174.706753) (xy 364.839554 -174.658118) (xy 364.819631 -174.606027)
			(xy 364.807505 -174.55159) (xy 364.803434 -174.495968) (xy 343.517238 -174.495968) (xy 343.517474 -174.508922)
			(xy 343.516965 -174.536808) (xy 343.508845 -174.591984) (xy 343.492777 -174.645391) (xy 343.469105 -174.695888)
			(xy 343.438332 -174.742401) (xy 343.401115 -174.783938) (xy 343.358247 -174.819613) (xy 343.310641 -174.848667)
			(xy 343.259312 -174.870479) (xy 343.205355 -174.884585) (xy 343.149918 -174.890685) (xy 343.094184 -174.888648)
			(xy 343.039341 -174.878518) (xy 342.986557 -174.860511) (xy 342.936957 -174.83501) (xy 342.891599 -174.802559)
			(xy 342.85145 -174.76385) (xy 342.817364 -174.719707) (xy 342.790068 -174.671072) (xy 342.770145 -174.618981)
			(xy 342.758019 -174.564544) (xy 342.753948 -174.508922) (xy 340.758345 -174.508922) (xy 340.738312 -174.539201)
			(xy 340.701095 -174.580738) (xy 340.658227 -174.616413) (xy 340.610621 -174.645467) (xy 340.559292 -174.667279)
			(xy 340.505335 -174.681385) (xy 340.449898 -174.687485) (xy 340.394164 -174.685448) (xy 340.339321 -174.675318)
			(xy 340.286537 -174.657311) (xy 340.236937 -174.63181) (xy 340.191579 -174.599359) (xy 340.15143 -174.56065)
			(xy 340.117344 -174.516507) (xy 340.090048 -174.467872) (xy 340.070125 -174.415781) (xy 340.057999 -174.361344)
			(xy 340.053928 -174.305722) (xy 339.421977 -174.305722) (xy 339.392366 -174.350479) (xy 339.355149 -174.392016)
			(xy 339.312281 -174.427691) (xy 339.264675 -174.456745) (xy 339.213346 -174.478557) (xy 339.159389 -174.492663)
			(xy 339.103952 -174.498763) (xy 339.048218 -174.496726) (xy 338.993375 -174.486596) (xy 338.940591 -174.468589)
			(xy 338.890991 -174.443088) (xy 338.845633 -174.410637) (xy 338.805484 -174.371928) (xy 338.771398 -174.327785)
			(xy 338.744102 -174.27915) (xy 338.724179 -174.227059) (xy 338.712053 -174.172622) (xy 338.707982 -174.117)
			(xy 337.439508 -174.117) (xy 337.438999 -174.144886) (xy 337.430879 -174.200062) (xy 337.414811 -174.253469)
			(xy 337.391139 -174.303966) (xy 337.360366 -174.350479) (xy 337.323149 -174.392016) (xy 337.280281 -174.427691)
			(xy 337.232675 -174.456745) (xy 337.181346 -174.478557) (xy 337.127389 -174.492663) (xy 337.071952 -174.498763)
			(xy 337.016218 -174.496726) (xy 336.961375 -174.486596) (xy 336.908591 -174.468589) (xy 336.858991 -174.443088)
			(xy 336.813633 -174.410637) (xy 336.773484 -174.371928) (xy 336.739398 -174.327785) (xy 336.712102 -174.27915)
			(xy 336.692179 -174.227059) (xy 336.680053 -174.172622) (xy 336.675982 -174.117) (xy 335.407508 -174.117)
			(xy 335.406999 -174.144886) (xy 335.398879 -174.200062) (xy 335.382811 -174.253469) (xy 335.359139 -174.303966)
			(xy 335.328366 -174.350479) (xy 335.291149 -174.392016) (xy 335.248281 -174.427691) (xy 335.200675 -174.456745)
			(xy 335.149346 -174.478557) (xy 335.095389 -174.492663) (xy 335.039952 -174.498763) (xy 334.984218 -174.496726)
			(xy 334.929375 -174.486596) (xy 334.876591 -174.468589) (xy 334.826991 -174.443088) (xy 334.781633 -174.410637)
			(xy 334.741484 -174.371928) (xy 334.707398 -174.327785) (xy 334.680102 -174.27915) (xy 334.660179 -174.227059)
			(xy 334.648053 -174.172622) (xy 334.643982 -174.117) (xy 308.484138 -174.117) (xy 308.320742 -175.006)
			(xy 359.789982 -175.006) (xy 359.794053 -174.950378) (xy 359.806179 -174.895941) (xy 359.826102 -174.84385)
			(xy 359.853398 -174.795215) (xy 359.887484 -174.751072) (xy 359.927633 -174.712363) (xy 359.972991 -174.679912)
			(xy 360.022591 -174.654411) (xy 360.075375 -174.636404) (xy 360.130218 -174.626274) (xy 360.185952 -174.624237)
			(xy 360.241389 -174.630337) (xy 360.295346 -174.644443) (xy 360.346675 -174.666255) (xy 360.394281 -174.695309)
			(xy 360.437149 -174.730984) (xy 360.474366 -174.772521) (xy 360.505139 -174.819034) (xy 360.528811 -174.869531)
			(xy 360.544879 -174.922938) (xy 360.552999 -174.978114) (xy 360.553508 -175.006) (xy 360.552999 -175.033886)
			(xy 360.544879 -175.089062) (xy 360.528811 -175.142469) (xy 360.505139 -175.192966) (xy 360.474366 -175.239479)
			(xy 360.437149 -175.281016) (xy 360.394281 -175.316691) (xy 360.346675 -175.345745) (xy 360.295346 -175.367557)
			(xy 360.241389 -175.381663) (xy 360.185952 -175.387763) (xy 360.130218 -175.385726) (xy 360.075375 -175.375596)
			(xy 360.022591 -175.357589) (xy 359.972991 -175.332088) (xy 359.927633 -175.299637) (xy 359.887484 -175.260928)
			(xy 359.853398 -175.216785) (xy 359.826102 -175.16815) (xy 359.806179 -175.116059) (xy 359.794053 -175.061622)
			(xy 359.789982 -175.006) (xy 308.320742 -175.006) (xy 308.221771 -175.54448) (xy 361.798868 -175.54448)
			(xy 361.802939 -175.488858) (xy 361.815065 -175.434421) (xy 361.834988 -175.38233) (xy 361.862284 -175.333695)
			(xy 361.89637 -175.289552) (xy 361.936519 -175.250843) (xy 361.981877 -175.218392) (xy 362.031477 -175.192891)
			(xy 362.084261 -175.174884) (xy 362.139104 -175.164754) (xy 362.194838 -175.162717) (xy 362.250275 -175.168817)
			(xy 362.304232 -175.182923) (xy 362.355561 -175.204735) (xy 362.403167 -175.233789) (xy 362.446035 -175.269464)
			(xy 362.483252 -175.311001) (xy 362.514025 -175.357514) (xy 362.537697 -175.408011) (xy 362.553765 -175.461418)
			(xy 362.561885 -175.516594) (xy 362.562394 -175.54448) (xy 362.561885 -175.572366) (xy 362.553765 -175.627542)
			(xy 362.537697 -175.680949) (xy 362.514025 -175.731446) (xy 362.483252 -175.777959) (xy 362.446035 -175.819496)
			(xy 362.403167 -175.855171) (xy 362.355561 -175.884225) (xy 362.304232 -175.906037) (xy 362.250275 -175.920143)
			(xy 362.194838 -175.926243) (xy 362.139104 -175.924206) (xy 362.084261 -175.914076) (xy 362.031477 -175.896069)
			(xy 361.981877 -175.870568) (xy 361.936519 -175.838117) (xy 361.89637 -175.799408) (xy 361.862284 -175.755265)
			(xy 361.834988 -175.70663) (xy 361.815065 -175.654539) (xy 361.802939 -175.600102) (xy 361.798868 -175.54448)
			(xy 308.221771 -175.54448) (xy 308.14997 -175.935132) (xy 363.717838 -175.935132) (xy 363.721909 -175.87951)
			(xy 363.734035 -175.825073) (xy 363.753958 -175.772982) (xy 363.781254 -175.724347) (xy 363.81534 -175.680204)
			(xy 363.855489 -175.641495) (xy 363.900847 -175.609044) (xy 363.950447 -175.583543) (xy 364.003231 -175.565536)
			(xy 364.058074 -175.555406) (xy 364.113808 -175.553369) (xy 364.169245 -175.559469) (xy 364.223202 -175.573575)
			(xy 364.274531 -175.595387) (xy 364.322137 -175.624441) (xy 364.358553 -175.654747) (xy 374.724716 -175.654747)
			(xy 374.724716 -175.600253) (xy 374.732471 -175.546312) (xy 374.747824 -175.494025) (xy 374.770461 -175.444454)
			(xy 374.799922 -175.39861) (xy 374.835607 -175.357424) (xy 374.87679 -175.321736) (xy 374.922633 -175.292272)
			(xy 374.972202 -175.269632) (xy 375.024489 -175.254276) (xy 375.078429 -175.246518) (xy 375.105676 -175.24603)
			(xy 375.133537 -175.246555) (xy 375.188664 -175.254693) (xy 375.242026 -175.270743) (xy 375.267474 -175.282098)
			(xy 375.279666 -175.287686) (xy 375.306082 -175.285908) (xy 375.389648 -175.229774) (xy 375.396643 -175.224609)
			(xy 375.406972 -175.210638) (xy 375.412039 -175.194018) (xy 375.412 -175.185324) (xy 375.412 -175.184816)
			(xy 375.411492 -175.16602) (xy 375.411933 -175.138765) (xy 375.419688 -175.084811) (xy 375.435043 -175.032509)
			(xy 375.457684 -174.982924) (xy 375.487152 -174.937067) (xy 375.522846 -174.89587) (xy 375.56404 -174.860172)
			(xy 375.609895 -174.8307) (xy 375.659477 -174.808054) (xy 375.711778 -174.792695) (xy 375.765732 -174.784936)
			(xy 375.820241 -174.784934) (xy 375.874196 -174.79269) (xy 375.926498 -174.808045) (xy 375.976082 -174.830687)
			(xy 376.021939 -174.860156) (xy 376.063135 -174.895851) (xy 376.098832 -174.937045) (xy 376.128303 -174.982901)
			(xy 376.150948 -175.032484) (xy 376.166306 -175.084784) (xy 376.174065 -175.138739) (xy 376.174066 -175.193248)
			(xy 376.166309 -175.247202) (xy 376.150953 -175.299504) (xy 376.128309 -175.349088) (xy 376.09884 -175.394944)
			(xy 376.063144 -175.43614) (xy 376.021949 -175.471836) (xy 375.976093 -175.501306) (xy 375.92651 -175.52395)
			(xy 375.874209 -175.539308) (xy 375.820255 -175.547065) (xy 375.793 -175.547528) (xy 375.765138 -175.547015)
			(xy 375.710011 -175.538873) (xy 375.656649 -175.522818) (xy 375.631202 -175.51146) (xy 375.61901 -175.505872)
			(xy 375.592594 -175.50765) (xy 375.509028 -175.563784) (xy 375.502049 -175.568968) (xy 375.491718 -175.582931)
			(xy 375.486643 -175.599542) (xy 375.486676 -175.608234) (xy 375.486676 -175.608742) (xy 375.487184 -175.627538)
			(xy 375.486951 -175.647368) (xy 375.482875 -175.686818) (xy 375.479056 -175.706278) (xy 375.476008 -175.71974)
			(xy 375.484898 -175.745902) (xy 375.572528 -175.82261) (xy 375.599706 -175.827436) (xy 375.61266 -175.822864)
			(xy 375.643764 -175.812443) (xy 375.708388 -175.801213) (xy 375.741184 -175.800512) (xy 375.741438 -175.800512)
			(xy 375.768686 -175.801019) (xy 375.822625 -175.808779) (xy 375.874912 -175.824137) (xy 375.92448 -175.84678)
			(xy 375.970322 -175.876246) (xy 376.011504 -175.911936) (xy 376.047188 -175.953123) (xy 376.076648 -175.998969)
			(xy 376.099283 -176.048541) (xy 376.114633 -176.10083) (xy 376.122385 -176.154771) (xy 376.122383 -176.209266)
			(xy 376.114625 -176.263206) (xy 376.09927 -176.315494) (xy 376.07663 -176.365064) (xy 376.047166 -176.410907)
			(xy 376.011478 -176.452091) (xy 375.970292 -176.487777) (xy 375.924448 -176.517238) (xy 375.874877 -176.539876)
			(xy 375.822589 -176.555229) (xy 375.768648 -176.562984) (xy 375.714153 -176.562984) (xy 375.660212 -176.555229)
			(xy 375.607924 -176.539876) (xy 375.558353 -176.517239) (xy 375.512509 -176.487777) (xy 375.471323 -176.452092)
			(xy 375.435635 -176.410908) (xy 375.406171 -176.365065) (xy 375.383531 -176.315495) (xy 375.368176 -176.263208)
			(xy 375.360418 -176.209268) (xy 375.35993 -176.18202) (xy 375.35993 -176.181258) (xy 375.360209 -176.16162)
			(xy 375.36428 -176.122554) (xy 375.368058 -176.10328) (xy 375.371106 -176.089818) (xy 375.362216 -176.063656)
			(xy 375.274586 -175.986948) (xy 375.247408 -175.982122) (xy 375.234454 -175.986694) (xy 375.203349 -175.99711)
			(xy 375.138726 -176.008344) (xy 375.10593 -176.009046) (xy 375.105676 -176.009046) (xy 375.078429 -176.008482)
			(xy 375.024489 -176.000724) (xy 374.972202 -175.985368) (xy 374.922633 -175.962728) (xy 374.87679 -175.933264)
			(xy 374.835607 -175.897576) (xy 374.799922 -175.85639) (xy 374.770461 -175.810546) (xy 374.747824 -175.760975)
			(xy 374.732471 -175.708688) (xy 374.724716 -175.654747) (xy 364.358553 -175.654747) (xy 364.365005 -175.660116)
			(xy 364.402222 -175.701653) (xy 364.432995 -175.748166) (xy 364.456667 -175.798663) (xy 364.472735 -175.85207)
			(xy 364.480855 -175.907246) (xy 364.481364 -175.935132) (xy 364.480855 -175.963018) (xy 364.472735 -176.018194)
			(xy 364.456667 -176.071601) (xy 364.432995 -176.122098) (xy 364.402222 -176.168611) (xy 364.365005 -176.210148)
			(xy 364.322137 -176.245823) (xy 364.274531 -176.274877) (xy 364.223202 -176.296689) (xy 364.169245 -176.310795)
			(xy 364.113808 -176.316895) (xy 364.058074 -176.314858) (xy 364.003231 -176.304728) (xy 363.950447 -176.286721)
			(xy 363.900847 -176.26122) (xy 363.855489 -176.228769) (xy 363.81534 -176.19006) (xy 363.781254 -176.145917)
			(xy 363.753958 -176.097282) (xy 363.734035 -176.045191) (xy 363.721909 -175.990754) (xy 363.717838 -175.935132)
			(xy 308.14997 -175.935132) (xy 307.970608 -176.911) (xy 334.643982 -176.911) (xy 334.648053 -176.855378)
			(xy 334.660179 -176.800941) (xy 334.680102 -176.74885) (xy 334.707398 -176.700215) (xy 334.741484 -176.656072)
			(xy 334.781633 -176.617363) (xy 334.826991 -176.584912) (xy 334.876591 -176.559411) (xy 334.929375 -176.541404)
			(xy 334.984218 -176.531274) (xy 335.039952 -176.529237) (xy 335.095389 -176.535337) (xy 335.149346 -176.549443)
			(xy 335.200675 -176.571255) (xy 335.248281 -176.600309) (xy 335.291149 -176.635984) (xy 335.309979 -176.657)
			(xy 336.675982 -176.657) (xy 336.680053 -176.601378) (xy 336.692179 -176.546941) (xy 336.712102 -176.49485)
			(xy 336.739398 -176.446215) (xy 336.773484 -176.402072) (xy 336.813633 -176.363363) (xy 336.858991 -176.330912)
			(xy 336.908591 -176.305411) (xy 336.961375 -176.287404) (xy 337.016218 -176.277274) (xy 337.071952 -176.275237)
			(xy 337.127389 -176.281337) (xy 337.181346 -176.295443) (xy 337.232675 -176.317255) (xy 337.280281 -176.346309)
			(xy 337.323149 -176.381984) (xy 337.360366 -176.423521) (xy 337.391139 -176.470034) (xy 337.414811 -176.520531)
			(xy 337.430879 -176.573938) (xy 337.438999 -176.629114) (xy 337.439508 -176.657) (xy 337.438999 -176.684886)
			(xy 337.430879 -176.740062) (xy 337.414811 -176.793469) (xy 337.391139 -176.843966) (xy 337.360366 -176.890479)
			(xy 337.323149 -176.932016) (xy 337.280281 -176.967691) (xy 337.250396 -176.98593) (xy 349.735392 -176.98593)
			(xy 349.739463 -176.930308) (xy 349.751589 -176.875871) (xy 349.771512 -176.82378) (xy 349.798808 -176.775145)
			(xy 349.832894 -176.731002) (xy 349.873043 -176.692293) (xy 349.918401 -176.659842) (xy 349.968001 -176.634341)
			(xy 350.020785 -176.616334) (xy 350.075628 -176.606204) (xy 350.131362 -176.604167) (xy 350.186799 -176.610267)
			(xy 350.240756 -176.624373) (xy 350.292085 -176.646185) (xy 350.339691 -176.675239) (xy 350.382559 -176.710914)
			(xy 350.419776 -176.752451) (xy 350.450549 -176.798964) (xy 350.474221 -176.849461) (xy 350.490289 -176.902868)
			(xy 350.498409 -176.958044) (xy 350.498918 -176.98593) (xy 350.498409 -177.013816) (xy 350.49485 -177.038)
			(xy 357.757982 -177.038) (xy 357.762053 -176.982378) (xy 357.774179 -176.927941) (xy 357.794102 -176.87585)
			(xy 357.821398 -176.827215) (xy 357.855484 -176.783072) (xy 357.895633 -176.744363) (xy 357.940991 -176.711912)
			(xy 357.990591 -176.686411) (xy 358.043375 -176.668404) (xy 358.098218 -176.658274) (xy 358.153952 -176.656237)
			(xy 358.209389 -176.662337) (xy 358.263346 -176.676443) (xy 358.314675 -176.698255) (xy 358.362281 -176.727309)
			(xy 358.405149 -176.762984) (xy 358.423979 -176.784) (xy 359.789982 -176.784) (xy 359.794053 -176.728378)
			(xy 359.806179 -176.673941) (xy 359.826102 -176.62185) (xy 359.853398 -176.573215) (xy 359.887484 -176.529072)
			(xy 359.927633 -176.490363) (xy 359.972991 -176.457912) (xy 360.022591 -176.432411) (xy 360.075375 -176.414404)
			(xy 360.130218 -176.404274) (xy 360.185952 -176.402237) (xy 360.191577 -176.402856) (xy 367.662623 -176.402856)
			(xy 367.662623 -176.348344) (xy 367.670381 -176.294387) (xy 367.685739 -176.242084) (xy 367.708384 -176.192499)
			(xy 367.737856 -176.146641) (xy 367.773554 -176.105445) (xy 367.814752 -176.069748) (xy 367.860611 -176.040278)
			(xy 367.910197 -176.017634) (xy 367.962501 -176.002278) (xy 368.016458 -175.994522) (xy 368.043714 -175.99406)
			(xy 368.072036 -175.994596) (xy 368.128055 -176.002983) (xy 368.18222 -176.019556) (xy 368.233342 -176.043952)
			(xy 368.280297 -176.075634) (xy 368.301524 -176.09439) (xy 368.311723 -176.103125) (xy 368.335572 -176.115449)
			(xy 368.361805 -176.121144) (xy 368.388616 -176.119817) (xy 368.414159 -176.111561) (xy 368.436675 -176.096944)
			(xy 368.454612 -176.076972) (xy 368.461036 -176.06518) (xy 368.473209 -176.041786) (xy 368.503134 -175.99836)
			(xy 368.538758 -175.959473) (xy 368.5794 -175.925865) (xy 368.624286 -175.898179) (xy 368.672559 -175.876942)
			(xy 368.723298 -175.86256) (xy 368.775535 -175.855307) (xy 368.801904 -175.854868) (xy 368.829153 -175.855402)
			(xy 368.883097 -175.863159) (xy 368.935388 -175.878513) (xy 368.984962 -175.901153) (xy 369.030809 -175.930618)
			(xy 369.071996 -175.966307) (xy 369.107685 -176.007495) (xy 369.137149 -176.053342) (xy 369.159788 -176.102916)
			(xy 369.175142 -176.155207) (xy 369.182898 -176.209151) (xy 369.182898 -176.263649) (xy 369.175142 -176.317593)
			(xy 369.159788 -176.369884) (xy 369.137149 -176.419458) (xy 369.107685 -176.465305) (xy 369.071996 -176.506493)
			(xy 369.030809 -176.542182) (xy 368.984962 -176.571647) (xy 368.935388 -176.594287) (xy 368.883097 -176.609641)
			(xy 368.829153 -176.617398) (xy 368.801904 -176.617884) (xy 368.773582 -176.617352) (xy 368.717562 -176.608966)
			(xy 368.663396 -176.592393) (xy 368.612275 -176.567996) (xy 368.56532 -176.536312) (xy 368.544094 -176.517554)
			(xy 368.533887 -176.508826) (xy 368.510042 -176.496494) (xy 368.483809 -176.490793) (xy 368.456996 -176.492117)
			(xy 368.431452 -176.500373) (xy 368.408937 -176.514994) (xy 368.391003 -176.53497) (xy 368.384582 -176.546764)
			(xy 368.372372 -176.570138) (xy 368.342454 -176.613565) (xy 368.306837 -176.652455) (xy 368.2662 -176.686066)
			(xy 368.221319 -176.713755) (xy 368.173051 -176.734995) (xy 368.122315 -176.74938) (xy 368.070082 -176.756636)
			(xy 368.043714 -176.757076) (xy 368.016458 -176.756678) (xy 367.962501 -176.748922) (xy 367.910197 -176.733566)
			(xy 367.860611 -176.710922) (xy 367.814752 -176.681452) (xy 367.773554 -176.645755) (xy 367.737856 -176.604559)
			(xy 367.708384 -176.558701) (xy 367.685739 -176.509116) (xy 367.670381 -176.456813) (xy 367.662623 -176.402856)
			(xy 360.191577 -176.402856) (xy 360.241389 -176.408337) (xy 360.295346 -176.422443) (xy 360.346675 -176.444255)
			(xy 360.394281 -176.473309) (xy 360.437149 -176.508984) (xy 360.474366 -176.550521) (xy 360.505139 -176.597034)
			(xy 360.528811 -176.647531) (xy 360.544879 -176.700938) (xy 360.552999 -176.756114) (xy 360.553508 -176.784)
			(xy 360.552999 -176.811886) (xy 360.544879 -176.867062) (xy 360.528811 -176.920469) (xy 360.505139 -176.970966)
			(xy 360.474366 -177.017479) (xy 360.437149 -177.059016) (xy 360.394281 -177.094691) (xy 360.346675 -177.123745)
			(xy 360.295346 -177.145557) (xy 360.241389 -177.159663) (xy 360.185952 -177.165763) (xy 360.130218 -177.163726)
			(xy 360.075375 -177.153596) (xy 360.022591 -177.135589) (xy 359.972991 -177.110088) (xy 359.927633 -177.077637)
			(xy 359.887484 -177.038928) (xy 359.853398 -176.994785) (xy 359.826102 -176.94615) (xy 359.806179 -176.894059)
			(xy 359.794053 -176.839622) (xy 359.789982 -176.784) (xy 358.423979 -176.784) (xy 358.442366 -176.804521)
			(xy 358.473139 -176.851034) (xy 358.496811 -176.901531) (xy 358.512879 -176.954938) (xy 358.520999 -177.010114)
			(xy 358.521508 -177.038) (xy 358.520999 -177.065886) (xy 358.512879 -177.121062) (xy 358.496811 -177.174469)
			(xy 358.485771 -177.19802) (xy 375.410982 -177.19802) (xy 375.415053 -177.142398) (xy 375.427179 -177.087961)
			(xy 375.447102 -177.03587) (xy 375.474398 -176.987235) (xy 375.508484 -176.943092) (xy 375.548633 -176.904383)
			(xy 375.593991 -176.871932) (xy 375.643591 -176.846431) (xy 375.696375 -176.828424) (xy 375.751218 -176.818294)
			(xy 375.806952 -176.816257) (xy 375.862389 -176.822357) (xy 375.916346 -176.836463) (xy 375.967675 -176.858275)
			(xy 376.015281 -176.887329) (xy 376.058149 -176.923004) (xy 376.095366 -176.964541) (xy 376.126139 -177.011054)
			(xy 376.149811 -177.061551) (xy 376.165879 -177.114958) (xy 376.173999 -177.170134) (xy 376.174508 -177.19802)
			(xy 376.173999 -177.225906) (xy 376.165879 -177.281082) (xy 376.149811 -177.334489) (xy 376.126139 -177.384986)
			(xy 376.095366 -177.431499) (xy 376.058149 -177.473036) (xy 376.015281 -177.508711) (xy 375.967675 -177.537765)
			(xy 375.916346 -177.559577) (xy 375.862389 -177.573683) (xy 375.806952 -177.579783) (xy 375.751218 -177.577746)
			(xy 375.696375 -177.567616) (xy 375.643591 -177.549609) (xy 375.593991 -177.524108) (xy 375.548633 -177.491657)
			(xy 375.508484 -177.452948) (xy 375.474398 -177.408805) (xy 375.447102 -177.36017) (xy 375.427179 -177.308079)
			(xy 375.415053 -177.253642) (xy 375.410982 -177.19802) (xy 358.485771 -177.19802) (xy 358.473139 -177.224966)
			(xy 358.442366 -177.271479) (xy 358.405149 -177.313016) (xy 358.362281 -177.348691) (xy 358.314675 -177.377745)
			(xy 358.263346 -177.399557) (xy 358.209389 -177.413663) (xy 358.153952 -177.419763) (xy 358.098218 -177.417726)
			(xy 358.043375 -177.407596) (xy 357.990591 -177.389589) (xy 357.940991 -177.364088) (xy 357.895633 -177.331637)
			(xy 357.855484 -177.292928) (xy 357.821398 -177.248785) (xy 357.794102 -177.20015) (xy 357.774179 -177.148059)
			(xy 357.762053 -177.093622) (xy 357.757982 -177.038) (xy 350.49485 -177.038) (xy 350.490289 -177.068992)
			(xy 350.474221 -177.122399) (xy 350.450549 -177.172896) (xy 350.419776 -177.219409) (xy 350.382559 -177.260946)
			(xy 350.339691 -177.296621) (xy 350.292085 -177.325675) (xy 350.240756 -177.347487) (xy 350.186799 -177.361593)
			(xy 350.131362 -177.367693) (xy 350.075628 -177.365656) (xy 350.020785 -177.355526) (xy 349.968001 -177.337519)
			(xy 349.918401 -177.312018) (xy 349.873043 -177.279567) (xy 349.832894 -177.240858) (xy 349.798808 -177.196715)
			(xy 349.771512 -177.14808) (xy 349.751589 -177.095989) (xy 349.739463 -177.041552) (xy 349.735392 -176.98593)
			(xy 337.250396 -176.98593) (xy 337.232675 -176.996745) (xy 337.181346 -177.018557) (xy 337.127389 -177.032663)
			(xy 337.071952 -177.038763) (xy 337.016218 -177.036726) (xy 336.961375 -177.026596) (xy 336.908591 -177.008589)
			(xy 336.858991 -176.983088) (xy 336.813633 -176.950637) (xy 336.773484 -176.911928) (xy 336.739398 -176.867785)
			(xy 336.712102 -176.81915) (xy 336.692179 -176.767059) (xy 336.680053 -176.712622) (xy 336.675982 -176.657)
			(xy 335.309979 -176.657) (xy 335.328366 -176.677521) (xy 335.359139 -176.724034) (xy 335.382811 -176.774531)
			(xy 335.398879 -176.827938) (xy 335.406999 -176.883114) (xy 335.407508 -176.911) (xy 335.406999 -176.938886)
			(xy 335.398879 -176.994062) (xy 335.382811 -177.047469) (xy 335.359139 -177.097966) (xy 335.328366 -177.144479)
			(xy 335.291149 -177.186016) (xy 335.248281 -177.221691) (xy 335.200675 -177.250745) (xy 335.149346 -177.272557)
			(xy 335.095389 -177.286663) (xy 335.039952 -177.292763) (xy 334.984218 -177.290726) (xy 334.929375 -177.280596)
			(xy 334.876591 -177.262589) (xy 334.826991 -177.237088) (xy 334.781633 -177.204637) (xy 334.741484 -177.165928)
			(xy 334.707398 -177.121785) (xy 334.680102 -177.07315) (xy 334.660179 -177.021059) (xy 334.648053 -176.966622)
			(xy 334.643982 -176.911) (xy 307.970608 -176.911) (xy 307.78387 -177.927) (xy 334.643982 -177.927)
			(xy 334.648053 -177.871378) (xy 334.660179 -177.816941) (xy 334.680102 -177.76485) (xy 334.707398 -177.716215)
			(xy 334.741484 -177.672072) (xy 334.781633 -177.633363) (xy 334.826991 -177.600912) (xy 334.876591 -177.575411)
			(xy 334.929375 -177.557404) (xy 334.984218 -177.547274) (xy 335.039952 -177.545237) (xy 335.095389 -177.551337)
			(xy 335.149346 -177.565443) (xy 335.200675 -177.587255) (xy 335.248281 -177.616309) (xy 335.291149 -177.651984)
			(xy 335.328366 -177.693521) (xy 335.359139 -177.740034) (xy 335.382811 -177.790531) (xy 335.398879 -177.843938)
			(xy 335.406999 -177.899114) (xy 335.407508 -177.927) (xy 335.406999 -177.954886) (xy 335.398879 -178.010062)
			(xy 335.382811 -178.063469) (xy 335.359139 -178.113966) (xy 335.328366 -178.160479) (xy 335.291149 -178.202016)
			(xy 335.248281 -178.237691) (xy 335.200675 -178.266745) (xy 335.149346 -178.288557) (xy 335.095389 -178.302663)
			(xy 335.039952 -178.308763) (xy 334.984218 -178.306726) (xy 334.929375 -178.296596) (xy 334.876591 -178.278589)
			(xy 334.826991 -178.253088) (xy 334.781633 -178.220637) (xy 334.741484 -178.181928) (xy 334.707398 -178.137785)
			(xy 334.680102 -178.08915) (xy 334.660179 -178.037059) (xy 334.648053 -177.982622) (xy 334.643982 -177.927)
			(xy 307.78387 -177.927) (xy 307.483595 -179.560728) (xy 327.1045 -179.560728) (xy 327.108571 -179.505106)
			(xy 327.120697 -179.450669) (xy 327.14062 -179.398578) (xy 327.167916 -179.349943) (xy 327.202002 -179.3058)
			(xy 327.242151 -179.267091) (xy 327.287509 -179.23464) (xy 327.337109 -179.209139) (xy 327.389893 -179.191132)
			(xy 327.444736 -179.181002) (xy 327.50047 -179.178965) (xy 327.555907 -179.185065) (xy 327.609864 -179.199171)
			(xy 327.661193 -179.220983) (xy 327.708799 -179.250037) (xy 327.751667 -179.285712) (xy 327.788884 -179.327249)
			(xy 327.819657 -179.373762) (xy 327.843329 -179.424259) (xy 327.859397 -179.477666) (xy 327.867517 -179.532842)
			(xy 327.868026 -179.560728) (xy 327.867517 -179.588614) (xy 327.859397 -179.64379) (xy 327.843329 -179.697197)
			(xy 327.819657 -179.747694) (xy 327.788884 -179.794207) (xy 327.751667 -179.835744) (xy 327.708799 -179.871419)
			(xy 327.661193 -179.900473) (xy 327.609864 -179.922285) (xy 327.555907 -179.936391) (xy 327.50047 -179.942491)
			(xy 327.444736 -179.940454) (xy 327.389893 -179.930324) (xy 327.337109 -179.912317) (xy 327.287509 -179.886816)
			(xy 327.242151 -179.854365) (xy 327.202002 -179.815656) (xy 327.167916 -179.771513) (xy 327.14062 -179.722878)
			(xy 327.120697 -179.670787) (xy 327.108571 -179.61635) (xy 327.1045 -179.560728) (xy 307.483595 -179.560728)
			(xy 307.083602 -181.737) (xy 325.601582 -181.737) (xy 325.605653 -181.681378) (xy 325.617779 -181.626941)
			(xy 325.637702 -181.57485) (xy 325.664998 -181.526215) (xy 325.699084 -181.482072) (xy 325.739233 -181.443363)
			(xy 325.784591 -181.410912) (xy 325.834191 -181.385411) (xy 325.886975 -181.367404) (xy 325.941818 -181.357274)
			(xy 325.997552 -181.355237) (xy 326.052989 -181.361337) (xy 326.106946 -181.375443) (xy 326.158275 -181.397255)
			(xy 326.205881 -181.426309) (xy 326.248749 -181.461984) (xy 326.285966 -181.503521) (xy 326.316739 -181.550034)
			(xy 326.340411 -181.600531) (xy 326.356479 -181.653938) (xy 326.364599 -181.709114) (xy 326.365108 -181.737)
			(xy 326.364599 -181.764886) (xy 326.356479 -181.820062) (xy 326.340411 -181.873469) (xy 326.316739 -181.923966)
			(xy 326.285966 -181.970479) (xy 326.248749 -182.012016) (xy 326.205881 -182.047691) (xy 326.158275 -182.076745)
			(xy 326.106946 -182.098557) (xy 326.052989 -182.112663) (xy 325.997552 -182.118763) (xy 325.941818 -182.116726)
			(xy 325.886975 -182.106596) (xy 325.834191 -182.088589) (xy 325.784591 -182.063088) (xy 325.739233 -182.030637)
			(xy 325.699084 -181.991928) (xy 325.664998 -181.947785) (xy 325.637702 -181.89915) (xy 325.617779 -181.847059)
			(xy 325.605653 -181.792622) (xy 325.601582 -181.737) (xy 307.083602 -181.737) (xy 306.887527 -182.8038)
			(xy 325.601582 -182.8038) (xy 325.605653 -182.748178) (xy 325.617779 -182.693741) (xy 325.637702 -182.64165)
			(xy 325.664998 -182.593015) (xy 325.699084 -182.548872) (xy 325.739233 -182.510163) (xy 325.784591 -182.477712)
			(xy 325.834191 -182.452211) (xy 325.886975 -182.434204) (xy 325.941818 -182.424074) (xy 325.997552 -182.422037)
			(xy 326.052989 -182.428137) (xy 326.106946 -182.442243) (xy 326.158275 -182.464055) (xy 326.205881 -182.493109)
			(xy 326.248749 -182.528784) (xy 326.285966 -182.570321) (xy 326.316739 -182.616834) (xy 326.340411 -182.667331)
			(xy 326.356479 -182.720738) (xy 326.364599 -182.775914) (xy 326.365108 -182.8038) (xy 326.364599 -182.831686)
			(xy 326.356479 -182.886862) (xy 326.340411 -182.940269) (xy 326.316739 -182.990766) (xy 326.285966 -183.037279)
			(xy 326.248749 -183.078816) (xy 326.205881 -183.114491) (xy 326.158275 -183.143545) (xy 326.106946 -183.165357)
			(xy 326.052989 -183.179463) (xy 325.997552 -183.185563) (xy 325.941818 -183.183526) (xy 325.886975 -183.173396)
			(xy 325.834191 -183.155389) (xy 325.784591 -183.129888) (xy 325.739233 -183.097437) (xy 325.699084 -183.058728)
			(xy 325.664998 -183.014585) (xy 325.637702 -182.96595) (xy 325.617779 -182.913859) (xy 325.605653 -182.859422)
			(xy 325.601582 -182.8038) (xy 306.887527 -182.8038) (xy 306.768902 -183.449214) (xy 324.294752 -183.449214)
			(xy 324.298823 -183.393592) (xy 324.310949 -183.339155) (xy 324.330872 -183.287064) (xy 324.358168 -183.238429)
			(xy 324.392254 -183.194286) (xy 324.432403 -183.155577) (xy 324.477761 -183.123126) (xy 324.527361 -183.097625)
			(xy 324.580145 -183.079618) (xy 324.634988 -183.069488) (xy 324.690722 -183.067451) (xy 324.746159 -183.073551)
			(xy 324.800116 -183.087657) (xy 324.851445 -183.109469) (xy 324.899051 -183.138523) (xy 324.941919 -183.174198)
			(xy 324.979136 -183.215735) (xy 325.009909 -183.262248) (xy 325.033581 -183.312745) (xy 325.049649 -183.366152)
			(xy 325.057769 -183.421328) (xy 325.058278 -183.449214) (xy 325.057769 -183.4771) (xy 325.049649 -183.532276)
			(xy 325.033581 -183.585683) (xy 325.009909 -183.63618) (xy 324.979136 -183.682693) (xy 324.941919 -183.72423)
			(xy 324.899051 -183.759905) (xy 324.851445 -183.788959) (xy 324.800116 -183.810771) (xy 324.746159 -183.824877)
			(xy 324.690722 -183.830977) (xy 324.634988 -183.82894) (xy 324.580145 -183.81881) (xy 324.527361 -183.800803)
			(xy 324.477761 -183.775302) (xy 324.432403 -183.742851) (xy 324.392254 -183.704142) (xy 324.358168 -183.659999)
			(xy 324.330872 -183.611364) (xy 324.310949 -183.559273) (xy 324.298823 -183.504836) (xy 324.294752 -183.449214)
			(xy 306.768902 -183.449214) (xy 305.656177 -189.503304) (xy 325.382888 -189.503304) (xy 325.386959 -189.447682)
			(xy 325.399085 -189.393245) (xy 325.419008 -189.341154) (xy 325.446304 -189.292519) (xy 325.48039 -189.248376)
			(xy 325.520539 -189.209667) (xy 325.565897 -189.177216) (xy 325.615497 -189.151715) (xy 325.668281 -189.133708)
			(xy 325.723124 -189.123578) (xy 325.778858 -189.121541) (xy 325.834295 -189.127641) (xy 325.888252 -189.141747)
			(xy 325.939581 -189.163559) (xy 325.987187 -189.192613) (xy 326.030055 -189.228288) (xy 326.067272 -189.269825)
			(xy 326.098045 -189.316338) (xy 326.121717 -189.366835) (xy 326.137785 -189.420242) (xy 326.145905 -189.475418)
			(xy 326.146414 -189.503304) (xy 326.145905 -189.53119) (xy 326.137785 -189.586366) (xy 326.121717 -189.639773)
			(xy 326.098045 -189.69027) (xy 326.067272 -189.736783) (xy 326.030055 -189.77832) (xy 325.987187 -189.813995)
			(xy 325.939581 -189.843049) (xy 325.888252 -189.864861) (xy 325.834295 -189.878967) (xy 325.778858 -189.885067)
			(xy 325.723124 -189.88303) (xy 325.668281 -189.8729) (xy 325.615497 -189.854893) (xy 325.565897 -189.829392)
			(xy 325.520539 -189.796941) (xy 325.48039 -189.758232) (xy 325.446304 -189.714089) (xy 325.419008 -189.665454)
			(xy 325.399085 -189.613363) (xy 325.386959 -189.558926) (xy 325.382888 -189.503304) (xy 305.656177 -189.503304)
			(xy 305.539466 -190.138304) (xy 324.620888 -190.138304) (xy 324.624959 -190.082682) (xy 324.637085 -190.028245)
			(xy 324.657008 -189.976154) (xy 324.684304 -189.927519) (xy 324.71839 -189.883376) (xy 324.758539 -189.844667)
			(xy 324.803897 -189.812216) (xy 324.853497 -189.786715) (xy 324.906281 -189.768708) (xy 324.961124 -189.758578)
			(xy 325.016858 -189.756541) (xy 325.072295 -189.762641) (xy 325.126252 -189.776747) (xy 325.177581 -189.798559)
			(xy 325.225187 -189.827613) (xy 325.268055 -189.863288) (xy 325.305272 -189.904825) (xy 325.336045 -189.951338)
			(xy 325.359717 -190.001835) (xy 325.375785 -190.055242) (xy 325.383905 -190.110418) (xy 325.384414 -190.138304)
			(xy 325.383905 -190.16619) (xy 325.375785 -190.221366) (xy 325.359717 -190.274773) (xy 325.336045 -190.32527)
			(xy 325.305272 -190.371783) (xy 325.268055 -190.41332) (xy 325.225187 -190.448995) (xy 325.177581 -190.478049)
			(xy 325.126252 -190.499861) (xy 325.072295 -190.513967) (xy 325.016858 -190.520067) (xy 324.961124 -190.51803)
			(xy 324.906281 -190.5079) (xy 324.853497 -190.489893) (xy 324.803897 -190.464392) (xy 324.758539 -190.431941)
			(xy 324.71839 -190.393232) (xy 324.684304 -190.349089) (xy 324.657008 -190.300454) (xy 324.637085 -190.248363)
			(xy 324.624959 -190.193926) (xy 324.620888 -190.138304) (xy 305.539466 -190.138304) (xy 305.422754 -190.773304)
			(xy 325.382888 -190.773304) (xy 325.386959 -190.717682) (xy 325.399085 -190.663245) (xy 325.419008 -190.611154)
			(xy 325.446304 -190.562519) (xy 325.48039 -190.518376) (xy 325.520539 -190.479667) (xy 325.565897 -190.447216)
			(xy 325.615497 -190.421715) (xy 325.668281 -190.403708) (xy 325.723124 -190.393578) (xy 325.778858 -190.391541)
			(xy 325.834295 -190.397641) (xy 325.888252 -190.411747) (xy 325.939581 -190.433559) (xy 325.987187 -190.462613)
			(xy 326.030055 -190.498288) (xy 326.067272 -190.539825) (xy 326.098045 -190.586338) (xy 326.121717 -190.636835)
			(xy 326.137785 -190.690242) (xy 326.145905 -190.745418) (xy 326.146414 -190.773304) (xy 326.145905 -190.80119)
			(xy 326.137785 -190.856366) (xy 326.121717 -190.909773) (xy 326.098045 -190.96027) (xy 326.067272 -191.006783)
			(xy 326.030055 -191.04832) (xy 325.987187 -191.083995) (xy 325.939581 -191.113049) (xy 325.888252 -191.134861)
			(xy 325.834295 -191.148967) (xy 325.778858 -191.155067) (xy 325.723124 -191.15303) (xy 325.668281 -191.1429)
			(xy 325.615497 -191.124893) (xy 325.565897 -191.099392) (xy 325.520539 -191.066941) (xy 325.48039 -191.028232)
			(xy 325.446304 -190.984089) (xy 325.419008 -190.935454) (xy 325.399085 -190.883363) (xy 325.386959 -190.828926)
			(xy 325.382888 -190.773304) (xy 305.422754 -190.773304) (xy 305.306043 -191.408304) (xy 324.620888 -191.408304)
			(xy 324.624959 -191.352682) (xy 324.637085 -191.298245) (xy 324.657008 -191.246154) (xy 324.684304 -191.197519)
			(xy 324.71839 -191.153376) (xy 324.758539 -191.114667) (xy 324.803897 -191.082216) (xy 324.853497 -191.056715)
			(xy 324.906281 -191.038708) (xy 324.961124 -191.028578) (xy 325.016858 -191.026541) (xy 325.072295 -191.032641)
			(xy 325.126252 -191.046747) (xy 325.177581 -191.068559) (xy 325.225187 -191.097613) (xy 325.268055 -191.133288)
			(xy 325.305272 -191.174825) (xy 325.336045 -191.221338) (xy 325.359717 -191.271835) (xy 325.375785 -191.325242)
			(xy 325.383905 -191.380418) (xy 325.384414 -191.408304) (xy 325.383905 -191.43619) (xy 325.375785 -191.491366)
			(xy 325.359717 -191.544773) (xy 325.336045 -191.59527) (xy 325.305272 -191.641783) (xy 325.268055 -191.68332)
			(xy 325.225187 -191.718995) (xy 325.177581 -191.748049) (xy 325.126252 -191.769861) (xy 325.072295 -191.783967)
			(xy 325.016858 -191.790067) (xy 324.961124 -191.78803) (xy 324.906281 -191.7779) (xy 324.853497 -191.759893)
			(xy 324.803897 -191.734392) (xy 324.758539 -191.701941) (xy 324.71839 -191.663232) (xy 324.684304 -191.619089)
			(xy 324.657008 -191.570454) (xy 324.637085 -191.518363) (xy 324.624959 -191.463926) (xy 324.620888 -191.408304)
			(xy 305.306043 -191.408304) (xy 305.189332 -192.043304) (xy 325.382888 -192.043304) (xy 325.386959 -191.987682)
			(xy 325.399085 -191.933245) (xy 325.419008 -191.881154) (xy 325.446304 -191.832519) (xy 325.48039 -191.788376)
			(xy 325.520539 -191.749667) (xy 325.565897 -191.717216) (xy 325.615497 -191.691715) (xy 325.668281 -191.673708)
			(xy 325.723124 -191.663578) (xy 325.778858 -191.661541) (xy 325.834295 -191.667641) (xy 325.888252 -191.681747)
			(xy 325.939581 -191.703559) (xy 325.987187 -191.732613) (xy 326.030055 -191.768288) (xy 326.067272 -191.809825)
			(xy 326.098045 -191.856338) (xy 326.121717 -191.906835) (xy 326.137785 -191.960242) (xy 326.145905 -192.015418)
			(xy 326.146414 -192.043304) (xy 326.145905 -192.07119) (xy 326.137785 -192.126366) (xy 326.121717 -192.179773)
			(xy 326.098045 -192.23027) (xy 326.067272 -192.276783) (xy 326.030055 -192.31832) (xy 325.987187 -192.353995)
			(xy 325.939581 -192.383049) (xy 325.888252 -192.404861) (xy 325.834295 -192.418967) (xy 325.778858 -192.425067)
			(xy 325.723124 -192.42303) (xy 325.668281 -192.4129) (xy 325.615497 -192.394893) (xy 325.565897 -192.369392)
			(xy 325.520539 -192.336941) (xy 325.48039 -192.298232) (xy 325.446304 -192.254089) (xy 325.419008 -192.205454)
			(xy 325.399085 -192.153363) (xy 325.386959 -192.098926) (xy 325.382888 -192.043304) (xy 305.189332 -192.043304)
			(xy 305.072621 -192.678304) (xy 324.620888 -192.678304) (xy 324.624959 -192.622682) (xy 324.637085 -192.568245)
			(xy 324.657008 -192.516154) (xy 324.684304 -192.467519) (xy 324.71839 -192.423376) (xy 324.758539 -192.384667)
			(xy 324.803897 -192.352216) (xy 324.853497 -192.326715) (xy 324.906281 -192.308708) (xy 324.961124 -192.298578)
			(xy 325.016858 -192.296541) (xy 325.072295 -192.302641) (xy 325.126252 -192.316747) (xy 325.177581 -192.338559)
			(xy 325.225187 -192.367613) (xy 325.268055 -192.403288) (xy 325.305272 -192.444825) (xy 325.336045 -192.491338)
			(xy 325.359717 -192.541835) (xy 325.375785 -192.595242) (xy 325.383905 -192.650418) (xy 325.384414 -192.678304)
			(xy 325.383905 -192.70619) (xy 325.375785 -192.761366) (xy 325.359717 -192.814773) (xy 325.336045 -192.86527)
			(xy 325.305272 -192.911783) (xy 325.268055 -192.95332) (xy 325.225187 -192.988995) (xy 325.177581 -193.018049)
			(xy 325.126252 -193.039861) (xy 325.072295 -193.053967) (xy 325.016858 -193.060067) (xy 324.961124 -193.05803)
			(xy 324.906281 -193.0479) (xy 324.853497 -193.029893) (xy 324.803897 -193.004392) (xy 324.758539 -192.971941)
			(xy 324.71839 -192.933232) (xy 324.684304 -192.889089) (xy 324.657008 -192.840454) (xy 324.637085 -192.788363)
			(xy 324.624959 -192.733926) (xy 324.620888 -192.678304) (xy 305.072621 -192.678304) (xy 304.955909 -193.313304)
			(xy 325.382888 -193.313304) (xy 325.386959 -193.257682) (xy 325.399085 -193.203245) (xy 325.419008 -193.151154)
			(xy 325.446304 -193.102519) (xy 325.48039 -193.058376) (xy 325.520539 -193.019667) (xy 325.565897 -192.987216)
			(xy 325.615497 -192.961715) (xy 325.668281 -192.943708) (xy 325.723124 -192.933578) (xy 325.778858 -192.931541)
			(xy 325.834295 -192.937641) (xy 325.888252 -192.951747) (xy 325.939581 -192.973559) (xy 325.987187 -193.002613)
			(xy 326.030055 -193.038288) (xy 326.067272 -193.079825) (xy 326.098045 -193.126338) (xy 326.121717 -193.176835)
			(xy 326.137785 -193.230242) (xy 326.145905 -193.285418) (xy 326.146414 -193.313304) (xy 326.145905 -193.34119)
			(xy 326.137785 -193.396366) (xy 326.121717 -193.449773) (xy 326.098045 -193.50027) (xy 326.067272 -193.546783)
			(xy 326.030055 -193.58832) (xy 325.987187 -193.623995) (xy 325.939581 -193.653049) (xy 325.888252 -193.674861)
			(xy 325.834295 -193.688967) (xy 325.778858 -193.695067) (xy 325.723124 -193.69303) (xy 325.668281 -193.6829)
			(xy 325.615497 -193.664893) (xy 325.565897 -193.639392) (xy 325.520539 -193.606941) (xy 325.48039 -193.568232)
			(xy 325.446304 -193.524089) (xy 325.419008 -193.475454) (xy 325.399085 -193.423363) (xy 325.386959 -193.368926)
			(xy 325.382888 -193.313304) (xy 304.955909 -193.313304) (xy 304.839198 -193.948304) (xy 324.620888 -193.948304)
			(xy 324.624959 -193.892682) (xy 324.637085 -193.838245) (xy 324.657008 -193.786154) (xy 324.684304 -193.737519)
			(xy 324.71839 -193.693376) (xy 324.758539 -193.654667) (xy 324.803897 -193.622216) (xy 324.853497 -193.596715)
			(xy 324.906281 -193.578708) (xy 324.961124 -193.568578) (xy 325.016858 -193.566541) (xy 325.072295 -193.572641)
			(xy 325.126252 -193.586747) (xy 325.177581 -193.608559) (xy 325.225187 -193.637613) (xy 325.268055 -193.673288)
			(xy 325.305272 -193.714825) (xy 325.336045 -193.761338) (xy 325.359717 -193.811835) (xy 325.375785 -193.865242)
			(xy 325.383905 -193.920418) (xy 325.384414 -193.948304) (xy 325.383905 -193.97619) (xy 325.375785 -194.031366)
			(xy 325.359717 -194.084773) (xy 325.336045 -194.13527) (xy 325.305272 -194.181783) (xy 325.268055 -194.22332)
			(xy 325.225187 -194.258995) (xy 325.177581 -194.288049) (xy 325.126252 -194.309861) (xy 325.072295 -194.323967)
			(xy 325.016858 -194.330067) (xy 324.961124 -194.32803) (xy 324.906281 -194.3179) (xy 324.853497 -194.299893)
			(xy 324.803897 -194.274392) (xy 324.758539 -194.241941) (xy 324.71839 -194.203232) (xy 324.684304 -194.159089)
			(xy 324.657008 -194.110454) (xy 324.637085 -194.058363) (xy 324.624959 -194.003926) (xy 324.620888 -193.948304)
			(xy 304.839198 -193.948304) (xy 304.722486 -194.583304) (xy 325.382888 -194.583304) (xy 325.386959 -194.527682)
			(xy 325.399085 -194.473245) (xy 325.419008 -194.421154) (xy 325.446304 -194.372519) (xy 325.48039 -194.328376)
			(xy 325.520539 -194.289667) (xy 325.565897 -194.257216) (xy 325.615497 -194.231715) (xy 325.668281 -194.213708)
			(xy 325.723124 -194.203578) (xy 325.778858 -194.201541) (xy 325.834295 -194.207641) (xy 325.888252 -194.221747)
			(xy 325.939581 -194.243559) (xy 325.987187 -194.272613) (xy 326.030055 -194.308288) (xy 326.067272 -194.349825)
			(xy 326.098045 -194.396338) (xy 326.121717 -194.446835) (xy 326.137785 -194.500242) (xy 326.145905 -194.555418)
			(xy 326.146414 -194.583304) (xy 326.145905 -194.61119) (xy 326.137785 -194.666366) (xy 326.121717 -194.719773)
			(xy 326.098045 -194.77027) (xy 326.067272 -194.816783) (xy 326.030055 -194.85832) (xy 325.987187 -194.893995)
			(xy 325.939581 -194.923049) (xy 325.888252 -194.944861) (xy 325.834295 -194.958967) (xy 325.778858 -194.965067)
			(xy 325.723124 -194.96303) (xy 325.668281 -194.9529) (xy 325.615497 -194.934893) (xy 325.565897 -194.909392)
			(xy 325.520539 -194.876941) (xy 325.48039 -194.838232) (xy 325.446304 -194.794089) (xy 325.419008 -194.745454)
			(xy 325.399085 -194.693363) (xy 325.386959 -194.638926) (xy 325.382888 -194.583304) (xy 304.722486 -194.583304)
			(xy 304.605775 -195.218304) (xy 324.620888 -195.218304) (xy 324.624959 -195.162682) (xy 324.637085 -195.108245)
			(xy 324.657008 -195.056154) (xy 324.684304 -195.007519) (xy 324.71839 -194.963376) (xy 324.758539 -194.924667)
			(xy 324.803897 -194.892216) (xy 324.853497 -194.866715) (xy 324.906281 -194.848708) (xy 324.961124 -194.838578)
			(xy 325.016858 -194.836541) (xy 325.072295 -194.842641) (xy 325.126252 -194.856747) (xy 325.177581 -194.878559)
			(xy 325.225187 -194.907613) (xy 325.268055 -194.943288) (xy 325.305272 -194.984825) (xy 325.336045 -195.031338)
			(xy 325.359717 -195.081835) (xy 325.375785 -195.135242) (xy 325.383905 -195.190418) (xy 325.384414 -195.218304)
			(xy 325.383905 -195.24619) (xy 325.375785 -195.301366) (xy 325.359717 -195.354773) (xy 325.336045 -195.40527)
			(xy 325.305272 -195.451783) (xy 325.268055 -195.49332) (xy 325.225187 -195.528995) (xy 325.177581 -195.558049)
			(xy 325.126252 -195.579861) (xy 325.072295 -195.593967) (xy 325.016858 -195.600067) (xy 324.961124 -195.59803)
			(xy 324.906281 -195.5879) (xy 324.853497 -195.569893) (xy 324.803897 -195.544392) (xy 324.758539 -195.511941)
			(xy 324.71839 -195.473232) (xy 324.684304 -195.429089) (xy 324.657008 -195.380454) (xy 324.637085 -195.328363)
			(xy 324.624959 -195.273926) (xy 324.620888 -195.218304) (xy 304.605775 -195.218304) (xy 304.472304 -195.94449)
			(xy 327.685398 -195.94449) (xy 327.689469 -195.888868) (xy 327.701595 -195.834431) (xy 327.721518 -195.78234)
			(xy 327.748814 -195.733705) (xy 327.7829 -195.689562) (xy 327.823049 -195.650853) (xy 327.868407 -195.618402)
			(xy 327.918007 -195.592901) (xy 327.970791 -195.574894) (xy 328.025634 -195.564764) (xy 328.081368 -195.562727)
			(xy 328.136805 -195.568827) (xy 328.190762 -195.582933) (xy 328.242091 -195.604745) (xy 328.289697 -195.633799)
			(xy 328.332565 -195.669474) (xy 328.369782 -195.711011) (xy 328.400555 -195.757524) (xy 328.424227 -195.808021)
			(xy 328.440295 -195.861428) (xy 328.448415 -195.916604) (xy 328.448924 -195.94449) (xy 328.448415 -195.972376)
			(xy 328.440295 -196.027552) (xy 328.424227 -196.080959) (xy 328.400555 -196.131456) (xy 328.369782 -196.177969)
			(xy 328.332565 -196.219506) (xy 328.289697 -196.255181) (xy 328.242091 -196.284235) (xy 328.190762 -196.306047)
			(xy 328.136805 -196.320153) (xy 328.081368 -196.326253) (xy 328.025634 -196.324216) (xy 327.970791 -196.314086)
			(xy 327.918007 -196.296079) (xy 327.868407 -196.270578) (xy 327.823049 -196.238127) (xy 327.7829 -196.199418)
			(xy 327.748814 -196.155275) (xy 327.721518 -196.10664) (xy 327.701595 -196.054549) (xy 327.689469 -196.000112)
			(xy 327.685398 -195.94449) (xy 304.472304 -195.94449) (xy 304.232299 -197.250304) (xy 327.685398 -197.250304)
			(xy 327.689469 -197.194682) (xy 327.701595 -197.140245) (xy 327.721518 -197.088154) (xy 327.748814 -197.039519)
			(xy 327.7829 -196.995376) (xy 327.823049 -196.956667) (xy 327.868407 -196.924216) (xy 327.918007 -196.898715)
			(xy 327.970791 -196.880708) (xy 328.025634 -196.870578) (xy 328.081368 -196.868541) (xy 328.136805 -196.874641)
			(xy 328.190762 -196.888747) (xy 328.242091 -196.910559) (xy 328.289697 -196.939613) (xy 328.332565 -196.975288)
			(xy 328.369782 -197.016825) (xy 328.400555 -197.063338) (xy 328.424227 -197.113835) (xy 328.440295 -197.167242)
			(xy 328.448415 -197.222418) (xy 328.448924 -197.250304) (xy 328.448415 -197.27819) (xy 328.440295 -197.333366)
			(xy 328.424227 -197.386773) (xy 328.400555 -197.43727) (xy 328.369782 -197.483783) (xy 328.332565 -197.52532)
			(xy 328.289697 -197.560995) (xy 328.242091 -197.590049) (xy 328.190762 -197.611861) (xy 328.136805 -197.625967)
			(xy 328.081368 -197.632067) (xy 328.025634 -197.63003) (xy 327.970791 -197.6199) (xy 327.918007 -197.601893)
			(xy 327.868407 -197.576392) (xy 327.823049 -197.543941) (xy 327.7829 -197.505232) (xy 327.748814 -197.461089)
			(xy 327.721518 -197.412454) (xy 327.701595 -197.360363) (xy 327.689469 -197.305926) (xy 327.685398 -197.250304)
			(xy 304.232299 -197.250304) (xy 304.045561 -198.266304) (xy 324.620888 -198.266304) (xy 324.624959 -198.210682)
			(xy 324.637085 -198.156245) (xy 324.657008 -198.104154) (xy 324.684304 -198.055519) (xy 324.71839 -198.011376)
			(xy 324.758539 -197.972667) (xy 324.803897 -197.940216) (xy 324.853497 -197.914715) (xy 324.906281 -197.896708)
			(xy 324.961124 -197.886578) (xy 325.016858 -197.884541) (xy 325.072295 -197.890641) (xy 325.126252 -197.904747)
			(xy 325.177581 -197.926559) (xy 325.225187 -197.955613) (xy 325.268055 -197.991288) (xy 325.305272 -198.032825)
			(xy 325.336045 -198.079338) (xy 325.359717 -198.129835) (xy 325.375785 -198.183242) (xy 325.383905 -198.238418)
			(xy 325.384414 -198.266304) (xy 325.383905 -198.29419) (xy 325.375785 -198.349366) (xy 325.359717 -198.402773)
			(xy 325.336045 -198.45327) (xy 325.305272 -198.499783) (xy 325.286885 -198.520304) (xy 327.685398 -198.520304)
			(xy 327.689469 -198.464682) (xy 327.701595 -198.410245) (xy 327.721518 -198.358154) (xy 327.748814 -198.309519)
			(xy 327.7829 -198.265376) (xy 327.823049 -198.226667) (xy 327.868407 -198.194216) (xy 327.918007 -198.168715)
			(xy 327.970791 -198.150708) (xy 328.025634 -198.140578) (xy 328.081368 -198.138541) (xy 328.136805 -198.144641)
			(xy 328.190762 -198.158747) (xy 328.242091 -198.180559) (xy 328.289697 -198.209613) (xy 328.332565 -198.245288)
			(xy 328.369782 -198.286825) (xy 328.400555 -198.333338) (xy 328.424227 -198.383835) (xy 328.440295 -198.437242)
			(xy 328.448415 -198.492418) (xy 328.448924 -198.520304) (xy 328.448415 -198.54819) (xy 328.440295 -198.603366)
			(xy 328.424227 -198.656773) (xy 328.400555 -198.70727) (xy 328.369782 -198.753783) (xy 328.332565 -198.79532)
			(xy 328.289697 -198.830995) (xy 328.242091 -198.860049) (xy 328.190762 -198.881861) (xy 328.136805 -198.895967)
			(xy 328.081368 -198.902067) (xy 328.025634 -198.90003) (xy 327.970791 -198.8899) (xy 327.918007 -198.871893)
			(xy 327.868407 -198.846392) (xy 327.823049 -198.813941) (xy 327.7829 -198.775232) (xy 327.748814 -198.731089)
			(xy 327.721518 -198.682454) (xy 327.701595 -198.630363) (xy 327.689469 -198.575926) (xy 327.685398 -198.520304)
			(xy 325.286885 -198.520304) (xy 325.268055 -198.54132) (xy 325.225187 -198.576995) (xy 325.177581 -198.606049)
			(xy 325.126252 -198.627861) (xy 325.072295 -198.641967) (xy 325.016858 -198.648067) (xy 324.961124 -198.64603)
			(xy 324.906281 -198.6359) (xy 324.853497 -198.617893) (xy 324.803897 -198.592392) (xy 324.758539 -198.559941)
			(xy 324.71839 -198.521232) (xy 324.684304 -198.477089) (xy 324.657008 -198.428454) (xy 324.637085 -198.376363)
			(xy 324.624959 -198.321926) (xy 324.620888 -198.266304) (xy 304.045561 -198.266304) (xy 303.858823 -199.282304)
			(xy 324.620888 -199.282304) (xy 324.624959 -199.226682) (xy 324.637085 -199.172245) (xy 324.657008 -199.120154)
			(xy 324.684304 -199.071519) (xy 324.71839 -199.027376) (xy 324.758539 -198.988667) (xy 324.803897 -198.956216)
			(xy 324.853497 -198.930715) (xy 324.906281 -198.912708) (xy 324.961124 -198.902578) (xy 325.016858 -198.900541)
			(xy 325.072295 -198.906641) (xy 325.126252 -198.920747) (xy 325.177581 -198.942559) (xy 325.225187 -198.971613)
			(xy 325.268055 -199.007288) (xy 325.305272 -199.048825) (xy 325.336045 -199.095338) (xy 325.359717 -199.145835)
			(xy 325.375785 -199.199242) (xy 325.383905 -199.254418) (xy 325.384414 -199.282304) (xy 325.383905 -199.31019)
			(xy 325.375785 -199.365366) (xy 325.359717 -199.418773) (xy 325.336045 -199.46927) (xy 325.305272 -199.515783)
			(xy 325.268055 -199.55732) (xy 325.225187 -199.592995) (xy 325.177581 -199.622049) (xy 325.126252 -199.643861)
			(xy 325.072295 -199.657967) (xy 325.016858 -199.664067) (xy 324.961124 -199.66203) (xy 324.906281 -199.6519)
			(xy 324.853497 -199.633893) (xy 324.803897 -199.608392) (xy 324.758539 -199.575941) (xy 324.71839 -199.537232)
			(xy 324.684304 -199.493089) (xy 324.657008 -199.444454) (xy 324.637085 -199.392363) (xy 324.624959 -199.337926)
			(xy 324.620888 -199.282304) (xy 303.858823 -199.282304) (xy 302.041675 -209.169) (xy 325.18934 -209.169)
			(xy 325.193411 -209.113378) (xy 325.205537 -209.058941) (xy 325.22546 -209.00685) (xy 325.252756 -208.958215)
			(xy 325.286842 -208.914072) (xy 325.326991 -208.875363) (xy 325.372349 -208.842912) (xy 325.421949 -208.817411)
			(xy 325.474733 -208.799404) (xy 325.529576 -208.789274) (xy 325.58531 -208.787237) (xy 325.640747 -208.793337)
			(xy 325.694704 -208.807443) (xy 325.746033 -208.829255) (xy 325.793639 -208.858309) (xy 325.836507 -208.893984)
			(xy 325.873724 -208.935521) (xy 325.904497 -208.982034) (xy 325.928169 -209.032531) (xy 325.944237 -209.085938)
			(xy 325.952357 -209.141114) (xy 325.952866 -209.169) (xy 325.952357 -209.196886) (xy 325.944237 -209.252062)
			(xy 325.928169 -209.305469) (xy 325.904497 -209.355966) (xy 325.873724 -209.402479) (xy 325.836507 -209.444016)
			(xy 325.793639 -209.479691) (xy 325.746033 -209.508745) (xy 325.694704 -209.530557) (xy 325.640747 -209.544663)
			(xy 325.58531 -209.550763) (xy 325.529576 -209.548726) (xy 325.474733 -209.538596) (xy 325.421949 -209.520589)
			(xy 325.372349 -209.495088) (xy 325.326991 -209.462637) (xy 325.286842 -209.423928) (xy 325.252756 -209.379785)
			(xy 325.22546 -209.33115) (xy 325.205537 -209.279059) (xy 325.193411 -209.224622) (xy 325.18934 -209.169)
			(xy 302.041675 -209.169) (xy 301.860166 -210.156552) (xy 325.090534 -210.156552) (xy 325.094605 -210.10093)
			(xy 325.106731 -210.046493) (xy 325.126654 -209.994402) (xy 325.15395 -209.945767) (xy 325.188036 -209.901624)
			(xy 325.228185 -209.862915) (xy 325.273543 -209.830464) (xy 325.323143 -209.804963) (xy 325.375927 -209.786956)
			(xy 325.43077 -209.776826) (xy 325.486504 -209.774789) (xy 325.541941 -209.780889) (xy 325.595898 -209.794995)
			(xy 325.647227 -209.816807) (xy 325.694833 -209.845861) (xy 325.737701 -209.881536) (xy 325.774918 -209.923073)
			(xy 325.805691 -209.969586) (xy 325.829363 -210.020083) (xy 325.845431 -210.07349) (xy 325.853551 -210.128666)
			(xy 325.85406 -210.156552) (xy 325.853551 -210.184438) (xy 325.845431 -210.239614) (xy 325.829363 -210.293021)
			(xy 325.805691 -210.343518) (xy 325.774918 -210.390031) (xy 325.737701 -210.431568) (xy 325.694833 -210.467243)
			(xy 325.647227 -210.496297) (xy 325.595898 -210.518109) (xy 325.541941 -210.532215) (xy 325.486504 -210.538315)
			(xy 325.43077 -210.536278) (xy 325.375927 -210.526148) (xy 325.323143 -210.508141) (xy 325.273543 -210.48264)
			(xy 325.228185 -210.450189) (xy 325.188036 -210.41148) (xy 325.15395 -210.367337) (xy 325.126654 -210.318702)
			(xy 325.106731 -210.266611) (xy 325.094605 -210.212174) (xy 325.090534 -210.156552) (xy 301.860166 -210.156552)
			(xy 301.481835 -212.214968) (xy 325.060308 -212.214968) (xy 325.064379 -212.159346) (xy 325.076505 -212.104909)
			(xy 325.096428 -212.052818) (xy 325.123724 -212.004183) (xy 325.15781 -211.96004) (xy 325.197959 -211.921331)
			(xy 325.243317 -211.88888) (xy 325.292917 -211.863379) (xy 325.345701 -211.845372) (xy 325.400544 -211.835242)
			(xy 325.456278 -211.833205) (xy 325.511715 -211.839305) (xy 325.565672 -211.853411) (xy 325.617001 -211.875223)
			(xy 325.664607 -211.904277) (xy 325.707475 -211.939952) (xy 325.744692 -211.981489) (xy 325.775465 -212.028002)
			(xy 325.799137 -212.078499) (xy 325.815205 -212.131906) (xy 325.823325 -212.187082) (xy 325.823834 -212.214968)
			(xy 325.823325 -212.242854) (xy 325.815205 -212.29803) (xy 325.799137 -212.351437) (xy 325.775465 -212.401934)
			(xy 325.744692 -212.448447) (xy 325.707475 -212.489984) (xy 325.664607 -212.525659) (xy 325.617001 -212.554713)
			(xy 325.565672 -212.576525) (xy 325.511715 -212.590631) (xy 325.456278 -212.596731) (xy 325.400544 -212.594694)
			(xy 325.345701 -212.584564) (xy 325.292917 -212.566557) (xy 325.243317 -212.541056) (xy 325.197959 -212.508605)
			(xy 325.15781 -212.469896) (xy 325.123724 -212.425753) (xy 325.096428 -212.377118) (xy 325.076505 -212.325027)
			(xy 325.064379 -212.27059) (xy 325.060308 -212.214968) (xy 301.481835 -212.214968) (xy 301.15383 -213.999572)
			(xy 301.152759 -214.009228) (xy 301.157077 -214.028154) (xy 301.162212 -214.036402) (xy 301.166276 -214.042498)
			(xy 301.174658 -214.048594) (xy 301.175674 -214.04961) (xy 301.198026 -214.065104) (xy 301.207678 -214.06739)
			(xy 301.235271 -214.074361) (xy 301.288163 -214.095369) (xy 301.337347 -214.124001) (xy 301.381731 -214.159623)
			(xy 301.42033 -214.201444) (xy 301.423472 -214.206074) (xy 325.076056 -214.206074) (xy 325.080127 -214.150452)
			(xy 325.092253 -214.096015) (xy 325.112176 -214.043924) (xy 325.139472 -213.995289) (xy 325.173558 -213.951146)
			(xy 325.213707 -213.912437) (xy 325.259065 -213.879986) (xy 325.308665 -213.854485) (xy 325.361449 -213.836478)
			(xy 325.416292 -213.826348) (xy 325.472026 -213.824311) (xy 325.527463 -213.830411) (xy 325.58142 -213.844517)
			(xy 325.632749 -213.866329) (xy 325.680355 -213.895383) (xy 325.723223 -213.931058) (xy 325.76044 -213.972595)
			(xy 325.791213 -214.019108) (xy 325.814885 -214.069605) (xy 325.830953 -214.123012) (xy 325.839073 -214.178188)
			(xy 325.839582 -214.206074) (xy 325.839073 -214.23396) (xy 325.83686 -214.249) (xy 326.134982 -214.249)
			(xy 326.139053 -214.193378) (xy 326.151179 -214.138941) (xy 326.171102 -214.08685) (xy 326.198398 -214.038215)
			(xy 326.232484 -213.994072) (xy 326.272633 -213.955363) (xy 326.317991 -213.922912) (xy 326.367591 -213.897411)
			(xy 326.420375 -213.879404) (xy 326.475218 -213.869274) (xy 326.530952 -213.867237) (xy 326.586389 -213.873337)
			(xy 326.640346 -213.887443) (xy 326.691675 -213.909255) (xy 326.739281 -213.938309) (xy 326.782149 -213.973984)
			(xy 326.819366 -214.015521) (xy 326.850139 -214.062034) (xy 326.873811 -214.112531) (xy 326.889879 -214.165938)
			(xy 326.897999 -214.221114) (xy 326.898508 -214.249) (xy 326.897999 -214.276886) (xy 326.889879 -214.332062)
			(xy 326.873811 -214.385469) (xy 326.850139 -214.435966) (xy 326.819366 -214.482479) (xy 326.782149 -214.524016)
			(xy 326.739281 -214.559691) (xy 326.691675 -214.588745) (xy 326.640346 -214.610557) (xy 326.586389 -214.624663)
			(xy 326.530952 -214.630763) (xy 326.475218 -214.628726) (xy 326.420375 -214.618596) (xy 326.367591 -214.600589)
			(xy 326.317991 -214.575088) (xy 326.272633 -214.542637) (xy 326.232484 -214.503928) (xy 326.198398 -214.459785)
			(xy 326.171102 -214.41115) (xy 326.151179 -214.359059) (xy 326.139053 -214.304622) (xy 326.134982 -214.249)
			(xy 325.83686 -214.249) (xy 325.830953 -214.289136) (xy 325.814885 -214.342543) (xy 325.791213 -214.39304)
			(xy 325.76044 -214.439553) (xy 325.723223 -214.48109) (xy 325.680355 -214.516765) (xy 325.632749 -214.545819)
			(xy 325.58142 -214.567631) (xy 325.527463 -214.581737) (xy 325.472026 -214.587837) (xy 325.416292 -214.5858)
			(xy 325.361449 -214.57567) (xy 325.308665 -214.557663) (xy 325.259065 -214.532162) (xy 325.213707 -214.499711)
			(xy 325.173558 -214.461002) (xy 325.139472 -214.416859) (xy 325.112176 -214.368224) (xy 325.092253 -214.316133)
			(xy 325.080127 -214.261696) (xy 325.076056 -214.206074) (xy 301.423472 -214.206074) (xy 301.452288 -214.248536)
			(xy 301.476894 -214.299852) (xy 301.493604 -214.354255) (xy 301.502045 -214.410536) (xy 301.502572 -214.438992)
			(xy 301.502109 -214.466244) (xy 301.494353 -214.520194) (xy 301.478997 -214.572491) (xy 301.456355 -214.62207)
			(xy 301.426886 -214.667921) (xy 301.391192 -214.709112) (xy 301.349999 -214.744803) (xy 301.304145 -214.774268)
			(xy 301.254565 -214.796907) (xy 301.202267 -214.812259) (xy 301.148316 -214.820011) (xy 301.121064 -214.8205)
			(xy 301.120302 -214.8205) (xy 301.105123 -214.820352) (xy 301.074861 -214.817933) (xy 301.05985 -214.815674)
			(xy 301.057056 -214.815166) (xy 301.04334 -214.814404) (xy 301.03445 -214.817198) (xy 301.024544 -214.820246)
			(xy 301.003716 -214.837772) (xy 301.0027 -214.838788) (xy 300.999144 -214.841582) (xy 300.83633 -215.727026)
			(xy 300.835555 -215.732025) (xy 300.835817 -215.742137) (xy 300.836838 -215.747092) (xy 300.83887 -215.756744)
			(xy 300.844966 -215.76538) (xy 300.844966 -215.765634) (xy 300.849792 -215.773) (xy 300.854866 -215.779928)
			(xy 300.868626 -215.790185) (xy 300.876716 -215.793066) (xy 300.87824 -215.793574) (xy 300.879764 -215.794082)
			(xy 300.896274 -215.797892) (xy 300.89729 -215.798146) (xy 300.923103 -215.803771) (xy 300.972978 -215.821191)
			(xy 301.019972 -215.845327) (xy 301.063186 -215.875716) (xy 301.101794 -215.911778) (xy 301.135056 -215.952822)
			(xy 301.162337 -215.998063) (xy 301.173134 -216.022174) (xy 301.176991 -216.031346) (xy 301.183853 -216.050024)
			(xy 301.18685 -216.059512) (xy 301.188628 -216.065354) (xy 301.191676 -216.07018) (xy 301.199042 -216.079578)
			(xy 301.260764 -216.1413) (xy 301.266779 -216.146025) (xy 301.28087 -216.151953) (xy 301.28845 -216.152984)
			(xy 301.710598 -216.152984) (xy 301.719234 -216.153238) (xy 301.827184 -216.153238) (xy 301.832139 -216.153355)
			(xy 301.841862 -216.155269) (xy 301.846488 -216.157048) (xy 301.855632 -216.160858) (xy 301.86249 -216.167716)
			(xy 301.862998 -216.168224) (xy 301.938944 -216.24417) (xy 301.945294 -216.250266) (xy 301.995586 -216.300558)
			(xy 302.097948 -216.403174) (xy 302.104021 -216.40837) (xy 302.118507 -216.415102) (xy 302.126396 -216.416382)
			(xy 302.130714 -216.416636) (xy 302.756316 -216.416636) (xy 302.761142 -216.416382) (xy 302.773535 -216.414606)
			(xy 302.794427 -216.400867) (xy 302.80102 -216.39022) (xy 302.802544 -216.387172) (xy 302.802798 -216.38641)
			(xy 302.805254 -216.381083) (xy 302.807936 -216.369667) (xy 302.808132 -216.363804) (xy 302.808132 -216.363042)
			(xy 302.80788 -216.355862) (xy 302.803876 -216.342072) (xy 302.800258 -216.335864) (xy 302.797464 -216.331546)
			(xy 302.792892 -216.326974) (xy 302.79086 -216.324942) (xy 302.417226 -215.951308) (xy 302.408336 -215.94445)
			(xy 302.39335 -215.935306) (xy 302.387762 -215.933528) (xy 302.362577 -215.924828) (xy 302.314709 -215.901426)
			(xy 302.270561 -215.871595) (xy 302.23099 -215.835914) (xy 302.196767 -215.795076) (xy 302.168555 -215.749875)
			(xy 302.146903 -215.701191) (xy 302.132232 -215.649968) (xy 302.124827 -215.597203) (xy 302.124364 -215.570562)
			(xy 302.124852 -215.543312) (xy 302.132613 -215.489367) (xy 302.147971 -215.437075) (xy 302.170614 -215.387501)
			(xy 302.200081 -215.341653) (xy 302.235772 -215.300465) (xy 302.276961 -215.264775) (xy 302.322809 -215.235309)
			(xy 302.372384 -215.212668) (xy 302.424676 -215.197311) (xy 302.478622 -215.189552) (xy 302.505872 -215.189054)
			(xy 302.532795 -215.189514) (xy 302.586108 -215.197077) (xy 302.63783 -215.212056) (xy 302.686933 -215.234155)
			(xy 302.732443 -215.262935) (xy 302.773457 -215.297825) (xy 302.809162 -215.338132) (xy 302.838848 -215.383056)
			(xy 302.858032 -215.423496) (xy 322.103748 -215.423496) (xy 322.107819 -215.367874) (xy 322.119945 -215.313437)
			(xy 322.139868 -215.261346) (xy 322.167164 -215.212711) (xy 322.20125 -215.168568) (xy 322.241399 -215.129859)
			(xy 322.286757 -215.097408) (xy 322.336357 -215.071907) (xy 322.389141 -215.0539) (xy 322.443984 -215.04377)
			(xy 322.499718 -215.041733) (xy 322.555155 -215.047833) (xy 322.609112 -215.061939) (xy 322.660441 -215.083751)
			(xy 322.708047 -215.112805) (xy 322.750915 -215.14848) (xy 322.788132 -215.190017) (xy 322.818905 -215.23653)
			(xy 322.842577 -215.287027) (xy 322.858645 -215.340434) (xy 322.866765 -215.39561) (xy 322.867274 -215.423496)
			(xy 322.866765 -215.451382) (xy 322.864103 -215.46947) (xy 325.506332 -215.46947) (xy 325.510403 -215.413848)
			(xy 325.522529 -215.359411) (xy 325.542452 -215.30732) (xy 325.569748 -215.258685) (xy 325.603834 -215.214542)
			(xy 325.643983 -215.175833) (xy 325.689341 -215.143382) (xy 325.738941 -215.117881) (xy 325.791725 -215.099874)
			(xy 325.846568 -215.089744) (xy 325.902302 -215.087707) (xy 325.957739 -215.093807) (xy 326.011696 -215.107913)
			(xy 326.063025 -215.129725) (xy 326.110631 -215.158779) (xy 326.153499 -215.194454) (xy 326.190716 -215.235991)
			(xy 326.221489 -215.282504) (xy 326.245161 -215.333001) (xy 326.261229 -215.386408) (xy 326.269349 -215.441584)
			(xy 326.269858 -215.46947) (xy 326.269349 -215.497356) (xy 326.261229 -215.552532) (xy 326.245161 -215.605939)
			(xy 326.221489 -215.656436) (xy 326.190716 -215.702949) (xy 326.153499 -215.744486) (xy 326.110631 -215.780161)
			(xy 326.063025 -215.809215) (xy 326.011696 -215.831027) (xy 325.957739 -215.845133) (xy 325.902302 -215.851233)
			(xy 325.846568 -215.849196) (xy 325.791725 -215.839066) (xy 325.738941 -215.821059) (xy 325.689341 -215.795558)
			(xy 325.643983 -215.763107) (xy 325.603834 -215.724398) (xy 325.569748 -215.680255) (xy 325.542452 -215.63162)
			(xy 325.522529 -215.579529) (xy 325.510403 -215.525092) (xy 325.506332 -215.46947) (xy 322.864103 -215.46947)
			(xy 322.858645 -215.506558) (xy 322.842577 -215.559965) (xy 322.818905 -215.610462) (xy 322.788132 -215.656975)
			(xy 322.750915 -215.698512) (xy 322.708047 -215.734187) (xy 322.660441 -215.763241) (xy 322.609112 -215.785053)
			(xy 322.555155 -215.799159) (xy 322.499718 -215.805259) (xy 322.443984 -215.803222) (xy 322.389141 -215.793092)
			(xy 322.336357 -215.775085) (xy 322.286757 -215.749584) (xy 322.241399 -215.717133) (xy 322.20125 -215.678424)
			(xy 322.167164 -215.634281) (xy 322.139868 -215.585646) (xy 322.119945 -215.533555) (xy 322.107819 -215.479118)
			(xy 322.103748 -215.423496) (xy 302.858032 -215.423496) (xy 302.861927 -215.431706) (xy 302.870362 -215.457278)
			(xy 302.872394 -215.463882) (xy 302.875696 -215.469216) (xy 302.880268 -215.475566) (xy 303.206404 -215.801702)
			(xy 303.209491 -215.804706) (xy 303.216515 -215.809693) (xy 303.220374 -215.811608) (xy 310.237378 -218.718384)
			(xy 310.243156 -218.720232) (xy 310.255229 -218.72138) (xy 310.261254 -218.72067) (xy 310.269295 -218.719219)
			(xy 310.283927 -218.711962) (xy 310.289956 -218.706446) (xy 312.096404 -216.899998) (xy 312.103803 -216.893152)
			(xy 312.122401 -216.88542) (xy 312.132472 -216.885012) (xy 324.596252 -216.885012) (xy 324.5993 -216.884758)
			(xy 324.600316 -216.884758) (xy 324.610534 -216.883458) (xy 324.628757 -216.873895) (xy 324.635622 -216.866216)
			(xy 324.641718 -216.858596) (xy 324.645274 -216.854532) (xy 324.652386 -216.84742) (xy 324.655688 -216.842086)
			(xy 324.655942 -216.841578) (xy 324.670983 -216.817704) (xy 324.706986 -216.774256) (xy 324.748993 -216.736582)
			(xy 324.796089 -216.705502) (xy 324.847246 -216.681695) (xy 324.901352 -216.665679) (xy 324.957225 -216.657802)
			(xy 325.01365 -216.658237) (xy 325.069395 -216.666974) (xy 325.123247 -216.683822) (xy 325.174032 -216.708415)
			(xy 325.220643 -216.740216) (xy 325.262064 -216.778533) (xy 325.297393 -216.822531) (xy 325.312024 -216.846658)
			(xy 325.315326 -216.852246) (xy 325.32066 -216.85758) (xy 325.325486 -216.86266) (xy 325.354442 -216.87917)
			(xy 325.359567 -216.881682) (xy 325.370591 -216.884633) (xy 325.376286 -216.885012) (xy 325.527162 -216.885012)
			(xy 325.53656 -216.883996) (xy 325.537068 -216.883996) (xy 325.544228 -216.882293) (xy 325.557257 -216.875463)
			(xy 325.562722 -216.870534) (xy 326.123046 -216.31021) (xy 326.12711 -216.304368) (xy 326.132952 -216.292684)
			(xy 326.135492 -216.285064) (xy 326.135492 -216.276936) (xy 326.136 -216.259918) (xy 326.136 -216.25941)
			(xy 326.138794 -216.2302) (xy 326.142339 -216.206578) (xy 326.154553 -216.1604) (xy 326.172434 -216.116106)
			(xy 326.183752 -216.095072) (xy 326.19793 -216.070725) (xy 326.232339 -216.026114) (xy 326.272936 -215.987049)
			(xy 326.318836 -215.95438) (xy 326.369042 -215.928817) (xy 326.422462 -215.910916) (xy 326.477934 -215.901067)
			(xy 326.506078 -215.899746) (xy 326.516238 -215.899238) (xy 326.544432 -215.886538) (xy 326.552052 -215.881204)
			(xy 328.155046 -214.27821) (xy 328.15911 -214.272368) (xy 328.164952 -214.260684) (xy 328.167492 -214.253064)
			(xy 328.167492 -214.244936) (xy 328.168 -214.227918) (xy 328.168 -214.22741) (xy 328.170794 -214.1982)
			(xy 328.174339 -214.174578) (xy 328.186553 -214.1284) (xy 328.204434 -214.084106) (xy 328.215752 -214.063072)
			(xy 328.22993 -214.038725) (xy 328.264339 -213.994114) (xy 328.304936 -213.955049) (xy 328.350836 -213.92238)
			(xy 328.401042 -213.896817) (xy 328.454462 -213.878916) (xy 328.509934 -213.869067) (xy 328.538078 -213.867746)
			(xy 328.548238 -213.867238) (xy 328.576432 -213.854538) (xy 328.584052 -213.849204) (xy 328.645012 -213.788244)
			(xy 328.651697 -213.78083) (xy 328.659298 -213.762393) (xy 328.659307 -213.74245) (xy 328.651721 -213.724006)
			(xy 328.645012 -213.716616) (xy 327.07199 -212.143594) (xy 327.061011 -212.133357) (xy 327.034556 -212.119202)
			(xy 327.005131 -212.113341) (xy 326.975272 -212.11628) (xy 326.947553 -212.127764) (xy 326.924365 -212.146804)
			(xy 326.907706 -212.171757) (xy 326.899014 -212.200474) (xy 326.898508 -212.215476) (xy 326.898508 -212.21573)
			(xy 326.898508 -212.217) (xy 326.898022 -212.244251) (xy 326.890266 -212.298199) (xy 326.874911 -212.350494)
			(xy 326.852269 -212.400071) (xy 326.822803 -212.445921) (xy 326.787112 -212.487112) (xy 326.745921 -212.522803)
			(xy 326.700071 -212.552269) (xy 326.650494 -212.574911) (xy 326.598199 -212.590266) (xy 326.544251 -212.598022)
			(xy 326.489749 -212.598022) (xy 326.435801 -212.590266) (xy 326.383506 -212.574911) (xy 326.333929 -212.552269)
			(xy 326.288079 -212.522803) (xy 326.246888 -212.487112) (xy 326.211197 -212.445921) (xy 326.181731 -212.400071)
			(xy 326.159089 -212.350494) (xy 326.143734 -212.298199) (xy 326.135978 -212.244251) (xy 326.135492 -212.217)
			(xy 326.135996 -212.189264) (xy 326.144041 -212.134377) (xy 326.159945 -212.081232) (xy 326.183375 -212.03095)
			(xy 326.213837 -211.984589) (xy 326.250688 -211.943125) (xy 326.293153 -211.907432) (xy 326.340338 -211.878262)
			(xy 326.391248 -211.85623) (xy 326.444812 -211.841799) (xy 326.472296 -211.838032) (xy 326.486266 -211.836508)
			(xy 326.517 -211.835238) (xy 326.517254 -211.835238) (xy 326.54506 -211.835731) (xy 326.600084 -211.843785)
			(xy 326.653356 -211.859743) (xy 326.703746 -211.883267) (xy 326.750187 -211.913859) (xy 326.771254 -211.932012)
			(xy 326.773286 -211.93379) (xy 326.774302 -211.93506) (xy 326.785263 -211.945119) (xy 326.811576 -211.958971)
			(xy 326.840767 -211.96464) (xy 326.870352 -211.961645) (xy 326.897814 -211.950239) (xy 326.920816 -211.931395)
			(xy 326.937402 -211.906714) (xy 326.946161 -211.878297) (xy 326.946768 -211.863432) (xy 326.946768 -210.520534)
			(xy 326.945501 -210.511802) (xy 326.937893 -210.495896) (xy 326.925377 -210.483476) (xy 326.917558 -210.479386)
			(xy 326.901302 -210.472782) (xy 326.900794 -210.472782) (xy 326.839326 -210.446874) (xy 326.834639 -210.445074)
			(xy 326.824787 -210.443152) (xy 326.819768 -210.443064) (xy 326.784462 -210.457542) (xy 326.777604 -210.463892)
			(xy 326.756307 -210.483107) (xy 326.709025 -210.515577) (xy 326.657414 -210.540603) (xy 326.602639 -210.557621)
			(xy 326.545933 -210.566246) (xy 326.517254 -210.566762) (xy 326.516746 -210.566762) (xy 326.49922 -210.566254)
			(xy 326.48779 -210.565492) (xy 326.459392 -210.562785) (xy 326.403797 -210.550008) (xy 326.350726 -210.529095)
			(xy 326.301361 -210.50051) (xy 326.256804 -210.464891) (xy 326.218048 -210.423034) (xy 326.185959 -210.375872)
			(xy 326.161253 -210.324456) (xy 326.144479 -210.269934) (xy 326.136013 -210.213522) (xy 326.135492 -210.185)
			(xy 326.135978 -210.157749) (xy 326.143734 -210.103801) (xy 326.159089 -210.051506) (xy 326.181731 -210.001929)
			(xy 326.211197 -209.956079) (xy 326.246888 -209.914888) (xy 326.288079 -209.879197) (xy 326.333929 -209.849731)
			(xy 326.383506 -209.827089) (xy 326.435801 -209.811734) (xy 326.489749 -209.803978) (xy 326.517 -209.803492)
			(xy 326.545596 -209.804002) (xy 326.602149 -209.812537) (xy 326.656794 -209.829416) (xy 326.708309 -209.854261)
			(xy 326.755539 -209.886516) (xy 326.776842 -209.9056) (xy 326.777096 -209.905854) (xy 326.779636 -209.90814)
			(xy 326.789796 -209.915506) (xy 326.793352 -209.917284) (xy 326.80021 -209.92084) (xy 326.804201 -209.922658)
			(xy 326.812627 -209.925086) (xy 326.816974 -209.925666) (xy 326.826626 -209.926682) (xy 326.836024 -209.924142)
			(xy 326.840596 -209.922872) (xy 326.872346 -209.90941) (xy 326.91832 -209.890106) (xy 326.925973 -209.886027)
			(xy 326.938175 -209.873722) (xy 326.94558 -209.858054) (xy 326.946768 -209.849466) (xy 326.946768 -208.210404)
			(xy 326.945712 -208.202834) (xy 326.939763 -208.188763) (xy 326.935084 -208.182718) (xy 326.878442 -208.126076)
			(xy 326.871292 -208.120506) (xy 326.854261 -208.114344) (xy 326.836151 -208.114486) (xy 326.819218 -208.120913)
			(xy 326.812148 -208.126584) (xy 326.8091 -208.129632) (xy 326.805809 -208.133109) (xy 326.800433 -208.141031)
			(xy 326.798432 -208.14538) (xy 326.79513 -208.153254) (xy 326.794622 -208.163668) (xy 326.793416 -208.190404)
			(xy 326.784445 -208.243166) (xy 326.76819 -208.294156) (xy 326.744968 -208.342375) (xy 326.715237 -208.386875)
			(xy 326.679579 -208.426785) (xy 326.638695 -208.46132) (xy 326.593385 -208.489804) (xy 326.54454 -208.511677)
			(xy 326.493118 -208.52651) (xy 326.440127 -208.534011) (xy 326.413368 -208.534508) (xy 326.386118 -208.53402)
			(xy 326.332174 -208.52626) (xy 326.279883 -208.510902) (xy 326.23031 -208.488259) (xy 326.184463 -208.458792)
			(xy 326.143277 -208.4231) (xy 326.107589 -208.381911) (xy 326.078126 -208.336062) (xy 326.055487 -208.286487)
			(xy 326.040133 -208.234195) (xy 326.032378 -208.18025) (xy 326.03186 -208.153) (xy 326.032391 -208.124475)
			(xy 326.040886 -208.06806) (xy 326.057687 -208.013539) (xy 326.082418 -207.962128) (xy 326.114529 -207.914972)
			(xy 326.153303 -207.873123) (xy 326.197877 -207.837514) (xy 326.247256 -207.80894) (xy 326.300339 -207.788036)
			(xy 326.328024 -207.781144) (xy 326.334628 -207.77962) (xy 326.346566 -207.77327) (xy 326.351392 -207.768698)
			(xy 326.35404 -207.766079) (xy 326.358626 -207.760212) (xy 326.360536 -207.757014) (xy 326.365362 -207.745584)
			(xy 326.377046 -207.704944) (xy 326.377046 -207.704436) (xy 326.386698 -207.671162) (xy 326.386698 -207.670908)
			(xy 326.387206 -207.668876) (xy 326.389171 -207.658752) (xy 326.385772 -207.638429) (xy 326.380602 -207.629506)
			(xy 326.377554 -207.624934) (xy 325.640446 -206.88808) (xy 325.63435 -206.88173) (xy 325.558404 -206.805784)
			(xy 325.557896 -206.805276) (xy 325.551038 -206.798418) (xy 325.547228 -206.789274) (xy 325.545457 -206.784646)
			(xy 325.543543 -206.774924) (xy 325.543418 -206.76997) (xy 325.543418 -206.66202) (xy 325.543164 -206.653384)
			(xy 325.543164 -201.962512) (xy 325.543418 -201.953876) (xy 325.543418 -201.845926) (xy 325.543534 -201.840971)
			(xy 325.545449 -201.831248) (xy 325.547228 -201.826622) (xy 325.551038 -201.817478) (xy 325.557896 -201.81062)
			(xy 325.558404 -201.810112) (xy 325.63435 -201.734166) (xy 325.640446 -201.727816) (xy 335.212944 -192.155572)
			(xy 335.215649 -192.152721) (xy 335.220241 -192.146342) (xy 335.222088 -192.142872) (xy 335.224673 -192.137446)
			(xy 335.227501 -192.125766) (xy 335.227676 -192.119758) (xy 335.227676 -186.528964) (xy 335.227151 -186.513973)
			(xy 335.218457 -186.48528) (xy 335.201799 -186.460352) (xy 335.178616 -186.441341) (xy 335.150909 -186.429887)
			(xy 335.121069 -186.42698) (xy 335.106264 -186.429396) (xy 335.08785 -186.432828) (xy 335.050572 -186.436517)
			(xy 335.031842 -186.436762) (xy 335.026 -186.436762) (xy 334.998731 -186.436276) (xy 334.944747 -186.428514)
			(xy 334.892417 -186.413149) (xy 334.842807 -186.390492) (xy 334.796926 -186.361006) (xy 334.755709 -186.325291)
			(xy 334.719994 -186.284074) (xy 334.690508 -186.238193) (xy 334.667851 -186.188583) (xy 334.652486 -186.136253)
			(xy 334.644724 -186.082269) (xy 334.644724 -186.027731) (xy 334.652486 -185.973747) (xy 334.667851 -185.921417)
			(xy 334.690508 -185.871807) (xy 334.719994 -185.825926) (xy 334.755709 -185.784709) (xy 334.796926 -185.748994)
			(xy 334.842807 -185.719508) (xy 334.892417 -185.696851) (xy 334.944747 -185.681486) (xy 334.998731 -185.673724)
			(xy 335.026 -185.673238) (xy 335.038738 -185.673316) (xy 335.064159 -185.67497) (xy 335.0768 -185.67654)
			(xy 335.104994 -185.681366) (xy 335.119877 -185.683966) (xy 335.14996 -185.681333) (xy 335.177961 -185.670028)
			(xy 335.20144 -185.651037) (xy 335.218348 -185.626017) (xy 335.227212 -185.59715) (xy 335.227676 -185.582052)
			(xy 335.227676 -185.512964) (xy 335.227151 -185.497973) (xy 335.218457 -185.46928) (xy 335.201799 -185.444352)
			(xy 335.178616 -185.425341) (xy 335.150909 -185.413887) (xy 335.121069 -185.41098) (xy 335.106264 -185.413396)
			(xy 335.08785 -185.416828) (xy 335.050572 -185.420517) (xy 335.031842 -185.420762) (xy 335.026 -185.420762)
			(xy 334.998731 -185.420276) (xy 334.944747 -185.412514) (xy 334.892417 -185.397149) (xy 334.842807 -185.374492)
			(xy 334.796926 -185.345006) (xy 334.755709 -185.309291) (xy 334.719994 -185.268074) (xy 334.690508 -185.222193)
			(xy 334.667851 -185.172583) (xy 334.652486 -185.120253) (xy 334.644724 -185.066269) (xy 334.644724 -185.011731)
			(xy 334.652486 -184.957747) (xy 334.667851 -184.905417) (xy 334.690508 -184.855807) (xy 334.719994 -184.809926)
			(xy 334.755709 -184.768709) (xy 334.796926 -184.732994) (xy 334.842807 -184.703508) (xy 334.892417 -184.680851)
			(xy 334.944747 -184.665486) (xy 334.998731 -184.657724) (xy 335.026 -184.657238) (xy 335.038738 -184.657316)
			(xy 335.064159 -184.65897) (xy 335.0768 -184.66054) (xy 335.104994 -184.665366) (xy 335.119877 -184.667966)
			(xy 335.14996 -184.665333) (xy 335.177961 -184.654028) (xy 335.20144 -184.635037) (xy 335.218348 -184.610017)
			(xy 335.227212 -184.58115) (xy 335.227676 -184.566052) (xy 335.227676 -184.496964) (xy 335.227151 -184.481973)
			(xy 335.218457 -184.45328) (xy 335.201799 -184.428352) (xy 335.178616 -184.409341) (xy 335.150909 -184.397887)
			(xy 335.121069 -184.39498) (xy 335.106264 -184.397396) (xy 335.08785 -184.400828) (xy 335.050572 -184.404517)
			(xy 335.031842 -184.404762) (xy 335.026 -184.404762) (xy 334.998731 -184.404276) (xy 334.944747 -184.396514)
			(xy 334.892417 -184.381149) (xy 334.842807 -184.358492) (xy 334.796926 -184.329006) (xy 334.755709 -184.293291)
			(xy 334.719994 -184.252074) (xy 334.690508 -184.206193) (xy 334.667851 -184.156583) (xy 334.652486 -184.104253)
			(xy 334.644724 -184.050269) (xy 334.644724 -183.995731) (xy 334.652486 -183.941747) (xy 334.667851 -183.889417)
			(xy 334.690508 -183.839807) (xy 334.719994 -183.793926) (xy 334.755709 -183.752709) (xy 334.796926 -183.716994)
			(xy 334.842807 -183.687508) (xy 334.892417 -183.664851) (xy 334.944747 -183.649486) (xy 334.998731 -183.641724)
			(xy 335.026 -183.641238) (xy 335.038738 -183.641316) (xy 335.064159 -183.64297) (xy 335.0768 -183.64454)
			(xy 335.104994 -183.649366) (xy 335.119877 -183.651966) (xy 335.14996 -183.649333) (xy 335.177961 -183.638028)
			(xy 335.20144 -183.619037) (xy 335.218348 -183.594017) (xy 335.227212 -183.56515) (xy 335.227676 -183.550052)
			(xy 335.227676 -182.464964) (xy 335.227151 -182.449973) (xy 335.218457 -182.42128) (xy 335.201799 -182.396352)
			(xy 335.178616 -182.377341) (xy 335.150909 -182.365887) (xy 335.121069 -182.36298) (xy 335.106264 -182.365396)
			(xy 335.08785 -182.368828) (xy 335.050572 -182.372517) (xy 335.031842 -182.372762) (xy 335.026 -182.372762)
			(xy 334.998731 -182.372276) (xy 334.944747 -182.364514) (xy 334.892417 -182.349149) (xy 334.842807 -182.326492)
			(xy 334.796926 -182.297006) (xy 334.755709 -182.261291) (xy 334.719994 -182.220074) (xy 334.690508 -182.174193)
			(xy 334.667851 -182.124583) (xy 334.652486 -182.072253) (xy 334.644724 -182.018269) (xy 334.644724 -181.963731)
			(xy 334.652486 -181.909747) (xy 334.667851 -181.857417) (xy 334.690508 -181.807807) (xy 334.719994 -181.761926)
			(xy 334.755709 -181.720709) (xy 334.796926 -181.684994) (xy 334.842807 -181.655508) (xy 334.892417 -181.632851)
			(xy 334.944747 -181.617486) (xy 334.998731 -181.609724) (xy 335.026 -181.609238) (xy 335.038738 -181.609316)
			(xy 335.064159 -181.61097) (xy 335.0768 -181.61254) (xy 335.094326 -181.615334) (xy 335.109009 -181.617472)
			(xy 335.138481 -181.614143) (xy 335.165752 -181.602485) (xy 335.188525 -181.583483) (xy 335.204877 -181.55874)
			(xy 335.21343 -181.530341) (xy 335.21396 -181.515512) (xy 335.21396 -181.450488) (xy 335.21341 -181.435666)
			(xy 335.204824 -181.407289) (xy 335.188465 -181.382565) (xy 335.165705 -181.363567) (xy 335.138454 -181.35189)
			(xy 335.109 -181.348515) (xy 335.094326 -181.350666) (xy 335.07758 -181.353513) (xy 335.043747 -181.356567)
			(xy 335.026762 -181.356762) (xy 335.026 -181.356762) (xy 334.998731 -181.356276) (xy 334.944747 -181.348514)
			(xy 334.892417 -181.333149) (xy 334.842807 -181.310492) (xy 334.796926 -181.281006) (xy 334.755709 -181.245291)
			(xy 334.719994 -181.204074) (xy 334.690508 -181.158193) (xy 334.667851 -181.108583) (xy 334.652486 -181.056253)
			(xy 334.644724 -181.002269) (xy 334.644724 -180.947731) (xy 334.652486 -180.893747) (xy 334.667851 -180.841417)
			(xy 334.690508 -180.791807) (xy 334.719994 -180.745926) (xy 334.755709 -180.704709) (xy 334.796926 -180.668994)
			(xy 334.842807 -180.639508) (xy 334.892417 -180.616851) (xy 334.944747 -180.601486) (xy 334.998731 -180.593724)
			(xy 335.026 -180.593238) (xy 335.052665 -180.593707) (xy 335.105475 -180.60113) (xy 335.156742 -180.615818)
			(xy 335.205471 -180.637486) (xy 335.250717 -180.665713) (xy 335.291603 -180.699953) (xy 335.327336 -180.739541)
			(xy 335.357222 -180.783709) (xy 335.380682 -180.831601) (xy 335.397261 -180.882288) (xy 335.402428 -180.908452)
			(xy 335.402428 -180.90896) (xy 335.403698 -180.916072) (xy 335.403698 -180.91658) (xy 335.413858 -180.935376)
			(xy 335.415658 -180.938488) (xy 335.419996 -180.944221) (xy 335.422494 -180.946806) (xy 335.445862 -180.970174)
			(xy 335.449267 -180.973224) (xy 335.456933 -180.978204) (xy 335.461102 -180.98008) (xy 335.506568 -180.995828)
			(xy 335.507076 -180.995828) (xy 335.513934 -180.998368) (xy 335.52602 -181.001964) (xy 335.550928 -180.998233)
			(xy 335.561432 -180.991256) (xy 336.715608 -179.83708) (xy 336.717863 -179.834094) (xy 336.721563 -179.827591)
			(xy 336.722974 -179.824126) (xy 336.72452 -179.819779) (xy 336.726187 -179.810705) (xy 336.726276 -179.806092)
			(xy 336.726276 -178.12893) (xy 336.724752 -178.116738) (xy 336.723228 -178.110642) (xy 336.720434 -178.105054)
			(xy 336.706534 -178.077454) (xy 336.686857 -178.018877) (xy 336.676873 -177.957896) (xy 336.676238 -177.927)
			(xy 336.676724 -177.899731) (xy 336.684486 -177.845747) (xy 336.699851 -177.793417) (xy 336.722508 -177.743807)
			(xy 336.751994 -177.697926) (xy 336.787709 -177.656709) (xy 336.828926 -177.620994) (xy 336.874807 -177.591508)
			(xy 336.924417 -177.568851) (xy 336.976747 -177.553486) (xy 337.030731 -177.545724) (xy 337.058 -177.545238)
			(xy 337.085108 -177.545713) (xy 337.138778 -177.553383) (xy 337.190824 -177.568569) (xy 337.240198 -177.590966)
			(xy 337.285906 -177.620123) (xy 337.327029 -177.655453) (xy 337.362741 -177.696246) (xy 337.392322 -177.74168)
			(xy 337.415178 -177.790843) (xy 337.430848 -177.842745) (xy 337.439018 -177.896342) (xy 337.439762 -177.923444)
			(xy 337.439762 -177.927) (xy 339.469982 -177.927) (xy 339.474053 -177.871378) (xy 339.486179 -177.816941)
			(xy 339.506102 -177.76485) (xy 339.533398 -177.716215) (xy 339.567484 -177.672072) (xy 339.607633 -177.633363)
			(xy 339.652991 -177.600912) (xy 339.702591 -177.575411) (xy 339.755375 -177.557404) (xy 339.810218 -177.547274)
			(xy 339.865952 -177.545237) (xy 339.872886 -177.546) (xy 354.455982 -177.546) (xy 354.460053 -177.490378)
			(xy 354.472179 -177.435941) (xy 354.492102 -177.38385) (xy 354.519398 -177.335215) (xy 354.553484 -177.291072)
			(xy 354.593633 -177.252363) (xy 354.638991 -177.219912) (xy 354.688591 -177.194411) (xy 354.741375 -177.176404)
			(xy 354.796218 -177.166274) (xy 354.851952 -177.164237) (xy 354.907389 -177.170337) (xy 354.961346 -177.184443)
			(xy 355.012675 -177.206255) (xy 355.060281 -177.235309) (xy 355.103149 -177.270984) (xy 355.140366 -177.312521)
			(xy 355.171139 -177.359034) (xy 355.194811 -177.409531) (xy 355.210879 -177.462938) (xy 355.218999 -177.518114)
			(xy 355.219508 -177.546) (xy 355.218999 -177.573886) (xy 355.212636 -177.61712) (xy 364.751364 -177.61712)
			(xy 364.755435 -177.561498) (xy 364.767561 -177.507061) (xy 364.787484 -177.45497) (xy 364.81478 -177.406335)
			(xy 364.848866 -177.362192) (xy 364.889015 -177.323483) (xy 364.934373 -177.291032) (xy 364.983973 -177.265531)
			(xy 365.036757 -177.247524) (xy 365.0916 -177.237394) (xy 365.147334 -177.235357) (xy 365.202771 -177.241457)
			(xy 365.256728 -177.255563) (xy 365.308057 -177.277375) (xy 365.355663 -177.306429) (xy 365.398531 -177.342104)
			(xy 365.435748 -177.383641) (xy 365.466521 -177.430154) (xy 365.490193 -177.480651) (xy 365.506261 -177.534058)
			(xy 365.514381 -177.589234) (xy 365.51489 -177.61712) (xy 365.514381 -177.645006) (xy 365.506261 -177.700182)
			(xy 365.490193 -177.753589) (xy 365.466521 -177.804086) (xy 365.435748 -177.850599) (xy 365.398531 -177.892136)
			(xy 365.355663 -177.927811) (xy 365.308057 -177.956865) (xy 365.256728 -177.978677) (xy 365.202771 -177.992783)
			(xy 365.147334 -177.998883) (xy 365.0916 -177.996846) (xy 365.036757 -177.986716) (xy 364.983973 -177.968709)
			(xy 364.934373 -177.943208) (xy 364.889015 -177.910757) (xy 364.848866 -177.872048) (xy 364.81478 -177.827905)
			(xy 364.787484 -177.77927) (xy 364.767561 -177.727179) (xy 364.755435 -177.672742) (xy 364.751364 -177.61712)
			(xy 355.212636 -177.61712) (xy 355.210879 -177.629062) (xy 355.194811 -177.682469) (xy 355.171139 -177.732966)
			(xy 355.140366 -177.779479) (xy 355.103149 -177.821016) (xy 355.060281 -177.856691) (xy 355.012675 -177.885745)
			(xy 354.961346 -177.907557) (xy 354.907389 -177.921663) (xy 354.851952 -177.927763) (xy 354.796218 -177.925726)
			(xy 354.741375 -177.915596) (xy 354.688591 -177.897589) (xy 354.638991 -177.872088) (xy 354.593633 -177.839637)
			(xy 354.553484 -177.800928) (xy 354.519398 -177.756785) (xy 354.492102 -177.70815) (xy 354.472179 -177.656059)
			(xy 354.460053 -177.601622) (xy 354.455982 -177.546) (xy 339.872886 -177.546) (xy 339.921389 -177.551337)
			(xy 339.975346 -177.565443) (xy 340.026675 -177.587255) (xy 340.074281 -177.616309) (xy 340.117149 -177.651984)
			(xy 340.154366 -177.693521) (xy 340.185139 -177.740034) (xy 340.208811 -177.790531) (xy 340.224879 -177.843938)
			(xy 340.232999 -177.899114) (xy 340.233508 -177.927) (xy 340.232999 -177.954886) (xy 340.224879 -178.010062)
			(xy 340.208811 -178.063469) (xy 340.185139 -178.113966) (xy 340.154366 -178.160479) (xy 340.117149 -178.202016)
			(xy 340.074281 -178.237691) (xy 340.026675 -178.266745) (xy 339.975346 -178.288557) (xy 339.921389 -178.302663)
			(xy 339.865952 -178.308763) (xy 339.810218 -178.306726) (xy 339.755375 -178.296596) (xy 339.702591 -178.278589)
			(xy 339.652991 -178.253088) (xy 339.607633 -178.220637) (xy 339.567484 -178.181928) (xy 339.533398 -178.137785)
			(xy 339.506102 -178.08915) (xy 339.486179 -178.037059) (xy 339.474053 -177.982622) (xy 339.469982 -177.927)
			(xy 337.439762 -177.927) (xy 337.439142 -177.957896) (xy 337.429145 -178.018876) (xy 337.409459 -178.07745)
			(xy 337.395566 -178.105054) (xy 337.392772 -178.110642) (xy 337.391248 -178.116738) (xy 337.389724 -178.12893)
			(xy 337.389724 -178.432968) (xy 341.689434 -178.432968) (xy 341.693505 -178.377346) (xy 341.705631 -178.322909)
			(xy 341.725554 -178.270818) (xy 341.75285 -178.222183) (xy 341.786936 -178.17804) (xy 341.827085 -178.139331)
			(xy 341.872443 -178.10688) (xy 341.922043 -178.081379) (xy 341.974827 -178.063372) (xy 342.02967 -178.053242)
			(xy 342.085404 -178.051205) (xy 342.140841 -178.057305) (xy 342.194798 -178.071411) (xy 342.246127 -178.093223)
			(xy 342.293733 -178.122277) (xy 342.336601 -178.157952) (xy 342.373818 -178.199489) (xy 342.404591 -178.246002)
			(xy 342.428263 -178.296499) (xy 342.4305 -178.303936) (xy 349.735392 -178.303936) (xy 349.739463 -178.248314)
			(xy 349.751589 -178.193877) (xy 349.771512 -178.141786) (xy 349.798808 -178.093151) (xy 349.832894 -178.049008)
			(xy 349.873043 -178.010299) (xy 349.918401 -177.977848) (xy 349.968001 -177.952347) (xy 350.020785 -177.93434)
			(xy 350.075628 -177.92421) (xy 350.131362 -177.922173) (xy 350.186799 -177.928273) (xy 350.240756 -177.942379)
			(xy 350.292085 -177.964191) (xy 350.339691 -177.993245) (xy 350.382559 -178.02892) (xy 350.405031 -178.054)
			(xy 357.757982 -178.054) (xy 357.762053 -177.998378) (xy 357.774179 -177.943941) (xy 357.794102 -177.89185)
			(xy 357.821398 -177.843215) (xy 357.855484 -177.799072) (xy 357.895633 -177.760363) (xy 357.940991 -177.727912)
			(xy 357.990591 -177.702411) (xy 358.043375 -177.684404) (xy 358.098218 -177.674274) (xy 358.153952 -177.672237)
			(xy 358.209389 -177.678337) (xy 358.263346 -177.692443) (xy 358.314675 -177.714255) (xy 358.362281 -177.743309)
			(xy 358.405149 -177.778984) (xy 358.442366 -177.820521) (xy 358.473139 -177.867034) (xy 358.496811 -177.917531)
			(xy 358.512879 -177.970938) (xy 358.520999 -178.026114) (xy 358.521508 -178.054) (xy 359.789982 -178.054)
			(xy 359.794053 -177.998378) (xy 359.806179 -177.943941) (xy 359.826102 -177.89185) (xy 359.853398 -177.843215)
			(xy 359.887484 -177.799072) (xy 359.927633 -177.760363) (xy 359.972991 -177.727912) (xy 360.022591 -177.702411)
			(xy 360.075375 -177.684404) (xy 360.130218 -177.674274) (xy 360.185952 -177.672237) (xy 360.241389 -177.678337)
			(xy 360.295346 -177.692443) (xy 360.346675 -177.714255) (xy 360.394281 -177.743309) (xy 360.437149 -177.778984)
			(xy 360.474366 -177.820521) (xy 360.505139 -177.867034) (xy 360.528811 -177.917531) (xy 360.544879 -177.970938)
			(xy 360.552999 -178.026114) (xy 360.553508 -178.054) (xy 360.552999 -178.081886) (xy 360.544879 -178.137062)
			(xy 360.528811 -178.190469) (xy 360.505139 -178.240966) (xy 360.487845 -178.267106) (xy 363.613444 -178.267106)
			(xy 363.617515 -178.211484) (xy 363.629641 -178.157047) (xy 363.649564 -178.104956) (xy 363.67686 -178.056321)
			(xy 363.710946 -178.012178) (xy 363.751095 -177.973469) (xy 363.796453 -177.941018) (xy 363.846053 -177.915517)
			(xy 363.898837 -177.89751) (xy 363.95368 -177.88738) (xy 364.009414 -177.885343) (xy 364.064851 -177.891443)
			(xy 364.118808 -177.905549) (xy 364.170137 -177.927361) (xy 364.217743 -177.956415) (xy 364.260611 -177.99209)
			(xy 364.297828 -178.033627) (xy 364.328601 -178.08014) (xy 364.352273 -178.130637) (xy 364.368341 -178.184044)
			(xy 364.376461 -178.23922) (xy 364.37697 -178.267106) (xy 364.376461 -178.294992) (xy 364.368341 -178.350168)
			(xy 364.352273 -178.403575) (xy 364.328601 -178.454072) (xy 364.297828 -178.500585) (xy 364.260611 -178.542122)
			(xy 364.217743 -178.577797) (xy 364.170137 -178.606851) (xy 364.118808 -178.628663) (xy 364.064851 -178.642769)
			(xy 364.009414 -178.648869) (xy 363.95368 -178.646832) (xy 363.898837 -178.636702) (xy 363.846053 -178.618695)
			(xy 363.796453 -178.593194) (xy 363.751095 -178.560743) (xy 363.710946 -178.522034) (xy 363.67686 -178.477891)
			(xy 363.649564 -178.429256) (xy 363.629641 -178.377165) (xy 363.617515 -178.322728) (xy 363.613444 -178.267106)
			(xy 360.487845 -178.267106) (xy 360.474366 -178.287479) (xy 360.437149 -178.329016) (xy 360.394281 -178.364691)
			(xy 360.346675 -178.393745) (xy 360.295346 -178.415557) (xy 360.241389 -178.429663) (xy 360.185952 -178.435763)
			(xy 360.130218 -178.433726) (xy 360.075375 -178.423596) (xy 360.022591 -178.405589) (xy 359.972991 -178.380088)
			(xy 359.927633 -178.347637) (xy 359.887484 -178.308928) (xy 359.853398 -178.264785) (xy 359.826102 -178.21615)
			(xy 359.806179 -178.164059) (xy 359.794053 -178.109622) (xy 359.789982 -178.054) (xy 358.521508 -178.054)
			(xy 358.520999 -178.081886) (xy 358.512879 -178.137062) (xy 358.496811 -178.190469) (xy 358.473139 -178.240966)
			(xy 358.442366 -178.287479) (xy 358.405149 -178.329016) (xy 358.362281 -178.364691) (xy 358.314675 -178.393745)
			(xy 358.263346 -178.415557) (xy 358.209389 -178.429663) (xy 358.153952 -178.435763) (xy 358.098218 -178.433726)
			(xy 358.043375 -178.423596) (xy 357.990591 -178.405589) (xy 357.940991 -178.380088) (xy 357.895633 -178.347637)
			(xy 357.855484 -178.308928) (xy 357.821398 -178.264785) (xy 357.794102 -178.21615) (xy 357.774179 -178.164059)
			(xy 357.762053 -178.109622) (xy 357.757982 -178.054) (xy 350.405031 -178.054) (xy 350.419776 -178.070457)
			(xy 350.450549 -178.11697) (xy 350.474221 -178.167467) (xy 350.490289 -178.220874) (xy 350.498409 -178.27605)
			(xy 350.498918 -178.303936) (xy 350.498409 -178.331822) (xy 350.490289 -178.386998) (xy 350.474221 -178.440405)
			(xy 350.450549 -178.490902) (xy 350.419776 -178.537415) (xy 350.397748 -178.562) (xy 354.455982 -178.562)
			(xy 354.460053 -178.506378) (xy 354.472179 -178.451941) (xy 354.492102 -178.39985) (xy 354.519398 -178.351215)
			(xy 354.553484 -178.307072) (xy 354.593633 -178.268363) (xy 354.638991 -178.235912) (xy 354.688591 -178.210411)
			(xy 354.741375 -178.192404) (xy 354.796218 -178.182274) (xy 354.851952 -178.180237) (xy 354.907389 -178.186337)
			(xy 354.961346 -178.200443) (xy 355.012675 -178.222255) (xy 355.060281 -178.251309) (xy 355.103149 -178.286984)
			(xy 355.140366 -178.328521) (xy 355.171139 -178.375034) (xy 355.194811 -178.425531) (xy 355.210879 -178.478938)
			(xy 355.218999 -178.534114) (xy 355.219508 -178.562) (xy 356.487982 -178.562) (xy 356.492053 -178.506378)
			(xy 356.504179 -178.451941) (xy 356.524102 -178.39985) (xy 356.551398 -178.351215) (xy 356.585484 -178.307072)
			(xy 356.625633 -178.268363) (xy 356.670991 -178.235912) (xy 356.720591 -178.210411) (xy 356.773375 -178.192404)
			(xy 356.828218 -178.182274) (xy 356.883952 -178.180237) (xy 356.939389 -178.186337) (xy 356.993346 -178.200443)
			(xy 357.044675 -178.222255) (xy 357.092281 -178.251309) (xy 357.135149 -178.286984) (xy 357.172366 -178.328521)
			(xy 357.203139 -178.375034) (xy 357.226811 -178.425531) (xy 357.242879 -178.478938) (xy 357.250999 -178.534114)
			(xy 357.251508 -178.562) (xy 357.250999 -178.589886) (xy 357.242879 -178.645062) (xy 357.226811 -178.698469)
			(xy 357.203139 -178.748966) (xy 357.172366 -178.795479) (xy 357.135149 -178.837016) (xy 357.092281 -178.872691)
			(xy 357.044675 -178.901745) (xy 356.993346 -178.923557) (xy 356.939389 -178.937663) (xy 356.883952 -178.943763)
			(xy 356.828218 -178.941726) (xy 356.773375 -178.931596) (xy 356.720591 -178.913589) (xy 356.670991 -178.888088)
			(xy 356.625633 -178.855637) (xy 356.585484 -178.816928) (xy 356.551398 -178.772785) (xy 356.524102 -178.72415)
			(xy 356.504179 -178.672059) (xy 356.492053 -178.617622) (xy 356.487982 -178.562) (xy 355.219508 -178.562)
			(xy 355.218999 -178.589886) (xy 355.210879 -178.645062) (xy 355.194811 -178.698469) (xy 355.171139 -178.748966)
			(xy 355.140366 -178.795479) (xy 355.103149 -178.837016) (xy 355.060281 -178.872691) (xy 355.012675 -178.901745)
			(xy 354.961346 -178.923557) (xy 354.907389 -178.937663) (xy 354.851952 -178.943763) (xy 354.796218 -178.941726)
			(xy 354.741375 -178.931596) (xy 354.688591 -178.913589) (xy 354.638991 -178.888088) (xy 354.593633 -178.855637)
			(xy 354.553484 -178.816928) (xy 354.519398 -178.772785) (xy 354.492102 -178.72415) (xy 354.472179 -178.672059)
			(xy 354.460053 -178.617622) (xy 354.455982 -178.562) (xy 350.397748 -178.562) (xy 350.382559 -178.578952)
			(xy 350.339691 -178.614627) (xy 350.292085 -178.643681) (xy 350.240756 -178.665493) (xy 350.186799 -178.679599)
			(xy 350.131362 -178.685699) (xy 350.075628 -178.683662) (xy 350.020785 -178.673532) (xy 349.968001 -178.655525)
			(xy 349.918401 -178.630024) (xy 349.873043 -178.597573) (xy 349.832894 -178.558864) (xy 349.798808 -178.514721)
			(xy 349.771512 -178.466086) (xy 349.751589 -178.413995) (xy 349.739463 -178.359558) (xy 349.735392 -178.303936)
			(xy 342.4305 -178.303936) (xy 342.444331 -178.349906) (xy 342.452451 -178.405082) (xy 342.45296 -178.432968)
			(xy 342.452451 -178.460854) (xy 342.444331 -178.51603) (xy 342.428263 -178.569437) (xy 342.404591 -178.619934)
			(xy 342.373818 -178.666447) (xy 342.336601 -178.707984) (xy 342.293733 -178.743659) (xy 342.246127 -178.772713)
			(xy 342.194798 -178.794525) (xy 342.140841 -178.808631) (xy 342.085404 -178.814731) (xy 342.02967 -178.812694)
			(xy 341.974827 -178.802564) (xy 341.922043 -178.784557) (xy 341.872443 -178.759056) (xy 341.827085 -178.726605)
			(xy 341.786936 -178.687896) (xy 341.75285 -178.643753) (xy 341.725554 -178.595118) (xy 341.705631 -178.543027)
			(xy 341.693505 -178.48859) (xy 341.689434 -178.432968) (xy 337.389724 -178.432968) (xy 337.389724 -179.441094)
			(xy 339.797388 -179.441094) (xy 339.801459 -179.385472) (xy 339.813585 -179.331035) (xy 339.833508 -179.278944)
			(xy 339.860804 -179.230309) (xy 339.89489 -179.186166) (xy 339.935039 -179.147457) (xy 339.980397 -179.115006)
			(xy 340.029997 -179.089505) (xy 340.082781 -179.071498) (xy 340.137624 -179.061368) (xy 340.193358 -179.059331)
			(xy 340.248795 -179.065431) (xy 340.266272 -179.07) (xy 359.789982 -179.07) (xy 359.794053 -179.014378)
			(xy 359.806179 -178.959941) (xy 359.826102 -178.90785) (xy 359.853398 -178.859215) (xy 359.887484 -178.815072)
			(xy 359.927633 -178.776363) (xy 359.972991 -178.743912) (xy 360.022591 -178.718411) (xy 360.075375 -178.700404)
			(xy 360.130218 -178.690274) (xy 360.185952 -178.688237) (xy 360.241389 -178.694337) (xy 360.295346 -178.708443)
			(xy 360.346675 -178.730255) (xy 360.394281 -178.759309) (xy 360.437149 -178.794984) (xy 360.474366 -178.836521)
			(xy 360.505139 -178.883034) (xy 360.521105 -178.917092) (xy 364.751364 -178.917092) (xy 364.755435 -178.86147)
			(xy 364.767561 -178.807033) (xy 364.787484 -178.754942) (xy 364.81478 -178.706307) (xy 364.848866 -178.662164)
			(xy 364.889015 -178.623455) (xy 364.934373 -178.591004) (xy 364.983973 -178.565503) (xy 365.036757 -178.547496)
			(xy 365.0916 -178.537366) (xy 365.147334 -178.535329) (xy 365.202771 -178.541429) (xy 365.256728 -178.555535)
			(xy 365.308057 -178.577347) (xy 365.355663 -178.606401) (xy 365.398531 -178.642076) (xy 365.435748 -178.683613)
			(xy 365.466521 -178.730126) (xy 365.490193 -178.780623) (xy 365.506261 -178.83403) (xy 365.514381 -178.889206)
			(xy 365.51489 -178.917092) (xy 374.703846 -178.917092) (xy 374.707917 -178.86147) (xy 374.720043 -178.807033)
			(xy 374.739966 -178.754942) (xy 374.767262 -178.706307) (xy 374.801348 -178.662164) (xy 374.841497 -178.623455)
			(xy 374.886855 -178.591004) (xy 374.936455 -178.565503) (xy 374.989239 -178.547496) (xy 375.044082 -178.537366)
			(xy 375.099816 -178.535329) (xy 375.155253 -178.541429) (xy 375.20921 -178.555535) (xy 375.260539 -178.577347)
			(xy 375.308145 -178.606401) (xy 375.351013 -178.642076) (xy 375.38823 -178.683613) (xy 375.419003 -178.730126)
			(xy 375.442675 -178.780623) (xy 375.458743 -178.83403) (xy 375.466863 -178.889206) (xy 375.467372 -178.917092)
			(xy 375.466863 -178.944978) (xy 375.458743 -179.000154) (xy 375.442675 -179.053561) (xy 375.419003 -179.104058)
			(xy 375.38823 -179.150571) (xy 375.351013 -179.192108) (xy 375.308145 -179.227783) (xy 375.260539 -179.256837)
			(xy 375.20921 -179.278649) (xy 375.155253 -179.292755) (xy 375.099816 -179.298855) (xy 375.044082 -179.296818)
			(xy 374.989239 -179.286688) (xy 374.936455 -179.268681) (xy 374.886855 -179.24318) (xy 374.841497 -179.210729)
			(xy 374.801348 -179.17202) (xy 374.767262 -179.127877) (xy 374.739966 -179.079242) (xy 374.720043 -179.027151)
			(xy 374.707917 -178.972714) (xy 374.703846 -178.917092) (xy 365.51489 -178.917092) (xy 365.514381 -178.944978)
			(xy 365.506261 -179.000154) (xy 365.490193 -179.053561) (xy 365.466521 -179.104058) (xy 365.435748 -179.150571)
			(xy 365.398531 -179.192108) (xy 365.355663 -179.227783) (xy 365.308057 -179.256837) (xy 365.256728 -179.278649)
			(xy 365.202771 -179.292755) (xy 365.147334 -179.298855) (xy 365.0916 -179.296818) (xy 365.036757 -179.286688)
			(xy 364.983973 -179.268681) (xy 364.934373 -179.24318) (xy 364.889015 -179.210729) (xy 364.848866 -179.17202)
			(xy 364.81478 -179.127877) (xy 364.787484 -179.079242) (xy 364.767561 -179.027151) (xy 364.755435 -178.972714)
			(xy 364.751364 -178.917092) (xy 360.521105 -178.917092) (xy 360.528811 -178.933531) (xy 360.544879 -178.986938)
			(xy 360.552999 -179.042114) (xy 360.553508 -179.07) (xy 360.552999 -179.097886) (xy 360.544879 -179.153062)
			(xy 360.528811 -179.206469) (xy 360.505139 -179.256966) (xy 360.474366 -179.303479) (xy 360.437149 -179.345016)
			(xy 360.394281 -179.380691) (xy 360.346675 -179.409745) (xy 360.295346 -179.431557) (xy 360.241389 -179.445663)
			(xy 360.185952 -179.451763) (xy 360.130218 -179.449726) (xy 360.075375 -179.439596) (xy 360.022591 -179.421589)
			(xy 359.972991 -179.396088) (xy 359.927633 -179.363637) (xy 359.887484 -179.324928) (xy 359.853398 -179.280785)
			(xy 359.826102 -179.23215) (xy 359.806179 -179.180059) (xy 359.794053 -179.125622) (xy 359.789982 -179.07)
			(xy 340.266272 -179.07) (xy 340.302752 -179.079537) (xy 340.354081 -179.101349) (xy 340.401687 -179.130403)
			(xy 340.444555 -179.166078) (xy 340.481772 -179.207615) (xy 340.512545 -179.254128) (xy 340.536217 -179.304625)
			(xy 340.552285 -179.358032) (xy 340.560405 -179.413208) (xy 340.560914 -179.441094) (xy 340.560405 -179.46898)
			(xy 340.552285 -179.524156) (xy 340.536217 -179.577563) (xy 340.512545 -179.62806) (xy 340.481772 -179.674573)
			(xy 340.444555 -179.71611) (xy 340.401687 -179.751785) (xy 340.363478 -179.775104) (xy 349.735392 -179.775104)
			(xy 349.739463 -179.719482) (xy 349.751589 -179.665045) (xy 349.771512 -179.612954) (xy 349.798808 -179.564319)
			(xy 349.832894 -179.520176) (xy 349.873043 -179.481467) (xy 349.918401 -179.449016) (xy 349.968001 -179.423515)
			(xy 350.020785 -179.405508) (xy 350.075628 -179.395378) (xy 350.131362 -179.393341) (xy 350.186799 -179.399441)
			(xy 350.240756 -179.413547) (xy 350.292085 -179.435359) (xy 350.339691 -179.464413) (xy 350.382559 -179.500088)
			(xy 350.419776 -179.541625) (xy 350.443842 -179.578) (xy 354.455982 -179.578) (xy 354.460053 -179.522378)
			(xy 354.472179 -179.467941) (xy 354.492102 -179.41585) (xy 354.519398 -179.367215) (xy 354.553484 -179.323072)
			(xy 354.593633 -179.284363) (xy 354.638991 -179.251912) (xy 354.688591 -179.226411) (xy 354.741375 -179.208404)
			(xy 354.796218 -179.198274) (xy 354.851952 -179.196237) (xy 354.907389 -179.202337) (xy 354.961346 -179.216443)
			(xy 355.012675 -179.238255) (xy 355.060281 -179.267309) (xy 355.103149 -179.302984) (xy 355.140366 -179.344521)
			(xy 355.171139 -179.391034) (xy 355.194811 -179.441531) (xy 355.210879 -179.494938) (xy 355.218999 -179.550114)
			(xy 355.219508 -179.578) (xy 356.487982 -179.578) (xy 356.492053 -179.522378) (xy 356.504179 -179.467941)
			(xy 356.524102 -179.41585) (xy 356.551398 -179.367215) (xy 356.585484 -179.323072) (xy 356.625633 -179.284363)
			(xy 356.670991 -179.251912) (xy 356.720591 -179.226411) (xy 356.773375 -179.208404) (xy 356.828218 -179.198274)
			(xy 356.883952 -179.196237) (xy 356.939389 -179.202337) (xy 356.993346 -179.216443) (xy 357.044675 -179.238255)
			(xy 357.092281 -179.267309) (xy 357.135149 -179.302984) (xy 357.172366 -179.344521) (xy 357.203139 -179.391034)
			(xy 357.226811 -179.441531) (xy 357.242879 -179.494938) (xy 357.250999 -179.550114) (xy 357.251309 -179.567078)
			(xy 372.98706 -179.567078) (xy 372.991131 -179.511456) (xy 373.003257 -179.457019) (xy 373.02318 -179.404928)
			(xy 373.050476 -179.356293) (xy 373.084562 -179.31215) (xy 373.124711 -179.273441) (xy 373.170069 -179.24099)
			(xy 373.219669 -179.215489) (xy 373.272453 -179.197482) (xy 373.327296 -179.187352) (xy 373.38303 -179.185315)
			(xy 373.438467 -179.191415) (xy 373.492424 -179.205521) (xy 373.543753 -179.227333) (xy 373.591359 -179.256387)
			(xy 373.634227 -179.292062) (xy 373.671444 -179.333599) (xy 373.702217 -179.380112) (xy 373.725889 -179.430609)
			(xy 373.741957 -179.484016) (xy 373.750077 -179.539192) (xy 373.750586 -179.567078) (xy 373.750387 -179.578)
			(xy 374.013982 -179.578) (xy 374.018053 -179.522378) (xy 374.030179 -179.467941) (xy 374.050102 -179.41585)
			(xy 374.077398 -179.367215) (xy 374.111484 -179.323072) (xy 374.151633 -179.284363) (xy 374.196991 -179.251912)
			(xy 374.246591 -179.226411) (xy 374.299375 -179.208404) (xy 374.354218 -179.198274) (xy 374.409952 -179.196237)
			(xy 374.465389 -179.202337) (xy 374.519346 -179.216443) (xy 374.570675 -179.238255) (xy 374.618281 -179.267309)
			(xy 374.661149 -179.302984) (xy 374.698366 -179.344521) (xy 374.729139 -179.391034) (xy 374.752811 -179.441531)
			(xy 374.768879 -179.494938) (xy 374.776999 -179.550114) (xy 374.777508 -179.578) (xy 374.776999 -179.605886)
			(xy 374.768879 -179.661062) (xy 374.752811 -179.714469) (xy 374.729139 -179.764966) (xy 374.698366 -179.811479)
			(xy 374.661149 -179.853016) (xy 374.618281 -179.888691) (xy 374.570675 -179.917745) (xy 374.519346 -179.939557)
			(xy 374.465389 -179.953663) (xy 374.409952 -179.959763) (xy 374.354218 -179.957726) (xy 374.299375 -179.947596)
			(xy 374.246591 -179.929589) (xy 374.196991 -179.904088) (xy 374.151633 -179.871637) (xy 374.111484 -179.832928)
			(xy 374.077398 -179.788785) (xy 374.050102 -179.74015) (xy 374.030179 -179.688059) (xy 374.018053 -179.633622)
			(xy 374.013982 -179.578) (xy 373.750387 -179.578) (xy 373.750077 -179.594964) (xy 373.741957 -179.65014)
			(xy 373.725889 -179.703547) (xy 373.702217 -179.754044) (xy 373.671444 -179.800557) (xy 373.634227 -179.842094)
			(xy 373.591359 -179.877769) (xy 373.543753 -179.906823) (xy 373.492424 -179.928635) (xy 373.438467 -179.942741)
			(xy 373.38303 -179.948841) (xy 373.327296 -179.946804) (xy 373.272453 -179.936674) (xy 373.219669 -179.918667)
			(xy 373.170069 -179.893166) (xy 373.124711 -179.860715) (xy 373.084562 -179.822006) (xy 373.050476 -179.777863)
			(xy 373.02318 -179.729228) (xy 373.003257 -179.677137) (xy 372.991131 -179.6227) (xy 372.98706 -179.567078)
			(xy 357.251309 -179.567078) (xy 357.251508 -179.578) (xy 357.250999 -179.605886) (xy 357.242879 -179.661062)
			(xy 357.226811 -179.714469) (xy 357.203139 -179.764966) (xy 357.172366 -179.811479) (xy 357.135149 -179.853016)
			(xy 357.092281 -179.888691) (xy 357.044675 -179.917745) (xy 356.993346 -179.939557) (xy 356.939389 -179.953663)
			(xy 356.883952 -179.959763) (xy 356.828218 -179.957726) (xy 356.773375 -179.947596) (xy 356.720591 -179.929589)
			(xy 356.670991 -179.904088) (xy 356.625633 -179.871637) (xy 356.585484 -179.832928) (xy 356.551398 -179.788785)
			(xy 356.524102 -179.74015) (xy 356.504179 -179.688059) (xy 356.492053 -179.633622) (xy 356.487982 -179.578)
			(xy 355.219508 -179.578) (xy 355.218999 -179.605886) (xy 355.210879 -179.661062) (xy 355.194811 -179.714469)
			(xy 355.171139 -179.764966) (xy 355.140366 -179.811479) (xy 355.103149 -179.853016) (xy 355.060281 -179.888691)
			(xy 355.012675 -179.917745) (xy 354.961346 -179.939557) (xy 354.907389 -179.953663) (xy 354.851952 -179.959763)
			(xy 354.796218 -179.957726) (xy 354.741375 -179.947596) (xy 354.688591 -179.929589) (xy 354.638991 -179.904088)
			(xy 354.593633 -179.871637) (xy 354.553484 -179.832928) (xy 354.519398 -179.788785) (xy 354.492102 -179.74015)
			(xy 354.472179 -179.688059) (xy 354.460053 -179.633622) (xy 354.455982 -179.578) (xy 350.443842 -179.578)
			(xy 350.450549 -179.588138) (xy 350.474221 -179.638635) (xy 350.490289 -179.692042) (xy 350.498409 -179.747218)
			(xy 350.498918 -179.775104) (xy 350.498409 -179.80299) (xy 350.490289 -179.858166) (xy 350.474221 -179.911573)
			(xy 350.450549 -179.96207) (xy 350.419776 -180.008583) (xy 350.382559 -180.05012) (xy 350.339691 -180.085795)
			(xy 350.339355 -180.086) (xy 357.757982 -180.086) (xy 357.762053 -180.030378) (xy 357.774179 -179.975941)
			(xy 357.794102 -179.92385) (xy 357.821398 -179.875215) (xy 357.855484 -179.831072) (xy 357.895633 -179.792363)
			(xy 357.940991 -179.759912) (xy 357.990591 -179.734411) (xy 358.043375 -179.716404) (xy 358.098218 -179.706274)
			(xy 358.153952 -179.704237) (xy 358.209389 -179.710337) (xy 358.263346 -179.724443) (xy 358.314675 -179.746255)
			(xy 358.362281 -179.775309) (xy 358.405149 -179.810984) (xy 358.442366 -179.852521) (xy 358.473139 -179.899034)
			(xy 358.496811 -179.949531) (xy 358.509823 -179.992782) (xy 363.22457 -179.992782) (xy 363.228641 -179.93716)
			(xy 363.240767 -179.882723) (xy 363.26069 -179.830632) (xy 363.287986 -179.781997) (xy 363.322072 -179.737854)
			(xy 363.362221 -179.699145) (xy 363.407579 -179.666694) (xy 363.457179 -179.641193) (xy 363.509963 -179.623186)
			(xy 363.564806 -179.613056) (xy 363.62054 -179.611019) (xy 363.675977 -179.617119) (xy 363.729934 -179.631225)
			(xy 363.781263 -179.653037) (xy 363.828869 -179.682091) (xy 363.871737 -179.717766) (xy 363.908954 -179.759303)
			(xy 363.939727 -179.805816) (xy 363.963399 -179.856313) (xy 363.979467 -179.90972) (xy 363.987587 -179.964896)
			(xy 363.988096 -179.992782) (xy 363.987587 -180.020668) (xy 363.979467 -180.075844) (xy 363.963399 -180.129251)
			(xy 363.939727 -180.179748) (xy 363.936549 -180.184552) (xy 375.485658 -180.184552) (xy 375.489729 -180.12893)
			(xy 375.501855 -180.074493) (xy 375.521778 -180.022402) (xy 375.549074 -179.973767) (xy 375.58316 -179.929624)
			(xy 375.623309 -179.890915) (xy 375.668667 -179.858464) (xy 375.718267 -179.832963) (xy 375.771051 -179.814956)
			(xy 375.825894 -179.804826) (xy 375.881628 -179.802789) (xy 375.937065 -179.808889) (xy 375.991022 -179.822995)
			(xy 376.042351 -179.844807) (xy 376.089957 -179.873861) (xy 376.132825 -179.909536) (xy 376.170042 -179.951073)
			(xy 376.200815 -179.997586) (xy 376.224487 -180.048083) (xy 376.240555 -180.10149) (xy 376.248675 -180.156666)
			(xy 376.249184 -180.184552) (xy 376.248675 -180.212438) (xy 376.240555 -180.267614) (xy 376.224487 -180.321021)
			(xy 376.200815 -180.371518) (xy 376.170042 -180.418031) (xy 376.132825 -180.459568) (xy 376.089957 -180.495243)
			(xy 376.042351 -180.524297) (xy 375.991022 -180.546109) (xy 375.937065 -180.560215) (xy 375.881628 -180.566315)
			(xy 375.825894 -180.564278) (xy 375.771051 -180.554148) (xy 375.718267 -180.536141) (xy 375.668667 -180.51064)
			(xy 375.623309 -180.478189) (xy 375.58316 -180.43948) (xy 375.549074 -180.395337) (xy 375.521778 -180.346702)
			(xy 375.501855 -180.294611) (xy 375.489729 -180.240174) (xy 375.485658 -180.184552) (xy 363.936549 -180.184552)
			(xy 363.908954 -180.226261) (xy 363.871737 -180.267798) (xy 363.828869 -180.303473) (xy 363.781263 -180.332527)
			(xy 363.729934 -180.354339) (xy 363.675977 -180.368445) (xy 363.62054 -180.374545) (xy 363.564806 -180.372508)
			(xy 363.509963 -180.362378) (xy 363.457179 -180.344371) (xy 363.407579 -180.31887) (xy 363.362221 -180.286419)
			(xy 363.322072 -180.24771) (xy 363.287986 -180.203567) (xy 363.26069 -180.154932) (xy 363.240767 -180.102841)
			(xy 363.228641 -180.048404) (xy 363.22457 -179.992782) (xy 358.509823 -179.992782) (xy 358.512879 -180.002938)
			(xy 358.520999 -180.058114) (xy 358.521508 -180.086) (xy 358.520999 -180.113886) (xy 358.512879 -180.169062)
			(xy 358.496811 -180.222469) (xy 358.473139 -180.272966) (xy 358.442366 -180.319479) (xy 358.405149 -180.361016)
			(xy 358.362281 -180.396691) (xy 358.314675 -180.425745) (xy 358.263346 -180.447557) (xy 358.209389 -180.461663)
			(xy 358.153952 -180.467763) (xy 358.098218 -180.465726) (xy 358.043375 -180.455596) (xy 357.990591 -180.437589)
			(xy 357.940991 -180.412088) (xy 357.895633 -180.379637) (xy 357.855484 -180.340928) (xy 357.821398 -180.296785)
			(xy 357.794102 -180.24815) (xy 357.774179 -180.196059) (xy 357.762053 -180.141622) (xy 357.757982 -180.086)
			(xy 350.339355 -180.086) (xy 350.292085 -180.114849) (xy 350.240756 -180.136661) (xy 350.186799 -180.150767)
			(xy 350.131362 -180.156867) (xy 350.075628 -180.15483) (xy 350.020785 -180.1447) (xy 349.968001 -180.126693)
			(xy 349.918401 -180.101192) (xy 349.873043 -180.068741) (xy 349.832894 -180.030032) (xy 349.798808 -179.985889)
			(xy 349.771512 -179.937254) (xy 349.751589 -179.885163) (xy 349.739463 -179.830726) (xy 349.735392 -179.775104)
			(xy 340.363478 -179.775104) (xy 340.354081 -179.780839) (xy 340.302752 -179.802651) (xy 340.248795 -179.816757)
			(xy 340.193358 -179.822857) (xy 340.137624 -179.82082) (xy 340.082781 -179.81069) (xy 340.029997 -179.792683)
			(xy 339.980397 -179.767182) (xy 339.935039 -179.734731) (xy 339.89489 -179.696022) (xy 339.860804 -179.651879)
			(xy 339.833508 -179.603244) (xy 339.813585 -179.551153) (xy 339.801459 -179.496716) (xy 339.797388 -179.441094)
			(xy 337.389724 -179.441094) (xy 337.389724 -179.947062) (xy 337.389978 -179.951634) (xy 337.389978 -179.951888)
			(xy 337.390232 -179.964334) (xy 337.390232 -179.968906) (xy 337.389724 -179.982114) (xy 337.389724 -180.081174)
			(xy 337.389608 -180.086129) (xy 337.387694 -180.095853) (xy 337.385914 -180.100478) (xy 337.382104 -180.109622)
			(xy 337.375246 -180.11648) (xy 337.374738 -180.116988) (xy 337.361784 -180.129942) (xy 337.354418 -180.13934)
			(xy 337.353148 -180.14188) (xy 337.350831 -180.146217) (xy 337.347768 -180.155557) (xy 337.347052 -180.160422)
			(xy 337.346036 -180.170074) (xy 337.350608 -180.185822) (xy 337.355942 -180.198268) (xy 337.358736 -180.203094)
			(xy 337.36915 -180.220112) (xy 337.378294 -180.229764) (xy 337.382612 -180.232812) (xy 337.41234 -180.25324)
			(xy 337.467052 -180.300246) (xy 337.515582 -180.353611) (xy 337.557197 -180.412527) (xy 337.591267 -180.476106)
			(xy 337.617277 -180.543384) (xy 337.634835 -180.613346) (xy 337.643675 -180.684934) (xy 337.644232 -180.721)
			(xy 337.643771 -180.753896) (xy 337.636405 -180.819275) (xy 337.621764 -180.883418) (xy 337.600035 -180.945518)
			(xy 337.571488 -181.004795) (xy 337.536485 -181.060503) (xy 337.503392 -181.102) (xy 357.757982 -181.102)
			(xy 357.762053 -181.046378) (xy 357.774179 -180.991941) (xy 357.794102 -180.93985) (xy 357.821398 -180.891215)
			(xy 357.855484 -180.847072) (xy 357.895633 -180.808363) (xy 357.940991 -180.775912) (xy 357.990591 -180.750411)
			(xy 358.043375 -180.732404) (xy 358.098218 -180.722274) (xy 358.153952 -180.720237) (xy 358.209389 -180.726337)
			(xy 358.263346 -180.740443) (xy 358.314675 -180.762255) (xy 358.362281 -180.791309) (xy 358.405149 -180.826984)
			(xy 358.442366 -180.868521) (xy 358.473139 -180.915034) (xy 358.496811 -180.965531) (xy 358.512879 -181.018938)
			(xy 358.520999 -181.074114) (xy 358.521313 -181.091332) (xy 363.853982 -181.091332) (xy 363.858053 -181.03571)
			(xy 363.870179 -180.981273) (xy 363.890102 -180.929182) (xy 363.917398 -180.880547) (xy 363.951484 -180.836404)
			(xy 363.991633 -180.797695) (xy 364.036991 -180.765244) (xy 364.086591 -180.739743) (xy 364.139375 -180.721736)
			(xy 364.194218 -180.711606) (xy 364.249952 -180.709569) (xy 364.305389 -180.715669) (xy 364.359346 -180.729775)
			(xy 364.410675 -180.751587) (xy 364.458281 -180.780641) (xy 364.501149 -180.816316) (xy 364.538366 -180.857853)
			(xy 364.569139 -180.904366) (xy 364.592811 -180.954863) (xy 364.608879 -181.00827) (xy 364.616999 -181.063446)
			(xy 364.617355 -181.08295) (xy 374.121932 -181.08295) (xy 374.126003 -181.027328) (xy 374.138129 -180.972891)
			(xy 374.158052 -180.9208) (xy 374.185348 -180.872165) (xy 374.219434 -180.828022) (xy 374.259583 -180.789313)
			(xy 374.304941 -180.756862) (xy 374.354541 -180.731361) (xy 374.407325 -180.713354) (xy 374.462168 -180.703224)
			(xy 374.517902 -180.701187) (xy 374.573339 -180.707287) (xy 374.627296 -180.721393) (xy 374.678625 -180.743205)
			(xy 374.726231 -180.772259) (xy 374.769099 -180.807934) (xy 374.806316 -180.849471) (xy 374.837089 -180.895984)
			(xy 374.860761 -180.946481) (xy 374.876829 -180.999888) (xy 374.884949 -181.055064) (xy 374.885458 -181.08295)
			(xy 374.884949 -181.110836) (xy 374.876829 -181.166012) (xy 374.860761 -181.219419) (xy 374.837089 -181.269916)
			(xy 374.806316 -181.316429) (xy 374.769099 -181.357966) (xy 374.726231 -181.393641) (xy 374.678625 -181.422695)
			(xy 374.627296 -181.444507) (xy 374.573339 -181.458613) (xy 374.517902 -181.464713) (xy 374.462168 -181.462676)
			(xy 374.407325 -181.452546) (xy 374.354541 -181.434539) (xy 374.304941 -181.409038) (xy 374.259583 -181.376587)
			(xy 374.219434 -181.337878) (xy 374.185348 -181.293735) (xy 374.158052 -181.2451) (xy 374.138129 -181.193009)
			(xy 374.126003 -181.138572) (xy 374.121932 -181.08295) (xy 364.617355 -181.08295) (xy 364.617508 -181.091332)
			(xy 364.616999 -181.119218) (xy 364.608879 -181.174394) (xy 364.592811 -181.227801) (xy 364.569139 -181.278298)
			(xy 364.538366 -181.324811) (xy 364.501149 -181.366348) (xy 364.458281 -181.402023) (xy 364.410675 -181.431077)
			(xy 364.359346 -181.452889) (xy 364.305389 -181.466995) (xy 364.249952 -181.473095) (xy 364.194218 -181.471058)
			(xy 364.139375 -181.460928) (xy 364.086591 -181.442921) (xy 364.036991 -181.41742) (xy 363.991633 -181.384969)
			(xy 363.951484 -181.34626) (xy 363.917398 -181.302117) (xy 363.890102 -181.253482) (xy 363.870179 -181.201391)
			(xy 363.858053 -181.146954) (xy 363.853982 -181.091332) (xy 358.521313 -181.091332) (xy 358.521508 -181.102)
			(xy 358.520999 -181.129886) (xy 358.512879 -181.185062) (xy 358.496811 -181.238469) (xy 358.473139 -181.288966)
			(xy 358.442366 -181.335479) (xy 358.405149 -181.377016) (xy 358.362281 -181.412691) (xy 358.314675 -181.441745)
			(xy 358.263346 -181.463557) (xy 358.209389 -181.477663) (xy 358.153952 -181.483763) (xy 358.098218 -181.481726)
			(xy 358.043375 -181.471596) (xy 357.990591 -181.453589) (xy 357.940991 -181.428088) (xy 357.895633 -181.395637)
			(xy 357.855484 -181.356928) (xy 357.821398 -181.312785) (xy 357.794102 -181.26415) (xy 357.774179 -181.212059)
			(xy 357.762053 -181.157622) (xy 357.757982 -181.102) (xy 337.503392 -181.102) (xy 337.495464 -181.111942)
			(xy 337.472528 -181.135528) (xy 337.132676 -181.475126) (xy 337.125905 -181.484615) (xy 337.12101 -181.50738)
			(xy 337.123278 -181.518814) (xy 337.13195 -181.55412) (xy 341.637364 -181.55412) (xy 341.641435 -181.498498)
			(xy 341.653561 -181.444061) (xy 341.673484 -181.39197) (xy 341.70078 -181.343335) (xy 341.734866 -181.299192)
			(xy 341.775015 -181.260483) (xy 341.820373 -181.228032) (xy 341.869973 -181.202531) (xy 341.922757 -181.184524)
			(xy 341.9776 -181.174394) (xy 342.033334 -181.172357) (xy 342.088771 -181.178457) (xy 342.142728 -181.192563)
			(xy 342.194057 -181.214375) (xy 342.241663 -181.243429) (xy 342.284531 -181.279104) (xy 342.321748 -181.320641)
			(xy 342.352521 -181.367154) (xy 342.376193 -181.417651) (xy 342.392261 -181.471058) (xy 342.400381 -181.526234)
			(xy 342.40089 -181.55412) (xy 342.400381 -181.582006) (xy 342.392261 -181.637182) (xy 342.376193 -181.690589)
			(xy 342.352521 -181.741086) (xy 342.321748 -181.787599) (xy 342.284531 -181.829136) (xy 342.241663 -181.864811)
			(xy 342.194057 -181.893865) (xy 342.142728 -181.915677) (xy 342.088771 -181.929783) (xy 342.033334 -181.935883)
			(xy 341.9776 -181.933846) (xy 341.922757 -181.923716) (xy 341.869973 -181.905709) (xy 341.820373 -181.880208)
			(xy 341.775015 -181.847757) (xy 341.734866 -181.809048) (xy 341.70078 -181.764905) (xy 341.673484 -181.71627)
			(xy 341.653561 -181.664179) (xy 341.641435 -181.609742) (xy 341.637364 -181.55412) (xy 337.13195 -181.55412)
			(xy 337.141058 -181.591204) (xy 337.143434 -181.599545) (xy 337.152907 -181.614057) (xy 337.16669 -181.624564)
			(xy 337.17484 -181.627526) (xy 337.175094 -181.627526) (xy 337.177888 -181.628542) (xy 337.179412 -181.62905)
			(xy 337.187794 -181.631844) (xy 337.191604 -181.632606) (xy 337.198208 -181.635908) (xy 337.224541 -181.646876)
			(xy 337.273889 -181.675485) (xy 337.31843 -181.711119) (xy 337.357174 -181.752983) (xy 337.389258 -181.800146)
			(xy 337.413968 -181.851557) (xy 337.430753 -181.906073) (xy 337.43924 -181.962479) (xy 337.439762 -181.991)
			(xy 337.439297 -182.017967) (xy 337.431706 -182.071364) (xy 337.416675 -182.123162) (xy 337.394504 -182.172328)
			(xy 337.374365 -182.204106) (xy 340.499444 -182.204106) (xy 340.503515 -182.148484) (xy 340.515641 -182.094047)
			(xy 340.535564 -182.041956) (xy 340.56286 -181.993321) (xy 340.596946 -181.949178) (xy 340.637095 -181.910469)
			(xy 340.682453 -181.878018) (xy 340.732053 -181.852517) (xy 340.784837 -181.83451) (xy 340.83968 -181.82438)
			(xy 340.895414 -181.822343) (xy 340.950851 -181.828443) (xy 341.004808 -181.842549) (xy 341.056137 -181.864361)
			(xy 341.103743 -181.893415) (xy 341.146611 -181.92909) (xy 341.183828 -181.970627) (xy 341.214601 -182.01714)
			(xy 341.238273 -182.067637) (xy 341.253425 -182.118) (xy 357.757982 -182.118) (xy 357.762053 -182.062378)
			(xy 357.774179 -182.007941) (xy 357.794102 -181.95585) (xy 357.821398 -181.907215) (xy 357.855484 -181.863072)
			(xy 357.895633 -181.824363) (xy 357.940991 -181.791912) (xy 357.990591 -181.766411) (xy 358.043375 -181.748404)
			(xy 358.098218 -181.738274) (xy 358.153952 -181.736237) (xy 358.209389 -181.742337) (xy 358.263346 -181.756443)
			(xy 358.314675 -181.778255) (xy 358.362281 -181.807309) (xy 358.405149 -181.842984) (xy 358.442366 -181.884521)
			(xy 358.473139 -181.931034) (xy 358.496811 -181.981531) (xy 358.512879 -182.034938) (xy 358.520999 -182.090114)
			(xy 358.521508 -182.118) (xy 359.789982 -182.118) (xy 359.794053 -182.062378) (xy 359.806179 -182.007941)
			(xy 359.826102 -181.95585) (xy 359.853398 -181.907215) (xy 359.887484 -181.863072) (xy 359.927633 -181.824363)
			(xy 359.972991 -181.791912) (xy 360.022591 -181.766411) (xy 360.075375 -181.748404) (xy 360.130218 -181.738274)
			(xy 360.185952 -181.736237) (xy 360.241389 -181.742337) (xy 360.295346 -181.756443) (xy 360.346675 -181.778255)
			(xy 360.394281 -181.807309) (xy 360.437149 -181.842984) (xy 360.474366 -181.884521) (xy 360.505139 -181.931034)
			(xy 360.528811 -181.981531) (xy 360.544879 -182.034938) (xy 360.552999 -182.090114) (xy 360.553508 -182.118)
			(xy 361.821982 -182.118) (xy 361.826053 -182.062378) (xy 361.838179 -182.007941) (xy 361.858102 -181.95585)
			(xy 361.885398 -181.907215) (xy 361.919484 -181.863072) (xy 361.959633 -181.824363) (xy 362.004991 -181.791912)
			(xy 362.054591 -181.766411) (xy 362.107375 -181.748404) (xy 362.162218 -181.738274) (xy 362.217952 -181.736237)
			(xy 362.273389 -181.742337) (xy 362.327346 -181.756443) (xy 362.378675 -181.778255) (xy 362.426281 -181.807309)
			(xy 362.469149 -181.842984) (xy 362.506366 -181.884521) (xy 362.537139 -181.931034) (xy 362.548937 -181.956202)
			(xy 365.106202 -181.956202) (xy 365.110273 -181.90058) (xy 365.122399 -181.846143) (xy 365.142322 -181.794052)
			(xy 365.169618 -181.745417) (xy 365.203704 -181.701274) (xy 365.243853 -181.662565) (xy 365.289211 -181.630114)
			(xy 365.338811 -181.604613) (xy 365.391595 -181.586606) (xy 365.446438 -181.576476) (xy 365.502172 -181.574439)
			(xy 365.557609 -181.580539) (xy 365.611566 -181.594645) (xy 365.662895 -181.616457) (xy 365.710501 -181.645511)
			(xy 365.753369 -181.681186) (xy 365.790586 -181.722723) (xy 365.821359 -181.769236) (xy 365.845031 -181.819733)
			(xy 365.861099 -181.87314) (xy 365.869219 -181.928316) (xy 365.869728 -181.956202) (xy 365.869219 -181.984088)
			(xy 365.861099 -182.039264) (xy 365.845031 -182.092671) (xy 365.821359 -182.143168) (xy 365.790586 -182.189681)
			(xy 365.753369 -182.231218) (xy 365.710501 -182.266893) (xy 365.662895 -182.295947) (xy 365.611566 -182.317759)
			(xy 365.557609 -182.331865) (xy 365.502172 -182.337965) (xy 365.446438 -182.335928) (xy 365.391595 -182.325798)
			(xy 365.338811 -182.307791) (xy 365.289211 -182.28229) (xy 365.243853 -182.249839) (xy 365.203704 -182.21113)
			(xy 365.169618 -182.166987) (xy 365.142322 -182.118352) (xy 365.122399 -182.066261) (xy 365.110273 -182.011824)
			(xy 365.106202 -181.956202) (xy 362.548937 -181.956202) (xy 362.560811 -181.981531) (xy 362.576879 -182.034938)
			(xy 362.584999 -182.090114) (xy 362.585508 -182.118) (xy 362.584999 -182.145886) (xy 362.576879 -182.201062)
			(xy 362.560811 -182.254469) (xy 362.537139 -182.304966) (xy 362.506366 -182.351479) (xy 362.469149 -182.393016)
			(xy 362.426281 -182.428691) (xy 362.378675 -182.457745) (xy 362.327346 -182.479557) (xy 362.273389 -182.493663)
			(xy 362.217952 -182.499763) (xy 362.162218 -182.497726) (xy 362.107375 -182.487596) (xy 362.054591 -182.469589)
			(xy 362.004991 -182.444088) (xy 361.959633 -182.411637) (xy 361.919484 -182.372928) (xy 361.885398 -182.328785)
			(xy 361.858102 -182.28015) (xy 361.838179 -182.228059) (xy 361.826053 -182.173622) (xy 361.821982 -182.118)
			(xy 360.553508 -182.118) (xy 360.552999 -182.145886) (xy 360.544879 -182.201062) (xy 360.528811 -182.254469)
			(xy 360.505139 -182.304966) (xy 360.474366 -182.351479) (xy 360.437149 -182.393016) (xy 360.394281 -182.428691)
			(xy 360.346675 -182.457745) (xy 360.295346 -182.479557) (xy 360.241389 -182.493663) (xy 360.185952 -182.499763)
			(xy 360.130218 -182.497726) (xy 360.075375 -182.487596) (xy 360.022591 -182.469589) (xy 359.972991 -182.444088)
			(xy 359.927633 -182.411637) (xy 359.887484 -182.372928) (xy 359.853398 -182.328785) (xy 359.826102 -182.28015)
			(xy 359.806179 -182.228059) (xy 359.794053 -182.173622) (xy 359.789982 -182.118) (xy 358.521508 -182.118)
			(xy 358.520999 -182.145886) (xy 358.512879 -182.201062) (xy 358.496811 -182.254469) (xy 358.473139 -182.304966)
			(xy 358.442366 -182.351479) (xy 358.405149 -182.393016) (xy 358.362281 -182.428691) (xy 358.314675 -182.457745)
			(xy 358.263346 -182.479557) (xy 358.209389 -182.493663) (xy 358.153952 -182.499763) (xy 358.098218 -182.497726)
			(xy 358.043375 -182.487596) (xy 357.990591 -182.469589) (xy 357.940991 -182.444088) (xy 357.895633 -182.411637)
			(xy 357.855484 -182.372928) (xy 357.821398 -182.328785) (xy 357.794102 -182.28015) (xy 357.774179 -182.228059)
			(xy 357.762053 -182.173622) (xy 357.757982 -182.118) (xy 341.253425 -182.118) (xy 341.254341 -182.121044)
			(xy 341.262461 -182.17622) (xy 341.26297 -182.204106) (xy 341.262461 -182.231992) (xy 341.254341 -182.287168)
			(xy 341.238273 -182.340575) (xy 341.214601 -182.391072) (xy 341.183828 -182.437585) (xy 341.146611 -182.479122)
			(xy 341.103743 -182.514797) (xy 341.056137 -182.543851) (xy 341.004808 -182.565663) (xy 340.950851 -182.579769)
			(xy 340.895414 -182.585869) (xy 340.83968 -182.583832) (xy 340.784837 -182.573702) (xy 340.732053 -182.555695)
			(xy 340.682453 -182.530194) (xy 340.637095 -182.497743) (xy 340.596946 -182.459034) (xy 340.56286 -182.414891)
			(xy 340.535564 -182.366256) (xy 340.515641 -182.314165) (xy 340.503515 -182.259728) (xy 340.499444 -182.204106)
			(xy 337.374365 -182.204106) (xy 337.365633 -182.217885) (xy 337.330638 -182.258924) (xy 337.290215 -182.29463)
			(xy 337.245169 -182.32429) (xy 337.196397 -182.347316) (xy 337.170776 -182.355744) (xy 337.16468 -182.357522)
			(xy 337.159346 -182.360824) (xy 337.150456 -182.367682) (xy 336.993738 -182.524654) (xy 336.916776 -182.601616)
			(xy 336.913341 -182.605233) (xy 336.907836 -182.613549) (xy 336.905854 -182.618126) (xy 336.902298 -182.626762)
			(xy 336.902298 -182.854092) (xy 341.637364 -182.854092) (xy 341.641435 -182.79847) (xy 341.653561 -182.744033)
			(xy 341.673484 -182.691942) (xy 341.70078 -182.643307) (xy 341.734866 -182.599164) (xy 341.775015 -182.560455)
			(xy 341.820373 -182.528004) (xy 341.869973 -182.502503) (xy 341.922757 -182.484496) (xy 341.9776 -182.474366)
			(xy 342.033334 -182.472329) (xy 342.088771 -182.478429) (xy 342.142728 -182.492535) (xy 342.194057 -182.514347)
			(xy 342.241663 -182.543401) (xy 342.284531 -182.579076) (xy 342.321748 -182.620613) (xy 342.352521 -182.667126)
			(xy 342.376193 -182.717623) (xy 342.392261 -182.77103) (xy 342.400381 -182.826206) (xy 342.40089 -182.854092)
			(xy 342.400381 -182.881978) (xy 342.392261 -182.937154) (xy 342.376193 -182.990561) (xy 342.352521 -183.041058)
			(xy 342.321748 -183.087571) (xy 342.284531 -183.129108) (xy 342.241663 -183.164783) (xy 342.194057 -183.193837)
			(xy 342.142728 -183.215649) (xy 342.088771 -183.229755) (xy 342.033334 -183.235855) (xy 341.9776 -183.233818)
			(xy 341.922757 -183.223688) (xy 341.869973 -183.205681) (xy 341.820373 -183.18018) (xy 341.775015 -183.147729)
			(xy 341.734866 -183.10902) (xy 341.70078 -183.064877) (xy 341.673484 -183.016242) (xy 341.653561 -182.964151)
			(xy 341.641435 -182.909714) (xy 341.637364 -182.854092) (xy 336.902298 -182.854092) (xy 336.902298 -183.504078)
			(xy 349.87357 -183.504078) (xy 349.874131 -183.475583) (xy 349.882581 -183.419224) (xy 349.899318 -183.364748)
			(xy 349.923971 -183.313367) (xy 349.955992 -183.266224) (xy 349.994667 -183.224368) (xy 350.016572 -183.206136)
			(xy 350.025087 -183.198504) (xy 350.034987 -183.177928) (xy 350.035622 -183.166512) (xy 350.035622 -183.087518)
			(xy 350.034972 -183.076104) (xy 350.025083 -183.055527) (xy 350.016572 -183.047894) (xy 349.994664 -183.029666)
			(xy 349.956 -182.987799) (xy 349.923983 -182.940653) (xy 349.899326 -182.889274) (xy 349.882575 -182.834802)
			(xy 349.874101 -182.778447) (xy 349.87357 -182.749952) (xy 349.874056 -182.722701) (xy 349.881812 -182.668753)
			(xy 349.897167 -182.616458) (xy 349.919809 -182.566881) (xy 349.949275 -182.521031) (xy 349.984966 -182.47984)
			(xy 350.026157 -182.444149) (xy 350.072007 -182.414683) (xy 350.121584 -182.392041) (xy 350.173879 -182.376686)
			(xy 350.227827 -182.36893) (xy 350.282329 -182.36893) (xy 350.336277 -182.376686) (xy 350.388572 -182.392041)
			(xy 350.438149 -182.414683) (xy 350.483999 -182.444149) (xy 350.52519 -182.47984) (xy 350.560881 -182.521031)
			(xy 350.590347 -182.566881) (xy 350.612989 -182.616458) (xy 350.628344 -182.668753) (xy 350.6361 -182.722701)
			(xy 350.636586 -182.749952) (xy 350.636062 -182.778448) (xy 350.627608 -182.83481) (xy 350.610864 -182.889287)
			(xy 350.586204 -182.940668) (xy 350.554176 -182.98781) (xy 350.515492 -183.029664) (xy 350.493584 -183.047894)
			(xy 350.485064 -183.055522) (xy 350.475165 -183.0761) (xy 350.474534 -183.087518) (xy 350.474534 -183.166512)
			(xy 350.475148 -183.177931) (xy 350.48506 -183.198509) (xy 350.493584 -183.206136) (xy 350.515497 -183.224358)
			(xy 350.554163 -183.266225) (xy 350.58618 -183.313372) (xy 350.610837 -183.364752) (xy 350.627587 -183.419225)
			(xy 350.636057 -183.475583) (xy 350.636317 -183.4896) (xy 351.481642 -183.4896) (xy 351.485713 -183.433978)
			(xy 351.497839 -183.379541) (xy 351.517762 -183.32745) (xy 351.545058 -183.278815) (xy 351.579144 -183.234672)
			(xy 351.619293 -183.195963) (xy 351.664651 -183.163512) (xy 351.714251 -183.138011) (xy 351.767035 -183.120004)
			(xy 351.821878 -183.109874) (xy 351.877612 -183.107837) (xy 351.933049 -183.113937) (xy 351.987006 -183.128043)
			(xy 352.038335 -183.149855) (xy 352.085941 -183.178909) (xy 352.128809 -183.214584) (xy 352.166026 -183.256121)
			(xy 352.196799 -183.302634) (xy 352.220471 -183.353131) (xy 352.230962 -183.388) (xy 356.360982 -183.388)
			(xy 356.365053 -183.332378) (xy 356.377179 -183.277941) (xy 356.397102 -183.22585) (xy 356.424398 -183.177215)
			(xy 356.458484 -183.133072) (xy 356.498633 -183.094363) (xy 356.543991 -183.061912) (xy 356.593591 -183.036411)
			(xy 356.646375 -183.018404) (xy 356.701218 -183.008274) (xy 356.756952 -183.006237) (xy 356.812389 -183.012337)
			(xy 356.866346 -183.026443) (xy 356.917675 -183.048255) (xy 356.965281 -183.077309) (xy 357.00105 -183.107076)
			(xy 359.782618 -183.107076) (xy 359.783104 -183.079825) (xy 359.79086 -183.025877) (xy 359.806215 -182.973582)
			(xy 359.828857 -182.924005) (xy 359.858323 -182.878155) (xy 359.894014 -182.836964) (xy 359.935205 -182.801273)
			(xy 359.981055 -182.771807) (xy 360.030632 -182.749165) (xy 360.082927 -182.73381) (xy 360.136875 -182.726054)
			(xy 360.191377 -182.726054) (xy 360.245325 -182.73381) (xy 360.29762 -182.749165) (xy 360.332713 -182.765192)
			(xy 367.038634 -182.765192) (xy 367.042705 -182.70957) (xy 367.054831 -182.655133) (xy 367.074754 -182.603042)
			(xy 367.10205 -182.554407) (xy 367.136136 -182.510264) (xy 367.176285 -182.471555) (xy 367.221643 -182.439104)
			(xy 367.271243 -182.413603) (xy 367.324027 -182.395596) (xy 367.37887 -182.385466) (xy 367.434604 -182.383429)
			(xy 367.490041 -182.389529) (xy 367.543998 -182.403635) (xy 367.595327 -182.425447) (xy 367.642933 -182.454501)
			(xy 367.685801 -182.490176) (xy 367.723018 -182.531713) (xy 367.753791 -182.578226) (xy 367.777463 -182.628723)
			(xy 367.780847 -182.63997) (xy 372.773446 -182.63997) (xy 372.777517 -182.584348) (xy 372.789643 -182.529911)
			(xy 372.809566 -182.47782) (xy 372.836862 -182.429185) (xy 372.870948 -182.385042) (xy 372.911097 -182.346333)
			(xy 372.956455 -182.313882) (xy 373.006055 -182.288381) (xy 373.058839 -182.270374) (xy 373.113682 -182.260244)
			(xy 373.169416 -182.258207) (xy 373.224853 -182.264307) (xy 373.27881 -182.278413) (xy 373.330139 -182.300225)
			(xy 373.377745 -182.329279) (xy 373.420613 -182.364954) (xy 373.45783 -182.406491) (xy 373.488603 -182.453004)
			(xy 373.512275 -182.503501) (xy 373.528343 -182.556908) (xy 373.536463 -182.612084) (xy 373.536972 -182.63997)
			(xy 373.536463 -182.667856) (xy 373.528343 -182.723032) (xy 373.512275 -182.776439) (xy 373.488603 -182.826936)
			(xy 373.45783 -182.873449) (xy 373.420613 -182.914986) (xy 373.377745 -182.950661) (xy 373.330139 -182.979715)
			(xy 373.27881 -183.001527) (xy 373.224853 -183.015633) (xy 373.169416 -183.021733) (xy 373.113682 -183.019696)
			(xy 373.058839 -183.009566) (xy 373.006055 -182.991559) (xy 372.956455 -182.966058) (xy 372.911097 -182.933607)
			(xy 372.870948 -182.894898) (xy 372.836862 -182.850755) (xy 372.809566 -182.80212) (xy 372.789643 -182.750029)
			(xy 372.777517 -182.695592) (xy 372.773446 -182.63997) (xy 367.780847 -182.63997) (xy 367.793531 -182.68213)
			(xy 367.801651 -182.737306) (xy 367.80216 -182.765192) (xy 367.801651 -182.793078) (xy 367.793531 -182.848254)
			(xy 367.777463 -182.901661) (xy 367.753791 -182.952158) (xy 367.723018 -182.998671) (xy 367.685801 -183.040208)
			(xy 367.642933 -183.075883) (xy 367.595568 -183.10479) (xy 375.476768 -183.10479) (xy 375.480839 -183.049168)
			(xy 375.492965 -182.994731) (xy 375.512888 -182.94264) (xy 375.540184 -182.894005) (xy 375.57427 -182.849862)
			(xy 375.614419 -182.811153) (xy 375.659777 -182.778702) (xy 375.709377 -182.753201) (xy 375.762161 -182.735194)
			(xy 375.817004 -182.725064) (xy 375.872738 -182.723027) (xy 375.928175 -182.729127) (xy 375.982132 -182.743233)
			(xy 376.033461 -182.765045) (xy 376.081067 -182.794099) (xy 376.123935 -182.829774) (xy 376.161152 -182.871311)
			(xy 376.191925 -182.917824) (xy 376.215597 -182.968321) (xy 376.231665 -183.021728) (xy 376.239785 -183.076904)
			(xy 376.240294 -183.10479) (xy 376.239785 -183.132676) (xy 376.231665 -183.187852) (xy 376.215597 -183.241259)
			(xy 376.191925 -183.291756) (xy 376.161152 -183.338269) (xy 376.123935 -183.379806) (xy 376.081067 -183.415481)
			(xy 376.033461 -183.444535) (xy 375.982132 -183.466347) (xy 375.928175 -183.480453) (xy 375.872738 -183.486553)
			(xy 375.817004 -183.484516) (xy 375.762161 -183.474386) (xy 375.709377 -183.456379) (xy 375.659777 -183.430878)
			(xy 375.614419 -183.398427) (xy 375.57427 -183.359718) (xy 375.540184 -183.315575) (xy 375.512888 -183.26694)
			(xy 375.492965 -183.214849) (xy 375.480839 -183.160412) (xy 375.476768 -183.10479) (xy 367.595568 -183.10479)
			(xy 367.595327 -183.104937) (xy 367.543998 -183.126749) (xy 367.490041 -183.140855) (xy 367.434604 -183.146955)
			(xy 367.37887 -183.144918) (xy 367.324027 -183.134788) (xy 367.271243 -183.116781) (xy 367.221643 -183.09128)
			(xy 367.176285 -183.058829) (xy 367.136136 -183.02012) (xy 367.10205 -182.975977) (xy 367.074754 -182.927342)
			(xy 367.054831 -182.875251) (xy 367.042705 -182.820814) (xy 367.038634 -182.765192) (xy 360.332713 -182.765192)
			(xy 360.347197 -182.771807) (xy 360.393047 -182.801273) (xy 360.434238 -182.836964) (xy 360.469929 -182.878155)
			(xy 360.499395 -182.924005) (xy 360.522037 -182.973582) (xy 360.537392 -183.025877) (xy 360.545148 -183.079825)
			(xy 360.545634 -183.107076) (xy 360.545235 -183.132858) (xy 360.538292 -183.183953) (xy 360.524529 -183.233647)
			(xy 360.504197 -183.281034) (xy 360.477667 -183.32525) (xy 360.445423 -183.365489) (xy 360.408051 -183.401018)
			(xy 360.387392 -183.416448) (xy 360.376425 -183.424986) (xy 360.359117 -183.446714) (xy 360.348315 -183.472307)
			(xy 360.344819 -183.499865) (xy 360.34889 -183.527344) (xy 360.360224 -183.552706) (xy 360.377982 -183.574068)
			(xy 360.38917 -183.58231) (xy 360.410565 -183.597638) (xy 360.449303 -183.633268) (xy 360.482777 -183.673883)
			(xy 360.510352 -183.718713) (xy 360.531505 -183.766908) (xy 360.545834 -183.817552) (xy 360.553067 -183.869684)
			(xy 360.553508 -183.896) (xy 360.553022 -183.923251) (xy 360.545266 -183.977199) (xy 360.529911 -184.029494)
			(xy 360.507269 -184.079071) (xy 360.477803 -184.124921) (xy 360.442112 -184.166112) (xy 360.400921 -184.201803)
			(xy 360.355071 -184.231269) (xy 360.305494 -184.253911) (xy 360.253199 -184.269266) (xy 360.199251 -184.277022)
			(xy 360.144749 -184.277022) (xy 360.090801 -184.269266) (xy 360.038506 -184.253911) (xy 359.988929 -184.231269)
			(xy 359.943079 -184.201803) (xy 359.901888 -184.166112) (xy 359.866197 -184.124921) (xy 359.836731 -184.079071)
			(xy 359.814089 -184.029494) (xy 359.798734 -183.977199) (xy 359.790978 -183.923251) (xy 359.790492 -183.896)
			(xy 359.790904 -183.870219) (xy 359.797849 -183.819125) (xy 359.811612 -183.769433) (xy 359.831942 -183.722047)
			(xy 359.858469 -183.677832) (xy 359.89071 -183.637591) (xy 359.928077 -183.60206) (xy 359.948734 -183.586628)
			(xy 359.959692 -183.578085) (xy 359.976988 -183.556358) (xy 359.987781 -183.530771) (xy 359.991271 -183.503221)
			(xy 359.987199 -183.475751) (xy 359.975867 -183.450398) (xy 359.958115 -183.429042) (xy 359.946956 -183.420766)
			(xy 359.925556 -183.405445) (xy 359.886816 -183.369815) (xy 359.853342 -183.329199) (xy 359.825767 -183.284367)
			(xy 359.804615 -183.236172) (xy 359.790288 -183.185526) (xy 359.783058 -183.133392) (xy 359.782618 -183.107076)
			(xy 357.00105 -183.107076) (xy 357.008149 -183.112984) (xy 357.045366 -183.154521) (xy 357.076139 -183.201034)
			(xy 357.099811 -183.251531) (xy 357.115879 -183.304938) (xy 357.123999 -183.360114) (xy 357.124508 -183.388)
			(xy 357.123999 -183.415886) (xy 357.115879 -183.471062) (xy 357.099811 -183.524469) (xy 357.076139 -183.574966)
			(xy 357.045366 -183.621479) (xy 357.008149 -183.663016) (xy 356.965281 -183.698691) (xy 356.917675 -183.727745)
			(xy 356.866346 -183.749557) (xy 356.812389 -183.763663) (xy 356.756952 -183.769763) (xy 356.701218 -183.767726)
			(xy 356.646375 -183.757596) (xy 356.593591 -183.739589) (xy 356.543991 -183.714088) (xy 356.498633 -183.681637)
			(xy 356.458484 -183.642928) (xy 356.424398 -183.598785) (xy 356.397102 -183.55015) (xy 356.377179 -183.498059)
			(xy 356.365053 -183.443622) (xy 356.360982 -183.388) (xy 352.230962 -183.388) (xy 352.236539 -183.406538)
			(xy 352.244659 -183.461714) (xy 352.245168 -183.4896) (xy 352.244659 -183.517486) (xy 352.236539 -183.572662)
			(xy 352.220471 -183.626069) (xy 352.196799 -183.676566) (xy 352.166026 -183.723079) (xy 352.128809 -183.764616)
			(xy 352.085941 -183.800291) (xy 352.038335 -183.829345) (xy 351.987006 -183.851157) (xy 351.933049 -183.865263)
			(xy 351.877612 -183.871363) (xy 351.821878 -183.869326) (xy 351.767035 -183.859196) (xy 351.714251 -183.841189)
			(xy 351.664651 -183.815688) (xy 351.619293 -183.783237) (xy 351.579144 -183.744528) (xy 351.545058 -183.700385)
			(xy 351.517762 -183.65175) (xy 351.497839 -183.599659) (xy 351.485713 -183.545222) (xy 351.481642 -183.4896)
			(xy 350.636317 -183.4896) (xy 350.636586 -183.504078) (xy 350.6361 -183.531329) (xy 350.628344 -183.585277)
			(xy 350.612989 -183.637572) (xy 350.590347 -183.687149) (xy 350.560881 -183.732999) (xy 350.52519 -183.77419)
			(xy 350.483999 -183.809881) (xy 350.438149 -183.839347) (xy 350.388572 -183.861989) (xy 350.336277 -183.877344)
			(xy 350.282329 -183.8851) (xy 350.227827 -183.8851) (xy 350.173879 -183.877344) (xy 350.121584 -183.861989)
			(xy 350.072007 -183.839347) (xy 350.026157 -183.809881) (xy 349.984966 -183.77419) (xy 349.949275 -183.732999)
			(xy 349.919809 -183.687149) (xy 349.897167 -183.637572) (xy 349.881812 -183.585277) (xy 349.874056 -183.531329)
			(xy 349.87357 -183.504078) (xy 336.902298 -183.504078) (xy 336.902298 -183.929782) (xy 340.11057 -183.929782)
			(xy 340.114641 -183.87416) (xy 340.126767 -183.819723) (xy 340.14669 -183.767632) (xy 340.173986 -183.718997)
			(xy 340.208072 -183.674854) (xy 340.248221 -183.636145) (xy 340.293579 -183.603694) (xy 340.343179 -183.578193)
			(xy 340.395963 -183.560186) (xy 340.450806 -183.550056) (xy 340.50654 -183.548019) (xy 340.561977 -183.554119)
			(xy 340.615934 -183.568225) (xy 340.667263 -183.590037) (xy 340.714869 -183.619091) (xy 340.757737 -183.654766)
			(xy 340.794954 -183.696303) (xy 340.825727 -183.742816) (xy 340.849399 -183.793313) (xy 340.865467 -183.84672)
			(xy 340.873587 -183.901896) (xy 340.874096 -183.929782) (xy 340.873587 -183.957668) (xy 340.865467 -184.012844)
			(xy 340.849399 -184.066251) (xy 340.825727 -184.116748) (xy 340.803727 -184.15) (xy 357.757982 -184.15)
			(xy 357.762053 -184.094378) (xy 357.774179 -184.039941) (xy 357.794102 -183.98785) (xy 357.821398 -183.939215)
			(xy 357.855484 -183.895072) (xy 357.895633 -183.856363) (xy 357.940991 -183.823912) (xy 357.990591 -183.798411)
			(xy 358.043375 -183.780404) (xy 358.098218 -183.770274) (xy 358.153952 -183.768237) (xy 358.209389 -183.774337)
			(xy 358.263346 -183.788443) (xy 358.314675 -183.810255) (xy 358.362281 -183.839309) (xy 358.405149 -183.874984)
			(xy 358.442366 -183.916521) (xy 358.473139 -183.963034) (xy 358.496811 -184.013531) (xy 358.512879 -184.066938)
			(xy 358.520999 -184.122114) (xy 358.521508 -184.15) (xy 358.520999 -184.177886) (xy 358.512879 -184.233062)
			(xy 358.496811 -184.286469) (xy 358.473139 -184.336966) (xy 358.442366 -184.383479) (xy 358.405149 -184.425016)
			(xy 358.362281 -184.460691) (xy 358.314675 -184.489745) (xy 358.263346 -184.511557) (xy 358.209389 -184.525663)
			(xy 358.153952 -184.531763) (xy 358.098218 -184.529726) (xy 358.043375 -184.519596) (xy 357.990591 -184.501589)
			(xy 357.940991 -184.476088) (xy 357.895633 -184.443637) (xy 357.855484 -184.404928) (xy 357.821398 -184.360785)
			(xy 357.794102 -184.31215) (xy 357.774179 -184.260059) (xy 357.762053 -184.205622) (xy 357.757982 -184.15)
			(xy 340.803727 -184.15) (xy 340.794954 -184.163261) (xy 340.757737 -184.204798) (xy 340.714869 -184.240473)
			(xy 340.667263 -184.269527) (xy 340.615934 -184.291339) (xy 340.561977 -184.305445) (xy 340.50654 -184.311545)
			(xy 340.450806 -184.309508) (xy 340.395963 -184.299378) (xy 340.343179 -184.281371) (xy 340.293579 -184.25587)
			(xy 340.248221 -184.223419) (xy 340.208072 -184.18471) (xy 340.173986 -184.140567) (xy 340.14669 -184.091932)
			(xy 340.126767 -184.039841) (xy 340.114641 -183.985404) (xy 340.11057 -183.929782) (xy 336.902298 -183.929782)
			(xy 336.902298 -185.028332) (xy 340.739982 -185.028332) (xy 340.744053 -184.97271) (xy 340.756179 -184.918273)
			(xy 340.776102 -184.866182) (xy 340.803398 -184.817547) (xy 340.837484 -184.773404) (xy 340.877633 -184.734695)
			(xy 340.922991 -184.702244) (xy 340.972591 -184.676743) (xy 341.025375 -184.658736) (xy 341.080218 -184.648606)
			(xy 341.135952 -184.646569) (xy 341.191389 -184.652669) (xy 341.245346 -184.666775) (xy 341.296675 -184.688587)
			(xy 341.344281 -184.717641) (xy 341.387149 -184.753316) (xy 341.424366 -184.794853) (xy 341.455139 -184.841366)
			(xy 341.478811 -184.891863) (xy 341.494879 -184.94527) (xy 341.502999 -185.000446) (xy 341.503355 -185.01995)
			(xy 351.007932 -185.01995) (xy 351.012003 -184.964328) (xy 351.024129 -184.909891) (xy 351.044052 -184.8578)
			(xy 351.071348 -184.809165) (xy 351.105434 -184.765022) (xy 351.145583 -184.726313) (xy 351.190941 -184.693862)
			(xy 351.240541 -184.668361) (xy 351.293325 -184.650354) (xy 351.348168 -184.640224) (xy 351.403902 -184.638187)
			(xy 351.459339 -184.644287) (xy 351.513296 -184.658393) (xy 351.564625 -184.680205) (xy 351.612231 -184.709259)
			(xy 351.655099 -184.744934) (xy 351.692316 -184.786471) (xy 351.723089 -184.832984) (xy 351.746761 -184.883481)
			(xy 351.762829 -184.936888) (xy 351.770949 -184.992064) (xy 351.771458 -185.01995) (xy 351.770949 -185.047836)
			(xy 351.762829 -185.103012) (xy 351.746761 -185.156419) (xy 351.74227 -185.166) (xy 357.757982 -185.166)
			(xy 357.762053 -185.110378) (xy 357.774179 -185.055941) (xy 357.794102 -185.00385) (xy 357.821398 -184.955215)
			(xy 357.855484 -184.911072) (xy 357.895633 -184.872363) (xy 357.940991 -184.839912) (xy 357.990591 -184.814411)
			(xy 358.043375 -184.796404) (xy 358.098218 -184.786274) (xy 358.153952 -184.784237) (xy 358.209389 -184.790337)
			(xy 358.263346 -184.804443) (xy 358.314675 -184.826255) (xy 358.362281 -184.855309) (xy 358.405149 -184.890984)
			(xy 358.442366 -184.932521) (xy 358.473139 -184.979034) (xy 358.496811 -185.029531) (xy 358.512879 -185.082938)
			(xy 358.520999 -185.138114) (xy 358.521508 -185.166) (xy 359.789982 -185.166) (xy 359.794053 -185.110378)
			(xy 359.806179 -185.055941) (xy 359.826102 -185.00385) (xy 359.853398 -184.955215) (xy 359.887484 -184.911072)
			(xy 359.927633 -184.872363) (xy 359.972991 -184.839912) (xy 360.022591 -184.814411) (xy 360.075375 -184.796404)
			(xy 360.130218 -184.786274) (xy 360.185952 -184.784237) (xy 360.241389 -184.790337) (xy 360.295346 -184.804443)
			(xy 360.346675 -184.826255) (xy 360.394281 -184.855309) (xy 360.437149 -184.890984) (xy 360.474366 -184.932521)
			(xy 360.505139 -184.979034) (xy 360.528811 -185.029531) (xy 360.544879 -185.082938) (xy 360.552999 -185.138114)
			(xy 360.553508 -185.166) (xy 362.583982 -185.166) (xy 362.588053 -185.110378) (xy 362.600179 -185.055941)
			(xy 362.620102 -185.00385) (xy 362.647398 -184.955215) (xy 362.681484 -184.911072) (xy 362.721633 -184.872363)
			(xy 362.766991 -184.839912) (xy 362.816591 -184.814411) (xy 362.869375 -184.796404) (xy 362.924218 -184.786274)
			(xy 362.979952 -184.784237) (xy 363.035389 -184.790337) (xy 363.089346 -184.804443) (xy 363.140675 -184.826255)
			(xy 363.188281 -184.855309) (xy 363.231149 -184.890984) (xy 363.241786 -184.902856) (xy 370.665246 -184.902856)
			(xy 370.669317 -184.847234) (xy 370.681443 -184.792797) (xy 370.701366 -184.740706) (xy 370.728662 -184.692071)
			(xy 370.762748 -184.647928) (xy 370.802897 -184.609219) (xy 370.848255 -184.576768) (xy 370.897855 -184.551267)
			(xy 370.950639 -184.53326) (xy 371.005482 -184.52313) (xy 371.061216 -184.521093) (xy 371.116653 -184.527193)
			(xy 371.17061 -184.541299) (xy 371.221939 -184.563111) (xy 371.269545 -184.592165) (xy 371.312413 -184.62784)
			(xy 371.34963 -184.669377) (xy 371.380403 -184.71589) (xy 371.404075 -184.766387) (xy 371.409675 -184.785)
			(xy 373.505982 -184.785) (xy 373.510053 -184.729378) (xy 373.522179 -184.674941) (xy 373.542102 -184.62285)
			(xy 373.569398 -184.574215) (xy 373.603484 -184.530072) (xy 373.643633 -184.491363) (xy 373.688991 -184.458912)
			(xy 373.738591 -184.433411) (xy 373.791375 -184.415404) (xy 373.846218 -184.405274) (xy 373.901952 -184.403237)
			(xy 373.957389 -184.409337) (xy 374.011346 -184.423443) (xy 374.062675 -184.445255) (xy 374.110281 -184.474309)
			(xy 374.153149 -184.509984) (xy 374.190366 -184.551521) (xy 374.221139 -184.598034) (xy 374.244811 -184.648531)
			(xy 374.260879 -184.701938) (xy 374.268999 -184.757114) (xy 374.269508 -184.785) (xy 374.268999 -184.812886)
			(xy 374.260879 -184.868062) (xy 374.244811 -184.921469) (xy 374.221139 -184.971966) (xy 374.190366 -185.018479)
			(xy 374.153149 -185.060016) (xy 374.110281 -185.095691) (xy 374.062675 -185.124745) (xy 374.011346 -185.146557)
			(xy 373.957389 -185.160663) (xy 373.901952 -185.166763) (xy 373.846218 -185.164726) (xy 373.791375 -185.154596)
			(xy 373.738591 -185.136589) (xy 373.688991 -185.111088) (xy 373.643633 -185.078637) (xy 373.603484 -185.039928)
			(xy 373.569398 -184.995785) (xy 373.542102 -184.94715) (xy 373.522179 -184.895059) (xy 373.510053 -184.840622)
			(xy 373.505982 -184.785) (xy 371.409675 -184.785) (xy 371.420143 -184.819794) (xy 371.428263 -184.87497)
			(xy 371.428772 -184.902856) (xy 371.428263 -184.930742) (xy 371.420143 -184.985918) (xy 371.404075 -185.039325)
			(xy 371.380403 -185.089822) (xy 371.34963 -185.136335) (xy 371.312413 -185.177872) (xy 371.269545 -185.213547)
			(xy 371.221939 -185.242601) (xy 371.17061 -185.264413) (xy 371.116653 -185.278519) (xy 371.061216 -185.284619)
			(xy 371.005482 -185.282582) (xy 370.950639 -185.272452) (xy 370.897855 -185.254445) (xy 370.848255 -185.228944)
			(xy 370.802897 -185.196493) (xy 370.762748 -185.157784) (xy 370.728662 -185.113641) (xy 370.701366 -185.065006)
			(xy 370.681443 -185.012915) (xy 370.669317 -184.958478) (xy 370.665246 -184.902856) (xy 363.241786 -184.902856)
			(xy 363.268366 -184.932521) (xy 363.299139 -184.979034) (xy 363.322811 -185.029531) (xy 363.338879 -185.082938)
			(xy 363.346999 -185.138114) (xy 363.347508 -185.166) (xy 363.346999 -185.193886) (xy 363.338879 -185.249062)
			(xy 363.322811 -185.302469) (xy 363.299139 -185.352966) (xy 363.268366 -185.399479) (xy 363.231149 -185.441016)
			(xy 363.188281 -185.476691) (xy 363.140675 -185.505745) (xy 363.089346 -185.527557) (xy 363.035389 -185.541663)
			(xy 362.979952 -185.547763) (xy 362.924218 -185.545726) (xy 362.869375 -185.535596) (xy 362.816591 -185.517589)
			(xy 362.766991 -185.492088) (xy 362.721633 -185.459637) (xy 362.681484 -185.420928) (xy 362.647398 -185.376785)
			(xy 362.620102 -185.32815) (xy 362.600179 -185.276059) (xy 362.588053 -185.221622) (xy 362.583982 -185.166)
			(xy 360.553508 -185.166) (xy 360.552999 -185.193886) (xy 360.544879 -185.249062) (xy 360.528811 -185.302469)
			(xy 360.505139 -185.352966) (xy 360.474366 -185.399479) (xy 360.437149 -185.441016) (xy 360.394281 -185.476691)
			(xy 360.346675 -185.505745) (xy 360.295346 -185.527557) (xy 360.241389 -185.541663) (xy 360.185952 -185.547763)
			(xy 360.130218 -185.545726) (xy 360.075375 -185.535596) (xy 360.022591 -185.517589) (xy 359.972991 -185.492088)
			(xy 359.927633 -185.459637) (xy 359.887484 -185.420928) (xy 359.853398 -185.376785) (xy 359.826102 -185.32815)
			(xy 359.806179 -185.276059) (xy 359.794053 -185.221622) (xy 359.789982 -185.166) (xy 358.521508 -185.166)
			(xy 358.520999 -185.193886) (xy 358.512879 -185.249062) (xy 358.496811 -185.302469) (xy 358.473139 -185.352966)
			(xy 358.442366 -185.399479) (xy 358.405149 -185.441016) (xy 358.362281 -185.476691) (xy 358.314675 -185.505745)
			(xy 358.263346 -185.527557) (xy 358.209389 -185.541663) (xy 358.153952 -185.547763) (xy 358.098218 -185.545726)
			(xy 358.043375 -185.535596) (xy 357.990591 -185.517589) (xy 357.940991 -185.492088) (xy 357.895633 -185.459637)
			(xy 357.855484 -185.420928) (xy 357.821398 -185.376785) (xy 357.794102 -185.32815) (xy 357.774179 -185.276059)
			(xy 357.762053 -185.221622) (xy 357.757982 -185.166) (xy 351.74227 -185.166) (xy 351.723089 -185.206916)
			(xy 351.692316 -185.253429) (xy 351.655099 -185.294966) (xy 351.612231 -185.330641) (xy 351.564625 -185.359695)
			(xy 351.513296 -185.381507) (xy 351.459339 -185.395613) (xy 351.403902 -185.401713) (xy 351.348168 -185.399676)
			(xy 351.293325 -185.389546) (xy 351.240541 -185.371539) (xy 351.190941 -185.346038) (xy 351.145583 -185.313587)
			(xy 351.105434 -185.274878) (xy 351.071348 -185.230735) (xy 351.044052 -185.1821) (xy 351.024129 -185.130009)
			(xy 351.012003 -185.075572) (xy 351.007932 -185.01995) (xy 341.503355 -185.01995) (xy 341.503508 -185.028332)
			(xy 341.502999 -185.056218) (xy 341.494879 -185.111394) (xy 341.478811 -185.164801) (xy 341.455139 -185.215298)
			(xy 341.424366 -185.261811) (xy 341.387149 -185.303348) (xy 341.344281 -185.339023) (xy 341.296675 -185.368077)
			(xy 341.245346 -185.389889) (xy 341.191389 -185.403995) (xy 341.135952 -185.410095) (xy 341.080218 -185.408058)
			(xy 341.025375 -185.397928) (xy 340.972591 -185.379921) (xy 340.922991 -185.35442) (xy 340.877633 -185.321969)
			(xy 340.837484 -185.28326) (xy 340.803398 -185.239117) (xy 340.776102 -185.190482) (xy 340.756179 -185.138391)
			(xy 340.744053 -185.083954) (xy 340.739982 -185.028332) (xy 336.902298 -185.028332) (xy 336.902298 -185.584846)
			(xy 336.902775 -185.594941) (xy 336.91062 -185.613549) (xy 336.917538 -185.620914) (xy 336.92846 -185.630312)
			(xy 336.928968 -185.63082) (xy 336.964528 -185.662316) (xy 336.967322 -185.664856) (xy 336.973672 -185.66892)
			(xy 336.977445 -185.671257) (xy 336.979134 -185.671968) (xy 364.803434 -185.671968) (xy 364.807505 -185.616346)
			(xy 364.819631 -185.561909) (xy 364.839554 -185.509818) (xy 364.86685 -185.461183) (xy 364.900936 -185.41704)
			(xy 364.941085 -185.378331) (xy 364.986443 -185.34588) (xy 365.036043 -185.320379) (xy 365.088827 -185.302372)
			(xy 365.14367 -185.292242) (xy 365.199404 -185.290205) (xy 365.254841 -185.296305) (xy 365.308798 -185.310411)
			(xy 365.360127 -185.332223) (xy 365.407733 -185.361277) (xy 365.450601 -185.396952) (xy 365.487818 -185.438489)
			(xy 365.518591 -185.485002) (xy 365.542263 -185.535499) (xy 365.558331 -185.588906) (xy 365.560948 -185.60669)
			(xy 367.120422 -185.60669) (xy 367.124493 -185.551068) (xy 367.136619 -185.496631) (xy 367.156542 -185.44454)
			(xy 367.183838 -185.395905) (xy 367.217924 -185.351762) (xy 367.258073 -185.313053) (xy 367.303431 -185.280602)
			(xy 367.353031 -185.255101) (xy 367.405815 -185.237094) (xy 367.460658 -185.226964) (xy 367.516392 -185.224927)
			(xy 367.571829 -185.231027) (xy 367.625786 -185.245133) (xy 367.677115 -185.266945) (xy 367.724721 -185.295999)
			(xy 367.767589 -185.331674) (xy 367.804806 -185.373211) (xy 367.835579 -185.419724) (xy 367.859251 -185.470221)
			(xy 367.875319 -185.523628) (xy 367.883439 -185.578804) (xy 367.883948 -185.60669) (xy 367.883439 -185.634576)
			(xy 367.875319 -185.689752) (xy 367.859251 -185.743159) (xy 367.835579 -185.793656) (xy 367.83072 -185.801)
			(xy 375.537982 -185.801) (xy 375.542053 -185.745378) (xy 375.554179 -185.690941) (xy 375.574102 -185.63885)
			(xy 375.601398 -185.590215) (xy 375.635484 -185.546072) (xy 375.675633 -185.507363) (xy 375.720991 -185.474912)
			(xy 375.770591 -185.449411) (xy 375.823375 -185.431404) (xy 375.878218 -185.421274) (xy 375.933952 -185.419237)
			(xy 375.989389 -185.425337) (xy 376.043346 -185.439443) (xy 376.094675 -185.461255) (xy 376.142281 -185.490309)
			(xy 376.185149 -185.525984) (xy 376.222366 -185.567521) (xy 376.253139 -185.614034) (xy 376.276811 -185.664531)
			(xy 376.292879 -185.717938) (xy 376.300999 -185.773114) (xy 376.301508 -185.801) (xy 377.569982 -185.801)
			(xy 377.574053 -185.745378) (xy 377.586179 -185.690941) (xy 377.606102 -185.63885) (xy 377.633398 -185.590215)
			(xy 377.667484 -185.546072) (xy 377.707633 -185.507363) (xy 377.752991 -185.474912) (xy 377.802591 -185.449411)
			(xy 377.855375 -185.431404) (xy 377.910218 -185.421274) (xy 377.965952 -185.419237) (xy 378.021389 -185.425337)
			(xy 378.075346 -185.439443) (xy 378.126675 -185.461255) (xy 378.174281 -185.490309) (xy 378.217149 -185.525984)
			(xy 378.254366 -185.567521) (xy 378.285139 -185.614034) (xy 378.308811 -185.664531) (xy 378.324879 -185.717938)
			(xy 378.332999 -185.773114) (xy 378.333508 -185.801) (xy 378.332999 -185.828886) (xy 378.324879 -185.884062)
			(xy 378.308811 -185.937469) (xy 378.285139 -185.987966) (xy 378.254366 -186.034479) (xy 378.217149 -186.076016)
			(xy 378.174281 -186.111691) (xy 378.126675 -186.140745) (xy 378.075346 -186.162557) (xy 378.021389 -186.176663)
			(xy 377.965952 -186.182763) (xy 377.910218 -186.180726) (xy 377.855375 -186.170596) (xy 377.802591 -186.152589)
			(xy 377.752991 -186.127088) (xy 377.707633 -186.094637) (xy 377.667484 -186.055928) (xy 377.633398 -186.011785)
			(xy 377.606102 -185.96315) (xy 377.586179 -185.911059) (xy 377.574053 -185.856622) (xy 377.569982 -185.801)
			(xy 376.301508 -185.801) (xy 376.300999 -185.828886) (xy 376.292879 -185.884062) (xy 376.276811 -185.937469)
			(xy 376.253139 -185.987966) (xy 376.222366 -186.034479) (xy 376.185149 -186.076016) (xy 376.142281 -186.111691)
			(xy 376.094675 -186.140745) (xy 376.043346 -186.162557) (xy 375.989389 -186.176663) (xy 375.933952 -186.182763)
			(xy 375.878218 -186.180726) (xy 375.823375 -186.170596) (xy 375.770591 -186.152589) (xy 375.720991 -186.127088)
			(xy 375.675633 -186.094637) (xy 375.635484 -186.055928) (xy 375.601398 -186.011785) (xy 375.574102 -185.96315)
			(xy 375.554179 -185.911059) (xy 375.542053 -185.856622) (xy 375.537982 -185.801) (xy 367.83072 -185.801)
			(xy 367.804806 -185.840169) (xy 367.767589 -185.881706) (xy 367.724721 -185.917381) (xy 367.677115 -185.946435)
			(xy 367.625786 -185.968247) (xy 367.571829 -185.982353) (xy 367.516392 -185.988453) (xy 367.460658 -185.986416)
			(xy 367.405815 -185.976286) (xy 367.353031 -185.958279) (xy 367.303431 -185.932778) (xy 367.258073 -185.900327)
			(xy 367.217924 -185.861618) (xy 367.183838 -185.817475) (xy 367.156542 -185.76884) (xy 367.136619 -185.716749)
			(xy 367.124493 -185.662312) (xy 367.120422 -185.60669) (xy 365.560948 -185.60669) (xy 365.566451 -185.644082)
			(xy 365.56696 -185.671968) (xy 365.566451 -185.699854) (xy 365.558331 -185.75503) (xy 365.542263 -185.808437)
			(xy 365.518591 -185.858934) (xy 365.487818 -185.905447) (xy 365.450601 -185.946984) (xy 365.407733 -185.982659)
			(xy 365.360127 -186.011713) (xy 365.308798 -186.033525) (xy 365.254841 -186.047631) (xy 365.199404 -186.053731)
			(xy 365.14367 -186.051694) (xy 365.088827 -186.041564) (xy 365.036043 -186.023557) (xy 364.986443 -185.998056)
			(xy 364.941085 -185.965605) (xy 364.900936 -185.926896) (xy 364.86685 -185.882753) (xy 364.839554 -185.834118)
			(xy 364.819631 -185.782027) (xy 364.807505 -185.72759) (xy 364.803434 -185.671968) (xy 336.979134 -185.671968)
			(xy 336.985623 -185.674699) (xy 336.989928 -185.675778) (xy 336.99831 -185.677556) (xy 337.0072 -185.67654)
			(xy 337.020916 -185.675016) (xy 337.021424 -185.675016) (xy 337.02371 -185.674762) (xy 337.057492 -185.673238)
			(xy 337.058 -185.673238) (xy 337.085269 -185.673724) (xy 337.139253 -185.681486) (xy 337.191583 -185.696851)
			(xy 337.241193 -185.719508) (xy 337.287074 -185.748994) (xy 337.328291 -185.784709) (xy 337.364006 -185.825926)
			(xy 337.393492 -185.871807) (xy 337.416149 -185.921417) (xy 337.431514 -185.973747) (xy 337.439276 -186.027731)
			(xy 337.439276 -186.055) (xy 338.707982 -186.055) (xy 338.712053 -185.999378) (xy 338.724179 -185.944941)
			(xy 338.744102 -185.89285) (xy 338.771398 -185.844215) (xy 338.805484 -185.800072) (xy 338.845633 -185.761363)
			(xy 338.890991 -185.728912) (xy 338.940591 -185.703411) (xy 338.993375 -185.685404) (xy 339.048218 -185.675274)
			(xy 339.103952 -185.673237) (xy 339.159389 -185.679337) (xy 339.213346 -185.693443) (xy 339.264675 -185.715255)
			(xy 339.312281 -185.744309) (xy 339.355149 -185.779984) (xy 339.392366 -185.821521) (xy 339.423139 -185.868034)
			(xy 339.446811 -185.918531) (xy 339.462879 -185.971938) (xy 339.470999 -186.027114) (xy 339.471508 -186.055)
			(xy 339.470999 -186.082886) (xy 339.462879 -186.138062) (xy 339.44966 -186.182) (xy 359.789982 -186.182)
			(xy 359.794053 -186.126378) (xy 359.806179 -186.071941) (xy 359.826102 -186.01985) (xy 359.853398 -185.971215)
			(xy 359.887484 -185.927072) (xy 359.927633 -185.888363) (xy 359.972991 -185.855912) (xy 360.022591 -185.830411)
			(xy 360.075375 -185.812404) (xy 360.130218 -185.802274) (xy 360.185952 -185.800237) (xy 360.241389 -185.806337)
			(xy 360.295346 -185.820443) (xy 360.346675 -185.842255) (xy 360.394281 -185.871309) (xy 360.437149 -185.906984)
			(xy 360.474366 -185.948521) (xy 360.505139 -185.995034) (xy 360.528811 -186.045531) (xy 360.544879 -186.098938)
			(xy 360.552999 -186.154114) (xy 360.553508 -186.182) (xy 360.552999 -186.209886) (xy 360.544879 -186.265062)
			(xy 360.528811 -186.318469) (xy 360.505139 -186.368966) (xy 360.474366 -186.415479) (xy 360.437149 -186.457016)
			(xy 360.394281 -186.492691) (xy 360.346675 -186.521745) (xy 360.295346 -186.543557) (xy 360.241389 -186.557663)
			(xy 360.185952 -186.563763) (xy 360.130218 -186.561726) (xy 360.075375 -186.551596) (xy 360.022591 -186.533589)
			(xy 359.972991 -186.508088) (xy 359.927633 -186.475637) (xy 359.887484 -186.436928) (xy 359.853398 -186.392785)
			(xy 359.826102 -186.34415) (xy 359.806179 -186.292059) (xy 359.794053 -186.237622) (xy 359.789982 -186.182)
			(xy 339.44966 -186.182) (xy 339.446811 -186.191469) (xy 339.423139 -186.241966) (xy 339.392366 -186.288479)
			(xy 339.355149 -186.330016) (xy 339.312281 -186.365691) (xy 339.264675 -186.394745) (xy 339.213346 -186.416557)
			(xy 339.159389 -186.430663) (xy 339.103952 -186.436763) (xy 339.048218 -186.434726) (xy 338.993375 -186.424596)
			(xy 338.940591 -186.406589) (xy 338.890991 -186.381088) (xy 338.845633 -186.348637) (xy 338.805484 -186.309928)
			(xy 338.771398 -186.265785) (xy 338.744102 -186.21715) (xy 338.724179 -186.165059) (xy 338.712053 -186.110622)
			(xy 338.707982 -186.055) (xy 337.439276 -186.055) (xy 337.439276 -186.082269) (xy 337.431514 -186.136253)
			(xy 337.416149 -186.188583) (xy 337.393492 -186.238193) (xy 337.364006 -186.284074) (xy 337.328291 -186.325291)
			(xy 337.287074 -186.361006) (xy 337.241193 -186.390492) (xy 337.191583 -186.413149) (xy 337.139253 -186.428514)
			(xy 337.085269 -186.436276) (xy 337.058 -186.436762) (xy 337.057238 -186.436762) (xy 337.045267 -186.436648)
			(xy 337.021374 -186.435121) (xy 337.009486 -186.433714) (xy 337.008724 -186.433714) (xy 337.007454 -186.43346)
			(xy 336.996786 -186.431936) (xy 336.989928 -186.433968) (xy 336.986626 -186.434984) (xy 336.98142 -186.436588)
			(xy 336.971814 -186.44172) (xy 336.967576 -186.445144) (xy 336.918046 -186.488324) (xy 336.910926 -186.495749)
			(xy 336.902802 -186.514626) (xy 336.902298 -186.5249) (xy 336.902298 -186.591194) (xy 336.902818 -186.601465)
			(xy 336.910934 -186.620342) (xy 336.918046 -186.62777) (xy 336.923634 -186.63285) (xy 336.924396 -186.633612)
			(xy 336.965036 -186.669934) (xy 336.972229 -186.675799) (xy 336.989547 -186.682436) (xy 336.998818 -186.682888)
			(xy 337.004152 -186.682888) (xy 337.006946 -186.682634) (xy 337.017766 -186.681457) (xy 337.039496 -186.680184)
			(xy 337.05038 -186.680094) (xy 337.077655 -186.680556) (xy 337.13165 -186.688317) (xy 337.183991 -186.703683)
			(xy 337.233613 -186.726342) (xy 337.279504 -186.755833) (xy 337.320732 -186.791554) (xy 337.356455 -186.83278)
			(xy 337.385948 -186.87867) (xy 337.399312 -186.907932) (xy 356.297228 -186.907932) (xy 356.301299 -186.85231)
			(xy 356.313425 -186.797873) (xy 356.333348 -186.745782) (xy 356.360644 -186.697147) (xy 356.39473 -186.653004)
			(xy 356.434879 -186.614295) (xy 356.480237 -186.581844) (xy 356.529837 -186.556343) (xy 356.582621 -186.538336)
			(xy 356.637464 -186.528206) (xy 356.693198 -186.526169) (xy 356.748635 -186.532269) (xy 356.802592 -186.546375)
			(xy 356.853921 -186.568187) (xy 356.901527 -186.597241) (xy 356.944395 -186.632916) (xy 356.981612 -186.674453)
			(xy 356.985344 -186.680094) (xy 362.911388 -186.680094) (xy 362.915459 -186.624472) (xy 362.927585 -186.570035)
			(xy 362.947508 -186.517944) (xy 362.974804 -186.469309) (xy 363.00889 -186.425166) (xy 363.049039 -186.386457)
			(xy 363.094397 -186.354006) (xy 363.143997 -186.328505) (xy 363.196781 -186.310498) (xy 363.251624 -186.300368)
			(xy 363.307358 -186.298331) (xy 363.362795 -186.304431) (xy 363.416752 -186.318537) (xy 363.468081 -186.340349)
			(xy 363.515687 -186.369403) (xy 363.558555 -186.405078) (xy 363.595772 -186.446615) (xy 363.626545 -186.493128)
			(xy 363.650217 -186.543625) (xy 363.666285 -186.597032) (xy 363.674405 -186.652208) (xy 363.674914 -186.680094)
			(xy 363.674405 -186.70798) (xy 363.666285 -186.763156) (xy 363.650217 -186.816563) (xy 363.645726 -186.826144)
			(xy 367.0841 -186.826144) (xy 367.088171 -186.770522) (xy 367.100297 -186.716085) (xy 367.12022 -186.663994)
			(xy 367.147516 -186.615359) (xy 367.181602 -186.571216) (xy 367.221751 -186.532507) (xy 367.267109 -186.500056)
			(xy 367.316709 -186.474555) (xy 367.369493 -186.456548) (xy 367.424336 -186.446418) (xy 367.48007 -186.444381)
			(xy 367.535507 -186.450481) (xy 367.589464 -186.464587) (xy 367.640793 -186.486399) (xy 367.688399 -186.515453)
			(xy 367.731267 -186.551128) (xy 367.768484 -186.592665) (xy 367.799257 -186.639178) (xy 367.822929 -186.689675)
			(xy 367.838997 -186.743082) (xy 367.847117 -186.798258) (xy 367.847459 -186.817) (xy 375.45086 -186.817)
			(xy 375.454931 -186.761378) (xy 375.467057 -186.706941) (xy 375.48698 -186.65485) (xy 375.514276 -186.606215)
			(xy 375.548362 -186.562072) (xy 375.588511 -186.523363) (xy 375.633869 -186.490912) (xy 375.683469 -186.465411)
			(xy 375.736253 -186.447404) (xy 375.791096 -186.437274) (xy 375.84683 -186.435237) (xy 375.902267 -186.441337)
			(xy 375.956224 -186.455443) (xy 376.007553 -186.477255) (xy 376.055159 -186.506309) (xy 376.098027 -186.541984)
			(xy 376.135244 -186.583521) (xy 376.166017 -186.630034) (xy 376.189689 -186.680531) (xy 376.205757 -186.733938)
			(xy 376.213877 -186.789114) (xy 376.214386 -186.817) (xy 376.213877 -186.844886) (xy 376.205757 -186.900062)
			(xy 376.189689 -186.953469) (xy 376.166017 -187.003966) (xy 376.135244 -187.050479) (xy 376.098027 -187.092016)
			(xy 376.055159 -187.127691) (xy 376.007553 -187.156745) (xy 375.956224 -187.178557) (xy 375.902267 -187.192663)
			(xy 375.84683 -187.198763) (xy 375.791096 -187.196726) (xy 375.736253 -187.186596) (xy 375.683469 -187.168589)
			(xy 375.633869 -187.143088) (xy 375.588511 -187.110637) (xy 375.548362 -187.071928) (xy 375.514276 -187.027785)
			(xy 375.48698 -186.97915) (xy 375.467057 -186.927059) (xy 375.454931 -186.872622) (xy 375.45086 -186.817)
			(xy 367.847459 -186.817) (xy 367.847626 -186.826144) (xy 367.847117 -186.85403) (xy 367.838997 -186.909206)
			(xy 367.822929 -186.962613) (xy 367.799257 -187.01311) (xy 367.768484 -187.059623) (xy 367.731267 -187.10116)
			(xy 367.688399 -187.136835) (xy 367.640793 -187.165889) (xy 367.589464 -187.187701) (xy 367.535507 -187.201807)
			(xy 367.48007 -187.207907) (xy 367.424336 -187.20587) (xy 367.369493 -187.19574) (xy 367.316709 -187.177733)
			(xy 367.267109 -187.152232) (xy 367.221751 -187.119781) (xy 367.181602 -187.081072) (xy 367.147516 -187.036929)
			(xy 367.12022 -186.988294) (xy 367.100297 -186.936203) (xy 367.088171 -186.881766) (xy 367.0841 -186.826144)
			(xy 363.645726 -186.826144) (xy 363.626545 -186.86706) (xy 363.595772 -186.913573) (xy 363.558555 -186.95511)
			(xy 363.515687 -186.990785) (xy 363.468081 -187.019839) (xy 363.416752 -187.041651) (xy 363.362795 -187.055757)
			(xy 363.307358 -187.061857) (xy 363.251624 -187.05982) (xy 363.196781 -187.04969) (xy 363.143997 -187.031683)
			(xy 363.094397 -187.006182) (xy 363.049039 -186.973731) (xy 363.00889 -186.935022) (xy 362.974804 -186.890879)
			(xy 362.947508 -186.842244) (xy 362.927585 -186.790153) (xy 362.915459 -186.735716) (xy 362.911388 -186.680094)
			(xy 356.985344 -186.680094) (xy 357.012385 -186.720966) (xy 357.036057 -186.771463) (xy 357.052125 -186.82487)
			(xy 357.060245 -186.880046) (xy 357.060754 -186.907932) (xy 357.060245 -186.935818) (xy 357.052125 -186.990994)
			(xy 357.036057 -187.044401) (xy 357.012385 -187.094898) (xy 356.981612 -187.141411) (xy 356.944395 -187.182948)
			(xy 356.901527 -187.218623) (xy 356.853921 -187.247677) (xy 356.802592 -187.269489) (xy 356.748635 -187.283595)
			(xy 356.693198 -187.289695) (xy 356.637464 -187.287658) (xy 356.582621 -187.277528) (xy 356.529837 -187.259521)
			(xy 356.480237 -187.23402) (xy 356.434879 -187.201569) (xy 356.39473 -187.16286) (xy 356.360644 -187.118717)
			(xy 356.333348 -187.070082) (xy 356.313425 -187.017991) (xy 356.301299 -186.963554) (xy 356.297228 -186.907932)
			(xy 337.399312 -186.907932) (xy 337.40861 -186.92829) (xy 337.423979 -186.98063) (xy 337.431742 -187.034625)
			(xy 337.431742 -187.089175) (xy 337.423979 -187.14317) (xy 337.40861 -187.19551) (xy 337.385948 -187.24513)
			(xy 337.356455 -187.29102) (xy 337.320732 -187.332246) (xy 337.279504 -187.367967) (xy 337.277196 -187.36945)
			(xy 339.129876 -187.36945) (xy 339.133947 -187.313828) (xy 339.146073 -187.259391) (xy 339.165996 -187.2073)
			(xy 339.193292 -187.158665) (xy 339.227378 -187.114522) (xy 339.267527 -187.075813) (xy 339.312885 -187.043362)
			(xy 339.362485 -187.017861) (xy 339.415269 -186.999854) (xy 339.470112 -186.989724) (xy 339.525846 -186.987687)
			(xy 339.581283 -186.993787) (xy 339.63524 -187.007893) (xy 339.686569 -187.029705) (xy 339.734175 -187.058759)
			(xy 339.777043 -187.094434) (xy 339.81426 -187.135971) (xy 339.845033 -187.182484) (xy 339.868705 -187.232981)
			(xy 339.884773 -187.286388) (xy 339.892893 -187.341564) (xy 339.893402 -187.36945) (xy 341.189054 -187.36945)
			(xy 341.193125 -187.313828) (xy 341.205251 -187.259391) (xy 341.225174 -187.2073) (xy 341.25247 -187.158665)
			(xy 341.286556 -187.114522) (xy 341.326705 -187.075813) (xy 341.372063 -187.043362) (xy 341.421663 -187.017861)
			(xy 341.474447 -186.999854) (xy 341.52929 -186.989724) (xy 341.585024 -186.987687) (xy 341.640461 -186.993787)
			(xy 341.694418 -187.007893) (xy 341.745747 -187.029705) (xy 341.793353 -187.058759) (xy 341.836221 -187.094434)
			(xy 341.873438 -187.135971) (xy 341.904211 -187.182484) (xy 341.927883 -187.232981) (xy 341.943951 -187.286388)
			(xy 341.952071 -187.341564) (xy 341.95258 -187.36945) (xy 341.952071 -187.397336) (xy 341.943951 -187.452512)
			(xy 341.927883 -187.505919) (xy 341.904211 -187.556416) (xy 341.873438 -187.602929) (xy 341.836221 -187.644466)
			(xy 341.793353 -187.680141) (xy 341.745747 -187.709195) (xy 341.694418 -187.731007) (xy 341.640461 -187.745113)
			(xy 341.585024 -187.751213) (xy 341.52929 -187.749176) (xy 341.474447 -187.739046) (xy 341.421663 -187.721039)
			(xy 341.372063 -187.695538) (xy 341.326705 -187.663087) (xy 341.286556 -187.624378) (xy 341.25247 -187.580235)
			(xy 341.225174 -187.5316) (xy 341.205251 -187.479509) (xy 341.193125 -187.425072) (xy 341.189054 -187.36945)
			(xy 339.893402 -187.36945) (xy 339.892893 -187.397336) (xy 339.884773 -187.452512) (xy 339.868705 -187.505919)
			(xy 339.845033 -187.556416) (xy 339.81426 -187.602929) (xy 339.777043 -187.644466) (xy 339.734175 -187.680141)
			(xy 339.686569 -187.709195) (xy 339.63524 -187.731007) (xy 339.581283 -187.745113) (xy 339.525846 -187.751213)
			(xy 339.470112 -187.749176) (xy 339.415269 -187.739046) (xy 339.362485 -187.721039) (xy 339.312885 -187.695538)
			(xy 339.267527 -187.663087) (xy 339.227378 -187.624378) (xy 339.193292 -187.580235) (xy 339.165996 -187.5316)
			(xy 339.146073 -187.479509) (xy 339.133947 -187.425072) (xy 339.129876 -187.36945) (xy 337.277196 -187.36945)
			(xy 337.233613 -187.397458) (xy 337.183991 -187.420117) (xy 337.13165 -187.435483) (xy 337.077655 -187.443244)
			(xy 337.05038 -187.443618) (xy 337.039051 -187.443573) (xy 337.01643 -187.442301) (xy 337.005168 -187.441078)
			(xy 337.000596 -187.44057) (xy 336.996871 -187.440548) (xy 336.989477 -187.441444) (xy 336.985864 -187.442348)
			(xy 336.98434 -187.442856) (xy 336.972148 -187.448444) (xy 336.965544 -187.453524) (xy 336.924396 -187.4901)
			(xy 336.923634 -187.490862) (xy 336.91957 -187.494418) (xy 336.911766 -187.501951) (xy 336.90281 -187.521684)
			(xy 336.902298 -187.532518) (xy 336.902298 -188.38545) (xy 341.189054 -188.38545) (xy 341.193125 -188.329828)
			(xy 341.205251 -188.275391) (xy 341.225174 -188.2233) (xy 341.25247 -188.174665) (xy 341.286556 -188.130522)
			(xy 341.326705 -188.091813) (xy 341.372063 -188.059362) (xy 341.421663 -188.033861) (xy 341.474447 -188.015854)
			(xy 341.52929 -188.005724) (xy 341.585024 -188.003687) (xy 341.640461 -188.009787) (xy 341.694418 -188.023893)
			(xy 341.745747 -188.045705) (xy 341.793353 -188.074759) (xy 341.836221 -188.110434) (xy 341.873438 -188.151971)
			(xy 341.904211 -188.198484) (xy 341.911485 -188.214) (xy 357.757982 -188.214) (xy 357.762053 -188.158378)
			(xy 357.774179 -188.103941) (xy 357.794102 -188.05185) (xy 357.821398 -188.003215) (xy 357.855484 -187.959072)
			(xy 357.895633 -187.920363) (xy 357.940991 -187.887912) (xy 357.990591 -187.862411) (xy 358.043375 -187.844404)
			(xy 358.098218 -187.834274) (xy 358.153952 -187.832237) (xy 358.209389 -187.838337) (xy 358.263346 -187.852443)
			(xy 358.314675 -187.874255) (xy 358.362281 -187.903309) (xy 358.405149 -187.938984) (xy 358.423979 -187.96)
			(xy 359.789982 -187.96) (xy 359.794053 -187.904378) (xy 359.806179 -187.849941) (xy 359.826102 -187.79785)
			(xy 359.853398 -187.749215) (xy 359.887484 -187.705072) (xy 359.927633 -187.666363) (xy 359.972991 -187.633912)
			(xy 360.022591 -187.608411) (xy 360.075375 -187.590404) (xy 360.130218 -187.580274) (xy 360.185952 -187.578237)
			(xy 360.241389 -187.584337) (xy 360.295346 -187.598443) (xy 360.346675 -187.620255) (xy 360.394281 -187.649309)
			(xy 360.437149 -187.684984) (xy 360.474366 -187.726521) (xy 360.505139 -187.773034) (xy 360.507054 -187.77712)
			(xy 373.201436 -187.77712) (xy 373.205507 -187.721498) (xy 373.217633 -187.667061) (xy 373.237556 -187.61497)
			(xy 373.264852 -187.566335) (xy 373.298938 -187.522192) (xy 373.339087 -187.483483) (xy 373.384445 -187.451032)
			(xy 373.434045 -187.425531) (xy 373.486829 -187.407524) (xy 373.541672 -187.397394) (xy 373.597406 -187.395357)
			(xy 373.652843 -187.401457) (xy 373.7068 -187.415563) (xy 373.758129 -187.437375) (xy 373.805735 -187.466429)
			(xy 373.848603 -187.502104) (xy 373.88582 -187.543641) (xy 373.916593 -187.590154) (xy 373.940265 -187.640651)
			(xy 373.956333 -187.694058) (xy 373.964453 -187.749234) (xy 373.964962 -187.77712) (xy 373.964453 -187.805006)
			(xy 373.960333 -187.833) (xy 375.537982 -187.833) (xy 375.542053 -187.777378) (xy 375.554179 -187.722941)
			(xy 375.574102 -187.67085) (xy 375.601398 -187.622215) (xy 375.635484 -187.578072) (xy 375.675633 -187.539363)
			(xy 375.720991 -187.506912) (xy 375.770591 -187.481411) (xy 375.823375 -187.463404) (xy 375.878218 -187.453274)
			(xy 375.933952 -187.451237) (xy 375.989389 -187.457337) (xy 376.043346 -187.471443) (xy 376.094675 -187.493255)
			(xy 376.142281 -187.522309) (xy 376.185149 -187.557984) (xy 376.222366 -187.599521) (xy 376.253139 -187.646034)
			(xy 376.276811 -187.696531) (xy 376.292879 -187.749938) (xy 376.300999 -187.805114) (xy 376.301508 -187.833)
			(xy 377.755656 -187.833) (xy 377.759727 -187.777378) (xy 377.771853 -187.722941) (xy 377.791776 -187.67085)
			(xy 377.819072 -187.622215) (xy 377.853158 -187.578072) (xy 377.893307 -187.539363) (xy 377.938665 -187.506912)
			(xy 377.988265 -187.481411) (xy 378.041049 -187.463404) (xy 378.095892 -187.453274) (xy 378.151626 -187.451237)
			(xy 378.207063 -187.457337) (xy 378.26102 -187.471443) (xy 378.312349 -187.493255) (xy 378.359955 -187.522309)
			(xy 378.402823 -187.557984) (xy 378.44004 -187.599521) (xy 378.470813 -187.646034) (xy 378.494485 -187.696531)
			(xy 378.510553 -187.749938) (xy 378.518673 -187.805114) (xy 378.519182 -187.833) (xy 378.518673 -187.860886)
			(xy 378.510553 -187.916062) (xy 378.494485 -187.969469) (xy 378.470813 -188.019966) (xy 378.44004 -188.066479)
			(xy 378.402823 -188.108016) (xy 378.359955 -188.143691) (xy 378.312349 -188.172745) (xy 378.26102 -188.194557)
			(xy 378.207063 -188.208663) (xy 378.151626 -188.214763) (xy 378.095892 -188.212726) (xy 378.041049 -188.202596)
			(xy 377.988265 -188.184589) (xy 377.938665 -188.159088) (xy 377.893307 -188.126637) (xy 377.853158 -188.087928)
			(xy 377.819072 -188.043785) (xy 377.791776 -187.99515) (xy 377.771853 -187.943059) (xy 377.759727 -187.888622)
			(xy 377.755656 -187.833) (xy 376.301508 -187.833) (xy 376.300999 -187.860886) (xy 376.292879 -187.916062)
			(xy 376.276811 -187.969469) (xy 376.253139 -188.019966) (xy 376.222366 -188.066479) (xy 376.185149 -188.108016)
			(xy 376.142281 -188.143691) (xy 376.094675 -188.172745) (xy 376.043346 -188.194557) (xy 375.989389 -188.208663)
			(xy 375.933952 -188.214763) (xy 375.878218 -188.212726) (xy 375.823375 -188.202596) (xy 375.770591 -188.184589)
			(xy 375.720991 -188.159088) (xy 375.675633 -188.126637) (xy 375.635484 -188.087928) (xy 375.601398 -188.043785)
			(xy 375.574102 -187.99515) (xy 375.554179 -187.943059) (xy 375.542053 -187.888622) (xy 375.537982 -187.833)
			(xy 373.960333 -187.833) (xy 373.956333 -187.860182) (xy 373.940265 -187.913589) (xy 373.916593 -187.964086)
			(xy 373.88582 -188.010599) (xy 373.848603 -188.052136) (xy 373.805735 -188.087811) (xy 373.758129 -188.116865)
			(xy 373.7068 -188.138677) (xy 373.652843 -188.152783) (xy 373.597406 -188.158883) (xy 373.541672 -188.156846)
			(xy 373.486829 -188.146716) (xy 373.434045 -188.128709) (xy 373.384445 -188.103208) (xy 373.339087 -188.070757)
			(xy 373.298938 -188.032048) (xy 373.264852 -187.987905) (xy 373.237556 -187.93927) (xy 373.217633 -187.887179)
			(xy 373.205507 -187.832742) (xy 373.201436 -187.77712) (xy 360.507054 -187.77712) (xy 360.528811 -187.823531)
			(xy 360.544879 -187.876938) (xy 360.552999 -187.932114) (xy 360.553508 -187.96) (xy 360.552999 -187.987886)
			(xy 360.544879 -188.043062) (xy 360.528811 -188.096469) (xy 360.505139 -188.146966) (xy 360.474366 -188.193479)
			(xy 360.437149 -188.235016) (xy 360.394281 -188.270691) (xy 360.346675 -188.299745) (xy 360.295346 -188.321557)
			(xy 360.241389 -188.335663) (xy 360.185952 -188.341763) (xy 360.130218 -188.339726) (xy 360.075375 -188.329596)
			(xy 360.022591 -188.311589) (xy 359.972991 -188.286088) (xy 359.927633 -188.253637) (xy 359.887484 -188.214928)
			(xy 359.853398 -188.170785) (xy 359.826102 -188.12215) (xy 359.806179 -188.070059) (xy 359.794053 -188.015622)
			(xy 359.789982 -187.96) (xy 358.423979 -187.96) (xy 358.442366 -187.980521) (xy 358.473139 -188.027034)
			(xy 358.496811 -188.077531) (xy 358.512879 -188.130938) (xy 358.520999 -188.186114) (xy 358.521508 -188.214)
			(xy 358.520999 -188.241886) (xy 358.512879 -188.297062) (xy 358.496811 -188.350469) (xy 358.473139 -188.400966)
			(xy 358.442366 -188.447479) (xy 358.405149 -188.489016) (xy 358.362281 -188.524691) (xy 358.314675 -188.553745)
			(xy 358.263346 -188.575557) (xy 358.209389 -188.589663) (xy 358.153952 -188.595763) (xy 358.098218 -188.593726)
			(xy 358.043375 -188.583596) (xy 357.990591 -188.565589) (xy 357.940991 -188.540088) (xy 357.895633 -188.507637)
			(xy 357.855484 -188.468928) (xy 357.821398 -188.424785) (xy 357.794102 -188.37615) (xy 357.774179 -188.324059)
			(xy 357.762053 -188.269622) (xy 357.757982 -188.214) (xy 341.911485 -188.214) (xy 341.927883 -188.248981)
			(xy 341.943951 -188.302388) (xy 341.952071 -188.357564) (xy 341.95258 -188.38545) (xy 341.952071 -188.413336)
			(xy 341.943951 -188.468512) (xy 341.927883 -188.521919) (xy 341.904211 -188.572416) (xy 341.873438 -188.618929)
			(xy 341.836221 -188.660466) (xy 341.793353 -188.696141) (xy 341.745747 -188.725195) (xy 341.694418 -188.747007)
			(xy 341.640461 -188.761113) (xy 341.585024 -188.767213) (xy 341.52929 -188.765176) (xy 341.474447 -188.755046)
			(xy 341.421663 -188.737039) (xy 341.372063 -188.711538) (xy 341.326705 -188.679087) (xy 341.286556 -188.640378)
			(xy 341.25247 -188.596235) (xy 341.225174 -188.5476) (xy 341.205251 -188.495509) (xy 341.193125 -188.441072)
			(xy 341.189054 -188.38545) (xy 336.902298 -188.38545) (xy 336.902298 -188.79312) (xy 364.751364 -188.79312)
			(xy 364.755435 -188.737498) (xy 364.767561 -188.683061) (xy 364.787484 -188.63097) (xy 364.81478 -188.582335)
			(xy 364.848866 -188.538192) (xy 364.889015 -188.499483) (xy 364.934373 -188.467032) (xy 364.983973 -188.441531)
			(xy 365.036757 -188.423524) (xy 365.0916 -188.413394) (xy 365.147334 -188.411357) (xy 365.202771 -188.417457)
			(xy 365.256728 -188.431563) (xy 365.308057 -188.453375) (xy 365.355663 -188.482429) (xy 365.398531 -188.518104)
			(xy 365.435748 -188.559641) (xy 365.466521 -188.606154) (xy 365.490193 -188.656651) (xy 365.506261 -188.710058)
			(xy 365.514381 -188.765234) (xy 365.51489 -188.79312) (xy 365.514381 -188.821006) (xy 365.506261 -188.876182)
			(xy 365.490193 -188.929589) (xy 365.466521 -188.980086) (xy 365.435748 -189.026599) (xy 365.398531 -189.068136)
			(xy 365.355663 -189.103811) (xy 365.308057 -189.132865) (xy 365.256728 -189.154677) (xy 365.202771 -189.168783)
			(xy 365.147334 -189.174883) (xy 365.0916 -189.172846) (xy 365.036757 -189.162716) (xy 364.983973 -189.144709)
			(xy 364.934373 -189.119208) (xy 364.889015 -189.086757) (xy 364.848866 -189.048048) (xy 364.81478 -189.003905)
			(xy 364.787484 -188.95527) (xy 364.767561 -188.903179) (xy 364.755435 -188.848742) (xy 364.751364 -188.79312)
			(xy 336.902298 -188.79312) (xy 336.902298 -189.567312) (xy 337.512912 -189.567312) (xy 337.516983 -189.51169)
			(xy 337.529109 -189.457253) (xy 337.549032 -189.405162) (xy 337.576328 -189.356527) (xy 337.610414 -189.312384)
			(xy 337.650563 -189.273675) (xy 337.695921 -189.241224) (xy 337.745521 -189.215723) (xy 337.798305 -189.197716)
			(xy 337.853148 -189.187586) (xy 337.908882 -189.185549) (xy 337.964319 -189.191649) (xy 338.018276 -189.205755)
			(xy 338.069605 -189.227567) (xy 338.117211 -189.256621) (xy 338.160079 -189.292296) (xy 338.197296 -189.333833)
			(xy 338.228069 -189.380346) (xy 338.237962 -189.40145) (xy 339.129876 -189.40145) (xy 339.133947 -189.345828)
			(xy 339.146073 -189.291391) (xy 339.165996 -189.2393) (xy 339.193292 -189.190665) (xy 339.227378 -189.146522)
			(xy 339.267527 -189.107813) (xy 339.312885 -189.075362) (xy 339.362485 -189.049861) (xy 339.415269 -189.031854)
			(xy 339.470112 -189.021724) (xy 339.525846 -189.019687) (xy 339.581283 -189.025787) (xy 339.63524 -189.039893)
			(xy 339.686569 -189.061705) (xy 339.734175 -189.090759) (xy 339.777043 -189.126434) (xy 339.81426 -189.167971)
			(xy 339.845033 -189.214484) (xy 339.868705 -189.264981) (xy 339.884773 -189.318388) (xy 339.892893 -189.373564)
			(xy 339.893402 -189.40145) (xy 341.189054 -189.40145) (xy 341.193125 -189.345828) (xy 341.205251 -189.291391)
			(xy 341.225174 -189.2393) (xy 341.25247 -189.190665) (xy 341.286556 -189.146522) (xy 341.326705 -189.107813)
			(xy 341.372063 -189.075362) (xy 341.421663 -189.049861) (xy 341.474447 -189.031854) (xy 341.52929 -189.021724)
			(xy 341.585024 -189.019687) (xy 341.640461 -189.025787) (xy 341.694418 -189.039893) (xy 341.745747 -189.061705)
			(xy 341.793353 -189.090759) (xy 341.836221 -189.126434) (xy 341.873438 -189.167971) (xy 341.904211 -189.214484)
			(xy 341.911485 -189.23) (xy 357.757982 -189.23) (xy 357.762053 -189.174378) (xy 357.774179 -189.119941)
			(xy 357.794102 -189.06785) (xy 357.821398 -189.019215) (xy 357.855484 -188.975072) (xy 357.895633 -188.936363)
			(xy 357.940991 -188.903912) (xy 357.990591 -188.878411) (xy 358.043375 -188.860404) (xy 358.098218 -188.850274)
			(xy 358.153952 -188.848237) (xy 358.209389 -188.854337) (xy 358.263346 -188.868443) (xy 358.314675 -188.890255)
			(xy 358.362281 -188.919309) (xy 358.405149 -188.954984) (xy 358.442366 -188.996521) (xy 358.473139 -189.043034)
			(xy 358.496811 -189.093531) (xy 358.512879 -189.146938) (xy 358.520999 -189.202114) (xy 358.521508 -189.23)
			(xy 359.789982 -189.23) (xy 359.794053 -189.174378) (xy 359.806179 -189.119941) (xy 359.826102 -189.06785)
			(xy 359.853398 -189.019215) (xy 359.887484 -188.975072) (xy 359.927633 -188.936363) (xy 359.972991 -188.903912)
			(xy 360.022591 -188.878411) (xy 360.075375 -188.860404) (xy 360.130218 -188.850274) (xy 360.185952 -188.848237)
			(xy 360.241389 -188.854337) (xy 360.295346 -188.868443) (xy 360.346675 -188.890255) (xy 360.394281 -188.919309)
			(xy 360.437149 -188.954984) (xy 360.474366 -188.996521) (xy 360.505139 -189.043034) (xy 360.528811 -189.093531)
			(xy 360.544879 -189.146938) (xy 360.552999 -189.202114) (xy 360.553508 -189.23) (xy 360.552999 -189.257886)
			(xy 360.544879 -189.313062) (xy 360.528811 -189.366469) (xy 360.505139 -189.416966) (xy 360.487845 -189.443106)
			(xy 363.638844 -189.443106) (xy 363.642915 -189.387484) (xy 363.655041 -189.333047) (xy 363.674964 -189.280956)
			(xy 363.70226 -189.232321) (xy 363.736346 -189.188178) (xy 363.776495 -189.149469) (xy 363.821853 -189.117018)
			(xy 363.871453 -189.091517) (xy 363.924237 -189.07351) (xy 363.97908 -189.06338) (xy 364.034814 -189.061343)
			(xy 364.090251 -189.067443) (xy 364.144208 -189.081549) (xy 364.195537 -189.103361) (xy 364.243143 -189.132415)
			(xy 364.286011 -189.16809) (xy 364.300062 -189.183772) (xy 373.253506 -189.183772) (xy 373.257577 -189.12815)
			(xy 373.269703 -189.073713) (xy 373.289626 -189.021622) (xy 373.316922 -188.972987) (xy 373.351008 -188.928844)
			(xy 373.391157 -188.890135) (xy 373.436515 -188.857684) (xy 373.486115 -188.832183) (xy 373.538899 -188.814176)
			(xy 373.593742 -188.804046) (xy 373.649476 -188.802009) (xy 373.704913 -188.808109) (xy 373.75887 -188.822215)
			(xy 373.810199 -188.844027) (xy 373.818347 -188.849) (xy 375.476768 -188.849) (xy 375.480839 -188.793378)
			(xy 375.492965 -188.738941) (xy 375.512888 -188.68685) (xy 375.540184 -188.638215) (xy 375.57427 -188.594072)
			(xy 375.614419 -188.555363) (xy 375.659777 -188.522912) (xy 375.709377 -188.497411) (xy 375.762161 -188.479404)
			(xy 375.817004 -188.469274) (xy 375.872738 -188.467237) (xy 375.928175 -188.473337) (xy 375.982132 -188.487443)
			(xy 376.033461 -188.509255) (xy 376.081067 -188.538309) (xy 376.123935 -188.573984) (xy 376.161152 -188.615521)
			(xy 376.191925 -188.662034) (xy 376.215597 -188.712531) (xy 376.231665 -188.765938) (xy 376.239785 -188.821114)
			(xy 376.240294 -188.849) (xy 376.239785 -188.876886) (xy 376.231665 -188.932062) (xy 376.215597 -188.985469)
			(xy 376.191925 -189.035966) (xy 376.161152 -189.082479) (xy 376.123935 -189.124016) (xy 376.081067 -189.159691)
			(xy 376.033461 -189.188745) (xy 375.982132 -189.210557) (xy 375.928175 -189.224663) (xy 375.872738 -189.230763)
			(xy 375.817004 -189.228726) (xy 375.762161 -189.218596) (xy 375.709377 -189.200589) (xy 375.659777 -189.175088)
			(xy 375.614419 -189.142637) (xy 375.57427 -189.103928) (xy 375.540184 -189.059785) (xy 375.512888 -189.01115)
			(xy 375.492965 -188.959059) (xy 375.480839 -188.904622) (xy 375.476768 -188.849) (xy 373.818347 -188.849)
			(xy 373.857805 -188.873081) (xy 373.900673 -188.908756) (xy 373.93789 -188.950293) (xy 373.968663 -188.996806)
			(xy 373.992335 -189.047303) (xy 374.008403 -189.10071) (xy 374.016523 -189.155886) (xy 374.017032 -189.183772)
			(xy 374.016523 -189.211658) (xy 374.008403 -189.266834) (xy 373.992335 -189.320241) (xy 373.968663 -189.370738)
			(xy 373.93789 -189.417251) (xy 373.900673 -189.458788) (xy 373.857805 -189.494463) (xy 373.810199 -189.523517)
			(xy 373.75887 -189.545329) (xy 373.704913 -189.559435) (xy 373.649476 -189.565535) (xy 373.593742 -189.563498)
			(xy 373.538899 -189.553368) (xy 373.486115 -189.535361) (xy 373.436515 -189.50986) (xy 373.391157 -189.477409)
			(xy 373.351008 -189.4387) (xy 373.316922 -189.394557) (xy 373.289626 -189.345922) (xy 373.269703 -189.293831)
			(xy 373.257577 -189.239394) (xy 373.253506 -189.183772) (xy 364.300062 -189.183772) (xy 364.323228 -189.209627)
			(xy 364.354001 -189.25614) (xy 364.377673 -189.306637) (xy 364.393741 -189.360044) (xy 364.401861 -189.41522)
			(xy 364.40237 -189.443106) (xy 364.401861 -189.470992) (xy 364.393741 -189.526168) (xy 364.377673 -189.579575)
			(xy 364.354001 -189.630072) (xy 364.323228 -189.676585) (xy 364.286011 -189.718122) (xy 364.243143 -189.753797)
			(xy 364.195537 -189.782851) (xy 364.144208 -189.804663) (xy 364.090251 -189.818769) (xy 364.034814 -189.824869)
			(xy 363.97908 -189.822832) (xy 363.924237 -189.812702) (xy 363.871453 -189.794695) (xy 363.821853 -189.769194)
			(xy 363.776495 -189.736743) (xy 363.736346 -189.698034) (xy 363.70226 -189.653891) (xy 363.674964 -189.605256)
			(xy 363.655041 -189.553165) (xy 363.642915 -189.498728) (xy 363.638844 -189.443106) (xy 360.487845 -189.443106)
			(xy 360.474366 -189.463479) (xy 360.437149 -189.505016) (xy 360.394281 -189.540691) (xy 360.346675 -189.569745)
			(xy 360.295346 -189.591557) (xy 360.241389 -189.605663) (xy 360.185952 -189.611763) (xy 360.130218 -189.609726)
			(xy 360.075375 -189.599596) (xy 360.022591 -189.581589) (xy 359.972991 -189.556088) (xy 359.927633 -189.523637)
			(xy 359.887484 -189.484928) (xy 359.853398 -189.440785) (xy 359.826102 -189.39215) (xy 359.806179 -189.340059)
			(xy 359.794053 -189.285622) (xy 359.789982 -189.23) (xy 358.521508 -189.23) (xy 358.520999 -189.257886)
			(xy 358.512879 -189.313062) (xy 358.496811 -189.366469) (xy 358.473139 -189.416966) (xy 358.442366 -189.463479)
			(xy 358.405149 -189.505016) (xy 358.362281 -189.540691) (xy 358.314675 -189.569745) (xy 358.263346 -189.591557)
			(xy 358.209389 -189.605663) (xy 358.153952 -189.611763) (xy 358.098218 -189.609726) (xy 358.043375 -189.599596)
			(xy 357.990591 -189.581589) (xy 357.940991 -189.556088) (xy 357.895633 -189.523637) (xy 357.855484 -189.484928)
			(xy 357.821398 -189.440785) (xy 357.794102 -189.39215) (xy 357.774179 -189.340059) (xy 357.762053 -189.285622)
			(xy 357.757982 -189.23) (xy 341.911485 -189.23) (xy 341.927883 -189.264981) (xy 341.943951 -189.318388)
			(xy 341.952071 -189.373564) (xy 341.95258 -189.40145) (xy 341.952071 -189.429336) (xy 341.943951 -189.484512)
			(xy 341.927883 -189.537919) (xy 341.904211 -189.588416) (xy 341.873438 -189.634929) (xy 341.836221 -189.676466)
			(xy 341.793353 -189.712141) (xy 341.745747 -189.741195) (xy 341.694418 -189.763007) (xy 341.640461 -189.777113)
			(xy 341.585024 -189.783213) (xy 341.52929 -189.781176) (xy 341.474447 -189.771046) (xy 341.421663 -189.753039)
			(xy 341.372063 -189.727538) (xy 341.326705 -189.695087) (xy 341.286556 -189.656378) (xy 341.25247 -189.612235)
			(xy 341.225174 -189.5636) (xy 341.205251 -189.511509) (xy 341.193125 -189.457072) (xy 341.189054 -189.40145)
			(xy 339.893402 -189.40145) (xy 339.892893 -189.429336) (xy 339.884773 -189.484512) (xy 339.868705 -189.537919)
			(xy 339.845033 -189.588416) (xy 339.81426 -189.634929) (xy 339.777043 -189.676466) (xy 339.734175 -189.712141)
			(xy 339.686569 -189.741195) (xy 339.63524 -189.763007) (xy 339.581283 -189.777113) (xy 339.525846 -189.783213)
			(xy 339.470112 -189.781176) (xy 339.415269 -189.771046) (xy 339.362485 -189.753039) (xy 339.312885 -189.727538)
			(xy 339.267527 -189.695087) (xy 339.227378 -189.656378) (xy 339.193292 -189.612235) (xy 339.165996 -189.5636)
			(xy 339.146073 -189.511509) (xy 339.133947 -189.457072) (xy 339.129876 -189.40145) (xy 338.237962 -189.40145)
			(xy 338.251741 -189.430843) (xy 338.267809 -189.48425) (xy 338.275929 -189.539426) (xy 338.276438 -189.567312)
			(xy 338.275929 -189.595198) (xy 338.267809 -189.650374) (xy 338.251741 -189.703781) (xy 338.228069 -189.754278)
			(xy 338.197296 -189.800791) (xy 338.160079 -189.842328) (xy 338.117211 -189.878003) (xy 338.069605 -189.907057)
			(xy 338.018276 -189.928869) (xy 337.964319 -189.942975) (xy 337.908882 -189.949075) (xy 337.853148 -189.947038)
			(xy 337.798305 -189.936908) (xy 337.745521 -189.918901) (xy 337.695921 -189.8934) (xy 337.650563 -189.860949)
			(xy 337.610414 -189.82224) (xy 337.576328 -189.778097) (xy 337.549032 -189.729462) (xy 337.529109 -189.677371)
			(xy 337.516983 -189.622934) (xy 337.512912 -189.567312) (xy 336.902298 -189.567312) (xy 336.902298 -190.41745)
			(xy 341.189054 -190.41745) (xy 341.193125 -190.361828) (xy 341.205251 -190.307391) (xy 341.225174 -190.2553)
			(xy 341.25247 -190.206665) (xy 341.286556 -190.162522) (xy 341.326705 -190.123813) (xy 341.372063 -190.091362)
			(xy 341.421663 -190.065861) (xy 341.474447 -190.047854) (xy 341.52929 -190.037724) (xy 341.585024 -190.035687)
			(xy 341.640461 -190.041787) (xy 341.694418 -190.055893) (xy 341.745747 -190.077705) (xy 341.770959 -190.093092)
			(xy 364.751364 -190.093092) (xy 364.755435 -190.03747) (xy 364.767561 -189.983033) (xy 364.787484 -189.930942)
			(xy 364.81478 -189.882307) (xy 364.848866 -189.838164) (xy 364.889015 -189.799455) (xy 364.934373 -189.767004)
			(xy 364.983973 -189.741503) (xy 365.036757 -189.723496) (xy 365.0916 -189.713366) (xy 365.147334 -189.711329)
			(xy 365.202771 -189.717429) (xy 365.256728 -189.731535) (xy 365.308057 -189.753347) (xy 365.355663 -189.782401)
			(xy 365.398531 -189.818076) (xy 365.435748 -189.859613) (xy 365.466521 -189.906126) (xy 365.490193 -189.956623)
			(xy 365.506261 -190.01003) (xy 365.514381 -190.065206) (xy 365.51489 -190.093092) (xy 374.703846 -190.093092)
			(xy 374.707917 -190.03747) (xy 374.720043 -189.983033) (xy 374.739966 -189.930942) (xy 374.767262 -189.882307)
			(xy 374.801348 -189.838164) (xy 374.841497 -189.799455) (xy 374.886855 -189.767004) (xy 374.936455 -189.741503)
			(xy 374.989239 -189.723496) (xy 375.044082 -189.713366) (xy 375.099816 -189.711329) (xy 375.155253 -189.717429)
			(xy 375.20921 -189.731535) (xy 375.260539 -189.753347) (xy 375.308145 -189.782401) (xy 375.351013 -189.818076)
			(xy 375.38823 -189.859613) (xy 375.419003 -189.906126) (xy 375.442675 -189.956623) (xy 375.458743 -190.01003)
			(xy 375.466863 -190.065206) (xy 375.467372 -190.093092) (xy 375.466863 -190.120978) (xy 375.458743 -190.176154)
			(xy 375.442675 -190.229561) (xy 375.419003 -190.280058) (xy 375.38823 -190.326571) (xy 375.351013 -190.368108)
			(xy 375.308145 -190.403783) (xy 375.260539 -190.432837) (xy 375.20921 -190.454649) (xy 375.155253 -190.468755)
			(xy 375.099816 -190.474855) (xy 375.044082 -190.472818) (xy 374.989239 -190.462688) (xy 374.936455 -190.444681)
			(xy 374.886855 -190.41918) (xy 374.841497 -190.386729) (xy 374.801348 -190.34802) (xy 374.767262 -190.303877)
			(xy 374.739966 -190.255242) (xy 374.720043 -190.203151) (xy 374.707917 -190.148714) (xy 374.703846 -190.093092)
			(xy 365.51489 -190.093092) (xy 365.514381 -190.120978) (xy 365.506261 -190.176154) (xy 365.490193 -190.229561)
			(xy 365.466521 -190.280058) (xy 365.435748 -190.326571) (xy 365.398531 -190.368108) (xy 365.355663 -190.403783)
			(xy 365.308057 -190.432837) (xy 365.256728 -190.454649) (xy 365.202771 -190.468755) (xy 365.147334 -190.474855)
			(xy 365.0916 -190.472818) (xy 365.036757 -190.462688) (xy 364.983973 -190.444681) (xy 364.934373 -190.41918)
			(xy 364.889015 -190.386729) (xy 364.848866 -190.34802) (xy 364.81478 -190.303877) (xy 364.787484 -190.255242)
			(xy 364.767561 -190.203151) (xy 364.755435 -190.148714) (xy 364.751364 -190.093092) (xy 341.770959 -190.093092)
			(xy 341.793353 -190.106759) (xy 341.836221 -190.142434) (xy 341.873438 -190.183971) (xy 341.904211 -190.230484)
			(xy 341.927883 -190.280981) (xy 341.943951 -190.334388) (xy 341.952071 -190.389564) (xy 341.95258 -190.41745)
			(xy 341.952071 -190.445336) (xy 341.943951 -190.500512) (xy 341.927883 -190.553919) (xy 341.904211 -190.604416)
			(xy 341.873438 -190.650929) (xy 341.838898 -190.689478) (xy 357.119348 -190.689478) (xy 357.1271 -190.635526)
			(xy 357.142452 -190.583227) (xy 357.16509 -190.533644) (xy 357.194555 -190.487788) (xy 357.230245 -190.446592)
			(xy 357.271435 -190.410894) (xy 357.317286 -190.381422) (xy 357.366865 -190.358775) (xy 357.419162 -190.343414)
			(xy 357.473112 -190.335652) (xy 357.527618 -190.335647) (xy 357.581571 -190.343399) (xy 357.63387 -190.358751)
			(xy 357.683453 -190.381389) (xy 357.729309 -190.410853) (xy 357.770506 -190.446543) (xy 357.806204 -190.487732)
			(xy 357.835676 -190.533583) (xy 357.858324 -190.583162) (xy 357.873685 -190.635458) (xy 357.881447 -190.689409)
			(xy 357.881936 -190.716662) (xy 357.881936 -190.716916) (xy 357.881736 -190.734999) (xy 357.878298 -190.771002)
			(xy 357.875078 -190.788798) (xy 357.87294 -190.802047) (xy 357.874908 -190.828804) (xy 357.883775 -190.854125)
			(xy 357.89893 -190.876263) (xy 357.919328 -190.893691) (xy 357.943559 -190.905206) (xy 357.969954 -190.910013)
			(xy 357.99669 -190.907782) (xy 358.009444 -190.903606) (xy 358.041012 -190.892869) (xy 358.106664 -190.881244)
			(xy 358.14 -190.880492) (xy 358.167251 -190.880978) (xy 358.221199 -190.888734) (xy 358.273494 -190.904089)
			(xy 358.323071 -190.926731) (xy 358.368921 -190.956197) (xy 358.410112 -190.991888) (xy 358.414829 -190.997332)
			(xy 363.853982 -190.997332) (xy 363.858053 -190.94171) (xy 363.870179 -190.887273) (xy 363.890102 -190.835182)
			(xy 363.917398 -190.786547) (xy 363.951484 -190.742404) (xy 363.991633 -190.703695) (xy 364.036991 -190.671244)
			(xy 364.086591 -190.645743) (xy 364.139375 -190.627736) (xy 364.194218 -190.617606) (xy 364.249952 -190.615569)
			(xy 364.305389 -190.621669) (xy 364.359346 -190.635775) (xy 364.410675 -190.657587) (xy 364.458281 -190.686641)
			(xy 364.501149 -190.722316) (xy 364.519752 -190.743078) (xy 372.98706 -190.743078) (xy 372.991131 -190.687456)
			(xy 373.003257 -190.633019) (xy 373.02318 -190.580928) (xy 373.050476 -190.532293) (xy 373.084562 -190.48815)
			(xy 373.124711 -190.449441) (xy 373.170069 -190.41699) (xy 373.219669 -190.391489) (xy 373.272453 -190.373482)
			(xy 373.327296 -190.363352) (xy 373.38303 -190.361315) (xy 373.438467 -190.367415) (xy 373.492424 -190.381521)
			(xy 373.543753 -190.403333) (xy 373.591359 -190.432387) (xy 373.634227 -190.468062) (xy 373.671444 -190.509599)
			(xy 373.702217 -190.556112) (xy 373.725889 -190.606609) (xy 373.732024 -190.627) (xy 379.474982 -190.627)
			(xy 379.479053 -190.571378) (xy 379.491179 -190.516941) (xy 379.511102 -190.46485) (xy 379.538398 -190.416215)
			(xy 379.572484 -190.372072) (xy 379.612633 -190.333363) (xy 379.657991 -190.300912) (xy 379.707591 -190.275411)
			(xy 379.760375 -190.257404) (xy 379.815218 -190.247274) (xy 379.870952 -190.245237) (xy 379.926389 -190.251337)
			(xy 379.980346 -190.265443) (xy 380.031675 -190.287255) (xy 380.079281 -190.316309) (xy 380.122149 -190.351984)
			(xy 380.159366 -190.393521) (xy 380.190139 -190.440034) (xy 380.213811 -190.490531) (xy 380.229879 -190.543938)
			(xy 380.237999 -190.599114) (xy 380.238508 -190.627) (xy 380.237999 -190.654886) (xy 380.229879 -190.710062)
			(xy 380.213811 -190.763469) (xy 380.190139 -190.813966) (xy 380.159366 -190.860479) (xy 380.122149 -190.902016)
			(xy 380.079281 -190.937691) (xy 380.031675 -190.966745) (xy 379.980346 -190.988557) (xy 379.926389 -191.002663)
			(xy 379.870952 -191.008763) (xy 379.815218 -191.006726) (xy 379.760375 -190.996596) (xy 379.707591 -190.978589)
			(xy 379.657991 -190.953088) (xy 379.612633 -190.920637) (xy 379.572484 -190.881928) (xy 379.538398 -190.837785)
			(xy 379.511102 -190.78915) (xy 379.491179 -190.737059) (xy 379.479053 -190.682622) (xy 379.474982 -190.627)
			(xy 373.732024 -190.627) (xy 373.741957 -190.660016) (xy 373.750077 -190.715192) (xy 373.750586 -190.743078)
			(xy 373.750077 -190.770964) (xy 373.741957 -190.82614) (xy 373.725889 -190.879547) (xy 373.702217 -190.930044)
			(xy 373.671444 -190.976557) (xy 373.634227 -191.018094) (xy 373.591359 -191.053769) (xy 373.543753 -191.082823)
			(xy 373.492424 -191.104635) (xy 373.438467 -191.118741) (xy 373.38303 -191.124841) (xy 373.327296 -191.122804)
			(xy 373.272453 -191.112674) (xy 373.219669 -191.094667) (xy 373.170069 -191.069166) (xy 373.124711 -191.036715)
			(xy 373.084562 -190.998006) (xy 373.050476 -190.953863) (xy 373.02318 -190.905228) (xy 373.003257 -190.853137)
			(xy 372.991131 -190.7987) (xy 372.98706 -190.743078) (xy 364.519752 -190.743078) (xy 364.538366 -190.763853)
			(xy 364.569139 -190.810366) (xy 364.592811 -190.860863) (xy 364.608879 -190.91427) (xy 364.616999 -190.969446)
			(xy 364.617508 -190.997332) (xy 364.616999 -191.025218) (xy 364.608879 -191.080394) (xy 364.592811 -191.133801)
			(xy 364.569139 -191.184298) (xy 364.538366 -191.230811) (xy 364.501149 -191.272348) (xy 364.485199 -191.285622)
			(xy 374.013982 -191.285622) (xy 374.018053 -191.23) (xy 374.030179 -191.175563) (xy 374.050102 -191.123472)
			(xy 374.077398 -191.074837) (xy 374.111484 -191.030694) (xy 374.151633 -190.991985) (xy 374.196991 -190.959534)
			(xy 374.246591 -190.934033) (xy 374.299375 -190.916026) (xy 374.354218 -190.905896) (xy 374.409952 -190.903859)
			(xy 374.465389 -190.909959) (xy 374.519346 -190.924065) (xy 374.570675 -190.945877) (xy 374.618281 -190.974931)
			(xy 374.661149 -191.010606) (xy 374.698366 -191.052143) (xy 374.729139 -191.098656) (xy 374.752811 -191.149153)
			(xy 374.768879 -191.20256) (xy 374.776999 -191.257736) (xy 374.777508 -191.285622) (xy 374.776999 -191.313508)
			(xy 374.768879 -191.368684) (xy 374.752811 -191.422091) (xy 374.729139 -191.472588) (xy 374.698366 -191.519101)
			(xy 374.661149 -191.560638) (xy 374.618281 -191.596313) (xy 374.570675 -191.625367) (xy 374.519346 -191.647179)
			(xy 374.481894 -191.65697) (xy 375.452892 -191.65697) (xy 375.456963 -191.601348) (xy 375.469089 -191.546911)
			(xy 375.489012 -191.49482) (xy 375.516308 -191.446185) (xy 375.550394 -191.402042) (xy 375.590543 -191.363333)
			(xy 375.635901 -191.330882) (xy 375.685501 -191.305381) (xy 375.738285 -191.287374) (xy 375.793128 -191.277244)
			(xy 375.848862 -191.275207) (xy 375.904299 -191.281307) (xy 375.958256 -191.295413) (xy 376.009585 -191.317225)
			(xy 376.057191 -191.346279) (xy 376.100059 -191.381954) (xy 376.137276 -191.423491) (xy 376.168049 -191.470004)
			(xy 376.191721 -191.520501) (xy 376.207789 -191.573908) (xy 376.215909 -191.629084) (xy 376.216418 -191.65697)
			(xy 376.215909 -191.684856) (xy 376.207789 -191.740032) (xy 376.191721 -191.793439) (xy 376.168049 -191.843936)
			(xy 376.137276 -191.890449) (xy 376.100059 -191.931986) (xy 376.057191 -191.967661) (xy 376.009585 -191.996715)
			(xy 375.958256 -192.018527) (xy 375.904299 -192.032633) (xy 375.848862 -192.038733) (xy 375.793128 -192.036696)
			(xy 375.738285 -192.026566) (xy 375.685501 -192.008559) (xy 375.635901 -191.983058) (xy 375.590543 -191.950607)
			(xy 375.550394 -191.911898) (xy 375.516308 -191.867755) (xy 375.489012 -191.81912) (xy 375.469089 -191.767029)
			(xy 375.456963 -191.712592) (xy 375.452892 -191.65697) (xy 374.481894 -191.65697) (xy 374.465389 -191.661285)
			(xy 374.409952 -191.667385) (xy 374.354218 -191.665348) (xy 374.299375 -191.655218) (xy 374.246591 -191.637211)
			(xy 374.196991 -191.61171) (xy 374.151633 -191.579259) (xy 374.111484 -191.54055) (xy 374.077398 -191.496407)
			(xy 374.050102 -191.447772) (xy 374.030179 -191.395681) (xy 374.018053 -191.341244) (xy 374.013982 -191.285622)
			(xy 364.485199 -191.285622) (xy 364.458281 -191.308023) (xy 364.410675 -191.337077) (xy 364.359346 -191.358889)
			(xy 364.305389 -191.372995) (xy 364.249952 -191.379095) (xy 364.194218 -191.377058) (xy 364.139375 -191.366928)
			(xy 364.086591 -191.348921) (xy 364.036991 -191.32342) (xy 363.991633 -191.290969) (xy 363.951484 -191.25226)
			(xy 363.917398 -191.208117) (xy 363.890102 -191.159482) (xy 363.870179 -191.107391) (xy 363.858053 -191.052954)
			(xy 363.853982 -190.997332) (xy 358.414829 -190.997332) (xy 358.445803 -191.033079) (xy 358.475269 -191.078929)
			(xy 358.497911 -191.128506) (xy 358.513266 -191.180801) (xy 358.521022 -191.234749) (xy 358.521022 -191.289251)
			(xy 358.513266 -191.343199) (xy 358.497911 -191.395494) (xy 358.475269 -191.445071) (xy 358.445803 -191.490921)
			(xy 358.410112 -191.532112) (xy 358.368921 -191.567803) (xy 358.323071 -191.597269) (xy 358.273494 -191.619911)
			(xy 358.221199 -191.635266) (xy 358.167251 -191.643022) (xy 358.112749 -191.643022) (xy 358.058801 -191.635266)
			(xy 358.006506 -191.619911) (xy 357.956929 -191.597269) (xy 357.911079 -191.567803) (xy 357.869888 -191.532112)
			(xy 357.834197 -191.490921) (xy 357.804731 -191.445071) (xy 357.782089 -191.395494) (xy 357.766734 -191.343199)
			(xy 357.758978 -191.289251) (xy 357.758492 -191.262) (xy 357.758492 -191.261746) (xy 357.758702 -191.243663)
			(xy 357.762133 -191.20766) (xy 357.76535 -191.189864) (xy 357.767488 -191.176617) (xy 357.765512 -191.149864)
			(xy 357.75664 -191.124548) (xy 357.741485 -191.102415) (xy 357.72109 -191.084989) (xy 357.696862 -191.073473)
			(xy 357.670471 -191.068662) (xy 357.643738 -191.070885) (xy 357.630984 -191.075056) (xy 357.599413 -191.085785)
			(xy 357.533763 -191.097416) (xy 357.500428 -191.09817) (xy 357.473175 -191.097752) (xy 357.419223 -191.089999)
			(xy 357.366923 -191.074647) (xy 357.317341 -191.052008) (xy 357.271485 -191.022543) (xy 357.23029 -190.986852)
			(xy 357.194592 -190.945662) (xy 357.165121 -190.899811) (xy 357.142474 -190.850232) (xy 357.127114 -190.797935)
			(xy 357.119352 -190.743984) (xy 357.119348 -190.689478) (xy 341.838898 -190.689478) (xy 341.836221 -190.692466)
			(xy 341.793353 -190.728141) (xy 341.745747 -190.757195) (xy 341.694418 -190.779007) (xy 341.640461 -190.793113)
			(xy 341.585024 -190.799213) (xy 341.52929 -190.797176) (xy 341.474447 -190.787046) (xy 341.421663 -190.769039)
			(xy 341.372063 -190.743538) (xy 341.326705 -190.711087) (xy 341.286556 -190.672378) (xy 341.25247 -190.628235)
			(xy 341.225174 -190.5796) (xy 341.205251 -190.527509) (xy 341.193125 -190.473072) (xy 341.189054 -190.41745)
			(xy 336.902298 -190.41745) (xy 336.902298 -190.837312) (xy 337.512912 -190.837312) (xy 337.516983 -190.78169)
			(xy 337.529109 -190.727253) (xy 337.549032 -190.675162) (xy 337.576328 -190.626527) (xy 337.610414 -190.582384)
			(xy 337.650563 -190.543675) (xy 337.695921 -190.511224) (xy 337.745521 -190.485723) (xy 337.798305 -190.467716)
			(xy 337.853148 -190.457586) (xy 337.908882 -190.455549) (xy 337.964319 -190.461649) (xy 338.018276 -190.475755)
			(xy 338.069605 -190.497567) (xy 338.117211 -190.526621) (xy 338.160079 -190.562296) (xy 338.197296 -190.603833)
			(xy 338.228069 -190.650346) (xy 338.251741 -190.700843) (xy 338.267809 -190.75425) (xy 338.275929 -190.809426)
			(xy 338.276438 -190.837312) (xy 338.275929 -190.865198) (xy 338.267809 -190.920374) (xy 338.251741 -190.973781)
			(xy 338.228069 -191.024278) (xy 338.197296 -191.070791) (xy 338.160079 -191.112328) (xy 338.117211 -191.148003)
			(xy 338.069605 -191.177057) (xy 338.018276 -191.198869) (xy 337.964319 -191.212975) (xy 337.908882 -191.219075)
			(xy 337.853148 -191.217038) (xy 337.798305 -191.206908) (xy 337.745521 -191.188901) (xy 337.695921 -191.1634)
			(xy 337.650563 -191.130949) (xy 337.610414 -191.09224) (xy 337.576328 -191.048097) (xy 337.549032 -190.999462)
			(xy 337.529109 -190.947371) (xy 337.516983 -190.892934) (xy 337.512912 -190.837312) (xy 336.902298 -190.837312)
			(xy 336.902298 -191.43345) (xy 339.129876 -191.43345) (xy 339.133947 -191.377828) (xy 339.146073 -191.323391)
			(xy 339.165996 -191.2713) (xy 339.193292 -191.222665) (xy 339.227378 -191.178522) (xy 339.267527 -191.139813)
			(xy 339.312885 -191.107362) (xy 339.362485 -191.081861) (xy 339.415269 -191.063854) (xy 339.470112 -191.053724)
			(xy 339.525846 -191.051687) (xy 339.581283 -191.057787) (xy 339.63524 -191.071893) (xy 339.686569 -191.093705)
			(xy 339.734175 -191.122759) (xy 339.777043 -191.158434) (xy 339.81426 -191.199971) (xy 339.845033 -191.246484)
			(xy 339.868705 -191.296981) (xy 339.884773 -191.350388) (xy 339.892893 -191.405564) (xy 339.893402 -191.43345)
			(xy 341.189054 -191.43345) (xy 341.193125 -191.377828) (xy 341.205251 -191.323391) (xy 341.225174 -191.2713)
			(xy 341.25247 -191.222665) (xy 341.286556 -191.178522) (xy 341.326705 -191.139813) (xy 341.372063 -191.107362)
			(xy 341.421663 -191.081861) (xy 341.474447 -191.063854) (xy 341.52929 -191.053724) (xy 341.585024 -191.051687)
			(xy 341.640461 -191.057787) (xy 341.694418 -191.071893) (xy 341.745747 -191.093705) (xy 341.793353 -191.122759)
			(xy 341.836221 -191.158434) (xy 341.873438 -191.199971) (xy 341.904211 -191.246484) (xy 341.927883 -191.296981)
			(xy 341.943951 -191.350388) (xy 341.952071 -191.405564) (xy 341.95258 -191.43345) (xy 341.952071 -191.461336)
			(xy 341.943951 -191.516512) (xy 341.927883 -191.569919) (xy 341.904211 -191.620416) (xy 341.873438 -191.666929)
			(xy 341.836221 -191.708466) (xy 341.793353 -191.744141) (xy 341.745747 -191.773195) (xy 341.694418 -191.795007)
			(xy 341.640461 -191.809113) (xy 341.585024 -191.815213) (xy 341.52929 -191.813176) (xy 341.474447 -191.803046)
			(xy 341.421663 -191.785039) (xy 341.372063 -191.759538) (xy 341.326705 -191.727087) (xy 341.286556 -191.688378)
			(xy 341.25247 -191.644235) (xy 341.225174 -191.5956) (xy 341.205251 -191.543509) (xy 341.193125 -191.489072)
			(xy 341.189054 -191.43345) (xy 339.893402 -191.43345) (xy 339.892893 -191.461336) (xy 339.884773 -191.516512)
			(xy 339.868705 -191.569919) (xy 339.845033 -191.620416) (xy 339.81426 -191.666929) (xy 339.777043 -191.708466)
			(xy 339.734175 -191.744141) (xy 339.686569 -191.773195) (xy 339.63524 -191.795007) (xy 339.581283 -191.809113)
			(xy 339.525846 -191.815213) (xy 339.470112 -191.813176) (xy 339.415269 -191.803046) (xy 339.362485 -191.785039)
			(xy 339.312885 -191.759538) (xy 339.267527 -191.727087) (xy 339.227378 -191.688378) (xy 339.193292 -191.644235)
			(xy 339.165996 -191.5956) (xy 339.146073 -191.543509) (xy 339.133947 -191.489072) (xy 339.129876 -191.43345)
			(xy 336.902298 -191.43345) (xy 336.902298 -192.44945) (xy 341.189054 -192.44945) (xy 341.193125 -192.393828)
			(xy 341.205251 -192.339391) (xy 341.225174 -192.2873) (xy 341.25247 -192.238665) (xy 341.286556 -192.194522)
			(xy 341.326705 -192.155813) (xy 341.372063 -192.123362) (xy 341.421663 -192.097861) (xy 341.474447 -192.079854)
			(xy 341.52929 -192.069724) (xy 341.585024 -192.067687) (xy 341.640461 -192.073787) (xy 341.694418 -192.087893)
			(xy 341.745747 -192.109705) (xy 341.793353 -192.138759) (xy 341.836221 -192.174434) (xy 341.873438 -192.215971)
			(xy 341.904211 -192.262484) (xy 341.911485 -192.278) (xy 357.757982 -192.278) (xy 357.762053 -192.222378)
			(xy 357.774179 -192.167941) (xy 357.794102 -192.11585) (xy 357.821398 -192.067215) (xy 357.855484 -192.023072)
			(xy 357.895633 -191.984363) (xy 357.940991 -191.951912) (xy 357.990591 -191.926411) (xy 358.043375 -191.908404)
			(xy 358.098218 -191.898274) (xy 358.153952 -191.896237) (xy 358.209389 -191.902337) (xy 358.263346 -191.916443)
			(xy 358.314675 -191.938255) (xy 358.362281 -191.967309) (xy 358.405149 -192.002984) (xy 358.442366 -192.044521)
			(xy 358.473139 -192.091034) (xy 358.496811 -192.141531) (xy 358.512879 -192.194938) (xy 358.520999 -192.250114)
			(xy 358.521313 -192.267332) (xy 363.853982 -192.267332) (xy 363.858053 -192.21171) (xy 363.870179 -192.157273)
			(xy 363.890102 -192.105182) (xy 363.917398 -192.056547) (xy 363.951484 -192.012404) (xy 363.991633 -191.973695)
			(xy 364.036991 -191.941244) (xy 364.086591 -191.915743) (xy 364.139375 -191.897736) (xy 364.194218 -191.887606)
			(xy 364.249952 -191.885569) (xy 364.305389 -191.891669) (xy 364.359346 -191.905775) (xy 364.410675 -191.927587)
			(xy 364.458281 -191.956641) (xy 364.501149 -191.992316) (xy 364.538366 -192.033853) (xy 364.569139 -192.080366)
			(xy 364.592811 -192.130863) (xy 364.608879 -192.18427) (xy 364.616999 -192.239446) (xy 364.617355 -192.25895)
			(xy 374.121932 -192.25895) (xy 374.126003 -192.203328) (xy 374.138129 -192.148891) (xy 374.158052 -192.0968)
			(xy 374.185348 -192.048165) (xy 374.219434 -192.004022) (xy 374.259583 -191.965313) (xy 374.304941 -191.932862)
			(xy 374.354541 -191.907361) (xy 374.407325 -191.889354) (xy 374.462168 -191.879224) (xy 374.517902 -191.877187)
			(xy 374.573339 -191.883287) (xy 374.627296 -191.897393) (xy 374.678625 -191.919205) (xy 374.726231 -191.948259)
			(xy 374.769099 -191.983934) (xy 374.806316 -192.025471) (xy 374.837089 -192.071984) (xy 374.860761 -192.122481)
			(xy 374.876829 -192.175888) (xy 374.884949 -192.231064) (xy 374.885458 -192.25895) (xy 374.884949 -192.286836)
			(xy 374.876829 -192.342012) (xy 374.860761 -192.395419) (xy 374.837089 -192.445916) (xy 374.806316 -192.492429)
			(xy 374.769099 -192.533966) (xy 374.726231 -192.569641) (xy 374.678625 -192.598695) (xy 374.627296 -192.620507)
			(xy 374.573339 -192.634613) (xy 374.517902 -192.640713) (xy 374.462168 -192.638676) (xy 374.407325 -192.628546)
			(xy 374.354541 -192.610539) (xy 374.304941 -192.585038) (xy 374.259583 -192.552587) (xy 374.219434 -192.513878)
			(xy 374.185348 -192.469735) (xy 374.158052 -192.4211) (xy 374.138129 -192.369009) (xy 374.126003 -192.314572)
			(xy 374.121932 -192.25895) (xy 364.617355 -192.25895) (xy 364.617508 -192.267332) (xy 364.616999 -192.295218)
			(xy 364.608879 -192.350394) (xy 364.592811 -192.403801) (xy 364.569139 -192.454298) (xy 364.538366 -192.500811)
			(xy 364.501149 -192.542348) (xy 364.458281 -192.578023) (xy 364.410675 -192.607077) (xy 364.359346 -192.628889)
			(xy 364.305389 -192.642995) (xy 364.249952 -192.649095) (xy 364.194218 -192.647058) (xy 364.139375 -192.636928)
			(xy 364.086591 -192.618921) (xy 364.036991 -192.59342) (xy 363.991633 -192.560969) (xy 363.951484 -192.52226)
			(xy 363.917398 -192.478117) (xy 363.890102 -192.429482) (xy 363.870179 -192.377391) (xy 363.858053 -192.322954)
			(xy 363.853982 -192.267332) (xy 358.521313 -192.267332) (xy 358.521508 -192.278) (xy 358.520999 -192.305886)
			(xy 358.512879 -192.361062) (xy 358.496811 -192.414469) (xy 358.473139 -192.464966) (xy 358.442366 -192.511479)
			(xy 358.405149 -192.553016) (xy 358.362281 -192.588691) (xy 358.314675 -192.617745) (xy 358.263346 -192.639557)
			(xy 358.209389 -192.653663) (xy 358.153952 -192.659763) (xy 358.098218 -192.657726) (xy 358.043375 -192.647596)
			(xy 357.990591 -192.629589) (xy 357.940991 -192.604088) (xy 357.895633 -192.571637) (xy 357.855484 -192.532928)
			(xy 357.821398 -192.488785) (xy 357.794102 -192.44015) (xy 357.774179 -192.388059) (xy 357.762053 -192.333622)
			(xy 357.757982 -192.278) (xy 341.911485 -192.278) (xy 341.927883 -192.312981) (xy 341.943951 -192.366388)
			(xy 341.952071 -192.421564) (xy 341.95258 -192.44945) (xy 341.952071 -192.477336) (xy 341.943951 -192.532512)
			(xy 341.927883 -192.585919) (xy 341.904211 -192.636416) (xy 341.873438 -192.682929) (xy 341.836221 -192.724466)
			(xy 341.793353 -192.760141) (xy 341.745747 -192.789195) (xy 341.694418 -192.811007) (xy 341.640461 -192.825113)
			(xy 341.585024 -192.831213) (xy 341.52929 -192.829176) (xy 341.474447 -192.819046) (xy 341.421663 -192.801039)
			(xy 341.372063 -192.775538) (xy 341.326705 -192.743087) (xy 341.286556 -192.704378) (xy 341.25247 -192.660235)
			(xy 341.225174 -192.6116) (xy 341.205251 -192.559509) (xy 341.193125 -192.505072) (xy 341.189054 -192.44945)
			(xy 336.902298 -192.44945) (xy 336.902298 -193.2813) (xy 336.902179 -193.286254) (xy 336.90026 -193.295976)
			(xy 336.898488 -193.300604) (xy 336.894678 -193.309748) (xy 336.88782 -193.316606) (xy 336.887312 -193.317114)
			(xy 336.765392 -193.439034) (xy 336.759296 -193.445384) (xy 336.739229 -193.46545) (xy 341.189054 -193.46545)
			(xy 341.193125 -193.409828) (xy 341.205251 -193.355391) (xy 341.225174 -193.3033) (xy 341.25247 -193.254665)
			(xy 341.286556 -193.210522) (xy 341.326705 -193.171813) (xy 341.372063 -193.139362) (xy 341.421663 -193.113861)
			(xy 341.474447 -193.095854) (xy 341.52929 -193.085724) (xy 341.585024 -193.083687) (xy 341.640461 -193.089787)
			(xy 341.694418 -193.103893) (xy 341.745747 -193.125705) (xy 341.793353 -193.154759) (xy 341.836221 -193.190434)
			(xy 341.873438 -193.231971) (xy 341.904211 -193.278484) (xy 341.911485 -193.294) (xy 357.757982 -193.294)
			(xy 357.762053 -193.238378) (xy 357.774179 -193.183941) (xy 357.794102 -193.13185) (xy 357.821398 -193.083215)
			(xy 357.855484 -193.039072) (xy 357.895633 -193.000363) (xy 357.940991 -192.967912) (xy 357.990591 -192.942411)
			(xy 358.043375 -192.924404) (xy 358.098218 -192.914274) (xy 358.153952 -192.912237) (xy 358.209389 -192.918337)
			(xy 358.263346 -192.932443) (xy 358.314675 -192.954255) (xy 358.362281 -192.983309) (xy 358.405149 -193.018984)
			(xy 358.442366 -193.060521) (xy 358.473139 -193.107034) (xy 358.496811 -193.157531) (xy 358.512879 -193.210938)
			(xy 358.520999 -193.266114) (xy 358.521508 -193.294) (xy 359.789982 -193.294) (xy 359.794053 -193.238378)
			(xy 359.806179 -193.183941) (xy 359.826102 -193.13185) (xy 359.853398 -193.083215) (xy 359.887484 -193.039072)
			(xy 359.927633 -193.000363) (xy 359.972991 -192.967912) (xy 360.022591 -192.942411) (xy 360.075375 -192.924404)
			(xy 360.130218 -192.914274) (xy 360.185952 -192.912237) (xy 360.241389 -192.918337) (xy 360.295346 -192.932443)
			(xy 360.346675 -192.954255) (xy 360.394281 -192.983309) (xy 360.437149 -193.018984) (xy 360.474366 -193.060521)
			(xy 360.505139 -193.107034) (xy 360.528811 -193.157531) (xy 360.544879 -193.210938) (xy 360.552999 -193.266114)
			(xy 360.553508 -193.294) (xy 361.821982 -193.294) (xy 361.826053 -193.238378) (xy 361.838179 -193.183941)
			(xy 361.858102 -193.13185) (xy 361.885398 -193.083215) (xy 361.919484 -193.039072) (xy 361.959633 -193.000363)
			(xy 362.004991 -192.967912) (xy 362.054591 -192.942411) (xy 362.107375 -192.924404) (xy 362.162218 -192.914274)
			(xy 362.217952 -192.912237) (xy 362.273389 -192.918337) (xy 362.327346 -192.932443) (xy 362.374837 -192.952624)
			(xy 369.261896 -192.952624) (xy 369.265967 -192.897002) (xy 369.278093 -192.842565) (xy 369.298016 -192.790474)
			(xy 369.325312 -192.741839) (xy 369.359398 -192.697696) (xy 369.399547 -192.658987) (xy 369.444905 -192.626536)
			(xy 369.494505 -192.601035) (xy 369.547289 -192.583028) (xy 369.602132 -192.572898) (xy 369.657866 -192.570861)
			(xy 369.713303 -192.576961) (xy 369.76726 -192.591067) (xy 369.818589 -192.612879) (xy 369.866195 -192.641933)
			(xy 369.909063 -192.677608) (xy 369.94628 -192.719145) (xy 369.977053 -192.765658) (xy 370.000725 -192.816155)
			(xy 370.016793 -192.869562) (xy 370.024913 -192.924738) (xy 370.025422 -192.952624) (xy 370.024913 -192.98051)
			(xy 370.016793 -193.035686) (xy 370.000725 -193.089093) (xy 369.977053 -193.13959) (xy 369.94628 -193.186103)
			(xy 369.909063 -193.22764) (xy 369.866195 -193.263315) (xy 369.818589 -193.292369) (xy 369.76726 -193.314181)
			(xy 369.713303 -193.328287) (xy 369.657866 -193.334387) (xy 369.602132 -193.33235) (xy 369.547289 -193.32222)
			(xy 369.494505 -193.304213) (xy 369.444905 -193.278712) (xy 369.399547 -193.246261) (xy 369.359398 -193.207552)
			(xy 369.325312 -193.163409) (xy 369.298016 -193.114774) (xy 369.278093 -193.062683) (xy 369.265967 -193.008246)
			(xy 369.261896 -192.952624) (xy 362.374837 -192.952624) (xy 362.378675 -192.954255) (xy 362.426281 -192.983309)
			(xy 362.469149 -193.018984) (xy 362.506366 -193.060521) (xy 362.537139 -193.107034) (xy 362.560811 -193.157531)
			(xy 362.576879 -193.210938) (xy 362.584999 -193.266114) (xy 362.585508 -193.294) (xy 362.584999 -193.321886)
			(xy 362.576879 -193.377062) (xy 362.560811 -193.430469) (xy 362.537139 -193.480966) (xy 362.506366 -193.527479)
			(xy 362.469149 -193.569016) (xy 362.426281 -193.604691) (xy 362.378675 -193.633745) (xy 362.327346 -193.655557)
			(xy 362.273389 -193.669663) (xy 362.217952 -193.675763) (xy 362.162218 -193.673726) (xy 362.107375 -193.663596)
			(xy 362.054591 -193.645589) (xy 362.004991 -193.620088) (xy 361.959633 -193.587637) (xy 361.919484 -193.548928)
			(xy 361.885398 -193.504785) (xy 361.858102 -193.45615) (xy 361.838179 -193.404059) (xy 361.826053 -193.349622)
			(xy 361.821982 -193.294) (xy 360.553508 -193.294) (xy 360.552999 -193.321886) (xy 360.544879 -193.377062)
			(xy 360.528811 -193.430469) (xy 360.505139 -193.480966) (xy 360.474366 -193.527479) (xy 360.437149 -193.569016)
			(xy 360.394281 -193.604691) (xy 360.346675 -193.633745) (xy 360.295346 -193.655557) (xy 360.241389 -193.669663)
			(xy 360.185952 -193.675763) (xy 360.130218 -193.673726) (xy 360.075375 -193.663596) (xy 360.022591 -193.645589)
			(xy 359.972991 -193.620088) (xy 359.927633 -193.587637) (xy 359.887484 -193.548928) (xy 359.853398 -193.504785)
			(xy 359.826102 -193.45615) (xy 359.806179 -193.404059) (xy 359.794053 -193.349622) (xy 359.789982 -193.294)
			(xy 358.521508 -193.294) (xy 358.520999 -193.321886) (xy 358.512879 -193.377062) (xy 358.496811 -193.430469)
			(xy 358.473139 -193.480966) (xy 358.442366 -193.527479) (xy 358.405149 -193.569016) (xy 358.362281 -193.604691)
			(xy 358.314675 -193.633745) (xy 358.263346 -193.655557) (xy 358.209389 -193.669663) (xy 358.153952 -193.675763)
			(xy 358.098218 -193.673726) (xy 358.043375 -193.663596) (xy 357.990591 -193.645589) (xy 357.940991 -193.620088)
			(xy 357.895633 -193.587637) (xy 357.855484 -193.548928) (xy 357.821398 -193.504785) (xy 357.794102 -193.45615)
			(xy 357.774179 -193.404059) (xy 357.762053 -193.349622) (xy 357.757982 -193.294) (xy 341.911485 -193.294)
			(xy 341.927883 -193.328981) (xy 341.943951 -193.382388) (xy 341.952071 -193.437564) (xy 341.95258 -193.46545)
			(xy 341.952071 -193.493336) (xy 341.943951 -193.548512) (xy 341.927883 -193.601919) (xy 341.904211 -193.652416)
			(xy 341.873438 -193.698929) (xy 341.836221 -193.740466) (xy 341.793353 -193.776141) (xy 341.745747 -193.805195)
			(xy 341.694418 -193.827007) (xy 341.640461 -193.841113) (xy 341.585024 -193.847213) (xy 341.52929 -193.845176)
			(xy 341.474447 -193.835046) (xy 341.421663 -193.817039) (xy 341.372063 -193.791538) (xy 341.326705 -193.759087)
			(xy 341.286556 -193.720378) (xy 341.25247 -193.676235) (xy 341.225174 -193.6276) (xy 341.205251 -193.575509)
			(xy 341.193125 -193.521072) (xy 341.189054 -193.46545) (xy 336.739229 -193.46545) (xy 336.210133 -193.994532)
			(xy 337.459826 -193.994532) (xy 337.463897 -193.93891) (xy 337.476023 -193.884473) (xy 337.495946 -193.832382)
			(xy 337.523242 -193.783747) (xy 337.557328 -193.739604) (xy 337.597477 -193.700895) (xy 337.642835 -193.668444)
			(xy 337.692435 -193.642943) (xy 337.745219 -193.624936) (xy 337.800062 -193.614806) (xy 337.855796 -193.612769)
			(xy 337.911233 -193.618869) (xy 337.96519 -193.632975) (xy 338.016519 -193.654787) (xy 338.064125 -193.683841)
			(xy 338.106993 -193.719516) (xy 338.14421 -193.761053) (xy 338.174983 -193.807566) (xy 338.198655 -193.858063)
			(xy 338.214723 -193.91147) (xy 338.222843 -193.966646) (xy 338.223148 -193.983356) (xy 369.228368 -193.983356)
			(xy 369.232439 -193.927734) (xy 369.244565 -193.873297) (xy 369.264488 -193.821206) (xy 369.291784 -193.772571)
			(xy 369.32587 -193.728428) (xy 369.366019 -193.689719) (xy 369.411377 -193.657268) (xy 369.460977 -193.631767)
			(xy 369.513761 -193.61376) (xy 369.568604 -193.60363) (xy 369.624338 -193.601593) (xy 369.679775 -193.607693)
			(xy 369.733732 -193.621799) (xy 369.785061 -193.643611) (xy 369.832667 -193.672665) (xy 369.875535 -193.70834)
			(xy 369.912752 -193.749877) (xy 369.943525 -193.79639) (xy 369.967197 -193.846887) (xy 369.983265 -193.900294)
			(xy 369.991385 -193.95547) (xy 369.991894 -193.983356) (xy 369.991385 -194.011242) (xy 369.983265 -194.066418)
			(xy 369.967197 -194.119825) (xy 369.943525 -194.170322) (xy 369.912752 -194.216835) (xy 369.875535 -194.258372)
			(xy 369.832667 -194.294047) (xy 369.806527 -194.31) (xy 379.761748 -194.31) (xy 379.765819 -194.254378)
			(xy 379.777945 -194.199941) (xy 379.797868 -194.14785) (xy 379.825164 -194.099215) (xy 379.85925 -194.055072)
			(xy 379.899399 -194.016363) (xy 379.944757 -193.983912) (xy 379.994357 -193.958411) (xy 380.047141 -193.940404)
			(xy 380.101984 -193.930274) (xy 380.157718 -193.928237) (xy 380.213155 -193.934337) (xy 380.267112 -193.948443)
			(xy 380.318441 -193.970255) (xy 380.366047 -193.999309) (xy 380.408915 -194.034984) (xy 380.446132 -194.076521)
			(xy 380.476905 -194.123034) (xy 380.500577 -194.173531) (xy 380.516645 -194.226938) (xy 380.524765 -194.282114)
			(xy 380.525274 -194.31) (xy 380.524765 -194.337886) (xy 380.516645 -194.393062) (xy 380.500577 -194.446469)
			(xy 380.476905 -194.496966) (xy 380.446132 -194.543479) (xy 380.408915 -194.585016) (xy 380.366047 -194.620691)
			(xy 380.318441 -194.649745) (xy 380.267112 -194.671557) (xy 380.213155 -194.685663) (xy 380.157718 -194.691763)
			(xy 380.101984 -194.689726) (xy 380.047141 -194.679596) (xy 379.994357 -194.661589) (xy 379.944757 -194.636088)
			(xy 379.899399 -194.603637) (xy 379.85925 -194.564928) (xy 379.825164 -194.520785) (xy 379.797868 -194.47215)
			(xy 379.777945 -194.420059) (xy 379.765819 -194.365622) (xy 379.761748 -194.31) (xy 369.806527 -194.31)
			(xy 369.785061 -194.323101) (xy 369.733732 -194.344913) (xy 369.679775 -194.359019) (xy 369.624338 -194.365119)
			(xy 369.568604 -194.363082) (xy 369.513761 -194.352952) (xy 369.460977 -194.334945) (xy 369.411377 -194.309444)
			(xy 369.366019 -194.276993) (xy 369.32587 -194.238284) (xy 369.291784 -194.194141) (xy 369.264488 -194.145506)
			(xy 369.244565 -194.093415) (xy 369.232439 -194.038978) (xy 369.228368 -193.983356) (xy 338.223148 -193.983356)
			(xy 338.223352 -193.994532) (xy 338.222843 -194.022418) (xy 338.214723 -194.077594) (xy 338.198655 -194.131001)
			(xy 338.174983 -194.181498) (xy 338.14421 -194.228011) (xy 338.106993 -194.269548) (xy 338.064125 -194.305223)
			(xy 338.016519 -194.334277) (xy 337.96519 -194.356089) (xy 337.911233 -194.370195) (xy 337.855796 -194.376295)
			(xy 337.800062 -194.374258) (xy 337.745219 -194.364128) (xy 337.692435 -194.346121) (xy 337.642835 -194.32062)
			(xy 337.597477 -194.288169) (xy 337.557328 -194.24946) (xy 337.523242 -194.205317) (xy 337.495946 -194.156682)
			(xy 337.476023 -194.104591) (xy 337.463897 -194.050154) (xy 337.459826 -193.994532) (xy 336.210133 -193.994532)
			(xy 335.723202 -194.48145) (xy 339.076282 -194.48145) (xy 339.080353 -194.425828) (xy 339.092479 -194.371391)
			(xy 339.112402 -194.3193) (xy 339.139698 -194.270665) (xy 339.173784 -194.226522) (xy 339.213933 -194.187813)
			(xy 339.259291 -194.155362) (xy 339.308891 -194.129861) (xy 339.361675 -194.111854) (xy 339.416518 -194.101724)
			(xy 339.472252 -194.099687) (xy 339.527689 -194.105787) (xy 339.581646 -194.119893) (xy 339.632975 -194.141705)
			(xy 339.680581 -194.170759) (xy 339.723449 -194.206434) (xy 339.760666 -194.247971) (xy 339.791439 -194.294484)
			(xy 339.815111 -194.344981) (xy 339.830798 -194.397122) (xy 359.795824 -194.397122) (xy 359.799895 -194.3415)
			(xy 359.812021 -194.287063) (xy 359.831944 -194.234972) (xy 359.85924 -194.186337) (xy 359.893326 -194.142194)
			(xy 359.933475 -194.103485) (xy 359.978833 -194.071034) (xy 360.028433 -194.045533) (xy 360.081217 -194.027526)
			(xy 360.13606 -194.017396) (xy 360.191794 -194.015359) (xy 360.247231 -194.021459) (xy 360.301188 -194.035565)
			(xy 360.352517 -194.057377) (xy 360.400123 -194.086431) (xy 360.442991 -194.122106) (xy 360.480208 -194.163643)
			(xy 360.510981 -194.210156) (xy 360.534653 -194.260653) (xy 360.550721 -194.31406) (xy 360.558841 -194.369236)
			(xy 360.55935 -194.397122) (xy 360.558841 -194.425008) (xy 360.550721 -194.480184) (xy 360.534653 -194.533591)
			(xy 360.510981 -194.584088) (xy 360.480208 -194.630601) (xy 360.442991 -194.672138) (xy 360.420326 -194.691)
			(xy 362.075982 -194.691) (xy 362.080053 -194.635378) (xy 362.092179 -194.580941) (xy 362.112102 -194.52885)
			(xy 362.139398 -194.480215) (xy 362.173484 -194.436072) (xy 362.213633 -194.397363) (xy 362.258991 -194.364912)
			(xy 362.308591 -194.339411) (xy 362.361375 -194.321404) (xy 362.416218 -194.311274) (xy 362.471952 -194.309237)
			(xy 362.527389 -194.315337) (xy 362.581346 -194.329443) (xy 362.632675 -194.351255) (xy 362.680281 -194.380309)
			(xy 362.723149 -194.415984) (xy 362.741979 -194.437) (xy 364.107982 -194.437) (xy 364.112053 -194.381378)
			(xy 364.124179 -194.326941) (xy 364.144102 -194.27485) (xy 364.171398 -194.226215) (xy 364.205484 -194.182072)
			(xy 364.245633 -194.143363) (xy 364.290991 -194.110912) (xy 364.340591 -194.085411) (xy 364.393375 -194.067404)
			(xy 364.448218 -194.057274) (xy 364.503952 -194.055237) (xy 364.559389 -194.061337) (xy 364.613346 -194.075443)
			(xy 364.664675 -194.097255) (xy 364.712281 -194.126309) (xy 364.755149 -194.161984) (xy 364.792366 -194.203521)
			(xy 364.823139 -194.250034) (xy 364.846811 -194.300531) (xy 364.862879 -194.353938) (xy 364.870999 -194.409114)
			(xy 364.871508 -194.437) (xy 364.870999 -194.464886) (xy 364.862879 -194.520062) (xy 364.846811 -194.573469)
			(xy 364.823139 -194.623966) (xy 364.792366 -194.670479) (xy 364.755149 -194.712016) (xy 364.712281 -194.747691)
			(xy 364.664675 -194.776745) (xy 364.613346 -194.798557) (xy 364.559389 -194.812663) (xy 364.503952 -194.818763)
			(xy 364.448218 -194.816726) (xy 364.393375 -194.806596) (xy 364.340591 -194.788589) (xy 364.290991 -194.763088)
			(xy 364.245633 -194.730637) (xy 364.205484 -194.691928) (xy 364.171398 -194.647785) (xy 364.144102 -194.59915)
			(xy 364.124179 -194.547059) (xy 364.112053 -194.492622) (xy 364.107982 -194.437) (xy 362.741979 -194.437)
			(xy 362.760366 -194.457521) (xy 362.791139 -194.504034) (xy 362.814811 -194.554531) (xy 362.830879 -194.607938)
			(xy 362.838999 -194.663114) (xy 362.839508 -194.691) (xy 362.838999 -194.718886) (xy 362.830879 -194.774062)
			(xy 362.814811 -194.827469) (xy 362.791139 -194.877966) (xy 362.760366 -194.924479) (xy 362.723149 -194.966016)
			(xy 362.680281 -195.001691) (xy 362.632675 -195.030745) (xy 362.581346 -195.052557) (xy 362.527389 -195.066663)
			(xy 362.471952 -195.072763) (xy 362.416218 -195.070726) (xy 362.361375 -195.060596) (xy 362.308591 -195.042589)
			(xy 362.258991 -195.017088) (xy 362.213633 -194.984637) (xy 362.173484 -194.945928) (xy 362.139398 -194.901785)
			(xy 362.112102 -194.85315) (xy 362.092179 -194.801059) (xy 362.080053 -194.746622) (xy 362.075982 -194.691)
			(xy 360.420326 -194.691) (xy 360.400123 -194.707813) (xy 360.352517 -194.736867) (xy 360.301188 -194.758679)
			(xy 360.247231 -194.772785) (xy 360.191794 -194.778885) (xy 360.13606 -194.776848) (xy 360.081217 -194.766718)
			(xy 360.028433 -194.748711) (xy 359.978833 -194.72321) (xy 359.933475 -194.690759) (xy 359.893326 -194.65205)
			(xy 359.85924 -194.607907) (xy 359.831944 -194.559272) (xy 359.812021 -194.507181) (xy 359.799895 -194.452744)
			(xy 359.795824 -194.397122) (xy 339.830798 -194.397122) (xy 339.831179 -194.398388) (xy 339.839299 -194.453564)
			(xy 339.839808 -194.48145) (xy 339.839299 -194.509336) (xy 339.831179 -194.564512) (xy 339.815111 -194.617919)
			(xy 339.791439 -194.668416) (xy 339.760666 -194.714929) (xy 339.723449 -194.756466) (xy 339.680581 -194.792141)
			(xy 339.632975 -194.821195) (xy 339.581646 -194.843007) (xy 339.527689 -194.857113) (xy 339.472252 -194.863213)
			(xy 339.416518 -194.861176) (xy 339.361675 -194.851046) (xy 339.308891 -194.833039) (xy 339.259291 -194.807538)
			(xy 339.213933 -194.775087) (xy 339.173784 -194.736378) (xy 339.139698 -194.692235) (xy 339.112402 -194.6436)
			(xy 339.092479 -194.591509) (xy 339.080353 -194.537072) (xy 339.076282 -194.48145) (xy 335.723202 -194.48145)
			(xy 334.497619 -195.707) (xy 362.075982 -195.707) (xy 362.080053 -195.651378) (xy 362.092179 -195.596941)
			(xy 362.112102 -195.54485) (xy 362.139398 -195.496215) (xy 362.173484 -195.452072) (xy 362.213633 -195.413363)
			(xy 362.258991 -195.380912) (xy 362.308591 -195.355411) (xy 362.361375 -195.337404) (xy 362.416218 -195.327274)
			(xy 362.471952 -195.325237) (xy 362.527389 -195.331337) (xy 362.581346 -195.345443) (xy 362.632675 -195.367255)
			(xy 362.680281 -195.396309) (xy 362.723149 -195.431984) (xy 362.760366 -195.473521) (xy 362.791139 -195.520034)
			(xy 362.814811 -195.570531) (xy 362.830879 -195.623938) (xy 362.838999 -195.679114) (xy 362.839508 -195.707)
			(xy 364.107982 -195.707) (xy 364.112053 -195.651378) (xy 364.124179 -195.596941) (xy 364.144102 -195.54485)
			(xy 364.171398 -195.496215) (xy 364.205484 -195.452072) (xy 364.245633 -195.413363) (xy 364.290991 -195.380912)
			(xy 364.340591 -195.355411) (xy 364.393375 -195.337404) (xy 364.448218 -195.327274) (xy 364.503952 -195.325237)
			(xy 364.559389 -195.331337) (xy 364.613346 -195.345443) (xy 364.664675 -195.367255) (xy 364.712281 -195.396309)
			(xy 364.755149 -195.431984) (xy 364.792366 -195.473521) (xy 364.823139 -195.520034) (xy 364.846811 -195.570531)
			(xy 364.862879 -195.623938) (xy 364.870999 -195.679114) (xy 364.871508 -195.707) (xy 366.901982 -195.707)
			(xy 366.906053 -195.651378) (xy 366.918179 -195.596941) (xy 366.938102 -195.54485) (xy 366.965398 -195.496215)
			(xy 366.999484 -195.452072) (xy 367.039633 -195.413363) (xy 367.084991 -195.380912) (xy 367.134591 -195.355411)
			(xy 367.187375 -195.337404) (xy 367.242218 -195.327274) (xy 367.297952 -195.325237) (xy 367.353389 -195.331337)
			(xy 367.407346 -195.345443) (xy 367.458675 -195.367255) (xy 367.506281 -195.396309) (xy 367.549149 -195.431984)
			(xy 367.586366 -195.473521) (xy 367.617139 -195.520034) (xy 367.640811 -195.570531) (xy 367.656879 -195.623938)
			(xy 367.664999 -195.679114) (xy 367.665508 -195.707) (xy 367.664999 -195.734886) (xy 367.656879 -195.790062)
			(xy 367.640811 -195.843469) (xy 367.617139 -195.893966) (xy 367.586366 -195.940479) (xy 367.549149 -195.982016)
			(xy 367.506281 -196.017691) (xy 367.458675 -196.046745) (xy 367.407346 -196.068557) (xy 367.353389 -196.082663)
			(xy 367.297952 -196.088763) (xy 367.242218 -196.086726) (xy 367.187375 -196.076596) (xy 367.134591 -196.058589)
			(xy 367.084991 -196.033088) (xy 367.039633 -196.000637) (xy 366.999484 -195.961928) (xy 366.965398 -195.917785)
			(xy 366.938102 -195.86915) (xy 366.918179 -195.817059) (xy 366.906053 -195.762622) (xy 366.901982 -195.707)
			(xy 364.871508 -195.707) (xy 364.870999 -195.734886) (xy 364.862879 -195.790062) (xy 364.846811 -195.843469)
			(xy 364.823139 -195.893966) (xy 364.792366 -195.940479) (xy 364.755149 -195.982016) (xy 364.712281 -196.017691)
			(xy 364.664675 -196.046745) (xy 364.613346 -196.068557) (xy 364.559389 -196.082663) (xy 364.503952 -196.088763)
			(xy 364.448218 -196.086726) (xy 364.393375 -196.076596) (xy 364.340591 -196.058589) (xy 364.290991 -196.033088)
			(xy 364.245633 -196.000637) (xy 364.205484 -195.961928) (xy 364.171398 -195.917785) (xy 364.144102 -195.86915)
			(xy 364.124179 -195.817059) (xy 364.112053 -195.762622) (xy 364.107982 -195.707) (xy 362.839508 -195.707)
			(xy 362.838999 -195.734886) (xy 362.830879 -195.790062) (xy 362.814811 -195.843469) (xy 362.791139 -195.893966)
			(xy 362.760366 -195.940479) (xy 362.723149 -195.982016) (xy 362.680281 -196.017691) (xy 362.632675 -196.046745)
			(xy 362.581346 -196.068557) (xy 362.527389 -196.082663) (xy 362.471952 -196.088763) (xy 362.416218 -196.086726)
			(xy 362.361375 -196.076596) (xy 362.308591 -196.058589) (xy 362.258991 -196.033088) (xy 362.213633 -196.000637)
			(xy 362.173484 -195.961928) (xy 362.139398 -195.917785) (xy 362.112102 -195.86915) (xy 362.092179 -195.817059)
			(xy 362.080053 -195.762622) (xy 362.075982 -195.707) (xy 334.497619 -195.707) (xy 333.691147 -196.51345)
			(xy 341.189054 -196.51345) (xy 341.193125 -196.457828) (xy 341.205251 -196.403391) (xy 341.225174 -196.3513)
			(xy 341.25247 -196.302665) (xy 341.286556 -196.258522) (xy 341.326705 -196.219813) (xy 341.372063 -196.187362)
			(xy 341.421663 -196.161861) (xy 341.474447 -196.143854) (xy 341.52929 -196.133724) (xy 341.585024 -196.131687)
			(xy 341.640461 -196.137787) (xy 341.694418 -196.151893) (xy 341.745747 -196.173705) (xy 341.793353 -196.202759)
			(xy 341.836221 -196.238434) (xy 341.873438 -196.279971) (xy 341.904211 -196.326484) (xy 341.927883 -196.376981)
			(xy 341.943951 -196.430388) (xy 341.950381 -196.47408) (xy 357.533192 -196.47408) (xy 357.537263 -196.418458)
			(xy 357.549389 -196.364021) (xy 357.569312 -196.31193) (xy 357.596608 -196.263295) (xy 357.630694 -196.219152)
			(xy 357.670843 -196.180443) (xy 357.716201 -196.147992) (xy 357.765801 -196.122491) (xy 357.818585 -196.104484)
			(xy 357.873428 -196.094354) (xy 357.929162 -196.092317) (xy 357.984599 -196.098417) (xy 358.038556 -196.112523)
			(xy 358.089885 -196.134335) (xy 358.137491 -196.163389) (xy 358.180359 -196.199064) (xy 358.192817 -196.212968)
			(xy 369.121434 -196.212968) (xy 369.125505 -196.157346) (xy 369.137631 -196.102909) (xy 369.157554 -196.050818)
			(xy 369.18485 -196.002183) (xy 369.218936 -195.95804) (xy 369.259085 -195.919331) (xy 369.304443 -195.88688)
			(xy 369.354043 -195.861379) (xy 369.406827 -195.843372) (xy 369.46167 -195.833242) (xy 369.517404 -195.831205)
			(xy 369.572841 -195.837305) (xy 369.626798 -195.851411) (xy 369.678127 -195.873223) (xy 369.725733 -195.902277)
			(xy 369.768601 -195.937952) (xy 369.805818 -195.979489) (xy 369.836591 -196.026002) (xy 369.860263 -196.076499)
			(xy 369.876331 -196.129906) (xy 369.884451 -196.185082) (xy 369.88496 -196.212968) (xy 369.884451 -196.240854)
			(xy 369.876331 -196.29603) (xy 369.8625 -196.342) (xy 379.808738 -196.342) (xy 379.812809 -196.286378)
			(xy 379.824935 -196.231941) (xy 379.844858 -196.17985) (xy 379.872154 -196.131215) (xy 379.90624 -196.087072)
			(xy 379.946389 -196.048363) (xy 379.991747 -196.015912) (xy 380.041347 -195.990411) (xy 380.094131 -195.972404)
			(xy 380.148974 -195.962274) (xy 380.204708 -195.960237) (xy 380.260145 -195.966337) (xy 380.314102 -195.980443)
			(xy 380.365431 -196.002255) (xy 380.413037 -196.031309) (xy 380.455905 -196.066984) (xy 380.493122 -196.108521)
			(xy 380.523895 -196.155034) (xy 380.547567 -196.205531) (xy 380.563635 -196.258938) (xy 380.571755 -196.314114)
			(xy 380.572264 -196.342) (xy 380.571755 -196.369886) (xy 380.563635 -196.425062) (xy 380.547567 -196.478469)
			(xy 380.523895 -196.528966) (xy 380.493122 -196.575479) (xy 380.455905 -196.617016) (xy 380.413037 -196.652691)
			(xy 380.365431 -196.681745) (xy 380.314102 -196.703557) (xy 380.260145 -196.717663) (xy 380.204708 -196.723763)
			(xy 380.148974 -196.721726) (xy 380.094131 -196.711596) (xy 380.041347 -196.693589) (xy 379.991747 -196.668088)
			(xy 379.946389 -196.635637) (xy 379.90624 -196.596928) (xy 379.872154 -196.552785) (xy 379.844858 -196.50415)
			(xy 379.824935 -196.452059) (xy 379.812809 -196.397622) (xy 379.808738 -196.342) (xy 369.8625 -196.342)
			(xy 369.860263 -196.349437) (xy 369.836591 -196.399934) (xy 369.805818 -196.446447) (xy 369.768601 -196.487984)
			(xy 369.725733 -196.523659) (xy 369.678127 -196.552713) (xy 369.626798 -196.574525) (xy 369.572841 -196.588631)
			(xy 369.517404 -196.594731) (xy 369.46167 -196.592694) (xy 369.406827 -196.582564) (xy 369.354043 -196.564557)
			(xy 369.304443 -196.539056) (xy 369.259085 -196.506605) (xy 369.218936 -196.467896) (xy 369.18485 -196.423753)
			(xy 369.157554 -196.375118) (xy 369.137631 -196.323027) (xy 369.125505 -196.26859) (xy 369.121434 -196.212968)
			(xy 358.192817 -196.212968) (xy 358.217576 -196.240601) (xy 358.248349 -196.287114) (xy 358.272021 -196.337611)
			(xy 358.288089 -196.391018) (xy 358.296209 -196.446194) (xy 358.296718 -196.47408) (xy 358.296209 -196.501966)
			(xy 358.288089 -196.557142) (xy 358.272021 -196.610549) (xy 358.248349 -196.661046) (xy 358.217576 -196.707559)
			(xy 358.180359 -196.749096) (xy 358.137491 -196.784771) (xy 358.089885 -196.813825) (xy 358.038556 -196.835637)
			(xy 357.984599 -196.849743) (xy 357.929162 -196.855843) (xy 357.873428 -196.853806) (xy 357.818585 -196.843676)
			(xy 357.765801 -196.825669) (xy 357.716201 -196.800168) (xy 357.670843 -196.767717) (xy 357.630694 -196.729008)
			(xy 357.596608 -196.684865) (xy 357.569312 -196.63623) (xy 357.549389 -196.584139) (xy 357.537263 -196.529702)
			(xy 357.533192 -196.47408) (xy 341.950381 -196.47408) (xy 341.952071 -196.485564) (xy 341.95258 -196.51345)
			(xy 341.952071 -196.541336) (xy 341.943951 -196.596512) (xy 341.927883 -196.649919) (xy 341.904211 -196.700416)
			(xy 341.873438 -196.746929) (xy 341.836221 -196.788466) (xy 341.793353 -196.824141) (xy 341.745747 -196.853195)
			(xy 341.694418 -196.875007) (xy 341.640461 -196.889113) (xy 341.585024 -196.895213) (xy 341.52929 -196.893176)
			(xy 341.474447 -196.883046) (xy 341.421663 -196.865039) (xy 341.372063 -196.839538) (xy 341.326705 -196.807087)
			(xy 341.286556 -196.768378) (xy 341.25247 -196.724235) (xy 341.225174 -196.6756) (xy 341.205251 -196.623509)
			(xy 341.193125 -196.569072) (xy 341.189054 -196.51345) (xy 333.691147 -196.51345) (xy 332.330941 -197.87362)
			(xy 337.520278 -197.87362) (xy 337.524349 -197.817998) (xy 337.536475 -197.763561) (xy 337.556398 -197.71147)
			(xy 337.583694 -197.662835) (xy 337.61778 -197.618692) (xy 337.657929 -197.579983) (xy 337.703287 -197.547532)
			(xy 337.752887 -197.522031) (xy 337.805671 -197.504024) (xy 337.860514 -197.493894) (xy 337.916248 -197.491857)
			(xy 337.971685 -197.497957) (xy 338.025642 -197.512063) (xy 338.066558 -197.52945) (xy 341.305386 -197.52945)
			(xy 341.309457 -197.473828) (xy 341.321583 -197.419391) (xy 341.341506 -197.3673) (xy 341.368802 -197.318665)
			(xy 341.402888 -197.274522) (xy 341.443037 -197.235813) (xy 341.488395 -197.203362) (xy 341.537995 -197.177861)
			(xy 341.590779 -197.159854) (xy 341.645622 -197.149724) (xy 341.701356 -197.147687) (xy 341.756793 -197.153787)
			(xy 341.81075 -197.167893) (xy 341.862079 -197.189705) (xy 341.909685 -197.218759) (xy 341.912491 -197.221094)
			(xy 367.229388 -197.221094) (xy 367.233459 -197.165472) (xy 367.245585 -197.111035) (xy 367.265508 -197.058944)
			(xy 367.292804 -197.010309) (xy 367.32689 -196.966166) (xy 367.367039 -196.927457) (xy 367.412397 -196.895006)
			(xy 367.461997 -196.869505) (xy 367.514781 -196.851498) (xy 367.569624 -196.841368) (xy 367.625358 -196.839331)
			(xy 367.680795 -196.845431) (xy 367.734752 -196.859537) (xy 367.786081 -196.881349) (xy 367.833687 -196.910403)
			(xy 367.876555 -196.946078) (xy 367.913772 -196.987615) (xy 367.944545 -197.034128) (xy 367.968217 -197.084625)
			(xy 367.984285 -197.138032) (xy 367.992405 -197.193208) (xy 367.992914 -197.221094) (xy 367.992405 -197.24898)
			(xy 367.984285 -197.304156) (xy 367.968217 -197.357563) (xy 367.944545 -197.40806) (xy 367.913772 -197.454573)
			(xy 367.876555 -197.49611) (xy 367.867014 -197.50405) (xy 369.061998 -197.50405) (xy 369.066069 -197.448428)
			(xy 369.078195 -197.393991) (xy 369.098118 -197.3419) (xy 369.125414 -197.293265) (xy 369.1595 -197.249122)
			(xy 369.199649 -197.210413) (xy 369.245007 -197.177962) (xy 369.294607 -197.152461) (xy 369.347391 -197.134454)
			(xy 369.402234 -197.124324) (xy 369.457968 -197.122287) (xy 369.513405 -197.128387) (xy 369.567362 -197.142493)
			(xy 369.618691 -197.164305) (xy 369.666297 -197.193359) (xy 369.709165 -197.229034) (xy 369.746382 -197.270571)
			(xy 369.777155 -197.317084) (xy 369.785738 -197.335394) (xy 378.916436 -197.335394) (xy 378.920507 -197.279772)
			(xy 378.932633 -197.225335) (xy 378.952556 -197.173244) (xy 378.979852 -197.124609) (xy 379.013938 -197.080466)
			(xy 379.054087 -197.041757) (xy 379.099445 -197.009306) (xy 379.149045 -196.983805) (xy 379.201829 -196.965798)
			(xy 379.256672 -196.955668) (xy 379.312406 -196.953631) (xy 379.367843 -196.959731) (xy 379.4218 -196.973837)
			(xy 379.473129 -196.995649) (xy 379.520735 -197.024703) (xy 379.563603 -197.060378) (xy 379.60082 -197.101915)
			(xy 379.631593 -197.148428) (xy 379.655265 -197.198925) (xy 379.671333 -197.252332) (xy 379.679453 -197.307508)
			(xy 379.679962 -197.335394) (xy 379.679549 -197.358) (xy 379.795784 -197.358) (xy 379.799855 -197.302378)
			(xy 379.811981 -197.247941) (xy 379.831904 -197.19585) (xy 379.8592 -197.147215) (xy 379.893286 -197.103072)
			(xy 379.933435 -197.064363) (xy 379.978793 -197.031912) (xy 380.028393 -197.006411) (xy 380.081177 -196.988404)
			(xy 380.13602 -196.978274) (xy 380.191754 -196.976237) (xy 380.247191 -196.982337) (xy 380.301148 -196.996443)
			(xy 380.352477 -197.018255) (xy 380.400083 -197.047309) (xy 380.442951 -197.082984) (xy 380.480168 -197.124521)
			(xy 380.510941 -197.171034) (xy 380.534613 -197.221531) (xy 380.550681 -197.274938) (xy 380.558801 -197.330114)
			(xy 380.55931 -197.358) (xy 380.558801 -197.385886) (xy 380.550681 -197.441062) (xy 380.534613 -197.494469)
			(xy 380.510941 -197.544966) (xy 380.480168 -197.591479) (xy 380.442951 -197.633016) (xy 380.400083 -197.668691)
			(xy 380.352477 -197.697745) (xy 380.301148 -197.719557) (xy 380.247191 -197.733663) (xy 380.191754 -197.739763)
			(xy 380.13602 -197.737726) (xy 380.081177 -197.727596) (xy 380.028393 -197.709589) (xy 379.978793 -197.684088)
			(xy 379.933435 -197.651637) (xy 379.893286 -197.612928) (xy 379.8592 -197.568785) (xy 379.831904 -197.52015)
			(xy 379.811981 -197.468059) (xy 379.799855 -197.413622) (xy 379.795784 -197.358) (xy 379.679549 -197.358)
			(xy 379.679453 -197.36328) (xy 379.671333 -197.418456) (xy 379.655265 -197.471863) (xy 379.631593 -197.52236)
			(xy 379.60082 -197.568873) (xy 379.563603 -197.61041) (xy 379.520735 -197.646085) (xy 379.473129 -197.675139)
			(xy 379.4218 -197.696951) (xy 379.367843 -197.711057) (xy 379.312406 -197.717157) (xy 379.256672 -197.71512)
			(xy 379.201829 -197.70499) (xy 379.149045 -197.686983) (xy 379.099445 -197.661482) (xy 379.054087 -197.629031)
			(xy 379.013938 -197.590322) (xy 378.979852 -197.546179) (xy 378.952556 -197.497544) (xy 378.932633 -197.445453)
			(xy 378.920507 -197.391016) (xy 378.916436 -197.335394) (xy 369.785738 -197.335394) (xy 369.800827 -197.367581)
			(xy 369.816895 -197.420988) (xy 369.825015 -197.476164) (xy 369.825524 -197.50405) (xy 369.825015 -197.531936)
			(xy 369.816895 -197.587112) (xy 369.800827 -197.640519) (xy 369.777155 -197.691016) (xy 369.746382 -197.737529)
			(xy 369.709165 -197.779066) (xy 369.666297 -197.814741) (xy 369.618691 -197.843795) (xy 369.567362 -197.865607)
			(xy 369.513405 -197.879713) (xy 369.457968 -197.885813) (xy 369.402234 -197.883776) (xy 369.347391 -197.873646)
			(xy 369.294607 -197.855639) (xy 369.245007 -197.830138) (xy 369.199649 -197.797687) (xy 369.1595 -197.758978)
			(xy 369.125414 -197.714835) (xy 369.098118 -197.6662) (xy 369.078195 -197.614109) (xy 369.066069 -197.559672)
			(xy 369.061998 -197.50405) (xy 367.867014 -197.50405) (xy 367.833687 -197.531785) (xy 367.786081 -197.560839)
			(xy 367.734752 -197.582651) (xy 367.680795 -197.596757) (xy 367.625358 -197.602857) (xy 367.569624 -197.60082)
			(xy 367.514781 -197.59069) (xy 367.461997 -197.572683) (xy 367.412397 -197.547182) (xy 367.367039 -197.514731)
			(xy 367.32689 -197.476022) (xy 367.292804 -197.431879) (xy 367.265508 -197.383244) (xy 367.245585 -197.331153)
			(xy 367.233459 -197.276716) (xy 367.229388 -197.221094) (xy 341.912491 -197.221094) (xy 341.952553 -197.254434)
			(xy 341.98977 -197.295971) (xy 342.020543 -197.342484) (xy 342.044215 -197.392981) (xy 342.060283 -197.446388)
			(xy 342.068403 -197.501564) (xy 342.068912 -197.52945) (xy 342.068403 -197.557336) (xy 342.060283 -197.612512)
			(xy 342.044215 -197.665919) (xy 342.020543 -197.716416) (xy 341.98977 -197.762929) (xy 341.952553 -197.804466)
			(xy 341.909685 -197.840141) (xy 341.862079 -197.869195) (xy 341.81075 -197.891007) (xy 341.756793 -197.905113)
			(xy 341.701356 -197.911213) (xy 341.645622 -197.909176) (xy 341.590779 -197.899046) (xy 341.537995 -197.881039)
			(xy 341.488395 -197.855538) (xy 341.443037 -197.823087) (xy 341.402888 -197.784378) (xy 341.368802 -197.740235)
			(xy 341.341506 -197.6916) (xy 341.321583 -197.639509) (xy 341.309457 -197.585072) (xy 341.305386 -197.52945)
			(xy 338.066558 -197.52945) (xy 338.076971 -197.533875) (xy 338.124577 -197.562929) (xy 338.167445 -197.598604)
			(xy 338.204662 -197.640141) (xy 338.235435 -197.686654) (xy 338.259107 -197.737151) (xy 338.275175 -197.790558)
			(xy 338.283295 -197.845734) (xy 338.283804 -197.87362) (xy 338.283295 -197.901506) (xy 338.275175 -197.956682)
			(xy 338.259107 -198.010089) (xy 338.235435 -198.060586) (xy 338.204662 -198.107099) (xy 338.167445 -198.148636)
			(xy 338.124577 -198.184311) (xy 338.076971 -198.213365) (xy 338.025642 -198.235177) (xy 337.971685 -198.249283)
			(xy 337.916248 -198.255383) (xy 337.860514 -198.253346) (xy 337.805671 -198.243216) (xy 337.752887 -198.225209)
			(xy 337.703287 -198.199708) (xy 337.657929 -198.167257) (xy 337.61778 -198.128548) (xy 337.583694 -198.084405)
			(xy 337.556398 -198.03577) (xy 337.536475 -197.983679) (xy 337.524349 -197.929242) (xy 337.520278 -197.87362)
			(xy 332.330941 -197.87362) (xy 331.659093 -198.54545) (xy 339.151466 -198.54545) (xy 339.155537 -198.489828)
			(xy 339.167663 -198.435391) (xy 339.187586 -198.3833) (xy 339.214882 -198.334665) (xy 339.248968 -198.290522)
			(xy 339.289117 -198.251813) (xy 339.334475 -198.219362) (xy 339.384075 -198.193861) (xy 339.436859 -198.175854)
			(xy 339.491702 -198.165724) (xy 339.547436 -198.163687) (xy 339.602873 -198.169787) (xy 339.65683 -198.183893)
			(xy 339.708159 -198.205705) (xy 339.755765 -198.234759) (xy 339.798633 -198.270434) (xy 339.83585 -198.311971)
			(xy 339.866623 -198.358484) (xy 339.890295 -198.408981) (xy 339.906363 -198.462388) (xy 339.906438 -198.4629)
			(xy 341.189054 -198.4629) (xy 341.193125 -198.407278) (xy 341.205251 -198.352841) (xy 341.225174 -198.30075)
			(xy 341.25247 -198.252115) (xy 341.286556 -198.207972) (xy 341.326705 -198.169263) (xy 341.372063 -198.136812)
			(xy 341.421663 -198.111311) (xy 341.474447 -198.093304) (xy 341.52929 -198.083174) (xy 341.585024 -198.081137)
			(xy 341.640461 -198.087237) (xy 341.694418 -198.101343) (xy 341.745747 -198.123155) (xy 341.793353 -198.152209)
			(xy 341.836221 -198.187884) (xy 341.873438 -198.229421) (xy 341.904211 -198.275934) (xy 341.927883 -198.326431)
			(xy 341.943951 -198.379838) (xy 341.952071 -198.435014) (xy 341.95258 -198.4629) (xy 341.952071 -198.490786)
			(xy 341.943951 -198.545962) (xy 341.927883 -198.599369) (xy 341.904211 -198.649866) (xy 341.873438 -198.696379)
			(xy 341.836221 -198.737916) (xy 341.793353 -198.773591) (xy 341.745747 -198.802645) (xy 341.694418 -198.824457)
			(xy 341.640461 -198.838563) (xy 341.585024 -198.844663) (xy 341.52929 -198.842626) (xy 341.474447 -198.832496)
			(xy 341.421663 -198.814489) (xy 341.372063 -198.788988) (xy 341.326705 -198.756537) (xy 341.286556 -198.717828)
			(xy 341.25247 -198.673685) (xy 341.225174 -198.62505) (xy 341.205251 -198.572959) (xy 341.193125 -198.518522)
			(xy 341.189054 -198.4629) (xy 339.906438 -198.4629) (xy 339.914483 -198.517564) (xy 339.914992 -198.54545)
			(xy 339.914483 -198.573336) (xy 339.906363 -198.628512) (xy 339.890295 -198.681919) (xy 339.866623 -198.732416)
			(xy 339.83585 -198.778929) (xy 339.798633 -198.820466) (xy 339.755765 -198.856141) (xy 339.708159 -198.885195)
			(xy 339.65683 -198.907007) (xy 339.602873 -198.921113) (xy 339.547436 -198.927213) (xy 339.491702 -198.925176)
			(xy 339.436859 -198.915046) (xy 339.384075 -198.897039) (xy 339.334475 -198.871538) (xy 339.289117 -198.839087)
			(xy 339.248968 -198.800378) (xy 339.214882 -198.756235) (xy 339.187586 -198.7076) (xy 339.167663 -198.655509)
			(xy 339.155537 -198.601072) (xy 339.151466 -198.54545) (xy 331.659093 -198.54545) (xy 331.25319 -198.951342)
			(xy 356.9622 -198.951342) (xy 356.966271 -198.89572) (xy 356.978397 -198.841283) (xy 356.99832 -198.789192)
			(xy 357.025616 -198.740557) (xy 357.059702 -198.696414) (xy 357.099851 -198.657705) (xy 357.145209 -198.625254)
			(xy 357.194809 -198.599753) (xy 357.247593 -198.581746) (xy 357.302436 -198.571616) (xy 357.35817 -198.569579)
			(xy 357.413607 -198.575679) (xy 357.452459 -198.585836) (xy 362.075982 -198.585836) (xy 362.080053 -198.530214)
			(xy 362.092179 -198.475777) (xy 362.112102 -198.423686) (xy 362.139398 -198.375051) (xy 362.173484 -198.330908)
			(xy 362.213633 -198.292199) (xy 362.258991 -198.259748) (xy 362.308591 -198.234247) (xy 362.361375 -198.21624)
			(xy 362.416218 -198.20611) (xy 362.471952 -198.204073) (xy 362.527389 -198.210173) (xy 362.581346 -198.224279)
			(xy 362.632675 -198.246091) (xy 362.680281 -198.275145) (xy 362.723149 -198.31082) (xy 362.760366 -198.352357)
			(xy 362.774685 -198.374) (xy 379.855982 -198.374) (xy 379.860053 -198.318378) (xy 379.872179 -198.263941)
			(xy 379.892102 -198.21185) (xy 379.919398 -198.163215) (xy 379.953484 -198.119072) (xy 379.993633 -198.080363)
			(xy 380.038991 -198.047912) (xy 380.088591 -198.022411) (xy 380.141375 -198.004404) (xy 380.196218 -197.994274)
			(xy 380.251952 -197.992237) (xy 380.307389 -197.998337) (xy 380.361346 -198.012443) (xy 380.412675 -198.034255)
			(xy 380.460281 -198.063309) (xy 380.503149 -198.098984) (xy 380.540366 -198.140521) (xy 380.571139 -198.187034)
			(xy 380.594811 -198.237531) (xy 380.610879 -198.290938) (xy 380.618999 -198.346114) (xy 380.619508 -198.374)
			(xy 380.618999 -198.401886) (xy 380.610879 -198.457062) (xy 380.594811 -198.510469) (xy 380.571139 -198.560966)
			(xy 380.540366 -198.607479) (xy 380.503149 -198.649016) (xy 380.460281 -198.684691) (xy 380.412675 -198.713745)
			(xy 380.361346 -198.735557) (xy 380.307389 -198.749663) (xy 380.251952 -198.755763) (xy 380.196218 -198.753726)
			(xy 380.141375 -198.743596) (xy 380.088591 -198.725589) (xy 380.038991 -198.700088) (xy 379.993633 -198.667637)
			(xy 379.953484 -198.628928) (xy 379.919398 -198.584785) (xy 379.892102 -198.53615) (xy 379.872179 -198.484059)
			(xy 379.860053 -198.429622) (xy 379.855982 -198.374) (xy 362.774685 -198.374) (xy 362.791139 -198.39887)
			(xy 362.814811 -198.449367) (xy 362.830879 -198.502774) (xy 362.838999 -198.55795) (xy 362.839508 -198.585836)
			(xy 362.838999 -198.613722) (xy 362.830879 -198.668898) (xy 362.814811 -198.722305) (xy 362.791139 -198.772802)
			(xy 362.760366 -198.819315) (xy 362.723149 -198.860852) (xy 362.680281 -198.896527) (xy 362.632675 -198.925581)
			(xy 362.581346 -198.947393) (xy 362.527389 -198.961499) (xy 362.471952 -198.967599) (xy 362.416218 -198.965562)
			(xy 362.361375 -198.955432) (xy 362.308591 -198.937425) (xy 362.258991 -198.911924) (xy 362.213633 -198.879473)
			(xy 362.173484 -198.840764) (xy 362.139398 -198.796621) (xy 362.112102 -198.747986) (xy 362.092179 -198.695895)
			(xy 362.080053 -198.641458) (xy 362.075982 -198.585836) (xy 357.452459 -198.585836) (xy 357.467564 -198.589785)
			(xy 357.518893 -198.611597) (xy 357.566499 -198.640651) (xy 357.609367 -198.676326) (xy 357.646584 -198.717863)
			(xy 357.677357 -198.764376) (xy 357.701029 -198.814873) (xy 357.717097 -198.86828) (xy 357.725217 -198.923456)
			(xy 357.725726 -198.951342) (xy 357.725217 -198.979228) (xy 357.717097 -199.034404) (xy 357.701029 -199.087811)
			(xy 357.677357 -199.138308) (xy 357.646584 -199.184821) (xy 357.609367 -199.226358) (xy 357.566499 -199.262033)
			(xy 357.518893 -199.291087) (xy 357.467564 -199.312899) (xy 357.413607 -199.327005) (xy 357.35817 -199.333105)
			(xy 357.302436 -199.331068) (xy 357.247593 -199.320938) (xy 357.194809 -199.302931) (xy 357.145209 -199.27743)
			(xy 357.099851 -199.244979) (xy 357.059702 -199.20627) (xy 357.025616 -199.162127) (xy 356.99832 -199.113492)
			(xy 356.978397 -199.061401) (xy 356.966271 -199.006964) (xy 356.9622 -198.951342) (xy 331.25319 -198.951342)
			(xy 330.870402 -199.33412) (xy 369.069364 -199.33412) (xy 369.073435 -199.278498) (xy 369.085561 -199.224061)
			(xy 369.105484 -199.17197) (xy 369.13278 -199.123335) (xy 369.166866 -199.079192) (xy 369.207015 -199.040483)
			(xy 369.252373 -199.008032) (xy 369.301973 -198.982531) (xy 369.354757 -198.964524) (xy 369.4096 -198.954394)
			(xy 369.465334 -198.952357) (xy 369.520771 -198.958457) (xy 369.574728 -198.972563) (xy 369.626057 -198.994375)
			(xy 369.673663 -199.023429) (xy 369.716531 -199.059104) (xy 369.753748 -199.100641) (xy 369.784521 -199.147154)
			(xy 369.808193 -199.197651) (xy 369.824261 -199.251058) (xy 369.832381 -199.306234) (xy 369.83289 -199.33412)
			(xy 369.832381 -199.362006) (xy 369.828261 -199.39) (xy 379.794006 -199.39) (xy 379.798077 -199.334378)
			(xy 379.810203 -199.279941) (xy 379.830126 -199.22785) (xy 379.857422 -199.179215) (xy 379.891508 -199.135072)
			(xy 379.931657 -199.096363) (xy 379.977015 -199.063912) (xy 380.026615 -199.038411) (xy 380.079399 -199.020404)
			(xy 380.134242 -199.010274) (xy 380.189976 -199.008237) (xy 380.245413 -199.014337) (xy 380.29937 -199.028443)
			(xy 380.350699 -199.050255) (xy 380.398305 -199.079309) (xy 380.441173 -199.114984) (xy 380.47839 -199.156521)
			(xy 380.509163 -199.203034) (xy 380.532835 -199.253531) (xy 380.548903 -199.306938) (xy 380.557023 -199.362114)
			(xy 380.557532 -199.39) (xy 380.557023 -199.417886) (xy 380.548903 -199.473062) (xy 380.532835 -199.526469)
			(xy 380.509163 -199.576966) (xy 380.47839 -199.623479) (xy 380.441173 -199.665016) (xy 380.398305 -199.700691)
			(xy 380.350699 -199.729745) (xy 380.29937 -199.751557) (xy 380.245413 -199.765663) (xy 380.189976 -199.771763)
			(xy 380.134242 -199.769726) (xy 380.079399 -199.759596) (xy 380.026615 -199.741589) (xy 379.977015 -199.716088)
			(xy 379.931657 -199.683637) (xy 379.891508 -199.644928) (xy 379.857422 -199.600785) (xy 379.830126 -199.55215)
			(xy 379.810203 -199.500059) (xy 379.798077 -199.445622) (xy 379.794006 -199.39) (xy 369.828261 -199.39)
			(xy 369.824261 -199.417182) (xy 369.808193 -199.470589) (xy 369.784521 -199.521086) (xy 369.753748 -199.567599)
			(xy 369.716531 -199.609136) (xy 369.673663 -199.644811) (xy 369.626057 -199.673865) (xy 369.574728 -199.695677)
			(xy 369.520771 -199.709783) (xy 369.465334 -199.715883) (xy 369.4096 -199.713846) (xy 369.354757 -199.703716)
			(xy 369.301973 -199.685709) (xy 369.252373 -199.660208) (xy 369.207015 -199.627757) (xy 369.166866 -199.589048)
			(xy 369.13278 -199.544905) (xy 369.105484 -199.49627) (xy 369.085561 -199.444179) (xy 369.073435 -199.389742)
			(xy 369.069364 -199.33412) (xy 330.870402 -199.33412) (xy 330.0525 -200.152) (xy 333.119982 -200.152)
			(xy 333.124053 -200.096378) (xy 333.136179 -200.041941) (xy 333.156102 -199.98985) (xy 333.183398 -199.941215)
			(xy 333.217484 -199.897072) (xy 333.257633 -199.858363) (xy 333.302991 -199.825912) (xy 333.352591 -199.800411)
			(xy 333.405375 -199.782404) (xy 333.460218 -199.772274) (xy 333.515952 -199.770237) (xy 333.571389 -199.776337)
			(xy 333.625346 -199.790443) (xy 333.676675 -199.812255) (xy 333.724281 -199.841309) (xy 333.767149 -199.876984)
			(xy 333.804366 -199.918521) (xy 333.835139 -199.965034) (xy 333.858811 -200.015531) (xy 333.874879 -200.068938)
			(xy 333.882999 -200.124114) (xy 333.883508 -200.152) (xy 334.135982 -200.152) (xy 334.140053 -200.096378)
			(xy 334.152179 -200.041941) (xy 334.172102 -199.98985) (xy 334.199398 -199.941215) (xy 334.233484 -199.897072)
			(xy 334.273633 -199.858363) (xy 334.318991 -199.825912) (xy 334.368591 -199.800411) (xy 334.421375 -199.782404)
			(xy 334.476218 -199.772274) (xy 334.531952 -199.770237) (xy 334.587389 -199.776337) (xy 334.641346 -199.790443)
			(xy 334.692675 -199.812255) (xy 334.740281 -199.841309) (xy 334.783149 -199.876984) (xy 334.820366 -199.918521)
			(xy 334.851139 -199.965034) (xy 334.874811 -200.015531) (xy 334.890879 -200.068938) (xy 334.898999 -200.124114)
			(xy 334.899508 -200.152) (xy 335.151982 -200.152) (xy 335.156053 -200.096378) (xy 335.168179 -200.041941)
			(xy 335.188102 -199.98985) (xy 335.215398 -199.941215) (xy 335.249484 -199.897072) (xy 335.289633 -199.858363)
			(xy 335.334991 -199.825912) (xy 335.384591 -199.800411) (xy 335.437375 -199.782404) (xy 335.492218 -199.772274)
			(xy 335.547952 -199.770237) (xy 335.603389 -199.776337) (xy 335.657346 -199.790443) (xy 335.708675 -199.812255)
			(xy 335.756281 -199.841309) (xy 335.799149 -199.876984) (xy 335.836366 -199.918521) (xy 335.867139 -199.965034)
			(xy 335.890811 -200.015531) (xy 335.906879 -200.068938) (xy 335.914999 -200.124114) (xy 335.915508 -200.152)
			(xy 336.167982 -200.152) (xy 336.172053 -200.096378) (xy 336.184179 -200.041941) (xy 336.204102 -199.98985)
			(xy 336.231398 -199.941215) (xy 336.265484 -199.897072) (xy 336.305633 -199.858363) (xy 336.350991 -199.825912)
			(xy 336.400591 -199.800411) (xy 336.453375 -199.782404) (xy 336.508218 -199.772274) (xy 336.563952 -199.770237)
			(xy 336.619389 -199.776337) (xy 336.673346 -199.790443) (xy 336.724675 -199.812255) (xy 336.772281 -199.841309)
			(xy 336.815149 -199.876984) (xy 336.852366 -199.918521) (xy 336.883139 -199.965034) (xy 336.906811 -200.015531)
			(xy 336.922879 -200.068938) (xy 336.930999 -200.124114) (xy 336.931508 -200.152) (xy 337.183982 -200.152)
			(xy 337.188053 -200.096378) (xy 337.200179 -200.041941) (xy 337.220102 -199.98985) (xy 337.247398 -199.941215)
			(xy 337.281484 -199.897072) (xy 337.321633 -199.858363) (xy 337.366991 -199.825912) (xy 337.416591 -199.800411)
			(xy 337.469375 -199.782404) (xy 337.524218 -199.772274) (xy 337.579952 -199.770237) (xy 337.635389 -199.776337)
			(xy 337.689346 -199.790443) (xy 337.740675 -199.812255) (xy 337.788281 -199.841309) (xy 337.831149 -199.876984)
			(xy 337.868366 -199.918521) (xy 337.899139 -199.965034) (xy 337.922811 -200.015531) (xy 337.938879 -200.068938)
			(xy 337.946999 -200.124114) (xy 337.947508 -200.152) (xy 338.199982 -200.152) (xy 338.204053 -200.096378)
			(xy 338.216179 -200.041941) (xy 338.236102 -199.98985) (xy 338.263398 -199.941215) (xy 338.297484 -199.897072)
			(xy 338.337633 -199.858363) (xy 338.382991 -199.825912) (xy 338.432591 -199.800411) (xy 338.485375 -199.782404)
			(xy 338.540218 -199.772274) (xy 338.595952 -199.770237) (xy 338.651389 -199.776337) (xy 338.705346 -199.790443)
			(xy 338.756675 -199.812255) (xy 338.804281 -199.841309) (xy 338.847149 -199.876984) (xy 338.884366 -199.918521)
			(xy 338.915139 -199.965034) (xy 338.938811 -200.015531) (xy 338.954879 -200.068938) (xy 338.962999 -200.124114)
			(xy 338.963508 -200.152) (xy 339.215982 -200.152) (xy 339.220053 -200.096378) (xy 339.232179 -200.041941)
			(xy 339.252102 -199.98985) (xy 339.279398 -199.941215) (xy 339.313484 -199.897072) (xy 339.353633 -199.858363)
			(xy 339.398991 -199.825912) (xy 339.448591 -199.800411) (xy 339.501375 -199.782404) (xy 339.556218 -199.772274)
			(xy 339.611952 -199.770237) (xy 339.667389 -199.776337) (xy 339.721346 -199.790443) (xy 339.772675 -199.812255)
			(xy 339.820281 -199.841309) (xy 339.863149 -199.876984) (xy 339.900366 -199.918521) (xy 339.931139 -199.965034)
			(xy 339.954811 -200.015531) (xy 339.970879 -200.068938) (xy 339.978999 -200.124114) (xy 339.979508 -200.152)
			(xy 340.231982 -200.152) (xy 340.236053 -200.096378) (xy 340.248179 -200.041941) (xy 340.268102 -199.98985)
			(xy 340.295398 -199.941215) (xy 340.329484 -199.897072) (xy 340.369633 -199.858363) (xy 340.414991 -199.825912)
			(xy 340.464591 -199.800411) (xy 340.517375 -199.782404) (xy 340.572218 -199.772274) (xy 340.627952 -199.770237)
			(xy 340.683389 -199.776337) (xy 340.737346 -199.790443) (xy 340.788675 -199.812255) (xy 340.836281 -199.841309)
			(xy 340.879149 -199.876984) (xy 340.916366 -199.918521) (xy 340.947139 -199.965034) (xy 340.970811 -200.015531)
			(xy 340.986879 -200.068938) (xy 340.994999 -200.124114) (xy 340.995508 -200.152) (xy 341.247982 -200.152)
			(xy 341.252053 -200.096378) (xy 341.264179 -200.041941) (xy 341.284102 -199.98985) (xy 341.311398 -199.941215)
			(xy 341.345484 -199.897072) (xy 341.385633 -199.858363) (xy 341.430991 -199.825912) (xy 341.480591 -199.800411)
			(xy 341.533375 -199.782404) (xy 341.588218 -199.772274) (xy 341.643952 -199.770237) (xy 341.699389 -199.776337)
			(xy 341.753346 -199.790443) (xy 341.804675 -199.812255) (xy 341.852281 -199.841309) (xy 341.895149 -199.876984)
			(xy 341.932366 -199.918521) (xy 341.963139 -199.965034) (xy 341.986811 -200.015531) (xy 342.002879 -200.068938)
			(xy 342.010999 -200.124114) (xy 342.011508 -200.152) (xy 342.2429 -200.152) (xy 342.246971 -200.096378)
			(xy 342.259097 -200.041941) (xy 342.27902 -199.98985) (xy 342.306316 -199.941215) (xy 342.340402 -199.897072)
			(xy 342.380551 -199.858363) (xy 342.425909 -199.825912) (xy 342.475509 -199.800411) (xy 342.528293 -199.782404)
			(xy 342.583136 -199.772274) (xy 342.63887 -199.770237) (xy 342.694307 -199.776337) (xy 342.748264 -199.790443)
			(xy 342.799593 -199.812255) (xy 342.847199 -199.841309) (xy 342.890067 -199.876984) (xy 342.927284 -199.918521)
			(xy 342.958057 -199.965034) (xy 342.981729 -200.015531) (xy 342.997797 -200.068938) (xy 343.005917 -200.124114)
			(xy 343.006426 -200.152) (xy 343.2335 -200.152) (xy 343.237571 -200.096378) (xy 343.249697 -200.041941)
			(xy 343.26962 -199.98985) (xy 343.296916 -199.941215) (xy 343.331002 -199.897072) (xy 343.371151 -199.858363)
			(xy 343.416509 -199.825912) (xy 343.466109 -199.800411) (xy 343.518893 -199.782404) (xy 343.573736 -199.772274)
			(xy 343.62947 -199.770237) (xy 343.684907 -199.776337) (xy 343.738864 -199.790443) (xy 343.790193 -199.812255)
			(xy 343.837799 -199.841309) (xy 343.880667 -199.876984) (xy 343.917884 -199.918521) (xy 343.948657 -199.965034)
			(xy 343.957598 -199.984106) (xy 367.982244 -199.984106) (xy 367.986315 -199.928484) (xy 367.998441 -199.874047)
			(xy 368.018364 -199.821956) (xy 368.04566 -199.773321) (xy 368.079746 -199.729178) (xy 368.119895 -199.690469)
			(xy 368.165253 -199.658018) (xy 368.214853 -199.632517) (xy 368.267637 -199.61451) (xy 368.32248 -199.60438)
			(xy 368.378214 -199.602343) (xy 368.433651 -199.608443) (xy 368.487608 -199.622549) (xy 368.538937 -199.644361)
			(xy 368.586543 -199.673415) (xy 368.629411 -199.70909) (xy 368.666628 -199.750627) (xy 368.697401 -199.79714)
			(xy 368.721073 -199.847637) (xy 368.737141 -199.901044) (xy 368.745261 -199.95622) (xy 368.74577 -199.984106)
			(xy 368.745261 -200.011992) (xy 368.737141 -200.067168) (xy 368.727361 -200.099676) (xy 380.524764 -200.099676)
			(xy 380.528835 -200.044054) (xy 380.540961 -199.989617) (xy 380.560884 -199.937526) (xy 380.58818 -199.888891)
			(xy 380.622266 -199.844748) (xy 380.662415 -199.806039) (xy 380.707773 -199.773588) (xy 380.757373 -199.748087)
			(xy 380.810157 -199.73008) (xy 380.865 -199.71995) (xy 380.920734 -199.717913) (xy 380.976171 -199.724013)
			(xy 381.030128 -199.738119) (xy 381.081457 -199.759931) (xy 381.129063 -199.788985) (xy 381.171931 -199.82466)
			(xy 381.209148 -199.866197) (xy 381.239921 -199.91271) (xy 381.263593 -199.963207) (xy 381.279661 -200.016614)
			(xy 381.287781 -200.07179) (xy 381.28829 -200.099676) (xy 381.287781 -200.127562) (xy 381.279661 -200.182738)
			(xy 381.263593 -200.236145) (xy 381.239921 -200.286642) (xy 381.209148 -200.333155) (xy 381.171931 -200.374692)
			(xy 381.129063 -200.410367) (xy 381.081457 -200.439421) (xy 381.030128 -200.461233) (xy 380.976171 -200.475339)
			(xy 380.920734 -200.481439) (xy 380.865 -200.479402) (xy 380.810157 -200.469272) (xy 380.757373 -200.451265)
			(xy 380.707773 -200.425764) (xy 380.662415 -200.393313) (xy 380.622266 -200.354604) (xy 380.58818 -200.310461)
			(xy 380.560884 -200.261826) (xy 380.540961 -200.209735) (xy 380.528835 -200.155298) (xy 380.524764 -200.099676)
			(xy 368.727361 -200.099676) (xy 368.721073 -200.120575) (xy 368.697401 -200.171072) (xy 368.666628 -200.217585)
			(xy 368.629411 -200.259122) (xy 368.586543 -200.294797) (xy 368.538937 -200.323851) (xy 368.487608 -200.345663)
			(xy 368.433651 -200.359769) (xy 368.378214 -200.365869) (xy 368.32248 -200.363832) (xy 368.267637 -200.353702)
			(xy 368.214853 -200.335695) (xy 368.165253 -200.310194) (xy 368.119895 -200.277743) (xy 368.079746 -200.239034)
			(xy 368.04566 -200.194891) (xy 368.018364 -200.146256) (xy 367.998441 -200.094165) (xy 367.986315 -200.039728)
			(xy 367.982244 -199.984106) (xy 343.957598 -199.984106) (xy 343.972329 -200.015531) (xy 343.988397 -200.068938)
			(xy 343.996517 -200.124114) (xy 343.997026 -200.152) (xy 343.996517 -200.179886) (xy 343.988397 -200.235062)
			(xy 343.972329 -200.288469) (xy 343.948657 -200.338966) (xy 343.917884 -200.385479) (xy 343.880667 -200.427016)
			(xy 343.837799 -200.462691) (xy 343.790193 -200.491745) (xy 343.738864 -200.513557) (xy 343.684907 -200.527663)
			(xy 343.62947 -200.533763) (xy 343.573736 -200.531726) (xy 343.518893 -200.521596) (xy 343.466109 -200.503589)
			(xy 343.416509 -200.478088) (xy 343.371151 -200.445637) (xy 343.331002 -200.406928) (xy 343.296916 -200.362785)
			(xy 343.26962 -200.31415) (xy 343.249697 -200.262059) (xy 343.237571 -200.207622) (xy 343.2335 -200.152)
			(xy 343.006426 -200.152) (xy 343.005917 -200.179886) (xy 342.997797 -200.235062) (xy 342.981729 -200.288469)
			(xy 342.958057 -200.338966) (xy 342.927284 -200.385479) (xy 342.890067 -200.427016) (xy 342.847199 -200.462691)
			(xy 342.799593 -200.491745) (xy 342.748264 -200.513557) (xy 342.694307 -200.527663) (xy 342.63887 -200.533763)
			(xy 342.583136 -200.531726) (xy 342.528293 -200.521596) (xy 342.475509 -200.503589) (xy 342.425909 -200.478088)
			(xy 342.380551 -200.445637) (xy 342.340402 -200.406928) (xy 342.306316 -200.362785) (xy 342.27902 -200.31415)
			(xy 342.259097 -200.262059) (xy 342.246971 -200.207622) (xy 342.2429 -200.152) (xy 342.011508 -200.152)
			(xy 342.010999 -200.179886) (xy 342.002879 -200.235062) (xy 341.986811 -200.288469) (xy 341.963139 -200.338966)
			(xy 341.932366 -200.385479) (xy 341.895149 -200.427016) (xy 341.852281 -200.462691) (xy 341.804675 -200.491745)
			(xy 341.753346 -200.513557) (xy 341.699389 -200.527663) (xy 341.643952 -200.533763) (xy 341.588218 -200.531726)
			(xy 341.533375 -200.521596) (xy 341.480591 -200.503589) (xy 341.430991 -200.478088) (xy 341.385633 -200.445637)
			(xy 341.345484 -200.406928) (xy 341.311398 -200.362785) (xy 341.284102 -200.31415) (xy 341.264179 -200.262059)
			(xy 341.252053 -200.207622) (xy 341.247982 -200.152) (xy 340.995508 -200.152) (xy 340.994999 -200.179886)
			(xy 340.986879 -200.235062) (xy 340.970811 -200.288469) (xy 340.947139 -200.338966) (xy 340.916366 -200.385479)
			(xy 340.879149 -200.427016) (xy 340.836281 -200.462691) (xy 340.788675 -200.491745) (xy 340.737346 -200.513557)
			(xy 340.683389 -200.527663) (xy 340.627952 -200.533763) (xy 340.572218 -200.531726) (xy 340.517375 -200.521596)
			(xy 340.464591 -200.503589) (xy 340.414991 -200.478088) (xy 340.369633 -200.445637) (xy 340.329484 -200.406928)
			(xy 340.295398 -200.362785) (xy 340.268102 -200.31415) (xy 340.248179 -200.262059) (xy 340.236053 -200.207622)
			(xy 340.231982 -200.152) (xy 339.979508 -200.152) (xy 339.978999 -200.179886) (xy 339.970879 -200.235062)
			(xy 339.954811 -200.288469) (xy 339.931139 -200.338966) (xy 339.900366 -200.385479) (xy 339.863149 -200.427016)
			(xy 339.820281 -200.462691) (xy 339.772675 -200.491745) (xy 339.721346 -200.513557) (xy 339.667389 -200.527663)
			(xy 339.611952 -200.533763) (xy 339.556218 -200.531726) (xy 339.501375 -200.521596) (xy 339.448591 -200.503589)
			(xy 339.398991 -200.478088) (xy 339.353633 -200.445637) (xy 339.313484 -200.406928) (xy 339.279398 -200.362785)
			(xy 339.252102 -200.31415) (xy 339.232179 -200.262059) (xy 339.220053 -200.207622) (xy 339.215982 -200.152)
			(xy 338.963508 -200.152) (xy 338.962999 -200.179886) (xy 338.954879 -200.235062) (xy 338.938811 -200.288469)
			(xy 338.915139 -200.338966) (xy 338.884366 -200.385479) (xy 338.847149 -200.427016) (xy 338.804281 -200.462691)
			(xy 338.756675 -200.491745) (xy 338.705346 -200.513557) (xy 338.651389 -200.527663) (xy 338.595952 -200.533763)
			(xy 338.540218 -200.531726) (xy 338.485375 -200.521596) (xy 338.432591 -200.503589) (xy 338.382991 -200.478088)
			(xy 338.337633 -200.445637) (xy 338.297484 -200.406928) (xy 338.263398 -200.362785) (xy 338.236102 -200.31415)
			(xy 338.216179 -200.262059) (xy 338.204053 -200.207622) (xy 338.199982 -200.152) (xy 337.947508 -200.152)
			(xy 337.946999 -200.179886) (xy 337.938879 -200.235062) (xy 337.922811 -200.288469) (xy 337.899139 -200.338966)
			(xy 337.868366 -200.385479) (xy 337.831149 -200.427016) (xy 337.788281 -200.462691) (xy 337.740675 -200.491745)
			(xy 337.689346 -200.513557) (xy 337.635389 -200.527663) (xy 337.579952 -200.533763) (xy 337.524218 -200.531726)
			(xy 337.469375 -200.521596) (xy 337.416591 -200.503589) (xy 337.366991 -200.478088) (xy 337.321633 -200.445637)
			(xy 337.281484 -200.406928) (xy 337.247398 -200.362785) (xy 337.220102 -200.31415) (xy 337.200179 -200.262059)
			(xy 337.188053 -200.207622) (xy 337.183982 -200.152) (xy 336.931508 -200.152) (xy 336.930999 -200.179886)
			(xy 336.922879 -200.235062) (xy 336.906811 -200.288469) (xy 336.883139 -200.338966) (xy 336.852366 -200.385479)
			(xy 336.815149 -200.427016) (xy 336.772281 -200.462691) (xy 336.724675 -200.491745) (xy 336.673346 -200.513557)
			(xy 336.619389 -200.527663) (xy 336.563952 -200.533763) (xy 336.508218 -200.531726) (xy 336.453375 -200.521596)
			(xy 336.400591 -200.503589) (xy 336.350991 -200.478088) (xy 336.305633 -200.445637) (xy 336.265484 -200.406928)
			(xy 336.231398 -200.362785) (xy 336.204102 -200.31415) (xy 336.184179 -200.262059) (xy 336.172053 -200.207622)
			(xy 336.167982 -200.152) (xy 335.915508 -200.152) (xy 335.914999 -200.179886) (xy 335.906879 -200.235062)
			(xy 335.890811 -200.288469) (xy 335.867139 -200.338966) (xy 335.836366 -200.385479) (xy 335.799149 -200.427016)
			(xy 335.756281 -200.462691) (xy 335.708675 -200.491745) (xy 335.657346 -200.513557) (xy 335.603389 -200.527663)
			(xy 335.547952 -200.533763) (xy 335.492218 -200.531726) (xy 335.437375 -200.521596) (xy 335.384591 -200.503589)
			(xy 335.334991 -200.478088) (xy 335.289633 -200.445637) (xy 335.249484 -200.406928) (xy 335.215398 -200.362785)
			(xy 335.188102 -200.31415) (xy 335.168179 -200.262059) (xy 335.156053 -200.207622) (xy 335.151982 -200.152)
			(xy 334.899508 -200.152) (xy 334.898999 -200.179886) (xy 334.890879 -200.235062) (xy 334.874811 -200.288469)
			(xy 334.851139 -200.338966) (xy 334.820366 -200.385479) (xy 334.783149 -200.427016) (xy 334.740281 -200.462691)
			(xy 334.692675 -200.491745) (xy 334.641346 -200.513557) (xy 334.587389 -200.527663) (xy 334.531952 -200.533763)
			(xy 334.476218 -200.531726) (xy 334.421375 -200.521596) (xy 334.368591 -200.503589) (xy 334.318991 -200.478088)
			(xy 334.273633 -200.445637) (xy 334.233484 -200.406928) (xy 334.199398 -200.362785) (xy 334.172102 -200.31415)
			(xy 334.152179 -200.262059) (xy 334.140053 -200.207622) (xy 334.135982 -200.152) (xy 333.883508 -200.152)
			(xy 333.882999 -200.179886) (xy 333.874879 -200.235062) (xy 333.858811 -200.288469) (xy 333.835139 -200.338966)
			(xy 333.804366 -200.385479) (xy 333.767149 -200.427016) (xy 333.724281 -200.462691) (xy 333.676675 -200.491745)
			(xy 333.625346 -200.513557) (xy 333.571389 -200.527663) (xy 333.515952 -200.533763) (xy 333.460218 -200.531726)
			(xy 333.405375 -200.521596) (xy 333.352591 -200.503589) (xy 333.302991 -200.478088) (xy 333.257633 -200.445637)
			(xy 333.217484 -200.406928) (xy 333.183398 -200.362785) (xy 333.156102 -200.31415) (xy 333.136179 -200.262059)
			(xy 333.124053 -200.207622) (xy 333.119982 -200.152) (xy 330.0525 -200.152) (xy 329.570395 -200.634092)
			(xy 369.069364 -200.634092) (xy 369.073435 -200.57847) (xy 369.085561 -200.524033) (xy 369.105484 -200.471942)
			(xy 369.13278 -200.423307) (xy 369.166866 -200.379164) (xy 369.207015 -200.340455) (xy 369.252373 -200.308004)
			(xy 369.301973 -200.282503) (xy 369.354757 -200.264496) (xy 369.4096 -200.254366) (xy 369.465334 -200.252329)
			(xy 369.520771 -200.258429) (xy 369.574728 -200.272535) (xy 369.626057 -200.294347) (xy 369.673663 -200.323401)
			(xy 369.716531 -200.359076) (xy 369.753748 -200.400613) (xy 369.784521 -200.447126) (xy 369.808193 -200.497623)
			(xy 369.824261 -200.55103) (xy 369.832381 -200.606206) (xy 369.83289 -200.634092) (xy 379.021846 -200.634092)
			(xy 379.025917 -200.57847) (xy 379.038043 -200.524033) (xy 379.057966 -200.471942) (xy 379.085262 -200.423307)
			(xy 379.119348 -200.379164) (xy 379.159497 -200.340455) (xy 379.204855 -200.308004) (xy 379.254455 -200.282503)
			(xy 379.307239 -200.264496) (xy 379.362082 -200.254366) (xy 379.417816 -200.252329) (xy 379.473253 -200.258429)
			(xy 379.52721 -200.272535) (xy 379.578539 -200.294347) (xy 379.626145 -200.323401) (xy 379.669013 -200.359076)
			(xy 379.70623 -200.400613) (xy 379.737003 -200.447126) (xy 379.760675 -200.497623) (xy 379.776743 -200.55103)
			(xy 379.784863 -200.606206) (xy 379.785372 -200.634092) (xy 379.784863 -200.661978) (xy 379.776743 -200.717154)
			(xy 379.760675 -200.770561) (xy 379.737003 -200.821058) (xy 379.70623 -200.867571) (xy 379.669013 -200.909108)
			(xy 379.626145 -200.944783) (xy 379.578539 -200.973837) (xy 379.52721 -200.995649) (xy 379.473253 -201.009755)
			(xy 379.417816 -201.015855) (xy 379.362082 -201.013818) (xy 379.307239 -201.003688) (xy 379.254455 -200.985681)
			(xy 379.204855 -200.96018) (xy 379.159497 -200.927729) (xy 379.119348 -200.88902) (xy 379.085262 -200.844877)
			(xy 379.057966 -200.796242) (xy 379.038043 -200.744151) (xy 379.025917 -200.689714) (xy 379.021846 -200.634092)
			(xy 369.83289 -200.634092) (xy 369.832381 -200.661978) (xy 369.824261 -200.717154) (xy 369.808193 -200.770561)
			(xy 369.784521 -200.821058) (xy 369.753748 -200.867571) (xy 369.716531 -200.909108) (xy 369.673663 -200.944783)
			(xy 369.626057 -200.973837) (xy 369.574728 -200.995649) (xy 369.520771 -201.009755) (xy 369.465334 -201.015855)
			(xy 369.4096 -201.013818) (xy 369.354757 -201.003688) (xy 369.301973 -200.985681) (xy 369.252373 -200.96018)
			(xy 369.207015 -200.927729) (xy 369.166866 -200.88902) (xy 369.13278 -200.844877) (xy 369.105484 -200.796242)
			(xy 369.085561 -200.744151) (xy 369.073435 -200.689714) (xy 369.069364 -200.634092) (xy 329.570395 -200.634092)
			(xy 328.94122 -201.26325) (xy 358.92562 -201.26325) (xy 358.929691 -201.207628) (xy 358.941817 -201.153191)
			(xy 358.96174 -201.1011) (xy 358.989036 -201.052465) (xy 359.023122 -201.008322) (xy 359.063271 -200.969613)
			(xy 359.108629 -200.937162) (xy 359.158229 -200.911661) (xy 359.211013 -200.893654) (xy 359.265856 -200.883524)
			(xy 359.32159 -200.881487) (xy 359.377027 -200.887587) (xy 359.430984 -200.901693) (xy 359.482313 -200.923505)
			(xy 359.529919 -200.952559) (xy 359.572787 -200.988234) (xy 359.610004 -201.029771) (xy 359.640777 -201.076284)
			(xy 359.664449 -201.126781) (xy 359.680517 -201.180188) (xy 359.688637 -201.235364) (xy 359.689146 -201.26325)
			(xy 359.688637 -201.291136) (xy 359.680517 -201.346312) (xy 359.664449 -201.399719) (xy 359.640777 -201.450216)
			(xy 359.610004 -201.496729) (xy 359.572787 -201.538266) (xy 359.529919 -201.573941) (xy 359.482313 -201.602995)
			(xy 359.430984 -201.624807) (xy 359.377027 -201.638913) (xy 359.32159 -201.645013) (xy 359.265856 -201.642976)
			(xy 359.211013 -201.632846) (xy 359.158229 -201.614839) (xy 359.108629 -201.589338) (xy 359.063271 -201.556887)
			(xy 359.023122 -201.518178) (xy 358.989036 -201.474035) (xy 358.96174 -201.4254) (xy 358.941817 -201.373309)
			(xy 358.929691 -201.318872) (xy 358.92562 -201.26325) (xy 328.94122 -201.26325) (xy 328.020446 -202.184)
			(xy 333.119982 -202.184) (xy 333.124053 -202.128378) (xy 333.136179 -202.073941) (xy 333.156102 -202.02185)
			(xy 333.183398 -201.973215) (xy 333.217484 -201.929072) (xy 333.257633 -201.890363) (xy 333.302991 -201.857912)
			(xy 333.352591 -201.832411) (xy 333.405375 -201.814404) (xy 333.460218 -201.804274) (xy 333.515952 -201.802237)
			(xy 333.571389 -201.808337) (xy 333.625346 -201.822443) (xy 333.676675 -201.844255) (xy 333.724281 -201.873309)
			(xy 333.767149 -201.908984) (xy 333.804366 -201.950521) (xy 333.835139 -201.997034) (xy 333.858811 -202.047531)
			(xy 333.874879 -202.100938) (xy 333.882999 -202.156114) (xy 333.883508 -202.184) (xy 335.151982 -202.184)
			(xy 335.156053 -202.128378) (xy 335.168179 -202.073941) (xy 335.188102 -202.02185) (xy 335.215398 -201.973215)
			(xy 335.249484 -201.929072) (xy 335.289633 -201.890363) (xy 335.334991 -201.857912) (xy 335.384591 -201.832411)
			(xy 335.437375 -201.814404) (xy 335.492218 -201.804274) (xy 335.547952 -201.802237) (xy 335.603389 -201.808337)
			(xy 335.657346 -201.822443) (xy 335.708675 -201.844255) (xy 335.756281 -201.873309) (xy 335.799149 -201.908984)
			(xy 335.836366 -201.950521) (xy 335.867139 -201.997034) (xy 335.890811 -202.047531) (xy 335.906879 -202.100938)
			(xy 335.914999 -202.156114) (xy 335.915508 -202.184) (xy 337.183982 -202.184) (xy 337.188053 -202.128378)
			(xy 337.200179 -202.073941) (xy 337.220102 -202.02185) (xy 337.247398 -201.973215) (xy 337.281484 -201.929072)
			(xy 337.321633 -201.890363) (xy 337.366991 -201.857912) (xy 337.416591 -201.832411) (xy 337.469375 -201.814404)
			(xy 337.524218 -201.804274) (xy 337.579952 -201.802237) (xy 337.635389 -201.808337) (xy 337.689346 -201.822443)
			(xy 337.740675 -201.844255) (xy 337.788281 -201.873309) (xy 337.831149 -201.908984) (xy 337.868366 -201.950521)
			(xy 337.899139 -201.997034) (xy 337.922811 -202.047531) (xy 337.938879 -202.100938) (xy 337.946999 -202.156114)
			(xy 337.947508 -202.184) (xy 339.215982 -202.184) (xy 339.220053 -202.128378) (xy 339.232179 -202.073941)
			(xy 339.252102 -202.02185) (xy 339.279398 -201.973215) (xy 339.313484 -201.929072) (xy 339.353633 -201.890363)
			(xy 339.398991 -201.857912) (xy 339.448591 -201.832411) (xy 339.501375 -201.814404) (xy 339.556218 -201.804274)
			(xy 339.611952 -201.802237) (xy 339.667389 -201.808337) (xy 339.721346 -201.822443) (xy 339.772675 -201.844255)
			(xy 339.820281 -201.873309) (xy 339.863149 -201.908984) (xy 339.900366 -201.950521) (xy 339.931139 -201.997034)
			(xy 339.954811 -202.047531) (xy 339.970879 -202.100938) (xy 339.978999 -202.156114) (xy 339.979508 -202.184)
			(xy 341.247982 -202.184) (xy 341.252053 -202.128378) (xy 341.264179 -202.073941) (xy 341.284102 -202.02185)
			(xy 341.311398 -201.973215) (xy 341.345484 -201.929072) (xy 341.385633 -201.890363) (xy 341.430991 -201.857912)
			(xy 341.480591 -201.832411) (xy 341.533375 -201.814404) (xy 341.588218 -201.804274) (xy 341.643952 -201.802237)
			(xy 341.699389 -201.808337) (xy 341.753346 -201.822443) (xy 341.804675 -201.844255) (xy 341.852281 -201.873309)
			(xy 341.895149 -201.908984) (xy 341.932366 -201.950521) (xy 341.963139 -201.997034) (xy 341.986811 -202.047531)
			(xy 342.002879 -202.100938) (xy 342.010999 -202.156114) (xy 342.011508 -202.184) (xy 342.2429 -202.184)
			(xy 342.246971 -202.128378) (xy 342.259097 -202.073941) (xy 342.27902 -202.02185) (xy 342.306316 -201.973215)
			(xy 342.340402 -201.929072) (xy 342.380551 -201.890363) (xy 342.425909 -201.857912) (xy 342.475509 -201.832411)
			(xy 342.528293 -201.814404) (xy 342.583136 -201.804274) (xy 342.63887 -201.802237) (xy 342.694307 -201.808337)
			(xy 342.748264 -201.822443) (xy 342.799593 -201.844255) (xy 342.847199 -201.873309) (xy 342.890067 -201.908984)
			(xy 342.927284 -201.950521) (xy 342.958057 -201.997034) (xy 342.981729 -202.047531) (xy 342.997797 -202.100938)
			(xy 343.005917 -202.156114) (xy 343.006426 -202.184) (xy 343.2335 -202.184) (xy 343.237571 -202.128378)
			(xy 343.249697 -202.073941) (xy 343.26962 -202.02185) (xy 343.296916 -201.973215) (xy 343.331002 -201.929072)
			(xy 343.371151 -201.890363) (xy 343.416509 -201.857912) (xy 343.466109 -201.832411) (xy 343.518893 -201.814404)
			(xy 343.573736 -201.804274) (xy 343.62947 -201.802237) (xy 343.636404 -201.803) (xy 362.075982 -201.803)
			(xy 362.080053 -201.747378) (xy 362.092179 -201.692941) (xy 362.112102 -201.64085) (xy 362.139398 -201.592215)
			(xy 362.173484 -201.548072) (xy 362.213633 -201.509363) (xy 362.258991 -201.476912) (xy 362.308591 -201.451411)
			(xy 362.361375 -201.433404) (xy 362.416218 -201.423274) (xy 362.471952 -201.421237) (xy 362.527389 -201.427337)
			(xy 362.581346 -201.441443) (xy 362.632675 -201.463255) (xy 362.680281 -201.492309) (xy 362.723149 -201.527984)
			(xy 362.732421 -201.538332) (xy 368.171982 -201.538332) (xy 368.176053 -201.48271) (xy 368.188179 -201.428273)
			(xy 368.208102 -201.376182) (xy 368.235398 -201.327547) (xy 368.269484 -201.283404) (xy 368.309633 -201.244695)
			(xy 368.354991 -201.212244) (xy 368.404591 -201.186743) (xy 368.457375 -201.168736) (xy 368.512218 -201.158606)
			(xy 368.567952 -201.156569) (xy 368.623389 -201.162669) (xy 368.677346 -201.176775) (xy 368.728675 -201.198587)
			(xy 368.776281 -201.227641) (xy 368.819149 -201.263316) (xy 368.837752 -201.284078) (xy 377.30506 -201.284078)
			(xy 377.309131 -201.228456) (xy 377.321257 -201.174019) (xy 377.34118 -201.121928) (xy 377.368476 -201.073293)
			(xy 377.402562 -201.02915) (xy 377.442711 -200.990441) (xy 377.488069 -200.95799) (xy 377.537669 -200.932489)
			(xy 377.590453 -200.914482) (xy 377.645296 -200.904352) (xy 377.70103 -200.902315) (xy 377.756467 -200.908415)
			(xy 377.810424 -200.922521) (xy 377.861753 -200.944333) (xy 377.909359 -200.973387) (xy 377.952227 -201.009062)
			(xy 377.989444 -201.050599) (xy 378.020217 -201.097112) (xy 378.043889 -201.147609) (xy 378.059957 -201.201016)
			(xy 378.068077 -201.256192) (xy 378.068586 -201.284078) (xy 378.068077 -201.311964) (xy 378.059957 -201.36714)
			(xy 378.043889 -201.420547) (xy 378.020217 -201.471044) (xy 377.989444 -201.517557) (xy 377.952227 -201.559094)
			(xy 377.909359 -201.594769) (xy 377.861753 -201.623823) (xy 377.810424 -201.645635) (xy 377.756467 -201.659741)
			(xy 377.70103 -201.665841) (xy 377.645296 -201.663804) (xy 377.590453 -201.653674) (xy 377.537669 -201.635667)
			(xy 377.488069 -201.610166) (xy 377.442711 -201.577715) (xy 377.402562 -201.539006) (xy 377.368476 -201.494863)
			(xy 377.34118 -201.446228) (xy 377.321257 -201.394137) (xy 377.309131 -201.3397) (xy 377.30506 -201.284078)
			(xy 368.837752 -201.284078) (xy 368.856366 -201.304853) (xy 368.887139 -201.351366) (xy 368.910811 -201.401863)
			(xy 368.926879 -201.45527) (xy 368.934999 -201.510446) (xy 368.935508 -201.538332) (xy 368.934999 -201.566218)
			(xy 368.926879 -201.621394) (xy 368.910811 -201.674801) (xy 368.887139 -201.725298) (xy 368.856366 -201.771811)
			(xy 368.819149 -201.813348) (xy 368.776281 -201.849023) (xy 368.728675 -201.878077) (xy 368.677346 -201.899889)
			(xy 368.623389 -201.913995) (xy 368.567952 -201.920095) (xy 368.512218 -201.918058) (xy 368.457375 -201.907928)
			(xy 368.404591 -201.889921) (xy 368.354991 -201.86442) (xy 368.309633 -201.831969) (xy 368.269484 -201.79326)
			(xy 368.235398 -201.749117) (xy 368.208102 -201.700482) (xy 368.188179 -201.648391) (xy 368.176053 -201.593954)
			(xy 368.171982 -201.538332) (xy 362.732421 -201.538332) (xy 362.760366 -201.569521) (xy 362.791139 -201.616034)
			(xy 362.814811 -201.666531) (xy 362.830879 -201.719938) (xy 362.838999 -201.775114) (xy 362.839508 -201.803)
			(xy 362.838999 -201.830886) (xy 362.830879 -201.886062) (xy 362.814811 -201.939469) (xy 362.791139 -201.989966)
			(xy 362.760366 -202.036479) (xy 362.723149 -202.078016) (xy 362.680281 -202.113691) (xy 362.632675 -202.142745)
			(xy 362.581346 -202.164557) (xy 362.527389 -202.178663) (xy 362.471952 -202.184763) (xy 362.416218 -202.182726)
			(xy 362.361375 -202.172596) (xy 362.308591 -202.154589) (xy 362.258991 -202.129088) (xy 362.213633 -202.096637)
			(xy 362.173484 -202.057928) (xy 362.139398 -202.013785) (xy 362.112102 -201.96515) (xy 362.092179 -201.913059)
			(xy 362.080053 -201.858622) (xy 362.075982 -201.803) (xy 343.636404 -201.803) (xy 343.684907 -201.808337)
			(xy 343.738864 -201.822443) (xy 343.790193 -201.844255) (xy 343.837799 -201.873309) (xy 343.880667 -201.908984)
			(xy 343.917884 -201.950521) (xy 343.948657 -201.997034) (xy 343.972329 -202.047531) (xy 343.988397 -202.100938)
			(xy 343.996517 -202.156114) (xy 343.997026 -202.184) (xy 343.996517 -202.211886) (xy 343.988397 -202.267062)
			(xy 343.972329 -202.320469) (xy 343.956526 -202.35418) (xy 379.391162 -202.35418) (xy 379.395233 -202.298558)
			(xy 379.407359 -202.244121) (xy 379.427282 -202.19203) (xy 379.454578 -202.143395) (xy 379.488664 -202.099252)
			(xy 379.528813 -202.060543) (xy 379.574171 -202.028092) (xy 379.623771 -202.002591) (xy 379.676555 -201.984584)
			(xy 379.731398 -201.974454) (xy 379.787132 -201.972417) (xy 379.842569 -201.978517) (xy 379.896526 -201.992623)
			(xy 379.947855 -202.014435) (xy 379.995461 -202.043489) (xy 380.038329 -202.079164) (xy 380.075546 -202.120701)
			(xy 380.106319 -202.167214) (xy 380.129991 -202.217711) (xy 380.146059 -202.271118) (xy 380.154179 -202.326294)
			(xy 380.154688 -202.35418) (xy 380.154179 -202.382066) (xy 380.151779 -202.398376) (xy 381.759712 -202.398376)
			(xy 381.763783 -202.342754) (xy 381.775909 -202.288317) (xy 381.795832 -202.236226) (xy 381.823128 -202.187591)
			(xy 381.857214 -202.143448) (xy 381.897363 -202.104739) (xy 381.942721 -202.072288) (xy 381.992321 -202.046787)
			(xy 382.045105 -202.02878) (xy 382.099948 -202.01865) (xy 382.155682 -202.016613) (xy 382.211119 -202.022713)
			(xy 382.265076 -202.036819) (xy 382.316405 -202.058631) (xy 382.364011 -202.087685) (xy 382.406879 -202.12336)
			(xy 382.444096 -202.164897) (xy 382.474869 -202.21141) (xy 382.498541 -202.261907) (xy 382.514609 -202.315314)
			(xy 382.522729 -202.37049) (xy 382.523238 -202.398376) (xy 382.522729 -202.426262) (xy 382.514609 -202.481438)
			(xy 382.498541 -202.534845) (xy 382.474869 -202.585342) (xy 382.444096 -202.631855) (xy 382.406879 -202.673392)
			(xy 382.364011 -202.709067) (xy 382.316405 -202.738121) (xy 382.265076 -202.759933) (xy 382.211119 -202.774039)
			(xy 382.155682 -202.780139) (xy 382.099948 -202.778102) (xy 382.045105 -202.767972) (xy 381.992321 -202.749965)
			(xy 381.942721 -202.724464) (xy 381.897363 -202.692013) (xy 381.857214 -202.653304) (xy 381.823128 -202.609161)
			(xy 381.795832 -202.560526) (xy 381.775909 -202.508435) (xy 381.763783 -202.453998) (xy 381.759712 -202.398376)
			(xy 380.151779 -202.398376) (xy 380.146059 -202.437242) (xy 380.129991 -202.490649) (xy 380.106319 -202.541146)
			(xy 380.075546 -202.587659) (xy 380.038329 -202.629196) (xy 379.995461 -202.664871) (xy 379.947855 -202.693925)
			(xy 379.896526 -202.715737) (xy 379.842569 -202.729843) (xy 379.787132 -202.735943) (xy 379.731398 -202.733906)
			(xy 379.676555 -202.723776) (xy 379.623771 -202.705769) (xy 379.574171 -202.680268) (xy 379.528813 -202.647817)
			(xy 379.488664 -202.609108) (xy 379.454578 -202.564965) (xy 379.427282 -202.51633) (xy 379.407359 -202.464239)
			(xy 379.395233 -202.409802) (xy 379.391162 -202.35418) (xy 343.956526 -202.35418) (xy 343.948657 -202.370966)
			(xy 343.917884 -202.417479) (xy 343.880667 -202.459016) (xy 343.837799 -202.494691) (xy 343.790193 -202.523745)
			(xy 343.738864 -202.545557) (xy 343.684907 -202.559663) (xy 343.62947 -202.565763) (xy 343.573736 -202.563726)
			(xy 343.518893 -202.553596) (xy 343.466109 -202.535589) (xy 343.416509 -202.510088) (xy 343.371151 -202.477637)
			(xy 343.331002 -202.438928) (xy 343.296916 -202.394785) (xy 343.26962 -202.34615) (xy 343.249697 -202.294059)
			(xy 343.237571 -202.239622) (xy 343.2335 -202.184) (xy 343.006426 -202.184) (xy 343.005917 -202.211886)
			(xy 342.997797 -202.267062) (xy 342.981729 -202.320469) (xy 342.958057 -202.370966) (xy 342.927284 -202.417479)
			(xy 342.890067 -202.459016) (xy 342.847199 -202.494691) (xy 342.799593 -202.523745) (xy 342.748264 -202.545557)
			(xy 342.694307 -202.559663) (xy 342.63887 -202.565763) (xy 342.583136 -202.563726) (xy 342.528293 -202.553596)
			(xy 342.475509 -202.535589) (xy 342.425909 -202.510088) (xy 342.380551 -202.477637) (xy 342.340402 -202.438928)
			(xy 342.306316 -202.394785) (xy 342.27902 -202.34615) (xy 342.259097 -202.294059) (xy 342.246971 -202.239622)
			(xy 342.2429 -202.184) (xy 342.011508 -202.184) (xy 342.010999 -202.211886) (xy 342.002879 -202.267062)
			(xy 341.986811 -202.320469) (xy 341.963139 -202.370966) (xy 341.932366 -202.417479) (xy 341.895149 -202.459016)
			(xy 341.852281 -202.494691) (xy 341.804675 -202.523745) (xy 341.753346 -202.545557) (xy 341.699389 -202.559663)
			(xy 341.643952 -202.565763) (xy 341.588218 -202.563726) (xy 341.533375 -202.553596) (xy 341.480591 -202.535589)
			(xy 341.430991 -202.510088) (xy 341.385633 -202.477637) (xy 341.345484 -202.438928) (xy 341.311398 -202.394785)
			(xy 341.284102 -202.34615) (xy 341.264179 -202.294059) (xy 341.252053 -202.239622) (xy 341.247982 -202.184)
			(xy 339.979508 -202.184) (xy 339.978999 -202.211886) (xy 339.970879 -202.267062) (xy 339.954811 -202.320469)
			(xy 339.931139 -202.370966) (xy 339.900366 -202.417479) (xy 339.863149 -202.459016) (xy 339.820281 -202.494691)
			(xy 339.772675 -202.523745) (xy 339.721346 -202.545557) (xy 339.667389 -202.559663) (xy 339.611952 -202.565763)
			(xy 339.556218 -202.563726) (xy 339.501375 -202.553596) (xy 339.448591 -202.535589) (xy 339.398991 -202.510088)
			(xy 339.353633 -202.477637) (xy 339.313484 -202.438928) (xy 339.279398 -202.394785) (xy 339.252102 -202.34615)
			(xy 339.232179 -202.294059) (xy 339.220053 -202.239622) (xy 339.215982 -202.184) (xy 337.947508 -202.184)
			(xy 337.946999 -202.211886) (xy 337.938879 -202.267062) (xy 337.922811 -202.320469) (xy 337.899139 -202.370966)
			(xy 337.868366 -202.417479) (xy 337.831149 -202.459016) (xy 337.788281 -202.494691) (xy 337.740675 -202.523745)
			(xy 337.689346 -202.545557) (xy 337.635389 -202.559663) (xy 337.579952 -202.565763) (xy 337.524218 -202.563726)
			(xy 337.469375 -202.553596) (xy 337.416591 -202.535589) (xy 337.366991 -202.510088) (xy 337.321633 -202.477637)
			(xy 337.281484 -202.438928) (xy 337.247398 -202.394785) (xy 337.220102 -202.34615) (xy 337.200179 -202.294059)
			(xy 337.188053 -202.239622) (xy 337.183982 -202.184) (xy 335.915508 -202.184) (xy 335.914999 -202.211886)
			(xy 335.906879 -202.267062) (xy 335.890811 -202.320469) (xy 335.867139 -202.370966) (xy 335.836366 -202.417479)
			(xy 335.799149 -202.459016) (xy 335.756281 -202.494691) (xy 335.708675 -202.523745) (xy 335.657346 -202.545557)
			(xy 335.603389 -202.559663) (xy 335.547952 -202.565763) (xy 335.492218 -202.563726) (xy 335.437375 -202.553596)
			(xy 335.384591 -202.535589) (xy 335.334991 -202.510088) (xy 335.289633 -202.477637) (xy 335.249484 -202.438928)
			(xy 335.215398 -202.394785) (xy 335.188102 -202.34615) (xy 335.168179 -202.294059) (xy 335.156053 -202.239622)
			(xy 335.151982 -202.184) (xy 333.883508 -202.184) (xy 333.882999 -202.211886) (xy 333.874879 -202.267062)
			(xy 333.858811 -202.320469) (xy 333.835139 -202.370966) (xy 333.804366 -202.417479) (xy 333.767149 -202.459016)
			(xy 333.724281 -202.494691) (xy 333.676675 -202.523745) (xy 333.625346 -202.545557) (xy 333.571389 -202.559663)
			(xy 333.515952 -202.565763) (xy 333.460218 -202.563726) (xy 333.405375 -202.553596) (xy 333.352591 -202.535589)
			(xy 333.302991 -202.510088) (xy 333.257633 -202.477637) (xy 333.217484 -202.438928) (xy 333.183398 -202.394785)
			(xy 333.156102 -202.34615) (xy 333.136179 -202.294059) (xy 333.124053 -202.239622) (xy 333.119982 -202.184)
			(xy 328.020446 -202.184) (xy 327.285096 -202.91933) (xy 327.281575 -202.923061) (xy 327.278496 -202.927751)
			(xy 328.673689 -202.927751) (xy 328.673689 -202.873249) (xy 328.681446 -202.819302) (xy 328.696801 -202.767007)
			(xy 328.719443 -202.717431) (xy 328.748909 -202.671581) (xy 328.784601 -202.630392) (xy 328.825792 -202.594701)
			(xy 328.871643 -202.565236) (xy 328.92122 -202.542596) (xy 328.973515 -202.527243) (xy 329.027463 -202.519488)
			(xy 329.054714 -202.519026) (xy 329.083706 -202.519589) (xy 329.141021 -202.528372) (xy 329.196349 -202.54572)
			(xy 329.248418 -202.571233) (xy 329.296031 -202.604325) (xy 329.338094 -202.644236) (xy 329.37364 -202.690047)
			(xy 329.388216 -202.715114) (xy 329.395877 -202.727765) (xy 329.417002 -202.748437) (xy 329.443168 -202.762183)
			(xy 329.472177 -202.767845) (xy 329.501591 -202.76495) (xy 329.528939 -202.753739) (xy 329.551922 -202.735155)
			(xy 329.560682 -202.723242) (xy 329.576015 -202.701771) (xy 329.611647 -202.66286) (xy 329.6523 -202.62923)
			(xy 329.697199 -202.601522) (xy 329.745487 -202.580264) (xy 329.796243 -202.565861) (xy 329.8485 -202.558589)
			(xy 329.87488 -202.558142) (xy 329.902137 -202.558504) (xy 329.956098 -202.566259) (xy 330.008405 -202.581616)
			(xy 330.057994 -202.60426) (xy 330.103856 -202.633731) (xy 330.145056 -202.66943) (xy 330.180757 -202.710628)
			(xy 330.21023 -202.756488) (xy 330.232877 -202.806076) (xy 330.248236 -202.858383) (xy 330.255995 -202.912343)
			(xy 330.255995 -202.946) (xy 334.135982 -202.946) (xy 334.140053 -202.890378) (xy 334.152179 -202.835941)
			(xy 334.172102 -202.78385) (xy 334.199398 -202.735215) (xy 334.233484 -202.691072) (xy 334.273633 -202.652363)
			(xy 334.318991 -202.619912) (xy 334.368591 -202.594411) (xy 334.421375 -202.576404) (xy 334.476218 -202.566274)
			(xy 334.531952 -202.564237) (xy 334.587389 -202.570337) (xy 334.641346 -202.584443) (xy 334.692675 -202.606255)
			(xy 334.740281 -202.635309) (xy 334.783149 -202.670984) (xy 334.820366 -202.712521) (xy 334.851139 -202.759034)
			(xy 334.874811 -202.809531) (xy 334.890879 -202.862938) (xy 334.898999 -202.918114) (xy 334.899508 -202.946)
			(xy 336.167982 -202.946) (xy 336.172053 -202.890378) (xy 336.184179 -202.835941) (xy 336.204102 -202.78385)
			(xy 336.231398 -202.735215) (xy 336.265484 -202.691072) (xy 336.305633 -202.652363) (xy 336.350991 -202.619912)
			(xy 336.400591 -202.594411) (xy 336.453375 -202.576404) (xy 336.508218 -202.566274) (xy 336.563952 -202.564237)
			(xy 336.619389 -202.570337) (xy 336.673346 -202.584443) (xy 336.724675 -202.606255) (xy 336.772281 -202.635309)
			(xy 336.815149 -202.670984) (xy 336.852366 -202.712521) (xy 336.883139 -202.759034) (xy 336.906811 -202.809531)
			(xy 336.922879 -202.862938) (xy 336.930999 -202.918114) (xy 336.931508 -202.946) (xy 336.930999 -202.973886)
			(xy 336.922879 -203.029062) (xy 336.906811 -203.082469) (xy 336.883139 -203.132966) (xy 336.852366 -203.179479)
			(xy 336.815149 -203.221016) (xy 336.772281 -203.256691) (xy 336.724675 -203.285745) (xy 336.673346 -203.307557)
			(xy 336.619389 -203.321663) (xy 336.563952 -203.327763) (xy 336.508218 -203.325726) (xy 336.453375 -203.315596)
			(xy 336.400591 -203.297589) (xy 336.350991 -203.272088) (xy 336.305633 -203.239637) (xy 336.265484 -203.200928)
			(xy 336.231398 -203.156785) (xy 336.204102 -203.10815) (xy 336.184179 -203.056059) (xy 336.172053 -203.001622)
			(xy 336.167982 -202.946) (xy 334.899508 -202.946) (xy 334.898999 -202.973886) (xy 334.890879 -203.029062)
			(xy 334.874811 -203.082469) (xy 334.851139 -203.132966) (xy 334.820366 -203.179479) (xy 334.783149 -203.221016)
			(xy 334.740281 -203.256691) (xy 334.692675 -203.285745) (xy 334.641346 -203.307557) (xy 334.587389 -203.321663)
			(xy 334.531952 -203.327763) (xy 334.476218 -203.325726) (xy 334.421375 -203.315596) (xy 334.368591 -203.297589)
			(xy 334.318991 -203.272088) (xy 334.273633 -203.239637) (xy 334.233484 -203.200928) (xy 334.199398 -203.156785)
			(xy 334.172102 -203.10815) (xy 334.152179 -203.056059) (xy 334.140053 -203.001622) (xy 334.135982 -202.946)
			(xy 330.255995 -202.946) (xy 330.255995 -202.966857) (xy 330.248236 -203.020817) (xy 330.232877 -203.073124)
			(xy 330.21023 -203.122712) (xy 330.180757 -203.168572) (xy 330.145056 -203.20977) (xy 330.103856 -203.245469)
			(xy 330.057994 -203.27494) (xy 330.008405 -203.297584) (xy 329.956098 -203.312941) (xy 329.902137 -203.320696)
			(xy 329.87488 -203.321158) (xy 329.84589 -203.320557) (xy 329.788579 -203.311775) (xy 329.733254 -203.294431)
			(xy 329.681187 -203.268923) (xy 329.633573 -203.235838) (xy 329.591508 -203.195935) (xy 329.555957 -203.150133)
			(xy 329.541378 -203.12507) (xy 329.533725 -203.112415) (xy 329.512598 -203.091745) (xy 329.48643 -203.078002)
			(xy 329.457421 -203.072341) (xy 329.428006 -203.075237) (xy 329.400658 -203.086447) (xy 329.377673 -203.10503)
			(xy 329.368912 -203.116942) (xy 329.353578 -203.138412) (xy 329.317947 -203.177324) (xy 329.277294 -203.210954)
			(xy 329.232396 -203.238663) (xy 329.184108 -203.259921) (xy 329.133351 -203.274324) (xy 329.081094 -203.281595)
			(xy 329.054714 -203.282042) (xy 329.027463 -203.281512) (xy 328.973515 -203.273757) (xy 328.92122 -203.258404)
			(xy 328.871643 -203.235764) (xy 328.825792 -203.206299) (xy 328.784601 -203.170608) (xy 328.748909 -203.129419)
			(xy 328.719443 -203.083569) (xy 328.696801 -203.033993) (xy 328.681446 -202.981698) (xy 328.673689 -202.927751)
			(xy 327.278496 -202.927751) (xy 327.275947 -202.931635) (xy 327.27392 -202.936348) (xy 327.270364 -202.944984)
			(xy 327.270364 -204.216) (xy 333.119982 -204.216) (xy 333.124053 -204.160378) (xy 333.136179 -204.105941)
			(xy 333.156102 -204.05385) (xy 333.183398 -204.005215) (xy 333.217484 -203.961072) (xy 333.257633 -203.922363)
			(xy 333.302991 -203.889912) (xy 333.352591 -203.864411) (xy 333.405375 -203.846404) (xy 333.460218 -203.836274)
			(xy 333.515952 -203.834237) (xy 333.571389 -203.840337) (xy 333.625346 -203.854443) (xy 333.676675 -203.876255)
			(xy 333.724281 -203.905309) (xy 333.767149 -203.940984) (xy 333.804366 -203.982521) (xy 333.835139 -204.029034)
			(xy 333.858811 -204.079531) (xy 333.874879 -204.132938) (xy 333.882999 -204.188114) (xy 333.883508 -204.216)
			(xy 334.135982 -204.216) (xy 334.140053 -204.160378) (xy 334.152179 -204.105941) (xy 334.172102 -204.05385)
			(xy 334.199398 -204.005215) (xy 334.233484 -203.961072) (xy 334.273633 -203.922363) (xy 334.318991 -203.889912)
			(xy 334.368591 -203.864411) (xy 334.421375 -203.846404) (xy 334.476218 -203.836274) (xy 334.531952 -203.834237)
			(xy 334.587389 -203.840337) (xy 334.641346 -203.854443) (xy 334.692675 -203.876255) (xy 334.740281 -203.905309)
			(xy 334.783149 -203.940984) (xy 334.820366 -203.982521) (xy 334.851139 -204.029034) (xy 334.874811 -204.079531)
			(xy 334.890879 -204.132938) (xy 334.898999 -204.188114) (xy 334.899508 -204.216) (xy 335.151982 -204.216)
			(xy 335.156053 -204.160378) (xy 335.168179 -204.105941) (xy 335.188102 -204.05385) (xy 335.215398 -204.005215)
			(xy 335.249484 -203.961072) (xy 335.289633 -203.922363) (xy 335.334991 -203.889912) (xy 335.384591 -203.864411)
			(xy 335.437375 -203.846404) (xy 335.492218 -203.836274) (xy 335.547952 -203.834237) (xy 335.603389 -203.840337)
			(xy 335.657346 -203.854443) (xy 335.708675 -203.876255) (xy 335.756281 -203.905309) (xy 335.799149 -203.940984)
			(xy 335.836366 -203.982521) (xy 335.867139 -204.029034) (xy 335.890811 -204.079531) (xy 335.906879 -204.132938)
			(xy 335.914999 -204.188114) (xy 335.915508 -204.216) (xy 335.914999 -204.243886) (xy 335.906879 -204.299062)
			(xy 335.890811 -204.352469) (xy 335.867139 -204.402966) (xy 335.836366 -204.449479) (xy 335.799149 -204.491016)
			(xy 335.756281 -204.526691) (xy 335.708675 -204.555745) (xy 335.657346 -204.577557) (xy 335.603389 -204.591663)
			(xy 335.547952 -204.597763) (xy 335.492218 -204.595726) (xy 335.437375 -204.585596) (xy 335.384591 -204.567589)
			(xy 335.334991 -204.542088) (xy 335.289633 -204.509637) (xy 335.249484 -204.470928) (xy 335.215398 -204.426785)
			(xy 335.188102 -204.37815) (xy 335.168179 -204.326059) (xy 335.156053 -204.271622) (xy 335.151982 -204.216)
			(xy 334.899508 -204.216) (xy 334.898999 -204.243886) (xy 334.890879 -204.299062) (xy 334.874811 -204.352469)
			(xy 334.851139 -204.402966) (xy 334.820366 -204.449479) (xy 334.783149 -204.491016) (xy 334.740281 -204.526691)
			(xy 334.692675 -204.555745) (xy 334.641346 -204.577557) (xy 334.587389 -204.591663) (xy 334.531952 -204.597763)
			(xy 334.476218 -204.595726) (xy 334.421375 -204.585596) (xy 334.368591 -204.567589) (xy 334.318991 -204.542088)
			(xy 334.273633 -204.509637) (xy 334.233484 -204.470928) (xy 334.199398 -204.426785) (xy 334.172102 -204.37815)
			(xy 334.152179 -204.326059) (xy 334.140053 -204.271622) (xy 334.135982 -204.216) (xy 333.883508 -204.216)
			(xy 333.882999 -204.243886) (xy 333.874879 -204.299062) (xy 333.858811 -204.352469) (xy 333.835139 -204.402966)
			(xy 333.804366 -204.449479) (xy 333.767149 -204.491016) (xy 333.724281 -204.526691) (xy 333.676675 -204.555745)
			(xy 333.625346 -204.577557) (xy 333.571389 -204.591663) (xy 333.515952 -204.597763) (xy 333.460218 -204.595726)
			(xy 333.405375 -204.585596) (xy 333.352591 -204.567589) (xy 333.302991 -204.542088) (xy 333.257633 -204.509637)
			(xy 333.217484 -204.470928) (xy 333.183398 -204.426785) (xy 333.156102 -204.37815) (xy 333.136179 -204.326059)
			(xy 333.124053 -204.271622) (xy 333.119982 -204.216) (xy 327.270364 -204.216) (xy 327.270364 -204.51953)
			(xy 327.270498 -204.524421) (xy 327.272411 -204.534016) (xy 327.274174 -204.53858) (xy 327.277534 -204.546042)
			(xy 327.288157 -204.558479) (xy 327.295002 -204.562964) (xy 327.367392 -204.606398) (xy 327.380346 -204.607922)
			(xy 327.393808 -204.609446) (xy 327.410572 -204.602334) (xy 327.412604 -204.601318) (xy 327.440312 -204.587328)
			(xy 327.499136 -204.567522) (xy 327.560386 -204.55748) (xy 327.59142 -204.556868) (xy 327.618686 -204.557356)
			(xy 327.672663 -204.565119) (xy 327.724987 -204.580485) (xy 327.77459 -204.603141) (xy 327.820465 -204.632625)
			(xy 327.861677 -204.668337) (xy 327.897387 -204.709551) (xy 327.926869 -204.755427) (xy 327.949522 -204.805032)
			(xy 327.964885 -204.857356) (xy 327.972646 -204.911334) (xy 327.972646 -204.965866) (xy 327.964885 -205.019844)
			(xy 327.949522 -205.072168) (xy 327.926869 -205.121773) (xy 327.897387 -205.167649) (xy 327.861677 -205.208863)
			(xy 327.820465 -205.244575) (xy 327.77459 -205.274059) (xy 327.724987 -205.296715) (xy 327.672663 -205.312081)
			(xy 327.618686 -205.319844) (xy 327.59142 -205.320392) (xy 327.591166 -205.320392) (xy 327.560513 -205.319785)
			(xy 327.499996 -205.309984) (xy 327.441827 -205.290623) (xy 327.414382 -205.276958) (xy 327.40854 -205.27391)
			(xy 327.39711 -205.271116) (xy 327.379838 -205.271116) (xy 327.37367 -205.271345) (xy 327.361719 -205.274418)
			(xy 327.356216 -205.277212) (xy 327.32218 -205.297532) (xy 327.295002 -205.313788) (xy 327.287716 -205.318598)
			(xy 327.276653 -205.332089) (xy 327.270734 -205.348501) (xy 327.270364 -205.357222) (xy 327.270364 -206.013558)
			(xy 327.271126 -206.02194) (xy 327.272904 -206.028544) (xy 327.27487 -206.034144) (xy 327.281031 -206.044285)
			(xy 327.285096 -206.04861) (xy 327.643312 -206.40675) (xy 330.361542 -206.40675) (xy 330.365613 -206.351128)
			(xy 330.377739 -206.296691) (xy 330.397662 -206.2446) (xy 330.424958 -206.195965) (xy 330.459044 -206.151822)
			(xy 330.499193 -206.113113) (xy 330.544551 -206.080662) (xy 330.594151 -206.055161) (xy 330.646935 -206.037154)
			(xy 330.701778 -206.027024) (xy 330.757512 -206.024987) (xy 330.812949 -206.031087) (xy 330.866906 -206.045193)
			(xy 330.918235 -206.067005) (xy 330.965841 -206.096059) (xy 331.008709 -206.131734) (xy 331.026401 -206.15148)
			(xy 333.627982 -206.15148) (xy 333.632053 -206.095858) (xy 333.644179 -206.041421) (xy 333.664102 -205.98933)
			(xy 333.691398 -205.940695) (xy 333.725484 -205.896552) (xy 333.765633 -205.857843) (xy 333.810991 -205.825392)
			(xy 333.860591 -205.799891) (xy 333.913375 -205.781884) (xy 333.968218 -205.771754) (xy 334.023952 -205.769717)
			(xy 334.079389 -205.775817) (xy 334.133346 -205.789923) (xy 334.184675 -205.811735) (xy 334.232281 -205.840789)
			(xy 334.275149 -205.876464) (xy 334.312366 -205.918001) (xy 334.343139 -205.964514) (xy 334.366811 -206.015011)
			(xy 334.382879 -206.068418) (xy 334.390999 -206.123594) (xy 334.391508 -206.15148) (xy 334.390999 -206.179366)
			(xy 334.382879 -206.234542) (xy 334.366811 -206.287949) (xy 334.343139 -206.338446) (xy 334.312366 -206.384959)
			(xy 334.275149 -206.426496) (xy 334.232281 -206.462171) (xy 334.184675 -206.491225) (xy 334.133346 -206.513037)
			(xy 334.079389 -206.527143) (xy 334.023952 -206.533243) (xy 333.968218 -206.531206) (xy 333.913375 -206.521076)
			(xy 333.860591 -206.503069) (xy 333.810991 -206.477568) (xy 333.765633 -206.445117) (xy 333.725484 -206.406408)
			(xy 333.691398 -206.362265) (xy 333.664102 -206.31363) (xy 333.644179 -206.261539) (xy 333.632053 -206.207102)
			(xy 333.627982 -206.15148) (xy 331.026401 -206.15148) (xy 331.045926 -206.173271) (xy 331.076699 -206.219784)
			(xy 331.100371 -206.270281) (xy 331.116439 -206.323688) (xy 331.124559 -206.378864) (xy 331.125068 -206.40675)
			(xy 331.124559 -206.434636) (xy 331.116439 -206.489812) (xy 331.100371 -206.543219) (xy 331.076699 -206.593716)
			(xy 331.045926 -206.640229) (xy 331.008709 -206.681766) (xy 330.965841 -206.717441) (xy 330.918235 -206.746495)
			(xy 330.866906 -206.768307) (xy 330.812949 -206.782413) (xy 330.757512 -206.788513) (xy 330.701778 -206.786476)
			(xy 330.646935 -206.776346) (xy 330.594151 -206.758339) (xy 330.544551 -206.732838) (xy 330.499193 -206.700387)
			(xy 330.459044 -206.661678) (xy 330.424958 -206.617535) (xy 330.397662 -206.5689) (xy 330.377739 -206.516809)
			(xy 330.365613 -206.462372) (xy 330.361542 -206.40675) (xy 327.643312 -206.40675) (xy 328.483722 -207.246982)
			(xy 328.489818 -207.253332) (xy 328.565764 -207.329278) (xy 328.566272 -207.329786) (xy 328.57313 -207.336644)
			(xy 328.57694 -207.345788) (xy 328.578715 -207.350415) (xy 328.580638 -207.360137) (xy 328.58075 -207.365092)
			(xy 328.58075 -207.473042) (xy 328.581004 -207.481678) (xy 328.581004 -208.17713) (xy 328.58202 -208.186782)
			(xy 328.583651 -208.194024) (xy 328.590497 -208.207189) (xy 328.595482 -208.21269) (xy 330.636118 -210.253326)
			(xy 330.64353 -210.26001) (xy 330.661963 -210.267607) (xy 330.681901 -210.267607) (xy 330.700334 -210.26001)
			(xy 330.707746 -210.253326) (xy 330.920598 -210.040474) (xy 330.927406 -210.032992) (xy 330.935018 -210.014268)
			(xy 330.934842 -209.994056) (xy 330.931266 -209.984594) (xy 330.931266 -209.98434) (xy 330.893674 -209.897726)
			(xy 330.889312 -209.8889) (xy 330.87523 -209.875167) (xy 330.857025 -209.867719) (xy 330.847192 -209.867246)
			(xy 330.843636 -209.867246) (xy 330.839826 -209.867246) (xy 330.835 -209.867246) (xy 330.807762 -209.86674)
			(xy 330.753845 -209.858949) (xy 330.701584 -209.843568) (xy 330.652042 -209.82091) (xy 330.606226 -209.791437)
			(xy 330.565069 -209.755746) (xy 330.529406 -209.714564) (xy 330.499964 -209.668728) (xy 330.47734 -209.619171)
			(xy 330.461995 -209.566899) (xy 330.454241 -209.512977) (xy 330.453746 -209.485738) (xy 330.454229 -209.458484)
			(xy 330.461981 -209.404529) (xy 330.477332 -209.352228) (xy 330.499971 -209.302643) (xy 330.529435 -209.256784)
			(xy 330.565126 -209.215586) (xy 330.606317 -209.179886) (xy 330.652169 -209.150411) (xy 330.701749 -209.127762)
			(xy 330.754047 -209.112399) (xy 330.808 -209.104635) (xy 330.835254 -209.10423) (xy 330.862495 -209.104712)
			(xy 330.916423 -209.112457) (xy 330.968701 -209.127796) (xy 331.018265 -209.150416) (xy 331.064106 -209.179858)
			(xy 331.105292 -209.215523) (xy 331.140984 -209.256684) (xy 331.170458 -209.302505) (xy 331.193112 -209.352053)
			(xy 331.208487 -209.404321) (xy 331.216269 -209.458243) (xy 331.216762 -209.485484) (xy 331.216762 -209.490056)
			(xy 331.216762 -209.49412) (xy 331.216762 -209.497422) (xy 331.217178 -209.507302) (xy 331.22458 -209.525619)
			(xy 331.238385 -209.539752) (xy 331.247242 -209.544158) (xy 331.253338 -209.546698) (xy 331.332078 -209.580734)
			(xy 331.345032 -209.584544) (xy 331.352144 -209.585052) (xy 331.354938 -209.585052) (xy 331.362118 -209.584801)
			(xy 331.375909 -209.580796) (xy 331.382116 -209.577178) (xy 331.386942 -209.57413) (xy 332.524608 -208.436464)
			(xy 332.525116 -208.435956) (xy 332.531974 -208.429098) (xy 332.540102 -208.410302) (xy 332.540102 -208.39811)
			(xy 332.540898 -208.373169) (xy 332.548216 -208.323808) (xy 332.561916 -208.275826) (xy 332.581764 -208.230042)
			(xy 332.60742 -208.187242) (xy 332.622652 -208.167478) (xy 332.628494 -208.160112) (xy 332.631796 -208.149952)
			(xy 332.634082 -208.135728) (xy 332.634082 -208.113884) (xy 332.634223 -208.108444) (xy 332.636527 -208.097811)
			(xy 332.638654 -208.092802) (xy 332.639924 -208.090262) (xy 332.642384 -208.084936) (xy 332.645076 -208.07352)
			(xy 332.645258 -208.067656) (xy 332.645258 -208.05267) (xy 332.645186 -208.048663) (xy 332.643902 -208.040752)
			(xy 332.642718 -208.036922) (xy 332.638908 -208.026508) (xy 332.632812 -208.019396) (xy 332.615419 -207.998489)
			(xy 332.586103 -207.952683) (xy 332.563575 -207.903184) (xy 332.548291 -207.850992) (xy 332.540559 -207.79716)
			(xy 332.540102 -207.769968) (xy 332.540102 -207.769714) (xy 332.540564 -207.742461) (xy 332.54832 -207.688509)
			(xy 332.563675 -207.63621) (xy 332.586317 -207.586629) (xy 332.615784 -207.540774) (xy 332.651478 -207.499581)
			(xy 332.692671 -207.463887) (xy 332.738525 -207.434418) (xy 332.788106 -207.411776) (xy 332.840405 -207.396421)
			(xy 332.894357 -207.388665) (xy 332.92161 -207.388206) (xy 332.947704 -207.388633) (xy 332.999406 -207.395746)
			(xy 333.049655 -207.409839) (xy 333.097516 -207.430649) (xy 333.142094 -207.457787) (xy 333.182557 -207.490746)
			(xy 333.218152 -207.528913) (xy 333.233522 -207.550004) (xy 333.237078 -207.555084) (xy 333.24165 -207.558894)
			(xy 333.25054 -207.56499) (xy 333.268066 -207.57388) (xy 333.277972 -207.57642) (xy 333.305912 -207.579468)
			(xy 333.30642 -207.579468) (xy 333.351886 -207.583532) (xy 333.357646 -207.583822) (xy 333.369054 -207.582152)
			(xy 333.374492 -207.58023) (xy 333.385414 -207.576166) (xy 333.393288 -207.567784) (xy 333.39405 -207.567022)
			(xy 334.646524 -206.314548) (xy 334.65311 -206.307168) (xy 334.660565 -206.288869) (xy 334.661002 -206.278988)
			(xy 334.661002 -206.26959) (xy 334.65897 -206.256382) (xy 334.658208 -206.253588) (xy 334.651794 -206.228744)
			(xy 334.644919 -206.177897) (xy 334.644492 -206.152242) (xy 334.644492 -206.15148) (xy 334.644979 -206.12423)
			(xy 334.652738 -206.070284) (xy 334.668095 -206.017992) (xy 334.690737 -205.968417) (xy 334.720204 -205.922569)
			(xy 334.755895 -205.881381) (xy 334.797085 -205.845692) (xy 334.842935 -205.816228) (xy 334.892511 -205.793588)
			(xy 334.944804 -205.778234) (xy 334.99875 -205.770478) (xy 335.026 -205.769972) (xy 335.026762 -205.769972)
			(xy 335.054062 -205.770362) (xy 335.108122 -205.778009) (xy 335.134458 -205.785212) (xy 335.138522 -205.786482)
			(xy 335.150714 -205.788006) (xy 335.16316 -205.786228) (xy 335.172304 -205.783942) (xy 335.185258 -205.776068)
			(xy 335.189576 -205.771496) (xy 336.29981 -204.661262) (xy 336.302858 -204.658468) (xy 336.310732 -204.651864)
			(xy 336.320638 -204.632306) (xy 336.3214 -204.621892) (xy 336.321908 -204.615542) (xy 336.319114 -204.552296)
			(xy 336.31886 -204.541628) (xy 336.301842 -204.506068) (xy 336.294222 -204.49921) (xy 336.274796 -204.481031)
			(xy 336.240665 -204.440222) (xy 336.212533 -204.395066) (xy 336.190946 -204.346441) (xy 336.176322 -204.295289)
			(xy 336.168946 -204.242601) (xy 336.168492 -204.216) (xy 336.168978 -204.188749) (xy 336.176734 -204.134801)
			(xy 336.192089 -204.082506) (xy 336.214731 -204.032929) (xy 336.244197 -203.987079) (xy 336.279888 -203.945888)
			(xy 336.321079 -203.910197) (xy 336.366929 -203.880731) (xy 336.416506 -203.858089) (xy 336.468801 -203.842734)
			(xy 336.522749 -203.834978) (xy 336.55 -203.834492) (xy 336.5766 -203.834952) (xy 336.629286 -203.842336)
			(xy 336.680438 -203.856961) (xy 336.729064 -203.878544) (xy 336.774223 -203.906668) (xy 336.815043 -203.940787)
			(xy 336.83321 -203.960222) (xy 336.840068 -203.967842) (xy 336.875628 -203.98486) (xy 336.886296 -203.985114)
			(xy 336.932524 -203.987146) (xy 336.933032 -203.987146) (xy 336.947002 -203.987908) (xy 336.953352 -203.987908)
			(xy 336.960514 -203.98744) (xy 336.974172 -203.983048) (xy 336.980276 -203.979272) (xy 336.982054 -203.978002)
			(xy 336.985864 -203.975208) (xy 338.20862 -202.752452) (xy 338.211649 -202.749463) (xy 338.218543 -202.744475)
			(xy 338.222336 -202.742546) (xy 338.266278 -202.720956) (xy 338.269978 -202.719047) (xy 338.276741 -202.714192)
			(xy 338.27974 -202.711304) (xy 338.28736 -202.703684) (xy 338.290154 -202.699874) (xy 338.308385 -202.679015)
			(xy 338.349838 -202.642266) (xy 338.396169 -202.611895) (xy 338.446403 -202.58854) (xy 338.499485 -202.572692)
			(xy 338.554301 -202.564684) (xy 338.582 -202.564238) (xy 338.611094 -202.564788) (xy 338.668607 -202.573635)
			(xy 338.724106 -202.591123) (xy 338.776301 -202.616845) (xy 338.823979 -202.650203) (xy 338.845398 -202.669902)
			(xy 338.854431 -202.678612) (xy 338.871462 -202.697042) (xy 338.879434 -202.706732) (xy 338.882736 -202.710796)
			(xy 338.887054 -202.714352) (xy 338.892134 -202.71867) (xy 338.918804 -202.73137) (xy 338.924138 -202.733148)
			(xy 338.927673 -202.734166) (xy 338.934939 -202.735312) (xy 338.938616 -202.735434) (xy 340.256876 -202.735434)
			(xy 340.262464 -202.734164) (xy 340.277196 -202.731116) (xy 340.283038 -202.728322) (xy 340.30412 -202.718416)
			(xy 340.3092 -202.714098) (xy 340.31301 -202.71105) (xy 340.31682 -202.706478) (xy 340.317836 -202.705208)
			(xy 340.31936 -202.703684) (xy 340.322154 -202.699874) (xy 340.340385 -202.679015) (xy 340.381838 -202.642266)
			(xy 340.428169 -202.611895) (xy 340.478403 -202.58854) (xy 340.531485 -202.572692) (xy 340.586301 -202.564684)
			(xy 340.614 -202.564238) (xy 340.643094 -202.564788) (xy 340.700607 -202.573635) (xy 340.756106 -202.591123)
			(xy 340.808301 -202.616845) (xy 340.855979 -202.650203) (xy 340.877398 -202.669902) (xy 340.886431 -202.678612)
			(xy 340.903462 -202.697042) (xy 340.911434 -202.706732) (xy 340.914736 -202.710796) (xy 340.919054 -202.714352)
			(xy 340.924134 -202.71867) (xy 340.950804 -202.73137) (xy 340.956138 -202.733148) (xy 340.959673 -202.734166)
			(xy 340.966939 -202.735312) (xy 340.970616 -202.735434) (xy 346.951046 -202.735434) (xy 346.960152 -202.735064)
			(xy 346.977213 -202.728692) (xy 346.98432 -202.722988) (xy 347.133164 -202.574144) (xy 347.13926 -202.568302)
			(xy 347.21546 -202.492102) (xy 347.222862 -202.485265) (xy 347.24146 -202.477552) (xy 347.251528 -202.477116)
			(xy 356.786434 -202.477116) (xy 356.791388 -202.477238) (xy 356.801106 -202.479164) (xy 356.805738 -202.480926)
			(xy 356.814882 -202.484736) (xy 356.82174 -202.491594) (xy 356.822248 -202.492102) (xy 356.898194 -202.568048)
			(xy 356.904544 -202.574144) (xy 357.138732 -202.808332) (xy 368.171982 -202.808332) (xy 368.176053 -202.75271)
			(xy 368.188179 -202.698273) (xy 368.208102 -202.646182) (xy 368.235398 -202.597547) (xy 368.269484 -202.553404)
			(xy 368.309633 -202.514695) (xy 368.354991 -202.482244) (xy 368.404591 -202.456743) (xy 368.457375 -202.438736)
			(xy 368.512218 -202.428606) (xy 368.567952 -202.426569) (xy 368.623389 -202.432669) (xy 368.677346 -202.446775)
			(xy 368.728675 -202.468587) (xy 368.776281 -202.497641) (xy 368.819149 -202.533316) (xy 368.856366 -202.574853)
			(xy 368.887139 -202.621366) (xy 368.910811 -202.671863) (xy 368.926879 -202.72527) (xy 368.934999 -202.780446)
			(xy 368.935355 -202.79995) (xy 378.439932 -202.79995) (xy 378.444003 -202.744328) (xy 378.456129 -202.689891)
			(xy 378.476052 -202.6378) (xy 378.503348 -202.589165) (xy 378.537434 -202.545022) (xy 378.577583 -202.506313)
			(xy 378.622941 -202.473862) (xy 378.672541 -202.448361) (xy 378.725325 -202.430354) (xy 378.780168 -202.420224)
			(xy 378.835902 -202.418187) (xy 378.891339 -202.424287) (xy 378.945296 -202.438393) (xy 378.996625 -202.460205)
			(xy 379.044231 -202.489259) (xy 379.087099 -202.524934) (xy 379.124316 -202.566471) (xy 379.155089 -202.612984)
			(xy 379.178761 -202.663481) (xy 379.194829 -202.716888) (xy 379.202949 -202.772064) (xy 379.203458 -202.79995)
			(xy 379.202949 -202.827836) (xy 379.194829 -202.883012) (xy 379.178761 -202.936419) (xy 379.155089 -202.986916)
			(xy 379.124316 -203.033429) (xy 379.087099 -203.074966) (xy 379.044231 -203.110641) (xy 378.996625 -203.139695)
			(xy 378.945296 -203.161507) (xy 378.891339 -203.175613) (xy 378.835902 -203.181713) (xy 378.780168 -203.179676)
			(xy 378.725325 -203.169546) (xy 378.672541 -203.151539) (xy 378.622941 -203.126038) (xy 378.577583 -203.093587)
			(xy 378.537434 -203.054878) (xy 378.503348 -203.010735) (xy 378.476052 -202.9621) (xy 378.456129 -202.910009)
			(xy 378.444003 -202.855572) (xy 378.439932 -202.79995) (xy 368.935355 -202.79995) (xy 368.935508 -202.808332)
			(xy 368.934999 -202.836218) (xy 368.926879 -202.891394) (xy 368.910811 -202.944801) (xy 368.887139 -202.995298)
			(xy 368.856366 -203.041811) (xy 368.819149 -203.083348) (xy 368.776281 -203.119023) (xy 368.728675 -203.148077)
			(xy 368.677346 -203.169889) (xy 368.623389 -203.183995) (xy 368.567952 -203.190095) (xy 368.512218 -203.188058)
			(xy 368.457375 -203.177928) (xy 368.404591 -203.159921) (xy 368.354991 -203.13442) (xy 368.309633 -203.101969)
			(xy 368.269484 -203.06326) (xy 368.235398 -203.019117) (xy 368.208102 -202.970482) (xy 368.188179 -202.918391)
			(xy 368.176053 -202.863954) (xy 368.171982 -202.808332) (xy 357.138732 -202.808332) (xy 358.1654 -203.835)
			(xy 362.075982 -203.835) (xy 362.080053 -203.779378) (xy 362.092179 -203.724941) (xy 362.112102 -203.67285)
			(xy 362.139398 -203.624215) (xy 362.173484 -203.580072) (xy 362.213633 -203.541363) (xy 362.258991 -203.508912)
			(xy 362.308591 -203.483411) (xy 362.361375 -203.465404) (xy 362.416218 -203.455274) (xy 362.471952 -203.453237)
			(xy 362.527389 -203.459337) (xy 362.581346 -203.473443) (xy 362.632675 -203.495255) (xy 362.680281 -203.524309)
			(xy 362.723149 -203.559984) (xy 362.760366 -203.601521) (xy 362.791139 -203.648034) (xy 362.814811 -203.698531)
			(xy 362.830879 -203.751938) (xy 362.838999 -203.807114) (xy 362.839508 -203.835) (xy 364.107982 -203.835)
			(xy 364.112053 -203.779378) (xy 364.124179 -203.724941) (xy 364.144102 -203.67285) (xy 364.171398 -203.624215)
			(xy 364.205484 -203.580072) (xy 364.245633 -203.541363) (xy 364.290991 -203.508912) (xy 364.340591 -203.483411)
			(xy 364.393375 -203.465404) (xy 364.448218 -203.455274) (xy 364.503952 -203.453237) (xy 364.559389 -203.459337)
			(xy 364.613346 -203.473443) (xy 364.664675 -203.495255) (xy 364.712281 -203.524309) (xy 364.755149 -203.559984)
			(xy 364.792366 -203.601521) (xy 364.823139 -203.648034) (xy 364.846811 -203.698531) (xy 364.862879 -203.751938)
			(xy 364.870999 -203.807114) (xy 364.871508 -203.835) (xy 366.139982 -203.835) (xy 366.144053 -203.779378)
			(xy 366.156179 -203.724941) (xy 366.176102 -203.67285) (xy 366.203398 -203.624215) (xy 366.237484 -203.580072)
			(xy 366.277633 -203.541363) (xy 366.322991 -203.508912) (xy 366.372591 -203.483411) (xy 366.425375 -203.465404)
			(xy 366.480218 -203.455274) (xy 366.535952 -203.453237) (xy 366.591389 -203.459337) (xy 366.645346 -203.473443)
			(xy 366.696675 -203.495255) (xy 366.744281 -203.524309) (xy 366.787149 -203.559984) (xy 366.824366 -203.601521)
			(xy 366.855139 -203.648034) (xy 366.878811 -203.698531) (xy 366.894879 -203.751938) (xy 366.902999 -203.807114)
			(xy 366.903508 -203.835) (xy 366.902999 -203.862886) (xy 366.894879 -203.918062) (xy 366.878811 -203.971469)
			(xy 366.855139 -204.021966) (xy 366.824366 -204.068479) (xy 366.787149 -204.110016) (xy 366.744281 -204.145691)
			(xy 366.696675 -204.174745) (xy 366.645346 -204.196557) (xy 366.591389 -204.210663) (xy 366.535952 -204.216763)
			(xy 366.480218 -204.214726) (xy 366.425375 -204.204596) (xy 366.372591 -204.186589) (xy 366.322991 -204.161088)
			(xy 366.277633 -204.128637) (xy 366.237484 -204.089928) (xy 366.203398 -204.045785) (xy 366.176102 -203.99715)
			(xy 366.156179 -203.945059) (xy 366.144053 -203.890622) (xy 366.139982 -203.835) (xy 364.871508 -203.835)
			(xy 364.870999 -203.862886) (xy 364.862879 -203.918062) (xy 364.846811 -203.971469) (xy 364.823139 -204.021966)
			(xy 364.792366 -204.068479) (xy 364.755149 -204.110016) (xy 364.712281 -204.145691) (xy 364.664675 -204.174745)
			(xy 364.613346 -204.196557) (xy 364.559389 -204.210663) (xy 364.503952 -204.216763) (xy 364.448218 -204.214726)
			(xy 364.393375 -204.204596) (xy 364.340591 -204.186589) (xy 364.290991 -204.161088) (xy 364.245633 -204.128637)
			(xy 364.205484 -204.089928) (xy 364.171398 -204.045785) (xy 364.144102 -203.99715) (xy 364.124179 -203.945059)
			(xy 364.112053 -203.890622) (xy 364.107982 -203.835) (xy 362.839508 -203.835) (xy 362.838999 -203.862886)
			(xy 362.830879 -203.918062) (xy 362.814811 -203.971469) (xy 362.791139 -204.021966) (xy 362.760366 -204.068479)
			(xy 362.723149 -204.110016) (xy 362.680281 -204.145691) (xy 362.632675 -204.174745) (xy 362.581346 -204.196557)
			(xy 362.527389 -204.210663) (xy 362.471952 -204.216763) (xy 362.416218 -204.214726) (xy 362.361375 -204.204596)
			(xy 362.308591 -204.186589) (xy 362.258991 -204.161088) (xy 362.213633 -204.128637) (xy 362.173484 -204.089928)
			(xy 362.139398 -204.045785) (xy 362.112102 -203.99715) (xy 362.092179 -203.945059) (xy 362.080053 -203.890622)
			(xy 362.075982 -203.835) (xy 358.1654 -203.835) (xy 360.1974 -205.867) (xy 362.075982 -205.867) (xy 362.080053 -205.811378)
			(xy 362.092179 -205.756941) (xy 362.112102 -205.70485) (xy 362.139398 -205.656215) (xy 362.173484 -205.612072)
			(xy 362.213633 -205.573363) (xy 362.258991 -205.540912) (xy 362.308591 -205.515411) (xy 362.361375 -205.497404)
			(xy 362.416218 -205.487274) (xy 362.471952 -205.485237) (xy 362.527389 -205.491337) (xy 362.581346 -205.505443)
			(xy 362.632675 -205.527255) (xy 362.680281 -205.556309) (xy 362.723149 -205.591984) (xy 362.741979 -205.613)
			(xy 364.107982 -205.613) (xy 364.112053 -205.557378) (xy 364.124179 -205.502941) (xy 364.144102 -205.45085)
			(xy 364.171398 -205.402215) (xy 364.205484 -205.358072) (xy 364.245633 -205.319363) (xy 364.290991 -205.286912)
			(xy 364.340591 -205.261411) (xy 364.393375 -205.243404) (xy 364.448218 -205.233274) (xy 364.503952 -205.231237)
			(xy 364.559389 -205.237337) (xy 364.613346 -205.251443) (xy 364.664675 -205.273255) (xy 364.712281 -205.302309)
			(xy 364.755149 -205.337984) (xy 364.792366 -205.379521) (xy 364.823139 -205.426034) (xy 364.846811 -205.476531)
			(xy 364.862879 -205.529938) (xy 364.870999 -205.585114) (xy 364.871508 -205.613) (xy 364.870999 -205.640886)
			(xy 364.862879 -205.696062) (xy 364.846811 -205.749469) (xy 364.823139 -205.799966) (xy 364.792366 -205.846479)
			(xy 364.773979 -205.867) (xy 367.155982 -205.867) (xy 367.160053 -205.811378) (xy 367.172179 -205.756941)
			(xy 367.192102 -205.70485) (xy 367.219398 -205.656215) (xy 367.253484 -205.612072) (xy 367.293633 -205.573363)
			(xy 367.338991 -205.540912) (xy 367.388591 -205.515411) (xy 367.441375 -205.497404) (xy 367.496218 -205.487274)
			(xy 367.551952 -205.485237) (xy 367.607389 -205.491337) (xy 367.661346 -205.505443) (xy 367.712675 -205.527255)
			(xy 367.760281 -205.556309) (xy 367.801849 -205.590902) (xy 377.328682 -205.590902) (xy 377.332753 -205.53528)
			(xy 377.344879 -205.480843) (xy 377.364802 -205.428752) (xy 377.392098 -205.380117) (xy 377.426184 -205.335974)
			(xy 377.466333 -205.297265) (xy 377.511691 -205.264814) (xy 377.561291 -205.239313) (xy 377.614075 -205.221306)
			(xy 377.668918 -205.211176) (xy 377.724652 -205.209139) (xy 377.780089 -205.215239) (xy 377.834046 -205.229345)
			(xy 377.885375 -205.251157) (xy 377.932981 -205.280211) (xy 377.975849 -205.315886) (xy 378.013066 -205.357423)
			(xy 378.043839 -205.403936) (xy 378.067511 -205.454433) (xy 378.077008 -205.486) (xy 379.816612 -205.486)
			(xy 379.820683 -205.430378) (xy 379.832809 -205.375941) (xy 379.852732 -205.32385) (xy 379.880028 -205.275215)
			(xy 379.914114 -205.231072) (xy 379.954263 -205.192363) (xy 379.999621 -205.159912) (xy 380.049221 -205.134411)
			(xy 380.102005 -205.116404) (xy 380.156848 -205.106274) (xy 380.212582 -205.104237) (xy 380.268019 -205.110337)
			(xy 380.321976 -205.124443) (xy 380.373305 -205.146255) (xy 380.420911 -205.175309) (xy 380.463779 -205.210984)
			(xy 380.500996 -205.252521) (xy 380.531769 -205.299034) (xy 380.555441 -205.349531) (xy 380.571509 -205.402938)
			(xy 380.579629 -205.458114) (xy 380.580138 -205.486) (xy 380.579629 -205.513886) (xy 380.571509 -205.569062)
			(xy 380.555441 -205.622469) (xy 380.531769 -205.672966) (xy 380.500996 -205.719479) (xy 380.463779 -205.761016)
			(xy 380.420911 -205.796691) (xy 380.373305 -205.825745) (xy 380.321976 -205.847557) (xy 380.268019 -205.861663)
			(xy 380.212582 -205.867763) (xy 380.156848 -205.865726) (xy 380.102005 -205.855596) (xy 380.049221 -205.837589)
			(xy 379.999621 -205.812088) (xy 379.954263 -205.779637) (xy 379.914114 -205.740928) (xy 379.880028 -205.696785)
			(xy 379.852732 -205.64815) (xy 379.832809 -205.596059) (xy 379.820683 -205.541622) (xy 379.816612 -205.486)
			(xy 378.077008 -205.486) (xy 378.083579 -205.50784) (xy 378.091699 -205.563016) (xy 378.092208 -205.590902)
			(xy 378.091699 -205.618788) (xy 378.083579 -205.673964) (xy 378.067511 -205.727371) (xy 378.043839 -205.777868)
			(xy 378.013066 -205.824381) (xy 377.975849 -205.865918) (xy 377.932981 -205.901593) (xy 377.885375 -205.930647)
			(xy 377.834046 -205.952459) (xy 377.780089 -205.966565) (xy 377.724652 -205.972665) (xy 377.668918 -205.970628)
			(xy 377.614075 -205.960498) (xy 377.561291 -205.942491) (xy 377.511691 -205.91699) (xy 377.466333 -205.884539)
			(xy 377.426184 -205.84583) (xy 377.392098 -205.801687) (xy 377.364802 -205.753052) (xy 377.344879 -205.700961)
			(xy 377.332753 -205.646524) (xy 377.328682 -205.590902) (xy 367.801849 -205.590902) (xy 367.803149 -205.591984)
			(xy 367.840366 -205.633521) (xy 367.871139 -205.680034) (xy 367.894811 -205.730531) (xy 367.910879 -205.783938)
			(xy 367.918999 -205.839114) (xy 367.919508 -205.867) (xy 367.918999 -205.894886) (xy 367.910879 -205.950062)
			(xy 367.894811 -206.003469) (xy 367.871139 -206.053966) (xy 367.840366 -206.100479) (xy 367.803149 -206.142016)
			(xy 367.760281 -206.177691) (xy 367.712675 -206.206745) (xy 367.661346 -206.228557) (xy 367.607389 -206.242663)
			(xy 367.551952 -206.248763) (xy 367.496218 -206.246726) (xy 367.441375 -206.236596) (xy 367.388591 -206.218589)
			(xy 367.338991 -206.193088) (xy 367.293633 -206.160637) (xy 367.253484 -206.121928) (xy 367.219398 -206.077785)
			(xy 367.192102 -206.02915) (xy 367.172179 -205.977059) (xy 367.160053 -205.922622) (xy 367.155982 -205.867)
			(xy 364.773979 -205.867) (xy 364.755149 -205.888016) (xy 364.712281 -205.923691) (xy 364.664675 -205.952745)
			(xy 364.613346 -205.974557) (xy 364.559389 -205.988663) (xy 364.503952 -205.994763) (xy 364.448218 -205.992726)
			(xy 364.393375 -205.982596) (xy 364.340591 -205.964589) (xy 364.290991 -205.939088) (xy 364.245633 -205.906637)
			(xy 364.205484 -205.867928) (xy 364.171398 -205.823785) (xy 364.144102 -205.77515) (xy 364.124179 -205.723059)
			(xy 364.112053 -205.668622) (xy 364.107982 -205.613) (xy 362.741979 -205.613) (xy 362.760366 -205.633521)
			(xy 362.791139 -205.680034) (xy 362.814811 -205.730531) (xy 362.830879 -205.783938) (xy 362.838999 -205.839114)
			(xy 362.839508 -205.867) (xy 362.838999 -205.894886) (xy 362.830879 -205.950062) (xy 362.814811 -206.003469)
			(xy 362.791139 -206.053966) (xy 362.760366 -206.100479) (xy 362.723149 -206.142016) (xy 362.680281 -206.177691)
			(xy 362.632675 -206.206745) (xy 362.581346 -206.228557) (xy 362.527389 -206.242663) (xy 362.471952 -206.248763)
			(xy 362.416218 -206.246726) (xy 362.361375 -206.236596) (xy 362.308591 -206.218589) (xy 362.258991 -206.193088)
			(xy 362.213633 -206.160637) (xy 362.173484 -206.121928) (xy 362.139398 -206.077785) (xy 362.112102 -206.02915)
			(xy 362.092179 -205.977059) (xy 362.080053 -205.922622) (xy 362.075982 -205.867) (xy 360.1974 -205.867)
			(xy 361.2134 -206.883) (xy 362.075982 -206.883) (xy 362.080053 -206.827378) (xy 362.092179 -206.772941)
			(xy 362.112102 -206.72085) (xy 362.139398 -206.672215) (xy 362.173484 -206.628072) (xy 362.213633 -206.589363)
			(xy 362.258991 -206.556912) (xy 362.308591 -206.531411) (xy 362.361375 -206.513404) (xy 362.416218 -206.503274)
			(xy 362.471952 -206.501237) (xy 362.527389 -206.507337) (xy 362.581346 -206.521443) (xy 362.632675 -206.543255)
			(xy 362.680281 -206.572309) (xy 362.723149 -206.607984) (xy 362.760366 -206.649521) (xy 362.791139 -206.696034)
			(xy 362.814811 -206.746531) (xy 362.830879 -206.799938) (xy 362.838999 -206.855114) (xy 362.839508 -206.883)
			(xy 364.107982 -206.883) (xy 364.112053 -206.827378) (xy 364.124179 -206.772941) (xy 364.144102 -206.72085)
			(xy 364.171398 -206.672215) (xy 364.205484 -206.628072) (xy 364.245633 -206.589363) (xy 364.290991 -206.556912)
			(xy 364.340591 -206.531411) (xy 364.393375 -206.513404) (xy 364.448218 -206.503274) (xy 364.503952 -206.501237)
			(xy 364.559389 -206.507337) (xy 364.613346 -206.521443) (xy 364.664675 -206.543255) (xy 364.712281 -206.572309)
			(xy 364.755149 -206.607984) (xy 364.792366 -206.649521) (xy 364.823139 -206.696034) (xy 364.846811 -206.746531)
			(xy 364.862879 -206.799938) (xy 364.870999 -206.855114) (xy 364.871508 -206.883) (xy 364.870999 -206.910886)
			(xy 364.862879 -206.966062) (xy 364.846811 -207.019469) (xy 364.823139 -207.069966) (xy 364.792366 -207.116479)
			(xy 364.755149 -207.158016) (xy 364.712281 -207.193691) (xy 364.664675 -207.222745) (xy 364.613346 -207.244557)
			(xy 364.559389 -207.258663) (xy 364.503952 -207.264763) (xy 364.448218 -207.262726) (xy 364.393375 -207.252596)
			(xy 364.340591 -207.234589) (xy 364.290991 -207.209088) (xy 364.245633 -207.176637) (xy 364.205484 -207.137928)
			(xy 364.171398 -207.093785) (xy 364.144102 -207.04515) (xy 364.124179 -206.993059) (xy 364.112053 -206.938622)
			(xy 364.107982 -206.883) (xy 362.839508 -206.883) (xy 362.838999 -206.910886) (xy 362.830879 -206.966062)
			(xy 362.814811 -207.019469) (xy 362.791139 -207.069966) (xy 362.760366 -207.116479) (xy 362.723149 -207.158016)
			(xy 362.680281 -207.193691) (xy 362.632675 -207.222745) (xy 362.581346 -207.244557) (xy 362.527389 -207.258663)
			(xy 362.471952 -207.264763) (xy 362.416218 -207.262726) (xy 362.361375 -207.252596) (xy 362.308591 -207.234589)
			(xy 362.258991 -207.209088) (xy 362.213633 -207.176637) (xy 362.173484 -207.137928) (xy 362.139398 -207.093785)
			(xy 362.112102 -207.04515) (xy 362.092179 -206.993059) (xy 362.080053 -206.938622) (xy 362.075982 -206.883)
			(xy 361.2134 -206.883) (xy 362.2294 -207.899) (xy 364.107982 -207.899) (xy 364.112053 -207.843378)
			(xy 364.124179 -207.788941) (xy 364.144102 -207.73685) (xy 364.171398 -207.688215) (xy 364.205484 -207.644072)
			(xy 364.245633 -207.605363) (xy 364.290991 -207.572912) (xy 364.340591 -207.547411) (xy 364.393375 -207.529404)
			(xy 364.448218 -207.519274) (xy 364.503952 -207.517237) (xy 364.559389 -207.523337) (xy 364.613346 -207.537443)
			(xy 364.664675 -207.559255) (xy 364.712281 -207.588309) (xy 364.755149 -207.623984) (xy 364.792366 -207.665521)
			(xy 364.823139 -207.712034) (xy 364.846811 -207.762531) (xy 364.862879 -207.815938) (xy 364.870999 -207.871114)
			(xy 364.871508 -207.899) (xy 367.155982 -207.899) (xy 367.160053 -207.843378) (xy 367.172179 -207.788941)
			(xy 367.192102 -207.73685) (xy 367.219398 -207.688215) (xy 367.253484 -207.644072) (xy 367.293633 -207.605363)
			(xy 367.338991 -207.572912) (xy 367.388591 -207.547411) (xy 367.441375 -207.529404) (xy 367.496218 -207.519274)
			(xy 367.551952 -207.517237) (xy 367.558886 -207.518) (xy 379.806706 -207.518) (xy 379.810777 -207.462378)
			(xy 379.822903 -207.407941) (xy 379.842826 -207.35585) (xy 379.870122 -207.307215) (xy 379.904208 -207.263072)
			(xy 379.944357 -207.224363) (xy 379.989715 -207.191912) (xy 380.039315 -207.166411) (xy 380.092099 -207.148404)
			(xy 380.146942 -207.138274) (xy 380.202676 -207.136237) (xy 380.258113 -207.142337) (xy 380.31207 -207.156443)
			(xy 380.363399 -207.178255) (xy 380.411005 -207.207309) (xy 380.453873 -207.242984) (xy 380.49109 -207.284521)
			(xy 380.521863 -207.331034) (xy 380.545535 -207.381531) (xy 380.561603 -207.434938) (xy 380.569723 -207.490114)
			(xy 380.570232 -207.518) (xy 380.569723 -207.545886) (xy 380.561603 -207.601062) (xy 380.545535 -207.654469)
			(xy 380.521863 -207.704966) (xy 380.49109 -207.751479) (xy 380.453873 -207.793016) (xy 380.411005 -207.828691)
			(xy 380.363399 -207.857745) (xy 380.31207 -207.879557) (xy 380.258113 -207.893663) (xy 380.202676 -207.899763)
			(xy 380.146942 -207.897726) (xy 380.092099 -207.887596) (xy 380.039315 -207.869589) (xy 379.989715 -207.844088)
			(xy 379.944357 -207.811637) (xy 379.904208 -207.772928) (xy 379.870122 -207.728785) (xy 379.842826 -207.68015)
			(xy 379.822903 -207.628059) (xy 379.810777 -207.573622) (xy 379.806706 -207.518) (xy 367.558886 -207.518)
			(xy 367.607389 -207.523337) (xy 367.661346 -207.537443) (xy 367.712675 -207.559255) (xy 367.760281 -207.588309)
			(xy 367.803149 -207.623984) (xy 367.840366 -207.665521) (xy 367.871139 -207.712034) (xy 367.894811 -207.762531)
			(xy 367.910879 -207.815938) (xy 367.918999 -207.871114) (xy 367.919508 -207.899) (xy 367.918999 -207.926886)
			(xy 367.910879 -207.982062) (xy 367.894811 -208.035469) (xy 367.871139 -208.085966) (xy 367.840366 -208.132479)
			(xy 367.803149 -208.174016) (xy 367.760281 -208.209691) (xy 367.712675 -208.238745) (xy 367.661346 -208.260557)
			(xy 367.607389 -208.274663) (xy 367.551952 -208.280763) (xy 367.496218 -208.278726) (xy 367.441375 -208.268596)
			(xy 367.388591 -208.250589) (xy 367.338991 -208.225088) (xy 367.293633 -208.192637) (xy 367.253484 -208.153928)
			(xy 367.219398 -208.109785) (xy 367.192102 -208.06115) (xy 367.172179 -208.009059) (xy 367.160053 -207.954622)
			(xy 367.155982 -207.899) (xy 364.871508 -207.899) (xy 364.870999 -207.926886) (xy 364.862879 -207.982062)
			(xy 364.846811 -208.035469) (xy 364.823139 -208.085966) (xy 364.792366 -208.132479) (xy 364.755149 -208.174016)
			(xy 364.712281 -208.209691) (xy 364.664675 -208.238745) (xy 364.613346 -208.260557) (xy 364.559389 -208.274663)
			(xy 364.503952 -208.280763) (xy 364.448218 -208.278726) (xy 364.393375 -208.268596) (xy 364.340591 -208.250589)
			(xy 364.290991 -208.225088) (xy 364.245633 -208.192637) (xy 364.205484 -208.153928) (xy 364.171398 -208.109785)
			(xy 364.144102 -208.06115) (xy 364.124179 -208.009059) (xy 364.112053 -207.954622) (xy 364.107982 -207.899)
			(xy 362.2294 -207.899) (xy 362.890308 -208.559908) (xy 368.70589 -208.559908) (xy 368.709961 -208.504286)
			(xy 368.722087 -208.449849) (xy 368.74201 -208.397758) (xy 368.769306 -208.349123) (xy 368.803392 -208.30498)
			(xy 368.843541 -208.266271) (xy 368.888899 -208.23382) (xy 368.938499 -208.208319) (xy 368.991283 -208.190312)
			(xy 369.046126 -208.180182) (xy 369.10186 -208.178145) (xy 369.157297 -208.184245) (xy 369.211254 -208.198351)
			(xy 369.262583 -208.220163) (xy 369.310189 -208.249217) (xy 369.353057 -208.284892) (xy 369.390274 -208.326429)
			(xy 369.421047 -208.372942) (xy 369.443131 -208.420052) (xy 378.864354 -208.420052) (xy 378.864354 -208.365548)
			(xy 378.87211 -208.3116) (xy 378.887464 -208.259305) (xy 378.910105 -208.209726) (xy 378.93957 -208.163875)
			(xy 378.97526 -208.122683) (xy 379.016449 -208.086989) (xy 379.062298 -208.05752) (xy 379.111875 -208.034876)
			(xy 379.164169 -208.019517) (xy 379.218117 -208.011756) (xy 379.245368 -208.011268) (xy 379.272317 -208.011677)
			(xy 379.325678 -208.019259) (xy 379.377441 -208.034276) (xy 379.426575 -208.056429) (xy 379.472102 -208.085277)
			(xy 379.513116 -208.120246) (xy 379.548799 -208.16064) (xy 379.578441 -208.205654) (xy 379.601453 -208.254391)
			(xy 379.609858 -208.28) (xy 379.614511 -208.293269) (xy 379.629862 -208.31681) (xy 379.651049 -208.335274)
			(xy 379.676468 -208.347263) (xy 379.704192 -208.351868) (xy 379.732122 -208.34874) (xy 379.75814 -208.338115)
			(xy 379.780277 -208.3208) (xy 379.788928 -208.309718) (xy 379.804341 -208.289161) (xy 379.839856 -208.252028)
			(xy 379.880034 -208.219999) (xy 379.924147 -208.193652) (xy 379.971397 -208.173464) (xy 380.020929 -208.1598)
			(xy 380.071847 -208.152909) (xy 380.097538 -208.152492) (xy 380.124787 -208.15298) (xy 380.178731 -208.160741)
			(xy 380.231021 -208.1761) (xy 380.280594 -208.198743) (xy 380.326439 -208.22821) (xy 380.367625 -208.263902)
			(xy 380.403312 -208.305091) (xy 380.432775 -208.35094) (xy 380.455414 -208.400514) (xy 380.470767 -208.452806)
			(xy 380.478522 -208.50675) (xy 380.478522 -208.56125) (xy 380.470767 -208.615194) (xy 380.455414 -208.667486)
			(xy 380.432775 -208.71706) (xy 380.403312 -208.762909) (xy 380.367625 -208.804098) (xy 380.326439 -208.83979)
			(xy 380.280594 -208.869257) (xy 380.231021 -208.8919) (xy 380.178731 -208.907259) (xy 380.124787 -208.91502)
			(xy 380.097538 -208.915508) (xy 380.070592 -208.91504) (xy 380.017235 -208.907461) (xy 379.965476 -208.892449)
			(xy 379.916345 -208.870302) (xy 379.87082 -208.841461) (xy 379.829807 -208.8065) (xy 379.794121 -208.766115)
			(xy 379.764475 -208.72111) (xy 379.741457 -208.672381) (xy 379.733048 -208.646776) (xy 379.728389 -208.633511)
			(xy 379.713037 -208.609974) (xy 379.69185 -208.591514) (xy 379.666433 -208.579527) (xy 379.638712 -208.574923)
			(xy 379.610785 -208.578049) (xy 379.584768 -208.588669) (xy 379.562631 -208.605979) (xy 379.553978 -208.617058)
			(xy 379.538554 -208.637607) (xy 379.503042 -208.674741) (xy 379.462867 -208.706772) (xy 379.418755 -208.733121)
			(xy 379.371507 -208.75331) (xy 379.321976 -208.766974) (xy 379.271059 -208.773867) (xy 379.245368 -208.774284)
			(xy 379.218117 -208.773844) (xy 379.164169 -208.766083) (xy 379.111875 -208.750724) (xy 379.062298 -208.72808)
			(xy 379.016449 -208.698611) (xy 378.97526 -208.662917) (xy 378.93957 -208.621725) (xy 378.910105 -208.575874)
			(xy 378.887464 -208.526295) (xy 378.87211 -208.474) (xy 378.864354 -208.420052) (xy 369.443131 -208.420052)
			(xy 369.444719 -208.423439) (xy 369.460787 -208.476846) (xy 369.468907 -208.532022) (xy 369.469416 -208.559908)
			(xy 369.468907 -208.587794) (xy 369.460787 -208.64297) (xy 369.444719 -208.696377) (xy 369.421047 -208.746874)
			(xy 369.390274 -208.793387) (xy 369.353057 -208.834924) (xy 369.310189 -208.870599) (xy 369.262583 -208.899653)
			(xy 369.211254 -208.921465) (xy 369.157297 -208.935571) (xy 369.10186 -208.941671) (xy 369.046126 -208.939634)
			(xy 368.991283 -208.929504) (xy 368.938499 -208.911497) (xy 368.888899 -208.885996) (xy 368.843541 -208.853545)
			(xy 368.803392 -208.814836) (xy 368.769306 -208.770693) (xy 368.74201 -208.722058) (xy 368.722087 -208.669967)
			(xy 368.709961 -208.61553) (xy 368.70589 -208.559908) (xy 362.890308 -208.559908) (xy 363.62513 -209.29473)
			(xy 363.631226 -209.30108) (xy 363.707172 -209.377026) (xy 363.70768 -209.377534) (xy 363.714538 -209.384392)
			(xy 363.718348 -209.393536) (xy 363.720119 -209.398164) (xy 363.722032 -209.407886) (xy 363.722158 -209.41284)
			(xy 363.722158 -209.52079) (xy 363.722412 -209.529426) (xy 363.722412 -209.677) (xy 364.107982 -209.677)
			(xy 364.112053 -209.621378) (xy 364.124179 -209.566941) (xy 364.144102 -209.51485) (xy 364.171398 -209.466215)
			(xy 364.205484 -209.422072) (xy 364.245633 -209.383363) (xy 364.290991 -209.350912) (xy 364.340591 -209.325411)
			(xy 364.393375 -209.307404) (xy 364.448218 -209.297274) (xy 364.503952 -209.295237) (xy 364.559389 -209.301337)
			(xy 364.613346 -209.315443) (xy 364.664675 -209.337255) (xy 364.712281 -209.366309) (xy 364.755149 -209.401984)
			(xy 364.792366 -209.443521) (xy 364.823139 -209.490034) (xy 364.846811 -209.540531) (xy 364.862879 -209.593938)
			(xy 364.870999 -209.649114) (xy 364.871508 -209.677) (xy 364.870999 -209.704886) (xy 364.862879 -209.760062)
			(xy 364.846811 -209.813469) (xy 364.823139 -209.863966) (xy 364.792366 -209.910479) (xy 364.773979 -209.931)
			(xy 368.70589 -209.931) (xy 368.709961 -209.875378) (xy 368.722087 -209.820941) (xy 368.74201 -209.76885)
			(xy 368.769306 -209.720215) (xy 368.803392 -209.676072) (xy 368.843541 -209.637363) (xy 368.888899 -209.604912)
			(xy 368.938499 -209.579411) (xy 368.991283 -209.561404) (xy 369.046126 -209.551274) (xy 369.10186 -209.549237)
			(xy 369.157297 -209.555337) (xy 369.211254 -209.569443) (xy 369.262583 -209.591255) (xy 369.310189 -209.620309)
			(xy 369.316047 -209.625184) (xy 377.160026 -209.625184) (xy 377.164097 -209.569562) (xy 377.176223 -209.515125)
			(xy 377.196146 -209.463034) (xy 377.223442 -209.414399) (xy 377.257528 -209.370256) (xy 377.297677 -209.331547)
			(xy 377.343035 -209.299096) (xy 377.392635 -209.273595) (xy 377.445419 -209.255588) (xy 377.500262 -209.245458)
			(xy 377.555996 -209.243421) (xy 377.611433 -209.249521) (xy 377.66539 -209.263627) (xy 377.716719 -209.285439)
			(xy 377.764325 -209.314493) (xy 377.807193 -209.350168) (xy 377.84441 -209.391705) (xy 377.875183 -209.438218)
			(xy 377.898855 -209.488715) (xy 377.914923 -209.542122) (xy 377.916082 -209.55) (xy 379.408942 -209.55)
			(xy 379.413013 -209.494378) (xy 379.425139 -209.439941) (xy 379.445062 -209.38785) (xy 379.472358 -209.339215)
			(xy 379.506444 -209.295072) (xy 379.546593 -209.256363) (xy 379.591951 -209.223912) (xy 379.641551 -209.198411)
			(xy 379.694335 -209.180404) (xy 379.749178 -209.170274) (xy 379.804912 -209.168237) (xy 379.860349 -209.174337)
			(xy 379.914306 -209.188443) (xy 379.965635 -209.210255) (xy 380.013241 -209.239309) (xy 380.056109 -209.274984)
			(xy 380.093326 -209.316521) (xy 380.124099 -209.363034) (xy 380.147771 -209.413531) (xy 380.163839 -209.466938)
			(xy 380.171959 -209.522114) (xy 380.172468 -209.55) (xy 380.171959 -209.577886) (xy 380.163839 -209.633062)
			(xy 380.147771 -209.686469) (xy 380.124099 -209.736966) (xy 380.093326 -209.783479) (xy 380.056109 -209.825016)
			(xy 380.013241 -209.860691) (xy 379.965635 -209.889745) (xy 379.914306 -209.911557) (xy 379.860349 -209.925663)
			(xy 379.804912 -209.931763) (xy 379.749178 -209.929726) (xy 379.694335 -209.919596) (xy 379.641551 -209.901589)
			(xy 379.591951 -209.876088) (xy 379.546593 -209.843637) (xy 379.506444 -209.804928) (xy 379.472358 -209.760785)
			(xy 379.445062 -209.71215) (xy 379.425139 -209.660059) (xy 379.413013 -209.605622) (xy 379.408942 -209.55)
			(xy 377.916082 -209.55) (xy 377.923043 -209.597298) (xy 377.923552 -209.625184) (xy 377.923043 -209.65307)
			(xy 377.914923 -209.708246) (xy 377.898855 -209.761653) (xy 377.875183 -209.81215) (xy 377.84441 -209.858663)
			(xy 377.807193 -209.9002) (xy 377.764325 -209.935875) (xy 377.716719 -209.964929) (xy 377.66539 -209.986741)
			(xy 377.611433 -210.000847) (xy 377.555996 -210.006947) (xy 377.500262 -210.00491) (xy 377.445419 -209.99478)
			(xy 377.392635 -209.976773) (xy 377.343035 -209.951272) (xy 377.297677 -209.918821) (xy 377.257528 -209.880112)
			(xy 377.223442 -209.835969) (xy 377.196146 -209.787334) (xy 377.176223 -209.735243) (xy 377.164097 -209.680806)
			(xy 377.160026 -209.625184) (xy 369.316047 -209.625184) (xy 369.353057 -209.655984) (xy 369.390274 -209.697521)
			(xy 369.421047 -209.744034) (xy 369.444719 -209.794531) (xy 369.460787 -209.847938) (xy 369.468907 -209.903114)
			(xy 369.469416 -209.931) (xy 369.468907 -209.958886) (xy 369.460787 -210.014062) (xy 369.444719 -210.067469)
			(xy 369.421047 -210.117966) (xy 369.390274 -210.164479) (xy 369.353057 -210.206016) (xy 369.339854 -210.217004)
			(xy 374.69394 -210.217004) (xy 374.698011 -210.161382) (xy 374.710137 -210.106945) (xy 374.73006 -210.054854)
			(xy 374.757356 -210.006219) (xy 374.791442 -209.962076) (xy 374.831591 -209.923367) (xy 374.876949 -209.890916)
			(xy 374.926549 -209.865415) (xy 374.979333 -209.847408) (xy 375.034176 -209.837278) (xy 375.08991 -209.835241)
			(xy 375.145347 -209.841341) (xy 375.199304 -209.855447) (xy 375.250633 -209.877259) (xy 375.298239 -209.906313)
			(xy 375.341107 -209.941988) (xy 375.378324 -209.983525) (xy 375.409097 -210.030038) (xy 375.432769 -210.080535)
			(xy 375.448837 -210.133942) (xy 375.456957 -210.189118) (xy 375.457466 -210.217004) (xy 375.456957 -210.24489)
			(xy 375.448837 -210.300066) (xy 375.432769 -210.353473) (xy 375.409097 -210.40397) (xy 375.378324 -210.450483)
			(xy 375.341107 -210.49202) (xy 375.298239 -210.527695) (xy 375.250633 -210.556749) (xy 375.228863 -210.566)
			(xy 379.759716 -210.566) (xy 379.763787 -210.510378) (xy 379.775913 -210.455941) (xy 379.795836 -210.40385)
			(xy 379.823132 -210.355215) (xy 379.857218 -210.311072) (xy 379.897367 -210.272363) (xy 379.942725 -210.239912)
			(xy 379.992325 -210.214411) (xy 380.045109 -210.196404) (xy 380.099952 -210.186274) (xy 380.155686 -210.184237)
			(xy 380.211123 -210.190337) (xy 380.26508 -210.204443) (xy 380.316409 -210.226255) (xy 380.364015 -210.255309)
			(xy 380.406883 -210.290984) (xy 380.4441 -210.332521) (xy 380.474873 -210.379034) (xy 380.498545 -210.429531)
			(xy 380.514613 -210.482938) (xy 380.522733 -210.538114) (xy 380.523242 -210.566) (xy 380.522733 -210.593886)
			(xy 380.514613 -210.649062) (xy 380.498545 -210.702469) (xy 380.474873 -210.752966) (xy 380.4441 -210.799479)
			(xy 380.406883 -210.841016) (xy 380.364015 -210.876691) (xy 380.316409 -210.905745) (xy 380.26508 -210.927557)
			(xy 380.211123 -210.941663) (xy 380.155686 -210.947763) (xy 380.099952 -210.945726) (xy 380.045109 -210.935596)
			(xy 379.992325 -210.917589) (xy 379.942725 -210.892088) (xy 379.897367 -210.859637) (xy 379.857218 -210.820928)
			(xy 379.823132 -210.776785) (xy 379.795836 -210.72815) (xy 379.775913 -210.676059) (xy 379.763787 -210.621622)
			(xy 379.759716 -210.566) (xy 375.228863 -210.566) (xy 375.199304 -210.578561) (xy 375.145347 -210.592667)
			(xy 375.08991 -210.598767) (xy 375.034176 -210.59673) (xy 374.979333 -210.5866) (xy 374.926549 -210.568593)
			(xy 374.876949 -210.543092) (xy 374.831591 -210.510641) (xy 374.791442 -210.471932) (xy 374.757356 -210.427789)
			(xy 374.73006 -210.379154) (xy 374.710137 -210.327063) (xy 374.698011 -210.272626) (xy 374.69394 -210.217004)
			(xy 369.339854 -210.217004) (xy 369.310189 -210.241691) (xy 369.262583 -210.270745) (xy 369.211254 -210.292557)
			(xy 369.157297 -210.306663) (xy 369.10186 -210.312763) (xy 369.046126 -210.310726) (xy 368.991283 -210.300596)
			(xy 368.938499 -210.282589) (xy 368.888899 -210.257088) (xy 368.843541 -210.224637) (xy 368.803392 -210.185928)
			(xy 368.769306 -210.141785) (xy 368.74201 -210.09315) (xy 368.722087 -210.041059) (xy 368.709961 -209.986622)
			(xy 368.70589 -209.931) (xy 364.773979 -209.931) (xy 364.755149 -209.952016) (xy 364.712281 -209.987691)
			(xy 364.664675 -210.016745) (xy 364.613346 -210.038557) (xy 364.559389 -210.052663) (xy 364.503952 -210.058763)
			(xy 364.448218 -210.056726) (xy 364.393375 -210.046596) (xy 364.340591 -210.028589) (xy 364.290991 -210.003088)
			(xy 364.245633 -209.970637) (xy 364.205484 -209.931928) (xy 364.171398 -209.887785) (xy 364.144102 -209.83915)
			(xy 364.124179 -209.787059) (xy 364.112053 -209.732622) (xy 364.107982 -209.677) (xy 363.722412 -209.677)
			(xy 363.722412 -210.710018) (xy 363.723457 -210.717593) (xy 363.729388 -210.731679) (xy 363.734096 -210.737704)
			(xy 363.947202 -210.95081) (xy 363.954057 -210.956135) (xy 363.970288 -210.962253) (xy 363.98763 -210.962611)
			(xy 363.99597 -210.960208) (xy 364.065058 -210.937094) (xy 364.071662 -210.932268) (xy 364.077504 -210.92795)
			(xy 364.098332 -210.903058) (xy 364.102142 -210.896962) (xy 364.106206 -210.887056) (xy 364.107222 -210.882992)
			(xy 364.107476 -210.88096) (xy 364.112567 -210.854767) (xy 364.129055 -210.804021) (xy 364.152444 -210.756063)
			(xy 364.18228 -210.711826) (xy 364.217981 -210.672171) (xy 364.258854 -210.637871) (xy 364.304101 -210.609592)
			(xy 364.352844 -210.587885) (xy 364.404134 -210.573173) (xy 364.456971 -210.56574) (xy 364.48365 -210.565238)
			(xy 364.510917 -210.565728) (xy 364.564895 -210.573495) (xy 364.617219 -210.588865) (xy 364.666823 -210.611524)
			(xy 364.712697 -210.641011) (xy 364.753909 -210.676726) (xy 364.789619 -210.717943) (xy 364.8191 -210.763821)
			(xy 364.841753 -210.813428) (xy 364.857115 -210.865754) (xy 364.864876 -210.919733) (xy 364.865412 -210.947)
			(xy 364.864948 -210.973651) (xy 364.857534 -211.026435) (xy 364.84285 -211.077674) (xy 364.821182 -211.126373)
			(xy 364.800119 -211.160106) (xy 369.071396 -211.160106) (xy 369.075467 -211.104484) (xy 369.087593 -211.050047)
			(xy 369.107516 -210.997956) (xy 369.134812 -210.949321) (xy 369.168898 -210.905178) (xy 369.209047 -210.866469)
			(xy 369.254405 -210.834018) (xy 369.304005 -210.808517) (xy 369.356789 -210.79051) (xy 369.411632 -210.78038)
			(xy 369.467366 -210.778343) (xy 369.522803 -210.784443) (xy 369.57676 -210.798549) (xy 369.628089 -210.820361)
			(xy 369.675695 -210.849415) (xy 369.718563 -210.88509) (xy 369.75578 -210.926627) (xy 369.786553 -210.97314)
			(xy 369.810225 -211.023637) (xy 369.826293 -211.077044) (xy 369.834413 -211.13222) (xy 369.834922 -211.160106)
			(xy 369.834413 -211.187992) (xy 369.826293 -211.243168) (xy 369.810225 -211.296575) (xy 369.786553 -211.347072)
			(xy 369.75578 -211.393585) (xy 369.718563 -211.435122) (xy 369.675695 -211.470797) (xy 369.628089 -211.499851)
			(xy 369.57676 -211.521663) (xy 369.522803 -211.535769) (xy 369.467366 -211.541869) (xy 369.411632 -211.539832)
			(xy 369.356789 -211.529702) (xy 369.304005 -211.511695) (xy 369.254405 -211.486194) (xy 369.209047 -211.453743)
			(xy 369.168898 -211.415034) (xy 369.134812 -211.370891) (xy 369.107516 -211.322256) (xy 369.087593 -211.270165)
			(xy 369.075467 -211.215728) (xy 369.071396 -211.160106) (xy 364.800119 -211.160106) (xy 364.792951 -211.171585)
			(xy 364.758706 -211.21243) (xy 364.719112 -211.248116) (xy 364.67494 -211.277947) (xy 364.627047 -211.301344)
			(xy 364.576366 -211.317852) (xy 364.550198 -211.32292) (xy 364.54969 -211.32292) (xy 364.542324 -211.324444)
			(xy 364.53699 -211.32673) (xy 364.526068 -211.333588) (xy 364.50016 -211.35467) (xy 364.495588 -211.364068)
			(xy 364.490254 -211.37372) (xy 364.48619 -211.38769) (xy 364.485936 -211.388452) (xy 364.484412 -211.39277)
			(xy 364.469934 -211.436204) (xy 364.466968 -211.448542) (xy 364.472161 -211.473347) (xy 364.47984 -211.483448)
			(xy 364.58271 -211.586318) (xy 364.590584 -211.592668) (xy 364.595918 -211.596224) (xy 364.60303 -211.59851)
			(xy 364.603284 -211.59851) (xy 364.628854 -211.606955) (xy 364.677509 -211.630029) (xy 364.722438 -211.659712)
			(xy 364.76275 -211.695414) (xy 364.797645 -211.736427) (xy 364.82643 -211.781936) (xy 364.848534 -211.831039)
			(xy 364.863519 -211.882761) (xy 364.871086 -211.936076) (xy 364.871508 -211.963) (xy 367.409982 -211.963)
			(xy 367.414053 -211.907378) (xy 367.426179 -211.852941) (xy 367.446102 -211.80085) (xy 367.473398 -211.752215)
			(xy 367.507484 -211.708072) (xy 367.547633 -211.669363) (xy 367.592991 -211.636912) (xy 367.642591 -211.611411)
			(xy 367.695375 -211.593404) (xy 367.750218 -211.583274) (xy 367.805952 -211.581237) (xy 367.861389 -211.587337)
			(xy 367.915346 -211.601443) (xy 367.966675 -211.623255) (xy 368.014281 -211.652309) (xy 368.057149 -211.687984)
			(xy 368.094366 -211.729521) (xy 368.125139 -211.776034) (xy 368.141105 -211.810092) (xy 378.849634 -211.810092)
			(xy 378.853705 -211.75447) (xy 378.865831 -211.700033) (xy 378.885754 -211.647942) (xy 378.91305 -211.599307)
			(xy 378.947136 -211.555164) (xy 378.987285 -211.516455) (xy 379.032643 -211.484004) (xy 379.082243 -211.458503)
			(xy 379.135027 -211.440496) (xy 379.18987 -211.430366) (xy 379.245604 -211.428329) (xy 379.301041 -211.434429)
			(xy 379.354998 -211.448535) (xy 379.406327 -211.470347) (xy 379.453933 -211.499401) (xy 379.496801 -211.535076)
			(xy 379.534018 -211.576613) (xy 379.564791 -211.623126) (xy 379.588463 -211.673623) (xy 379.599107 -211.709)
			(xy 383.29184 -211.709) (xy 383.295911 -211.653378) (xy 383.308037 -211.598941) (xy 383.32796 -211.54685)
			(xy 383.355256 -211.498215) (xy 383.389342 -211.454072) (xy 383.429491 -211.415363) (xy 383.474849 -211.382912)
			(xy 383.524449 -211.357411) (xy 383.577233 -211.339404) (xy 383.632076 -211.329274) (xy 383.68781 -211.327237)
			(xy 383.743247 -211.333337) (xy 383.797204 -211.347443) (xy 383.848533 -211.369255) (xy 383.896139 -211.398309)
			(xy 383.939007 -211.433984) (xy 383.976224 -211.475521) (xy 384.006997 -211.522034) (xy 384.030669 -211.572531)
			(xy 384.046737 -211.625938) (xy 384.054857 -211.681114) (xy 384.055366 -211.709) (xy 384.054857 -211.736886)
			(xy 384.046737 -211.792062) (xy 384.030669 -211.845469) (xy 384.006997 -211.895966) (xy 383.976224 -211.942479)
			(xy 383.939007 -211.984016) (xy 383.896139 -212.019691) (xy 383.848533 -212.048745) (xy 383.797204 -212.070557)
			(xy 383.743247 -212.084663) (xy 383.68781 -212.090763) (xy 383.632076 -212.088726) (xy 383.577233 -212.078596)
			(xy 383.524449 -212.060589) (xy 383.474849 -212.035088) (xy 383.429491 -212.002637) (xy 383.389342 -211.963928)
			(xy 383.355256 -211.919785) (xy 383.32796 -211.87115) (xy 383.308037 -211.819059) (xy 383.295911 -211.764622)
			(xy 383.29184 -211.709) (xy 379.599107 -211.709) (xy 379.604531 -211.72703) (xy 379.612651 -211.782206)
			(xy 379.61316 -211.810092) (xy 379.612651 -211.837978) (xy 379.604531 -211.893154) (xy 379.588463 -211.946561)
			(xy 379.564791 -211.997058) (xy 379.534018 -212.043571) (xy 379.496801 -212.085108) (xy 379.453933 -212.120783)
			(xy 379.406327 -212.149837) (xy 379.354998 -212.171649) (xy 379.301041 -212.185755) (xy 379.245604 -212.191855)
			(xy 379.18987 -212.189818) (xy 379.135027 -212.179688) (xy 379.082243 -212.161681) (xy 379.032643 -212.13618)
			(xy 378.987285 -212.103729) (xy 378.947136 -212.06502) (xy 378.91305 -212.020877) (xy 378.885754 -211.972242)
			(xy 378.865831 -211.920151) (xy 378.853705 -211.865714) (xy 378.849634 -211.810092) (xy 368.141105 -211.810092)
			(xy 368.148811 -211.826531) (xy 368.164879 -211.879938) (xy 368.172999 -211.935114) (xy 368.173508 -211.963)
			(xy 368.172999 -211.990886) (xy 368.164879 -212.046062) (xy 368.148811 -212.099469) (xy 368.125139 -212.149966)
			(xy 368.094366 -212.196479) (xy 368.057149 -212.238016) (xy 368.014281 -212.273691) (xy 367.966675 -212.302745)
			(xy 367.915346 -212.324557) (xy 367.861389 -212.338663) (xy 367.805952 -212.344763) (xy 367.750218 -212.342726)
			(xy 367.695375 -212.332596) (xy 367.642591 -212.314589) (xy 367.592991 -212.289088) (xy 367.547633 -212.256637)
			(xy 367.507484 -212.217928) (xy 367.473398 -212.173785) (xy 367.446102 -212.12515) (xy 367.426179 -212.073059)
			(xy 367.414053 -212.018622) (xy 367.409982 -211.963) (xy 364.871508 -211.963) (xy 364.871022 -211.990251)
			(xy 364.863266 -212.044199) (xy 364.847911 -212.096494) (xy 364.825269 -212.146071) (xy 364.795803 -212.191921)
			(xy 364.760112 -212.233112) (xy 364.718921 -212.268803) (xy 364.673071 -212.298269) (xy 364.623494 -212.320911)
			(xy 364.571199 -212.336266) (xy 364.517251 -212.344022) (xy 364.49 -212.344508) (xy 364.49 -212.344762)
			(xy 364.463054 -212.344298) (xy 364.409698 -212.336715) (xy 364.35794 -212.3217) (xy 364.30881 -212.299551)
			(xy 364.263285 -212.27071) (xy 364.222271 -212.23575) (xy 364.186585 -212.195366) (xy 364.156936 -212.150363)
			(xy 364.133914 -212.101636) (xy 364.12551 -212.07603) (xy 364.123478 -212.069426) (xy 364.120176 -212.064346)
			(xy 364.115604 -212.057996) (xy 363.155738 -211.09813) (xy 363.149642 -211.09178) (xy 363.073696 -211.015834)
			(xy 363.073188 -211.015326) (xy 363.06633 -211.008468) (xy 363.06252 -210.999324) (xy 363.060745 -210.994696)
			(xy 363.058822 -210.984975) (xy 363.05871 -210.98002) (xy 363.05871 -210.87207) (xy 363.058456 -210.863434)
			(xy 363.058456 -210.332574) (xy 363.057406 -210.324911) (xy 363.051321 -210.310698) (xy 363.046518 -210.304634)
			(xy 362.983272 -210.241388) (xy 362.904532 -210.162394) (xy 362.900937 -210.159121) (xy 362.892753 -210.153874)
			(xy 362.888276 -210.15198) (xy 362.87964 -210.148424) (xy 362.866686 -210.148424) (xy 362.788708 -210.152742)
			(xy 362.784086 -210.153285) (xy 362.775136 -210.155835) (xy 362.770928 -210.157822) (xy 362.761784 -210.162394)
			(xy 362.754672 -210.171284) (xy 362.735795 -210.193688) (xy 362.692395 -210.233039) (xy 362.643498 -210.265304)
			(xy 362.590249 -210.289728) (xy 362.533896 -210.305738) (xy 362.47576 -210.312958) (xy 362.417203 -210.31122)
			(xy 362.359597 -210.300565) (xy 362.331762 -210.291426) (xy 362.330492 -210.290918) (xy 362.303308 -210.280707)
			(xy 362.252148 -210.253239) (xy 362.205743 -210.218334) (xy 362.165165 -210.176798) (xy 362.131351 -210.129592)
			(xy 362.105083 -210.077805) (xy 362.086968 -210.022636) (xy 362.077425 -209.965358) (xy 362.076492 -209.936334)
			(xy 362.076492 -209.929984) (xy 362.077036 -209.901989) (xy 362.085319 -209.846615) (xy 362.101604 -209.793044)
			(xy 362.125539 -209.742427) (xy 362.156612 -209.695849) (xy 362.194156 -209.654311) (xy 362.21543 -209.636106)
			(xy 362.217462 -209.634582) (xy 362.22178 -209.630264) (xy 362.22798 -209.623451) (xy 362.23552 -209.606657)
			(xy 362.236512 -209.597498) (xy 362.239052 -209.554572) (xy 362.239052 -209.554064) (xy 362.240576 -209.530188)
			(xy 362.240576 -209.520028) (xy 362.24036 -209.513218) (xy 362.236757 -209.500084) (xy 362.233464 -209.49412)
			(xy 362.228384 -209.486246) (xy 356.4636 -203.721462) (xy 356.45987 -203.717941) (xy 356.451295 -203.712311)
			(xy 356.446582 -203.710286) (xy 356.437946 -203.70673) (xy 356.423976 -203.70673) (xy 356.41396 -203.707154)
			(xy 356.395457 -203.71483) (xy 356.381299 -203.729002) (xy 356.373644 -203.747514) (xy 356.373176 -203.75753)
			(xy 356.373176 -205.784196) (xy 356.372922 -205.798166) (xy 356.386384 -205.82128) (xy 356.394766 -205.831948)
			(xy 356.399084 -205.836012) (xy 356.404672 -205.839314) (xy 356.428792 -205.853817) (xy 356.472872 -205.888807)
			(xy 356.511335 -205.929892) (xy 356.543347 -205.97618) (xy 356.568212 -206.026669) (xy 356.585392 -206.080262)
			(xy 356.594514 -206.135797) (xy 356.595426 -206.163926) (xy 356.595426 -206.164434) (xy 356.595567 -206.176118)
			(xy 356.864664 -206.176118) (xy 356.868735 -206.120496) (xy 356.880861 -206.066059) (xy 356.900784 -206.013968)
			(xy 356.92808 -205.965333) (xy 356.962166 -205.92119) (xy 357.002315 -205.882481) (xy 357.047673 -205.85003)
			(xy 357.097273 -205.824529) (xy 357.150057 -205.806522) (xy 357.2049 -205.796392) (xy 357.260634 -205.794355)
			(xy 357.316071 -205.800455) (xy 357.370028 -205.814561) (xy 357.421357 -205.836373) (xy 357.468963 -205.865427)
			(xy 357.511831 -205.901102) (xy 357.549048 -205.942639) (xy 357.579821 -205.989152) (xy 357.603493 -206.039649)
			(xy 357.619561 -206.093056) (xy 357.627681 -206.148232) (xy 357.62819 -206.176118) (xy 357.627681 -206.204004)
			(xy 357.619561 -206.25918) (xy 357.603493 -206.312587) (xy 357.579821 -206.363084) (xy 357.549048 -206.409597)
			(xy 357.511831 -206.451134) (xy 357.468963 -206.486809) (xy 357.421357 -206.515863) (xy 357.370028 -206.537675)
			(xy 357.316071 -206.551781) (xy 357.260634 -206.557881) (xy 357.2049 -206.555844) (xy 357.150057 -206.545714)
			(xy 357.097273 -206.527707) (xy 357.047673 -206.502206) (xy 357.002315 -206.469755) (xy 356.962166 -206.431046)
			(xy 356.92808 -206.386903) (xy 356.900784 -206.338268) (xy 356.880861 -206.286177) (xy 356.868735 -206.23174)
			(xy 356.864664 -206.176118) (xy 356.595567 -206.176118) (xy 356.595776 -206.193359) (xy 356.5888 -206.250781)
			(xy 356.57324 -206.306492) (xy 356.549451 -206.359218) (xy 356.51798 -206.407752) (xy 356.479546 -206.450981)
			(xy 356.435029 -206.487916) (xy 356.410514 -206.50327) (xy 356.404926 -206.506572) (xy 356.4001 -206.511398)
			(xy 356.39502 -206.516224) (xy 356.380034 -206.542386) (xy 356.378065 -206.545847) (xy 356.375128 -206.553248)
			(xy 356.374192 -206.557118) (xy 356.373176 -206.567024) (xy 356.373176 -208.258918) (xy 356.59009 -208.258918)
			(xy 356.594161 -208.203296) (xy 356.606287 -208.148859) (xy 356.62621 -208.096768) (xy 356.653506 -208.048133)
			(xy 356.687592 -208.00399) (xy 356.727741 -207.965281) (xy 356.773099 -207.93283) (xy 356.822699 -207.907329)
			(xy 356.875483 -207.889322) (xy 356.930326 -207.879192) (xy 356.98606 -207.877155) (xy 357.041497 -207.883255)
			(xy 357.095454 -207.897361) (xy 357.146783 -207.919173) (xy 357.194389 -207.948227) (xy 357.237257 -207.983902)
			(xy 357.274474 -208.025439) (xy 357.305247 -208.071952) (xy 357.328919 -208.122449) (xy 357.344987 -208.175856)
			(xy 357.353107 -208.231032) (xy 357.353616 -208.258918) (xy 357.353107 -208.286804) (xy 357.344987 -208.34198)
			(xy 357.328919 -208.395387) (xy 357.305247 -208.445884) (xy 357.274474 -208.492397) (xy 357.237257 -208.533934)
			(xy 357.194389 -208.569609) (xy 357.146783 -208.598663) (xy 357.095454 -208.620475) (xy 357.041497 -208.634581)
			(xy 356.98606 -208.640681) (xy 356.930326 -208.638644) (xy 356.875483 -208.628514) (xy 356.822699 -208.610507)
			(xy 356.773099 -208.585006) (xy 356.727741 -208.552555) (xy 356.687592 -208.513846) (xy 356.653506 -208.469703)
			(xy 356.62621 -208.421068) (xy 356.606287 -208.368977) (xy 356.594161 -208.31454) (xy 356.59009 -208.258918)
			(xy 356.373176 -208.258918) (xy 356.373176 -209.279236) (xy 358.634028 -209.279236) (xy 358.638099 -209.223614)
			(xy 358.650225 -209.169177) (xy 358.670148 -209.117086) (xy 358.697444 -209.068451) (xy 358.73153 -209.024308)
			(xy 358.771679 -208.985599) (xy 358.817037 -208.953148) (xy 358.866637 -208.927647) (xy 358.919421 -208.90964)
			(xy 358.974264 -208.89951) (xy 359.029998 -208.897473) (xy 359.085435 -208.903573) (xy 359.139392 -208.917679)
			(xy 359.190721 -208.939491) (xy 359.238327 -208.968545) (xy 359.281195 -209.00422) (xy 359.318412 -209.045757)
			(xy 359.349185 -209.09227) (xy 359.372857 -209.142767) (xy 359.388925 -209.196174) (xy 359.397045 -209.25135)
			(xy 359.397554 -209.279236) (xy 359.397045 -209.307122) (xy 359.388925 -209.362298) (xy 359.372857 -209.415705)
			(xy 359.349185 -209.466202) (xy 359.318412 -209.512715) (xy 359.281195 -209.554252) (xy 359.238327 -209.589927)
			(xy 359.190721 -209.618981) (xy 359.139392 -209.640793) (xy 359.085435 -209.654899) (xy 359.029998 -209.660999)
			(xy 358.974264 -209.658962) (xy 358.919421 -209.648832) (xy 358.866637 -209.630825) (xy 358.817037 -209.605324)
			(xy 358.771679 -209.572873) (xy 358.73153 -209.534164) (xy 358.697444 -209.490021) (xy 358.670148 -209.441386)
			(xy 358.650225 -209.389295) (xy 358.638099 -209.334858) (xy 358.634028 -209.279236) (xy 356.373176 -209.279236)
			(xy 356.373176 -210.312) (xy 358.646982 -210.312) (xy 358.651053 -210.256378) (xy 358.663179 -210.201941)
			(xy 358.683102 -210.14985) (xy 358.710398 -210.101215) (xy 358.744484 -210.057072) (xy 358.784633 -210.018363)
			(xy 358.829991 -209.985912) (xy 358.879591 -209.960411) (xy 358.932375 -209.942404) (xy 358.987218 -209.932274)
			(xy 359.042952 -209.930237) (xy 359.098389 -209.936337) (xy 359.152346 -209.950443) (xy 359.203675 -209.972255)
			(xy 359.251281 -210.001309) (xy 359.294149 -210.036984) (xy 359.331366 -210.078521) (xy 359.362139 -210.125034)
			(xy 359.385811 -210.175531) (xy 359.401879 -210.228938) (xy 359.409999 -210.284114) (xy 359.410508 -210.312)
			(xy 359.409999 -210.339886) (xy 359.401879 -210.395062) (xy 359.385811 -210.448469) (xy 359.362139 -210.498966)
			(xy 359.331366 -210.545479) (xy 359.294149 -210.587016) (xy 359.251281 -210.622691) (xy 359.203675 -210.651745)
			(xy 359.152346 -210.673557) (xy 359.098389 -210.687663) (xy 359.042952 -210.693763) (xy 358.987218 -210.691726)
			(xy 358.932375 -210.681596) (xy 358.879591 -210.663589) (xy 358.829991 -210.638088) (xy 358.784633 -210.605637)
			(xy 358.744484 -210.566928) (xy 358.710398 -210.522785) (xy 358.683102 -210.47415) (xy 358.663179 -210.422059)
			(xy 358.651053 -210.367622) (xy 358.646982 -210.312) (xy 356.373176 -210.312) (xy 356.373176 -211.328)
			(xy 358.646982 -211.328) (xy 358.651053 -211.272378) (xy 358.663179 -211.217941) (xy 358.683102 -211.16585)
			(xy 358.710398 -211.117215) (xy 358.744484 -211.073072) (xy 358.784633 -211.034363) (xy 358.829991 -211.001912)
			(xy 358.879591 -210.976411) (xy 358.932375 -210.958404) (xy 358.987218 -210.948274) (xy 359.042952 -210.946237)
			(xy 359.049886 -210.947) (xy 362.075982 -210.947) (xy 362.080053 -210.891378) (xy 362.092179 -210.836941)
			(xy 362.112102 -210.78485) (xy 362.139398 -210.736215) (xy 362.173484 -210.692072) (xy 362.213633 -210.653363)
			(xy 362.258991 -210.620912) (xy 362.308591 -210.595411) (xy 362.361375 -210.577404) (xy 362.416218 -210.567274)
			(xy 362.471952 -210.565237) (xy 362.527389 -210.571337) (xy 362.581346 -210.585443) (xy 362.632675 -210.607255)
			(xy 362.680281 -210.636309) (xy 362.723149 -210.671984) (xy 362.760366 -210.713521) (xy 362.791139 -210.760034)
			(xy 362.814811 -210.810531) (xy 362.830879 -210.863938) (xy 362.838999 -210.919114) (xy 362.839508 -210.947)
			(xy 362.838999 -210.974886) (xy 362.830879 -211.030062) (xy 362.814811 -211.083469) (xy 362.791139 -211.133966)
			(xy 362.760366 -211.180479) (xy 362.723149 -211.222016) (xy 362.680281 -211.257691) (xy 362.632675 -211.286745)
			(xy 362.581346 -211.308557) (xy 362.527389 -211.322663) (xy 362.471952 -211.328763) (xy 362.416218 -211.326726)
			(xy 362.361375 -211.316596) (xy 362.308591 -211.298589) (xy 362.258991 -211.273088) (xy 362.213633 -211.240637)
			(xy 362.173484 -211.201928) (xy 362.139398 -211.157785) (xy 362.112102 -211.10915) (xy 362.092179 -211.057059)
			(xy 362.080053 -211.002622) (xy 362.075982 -210.947) (xy 359.049886 -210.947) (xy 359.098389 -210.952337)
			(xy 359.152346 -210.966443) (xy 359.203675 -210.988255) (xy 359.251281 -211.017309) (xy 359.294149 -211.052984)
			(xy 359.331366 -211.094521) (xy 359.362139 -211.141034) (xy 359.385811 -211.191531) (xy 359.401879 -211.244938)
			(xy 359.409999 -211.300114) (xy 359.410508 -211.328) (xy 359.409999 -211.355886) (xy 359.401879 -211.411062)
			(xy 359.385811 -211.464469) (xy 359.362139 -211.514966) (xy 359.331366 -211.561479) (xy 359.294149 -211.603016)
			(xy 359.251281 -211.638691) (xy 359.203675 -211.667745) (xy 359.152346 -211.689557) (xy 359.098389 -211.703663)
			(xy 359.042952 -211.709763) (xy 358.987218 -211.707726) (xy 358.932375 -211.697596) (xy 358.879591 -211.679589)
			(xy 358.829991 -211.654088) (xy 358.784633 -211.621637) (xy 358.744484 -211.582928) (xy 358.710398 -211.538785)
			(xy 358.683102 -211.49015) (xy 358.663179 -211.438059) (xy 358.651053 -211.383622) (xy 358.646982 -211.328)
			(xy 356.373176 -211.328) (xy 356.373176 -212.344) (xy 356.614982 -212.344) (xy 356.619053 -212.288378)
			(xy 356.631179 -212.233941) (xy 356.651102 -212.18185) (xy 356.678398 -212.133215) (xy 356.712484 -212.089072)
			(xy 356.752633 -212.050363) (xy 356.797991 -212.017912) (xy 356.847591 -211.992411) (xy 356.900375 -211.974404)
			(xy 356.955218 -211.964274) (xy 357.010952 -211.962237) (xy 357.066389 -211.968337) (xy 357.120346 -211.982443)
			(xy 357.171675 -212.004255) (xy 357.219281 -212.033309) (xy 357.262149 -212.068984) (xy 357.299366 -212.110521)
			(xy 357.330139 -212.157034) (xy 357.353811 -212.207531) (xy 357.369879 -212.260938) (xy 357.377999 -212.316114)
			(xy 357.378508 -212.344) (xy 358.646982 -212.344) (xy 358.651053 -212.288378) (xy 358.663179 -212.233941)
			(xy 358.683102 -212.18185) (xy 358.710398 -212.133215) (xy 358.744484 -212.089072) (xy 358.784633 -212.050363)
			(xy 358.829991 -212.017912) (xy 358.879591 -211.992411) (xy 358.932375 -211.974404) (xy 358.987218 -211.964274)
			(xy 359.042952 -211.962237) (xy 359.098389 -211.968337) (xy 359.152346 -211.982443) (xy 359.203675 -212.004255)
			(xy 359.251281 -212.033309) (xy 359.294149 -212.068984) (xy 359.331366 -212.110521) (xy 359.362139 -212.157034)
			(xy 359.385811 -212.207531) (xy 359.401879 -212.260938) (xy 359.409999 -212.316114) (xy 359.410508 -212.344)
			(xy 359.409999 -212.371886) (xy 359.401879 -212.427062) (xy 359.391946 -212.460078) (xy 368.583208 -212.460078)
			(xy 368.587279 -212.404456) (xy 368.599405 -212.350019) (xy 368.619328 -212.297928) (xy 368.646624 -212.249293)
			(xy 368.68071 -212.20515) (xy 368.720859 -212.166441) (xy 368.766217 -212.13399) (xy 368.815817 -212.108489)
			(xy 368.868601 -212.090482) (xy 368.923444 -212.080352) (xy 368.979178 -212.078315) (xy 369.034615 -212.084415)
			(xy 369.088572 -212.098521) (xy 369.139901 -212.120333) (xy 369.187507 -212.149387) (xy 369.230375 -212.185062)
			(xy 369.267592 -212.226599) (xy 369.298365 -212.273112) (xy 369.322037 -212.323609) (xy 369.338105 -212.377016)
			(xy 369.346225 -212.432192) (xy 369.346734 -212.460078) (xy 377.30506 -212.460078) (xy 377.309131 -212.404456)
			(xy 377.321257 -212.350019) (xy 377.34118 -212.297928) (xy 377.368476 -212.249293) (xy 377.402562 -212.20515)
			(xy 377.442711 -212.166441) (xy 377.488069 -212.13399) (xy 377.537669 -212.108489) (xy 377.590453 -212.090482)
			(xy 377.645296 -212.080352) (xy 377.70103 -212.078315) (xy 377.756467 -212.084415) (xy 377.810424 -212.098521)
			(xy 377.861753 -212.120333) (xy 377.909359 -212.149387) (xy 377.952227 -212.185062) (xy 377.989444 -212.226599)
			(xy 378.020217 -212.273112) (xy 378.043889 -212.323609) (xy 378.059957 -212.377016) (xy 378.068077 -212.432192)
			(xy 378.068586 -212.460078) (xy 378.068077 -212.487964) (xy 378.059957 -212.54314) (xy 378.043889 -212.596547)
			(xy 378.020217 -212.647044) (xy 377.998217 -212.680296) (xy 378.744732 -212.680296) (xy 378.748803 -212.624674)
			(xy 378.760929 -212.570237) (xy 378.780852 -212.518146) (xy 378.808148 -212.469511) (xy 378.842234 -212.425368)
			(xy 378.882383 -212.386659) (xy 378.927741 -212.354208) (xy 378.977341 -212.328707) (xy 379.030125 -212.3107)
			(xy 379.084968 -212.30057) (xy 379.140702 -212.298533) (xy 379.196139 -212.304633) (xy 379.250096 -212.318739)
			(xy 379.301425 -212.340551) (xy 379.349031 -212.369605) (xy 379.391899 -212.40528) (xy 379.429116 -212.446817)
			(xy 379.459889 -212.49333) (xy 379.483561 -212.543827) (xy 379.499629 -212.597234) (xy 379.507749 -212.65241)
			(xy 379.508258 -212.680296) (xy 379.507749 -212.708182) (xy 379.499629 -212.763358) (xy 379.483561 -212.816765)
			(xy 379.459889 -212.867262) (xy 379.429116 -212.913775) (xy 379.391899 -212.955312) (xy 379.349031 -212.990987)
			(xy 379.301425 -213.020041) (xy 379.250096 -213.041853) (xy 379.196139 -213.055959) (xy 379.140702 -213.062059)
			(xy 379.084968 -213.060022) (xy 379.030125 -213.049892) (xy 378.977341 -213.031885) (xy 378.927741 -213.006384)
			(xy 378.882383 -212.973933) (xy 378.842234 -212.935224) (xy 378.808148 -212.891081) (xy 378.780852 -212.842446)
			(xy 378.760929 -212.790355) (xy 378.748803 -212.735918) (xy 378.744732 -212.680296) (xy 377.998217 -212.680296)
			(xy 377.989444 -212.693557) (xy 377.952227 -212.735094) (xy 377.909359 -212.770769) (xy 377.861753 -212.799823)
			(xy 377.810424 -212.821635) (xy 377.756467 -212.835741) (xy 377.70103 -212.841841) (xy 377.645296 -212.839804)
			(xy 377.590453 -212.829674) (xy 377.537669 -212.811667) (xy 377.488069 -212.786166) (xy 377.442711 -212.753715)
			(xy 377.402562 -212.715006) (xy 377.368476 -212.670863) (xy 377.34118 -212.622228) (xy 377.321257 -212.570137)
			(xy 377.309131 -212.5157) (xy 377.30506 -212.460078) (xy 369.346734 -212.460078) (xy 369.346225 -212.487964)
			(xy 369.338105 -212.54314) (xy 369.322037 -212.596547) (xy 369.298365 -212.647044) (xy 369.267592 -212.693557)
			(xy 369.230375 -212.735094) (xy 369.187507 -212.770769) (xy 369.139901 -212.799823) (xy 369.088572 -212.821635)
			(xy 369.034615 -212.835741) (xy 368.979178 -212.841841) (xy 368.923444 -212.839804) (xy 368.868601 -212.829674)
			(xy 368.815817 -212.811667) (xy 368.766217 -212.786166) (xy 368.720859 -212.753715) (xy 368.68071 -212.715006)
			(xy 368.646624 -212.670863) (xy 368.619328 -212.622228) (xy 368.599405 -212.570137) (xy 368.587279 -212.5157)
			(xy 368.583208 -212.460078) (xy 359.391946 -212.460078) (xy 359.385811 -212.480469) (xy 359.362139 -212.530966)
			(xy 359.331366 -212.577479) (xy 359.294149 -212.619016) (xy 359.251281 -212.654691) (xy 359.203675 -212.683745)
			(xy 359.152346 -212.705557) (xy 359.098389 -212.719663) (xy 359.042952 -212.725763) (xy 358.987218 -212.723726)
			(xy 358.932375 -212.713596) (xy 358.879591 -212.695589) (xy 358.829991 -212.670088) (xy 358.784633 -212.637637)
			(xy 358.744484 -212.598928) (xy 358.710398 -212.554785) (xy 358.683102 -212.50615) (xy 358.663179 -212.454059)
			(xy 358.651053 -212.399622) (xy 358.646982 -212.344) (xy 357.378508 -212.344) (xy 357.377999 -212.371886)
			(xy 357.369879 -212.427062) (xy 357.353811 -212.480469) (xy 357.330139 -212.530966) (xy 357.299366 -212.577479)
			(xy 357.262149 -212.619016) (xy 357.219281 -212.654691) (xy 357.171675 -212.683745) (xy 357.120346 -212.705557)
			(xy 357.066389 -212.719663) (xy 357.010952 -212.725763) (xy 356.955218 -212.723726) (xy 356.900375 -212.713596)
			(xy 356.847591 -212.695589) (xy 356.797991 -212.670088) (xy 356.752633 -212.637637) (xy 356.712484 -212.598928)
			(xy 356.678398 -212.554785) (xy 356.651102 -212.50615) (xy 356.631179 -212.454059) (xy 356.619053 -212.399622)
			(xy 356.614982 -212.344) (xy 356.373176 -212.344) (xy 356.373176 -213.055962) (xy 356.373176 -213.05901)
			(xy 356.373504 -213.062645) (xy 356.375038 -213.069782) (xy 356.376224 -213.073234) (xy 356.377748 -213.077044)
			(xy 356.396539 -213.095556) (xy 356.429476 -213.136759) (xy 356.456571 -213.182017) (xy 356.477333 -213.230509)
			(xy 356.491382 -213.281353) (xy 356.498464 -213.333625) (xy 356.498906 -213.36) (xy 358.646982 -213.36)
			(xy 358.651053 -213.304378) (xy 358.663179 -213.249941) (xy 358.683102 -213.19785) (xy 358.710398 -213.149215)
			(xy 358.744484 -213.105072) (xy 358.784633 -213.066363) (xy 358.829991 -213.033912) (xy 358.879591 -213.008411)
			(xy 358.932375 -212.990404) (xy 358.987218 -212.980274) (xy 359.042952 -212.978237) (xy 359.049886 -212.979)
			(xy 362.075982 -212.979) (xy 362.080053 -212.923378) (xy 362.092179 -212.868941) (xy 362.112102 -212.81685)
			(xy 362.139398 -212.768215) (xy 362.173484 -212.724072) (xy 362.213633 -212.685363) (xy 362.258991 -212.652912)
			(xy 362.308591 -212.627411) (xy 362.361375 -212.609404) (xy 362.416218 -212.599274) (xy 362.471952 -212.597237)
			(xy 362.527389 -212.603337) (xy 362.581346 -212.617443) (xy 362.632675 -212.639255) (xy 362.680281 -212.668309)
			(xy 362.723149 -212.703984) (xy 362.760366 -212.745521) (xy 362.791139 -212.792034) (xy 362.814811 -212.842531)
			(xy 362.830879 -212.895938) (xy 362.838999 -212.951114) (xy 362.839508 -212.979) (xy 362.838999 -213.006886)
			(xy 362.830879 -213.062062) (xy 362.814811 -213.115469) (xy 362.791139 -213.165966) (xy 362.760366 -213.212479)
			(xy 362.723149 -213.254016) (xy 362.680281 -213.289691) (xy 362.632675 -213.318745) (xy 362.581346 -213.340557)
			(xy 362.527389 -213.354663) (xy 362.471952 -213.360763) (xy 362.416218 -213.358726) (xy 362.361375 -213.348596)
			(xy 362.308591 -213.330589) (xy 362.258991 -213.305088) (xy 362.213633 -213.272637) (xy 362.173484 -213.233928)
			(xy 362.139398 -213.189785) (xy 362.112102 -213.14115) (xy 362.092179 -213.089059) (xy 362.080053 -213.034622)
			(xy 362.075982 -212.979) (xy 359.049886 -212.979) (xy 359.098389 -212.984337) (xy 359.152346 -212.998443)
			(xy 359.203675 -213.020255) (xy 359.251281 -213.049309) (xy 359.294149 -213.084984) (xy 359.331366 -213.126521)
			(xy 359.362139 -213.173034) (xy 359.385811 -213.223531) (xy 359.401879 -213.276938) (xy 359.409999 -213.332114)
			(xy 359.410508 -213.36) (xy 359.409999 -213.387886) (xy 359.401879 -213.443062) (xy 359.385811 -213.496469)
			(xy 359.362139 -213.546966) (xy 359.331366 -213.593479) (xy 359.294149 -213.635016) (xy 359.251281 -213.670691)
			(xy 359.203675 -213.699745) (xy 359.152346 -213.721557) (xy 359.098389 -213.735663) (xy 359.042952 -213.741763)
			(xy 358.987218 -213.739726) (xy 358.932375 -213.729596) (xy 358.879591 -213.711589) (xy 358.829991 -213.686088)
			(xy 358.784633 -213.653637) (xy 358.744484 -213.614928) (xy 358.710398 -213.570785) (xy 358.683102 -213.52215)
			(xy 358.663179 -213.470059) (xy 358.651053 -213.415622) (xy 358.646982 -213.36) (xy 356.498906 -213.36)
			(xy 356.498478 -213.386315) (xy 356.491418 -213.438469) (xy 356.477426 -213.489204) (xy 356.456755 -213.537605)
			(xy 356.429779 -213.582795) (xy 356.396984 -213.623958) (xy 356.378256 -213.642448) (xy 356.376986 -213.645496)
			(xy 356.373176 -213.654894) (xy 356.373176 -214.376) (xy 356.614982 -214.376) (xy 356.619053 -214.320378)
			(xy 356.631179 -214.265941) (xy 356.651102 -214.21385) (xy 356.678398 -214.165215) (xy 356.712484 -214.121072)
			(xy 356.752633 -214.082363) (xy 356.797991 -214.049912) (xy 356.847591 -214.024411) (xy 356.900375 -214.006404)
			(xy 356.955218 -213.996274) (xy 357.010952 -213.994237) (xy 357.066389 -214.000337) (xy 357.120346 -214.014443)
			(xy 357.171675 -214.036255) (xy 357.219281 -214.065309) (xy 357.262149 -214.100984) (xy 357.299366 -214.142521)
			(xy 357.330139 -214.189034) (xy 357.353811 -214.239531) (xy 357.369879 -214.292938) (xy 357.377999 -214.348114)
			(xy 357.378508 -214.376) (xy 358.646982 -214.376) (xy 358.651053 -214.320378) (xy 358.663179 -214.265941)
			(xy 358.683102 -214.21385) (xy 358.710398 -214.165215) (xy 358.744484 -214.121072) (xy 358.784633 -214.082363)
			(xy 358.829991 -214.049912) (xy 358.879591 -214.024411) (xy 358.932375 -214.006404) (xy 358.987218 -213.996274)
			(xy 359.042952 -213.994237) (xy 359.049886 -213.995) (xy 362.075982 -213.995) (xy 362.080053 -213.939378)
			(xy 362.092179 -213.884941) (xy 362.112102 -213.83285) (xy 362.139398 -213.784215) (xy 362.173484 -213.740072)
			(xy 362.213633 -213.701363) (xy 362.258991 -213.668912) (xy 362.308591 -213.643411) (xy 362.361375 -213.625404)
			(xy 362.416218 -213.615274) (xy 362.471952 -213.613237) (xy 362.527389 -213.619337) (xy 362.581346 -213.633443)
			(xy 362.632675 -213.655255) (xy 362.680281 -213.684309) (xy 362.723149 -213.719984) (xy 362.760366 -213.761521)
			(xy 362.791139 -213.808034) (xy 362.814811 -213.858531) (xy 362.830879 -213.911938) (xy 362.838999 -213.967114)
			(xy 362.83916 -213.97595) (xy 378.439932 -213.97595) (xy 378.444003 -213.920328) (xy 378.456129 -213.865891)
			(xy 378.476052 -213.8138) (xy 378.503348 -213.765165) (xy 378.537434 -213.721022) (xy 378.577583 -213.682313)
			(xy 378.622941 -213.649862) (xy 378.672541 -213.624361) (xy 378.725325 -213.606354) (xy 378.780168 -213.596224)
			(xy 378.835902 -213.594187) (xy 378.891339 -213.600287) (xy 378.945296 -213.614393) (xy 378.996625 -213.636205)
			(xy 379.044231 -213.665259) (xy 379.087099 -213.700934) (xy 379.124316 -213.742471) (xy 379.155089 -213.788984)
			(xy 379.178761 -213.839481) (xy 379.194829 -213.892888) (xy 379.202949 -213.948064) (xy 379.203458 -213.97595)
			(xy 379.202949 -214.003836) (xy 379.194829 -214.059012) (xy 379.178761 -214.112419) (xy 379.155089 -214.162916)
			(xy 379.124316 -214.209429) (xy 379.087099 -214.250966) (xy 379.044231 -214.286641) (xy 378.996625 -214.315695)
			(xy 378.945296 -214.337507) (xy 378.891339 -214.351613) (xy 378.835902 -214.357713) (xy 378.780168 -214.355676)
			(xy 378.725325 -214.345546) (xy 378.672541 -214.327539) (xy 378.622941 -214.302038) (xy 378.577583 -214.269587)
			(xy 378.537434 -214.230878) (xy 378.503348 -214.186735) (xy 378.476052 -214.1381) (xy 378.456129 -214.086009)
			(xy 378.444003 -214.031572) (xy 378.439932 -213.97595) (xy 362.83916 -213.97595) (xy 362.839508 -213.995)
			(xy 362.838999 -214.022886) (xy 362.830879 -214.078062) (xy 362.814811 -214.131469) (xy 362.791139 -214.181966)
			(xy 362.760366 -214.228479) (xy 362.723149 -214.270016) (xy 362.680281 -214.305691) (xy 362.632675 -214.334745)
			(xy 362.581346 -214.356557) (xy 362.527389 -214.370663) (xy 362.471952 -214.376763) (xy 362.416218 -214.374726)
			(xy 362.361375 -214.364596) (xy 362.308591 -214.346589) (xy 362.258991 -214.321088) (xy 362.213633 -214.288637)
			(xy 362.173484 -214.249928) (xy 362.139398 -214.205785) (xy 362.112102 -214.15715) (xy 362.092179 -214.105059)
			(xy 362.080053 -214.050622) (xy 362.075982 -213.995) (xy 359.049886 -213.995) (xy 359.098389 -214.000337)
			(xy 359.152346 -214.014443) (xy 359.203675 -214.036255) (xy 359.251281 -214.065309) (xy 359.294149 -214.100984)
			(xy 359.331366 -214.142521) (xy 359.362139 -214.189034) (xy 359.385811 -214.239531) (xy 359.401879 -214.292938)
			(xy 359.409999 -214.348114) (xy 359.410508 -214.376) (xy 359.409999 -214.403886) (xy 359.401879 -214.459062)
			(xy 359.38866 -214.503) (xy 367.663982 -214.503) (xy 367.668053 -214.447378) (xy 367.680179 -214.392941)
			(xy 367.700102 -214.34085) (xy 367.727398 -214.292215) (xy 367.761484 -214.248072) (xy 367.801633 -214.209363)
			(xy 367.846991 -214.176912) (xy 367.896591 -214.151411) (xy 367.949375 -214.133404) (xy 368.004218 -214.123274)
			(xy 368.059952 -214.121237) (xy 368.115389 -214.127337) (xy 368.169346 -214.141443) (xy 368.220675 -214.163255)
			(xy 368.268281 -214.192309) (xy 368.311149 -214.227984) (xy 368.348366 -214.269521) (xy 368.379139 -214.316034)
			(xy 368.402811 -214.366531) (xy 368.418879 -214.419938) (xy 368.426999 -214.475114) (xy 368.427508 -214.503)
			(xy 368.426999 -214.530886) (xy 368.418879 -214.586062) (xy 368.402811 -214.639469) (xy 368.379139 -214.689966)
			(xy 368.348366 -214.736479) (xy 368.311149 -214.778016) (xy 368.268281 -214.813691) (xy 368.220675 -214.842745)
			(xy 368.169346 -214.864557) (xy 368.115389 -214.878663) (xy 368.059952 -214.884763) (xy 368.004218 -214.882726)
			(xy 367.949375 -214.872596) (xy 367.896591 -214.854589) (xy 367.846991 -214.829088) (xy 367.801633 -214.796637)
			(xy 367.761484 -214.757928) (xy 367.727398 -214.713785) (xy 367.700102 -214.66515) (xy 367.680179 -214.613059)
			(xy 367.668053 -214.558622) (xy 367.663982 -214.503) (xy 359.38866 -214.503) (xy 359.385811 -214.512469)
			(xy 359.362139 -214.562966) (xy 359.331366 -214.609479) (xy 359.294149 -214.651016) (xy 359.251281 -214.686691)
			(xy 359.203675 -214.715745) (xy 359.152346 -214.737557) (xy 359.098389 -214.751663) (xy 359.042952 -214.757763)
			(xy 358.987218 -214.755726) (xy 358.932375 -214.745596) (xy 358.879591 -214.727589) (xy 358.829991 -214.702088)
			(xy 358.784633 -214.669637) (xy 358.744484 -214.630928) (xy 358.710398 -214.586785) (xy 358.683102 -214.53815)
			(xy 358.663179 -214.486059) (xy 358.651053 -214.431622) (xy 358.646982 -214.376) (xy 357.378508 -214.376)
			(xy 357.377999 -214.403886) (xy 357.369879 -214.459062) (xy 357.353811 -214.512469) (xy 357.330139 -214.562966)
			(xy 357.299366 -214.609479) (xy 357.262149 -214.651016) (xy 357.219281 -214.686691) (xy 357.171675 -214.715745)
			(xy 357.120346 -214.737557) (xy 357.066389 -214.751663) (xy 357.010952 -214.757763) (xy 356.955218 -214.755726)
			(xy 356.900375 -214.745596) (xy 356.847591 -214.727589) (xy 356.797991 -214.702088) (xy 356.752633 -214.669637)
			(xy 356.712484 -214.630928) (xy 356.678398 -214.586785) (xy 356.651102 -214.53815) (xy 356.631179 -214.486059)
			(xy 356.619053 -214.431622) (xy 356.614982 -214.376) (xy 356.373176 -214.376) (xy 356.373176 -215.087962)
			(xy 356.373176 -215.09101) (xy 356.373504 -215.094645) (xy 356.375038 -215.101782) (xy 356.376224 -215.105234)
			(xy 356.377748 -215.109044) (xy 356.396539 -215.127556) (xy 356.429476 -215.168759) (xy 356.456571 -215.214017)
			(xy 356.477333 -215.262509) (xy 356.491382 -215.313353) (xy 356.498464 -215.365625) (xy 356.498906 -215.392)
			(xy 358.646982 -215.392) (xy 358.651053 -215.336378) (xy 358.663179 -215.281941) (xy 358.683102 -215.22985)
			(xy 358.710398 -215.181215) (xy 358.744484 -215.137072) (xy 358.784633 -215.098363) (xy 358.829991 -215.065912)
			(xy 358.879591 -215.040411) (xy 358.932375 -215.022404) (xy 358.987218 -215.012274) (xy 359.042952 -215.010237)
			(xy 359.049886 -215.011) (xy 362.075982 -215.011) (xy 362.080053 -214.955378) (xy 362.092179 -214.900941)
			(xy 362.112102 -214.84885) (xy 362.139398 -214.800215) (xy 362.173484 -214.756072) (xy 362.213633 -214.717363)
			(xy 362.258991 -214.684912) (xy 362.308591 -214.659411) (xy 362.361375 -214.641404) (xy 362.416218 -214.631274)
			(xy 362.471952 -214.629237) (xy 362.527389 -214.635337) (xy 362.581346 -214.649443) (xy 362.632675 -214.671255)
			(xy 362.680281 -214.700309) (xy 362.723149 -214.735984) (xy 362.760366 -214.777521) (xy 362.791139 -214.824034)
			(xy 362.814811 -214.874531) (xy 362.830879 -214.927938) (xy 362.838999 -214.983114) (xy 362.839508 -215.011)
			(xy 364.107982 -215.011) (xy 364.112053 -214.955378) (xy 364.124179 -214.900941) (xy 364.144102 -214.84885)
			(xy 364.171398 -214.800215) (xy 364.205484 -214.756072) (xy 364.245633 -214.717363) (xy 364.290991 -214.684912)
			(xy 364.340591 -214.659411) (xy 364.393375 -214.641404) (xy 364.448218 -214.631274) (xy 364.503952 -214.629237)
			(xy 364.559389 -214.635337) (xy 364.613346 -214.649443) (xy 364.664675 -214.671255) (xy 364.712281 -214.700309)
			(xy 364.755149 -214.735984) (xy 364.792366 -214.777521) (xy 364.823139 -214.824034) (xy 364.846811 -214.874531)
			(xy 364.862879 -214.927938) (xy 364.870999 -214.983114) (xy 364.871508 -215.011) (xy 366.139982 -215.011)
			(xy 366.144053 -214.955378) (xy 366.156179 -214.900941) (xy 366.176102 -214.84885) (xy 366.203398 -214.800215)
			(xy 366.237484 -214.756072) (xy 366.277633 -214.717363) (xy 366.322991 -214.684912) (xy 366.372591 -214.659411)
			(xy 366.425375 -214.641404) (xy 366.480218 -214.631274) (xy 366.535952 -214.629237) (xy 366.591389 -214.635337)
			(xy 366.645346 -214.649443) (xy 366.696675 -214.671255) (xy 366.744281 -214.700309) (xy 366.787149 -214.735984)
			(xy 366.824366 -214.777521) (xy 366.855139 -214.824034) (xy 366.878811 -214.874531) (xy 366.894879 -214.927938)
			(xy 366.902999 -214.983114) (xy 366.903508 -215.011) (xy 366.902999 -215.038886) (xy 366.894879 -215.094062)
			(xy 366.878811 -215.147469) (xy 366.855139 -215.197966) (xy 366.824366 -215.244479) (xy 366.787149 -215.286016)
			(xy 366.744281 -215.321691) (xy 366.696675 -215.350745) (xy 366.645346 -215.372557) (xy 366.591389 -215.386663)
			(xy 366.535952 -215.392763) (xy 366.480218 -215.390726) (xy 366.425375 -215.380596) (xy 366.372591 -215.362589)
			(xy 366.322991 -215.337088) (xy 366.277633 -215.304637) (xy 366.237484 -215.265928) (xy 366.203398 -215.221785)
			(xy 366.176102 -215.17315) (xy 366.156179 -215.121059) (xy 366.144053 -215.066622) (xy 366.139982 -215.011)
			(xy 364.871508 -215.011) (xy 364.870999 -215.038886) (xy 364.862879 -215.094062) (xy 364.846811 -215.147469)
			(xy 364.823139 -215.197966) (xy 364.792366 -215.244479) (xy 364.755149 -215.286016) (xy 364.712281 -215.321691)
			(xy 364.664675 -215.350745) (xy 364.613346 -215.372557) (xy 364.559389 -215.386663) (xy 364.503952 -215.392763)
			(xy 364.448218 -215.390726) (xy 364.393375 -215.380596) (xy 364.340591 -215.362589) (xy 364.290991 -215.337088)
			(xy 364.245633 -215.304637) (xy 364.205484 -215.265928) (xy 364.171398 -215.221785) (xy 364.144102 -215.17315)
			(xy 364.124179 -215.121059) (xy 364.112053 -215.066622) (xy 364.107982 -215.011) (xy 362.839508 -215.011)
			(xy 362.838999 -215.038886) (xy 362.830879 -215.094062) (xy 362.814811 -215.147469) (xy 362.791139 -215.197966)
			(xy 362.760366 -215.244479) (xy 362.723149 -215.286016) (xy 362.680281 -215.321691) (xy 362.632675 -215.350745)
			(xy 362.581346 -215.372557) (xy 362.527389 -215.386663) (xy 362.471952 -215.392763) (xy 362.416218 -215.390726)
			(xy 362.361375 -215.380596) (xy 362.308591 -215.362589) (xy 362.258991 -215.337088) (xy 362.213633 -215.304637)
			(xy 362.173484 -215.265928) (xy 362.139398 -215.221785) (xy 362.112102 -215.17315) (xy 362.092179 -215.121059)
			(xy 362.080053 -215.066622) (xy 362.075982 -215.011) (xy 359.049886 -215.011) (xy 359.098389 -215.016337)
			(xy 359.152346 -215.030443) (xy 359.203675 -215.052255) (xy 359.251281 -215.081309) (xy 359.294149 -215.116984)
			(xy 359.331366 -215.158521) (xy 359.362139 -215.205034) (xy 359.385811 -215.255531) (xy 359.401879 -215.308938)
			(xy 359.409999 -215.364114) (xy 359.410508 -215.392) (xy 359.409999 -215.419886) (xy 359.401879 -215.475062)
			(xy 359.385811 -215.528469) (xy 359.362139 -215.578966) (xy 359.331366 -215.625479) (xy 359.294149 -215.667016)
			(xy 359.251281 -215.702691) (xy 359.203675 -215.731745) (xy 359.152346 -215.753557) (xy 359.098389 -215.767663)
			(xy 359.042952 -215.773763) (xy 358.987218 -215.771726) (xy 358.932375 -215.761596) (xy 358.879591 -215.743589)
			(xy 358.829991 -215.718088) (xy 358.784633 -215.685637) (xy 358.744484 -215.646928) (xy 358.710398 -215.602785)
			(xy 358.683102 -215.55415) (xy 358.663179 -215.502059) (xy 358.651053 -215.447622) (xy 358.646982 -215.392)
			(xy 356.498906 -215.392) (xy 356.498478 -215.418315) (xy 356.491418 -215.470469) (xy 356.477426 -215.521204)
			(xy 356.456755 -215.569605) (xy 356.429779 -215.614795) (xy 356.396984 -215.655958) (xy 356.378256 -215.674448)
			(xy 356.376986 -215.677496) (xy 356.373176 -215.686894) (xy 356.373176 -216.408) (xy 358.646982 -216.408)
			(xy 358.651053 -216.352378) (xy 358.663179 -216.297941) (xy 358.683102 -216.24585) (xy 358.710398 -216.197215)
			(xy 358.744484 -216.153072) (xy 358.784633 -216.114363) (xy 358.829991 -216.081912) (xy 358.879591 -216.056411)
			(xy 358.932375 -216.038404) (xy 358.987218 -216.028274) (xy 359.042952 -216.026237) (xy 359.098389 -216.032337)
			(xy 359.152346 -216.046443) (xy 359.203675 -216.068255) (xy 359.251281 -216.097309) (xy 359.294149 -216.132984)
			(xy 359.331366 -216.174521) (xy 359.362139 -216.221034) (xy 359.385811 -216.271531) (xy 359.401879 -216.324938)
			(xy 359.409999 -216.380114) (xy 359.410508 -216.408) (xy 359.409999 -216.435886) (xy 359.401879 -216.491062)
			(xy 359.385811 -216.544469) (xy 359.362139 -216.594966) (xy 359.331366 -216.641479) (xy 359.294149 -216.683016)
			(xy 359.251281 -216.718691) (xy 359.203675 -216.747745) (xy 359.152346 -216.769557) (xy 359.098389 -216.783663)
			(xy 359.042952 -216.789763) (xy 358.987218 -216.787726) (xy 358.932375 -216.777596) (xy 358.879591 -216.759589)
			(xy 358.829991 -216.734088) (xy 358.784633 -216.701637) (xy 358.744484 -216.662928) (xy 358.710398 -216.618785)
			(xy 358.683102 -216.57015) (xy 358.663179 -216.518059) (xy 358.651053 -216.463622) (xy 358.646982 -216.408)
			(xy 356.373176 -216.408) (xy 356.373176 -216.926668) (xy 364.16183 -216.926668) (xy 364.165901 -216.871046)
			(xy 364.178027 -216.816609) (xy 364.19795 -216.764518) (xy 364.225246 -216.715883) (xy 364.259332 -216.67174)
			(xy 364.299481 -216.633031) (xy 364.344839 -216.60058) (xy 364.394439 -216.575079) (xy 364.447223 -216.557072)
			(xy 364.502066 -216.546942) (xy 364.5578 -216.544905) (xy 364.613237 -216.551005) (xy 364.667194 -216.565111)
			(xy 364.718523 -216.586923) (xy 364.766129 -216.615977) (xy 364.808997 -216.651652) (xy 364.846214 -216.693189)
			(xy 364.876987 -216.739702) (xy 364.900659 -216.790199) (xy 364.916727 -216.843606) (xy 364.924847 -216.898782)
			(xy 364.925356 -216.926668) (xy 364.924847 -216.954554) (xy 364.916727 -217.00973) (xy 364.900659 -217.063137)
			(xy 364.876987 -217.113634) (xy 364.846214 -217.160147) (xy 364.808997 -217.201684) (xy 364.766129 -217.237359)
			(xy 364.718523 -217.266413) (xy 364.667194 -217.288225) (xy 364.613237 -217.302331) (xy 364.5578 -217.308431)
			(xy 364.502066 -217.306394) (xy 364.447223 -217.296264) (xy 364.394439 -217.278257) (xy 364.344839 -217.252756)
			(xy 364.299481 -217.220305) (xy 364.259332 -217.181596) (xy 364.225246 -217.137453) (xy 364.19795 -217.088818)
			(xy 364.178027 -217.036727) (xy 364.165901 -216.98229) (xy 364.16183 -216.926668) (xy 356.373176 -216.926668)
			(xy 356.373176 -217.424) (xy 358.646982 -217.424) (xy 358.651053 -217.368378) (xy 358.663179 -217.313941)
			(xy 358.683102 -217.26185) (xy 358.710398 -217.213215) (xy 358.744484 -217.169072) (xy 358.784633 -217.130363)
			(xy 358.829991 -217.097912) (xy 358.879591 -217.072411) (xy 358.932375 -217.054404) (xy 358.987218 -217.044274)
			(xy 359.042952 -217.042237) (xy 359.098389 -217.048337) (xy 359.152346 -217.062443) (xy 359.203675 -217.084255)
			(xy 359.251281 -217.113309) (xy 359.294149 -217.148984) (xy 359.331366 -217.190521) (xy 359.362139 -217.237034)
			(xy 359.385811 -217.287531) (xy 359.401879 -217.340938) (xy 359.409999 -217.396114) (xy 359.410508 -217.424)
			(xy 359.409999 -217.451886) (xy 359.401879 -217.507062) (xy 359.385811 -217.560469) (xy 359.362139 -217.610966)
			(xy 359.331366 -217.657479) (xy 359.294149 -217.699016) (xy 359.251281 -217.734691) (xy 359.203675 -217.763745)
			(xy 359.152346 -217.785557) (xy 359.098389 -217.799663) (xy 359.042952 -217.805763) (xy 358.987218 -217.803726)
			(xy 358.932375 -217.793596) (xy 358.879591 -217.775589) (xy 358.829991 -217.750088) (xy 358.784633 -217.717637)
			(xy 358.744484 -217.678928) (xy 358.710398 -217.634785) (xy 358.683102 -217.58615) (xy 358.663179 -217.534059)
			(xy 358.651053 -217.479622) (xy 358.646982 -217.424) (xy 356.373176 -217.424) (xy 356.373176 -218.44)
			(xy 356.614982 -218.44) (xy 356.619053 -218.384378) (xy 356.631179 -218.329941) (xy 356.651102 -218.27785)
			(xy 356.678398 -218.229215) (xy 356.712484 -218.185072) (xy 356.752633 -218.146363) (xy 356.797991 -218.113912)
			(xy 356.847591 -218.088411) (xy 356.900375 -218.070404) (xy 356.955218 -218.060274) (xy 357.010952 -218.058237)
			(xy 357.066389 -218.064337) (xy 357.120346 -218.078443) (xy 357.171675 -218.100255) (xy 357.219281 -218.129309)
			(xy 357.262149 -218.164984) (xy 357.299366 -218.206521) (xy 357.330139 -218.253034) (xy 357.353811 -218.303531)
			(xy 357.369879 -218.356938) (xy 357.377999 -218.412114) (xy 357.378508 -218.44) (xy 358.646982 -218.44)
			(xy 358.651053 -218.384378) (xy 358.663179 -218.329941) (xy 358.683102 -218.27785) (xy 358.710398 -218.229215)
			(xy 358.744484 -218.185072) (xy 358.784633 -218.146363) (xy 358.829991 -218.113912) (xy 358.879591 -218.088411)
			(xy 358.932375 -218.070404) (xy 358.987218 -218.060274) (xy 359.042952 -218.058237) (xy 359.098389 -218.064337)
			(xy 359.152346 -218.078443) (xy 359.203675 -218.100255) (xy 359.251281 -218.129309) (xy 359.294149 -218.164984)
			(xy 359.331366 -218.206521) (xy 359.362139 -218.253034) (xy 359.385811 -218.303531) (xy 359.401879 -218.356938)
			(xy 359.409999 -218.412114) (xy 359.410508 -218.44) (xy 359.409999 -218.467886) (xy 359.401879 -218.523062)
			(xy 359.385811 -218.576469) (xy 359.362139 -218.626966) (xy 359.331366 -218.673479) (xy 359.294149 -218.715016)
			(xy 359.251281 -218.750691) (xy 359.203675 -218.779745) (xy 359.19386 -218.783916) (xy 373.884188 -218.783916)
			(xy 373.888259 -218.728294) (xy 373.900385 -218.673857) (xy 373.920308 -218.621766) (xy 373.947604 -218.573131)
			(xy 373.98169 -218.528988) (xy 374.021839 -218.490279) (xy 374.067197 -218.457828) (xy 374.116797 -218.432327)
			(xy 374.169581 -218.41432) (xy 374.224424 -218.40419) (xy 374.280158 -218.402153) (xy 374.289401 -218.40317)
			(xy 380.707644 -218.40317) (xy 380.711715 -218.347548) (xy 380.723841 -218.293111) (xy 380.743764 -218.24102)
			(xy 380.77106 -218.192385) (xy 380.805146 -218.148242) (xy 380.845295 -218.109533) (xy 380.890653 -218.077082)
			(xy 380.940253 -218.051581) (xy 380.993037 -218.033574) (xy 381.04788 -218.023444) (xy 381.103614 -218.021407)
			(xy 381.159051 -218.027507) (xy 381.213008 -218.041613) (xy 381.264337 -218.063425) (xy 381.311943 -218.092479)
			(xy 381.354811 -218.128154) (xy 381.392028 -218.169691) (xy 381.422801 -218.216204) (xy 381.446473 -218.266701)
			(xy 381.462541 -218.320108) (xy 381.469382 -218.366594) (xy 381.872234 -218.366594) (xy 381.876305 -218.310972)
			(xy 381.888431 -218.256535) (xy 381.908354 -218.204444) (xy 381.93565 -218.155809) (xy 381.969736 -218.111666)
			(xy 382.009885 -218.072957) (xy 382.055243 -218.040506) (xy 382.104843 -218.015005) (xy 382.157627 -217.996998)
			(xy 382.21247 -217.986868) (xy 382.268204 -217.984831) (xy 382.323641 -217.990931) (xy 382.377598 -218.005037)
			(xy 382.428927 -218.026849) (xy 382.476533 -218.055903) (xy 382.519401 -218.091578) (xy 382.556618 -218.133115)
			(xy 382.587391 -218.179628) (xy 382.611063 -218.230125) (xy 382.627131 -218.283532) (xy 382.635251 -218.338708)
			(xy 382.63576 -218.366594) (xy 382.635251 -218.39448) (xy 382.627131 -218.449656) (xy 382.611063 -218.503063)
			(xy 382.587391 -218.55356) (xy 382.556618 -218.600073) (xy 382.519401 -218.64161) (xy 382.476533 -218.677285)
			(xy 382.428927 -218.706339) (xy 382.377598 -218.728151) (xy 382.323641 -218.742257) (xy 382.268204 -218.748357)
			(xy 382.21247 -218.74632) (xy 382.157627 -218.73619) (xy 382.104843 -218.718183) (xy 382.055243 -218.692682)
			(xy 382.009885 -218.660231) (xy 381.969736 -218.621522) (xy 381.93565 -218.577379) (xy 381.908354 -218.528744)
			(xy 381.888431 -218.476653) (xy 381.876305 -218.422216) (xy 381.872234 -218.366594) (xy 381.469382 -218.366594)
			(xy 381.470661 -218.375284) (xy 381.47117 -218.40317) (xy 381.470661 -218.431056) (xy 381.462541 -218.486232)
			(xy 381.446473 -218.539639) (xy 381.422801 -218.590136) (xy 381.392028 -218.636649) (xy 381.354811 -218.678186)
			(xy 381.311943 -218.713861) (xy 381.264337 -218.742915) (xy 381.213008 -218.764727) (xy 381.159051 -218.778833)
			(xy 381.103614 -218.784933) (xy 381.04788 -218.782896) (xy 380.993037 -218.772766) (xy 380.940253 -218.754759)
			(xy 380.890653 -218.729258) (xy 380.845295 -218.696807) (xy 380.805146 -218.658098) (xy 380.77106 -218.613955)
			(xy 380.743764 -218.56532) (xy 380.723841 -218.513229) (xy 380.711715 -218.458792) (xy 380.707644 -218.40317)
			(xy 374.289401 -218.40317) (xy 374.335595 -218.408253) (xy 374.389552 -218.422359) (xy 374.440881 -218.444171)
			(xy 374.488487 -218.473225) (xy 374.531355 -218.5089) (xy 374.568572 -218.550437) (xy 374.599345 -218.59695)
			(xy 374.623017 -218.647447) (xy 374.639085 -218.700854) (xy 374.647205 -218.75603) (xy 374.647714 -218.783916)
			(xy 374.647205 -218.811802) (xy 374.639085 -218.866978) (xy 374.623017 -218.920385) (xy 374.599345 -218.970882)
			(xy 374.568572 -219.017395) (xy 374.531355 -219.058932) (xy 374.488487 -219.094607) (xy 374.440881 -219.123661)
			(xy 374.389552 -219.145473) (xy 374.335595 -219.159579) (xy 374.280158 -219.165679) (xy 374.224424 -219.163642)
			(xy 374.169581 -219.153512) (xy 374.116797 -219.135505) (xy 374.067197 -219.110004) (xy 374.021839 -219.077553)
			(xy 373.98169 -219.038844) (xy 373.947604 -218.994701) (xy 373.920308 -218.946066) (xy 373.900385 -218.893975)
			(xy 373.888259 -218.839538) (xy 373.884188 -218.783916) (xy 359.19386 -218.783916) (xy 359.152346 -218.801557)
			(xy 359.098389 -218.815663) (xy 359.042952 -218.821763) (xy 358.987218 -218.819726) (xy 358.932375 -218.809596)
			(xy 358.879591 -218.791589) (xy 358.829991 -218.766088) (xy 358.784633 -218.733637) (xy 358.744484 -218.694928)
			(xy 358.710398 -218.650785) (xy 358.683102 -218.60215) (xy 358.663179 -218.550059) (xy 358.651053 -218.495622)
			(xy 358.646982 -218.44) (xy 357.378508 -218.44) (xy 357.377999 -218.467886) (xy 357.369879 -218.523062)
			(xy 357.353811 -218.576469) (xy 357.330139 -218.626966) (xy 357.299366 -218.673479) (xy 357.262149 -218.715016)
			(xy 357.219281 -218.750691) (xy 357.171675 -218.779745) (xy 357.120346 -218.801557) (xy 357.066389 -218.815663)
			(xy 357.010952 -218.821763) (xy 356.955218 -218.819726) (xy 356.900375 -218.809596) (xy 356.847591 -218.791589)
			(xy 356.797991 -218.766088) (xy 356.752633 -218.733637) (xy 356.712484 -218.694928) (xy 356.678398 -218.650785)
			(xy 356.651102 -218.60215) (xy 356.631179 -218.550059) (xy 356.619053 -218.495622) (xy 356.614982 -218.44)
			(xy 356.373176 -218.44) (xy 356.373176 -219.151962) (xy 356.373176 -219.15501) (xy 356.373504 -219.158645)
			(xy 356.375038 -219.165782) (xy 356.376224 -219.169234) (xy 356.377748 -219.173044) (xy 356.396539 -219.191556)
			(xy 356.429476 -219.232759) (xy 356.456571 -219.278017) (xy 356.477333 -219.326509) (xy 356.491382 -219.377353)
			(xy 356.498464 -219.429625) (xy 356.498906 -219.456) (xy 358.646982 -219.456) (xy 358.651053 -219.400378)
			(xy 358.663179 -219.345941) (xy 358.683102 -219.29385) (xy 358.710398 -219.245215) (xy 358.744484 -219.201072)
			(xy 358.784633 -219.162363) (xy 358.829991 -219.129912) (xy 358.879591 -219.104411) (xy 358.932375 -219.086404)
			(xy 358.987218 -219.076274) (xy 359.042952 -219.074237) (xy 359.098389 -219.080337) (xy 359.152346 -219.094443)
			(xy 359.203675 -219.116255) (xy 359.251281 -219.145309) (xy 359.294149 -219.180984) (xy 359.331366 -219.222521)
			(xy 359.362139 -219.269034) (xy 359.385811 -219.319531) (xy 359.401879 -219.372938) (xy 359.409999 -219.428114)
			(xy 359.410508 -219.456) (xy 359.409999 -219.483886) (xy 359.401879 -219.539062) (xy 359.396302 -219.5576)
			(xy 367.594386 -219.5576) (xy 367.598457 -219.501978) (xy 367.610583 -219.447541) (xy 367.630506 -219.39545)
			(xy 367.657802 -219.346815) (xy 367.691888 -219.302672) (xy 367.732037 -219.263963) (xy 367.777395 -219.231512)
			(xy 367.826995 -219.206011) (xy 367.879779 -219.188004) (xy 367.934622 -219.177874) (xy 367.990356 -219.175837)
			(xy 368.045793 -219.181937) (xy 368.09975 -219.196043) (xy 368.151079 -219.217855) (xy 368.198685 -219.246909)
			(xy 368.241553 -219.282584) (xy 368.27877 -219.324121) (xy 368.309543 -219.370634) (xy 368.333215 -219.421131)
			(xy 368.349283 -219.474538) (xy 368.357403 -219.529714) (xy 368.357912 -219.5576) (xy 368.357403 -219.585486)
			(xy 368.349283 -219.640662) (xy 368.333215 -219.694069) (xy 368.309543 -219.744566) (xy 368.27877 -219.791079)
			(xy 368.241553 -219.832616) (xy 368.198685 -219.868291) (xy 368.151079 -219.897345) (xy 368.09975 -219.919157)
			(xy 368.045793 -219.933263) (xy 367.990356 -219.939363) (xy 367.934622 -219.937326) (xy 367.879779 -219.927196)
			(xy 367.826995 -219.909189) (xy 367.777395 -219.883688) (xy 367.732037 -219.851237) (xy 367.691888 -219.812528)
			(xy 367.657802 -219.768385) (xy 367.630506 -219.71975) (xy 367.610583 -219.667659) (xy 367.598457 -219.613222)
			(xy 367.594386 -219.5576) (xy 359.396302 -219.5576) (xy 359.385811 -219.592469) (xy 359.362139 -219.642966)
			(xy 359.331366 -219.689479) (xy 359.294149 -219.731016) (xy 359.251281 -219.766691) (xy 359.203675 -219.795745)
			(xy 359.152346 -219.817557) (xy 359.098389 -219.831663) (xy 359.042952 -219.837763) (xy 358.987218 -219.835726)
			(xy 358.932375 -219.825596) (xy 358.879591 -219.807589) (xy 358.829991 -219.782088) (xy 358.784633 -219.749637)
			(xy 358.744484 -219.710928) (xy 358.710398 -219.666785) (xy 358.683102 -219.61815) (xy 358.663179 -219.566059)
			(xy 358.651053 -219.511622) (xy 358.646982 -219.456) (xy 356.498906 -219.456) (xy 356.498478 -219.482315)
			(xy 356.491418 -219.534469) (xy 356.477426 -219.585204) (xy 356.456755 -219.633605) (xy 356.429779 -219.678795)
			(xy 356.396984 -219.719958) (xy 356.378256 -219.738448) (xy 356.376986 -219.741496) (xy 356.373176 -219.750894)
			(xy 356.373176 -220.472) (xy 356.614982 -220.472) (xy 356.619053 -220.416378) (xy 356.631179 -220.361941)
			(xy 356.651102 -220.30985) (xy 356.678398 -220.261215) (xy 356.712484 -220.217072) (xy 356.752633 -220.178363)
			(xy 356.797991 -220.145912) (xy 356.847591 -220.120411) (xy 356.900375 -220.102404) (xy 356.955218 -220.092274)
			(xy 357.010952 -220.090237) (xy 357.066389 -220.096337) (xy 357.120346 -220.110443) (xy 357.171675 -220.132255)
			(xy 357.219281 -220.161309) (xy 357.262149 -220.196984) (xy 357.299366 -220.238521) (xy 357.330139 -220.285034)
			(xy 357.353811 -220.335531) (xy 357.369879 -220.388938) (xy 357.377999 -220.444114) (xy 357.378508 -220.472)
			(xy 358.646982 -220.472) (xy 358.651053 -220.416378) (xy 358.663179 -220.361941) (xy 358.683102 -220.30985)
			(xy 358.710398 -220.261215) (xy 358.744484 -220.217072) (xy 358.784633 -220.178363) (xy 358.829991 -220.145912)
			(xy 358.879591 -220.120411) (xy 358.932375 -220.102404) (xy 358.987218 -220.092274) (xy 359.042952 -220.090237)
			(xy 359.098389 -220.096337) (xy 359.152346 -220.110443) (xy 359.203675 -220.132255) (xy 359.251281 -220.161309)
			(xy 359.294149 -220.196984) (xy 359.331366 -220.238521) (xy 359.362139 -220.285034) (xy 359.385811 -220.335531)
			(xy 359.401879 -220.388938) (xy 359.409999 -220.444114) (xy 359.410508 -220.472) (xy 359.409999 -220.499886)
			(xy 359.401879 -220.555062) (xy 359.385811 -220.608469) (xy 359.362139 -220.658966) (xy 359.331366 -220.705479)
			(xy 359.294149 -220.747016) (xy 359.251281 -220.782691) (xy 359.203675 -220.811745) (xy 359.152346 -220.833557)
			(xy 359.102264 -220.84665) (xy 364.12881 -220.84665) (xy 364.132881 -220.791028) (xy 364.145007 -220.736591)
			(xy 364.16493 -220.6845) (xy 364.192226 -220.635865) (xy 364.226312 -220.591722) (xy 364.266461 -220.553013)
			(xy 364.311819 -220.520562) (xy 364.361419 -220.495061) (xy 364.414203 -220.477054) (xy 364.469046 -220.466924)
			(xy 364.52478 -220.464887) (xy 364.580217 -220.470987) (xy 364.634174 -220.485093) (xy 364.685503 -220.506905)
			(xy 364.714045 -220.524324) (xy 374.238264 -220.524324) (xy 374.242335 -220.468702) (xy 374.254461 -220.414265)
			(xy 374.274384 -220.362174) (xy 374.30168 -220.313539) (xy 374.335766 -220.269396) (xy 374.375915 -220.230687)
			(xy 374.421273 -220.198236) (xy 374.470873 -220.172735) (xy 374.523657 -220.154728) (xy 374.5785 -220.144598)
			(xy 374.634234 -220.142561) (xy 374.689671 -220.148661) (xy 374.743628 -220.162767) (xy 374.794957 -220.184579)
			(xy 374.842563 -220.213633) (xy 374.885431 -220.249308) (xy 374.922648 -220.290845) (xy 374.944697 -220.324172)
			(xy 383.84683 -220.324172) (xy 383.850901 -220.26855) (xy 383.863027 -220.214113) (xy 383.88295 -220.162022)
			(xy 383.910246 -220.113387) (xy 383.944332 -220.069244) (xy 383.984481 -220.030535) (xy 384.029839 -219.998084)
			(xy 384.079439 -219.972583) (xy 384.132223 -219.954576) (xy 384.187066 -219.944446) (xy 384.2428 -219.942409)
			(xy 384.298237 -219.948509) (xy 384.352194 -219.962615) (xy 384.403523 -219.984427) (xy 384.451129 -220.013481)
			(xy 384.493997 -220.049156) (xy 384.531214 -220.090693) (xy 384.561987 -220.137206) (xy 384.585659 -220.187703)
			(xy 384.601727 -220.24111) (xy 384.609847 -220.296286) (xy 384.610356 -220.324172) (xy 384.609847 -220.352058)
			(xy 384.601727 -220.407234) (xy 384.585659 -220.460641) (xy 384.561987 -220.511138) (xy 384.531214 -220.557651)
			(xy 384.493997 -220.599188) (xy 384.451129 -220.634863) (xy 384.403523 -220.663917) (xy 384.352194 -220.685729)
			(xy 384.298237 -220.699835) (xy 384.2428 -220.705935) (xy 384.187066 -220.703898) (xy 384.132223 -220.693768)
			(xy 384.079439 -220.675761) (xy 384.029839 -220.65026) (xy 383.984481 -220.617809) (xy 383.944332 -220.5791)
			(xy 383.910246 -220.534957) (xy 383.88295 -220.486322) (xy 383.863027 -220.434231) (xy 383.850901 -220.379794)
			(xy 383.84683 -220.324172) (xy 374.944697 -220.324172) (xy 374.953421 -220.337358) (xy 374.977093 -220.387855)
			(xy 374.993161 -220.441262) (xy 375.001281 -220.496438) (xy 375.00179 -220.524324) (xy 375.001281 -220.55221)
			(xy 374.993161 -220.607386) (xy 374.977093 -220.660793) (xy 374.953421 -220.71129) (xy 374.922648 -220.757803)
			(xy 374.885431 -220.79934) (xy 374.842563 -220.835015) (xy 374.794957 -220.864069) (xy 374.743628 -220.885881)
			(xy 374.689671 -220.899987) (xy 374.634234 -220.906087) (xy 374.5785 -220.90405) (xy 374.523657 -220.89392)
			(xy 374.470873 -220.875913) (xy 374.421273 -220.850412) (xy 374.375915 -220.817961) (xy 374.335766 -220.779252)
			(xy 374.30168 -220.735109) (xy 374.274384 -220.686474) (xy 374.254461 -220.634383) (xy 374.242335 -220.579946)
			(xy 374.238264 -220.524324) (xy 364.714045 -220.524324) (xy 364.733109 -220.535959) (xy 364.775977 -220.571634)
			(xy 364.813194 -220.613171) (xy 364.843967 -220.659684) (xy 364.867639 -220.710181) (xy 364.883707 -220.763588)
			(xy 364.891827 -220.818764) (xy 364.892336 -220.84665) (xy 364.891827 -220.874536) (xy 364.883707 -220.929712)
			(xy 364.867639 -220.983119) (xy 364.843967 -221.033616) (xy 364.813194 -221.080129) (xy 364.775977 -221.121666)
			(xy 364.733109 -221.157341) (xy 364.685503 -221.186395) (xy 364.634174 -221.208207) (xy 364.580217 -221.222313)
			(xy 364.52478 -221.228413) (xy 364.469046 -221.226376) (xy 364.414203 -221.216246) (xy 364.361419 -221.198239)
			(xy 364.311819 -221.172738) (xy 364.266461 -221.140287) (xy 364.226312 -221.101578) (xy 364.192226 -221.057435)
			(xy 364.16493 -221.0088) (xy 364.145007 -220.956709) (xy 364.132881 -220.902272) (xy 364.12881 -220.84665)
			(xy 359.102264 -220.84665) (xy 359.098389 -220.847663) (xy 359.042952 -220.853763) (xy 358.987218 -220.851726)
			(xy 358.932375 -220.841596) (xy 358.879591 -220.823589) (xy 358.829991 -220.798088) (xy 358.784633 -220.765637)
			(xy 358.744484 -220.726928) (xy 358.710398 -220.682785) (xy 358.683102 -220.63415) (xy 358.663179 -220.582059)
			(xy 358.651053 -220.527622) (xy 358.646982 -220.472) (xy 357.378508 -220.472) (xy 357.377999 -220.499886)
			(xy 357.369879 -220.555062) (xy 357.353811 -220.608469) (xy 357.330139 -220.658966) (xy 357.299366 -220.705479)
			(xy 357.262149 -220.747016) (xy 357.219281 -220.782691) (xy 357.171675 -220.811745) (xy 357.120346 -220.833557)
			(xy 357.066389 -220.847663) (xy 357.010952 -220.853763) (xy 356.955218 -220.851726) (xy 356.900375 -220.841596)
			(xy 356.847591 -220.823589) (xy 356.797991 -220.798088) (xy 356.752633 -220.765637) (xy 356.712484 -220.726928)
			(xy 356.678398 -220.682785) (xy 356.651102 -220.63415) (xy 356.631179 -220.582059) (xy 356.619053 -220.527622)
			(xy 356.614982 -220.472) (xy 356.373176 -220.472) (xy 356.373176 -221.488) (xy 358.646982 -221.488)
			(xy 358.651053 -221.432378) (xy 358.663179 -221.377941) (xy 358.683102 -221.32585) (xy 358.710398 -221.277215)
			(xy 358.744484 -221.233072) (xy 358.784633 -221.194363) (xy 358.829991 -221.161912) (xy 358.879591 -221.136411)
			(xy 358.932375 -221.118404) (xy 358.987218 -221.108274) (xy 359.042952 -221.106237) (xy 359.098389 -221.112337)
			(xy 359.152346 -221.126443) (xy 359.203675 -221.148255) (xy 359.251281 -221.177309) (xy 359.294149 -221.212984)
			(xy 359.331366 -221.254521) (xy 359.362139 -221.301034) (xy 359.377033 -221.332806) (xy 370.740684 -221.332806)
			(xy 370.744755 -221.277184) (xy 370.756881 -221.222747) (xy 370.776804 -221.170656) (xy 370.8041 -221.122021)
			(xy 370.838186 -221.077878) (xy 370.878335 -221.039169) (xy 370.923693 -221.006718) (xy 370.973293 -220.981217)
			(xy 371.026077 -220.96321) (xy 371.08092 -220.95308) (xy 371.136654 -220.951043) (xy 371.192091 -220.957143)
			(xy 371.246048 -220.971249) (xy 371.297377 -220.993061) (xy 371.344983 -221.022115) (xy 371.387851 -221.05779)
			(xy 371.425068 -221.099327) (xy 371.455841 -221.14584) (xy 371.479513 -221.196337) (xy 371.495581 -221.249744)
			(xy 371.503701 -221.30492) (xy 371.50421 -221.332806) (xy 371.503701 -221.360692) (xy 371.495581 -221.415868)
			(xy 371.479513 -221.469275) (xy 371.455841 -221.519772) (xy 371.425068 -221.566285) (xy 371.387851 -221.607822)
			(xy 371.344983 -221.643497) (xy 371.297377 -221.672551) (xy 371.246048 -221.694363) (xy 371.192091 -221.708469)
			(xy 371.136654 -221.714569) (xy 371.08092 -221.712532) (xy 371.026077 -221.702402) (xy 370.973293 -221.684395)
			(xy 370.923693 -221.658894) (xy 370.878335 -221.626443) (xy 370.838186 -221.587734) (xy 370.8041 -221.543591)
			(xy 370.776804 -221.494956) (xy 370.756881 -221.442865) (xy 370.744755 -221.388428) (xy 370.740684 -221.332806)
			(xy 359.377033 -221.332806) (xy 359.385811 -221.351531) (xy 359.401879 -221.404938) (xy 359.409999 -221.460114)
			(xy 359.410508 -221.488) (xy 359.409999 -221.515886) (xy 359.401879 -221.571062) (xy 359.385811 -221.624469)
			(xy 359.362139 -221.674966) (xy 359.331366 -221.721479) (xy 359.294149 -221.763016) (xy 359.251281 -221.798691)
			(xy 359.203675 -221.827745) (xy 359.152346 -221.849557) (xy 359.098389 -221.863663) (xy 359.042952 -221.869763)
			(xy 358.987218 -221.867726) (xy 358.932375 -221.857596) (xy 358.879591 -221.839589) (xy 358.829991 -221.814088)
			(xy 358.784633 -221.781637) (xy 358.744484 -221.742928) (xy 358.710398 -221.698785) (xy 358.683102 -221.65015)
			(xy 358.663179 -221.598059) (xy 358.651053 -221.543622) (xy 358.646982 -221.488) (xy 356.373176 -221.488)
			(xy 356.373176 -222.199962) (xy 356.373176 -222.20301) (xy 356.373504 -222.206645) (xy 356.375038 -222.213782)
			(xy 356.376224 -222.217234) (xy 356.377748 -222.221044) (xy 356.396539 -222.239556) (xy 356.429476 -222.280759)
			(xy 356.456571 -222.326017) (xy 356.477333 -222.374509) (xy 356.491382 -222.425353) (xy 356.498464 -222.477625)
			(xy 356.498906 -222.504) (xy 358.646982 -222.504) (xy 358.651053 -222.448378) (xy 358.663179 -222.393941)
			(xy 358.683102 -222.34185) (xy 358.710398 -222.293215) (xy 358.744484 -222.249072) (xy 358.784633 -222.210363)
			(xy 358.829991 -222.177912) (xy 358.879591 -222.152411) (xy 358.932375 -222.134404) (xy 358.987218 -222.124274)
			(xy 359.042952 -222.122237) (xy 359.098389 -222.128337) (xy 359.152346 -222.142443) (xy 359.203675 -222.164255)
			(xy 359.216818 -222.172276) (xy 364.118904 -222.172276) (xy 364.122975 -222.116654) (xy 364.135101 -222.062217)
			(xy 364.155024 -222.010126) (xy 364.18232 -221.961491) (xy 364.216406 -221.917348) (xy 364.256555 -221.878639)
			(xy 364.301913 -221.846188) (xy 364.351513 -221.820687) (xy 364.404297 -221.80268) (xy 364.45914 -221.79255)
			(xy 364.514874 -221.790513) (xy 364.570311 -221.796613) (xy 364.624268 -221.810719) (xy 364.675597 -221.832531)
			(xy 364.723203 -221.861585) (xy 364.766071 -221.89726) (xy 364.803288 -221.938797) (xy 364.811053 -221.950534)
			(xy 365.350296 -221.950534) (xy 365.354367 -221.894912) (xy 365.366493 -221.840475) (xy 365.386416 -221.788384)
			(xy 365.413712 -221.739749) (xy 365.447798 -221.695606) (xy 365.487947 -221.656897) (xy 365.533305 -221.624446)
			(xy 365.582905 -221.598945) (xy 365.635689 -221.580938) (xy 365.690532 -221.570808) (xy 365.746266 -221.568771)
			(xy 365.801703 -221.574871) (xy 365.85566 -221.588977) (xy 365.906989 -221.610789) (xy 365.954595 -221.639843)
			(xy 365.997463 -221.675518) (xy 366.03468 -221.717055) (xy 366.065453 -221.763568) (xy 366.089125 -221.814065)
			(xy 366.105193 -221.867472) (xy 366.113313 -221.922648) (xy 366.113822 -221.950534) (xy 366.113313 -221.97842)
			(xy 366.105193 -222.033596) (xy 366.0961 -222.063818) (xy 373.879364 -222.063818) (xy 373.87985 -222.036567)
			(xy 373.887606 -221.982619) (xy 373.902961 -221.930324) (xy 373.925603 -221.880747) (xy 373.955069 -221.834897)
			(xy 373.99076 -221.793706) (xy 374.031951 -221.758015) (xy 374.077801 -221.728549) (xy 374.127378 -221.705907)
			(xy 374.179673 -221.690552) (xy 374.233621 -221.682796) (xy 374.288123 -221.682796) (xy 374.342071 -221.690552)
			(xy 374.394366 -221.705907) (xy 374.440026 -221.72676) (xy 376.14428 -221.72676) (xy 376.148351 -221.671138)
			(xy 376.160477 -221.616701) (xy 376.1804 -221.56461) (xy 376.207696 -221.515975) (xy 376.241782 -221.471832)
			(xy 376.281931 -221.433123) (xy 376.327289 -221.400672) (xy 376.376889 -221.375171) (xy 376.429673 -221.357164)
			(xy 376.484516 -221.347034) (xy 376.54025 -221.344997) (xy 376.595687 -221.351097) (xy 376.649644 -221.365203)
			(xy 376.700973 -221.387015) (xy 376.748579 -221.416069) (xy 376.791447 -221.451744) (xy 376.828664 -221.493281)
			(xy 376.859437 -221.539794) (xy 376.883109 -221.590291) (xy 376.899177 -221.643698) (xy 376.907297 -221.698874)
			(xy 376.907338 -221.701106) (xy 377.605034 -221.701106) (xy 377.609105 -221.645484) (xy 377.621231 -221.591047)
			(xy 377.641154 -221.538956) (xy 377.66845 -221.490321) (xy 377.702536 -221.446178) (xy 377.742685 -221.407469)
			(xy 377.788043 -221.375018) (xy 377.837643 -221.349517) (xy 377.890427 -221.33151) (xy 377.94527 -221.32138)
			(xy 378.001004 -221.319343) (xy 378.056441 -221.325443) (xy 378.110398 -221.339549) (xy 378.161727 -221.361361)
			(xy 378.209333 -221.390415) (xy 378.252201 -221.42609) (xy 378.289418 -221.467627) (xy 378.320191 -221.51414)
			(xy 378.343863 -221.564637) (xy 378.359931 -221.618044) (xy 378.368051 -221.67322) (xy 378.36856 -221.701106)
			(xy 378.368051 -221.728992) (xy 378.359931 -221.784168) (xy 378.343863 -221.837575) (xy 378.320191 -221.888072)
			(xy 378.289418 -221.934585) (xy 378.271031 -221.955106) (xy 380.780034 -221.955106) (xy 380.784105 -221.899484)
			(xy 380.796231 -221.845047) (xy 380.816154 -221.792956) (xy 380.84345 -221.744321) (xy 380.877536 -221.700178)
			(xy 380.917685 -221.661469) (xy 380.963043 -221.629018) (xy 381.012643 -221.603517) (xy 381.065427 -221.58551)
			(xy 381.12027 -221.57538) (xy 381.176004 -221.573343) (xy 381.231441 -221.579443) (xy 381.285398 -221.593549)
			(xy 381.336727 -221.615361) (xy 381.384333 -221.644415) (xy 381.427201 -221.68009) (xy 381.464418 -221.721627)
			(xy 381.495191 -221.76814) (xy 381.518863 -221.818637) (xy 381.534931 -221.872044) (xy 381.543051 -221.92722)
			(xy 381.543286 -221.94012) (xy 385.30479 -221.94012) (xy 385.308861 -221.884498) (xy 385.320987 -221.830061)
			(xy 385.34091 -221.77797) (xy 385.368206 -221.729335) (xy 385.402292 -221.685192) (xy 385.442441 -221.646483)
			(xy 385.487799 -221.614032) (xy 385.537399 -221.588531) (xy 385.590183 -221.570524) (xy 385.645026 -221.560394)
			(xy 385.70076 -221.558357) (xy 385.756197 -221.564457) (xy 385.810154 -221.578563) (xy 385.861483 -221.600375)
			(xy 385.909089 -221.629429) (xy 385.951957 -221.665104) (xy 385.989174 -221.706641) (xy 386.019947 -221.753154)
			(xy 386.043619 -221.803651) (xy 386.059687 -221.857058) (xy 386.067807 -221.912234) (xy 386.068316 -221.94012)
			(xy 386.067807 -221.968006) (xy 386.059687 -222.023182) (xy 386.043619 -222.076589) (xy 386.019947 -222.127086)
			(xy 385.989174 -222.173599) (xy 385.951957 -222.215136) (xy 385.909089 -222.250811) (xy 385.861483 -222.279865)
			(xy 385.810154 -222.301677) (xy 385.756197 -222.315783) (xy 385.70076 -222.321883) (xy 385.645026 -222.319846)
			(xy 385.590183 -222.309716) (xy 385.537399 -222.291709) (xy 385.487799 -222.266208) (xy 385.442441 -222.233757)
			(xy 385.402292 -222.195048) (xy 385.368206 -222.150905) (xy 385.34091 -222.10227) (xy 385.320987 -222.050179)
			(xy 385.308861 -221.995742) (xy 385.30479 -221.94012) (xy 381.543286 -221.94012) (xy 381.54356 -221.955106)
			(xy 381.543051 -221.982992) (xy 381.534931 -222.038168) (xy 381.518863 -222.091575) (xy 381.495191 -222.142072)
			(xy 381.464418 -222.188585) (xy 381.427201 -222.230122) (xy 381.384333 -222.265797) (xy 381.336727 -222.294851)
			(xy 381.285398 -222.316663) (xy 381.231441 -222.330769) (xy 381.176004 -222.336869) (xy 381.12027 -222.334832)
			(xy 381.065427 -222.324702) (xy 381.012643 -222.306695) (xy 380.963043 -222.281194) (xy 380.917685 -222.248743)
			(xy 380.877536 -222.210034) (xy 380.84345 -222.165891) (xy 380.816154 -222.117256) (xy 380.796231 -222.065165)
			(xy 380.784105 -222.010728) (xy 380.780034 -221.955106) (xy 378.271031 -221.955106) (xy 378.252201 -221.976122)
			(xy 378.209333 -222.011797) (xy 378.161727 -222.040851) (xy 378.110398 -222.062663) (xy 378.056441 -222.076769)
			(xy 378.001004 -222.082869) (xy 377.94527 -222.080832) (xy 377.890427 -222.070702) (xy 377.837643 -222.052695)
			(xy 377.788043 -222.027194) (xy 377.742685 -221.994743) (xy 377.702536 -221.956034) (xy 377.66845 -221.911891)
			(xy 377.641154 -221.863256) (xy 377.621231 -221.811165) (xy 377.609105 -221.756728) (xy 377.605034 -221.701106)
			(xy 376.907338 -221.701106) (xy 376.907806 -221.72676) (xy 376.907297 -221.754646) (xy 376.899177 -221.809822)
			(xy 376.883109 -221.863229) (xy 376.859437 -221.913726) (xy 376.828664 -221.960239) (xy 376.791447 -222.001776)
			(xy 376.748579 -222.037451) (xy 376.700973 -222.066505) (xy 376.649644 -222.088317) (xy 376.595687 -222.102423)
			(xy 376.54025 -222.108523) (xy 376.484516 -222.106486) (xy 376.429673 -222.096356) (xy 376.376889 -222.078349)
			(xy 376.327289 -222.052848) (xy 376.281931 -222.020397) (xy 376.241782 -221.981688) (xy 376.207696 -221.937545)
			(xy 376.1804 -221.88891) (xy 376.160477 -221.836819) (xy 376.148351 -221.782382) (xy 376.14428 -221.72676)
			(xy 374.440026 -221.72676) (xy 374.443943 -221.728549) (xy 374.489793 -221.758015) (xy 374.530984 -221.793706)
			(xy 374.566675 -221.834897) (xy 374.596141 -221.880747) (xy 374.618783 -221.930324) (xy 374.634138 -221.982619)
			(xy 374.641894 -222.036567) (xy 374.64238 -222.063818) (xy 374.641899 -222.090681) (xy 374.634359 -222.143876)
			(xy 374.619432 -222.195488) (xy 374.597413 -222.244495) (xy 374.568736 -222.289929) (xy 374.551702 -222.310706)
			(xy 374.544082 -222.319596) (xy 374.53824 -222.342202) (xy 374.558814 -222.443548) (xy 374.573038 -222.46209)
			(xy 374.583198 -222.46717) (xy 374.606495 -222.479423) (xy 374.64977 -222.509392) (xy 374.688516 -222.545023)
			(xy 374.721997 -222.585642) (xy 374.749578 -222.630476) (xy 374.770736 -222.678676) (xy 374.785069 -222.729326)
			(xy 374.792305 -222.781465) (xy 374.792748 -222.807784) (xy 374.792262 -222.835035) (xy 374.784506 -222.888983)
			(xy 374.769151 -222.941278) (xy 374.746509 -222.990855) (xy 374.717043 -223.036705) (xy 374.681352 -223.077896)
			(xy 374.658028 -223.098106) (xy 377.605034 -223.098106) (xy 377.609105 -223.042484) (xy 377.621231 -222.988047)
			(xy 377.641154 -222.935956) (xy 377.66845 -222.887321) (xy 377.702536 -222.843178) (xy 377.742685 -222.804469)
			(xy 377.788043 -222.772018) (xy 377.837643 -222.746517) (xy 377.890427 -222.72851) (xy 377.94527 -222.71838)
			(xy 378.001004 -222.716343) (xy 378.056441 -222.722443) (xy 378.110398 -222.736549) (xy 378.161727 -222.758361)
			(xy 378.209333 -222.787415) (xy 378.252201 -222.82309) (xy 378.289418 -222.864627) (xy 378.320191 -222.91114)
			(xy 378.343863 -222.961637) (xy 378.359931 -223.015044) (xy 378.368051 -223.07022) (xy 378.36856 -223.098106)
			(xy 378.368051 -223.125992) (xy 378.359931 -223.181168) (xy 378.343863 -223.234575) (xy 378.341277 -223.240092)
			(xy 385.3213 -223.240092) (xy 385.325371 -223.18447) (xy 385.337497 -223.130033) (xy 385.35742 -223.077942)
			(xy 385.384716 -223.029307) (xy 385.418802 -222.985164) (xy 385.458951 -222.946455) (xy 385.504309 -222.914004)
			(xy 385.553909 -222.888503) (xy 385.606693 -222.870496) (xy 385.661536 -222.860366) (xy 385.71727 -222.858329)
			(xy 385.772707 -222.864429) (xy 385.826664 -222.878535) (xy 385.877993 -222.900347) (xy 385.925599 -222.929401)
			(xy 385.968467 -222.965076) (xy 386.005684 -223.006613) (xy 386.036457 -223.053126) (xy 386.060129 -223.103623)
			(xy 386.076197 -223.15703) (xy 386.084317 -223.212206) (xy 386.084826 -223.240092) (xy 386.084317 -223.267978)
			(xy 386.076197 -223.323154) (xy 386.060129 -223.376561) (xy 386.036457 -223.427058) (xy 386.005684 -223.473571)
			(xy 385.968467 -223.515108) (xy 385.925599 -223.550783) (xy 385.877993 -223.579837) (xy 385.826664 -223.601649)
			(xy 385.772707 -223.615755) (xy 385.71727 -223.621855) (xy 385.661536 -223.619818) (xy 385.606693 -223.609688)
			(xy 385.553909 -223.591681) (xy 385.504309 -223.56618) (xy 385.458951 -223.533729) (xy 385.418802 -223.49502)
			(xy 385.384716 -223.450877) (xy 385.35742 -223.402242) (xy 385.337497 -223.350151) (xy 385.325371 -223.295714)
			(xy 385.3213 -223.240092) (xy 378.341277 -223.240092) (xy 378.320191 -223.285072) (xy 378.289418 -223.331585)
			(xy 378.252201 -223.373122) (xy 378.209333 -223.408797) (xy 378.161727 -223.437851) (xy 378.110398 -223.459663)
			(xy 378.056441 -223.473769) (xy 378.001004 -223.479869) (xy 377.94527 -223.477832) (xy 377.890427 -223.467702)
			(xy 377.837643 -223.449695) (xy 377.788043 -223.424194) (xy 377.742685 -223.391743) (xy 377.702536 -223.353034)
			(xy 377.66845 -223.308891) (xy 377.641154 -223.260256) (xy 377.621231 -223.208165) (xy 377.609105 -223.153728)
			(xy 377.605034 -223.098106) (xy 374.658028 -223.098106) (xy 374.640161 -223.113587) (xy 374.594311 -223.143053)
			(xy 374.544734 -223.165695) (xy 374.492439 -223.18105) (xy 374.438491 -223.188806) (xy 374.383989 -223.188806)
			(xy 374.330041 -223.18105) (xy 374.277746 -223.165695) (xy 374.228169 -223.143053) (xy 374.182319 -223.113587)
			(xy 374.141128 -223.077896) (xy 374.105437 -223.036705) (xy 374.075971 -222.990855) (xy 374.053329 -222.941278)
			(xy 374.037974 -222.888983) (xy 374.030218 -222.835035) (xy 374.029732 -222.807784) (xy 374.030177 -222.78092)
			(xy 374.037729 -222.727724) (xy 374.052665 -222.676113) (xy 374.074692 -222.627106) (xy 374.103374 -222.581673)
			(xy 374.12041 -222.560896) (xy 374.12803 -222.552006) (xy 374.133872 -222.5294) (xy 374.113298 -222.428054)
			(xy 374.099074 -222.409512) (xy 374.088914 -222.404432) (xy 374.06562 -222.392173) (xy 374.022345 -222.362205)
			(xy 373.983599 -222.326575) (xy 373.950117 -222.285957) (xy 373.922535 -222.241124) (xy 373.901377 -222.192925)
			(xy 373.887043 -222.142276) (xy 373.879807 -222.090137) (xy 373.879364 -222.063818) (xy 366.0961 -222.063818)
			(xy 366.089125 -222.087003) (xy 366.065453 -222.1375) (xy 366.03468 -222.184013) (xy 365.997463 -222.22555)
			(xy 365.954595 -222.261225) (xy 365.906989 -222.290279) (xy 365.85566 -222.312091) (xy 365.801703 -222.326197)
			(xy 365.746266 -222.332297) (xy 365.690532 -222.33026) (xy 365.635689 -222.32013) (xy 365.582905 -222.302123)
			(xy 365.533305 -222.276622) (xy 365.487947 -222.244171) (xy 365.447798 -222.205462) (xy 365.413712 -222.161319)
			(xy 365.386416 -222.112684) (xy 365.366493 -222.060593) (xy 365.354367 -222.006156) (xy 365.350296 -221.950534)
			(xy 364.811053 -221.950534) (xy 364.834061 -221.98531) (xy 364.857733 -222.035807) (xy 364.873801 -222.089214)
			(xy 364.881921 -222.14439) (xy 364.88243 -222.172276) (xy 364.881921 -222.200162) (xy 364.873801 -222.255338)
			(xy 364.857733 -222.308745) (xy 364.834061 -222.359242) (xy 364.803288 -222.405755) (xy 364.766071 -222.447292)
			(xy 364.723203 -222.482967) (xy 364.675597 -222.512021) (xy 364.624268 -222.533833) (xy 364.570311 -222.547939)
			(xy 364.514874 -222.554039) (xy 364.45914 -222.552002) (xy 364.404297 -222.541872) (xy 364.351513 -222.523865)
			(xy 364.301913 -222.498364) (xy 364.256555 -222.465913) (xy 364.216406 -222.427204) (xy 364.18232 -222.383061)
			(xy 364.155024 -222.334426) (xy 364.135101 -222.282335) (xy 364.122975 -222.227898) (xy 364.118904 -222.172276)
			(xy 359.216818 -222.172276) (xy 359.251281 -222.193309) (xy 359.294149 -222.228984) (xy 359.331366 -222.270521)
			(xy 359.362139 -222.317034) (xy 359.385811 -222.367531) (xy 359.401879 -222.420938) (xy 359.409999 -222.476114)
			(xy 359.410508 -222.504) (xy 359.409999 -222.531886) (xy 359.401879 -222.587062) (xy 359.385811 -222.640469)
			(xy 359.362139 -222.690966) (xy 359.331366 -222.737479) (xy 359.294149 -222.779016) (xy 359.251281 -222.814691)
			(xy 359.203675 -222.843745) (xy 359.152346 -222.865557) (xy 359.098389 -222.879663) (xy 359.042952 -222.885763)
			(xy 358.987218 -222.883726) (xy 358.932375 -222.873596) (xy 358.879591 -222.855589) (xy 358.829991 -222.830088)
			(xy 358.784633 -222.797637) (xy 358.744484 -222.758928) (xy 358.710398 -222.714785) (xy 358.683102 -222.66615)
			(xy 358.663179 -222.614059) (xy 358.651053 -222.559622) (xy 358.646982 -222.504) (xy 356.498906 -222.504)
			(xy 356.498478 -222.530315) (xy 356.491418 -222.582469) (xy 356.477426 -222.633204) (xy 356.456755 -222.681605)
			(xy 356.429779 -222.726795) (xy 356.396984 -222.767958) (xy 356.378256 -222.786448) (xy 356.376986 -222.789496)
			(xy 356.373176 -222.798894) (xy 356.373176 -223.52) (xy 356.614982 -223.52) (xy 356.619053 -223.464378)
			(xy 356.631179 -223.409941) (xy 356.651102 -223.35785) (xy 356.678398 -223.309215) (xy 356.712484 -223.265072)
			(xy 356.752633 -223.226363) (xy 356.797991 -223.193912) (xy 356.847591 -223.168411) (xy 356.900375 -223.150404)
			(xy 356.955218 -223.140274) (xy 357.010952 -223.138237) (xy 357.066389 -223.144337) (xy 357.120346 -223.158443)
			(xy 357.171675 -223.180255) (xy 357.219281 -223.209309) (xy 357.262149 -223.244984) (xy 357.299366 -223.286521)
			(xy 357.330139 -223.333034) (xy 357.353811 -223.383531) (xy 357.356736 -223.393254) (xy 359.73842 -223.393254)
			(xy 359.742491 -223.337632) (xy 359.754617 -223.283195) (xy 359.77454 -223.231104) (xy 359.801836 -223.182469)
			(xy 359.835922 -223.138326) (xy 359.876071 -223.099617) (xy 359.921429 -223.067166) (xy 359.971029 -223.041665)
			(xy 360.023813 -223.023658) (xy 360.078656 -223.013528) (xy 360.13439 -223.011491) (xy 360.189827 -223.017591)
			(xy 360.243784 -223.031697) (xy 360.295113 -223.053509) (xy 360.342719 -223.082563) (xy 360.385587 -223.118238)
			(xy 360.422804 -223.159775) (xy 360.453577 -223.206288) (xy 360.477249 -223.256785) (xy 360.493317 -223.310192)
			(xy 360.501437 -223.365368) (xy 360.501946 -223.393254) (xy 360.501437 -223.42114) (xy 360.493317 -223.476316)
			(xy 360.477249 -223.529723) (xy 360.453577 -223.58022) (xy 360.422804 -223.626733) (xy 360.385587 -223.66827)
			(xy 360.342719 -223.703945) (xy 360.295113 -223.732999) (xy 360.243784 -223.754811) (xy 360.189827 -223.768917)
			(xy 360.13439 -223.775017) (xy 360.078656 -223.77298) (xy 360.023813 -223.76285) (xy 359.971029 -223.744843)
			(xy 359.921429 -223.719342) (xy 359.876071 -223.686891) (xy 359.835922 -223.648182) (xy 359.801836 -223.604039)
			(xy 359.77454 -223.555404) (xy 359.754617 -223.503313) (xy 359.742491 -223.448876) (xy 359.73842 -223.393254)
			(xy 357.356736 -223.393254) (xy 357.369879 -223.436938) (xy 357.377999 -223.492114) (xy 357.378508 -223.52)
			(xy 357.377999 -223.547886) (xy 357.369879 -223.603062) (xy 357.353811 -223.656469) (xy 357.330139 -223.706966)
			(xy 357.299366 -223.753479) (xy 357.262149 -223.795016) (xy 357.219281 -223.830691) (xy 357.171675 -223.859745)
			(xy 357.120346 -223.881557) (xy 357.066389 -223.895663) (xy 357.010952 -223.901763) (xy 356.955218 -223.899726)
			(xy 356.900375 -223.889596) (xy 356.847591 -223.871589) (xy 356.797991 -223.846088) (xy 356.752633 -223.813637)
			(xy 356.712484 -223.774928) (xy 356.678398 -223.730785) (xy 356.651102 -223.68215) (xy 356.631179 -223.630059)
			(xy 356.619053 -223.575622) (xy 356.614982 -223.52) (xy 356.373176 -223.52) (xy 356.373176 -224.067116)
			(xy 376.189746 -224.067116) (xy 376.193817 -224.011494) (xy 376.205943 -223.957057) (xy 376.225866 -223.904966)
			(xy 376.253162 -223.856331) (xy 376.287248 -223.812188) (xy 376.327397 -223.773479) (xy 376.372755 -223.741028)
			(xy 376.422355 -223.715527) (xy 376.475139 -223.69752) (xy 376.529982 -223.68739) (xy 376.585716 -223.685353)
			(xy 376.641153 -223.691453) (xy 376.69511 -223.705559) (xy 376.746439 -223.727371) (xy 376.794045 -223.756425)
			(xy 376.836913 -223.7921) (xy 376.87413 -223.833637) (xy 376.904903 -223.88015) (xy 376.928575 -223.930647)
			(xy 376.944643 -223.984054) (xy 376.952763 -224.03923) (xy 376.953272 -224.067116) (xy 376.952763 -224.095002)
			(xy 376.944643 -224.150178) (xy 376.928575 -224.203585) (xy 376.904903 -224.254082) (xy 376.87413 -224.300595)
			(xy 376.836913 -224.342132) (xy 376.794045 -224.377807) (xy 376.746439 -224.406861) (xy 376.69511 -224.428673)
			(xy 376.641153 -224.442779) (xy 376.585716 -224.448879) (xy 376.529982 -224.446842) (xy 376.475139 -224.436712)
			(xy 376.422355 -224.418705) (xy 376.372755 -224.393204) (xy 376.327397 -224.360753) (xy 376.287248 -224.322044)
			(xy 376.253162 -224.277901) (xy 376.225866 -224.229266) (xy 376.205943 -224.177175) (xy 376.193817 -224.122738)
			(xy 376.189746 -224.067116) (xy 356.373176 -224.067116) (xy 356.373176 -224.231962) (xy 356.373176 -224.23501)
			(xy 356.373504 -224.238645) (xy 356.375038 -224.245782) (xy 356.376224 -224.249234) (xy 356.377748 -224.253044)
			(xy 356.396539 -224.271556) (xy 356.429476 -224.312759) (xy 356.456571 -224.358017) (xy 356.477333 -224.406509)
			(xy 356.491382 -224.457353) (xy 356.498464 -224.509625) (xy 356.498906 -224.536) (xy 358.646982 -224.536)
			(xy 358.651053 -224.480378) (xy 358.663179 -224.425941) (xy 358.683102 -224.37385) (xy 358.710398 -224.325215)
			(xy 358.744484 -224.281072) (xy 358.784633 -224.242363) (xy 358.829991 -224.209912) (xy 358.879591 -224.184411)
			(xy 358.932375 -224.166404) (xy 358.987218 -224.156274) (xy 359.042952 -224.154237) (xy 359.098389 -224.160337)
			(xy 359.152346 -224.174443) (xy 359.203675 -224.196255) (xy 359.251281 -224.225309) (xy 359.294149 -224.260984)
			(xy 359.331366 -224.302521) (xy 359.362139 -224.349034) (xy 359.385811 -224.399531) (xy 359.401879 -224.452938)
			(xy 359.409999 -224.508114) (xy 359.410508 -224.536) (xy 359.409999 -224.563886) (xy 359.401879 -224.619062)
			(xy 359.385811 -224.672469) (xy 359.362139 -224.722966) (xy 359.331366 -224.769479) (xy 359.294149 -224.811016)
			(xy 359.251281 -224.846691) (xy 359.203675 -224.875745) (xy 359.152346 -224.897557) (xy 359.098389 -224.911663)
			(xy 359.042952 -224.917763) (xy 358.987218 -224.915726) (xy 358.932375 -224.905596) (xy 358.879591 -224.887589)
			(xy 358.829991 -224.862088) (xy 358.784633 -224.829637) (xy 358.744484 -224.790928) (xy 358.710398 -224.746785)
			(xy 358.683102 -224.69815) (xy 358.663179 -224.646059) (xy 358.651053 -224.591622) (xy 358.646982 -224.536)
			(xy 356.498906 -224.536) (xy 356.498478 -224.562315) (xy 356.491418 -224.614469) (xy 356.477426 -224.665204)
			(xy 356.456755 -224.713605) (xy 356.429779 -224.758795) (xy 356.396984 -224.799958) (xy 356.378256 -224.818448)
			(xy 356.376986 -224.821496) (xy 356.373176 -224.830894) (xy 356.373176 -224.994978) (xy 376.095512 -224.994978)
			(xy 376.099583 -224.939356) (xy 376.111709 -224.884919) (xy 376.131632 -224.832828) (xy 376.158928 -224.784193)
			(xy 376.193014 -224.74005) (xy 376.233163 -224.701341) (xy 376.278521 -224.66889) (xy 376.328121 -224.643389)
			(xy 376.380905 -224.625382) (xy 376.435748 -224.615252) (xy 376.491482 -224.613215) (xy 376.546919 -224.619315)
			(xy 376.600876 -224.633421) (xy 376.652205 -224.655233) (xy 376.699811 -224.684287) (xy 376.742679 -224.719962)
			(xy 376.779896 -224.761499) (xy 376.810669 -224.808012) (xy 376.834341 -224.858509) (xy 376.850409 -224.911916)
			(xy 376.858529 -224.967092) (xy 376.859038 -224.994978) (xy 376.858529 -225.022864) (xy 376.850409 -225.07804)
			(xy 376.834341 -225.131447) (xy 376.810669 -225.181944) (xy 376.779896 -225.228457) (xy 376.742679 -225.269994)
			(xy 376.699811 -225.305669) (xy 376.652205 -225.334723) (xy 376.600876 -225.356535) (xy 376.546919 -225.370641)
			(xy 376.491482 -225.376741) (xy 376.435748 -225.374704) (xy 376.380905 -225.364574) (xy 376.328121 -225.346567)
			(xy 376.278521 -225.321066) (xy 376.233163 -225.288615) (xy 376.193014 -225.249906) (xy 376.158928 -225.205763)
			(xy 376.131632 -225.157128) (xy 376.111709 -225.105037) (xy 376.099583 -225.0506) (xy 376.095512 -224.994978)
			(xy 356.373176 -224.994978) (xy 356.373176 -225.552) (xy 356.614982 -225.552) (xy 356.619053 -225.496378)
			(xy 356.631179 -225.441941) (xy 356.651102 -225.38985) (xy 356.678398 -225.341215) (xy 356.712484 -225.297072)
			(xy 356.752633 -225.258363) (xy 356.797991 -225.225912) (xy 356.847591 -225.200411) (xy 356.900375 -225.182404)
			(xy 356.955218 -225.172274) (xy 357.010952 -225.170237) (xy 357.066389 -225.176337) (xy 357.120346 -225.190443)
			(xy 357.171675 -225.212255) (xy 357.219281 -225.241309) (xy 357.262149 -225.276984) (xy 357.299366 -225.318521)
			(xy 357.330139 -225.365034) (xy 357.353811 -225.415531) (xy 357.369879 -225.468938) (xy 357.377999 -225.524114)
			(xy 357.378508 -225.552) (xy 358.646982 -225.552) (xy 358.651053 -225.496378) (xy 358.663179 -225.441941)
			(xy 358.683102 -225.38985) (xy 358.710398 -225.341215) (xy 358.744484 -225.297072) (xy 358.784633 -225.258363)
			(xy 358.829991 -225.225912) (xy 358.879591 -225.200411) (xy 358.932375 -225.182404) (xy 358.987218 -225.172274)
			(xy 359.042952 -225.170237) (xy 359.098389 -225.176337) (xy 359.152346 -225.190443) (xy 359.203675 -225.212255)
			(xy 359.251281 -225.241309) (xy 359.294149 -225.276984) (xy 359.331366 -225.318521) (xy 359.362139 -225.365034)
			(xy 359.385811 -225.415531) (xy 359.401879 -225.468938) (xy 359.409999 -225.524114) (xy 359.410508 -225.552)
			(xy 359.410355 -225.560382) (xy 368.588796 -225.560382) (xy 368.592867 -225.50476) (xy 368.604993 -225.450323)
			(xy 368.624916 -225.398232) (xy 368.652212 -225.349597) (xy 368.686298 -225.305454) (xy 368.726447 -225.266745)
			(xy 368.771805 -225.234294) (xy 368.821405 -225.208793) (xy 368.874189 -225.190786) (xy 368.929032 -225.180656)
			(xy 368.984766 -225.178619) (xy 369.040203 -225.184719) (xy 369.09416 -225.198825) (xy 369.145489 -225.220637)
			(xy 369.193095 -225.249691) (xy 369.235963 -225.285366) (xy 369.27318 -225.326903) (xy 369.303953 -225.373416)
			(xy 369.327625 -225.423913) (xy 369.343693 -225.47732) (xy 369.351813 -225.532496) (xy 369.352322 -225.560382)
			(xy 369.351813 -225.588268) (xy 369.343693 -225.643444) (xy 369.327625 -225.696851) (xy 369.303953 -225.747348)
			(xy 369.27318 -225.793861) (xy 369.235963 -225.835398) (xy 369.193095 -225.871073) (xy 369.145489 -225.900127)
			(xy 369.09416 -225.921939) (xy 369.040203 -225.936045) (xy 368.984766 -225.942145) (xy 368.929032 -225.940108)
			(xy 368.874189 -225.929978) (xy 368.821405 -225.911971) (xy 368.771805 -225.88647) (xy 368.726447 -225.854019)
			(xy 368.686298 -225.81531) (xy 368.652212 -225.771167) (xy 368.624916 -225.722532) (xy 368.604993 -225.670441)
			(xy 368.592867 -225.616004) (xy 368.588796 -225.560382) (xy 359.410355 -225.560382) (xy 359.409999 -225.579886)
			(xy 359.401879 -225.635062) (xy 359.385811 -225.688469) (xy 359.362139 -225.738966) (xy 359.331366 -225.785479)
			(xy 359.294149 -225.827016) (xy 359.251281 -225.862691) (xy 359.203675 -225.891745) (xy 359.152346 -225.913557)
			(xy 359.098389 -225.927663) (xy 359.042952 -225.933763) (xy 358.987218 -225.931726) (xy 358.932375 -225.921596)
			(xy 358.879591 -225.903589) (xy 358.829991 -225.878088) (xy 358.784633 -225.845637) (xy 358.744484 -225.806928)
			(xy 358.710398 -225.762785) (xy 358.683102 -225.71415) (xy 358.663179 -225.662059) (xy 358.651053 -225.607622)
			(xy 358.646982 -225.552) (xy 357.378508 -225.552) (xy 357.377999 -225.579886) (xy 357.369879 -225.635062)
			(xy 357.353811 -225.688469) (xy 357.330139 -225.738966) (xy 357.299366 -225.785479) (xy 357.262149 -225.827016)
			(xy 357.219281 -225.862691) (xy 357.171675 -225.891745) (xy 357.120346 -225.913557) (xy 357.066389 -225.927663)
			(xy 357.010952 -225.933763) (xy 356.955218 -225.931726) (xy 356.900375 -225.921596) (xy 356.847591 -225.903589)
			(xy 356.797991 -225.878088) (xy 356.752633 -225.845637) (xy 356.712484 -225.806928) (xy 356.678398 -225.762785)
			(xy 356.651102 -225.71415) (xy 356.631179 -225.662059) (xy 356.619053 -225.607622) (xy 356.614982 -225.552)
			(xy 356.373176 -225.552) (xy 356.373176 -226.268534) (xy 356.373325 -226.274402) (xy 356.376019 -226.285825)
			(xy 356.37851 -226.29114) (xy 356.38613 -226.30638) (xy 356.390956 -226.311714) (xy 356.409457 -226.332885)
			(xy 356.44068 -226.379641) (xy 356.464708 -226.43047) (xy 356.481022 -226.484274) (xy 356.489268 -226.539889)
			(xy 356.489762 -226.568) (xy 358.646982 -226.568) (xy 358.651053 -226.512378) (xy 358.663179 -226.457941)
			(xy 358.683102 -226.40585) (xy 358.710398 -226.357215) (xy 358.744484 -226.313072) (xy 358.784633 -226.274363)
			(xy 358.829991 -226.241912) (xy 358.879591 -226.216411) (xy 358.932375 -226.198404) (xy 358.987218 -226.188274)
			(xy 359.042952 -226.186237) (xy 359.098389 -226.192337) (xy 359.152346 -226.206443) (xy 359.203675 -226.228255)
			(xy 359.251281 -226.257309) (xy 359.294149 -226.292984) (xy 359.331366 -226.334521) (xy 359.362139 -226.381034)
			(xy 359.385811 -226.431531) (xy 359.401879 -226.484938) (xy 359.409999 -226.540114) (xy 359.410309 -226.557078)
			(xy 365.688624 -226.557078) (xy 365.692695 -226.501456) (xy 365.704821 -226.447019) (xy 365.724744 -226.394928)
			(xy 365.75204 -226.346293) (xy 365.786126 -226.30215) (xy 365.826275 -226.263441) (xy 365.871633 -226.23099)
			(xy 365.921233 -226.205489) (xy 365.974017 -226.187482) (xy 366.02886 -226.177352) (xy 366.084594 -226.175315)
			(xy 366.140031 -226.181415) (xy 366.193988 -226.195521) (xy 366.245317 -226.217333) (xy 366.292923 -226.246387)
			(xy 366.335791 -226.282062) (xy 366.373008 -226.323599) (xy 366.403781 -226.370112) (xy 366.427453 -226.420609)
			(xy 366.443521 -226.474016) (xy 366.451641 -226.529192) (xy 366.45215 -226.557078) (xy 366.451641 -226.584964)
			(xy 366.443521 -226.64014) (xy 366.427453 -226.693547) (xy 366.403781 -226.744044) (xy 366.373008 -226.790557)
			(xy 366.335791 -226.832094) (xy 366.292923 -226.867769) (xy 366.245317 -226.896823) (xy 366.193988 -226.918635)
			(xy 366.140031 -226.932741) (xy 366.084594 -226.938841) (xy 366.02886 -226.936804) (xy 365.974017 -226.926674)
			(xy 365.921233 -226.908667) (xy 365.871633 -226.883166) (xy 365.826275 -226.850715) (xy 365.786126 -226.812006)
			(xy 365.75204 -226.767863) (xy 365.724744 -226.719228) (xy 365.704821 -226.667137) (xy 365.692695 -226.6127)
			(xy 365.688624 -226.557078) (xy 359.410309 -226.557078) (xy 359.410508 -226.568) (xy 359.409999 -226.595886)
			(xy 359.401879 -226.651062) (xy 359.385811 -226.704469) (xy 359.362139 -226.754966) (xy 359.331366 -226.801479)
			(xy 359.294149 -226.843016) (xy 359.251281 -226.878691) (xy 359.203675 -226.907745) (xy 359.152346 -226.929557)
			(xy 359.098389 -226.943663) (xy 359.042952 -226.949763) (xy 358.987218 -226.947726) (xy 358.932375 -226.937596)
			(xy 358.879591 -226.919589) (xy 358.829991 -226.894088) (xy 358.784633 -226.861637) (xy 358.744484 -226.822928)
			(xy 358.710398 -226.778785) (xy 358.683102 -226.73015) (xy 358.663179 -226.678059) (xy 358.651053 -226.623622)
			(xy 358.646982 -226.568) (xy 356.489762 -226.568) (xy 356.489762 -226.568254) (xy 356.489285 -226.594833)
			(xy 356.481896 -226.647475) (xy 356.47503 -226.673156) (xy 356.472998 -226.680014) (xy 356.471728 -226.685602)
			(xy 356.470231 -226.694427) (xy 356.472834 -226.712125) (xy 356.476808 -226.720146) (xy 356.479856 -226.724972)
			(xy 356.485444 -226.731576) (xy 356.940866 -227.186998) (xy 356.9462 -227.192586) (xy 356.966266 -227.203254)
			(xy 356.980236 -227.202492) (xy 356.996238 -227.202238) (xy 356.997254 -227.202238) (xy 357.0245 -227.202741)
			(xy 357.078434 -227.210525) (xy 357.130713 -227.2259) (xy 357.180274 -227.248552) (xy 357.226111 -227.278021)
			(xy 357.267291 -227.313709) (xy 357.302979 -227.354889) (xy 357.332448 -227.400726) (xy 357.3551 -227.450287)
			(xy 357.370475 -227.502566) (xy 357.378259 -227.5565) (xy 357.378762 -227.583746) (xy 357.378762 -227.584)
			(xy 359.556556 -227.584) (xy 359.560627 -227.528378) (xy 359.572753 -227.473941) (xy 359.592676 -227.42185)
			(xy 359.619972 -227.373215) (xy 359.654058 -227.329072) (xy 359.694207 -227.290363) (xy 359.739565 -227.257912)
			(xy 359.789165 -227.232411) (xy 359.841949 -227.214404) (xy 359.896792 -227.204274) (xy 359.952526 -227.202237)
			(xy 360.007963 -227.208337) (xy 360.06192 -227.222443) (xy 360.113249 -227.244255) (xy 360.160855 -227.273309)
			(xy 360.203723 -227.308984) (xy 360.24094 -227.350521) (xy 360.271713 -227.397034) (xy 360.295385 -227.447531)
			(xy 360.311453 -227.500938) (xy 360.319573 -227.556114) (xy 360.320082 -227.584) (xy 360.319573 -227.611886)
			(xy 360.311453 -227.667062) (xy 360.295385 -227.720469) (xy 360.271713 -227.770966) (xy 360.24094 -227.817479)
			(xy 360.203723 -227.859016) (xy 360.160855 -227.894691) (xy 360.113249 -227.923745) (xy 360.06192 -227.945557)
			(xy 360.007963 -227.959663) (xy 359.952526 -227.965763) (xy 359.896792 -227.963726) (xy 359.841949 -227.953596)
			(xy 359.789165 -227.935589) (xy 359.739565 -227.910088) (xy 359.694207 -227.877637) (xy 359.654058 -227.838928)
			(xy 359.619972 -227.794785) (xy 359.592676 -227.74615) (xy 359.572753 -227.694059) (xy 359.560627 -227.639622)
			(xy 359.556556 -227.584) (xy 357.378762 -227.584) (xy 357.378762 -227.584762) (xy 357.378508 -227.600764)
			(xy 357.377746 -227.614734) (xy 357.387144 -227.63226) (xy 357.39197 -227.638102) (xy 358.46512 -228.711252)
			(xy 358.470801 -228.716441) (xy 358.484508 -228.723412) (xy 358.492044 -228.724968) (xy 358.492552 -228.724968)
			(xy 358.50068 -228.72573) (xy 358.539542 -228.72573) (xy 358.544597 -228.725462) (xy 358.554453 -228.723164)
			(xy 358.5591 -228.721158) (xy 358.598216 -228.701854) (xy 358.59847 -228.701854) (xy 358.626156 -228.688138)
			(xy 358.63149 -228.683566) (xy 358.63732 -228.678145) (xy 358.645601 -228.664562) (xy 358.647746 -228.656896)
			(xy 358.649778 -228.648768) (xy 358.64927 -228.639624) (xy 358.649016 -228.63683) (xy 358.647492 -228.600762)
			(xy 358.647492 -228.599746) (xy 358.647995 -228.572507) (xy 358.655781 -228.518586) (xy 358.671158 -228.466322)
			(xy 358.693814 -228.416777) (xy 358.723287 -228.370958) (xy 358.758978 -228.329798) (xy 358.800162 -228.294134)
			(xy 358.846 -228.264692) (xy 358.89556 -228.242069) (xy 358.947835 -228.226727) (xy 359.00176 -228.218977)
			(xy 359.029 -228.218492) (xy 359.056251 -228.218978) (xy 359.110199 -228.226734) (xy 359.162494 -228.242089)
			(xy 359.212071 -228.264731) (xy 359.257921 -228.294197) (xy 359.299112 -228.329888) (xy 359.334803 -228.371079)
			(xy 359.364269 -228.416929) (xy 359.386911 -228.466506) (xy 359.402266 -228.518801) (xy 359.410022 -228.572749)
			(xy 359.410022 -228.627251) (xy 359.402266 -228.681199) (xy 359.386911 -228.733494) (xy 359.364269 -228.783071)
			(xy 359.334803 -228.828921) (xy 359.299112 -228.870112) (xy 359.257921 -228.905803) (xy 359.212071 -228.935269)
			(xy 359.162494 -228.957911) (xy 359.110199 -228.973266) (xy 359.056251 -228.981022) (xy 359.029 -228.981508)
			(xy 359.025952 -228.981508) (xy 359.025444 -228.981508) (xy 358.98836 -228.97973) (xy 358.986074 -228.979476)
			(xy 358.982518 -228.979476) (xy 358.975477 -228.979695) (xy 358.961935 -228.983552) (xy 358.955848 -228.987096)
			(xy 358.95026 -228.990906) (xy 358.945942 -228.995732) (xy 358.943379 -228.998543) (xy 358.939041 -229.004792)
			(xy 358.937306 -229.008178) (xy 358.905302 -229.075234) (xy 358.895396 -229.096062) (xy 358.891719 -229.105557)
			(xy 358.891446 -229.1259) (xy 358.899139 -229.144733) (xy 358.906064 -229.152196) (xy 358.972866 -229.218998)
			(xy 358.9782 -229.224586) (xy 358.998266 -229.235254) (xy 359.01249 -229.234746) (xy 359.023666 -229.234492)
			(xy 359.02773 -229.234492) (xy 359.029254 -229.234492) (xy 359.056482 -229.234994) (xy 359.11038 -229.242774)
			(xy 359.162624 -229.258138) (xy 359.212152 -229.280775) (xy 359.257958 -229.310224) (xy 359.299112 -229.345888)
			(xy 359.334776 -229.387042) (xy 359.364225 -229.432848) (xy 359.386862 -229.482376) (xy 359.402226 -229.53462)
			(xy 359.410006 -229.588518) (xy 359.410508 -229.615746) (xy 359.410508 -229.623366) (xy 359.410254 -229.628954)
			(xy 359.410254 -229.635304) (xy 359.41071 -229.645183) (xy 359.418145 -229.663489) (xy 359.424732 -229.670864)
			(xy 359.698798 -229.94493) (xy 361.108242 -229.94493) (xy 361.112313 -229.889308) (xy 361.124439 -229.834871)
			(xy 361.144362 -229.78278) (xy 361.171658 -229.734145) (xy 361.205744 -229.690002) (xy 361.245893 -229.651293)
			(xy 361.291251 -229.618842) (xy 361.340851 -229.593341) (xy 361.393635 -229.575334) (xy 361.448478 -229.565204)
			(xy 361.504212 -229.563167) (xy 361.559649 -229.569267) (xy 361.613606 -229.583373) (xy 361.664935 -229.605185)
			(xy 361.712541 -229.634239) (xy 361.755409 -229.669914) (xy 361.792626 -229.711451) (xy 361.823399 -229.757964)
			(xy 361.847071 -229.808461) (xy 361.863139 -229.861868) (xy 361.871259 -229.917044) (xy 361.871768 -229.94493)
			(xy 361.871259 -229.972816) (xy 361.863139 -230.027992) (xy 361.847071 -230.081399) (xy 361.823399 -230.131896)
			(xy 361.792626 -230.178409) (xy 361.755409 -230.219946) (xy 361.712541 -230.255621) (xy 361.664935 -230.284675)
			(xy 361.613606 -230.306487) (xy 361.559649 -230.320593) (xy 361.504212 -230.326693) (xy 361.448478 -230.324656)
			(xy 361.393635 -230.314526) (xy 361.340851 -230.296519) (xy 361.291251 -230.271018) (xy 361.245893 -230.238567)
			(xy 361.205744 -230.199858) (xy 361.171658 -230.155715) (xy 361.144362 -230.10708) (xy 361.124439 -230.054989)
			(xy 361.112313 -230.000552) (xy 361.108242 -229.94493) (xy 359.698798 -229.94493) (xy 359.958894 -230.205026)
			(xy 359.969308 -230.20909) (xy 359.979468 -230.2129) (xy 359.99039 -230.212392) (xy 360.013504 -230.21163)
			(xy 360.040773 -230.212117) (xy 360.094757 -230.219879) (xy 360.147086 -230.235244) (xy 360.196697 -230.257901)
			(xy 360.242578 -230.287387) (xy 360.283795 -230.323102) (xy 360.319511 -230.364319) (xy 360.348997 -230.4102)
			(xy 360.371654 -230.45981) (xy 360.38702 -230.512139) (xy 360.394783 -230.566123) (xy 360.395266 -230.593392)
			(xy 360.395266 -230.5939) (xy 360.395012 -230.601266) (xy 360.395012 -230.601774) (xy 360.394758 -230.605584)
			(xy 360.394758 -230.608124) (xy 360.394504 -230.611934) (xy 360.394504 -230.619554) (xy 360.394971 -230.629428)
			(xy 360.402423 -230.647717) (xy 360.408982 -230.655114) (xy 360.938064 -231.184196) (xy 360.94374 -231.189396)
			(xy 360.957443 -231.19639) (xy 360.964988 -231.197912) (xy 360.965496 -231.197912) (xy 360.973624 -231.198674)
			(xy 360.989372 -231.198674) (xy 360.999423 -231.199178) (xy 361.017986 -231.206898) (xy 361.02544 -231.21366)
			(xy 361.233212 -231.421432) (xy 361.238892 -231.426623) (xy 361.252598 -231.4336) (xy 361.260136 -231.435148)
			(xy 361.260644 -231.435148) (xy 361.268772 -231.43591) (xy 361.75823 -231.43591) (xy 361.773725 -231.435314)
			(xy 361.803267 -231.42594) (xy 361.828648 -231.408153) (xy 361.847542 -231.383584) (xy 361.858214 -231.354486)
			(xy 361.859687 -231.323528) (xy 361.856274 -231.308402) (xy 361.850475 -231.284758) (xy 361.844234 -231.236477)
			(xy 361.843828 -231.212136) (xy 361.843828 -231.211374) (xy 361.844316 -231.184106) (xy 361.852081 -231.130124)
			(xy 361.867448 -231.077797) (xy 361.890106 -231.02819) (xy 361.919592 -230.982311) (xy 361.955307 -230.941096)
			(xy 361.996524 -230.905383) (xy 362.042404 -230.875898) (xy 362.092012 -230.853243) (xy 362.14434 -230.837877)
			(xy 362.198322 -230.830115) (xy 362.22559 -230.829612) (xy 362.252486 -230.830079) (xy 362.305743 -230.837649)
			(xy 362.357409 -230.852624) (xy 362.406459 -230.874709) (xy 362.45192 -230.903466) (xy 362.49289 -230.938323)
			(xy 362.511086 -230.958136) (xy 362.518668 -230.966773) (xy 362.532901 -230.984819) (xy 362.539534 -230.994204)
			(xy 362.540804 -230.995982) (xy 362.548932 -231.007412) (xy 362.551472 -231.010968) (xy 362.558838 -231.018334)
			(xy 362.564202 -231.023156) (xy 362.576972 -231.029846) (xy 362.583984 -231.031542) (xy 362.596938 -231.033574)
			(xy 362.609384 -231.031796) (xy 362.61421 -231.030272) (xy 362.621502 -231.027461) (xy 362.634044 -231.018149)
			(xy 362.638848 -231.011984) (xy 362.641896 -231.007412) (xy 362.646313 -230.998571) (xy 362.648784 -230.978979)
			(xy 362.646722 -230.969312) (xy 362.64342 -230.956866) (xy 362.640372 -230.952294) (xy 362.634784 -230.940102)
			(xy 362.631228 -230.932228) (xy 362.621126 -230.908059) (xy 362.606888 -230.857649) (xy 362.599676 -230.805765)
			(xy 362.599224 -230.779574) (xy 362.599224 -230.779066) (xy 362.599692 -230.752084) (xy 362.607294 -230.698657)
			(xy 362.622342 -230.646832) (xy 362.644536 -230.597643) (xy 362.673435 -230.552067) (xy 362.708461 -230.511014)
			(xy 362.748919 -230.475301) (xy 362.794001 -230.44564) (xy 362.84281 -230.42262) (xy 362.894374 -230.406702)
			(xy 362.947665 -230.398201) (xy 362.974636 -230.397304) (xy 362.975906 -230.397304) (xy 362.97997 -230.397304)
			(xy 362.98124 -230.397304) (xy 363.013156 -230.397987) (xy 363.076087 -230.40869) (xy 363.136356 -230.429723)
			(xy 363.164628 -230.444548) (xy 363.165136 -230.444802) (xy 363.170978 -230.44785) (xy 363.177582 -230.449628)
			(xy 363.189774 -230.451152) (xy 363.209586 -230.451152) (xy 363.217714 -230.45039) (xy 363.218222 -230.45039)
			(xy 363.225741 -230.44879) (xy 363.23943 -230.441815) (xy 363.245146 -230.436674) (xy 364.373668 -229.308152)
			(xy 364.378864 -229.302474) (xy 364.385852 -229.28877) (xy 364.387384 -229.281228) (xy 364.387384 -229.28072)
			(xy 364.388146 -229.272592) (xy 364.388146 -229.245922) (xy 364.388051 -229.242243) (xy 364.386907 -229.234972)
			(xy 364.38586 -229.231444) (xy 364.385352 -229.22992) (xy 364.385352 -229.229666) (xy 364.382812 -229.221792)
			(xy 364.377478 -229.214934) (xy 364.362373 -229.194804) (xy 364.337026 -229.151326) (xy 364.317617 -229.104891)
			(xy 364.304486 -229.056307) (xy 364.297858 -229.006418) (xy 364.297468 -228.981254) (xy 364.297468 -228.981)
			(xy 364.297932 -228.95373) (xy 364.305694 -228.899745) (xy 364.32106 -228.847414) (xy 364.343718 -228.797802)
			(xy 364.373206 -228.751921) (xy 364.408924 -228.710703) (xy 364.450145 -228.674988) (xy 364.496029 -228.645504)
			(xy 364.545642 -228.62285) (xy 364.597974 -228.607487) (xy 364.65196 -228.599729) (xy 364.67923 -228.599238)
			(xy 364.704234 -228.599621) (xy 364.753814 -228.60614) (xy 364.802116 -228.619088) (xy 364.848309 -228.638243)
			(xy 364.8916 -228.663275) (xy 364.91164 -228.678232) (xy 364.915704 -228.68128) (xy 364.919006 -228.68382)
			(xy 364.927388 -228.68636) (xy 364.927896 -228.686614) (xy 364.929928 -228.687122) (xy 364.942882 -228.6889)
			(xy 364.978442 -228.68763) (xy 364.986648 -228.686399) (xy 365.001683 -228.679403) (xy 365.007906 -228.673914)
			(xy 365.182658 -228.499162) (xy 365.187738 -228.49332) (xy 365.192056 -228.487478) (xy 365.200184 -228.46538)
			(xy 365.203232 -228.45268) (xy 365.204248 -228.441758) (xy 365.198152 -228.420168) (xy 365.194088 -228.412548)
			(xy 365.190024 -228.40442) (xy 365.177577 -228.378024) (xy 365.160025 -228.32237) (xy 365.151174 -228.264689)
			(xy 365.150654 -228.23551) (xy 365.150654 -228.22789) (xy 365.15162 -228.201119) (xy 365.160128 -228.148231)
			(xy 365.175951 -228.097052) (xy 365.198778 -228.04859) (xy 365.228159 -228.003798) (xy 365.263518 -227.963556)
			(xy 365.304158 -227.928656) (xy 365.34928 -227.899785) (xy 365.397997 -227.877509) (xy 365.449352 -227.862266)
			(xy 365.502334 -227.854358) (xy 365.529114 -227.853748) (xy 365.53013 -227.853748) (xy 365.534956 -227.853494)
			(xy 365.563654 -227.854215) (xy 365.620347 -227.863227) (xy 365.675046 -227.880646) (xy 365.72651 -227.906078)
			(xy 365.750348 -227.922074) (xy 365.754666 -227.925122) (xy 365.75873 -227.927154) (xy 365.764055 -227.929618)
			(xy 365.775471 -227.932316) (xy 365.781336 -227.932488) (xy 367.350294 -227.932488) (xy 367.363502 -227.93071)
			(xy 367.386616 -227.923344) (xy 367.392712 -227.91928) (xy 367.416331 -227.904148) (xy 367.467067 -227.880226)
			(xy 367.520758 -227.863986) (xy 367.576247 -227.855777) (xy 367.632341 -227.855777) (xy 367.68783 -227.863986)
			(xy 367.741521 -227.880226) (xy 367.792257 -227.904148) (xy 367.815876 -227.91928) (xy 367.821972 -227.923344)
			(xy 367.845086 -227.93071) (xy 367.858294 -227.932488) (xy 368.364262 -227.932488) (xy 368.368005 -227.932408)
			(xy 368.375403 -227.931261) (xy 368.378994 -227.930202) (xy 368.402108 -227.922836) (xy 368.408458 -227.918264)
			(xy 368.43044 -227.903525) (xy 368.477645 -227.879592) (xy 368.5277 -227.862399) (xy 368.579648 -227.852277)
			(xy 368.632496 -227.849418) (xy 368.658902 -227.851208) (xy 368.685913 -227.854001) (xy 368.738817 -227.866242)
			(xy 368.764312 -227.875592) (xy 368.785643 -227.884162) (xy 368.826267 -227.905682) (xy 368.845338 -227.918518)
			(xy 368.851434 -227.922836) (xy 368.873024 -227.929948) (xy 368.876859 -227.931107) (xy 368.884767 -227.932378)
			(xy 368.888772 -227.932488) (xy 369.079526 -227.932488) (xy 369.089529 -227.931995) (xy 369.10801 -227.924331)
			(xy 369.122152 -227.910178) (xy 369.129803 -227.891692) (xy 369.130326 -227.881688) (xy 369.130326 -227.856034)
			(xy 369.130188 -227.851144) (xy 369.128268 -227.841552) (xy 369.126516 -227.836984) (xy 369.12296 -227.828094)
			(xy 369.031266 -227.7364) (xy 369.025754 -227.732075) (xy 369.013002 -227.726285) (xy 369.00612 -227.72497)
			(xy 368.999262 -227.724462) (xy 367.860072 -227.724462) (xy 367.850005 -227.724033) (xy 367.831411 -227.716307)
			(xy 367.824004 -227.709476) (xy 367.725198 -227.61067) (xy 367.719102 -227.604828) (xy 367.03381 -226.919536)
			(xy 367.025936 -226.913186) (xy 367.010442 -226.904042) (xy 367.004854 -226.902264) (xy 366.979692 -226.893566)
			(xy 366.931868 -226.870173) (xy 366.887761 -226.840358) (xy 366.848229 -226.804699) (xy 366.814038 -226.76389)
			(xy 366.785855 -226.718723) (xy 366.764225 -226.670076) (xy 366.74957 -226.618894) (xy 366.742174 -226.566171)
			(xy 366.74171 -226.539552) (xy 366.7422 -226.512303) (xy 366.749962 -226.458362) (xy 366.765321 -226.406074)
			(xy 366.787965 -226.356504) (xy 366.817433 -226.310661) (xy 366.853125 -226.269478) (xy 366.894314 -226.233793)
			(xy 366.940162 -226.204334) (xy 366.989736 -226.181698) (xy 367.042027 -226.166348) (xy 367.095969 -226.158595)
			(xy 367.123218 -226.158044) (xy 367.150133 -226.158501) (xy 367.203428 -226.166059) (xy 367.255131 -226.181036)
			(xy 367.304215 -226.203135) (xy 367.349703 -226.231917) (xy 367.390692 -226.266809) (xy 367.426367 -226.307119)
			(xy 367.456019 -226.352044) (xy 367.479059 -226.400693) (xy 367.487454 -226.426268) (xy 367.48974 -226.433126)
			(xy 367.492788 -226.437952) (xy 367.49736 -226.444302) (xy 367.688622 -226.635564) (xy 368.077242 -227.024438)
			(xy 368.083238 -227.029675) (xy 368.097593 -227.036535) (xy 368.105436 -227.0379) (xy 368.105944 -227.0379)
			(xy 368.112294 -227.038408) (xy 369.250722 -227.038408) (xy 369.26079 -227.038835) (xy 369.279388 -227.046556)
			(xy 369.28679 -227.053394) (xy 369.308888 -227.075492) (xy 369.309396 -227.076) (xy 369.36299 -227.129594)
			(xy 369.369086 -227.135436) (xy 369.47729 -227.24364) (xy 369.47983 -227.24618) (xy 369.49115 -227.25531)
			(xy 369.517586 -227.267395) (xy 369.546357 -227.271543) (xy 369.57513 -227.267419) (xy 369.601577 -227.255357)
			(xy 369.623556 -227.236334) (xy 369.639286 -227.21189) (xy 369.647493 -227.184006) (xy 369.647978 -227.169472)
			(xy 369.647978 -226.675188) (xy 369.648098 -226.670234) (xy 369.650018 -226.660513) (xy 369.651788 -226.655884)
			(xy 369.655598 -226.64674) (xy 369.662456 -226.639882) (xy 369.662964 -226.639374) (xy 369.786662 -226.515676)
			(xy 369.791488 -226.510088) (xy 369.796154 -226.503347) (xy 369.801334 -226.487801) (xy 369.801648 -226.479608)
			(xy 369.801648 -225.94824) (xy 369.801479 -225.942723) (xy 369.799036 -225.931961) (xy 369.796822 -225.926904)
			(xy 369.795552 -225.924364) (xy 369.781709 -225.896793) (xy 369.762126 -225.838295) (xy 369.7522 -225.777409)
			(xy 369.75161 -225.746564) (xy 369.75161 -225.746056) (xy 369.75288 -225.715576) (xy 369.755694 -225.687253)
			(xy 369.768646 -225.631832) (xy 369.789683 -225.578947) (xy 369.818338 -225.529772) (xy 369.853977 -225.485396)
			(xy 369.895808 -225.446803) (xy 369.942906 -225.414848) (xy 369.994226 -225.39024) (xy 370.048631 -225.373523)
			(xy 370.104915 -225.365069) (xy 370.133372 -225.364548) (xy 370.159967 -225.365007) (xy 370.212641 -225.372391)
			(xy 370.263779 -225.387019) (xy 370.31239 -225.408609) (xy 370.35753 -225.43674) (xy 370.398326 -225.47087)
			(xy 370.433986 -225.510334) (xy 370.463819 -225.554369) (xy 370.487247 -225.602121) (xy 370.503815 -225.652664)
			(xy 370.513203 -225.705018) (xy 370.514626 -225.731578) (xy 370.515134 -225.743516) (xy 370.515134 -225.74631)
			(xy 370.514562 -225.777198) (xy 370.504658 -225.838175) (xy 370.485063 -225.89676) (xy 370.471192 -225.924364)
			(xy 370.469922 -225.926904) (xy 370.467709 -225.931961) (xy 370.465267 -225.942723) (xy 370.465096 -225.94824)
			(xy 370.465096 -226.324922) (xy 373.869964 -226.324922) (xy 373.874035 -226.2693) (xy 373.886161 -226.214863)
			(xy 373.906084 -226.162772) (xy 373.93338 -226.114137) (xy 373.967466 -226.069994) (xy 374.007615 -226.031285)
			(xy 374.052973 -225.998834) (xy 374.102573 -225.973333) (xy 374.155357 -225.955326) (xy 374.2102 -225.945196)
			(xy 374.265934 -225.943159) (xy 374.321371 -225.949259) (xy 374.375328 -225.963365) (xy 374.426657 -225.985177)
			(xy 374.474263 -226.014231) (xy 374.517131 -226.049906) (xy 374.554348 -226.091443) (xy 374.585121 -226.137956)
			(xy 374.608793 -226.188453) (xy 374.624861 -226.24186) (xy 374.632981 -226.297036) (xy 374.63349 -226.324922)
			(xy 374.632981 -226.352808) (xy 374.624861 -226.407984) (xy 374.608793 -226.461391) (xy 374.585121 -226.511888)
			(xy 374.554348 -226.558401) (xy 374.517131 -226.599938) (xy 374.474263 -226.635613) (xy 374.426657 -226.664667)
			(xy 374.375328 -226.686479) (xy 374.321371 -226.700585) (xy 374.265934 -226.706685) (xy 374.2102 -226.704648)
			(xy 374.155357 -226.694518) (xy 374.102573 -226.676511) (xy 374.052973 -226.65101) (xy 374.007615 -226.618559)
			(xy 373.967466 -226.57985) (xy 373.93338 -226.535707) (xy 373.906084 -226.487072) (xy 373.886161 -226.434981)
			(xy 373.874035 -226.380544) (xy 373.869964 -226.324922) (xy 370.465096 -226.324922) (xy 370.465096 -226.75469)
			(xy 370.464978 -226.759645) (xy 370.463061 -226.769367) (xy 370.461286 -226.773994) (xy 370.457476 -226.783138)
			(xy 370.450618 -226.789996) (xy 370.45011 -226.790504) (xy 370.425726 -226.814888) (xy 370.4209 -226.820476)
			(xy 370.416222 -226.827214) (xy 370.411023 -226.84276) (xy 370.41074 -226.850956) (xy 370.41074 -227.397056)
			(xy 379.336298 -227.397056) (xy 379.340369 -227.341434) (xy 379.352495 -227.286997) (xy 379.372418 -227.234906)
			(xy 379.399714 -227.186271) (xy 379.4338 -227.142128) (xy 379.473949 -227.103419) (xy 379.519307 -227.070968)
			(xy 379.568907 -227.045467) (xy 379.621691 -227.02746) (xy 379.676534 -227.01733) (xy 379.732268 -227.015293)
			(xy 379.787705 -227.021393) (xy 379.841662 -227.035499) (xy 379.892991 -227.057311) (xy 379.940597 -227.086365)
			(xy 379.983465 -227.12204) (xy 380.020682 -227.163577) (xy 380.051455 -227.21009) (xy 380.075127 -227.260587)
			(xy 380.091195 -227.313994) (xy 380.099315 -227.36917) (xy 380.099824 -227.397056) (xy 380.099315 -227.424942)
			(xy 380.091195 -227.480118) (xy 380.075127 -227.533525) (xy 380.051455 -227.584022) (xy 380.020682 -227.630535)
			(xy 379.983465 -227.672072) (xy 379.940597 -227.707747) (xy 379.892991 -227.736801) (xy 379.841662 -227.758613)
			(xy 379.787705 -227.772719) (xy 379.732268 -227.778819) (xy 379.676534 -227.776782) (xy 379.621691 -227.766652)
			(xy 379.568907 -227.748645) (xy 379.519307 -227.723144) (xy 379.473949 -227.690693) (xy 379.4338 -227.651984)
			(xy 379.399714 -227.607841) (xy 379.372418 -227.559206) (xy 379.352495 -227.507115) (xy 379.340369 -227.452678)
			(xy 379.336298 -227.397056) (xy 370.41074 -227.397056) (xy 370.41074 -227.94595) (xy 373.85828 -227.94595)
			(xy 373.862351 -227.890328) (xy 373.874477 -227.835891) (xy 373.8944 -227.7838) (xy 373.921696 -227.735165)
			(xy 373.955782 -227.691022) (xy 373.995931 -227.652313) (xy 374.041289 -227.619862) (xy 374.090889 -227.594361)
			(xy 374.143673 -227.576354) (xy 374.198516 -227.566224) (xy 374.25425 -227.564187) (xy 374.309687 -227.570287)
			(xy 374.363644 -227.584393) (xy 374.414973 -227.606205) (xy 374.462579 -227.635259) (xy 374.505447 -227.670934)
			(xy 374.542664 -227.712471) (xy 374.573437 -227.758984) (xy 374.597109 -227.809481) (xy 374.613177 -227.862888)
			(xy 374.621297 -227.918064) (xy 374.621806 -227.94595) (xy 374.621297 -227.973836) (xy 374.613177 -228.029012)
			(xy 374.597109 -228.082419) (xy 374.573437 -228.132916) (xy 374.542664 -228.179429) (xy 374.505447 -228.220966)
			(xy 374.462579 -228.256641) (xy 374.414973 -228.285695) (xy 374.363644 -228.307507) (xy 374.309687 -228.321613)
			(xy 374.25425 -228.327713) (xy 374.198516 -228.325676) (xy 374.143673 -228.315546) (xy 374.090889 -228.297539)
			(xy 374.041289 -228.272038) (xy 373.995931 -228.239587) (xy 373.955782 -228.200878) (xy 373.921696 -228.156735)
			(xy 373.8944 -228.1081) (xy 373.874477 -228.056009) (xy 373.862351 -228.001572) (xy 373.85828 -227.94595)
			(xy 370.41074 -227.94595) (xy 370.41074 -228.30663) (xy 370.410904 -228.312641) (xy 370.413721 -228.324326)
			(xy 370.416328 -228.329744) (xy 370.41817 -228.333216) (xy 370.422767 -228.339591) (xy 370.425472 -228.342444)
			(xy 370.454174 -228.371146) (xy 370.460869 -228.378552) (xy 370.468475 -228.396988) (xy 370.468906 -228.40696)
			(xy 370.468906 -228.467666) (xy 381.166114 -228.467666) (xy 381.170185 -228.412044) (xy 381.182311 -228.357607)
			(xy 381.202234 -228.305516) (xy 381.22953 -228.256881) (xy 381.263616 -228.212738) (xy 381.303765 -228.174029)
			(xy 381.349123 -228.141578) (xy 381.398723 -228.116077) (xy 381.451507 -228.09807) (xy 381.50635 -228.08794)
			(xy 381.562084 -228.085903) (xy 381.617521 -228.092003) (xy 381.671478 -228.106109) (xy 381.722807 -228.127921)
			(xy 381.770413 -228.156975) (xy 381.813281 -228.19265) (xy 381.850498 -228.234187) (xy 381.881271 -228.2807)
			(xy 381.904943 -228.331197) (xy 381.921011 -228.384604) (xy 381.929131 -228.43978) (xy 381.92964 -228.467666)
			(xy 381.929131 -228.495552) (xy 381.921011 -228.550728) (xy 381.904943 -228.604135) (xy 381.881271 -228.654632)
			(xy 381.850498 -228.701145) (xy 381.813281 -228.742682) (xy 381.770413 -228.778357) (xy 381.722807 -228.807411)
			(xy 381.671478 -228.829223) (xy 381.617521 -228.843329) (xy 381.562084 -228.849429) (xy 381.50635 -228.847392)
			(xy 381.451507 -228.837262) (xy 381.398723 -228.819255) (xy 381.349123 -228.793754) (xy 381.303765 -228.761303)
			(xy 381.263616 -228.722594) (xy 381.22953 -228.678451) (xy 381.202234 -228.629816) (xy 381.182311 -228.577725)
			(xy 381.170185 -228.523288) (xy 381.166114 -228.467666) (xy 370.468906 -228.467666) (xy 370.468906 -229.29088)
			(xy 370.468469 -229.300944) (xy 370.460735 -229.319528) (xy 370.45392 -229.326948) (xy 369.835938 -229.94493)
			(xy 371.092982 -229.94493) (xy 371.097053 -229.889308) (xy 371.109179 -229.834871) (xy 371.129102 -229.78278)
			(xy 371.156398 -229.734145) (xy 371.190484 -229.690002) (xy 371.230633 -229.651293) (xy 371.275991 -229.618842)
			(xy 371.325591 -229.593341) (xy 371.378375 -229.575334) (xy 371.433218 -229.565204) (xy 371.488952 -229.563167)
			(xy 371.544389 -229.569267) (xy 371.598346 -229.583373) (xy 371.649675 -229.605185) (xy 371.697281 -229.634239)
			(xy 371.740149 -229.669914) (xy 371.777366 -229.711451) (xy 371.808139 -229.757964) (xy 371.831811 -229.808461)
			(xy 371.847879 -229.861868) (xy 371.855999 -229.917044) (xy 371.856508 -229.94493) (xy 371.855999 -229.972816)
			(xy 371.847879 -230.027992) (xy 371.831811 -230.081399) (xy 371.808139 -230.131896) (xy 371.777366 -230.178409)
			(xy 371.740149 -230.219946) (xy 371.697281 -230.255621) (xy 371.649675 -230.284675) (xy 371.598346 -230.306487)
			(xy 371.544389 -230.320593) (xy 371.488952 -230.326693) (xy 371.433218 -230.324656) (xy 371.378375 -230.314526)
			(xy 371.325591 -230.296519) (xy 371.275991 -230.271018) (xy 371.230633 -230.238567) (xy 371.190484 -230.199858)
			(xy 371.156398 -230.155715) (xy 371.129102 -230.10708) (xy 371.109179 -230.054989) (xy 371.097053 -230.000552)
			(xy 371.092982 -229.94493) (xy 369.835938 -229.94493) (xy 368.706908 -231.07396) (xy 381.686814 -231.07396)
			(xy 381.690885 -231.018338) (xy 381.703011 -230.963901) (xy 381.722934 -230.91181) (xy 381.75023 -230.863175)
			(xy 381.784316 -230.819032) (xy 381.824465 -230.780323) (xy 381.869823 -230.747872) (xy 381.919423 -230.722371)
			(xy 381.972207 -230.704364) (xy 382.02705 -230.694234) (xy 382.082784 -230.692197) (xy 382.138221 -230.698297)
			(xy 382.192178 -230.712403) (xy 382.243507 -230.734215) (xy 382.291113 -230.763269) (xy 382.333981 -230.798944)
			(xy 382.371198 -230.840481) (xy 382.401971 -230.886994) (xy 382.40975 -230.903589) (xy 383.216061 -230.903589)
			(xy 383.216061 -230.843611) (xy 383.22389 -230.784147) (xy 383.239413 -230.726213) (xy 383.262366 -230.670801)
			(xy 383.292355 -230.618858) (xy 383.328867 -230.571275) (xy 383.371278 -230.528865) (xy 383.418862 -230.492353)
			(xy 383.470804 -230.462364) (xy 383.526216 -230.439412) (xy 383.584151 -230.423889) (xy 383.643615 -230.416061)
			(xy 383.673604 -230.415592) (xy 384.537204 -230.415592) (xy 384.567185 -230.416174) (xy 384.626634 -230.424001)
			(xy 384.684553 -230.439521) (xy 384.739951 -230.462468) (xy 384.79188 -230.492449) (xy 384.839451 -230.528952)
			(xy 384.88185 -230.571352) (xy 384.918353 -230.618924) (xy 384.948334 -230.670853) (xy 384.97128 -230.726251)
			(xy 384.986799 -230.78417) (xy 384.994626 -230.843619) (xy 384.994626 -230.903581) (xy 384.986799 -230.96303)
			(xy 384.97128 -231.020949) (xy 384.948334 -231.076347) (xy 384.918353 -231.128276) (xy 384.88185 -231.175848)
			(xy 384.839451 -231.218248) (xy 384.79188 -231.254751) (xy 384.739951 -231.284732) (xy 384.684553 -231.307679)
			(xy 384.626634 -231.323199) (xy 384.567185 -231.331026) (xy 384.537204 -231.331516) (xy 383.673604 -231.331516)
			(xy 383.643615 -231.331139) (xy 383.584151 -231.323311) (xy 383.526216 -231.307788) (xy 383.470804 -231.284836)
			(xy 383.418862 -231.254847) (xy 383.371278 -231.218335) (xy 383.328867 -231.175925) (xy 383.292355 -231.128342)
			(xy 383.262366 -231.076399) (xy 383.239413 -231.020987) (xy 383.22389 -230.963053) (xy 383.216061 -230.903589)
			(xy 382.40975 -230.903589) (xy 382.425643 -230.937491) (xy 382.441711 -230.990898) (xy 382.449831 -231.046074)
			(xy 382.45034 -231.07396) (xy 382.449831 -231.101846) (xy 382.441711 -231.157022) (xy 382.425643 -231.210429)
			(xy 382.401971 -231.260926) (xy 382.371198 -231.307439) (xy 382.333981 -231.348976) (xy 382.291113 -231.384651)
			(xy 382.243507 -231.413705) (xy 382.192178 -231.435517) (xy 382.138221 -231.449623) (xy 382.082784 -231.455723)
			(xy 382.02705 -231.453686) (xy 381.972207 -231.443556) (xy 381.919423 -231.425549) (xy 381.869823 -231.400048)
			(xy 381.824465 -231.367597) (xy 381.784316 -231.328888) (xy 381.75023 -231.284745) (xy 381.722934 -231.23611)
			(xy 381.703011 -231.184019) (xy 381.690885 -231.129582) (xy 381.686814 -231.07396) (xy 368.706908 -231.07396)
			(xy 368.250978 -231.52989) (xy 368.247455 -231.53362) (xy 368.241823 -231.542193) (xy 368.239802 -231.546908)
			(xy 368.236246 -231.555544) (xy 368.236246 -232.353104) (xy 375.625104 -232.353104) (xy 375.629175 -232.297482)
			(xy 375.641301 -232.243045) (xy 375.661224 -232.190954) (xy 375.68852 -232.142319) (xy 375.722606 -232.098176)
			(xy 375.762755 -232.059467) (xy 375.808113 -232.027016) (xy 375.857713 -232.001515) (xy 375.910497 -231.983508)
			(xy 375.96534 -231.973378) (xy 376.021074 -231.971341) (xy 376.076511 -231.977441) (xy 376.130468 -231.991547)
			(xy 376.181797 -232.013359) (xy 376.229403 -232.042413) (xy 376.272271 -232.078088) (xy 376.309488 -232.119625)
			(xy 376.340261 -232.166138) (xy 376.363933 -232.216635) (xy 376.380001 -232.270042) (xy 376.388121 -232.325218)
			(xy 376.38863 -232.353104) (xy 376.388121 -232.38099) (xy 376.380001 -232.436166) (xy 376.363933 -232.489573)
			(xy 376.340261 -232.54007) (xy 376.309488 -232.586583) (xy 376.272271 -232.62812) (xy 376.229403 -232.663795)
			(xy 376.181797 -232.692849) (xy 376.130468 -232.714661) (xy 376.076511 -232.728767) (xy 376.021074 -232.734867)
			(xy 375.96534 -232.73283) (xy 375.910497 -232.7227) (xy 375.857713 -232.704693) (xy 375.808113 -232.679192)
			(xy 375.762755 -232.646741) (xy 375.722606 -232.608032) (xy 375.68852 -232.563889) (xy 375.661224 -232.515254)
			(xy 375.641301 -232.463163) (xy 375.629175 -232.408726) (xy 375.625104 -232.353104) (xy 368.236246 -232.353104)
			(xy 368.236246 -233.189018) (xy 368.236669 -233.199034) (xy 368.244344 -233.217536) (xy 368.258517 -233.231692)
			(xy 368.27703 -233.239343) (xy 368.287046 -233.239818) (xy 379.752352 -233.239818) (xy 379.763315 -233.238671)
			(xy 379.782791 -233.228394) (xy 379.789944 -233.220006) (xy 379.805242 -233.197072) (xy 379.841381 -233.155441)
			(xy 379.883124 -233.119431) (xy 379.929606 -233.08979) (xy 379.954536 -233.07802) (xy 379.977211 -233.068251)
			(xy 380.024477 -233.053982) (xy 380.04877 -233.049572) (xy 380.079727 -233.045088) (xy 380.142273 -233.045088)
			(xy 380.17323 -233.049572) (xy 380.199407 -233.05436) (xy 380.250197 -233.070242) (xy 380.298284 -233.093035)
			(xy 380.342732 -233.122297) (xy 380.382676 -233.157458) (xy 380.417341 -233.197834) (xy 380.432056 -233.220006)
			(xy 380.439191 -233.228409) (xy 380.458683 -233.238658) (xy 380.469648 -233.239818) (xy 387.214872 -233.239818)
			(xy 387.228943 -233.239381) (xy 387.256022 -233.231721) (xy 387.279975 -233.216949) (xy 387.298976 -233.196191)
			(xy 387.311577 -233.171028) (xy 387.316818 -233.143379) (xy 387.315964 -233.129328) (xy 387.161024 -231.381808)
			(xy 387.160023 -231.37368) (xy 387.153549 -231.358649) (xy 387.148324 -231.352344) (xy 387.138926 -231.342184)
			(xy 387.134608 -231.339136) (xy 387.113679 -231.323695) (xy 387.075794 -231.28806) (xy 387.043091 -231.247617)
			(xy 387.016176 -231.203112) (xy 386.995544 -231.155369) (xy 386.981577 -231.105269) (xy 386.974533 -231.053737)
			(xy 386.97408 -231.027732) (xy 386.974406 -231.002698) (xy 386.980817 -230.953044) (xy 386.993664 -230.904654)
			(xy 387.012728 -230.858359) (xy 387.02488 -230.83647) (xy 387.032246 -230.824532) (xy 387.044198 -230.806105)
			(xy 387.071697 -230.771854) (xy 387.08711 -230.756206) (xy 387.087618 -230.755698) (xy 387.094023 -230.748714)
			(xy 387.101606 -230.731362) (xy 387.10235 -230.721916) (xy 387.051296 -230.146098) (xy 386.978906 -229.33025)
			(xy 386.978652 -229.327964) (xy 386.976477 -229.314788) (xy 386.966177 -229.290158) (xy 386.949842 -229.269043)
			(xy 386.928588 -229.252888) (xy 386.903871 -229.242799) (xy 386.877383 -229.239466) (xy 386.864098 -229.240842)
			(xy 386.851272 -229.242499) (xy 386.825468 -229.244277) (xy 386.812536 -229.244398) (xy 386.811774 -229.244398)
			(xy 386.784505 -229.24391) (xy 386.730522 -229.236145) (xy 386.678194 -229.220778) (xy 386.628585 -229.198121)
			(xy 386.582704 -229.168635) (xy 386.541487 -229.13292) (xy 386.505771 -229.091704) (xy 386.476284 -229.045824)
			(xy 386.453625 -228.996216) (xy 386.438257 -228.943888) (xy 386.430491 -228.889905) (xy 386.430012 -228.862636)
			(xy 386.430457 -228.836229) (xy 386.437736 -228.783918) (xy 386.452159 -228.733111) (xy 386.473451 -228.684778)
			(xy 386.501205 -228.639843) (xy 386.534891 -228.599166) (xy 386.573865 -228.563522) (xy 386.595366 -228.548184)
			(xy 386.606456 -228.540054) (xy 386.624181 -228.519046) (xy 386.635651 -228.494066) (xy 386.64003 -228.466931)
			(xy 386.637003 -228.439611) (xy 386.626787 -228.414093) (xy 386.610127 -228.392231) (xy 386.59943 -228.383592)
			(xy 386.5764 -228.365428) (xy 386.535667 -228.323228) (xy 386.501869 -228.275293) (xy 386.4758 -228.222753)
			(xy 386.458075 -228.166843) (xy 386.44911 -228.10888) (xy 386.448554 -228.079554) (xy 386.44901 -228.053059)
			(xy 386.456344 -228.000578) (xy 386.470864 -227.949615) (xy 386.492291 -227.901149) (xy 386.520214 -227.856112)
			(xy 386.554096 -227.815368) (xy 386.593286 -227.779701) (xy 386.637032 -227.749795) (xy 386.684492 -227.726226)
			(xy 386.734756 -227.709445) (xy 386.76072 -227.704142) (xy 386.766816 -227.702872) (xy 386.789422 -227.689664)
			(xy 386.79335 -227.687307) (xy 386.800375 -227.681428) (xy 386.803392 -227.67798) (xy 386.81787 -227.6602)
			(xy 386.822837 -227.652964) (xy 386.828034 -227.636211) (xy 386.82803 -227.627434) (xy 378.908818 -138.330432)
			(xy 378.90704 -138.30808) (xy 378.90704 -138.307826) (xy 378.906278 -138.29919) (xy 378.906024 -138.298174)
			(xy 378.906024 -138.29665) (xy 378.90577 -138.284458) (xy 378.90577 -138.283442) (xy 378.905262 -138.266424)
			(xy 378.391166 -117.095016) (xy 378.390912 -117.080284) (xy 378.390404 -117.058186) (xy 378.390404 -117.054884)
			(xy 378.390404 -117.054122) (xy 378.39142 -117.035326) (xy 378.39142 -117.034818) (xy 378.392182 -117.017292)
			(xy 379.065028 -104.532938) (xy 379.065028 -104.531922) (xy 379.06833 -104.47655) (xy 379.068584 -104.472994)
			(xy 379.068838 -104.46639) (xy 379.071378 -104.44861) (xy 379.071378 -104.447594) (xy 379.073918 -104.428036)
			(xy 380.99873 -90.367104) (xy 380.99873 -90.362024) (xy 380.998369 -90.353483) (xy 380.992662 -90.337381)
			(xy 380.987554 -90.330528) (xy 380.98095 -90.322908) (xy 380.973076 -90.31351) (xy 380.969864 -90.310143)
			(xy 380.962452 -90.304519) (xy 380.958344 -90.302334) (xy 380.949454 -90.298016) (xy 380.938532 -90.297254)
			(xy 380.909651 -90.295157) (xy 380.852967 -90.283334) (xy 380.798721 -90.26308) (xy 380.748159 -90.234862)
			(xy 380.702441 -90.199327) (xy 380.662619 -90.157291) (xy 380.629606 -90.10972) (xy 380.604161 -90.057707)
			(xy 380.586868 -90.002446) (xy 380.578125 -89.945206) (xy 380.577598 -89.916254) (xy 380.578087 -89.889005)
			(xy 380.585849 -89.835063) (xy 380.601208 -89.782774) (xy 380.623852 -89.733203) (xy 380.653319 -89.687358)
			(xy 380.689011 -89.646174) (xy 380.7302 -89.610488) (xy 380.776048 -89.581027) (xy 380.825623 -89.55839)
			(xy 380.877913 -89.543038) (xy 380.931857 -89.535283) (xy 380.959106 -89.534746) (xy 380.977448 -89.53499)
			(xy 381.01396 -89.538554) (xy 381.032004 -89.541858) (xy 381.032258 -89.541858) (xy 381.037308 -89.542716)
			(xy 381.04755 -89.542586) (xy 381.052578 -89.541604) (xy 381.059182 -89.54008) (xy 381.069088 -89.535)
			(xy 381.103378 -89.5096) (xy 381.109038 -89.504577) (xy 381.117301 -89.491907) (xy 381.119634 -89.484708)
			(xy 381.322326 -88.002872) (xy 381.321708 -87.992644) (xy 381.313457 -87.973906) (xy 381.306324 -87.96655)
			(xy 381.262636 -87.928704) (xy 381.262128 -87.928196) (xy 381.248412 -87.916258) (xy 381.244624 -87.9133)
			(xy 381.236186 -87.908698) (xy 381.231648 -87.907114) (xy 381.226952 -87.905735) (xy 381.217233 -87.90459)
			(xy 381.212344 -87.904828) (xy 381.204216 -87.905844) (xy 381.202184 -87.906352) (xy 381.20066 -87.90686)
			(xy 381.175637 -87.91338) (xy 381.124406 -87.920389) (xy 381.098552 -87.92083) (xy 381.098044 -87.92083)
			(xy 381.070773 -87.92037) (xy 381.016786 -87.912613) (xy 380.964453 -87.897252) (xy 380.914838 -87.874599)
			(xy 380.868953 -87.845115) (xy 380.827731 -87.8094) (xy 380.792012 -87.768183) (xy 380.762522 -87.722301)
			(xy 380.739863 -87.672689) (xy 380.724496 -87.620357) (xy 380.716734 -87.566371) (xy 380.716734 -87.511829)
			(xy 380.724496 -87.457843) (xy 380.739863 -87.405511) (xy 380.762522 -87.355899) (xy 380.792012 -87.310017)
			(xy 380.827731 -87.2688) (xy 380.868953 -87.233085) (xy 380.914838 -87.203601) (xy 380.964453 -87.180948)
			(xy 381.016786 -87.165587) (xy 381.070773 -87.15783) (xy 381.098044 -87.157306) (xy 381.122437 -87.15769)
			(xy 381.170824 -87.163902) (xy 381.218026 -87.176233) (xy 381.26327 -87.19448) (xy 381.284734 -87.206074)
			(xy 381.29464 -87.210138) (xy 381.301498 -87.212424) (xy 381.31369 -87.212424) (xy 381.323088 -87.211408)
			(xy 381.33528 -87.20836) (xy 381.341122 -87.20709) (xy 381.41148 -87.171784) (xy 381.422448 -87.165598)
			(xy 381.436973 -87.145069) (xy 381.439166 -87.132668) (xy 381.581914 -85.979254) (xy 381.582724 -85.967943)
			(xy 381.575596 -85.946448) (xy 381.568198 -85.937852) (xy 381.562864 -85.932264) (xy 381.511556 -85.880702)
			(xy 381.507546 -85.876842) (xy 381.498187 -85.870821) (xy 381.493014 -85.868764) (xy 381.482092 -85.8647)
			(xy 381.470408 -85.86597) (xy 381.460087 -85.866969) (xy 381.439375 -85.867984) (xy 381.429006 -85.868002)
			(xy 381.427482 -85.868002) (xy 381.400241 -85.867501) (xy 381.346317 -85.85972) (xy 381.294049 -85.844346)
			(xy 381.2445 -85.821692) (xy 381.198677 -85.79222) (xy 381.157513 -85.756528) (xy 381.121846 -85.715343)
			(xy 381.092401 -85.669504) (xy 381.069776 -85.619941) (xy 381.054433 -85.567664) (xy 381.046683 -85.513735)
			(xy 381.046228 -85.486494) (xy 381.046692 -85.459242) (xy 381.05445 -85.405294) (xy 381.069807 -85.352999)
			(xy 381.09245 -85.303422) (xy 381.121919 -85.257572) (xy 381.157613 -85.216383) (xy 381.198806 -85.180693)
			(xy 381.244659 -85.15123) (xy 381.294238 -85.128592) (xy 381.346535 -85.113241) (xy 381.400484 -85.105489)
			(xy 381.427736 -85.104986) (xy 381.459789 -85.105642) (xy 381.522991 -85.116368) (xy 381.553466 -85.126322)
			(xy 381.561594 -85.129116) (xy 381.583438 -85.129116) (xy 381.590104 -85.128917) (xy 381.602973 -85.125434)
			(xy 381.608838 -85.122258) (xy 381.62103 -85.115146) (xy 381.621538 -85.114638) (xy 381.6731 -85.083396)
			(xy 381.682691 -85.076905) (xy 381.695243 -85.057468) (xy 381.69723 -85.046058) (xy 381.702564 -85.003132)
			(xy 382.238758 -80.667352) (xy 382.435354 -79.07909) (xy 382.668272 -77.196442) (xy 382.668272 -77.195172)
			(xy 382.668526 -77.189838) (xy 382.66878 -77.185774) (xy 383.43713 -62.641988) (xy 383.43713 -62.6364)
			(xy 383.345436 -61.013848) (xy 383.344226 -61.001494) (xy 383.331584 -60.980165) (xy 383.321306 -60.973208)
			(xy 383.318258 -60.971684) (xy 383.295419 -60.959253) (xy 383.25303 -60.929137) (xy 383.21512 -60.893548)
			(xy 383.182391 -60.853143) (xy 383.155448 -60.808669) (xy 383.134791 -60.760951) (xy 383.1208 -60.710871)
			(xy 383.113736 -60.659355) (xy 383.11328 -60.633356) (xy 383.114804 -60.600336) (xy 383.116074 -60.588652)
			(xy 383.119735 -60.561555) (xy 383.133813 -60.508719) (xy 383.155293 -60.458436) (xy 383.183735 -60.411737)
			(xy 383.218556 -60.369579) (xy 383.259041 -60.332826) (xy 383.281428 -60.317126) (xy 383.286637 -60.313364)
			(xy 383.295126 -60.303723) (xy 383.298192 -60.298076) (xy 383.301494 -60.29198) (xy 383.304034 -60.279026)
			(xy 383.216404 -58.729626) (xy 383.215384 -58.721895) (xy 383.209311 -58.707542) (xy 383.204466 -58.701432)
			(xy 383.204212 -58.701178) (xy 383.186445 -58.680216) (xy 383.156493 -58.634147) (xy 383.133468 -58.584254)
			(xy 383.117847 -58.531572) (xy 383.109953 -58.477193) (xy 383.10947 -58.449718) (xy 383.110004 -58.420752)
			(xy 383.118746 -58.363484) (xy 383.136032 -58.308191) (xy 383.161466 -58.256141) (xy 383.177542 -58.23204)
			(xy 383.178812 -58.230262) (xy 383.182733 -58.223428) (xy 383.186619 -58.208167) (xy 383.186432 -58.20029)
			(xy 383.13106 -57.217056) (xy 383.057654 -55.917846) (xy 382.985772 -54.644798) (xy 382.984305 -54.635125)
			(xy 382.975117 -54.617874) (xy 382.960128 -54.605329) (xy 382.950974 -54.601872) (xy 382.95072 -54.601872)
			(xy 382.925474 -54.593242) (xy 382.877489 -54.569918) (xy 382.833222 -54.540137) (xy 382.793534 -54.504479)
			(xy 382.759201 -54.46364) (xy 382.730892 -54.418417) (xy 382.709158 -54.369691) (xy 382.694425 -54.318413)
			(xy 382.686978 -54.265582) (xy 382.68656 -54.238906) (xy 382.687034 -54.211575) (xy 382.694839 -54.157474)
			(xy 382.710278 -54.105038) (xy 382.733034 -54.055338) (xy 382.762643 -54.009391) (xy 382.7985 -53.968133)
			(xy 382.839872 -53.932409) (xy 382.885915 -53.902947) (xy 382.910588 -53.89118) (xy 382.910842 -53.89118)
			(xy 382.917772 -53.887728) (xy 382.929288 -53.877389) (xy 382.933448 -53.87086) (xy 382.937258 -53.864764)
			(xy 382.940814 -53.850032) (xy 382.84404 -52.13731) (xy 382.819656 -51.70551) (xy 382.818257 -51.692974)
			(xy 382.805074 -51.671506) (xy 382.79451 -51.664616) (xy 382.79324 -51.663854) (xy 382.787777 -51.660875)
			(xy 382.775827 -51.657418) (xy 382.769618 -51.656996) (xy 382.757172 -51.656488) (xy 382.745488 -51.66233)
			(xy 382.719122 -51.67474) (xy 382.663558 -51.692291) (xy 382.605967 -51.701165) (xy 382.576832 -51.7017)
			(xy 382.57226 -51.7017) (xy 382.545145 -51.700916) (xy 382.491537 -51.692626) (xy 382.439643 -51.676832)
			(xy 382.390508 -51.65385) (xy 382.34512 -51.624144) (xy 382.304396 -51.588311) (xy 382.269153 -51.547074)
			(xy 382.254252 -51.524408) (xy 382.252982 -51.522122) (xy 382.252474 -51.521614) (xy 382.251458 -51.520344)
			(xy 382.25095 -51.519582) (xy 382.246378 -51.513994) (xy 382.239868 -51.507519) (xy 382.223461 -51.499308)
			(xy 382.214374 -51.497992) (xy 382.17475 -51.493928) (xy 382.174242 -51.493928) (xy 382.15062 -51.491388)
			(xy 382.150112 -51.491388) (xy 382.134364 -51.489864) (xy 382.12273 -51.489268) (xy 382.100902 -51.497337)
			(xy 382.092454 -51.505358) (xy 382.0922 -51.505612) (xy 382.074105 -51.524179) (xy 382.033769 -51.556748)
			(xy 381.989395 -51.583558) (xy 381.941802 -51.604116) (xy 381.891863 -51.618044) (xy 381.8405 -51.625084)
			(xy 381.814578 -51.6255) (xy 381.787328 -51.625013) (xy 381.733383 -51.617254) (xy 381.681091 -51.601896)
			(xy 381.631517 -51.579254) (xy 381.58567 -51.549787) (xy 381.544483 -51.514095) (xy 381.508795 -51.472906)
			(xy 381.479332 -51.427056) (xy 381.456693 -51.37748) (xy 381.44134 -51.325188) (xy 381.433585 -51.271242)
			(xy 381.43307 -51.243992) (xy 381.433495 -51.218481) (xy 381.440291 -51.167914) (xy 381.453761 -51.118702)
			(xy 381.473665 -51.071723) (xy 381.499648 -51.027812) (xy 381.515112 -51.007518) (xy 381.517652 -51.00447)
			(xy 381.518668 -51.002946) (xy 381.52197 -50.996342) (xy 381.524316 -50.99112) (xy 381.526884 -50.979966)
			(xy 381.52705 -50.974244) (xy 381.52705 -50.94224) (xy 381.538226 -50.94224) (xy 381.538226 -50.89144)
			(xy 381.537893 -50.882836) (xy 381.532184 -50.866602) (xy 381.52705 -50.85969) (xy 381.52578 -50.858166)
			(xy 381.508385 -50.83729) (xy 381.479065 -50.79154) (xy 381.456536 -50.742092) (xy 381.441254 -50.689947)
			(xy 381.433528 -50.636161) (xy 381.43307 -50.608992) (xy 381.433556 -50.581741) (xy 381.441314 -50.527793)
			(xy 381.456669 -50.475497) (xy 381.479311 -50.42592) (xy 381.508777 -50.380069) (xy 381.544468 -50.338878)
			(xy 381.585658 -50.303185) (xy 381.631508 -50.273717) (xy 381.681084 -50.251074) (xy 381.733379 -50.235717)
			(xy 381.787327 -50.227957) (xy 381.814578 -50.227484) (xy 381.842617 -50.227985) (xy 381.898089 -50.236208)
			(xy 381.951759 -50.252464) (xy 382.00247 -50.276404) (xy 382.049129 -50.30751) (xy 382.090731 -50.345114)
			(xy 382.108964 -50.366422) (xy 382.109218 -50.366676) (xy 382.116076 -50.374804) (xy 382.139698 -50.386488)
			(xy 382.146048 -50.389536) (xy 382.150939 -50.391615) (xy 382.161311 -50.393921) (xy 382.166622 -50.394108)
			(xy 382.224026 -50.394108) (xy 382.229401 -50.393941) (xy 382.2399 -50.391627) (xy 382.244854 -50.389536)
			(xy 382.251204 -50.386488) (xy 382.265174 -50.379884) (xy 382.269281 -50.377776) (xy 382.276697 -50.37228)
			(xy 382.279906 -50.368962) (xy 382.282446 -50.365914) (xy 382.299483 -50.346016) (xy 382.338094 -50.310615)
			(xy 382.381181 -50.280823) (xy 382.404366 -50.268632) (xy 382.422276 -50.259817) (xy 382.459564 -50.245562)
			(xy 382.478788 -50.240184) (xy 382.479042 -50.240184) (xy 382.47955 -50.23993) (xy 382.48336 -50.238914)
			(xy 382.489964 -50.237136) (xy 382.494028 -50.234088) (xy 382.498346 -50.230532) (xy 382.500378 -50.229008)
			(xy 382.505966 -50.223166) (xy 382.511554 -50.21453) (xy 382.520952 -50.197004) (xy 382.525355 -50.187512)
			(xy 382.526918 -50.166667) (xy 382.524 -50.156618) (xy 382.456436 -49.961292) (xy 382.44653 -49.93259)
			(xy 382.429004 -49.88179) (xy 382.424913 -49.872636) (xy 382.410943 -49.858274) (xy 382.392534 -49.850365)
			(xy 382.382522 -49.849786) (xy 382.347978 -49.849786) (xy 382.343366 -49.849887) (xy 382.334293 -49.851548)
			(xy 382.329944 -49.853088) (xy 382.321816 -49.856136) (xy 382.314704 -49.862232) (xy 382.293772 -49.879873)
			(xy 382.247805 -49.909597) (xy 382.198058 -49.932439) (xy 382.145555 -49.947928) (xy 382.091376 -49.955747)
			(xy 382.064006 -49.956212) (xy 382.038494 -49.955788) (xy 381.987925 -49.948995) (xy 381.938711 -49.935529)
			(xy 381.891728 -49.91563) (xy 381.847813 -49.889652) (xy 381.827532 -49.87417) (xy 381.824484 -49.87163)
			(xy 381.82296 -49.870614) (xy 381.816356 -49.867312) (xy 381.811134 -49.864966) (xy 381.79998 -49.862395)
			(xy 381.794258 -49.862232) (xy 381.762254 -49.862232) (xy 381.762254 -49.851056) (xy 381.711454 -49.851056)
			(xy 381.70285 -49.851389) (xy 381.686619 -49.857101) (xy 381.679704 -49.862232) (xy 381.67818 -49.863502)
			(xy 381.657302 -49.880892) (xy 381.611551 -49.910203) (xy 381.562103 -49.932723) (xy 381.509958 -49.947994)
			(xy 381.456173 -49.955708) (xy 381.429006 -49.956212) (xy 381.403494 -49.955788) (xy 381.352925 -49.948995)
			(xy 381.303711 -49.935529) (xy 381.256728 -49.91563) (xy 381.212813 -49.889652) (xy 381.192532 -49.87417)
			(xy 381.189484 -49.87163) (xy 381.18796 -49.870614) (xy 381.181356 -49.867312) (xy 381.176134 -49.864966)
			(xy 381.16498 -49.862395) (xy 381.159258 -49.862232) (xy 381.127254 -49.862232) (xy 381.127254 -49.851056)
			(xy 381.076454 -49.851056) (xy 381.06785 -49.851389) (xy 381.051619 -49.857101) (xy 381.044704 -49.862232)
			(xy 381.04318 -49.863502) (xy 381.022302 -49.880892) (xy 380.976551 -49.910203) (xy 380.927103 -49.932723)
			(xy 380.874958 -49.947994) (xy 380.821173 -49.955708) (xy 380.794006 -49.956212) (xy 380.766753 -49.955749)
			(xy 380.7128 -49.947993) (xy 380.660501 -49.932637) (xy 380.61092 -49.909995) (xy 380.565066 -49.880526)
			(xy 380.523872 -49.844832) (xy 380.488177 -49.803639) (xy 380.458708 -49.757785) (xy 380.436065 -49.708204)
			(xy 380.420709 -49.655905) (xy 380.412951 -49.601953) (xy 380.412951 -49.547447) (xy 380.420709 -49.493495)
			(xy 380.436065 -49.441196) (xy 380.458708 -49.391615) (xy 380.488177 -49.345761) (xy 380.523872 -49.304568)
			(xy 380.565066 -49.268874) (xy 380.61092 -49.239405) (xy 380.660501 -49.216763) (xy 380.7128 -49.201407)
			(xy 380.766753 -49.193651) (xy 380.794006 -49.193196) (xy 380.819517 -49.193621) (xy 380.870086 -49.200416)
			(xy 380.919299 -49.213883) (xy 380.966281 -49.233784) (xy 381.010194 -49.259763) (xy 381.03048 -49.275238)
			(xy 381.033528 -49.277778) (xy 381.035052 -49.278794) (xy 381.041656 -49.282096) (xy 381.046878 -49.284441)
			(xy 381.058032 -49.287008) (xy 381.063754 -49.287176) (xy 381.095758 -49.287176) (xy 381.095758 -49.298352)
			(xy 381.146558 -49.298352) (xy 381.155161 -49.298017) (xy 381.171391 -49.292303) (xy 381.178308 -49.287176)
			(xy 381.179832 -49.285906) (xy 381.200708 -49.26851) (xy 381.246457 -49.239188) (xy 381.295904 -49.216657)
			(xy 381.34805 -49.201373) (xy 381.401837 -49.193646) (xy 381.429006 -49.193196) (xy 381.454517 -49.193621)
			(xy 381.505086 -49.200416) (xy 381.554299 -49.213883) (xy 381.601281 -49.233784) (xy 381.645194 -49.259763)
			(xy 381.66548 -49.275238) (xy 381.668528 -49.277778) (xy 381.670052 -49.278794) (xy 381.676656 -49.282096)
			(xy 381.681878 -49.284441) (xy 381.693032 -49.287008) (xy 381.698754 -49.287176) (xy 381.730758 -49.287176)
			(xy 381.730758 -49.298352) (xy 381.781558 -49.298352) (xy 381.790161 -49.298017) (xy 381.806391 -49.292303)
			(xy 381.813308 -49.287176) (xy 381.814832 -49.285906) (xy 381.822198 -49.279302) (xy 381.823214 -49.278794)
			(xy 381.824484 -49.277778) (xy 381.824992 -49.27727) (xy 381.84709 -49.26076) (xy 381.87884 -49.240948)
			(xy 381.879094 -49.240948) (xy 381.889056 -49.234847) (xy 381.902527 -49.215791) (xy 381.905002 -49.204372)
			(xy 381.917956 -49.124108) (xy 381.91885 -49.113092) (xy 381.912257 -49.092022) (xy 381.905256 -49.083468)
			(xy 381.905002 -49.083214) (xy 376.170952 -42.832782) (xy 376.164528 -42.825761) (xy 376.147822 -42.816678)
			(xy 376.128954 -42.814306) (xy 376.119644 -42.816272) (xy 376.11812 -42.81678) (xy 376.117612 -42.817034)
			(xy 376.06859 -42.832782) (xy 376.026934 -42.84599) (xy 376.018336 -42.849584) (xy 376.004281 -42.861799)
			(xy 375.995476 -42.878206) (xy 375.993914 -42.887392) (xy 375.993914 -42.887646) (xy 375.990046 -42.915019)
			(xy 375.975438 -42.968336) (xy 375.953287 -43.018985) (xy 375.924057 -43.065907) (xy 375.88836 -43.108118)
			(xy 375.846945 -43.144734) (xy 375.800677 -43.17499) (xy 375.750527 -43.19825) (xy 375.697545 -43.214027)
			(xy 375.642841 -43.221992) (xy 375.6152 -43.222418) (xy 375.587948 -43.221932) (xy 375.533999 -43.214175)
			(xy 375.481703 -43.19882) (xy 375.432124 -43.176178) (xy 375.386273 -43.146711) (xy 375.345081 -43.111019)
			(xy 375.309389 -43.069827) (xy 375.279922 -43.023976) (xy 375.25728 -42.974397) (xy 375.241925 -42.922101)
			(xy 375.234168 -42.868152) (xy 375.234168 -42.813648) (xy 375.241925 -42.759699) (xy 375.25728 -42.707403)
			(xy 375.279922 -42.657824) (xy 375.309389 -42.611973) (xy 375.345081 -42.570781) (xy 375.386273 -42.535089)
			(xy 375.432124 -42.505622) (xy 375.481703 -42.48298) (xy 375.533999 -42.467625) (xy 375.587948 -42.459868)
			(xy 375.6152 -42.459402) (xy 375.623074 -42.459402) (xy 375.631977 -42.45897) (xy 375.648686 -42.452802)
			(xy 375.662285 -42.441301) (xy 375.667016 -42.433748) (xy 375.671334 -42.426128) (xy 375.710958 -42.356024)
			(xy 375.714598 -42.347758) (xy 375.716415 -42.329802) (xy 375.714514 -42.320972) (xy 375.709688 -42.304208)
			(xy 375.706132 -42.298366) (xy 375.702576 -42.292524) (xy 375.12625 -41.331388) (xy 375.118884 -41.322498)
			(xy 375.11863 -41.322244) (xy 375.113296 -41.317164) (xy 375.106184 -41.313354) (xy 375.105422 -41.3131)
			(xy 375.081999 -41.300902) (xy 375.03846 -41.271011) (xy 374.999465 -41.235397) (xy 374.965761 -41.194739)
			(xy 374.937992 -41.149818) (xy 374.91669 -41.101494) (xy 374.902265 -41.050691) (xy 374.89499 -40.998384)
			(xy 374.894602 -40.971978) (xy 374.894602 -40.960548) (xy 374.894856 -40.953182) (xy 374.893078 -40.946324)
			(xy 374.892146 -40.942662) (xy 374.889344 -40.935646) (xy 374.88749 -40.932354) (xy 374.551194 -40.372284)
			(xy 374.54502 -40.3631) (xy 374.526711 -40.350715) (xy 374.515888 -40.348408) (xy 374.48946 -40.343589)
			(xy 374.438203 -40.327507) (xy 374.38971 -40.304392) (xy 374.344939 -40.274703) (xy 374.304776 -40.239027)
			(xy 374.270015 -40.198069) (xy 374.241344 -40.152639) (xy 374.21933 -40.103636) (xy 374.204409 -40.05203)
			(xy 374.196875 -39.99884) (xy 374.196356 -39.97198) (xy 374.196356 -39.968678) (xy 374.197006 -39.941874)
			(xy 374.204909 -39.888843) (xy 374.212104 -39.863014) (xy 374.213882 -39.85768) (xy 374.213882 -39.857426)
			(xy 374.21439 -39.856156) (xy 374.21439 -39.855648) (xy 374.215406 -39.852854) (xy 374.216676 -39.849298)
			(xy 374.218454 -39.838884) (xy 374.219199 -39.830444) (xy 374.215831 -39.813851) (xy 374.21185 -39.806372)
			(xy 374.211596 -39.805864) (xy 374.01627 -39.479982) (xy 373.688864 -38.933628) (xy 373.681247 -38.92349)
			(xy 373.658859 -38.911649) (xy 373.646192 -38.911022) (xy 373.64543 -38.911022) (xy 373.60352 -38.911784)
			(xy 373.596598 -38.912152) (xy 373.58333 -38.916141) (xy 373.577358 -38.919658) (xy 373.571516 -38.923214)
			(xy 373.562118 -38.933374) (xy 373.55907 -38.939724) (xy 373.54556 -38.965571) (xy 373.512487 -39.013608)
			(xy 373.473108 -39.056627) (xy 373.428175 -39.093807) (xy 373.378546 -39.124439) (xy 373.325168 -39.147937)
			(xy 373.26906 -39.163853) (xy 373.211295 -39.171883) (xy 373.182134 -39.172388) (xy 373.153269 -39.171911)
			(xy 373.09608 -39.164033) (xy 373.040499 -39.148432) (xy 372.987563 -39.1254) (xy 372.938261 -39.095367)
			(xy 372.893513 -39.058894) (xy 372.854155 -39.016662) (xy 372.820921 -38.969458) (xy 372.80723 -38.944042)
			(xy 372.805706 -38.940994) (xy 372.799047 -38.931093) (xy 372.7789 -38.918367) (xy 372.767098 -38.91661)
			(xy 372.758208 -38.916102) (xy 372.72976 -38.914324) (xy 372.71892 -38.914113) (xy 372.698651 -38.921747)
			(xy 372.690644 -38.929056) (xy 372.686834 -38.932866) (xy 372.685056 -38.935152) (xy 372.684294 -38.936168)
			(xy 372.666082 -38.958791) (xy 372.623974 -38.998789) (xy 372.576297 -39.031952) (xy 372.52415 -39.057516)
			(xy 372.468734 -39.074893) (xy 372.411326 -39.083682) (xy 372.382288 -39.08425) (xy 372.382034 -39.08425)
			(xy 372.354777 -39.083789) (xy 372.300816 -39.076035) (xy 372.248508 -39.060681) (xy 372.198918 -39.038038)
			(xy 372.153056 -39.008567) (xy 372.111854 -38.97287) (xy 372.076153 -38.931671) (xy 372.046679 -38.885812)
			(xy 372.024031 -38.836224) (xy 372.008672 -38.783917) (xy 372.000913 -38.729957) (xy 372.000913 -38.675443)
			(xy 372.008672 -38.621483) (xy 372.024031 -38.569176) (xy 372.046679 -38.519588) (xy 372.076153 -38.473729)
			(xy 372.111854 -38.43253) (xy 372.153056 -38.396833) (xy 372.198918 -38.367362) (xy 372.248508 -38.344719)
			(xy 372.300816 -38.329365) (xy 372.354777 -38.321611) (xy 372.382034 -38.321234) (xy 372.409517 -38.321714)
			(xy 372.463914 -38.329598) (xy 372.51662 -38.345197) (xy 372.566546 -38.36819) (xy 372.61266 -38.398102)
			(xy 372.65401 -38.434315) (xy 372.689743 -38.476082) (xy 372.704868 -38.499034) (xy 372.704868 -38.499288)
			(xy 372.707408 -38.503352) (xy 372.70817 -38.504368) (xy 372.712488 -38.508432) (xy 372.72087 -38.515036)
			(xy 372.740174 -38.526974) (xy 372.74351 -38.528968) (xy 372.750653 -38.53203) (xy 372.754398 -38.53307)
			(xy 372.763796 -38.534594) (xy 372.76405 -38.534594) (xy 372.788434 -38.536118) (xy 372.794993 -38.53631)
			(xy 372.807856 -38.533743) (xy 372.813834 -38.531038) (xy 372.819676 -38.528244) (xy 372.829582 -38.519608)
			(xy 372.833392 -38.513766) (xy 372.850293 -38.489793) (xy 372.889665 -38.446317) (xy 372.934681 -38.408716)
			(xy 372.984474 -38.377717) (xy 373.038082 -38.353916) (xy 373.094471 -38.337774) (xy 373.152553 -38.329602)
			(xy 373.18188 -38.329108) (xy 373.182388 -38.329108) (xy 373.194834 -38.329362) (xy 373.204994 -38.328346)
			(xy 373.20982 -38.327076) (xy 373.218264 -38.324069) (xy 373.232458 -38.313145) (xy 373.237506 -38.30574)
			(xy 373.23776 -38.305232) (xy 373.238522 -38.303708) (xy 373.23903 -38.302946) (xy 373.245634 -38.291262)
			(xy 373.245634 -38.290754) (xy 373.253508 -38.27653) (xy 373.257572 -38.265862) (xy 373.259096 -38.253416)
			(xy 373.259096 -38.231064) (xy 373.259096 -38.229032) (xy 373.258702 -38.22311) (xy 373.255498 -38.211684)
			(xy 373.252746 -38.206426) (xy 373.168164 -38.065202) (xy 372.38686 -36.762436) (xy 372.378732 -36.756594)
			(xy 372.353705 -36.73662) (xy 372.310067 -36.689767) (xy 372.274866 -36.636285) (xy 372.261384 -36.607242)
			(xy 372.257574 -36.598352) (xy 371.836696 -36.177474) (xy 371.826536 -36.1696) (xy 371.821202 -36.166552)
			(xy 371.815106 -36.164774) (xy 371.779292 -36.153344) (xy 371.77091 -36.15055) (xy 371.762528 -36.15055)
			(xy 371.757972 -36.150748) (xy 371.749031 -36.152541) (xy 371.744748 -36.154106) (xy 371.724682 -36.16198)
			(xy 371.718078 -36.167568) (xy 371.697277 -36.18461) (xy 371.651793 -36.213297) (xy 371.602733 -36.235318)
			(xy 371.55107 -36.250237) (xy 371.497824 -36.25776) (xy 371.470936 -36.258246) (xy 371.44412 -36.257787)
			(xy 371.391017 -36.250271) (xy 371.339488 -36.235397) (xy 371.290549 -36.213457) (xy 371.245162 -36.184882)
			(xy 371.204222 -36.150237) (xy 371.168534 -36.110202) (xy 371.1388 -36.065566) (xy 371.115607 -36.017207)
			(xy 371.099411 -35.966079) (xy 371.090531 -35.913187) (xy 371.089428 -35.88639) (xy 371.089428 -35.875976)
			(xy 371.089925 -35.847555) (xy 371.098311 -35.791335) (xy 371.114952 -35.736984) (xy 371.126766 -35.71113)
			(xy 371.12956 -35.705542) (xy 371.131846 -35.695128) (xy 371.131846 -35.672522) (xy 371.13135 -35.66308)
			(xy 371.124433 -35.645501) (xy 371.118384 -35.638232) (xy 371.082824 -35.602672) (xy 371.0528 -35.572019)
			(xy 370.997588 -35.506331) (xy 370.948278 -35.436105) (xy 370.92636 -35.399218) (xy 370.921534 -35.390582)
			(xy 370.898166 -35.372802) (xy 370.89408 -35.369808) (xy 370.884992 -35.36534) (xy 370.880132 -35.363912)
			(xy 370.84889 -35.355784) (xy 370.848382 -35.355784) (xy 370.828316 -35.350958) (xy 370.817902 -35.349688)
			(xy 370.790216 -35.357816) (xy 370.78412 -35.361626) (xy 370.744009 -35.386576) (xy 370.659932 -35.429653)
			(xy 370.572159 -35.464589) (xy 370.481478 -35.491072) (xy 370.388698 -35.508864) (xy 370.294653 -35.517805)
			(xy 370.247418 -35.518344) (xy 370.234464 -35.518344) (xy 370.216684 -35.517836) (xy 370.216176 -35.517836)
			(xy 370.17112 -35.515923) (xy 370.081598 -35.504974) (xy 369.993431 -35.485988) (xy 369.907337 -35.459121)
			(xy 369.82402 -35.424591) (xy 369.744161 -35.382681) (xy 369.668411 -35.333733) (xy 369.597389 -35.278147)
			(xy 369.531675 -35.216376) (xy 369.471805 -35.148925) (xy 369.418269 -35.076345) (xy 369.394486 -35.03803)
			(xy 369.391946 -35.033712) (xy 369.383056 -35.023806) (xy 369.376706 -35.017964) (xy 369.354532 -34.999744)
			(xy 369.315381 -34.957781) (xy 369.282949 -34.910433) (xy 369.257969 -34.858764) (xy 369.241001 -34.80394)
			(xy 369.232428 -34.747193) (xy 369.231926 -34.718498) (xy 369.231926 -34.718244) (xy 369.23243 -34.689809)
			(xy 369.240846 -34.633566) (xy 369.24869 -34.60623) (xy 369.250214 -34.599118) (xy 369.251992 -34.588196)
			(xy 369.251992 -34.584386) (xy 369.251738 -34.581592) (xy 369.24996 -34.52114) (xy 369.24996 -34.502852)
			(xy 369.24996 -34.50082) (xy 369.250722 -34.481008) (xy 369.251733 -34.458462) (xy 369.255546 -34.413487)
			(xy 369.258342 -34.391092) (xy 369.265196 -34.343493) (xy 369.286879 -34.249797) (xy 369.317481 -34.158623)
			(xy 369.336574 -34.114486) (xy 369.339622 -34.104834) (xy 369.343178 -34.089594) (xy 369.343178 -34.088578)
			(xy 369.339622 -34.073338) (xy 369.336574 -34.063686) (xy 369.319894 -34.025283) (xy 369.292284 -33.946233)
			(xy 369.271404 -33.865145) (xy 369.257403 -33.782591) (xy 369.250378 -33.699153) (xy 369.24996 -33.657286)
			(xy 369.251992 -33.595564) (xy 369.252754 -33.585404) (xy 369.252754 -33.58388) (xy 369.251992 -33.581594)
			(xy 369.251484 -33.58007) (xy 369.250722 -33.578038) (xy 369.242086 -33.56356) (xy 369.235736 -33.555178)
			(xy 369.20805 -33.52546) (xy 369.204226 -33.521544) (xy 369.195257 -33.515271) (xy 369.19027 -33.513014)
			(xy 369.180618 -33.509204) (xy 369.173506 -33.509458) (xy 369.16995 -33.509458) (xy 369.153186 -33.509712)
			(xy 368.657632 -33.509712) (xy 368.614376 -33.509249) (xy 368.528189 -33.501752) (xy 368.442977 -33.486811)
			(xy 368.359381 -33.46454) (xy 368.318542 -33.450276) (xy 368.314241 -33.448832) (xy 368.305299 -33.447303)
			(xy 368.300762 -33.447228) (xy 368.267742 -33.459928) (xy 368.260884 -33.46577) (xy 368.226889 -33.494747)
			(xy 368.154573 -33.547194) (xy 368.077857 -33.592965) (xy 367.997355 -33.631692) (xy 367.913713 -33.663065)
			(xy 367.8276 -33.686832) (xy 367.739707 -33.702804) (xy 367.650738 -33.710853) (xy 367.606072 -33.711388)
			(xy 367.606072 -33.711642) (xy 367.60531 -33.711642) (xy 367.55883 -33.711108) (xy 367.466272 -33.702455)
			(xy 367.374922 -33.685225) (xy 367.285573 -33.659566) (xy 367.199 -33.625702) (xy 367.115955 -33.583926)
			(xy 367.037159 -33.534602) (xy 366.963297 -33.478156) (xy 366.895009 -33.415081) (xy 366.832889 -33.345923)
			(xy 366.777477 -33.271283) (xy 366.752886 -33.231836) (xy 366.750346 -33.227772) (xy 366.7379 -33.214056)
			(xy 366.734598 -33.211516) (xy 366.712395 -33.193284) (xy 366.673189 -33.151292) (xy 366.640707 -33.103907)
			(xy 366.615679 -33.052195) (xy 366.598669 -32.997322) (xy 366.59006 -32.940521) (xy 366.589564 -32.911796)
			(xy 366.589818 -32.90062) (xy 366.590749 -32.878771) (xy 366.596991 -32.835484) (xy 366.602264 -32.81426)
			(xy 366.606582 -32.79902) (xy 366.608106 -32.791908) (xy 366.609884 -32.780986) (xy 366.609884 -32.777176)
			(xy 366.60963 -32.774382) (xy 366.607852 -32.714692) (xy 366.607852 -32.707326) (xy 366.608451 -32.670113)
			(xy 366.614509 -32.595927) (xy 366.626085 -32.522399) (xy 366.634268 -32.486092) (xy 366.645634 -32.440144)
			(xy 366.675911 -32.350457) (xy 366.69472 -32.307022) (xy 366.696498 -32.302958) (xy 366.70107 -32.282892)
			(xy 366.70107 -32.281876) (xy 366.696498 -32.26181) (xy 366.695228 -32.259016) (xy 366.679104 -32.222083)
			(xy 366.652166 -32.146125) (xy 366.631438 -32.068242) (xy 366.617053 -31.988943) (xy 366.612678 -31.948882)
			(xy 366.610414 -31.924434) (xy 366.608001 -31.87539) (xy 366.607852 -31.850838) (xy 366.607852 -31.850584)
			(xy 366.60963 -31.789878) (xy 366.609884 -31.78683) (xy 366.609884 -31.78302) (xy 366.608106 -31.772098)
			(xy 366.606582 -31.76524) (xy 366.598754 -31.7379) (xy 366.590335 -31.68166) (xy 366.589818 -31.653226)
			(xy 366.589818 -31.652972) (xy 366.590363 -31.623902) (xy 366.599174 -31.566433) (xy 366.616587 -31.510962)
			(xy 366.642201 -31.458769) (xy 366.675425 -31.411057) (xy 366.715492 -31.368928) (xy 366.738154 -31.350712)
			(xy 366.743234 -31.34614) (xy 366.749076 -31.339028) (xy 366.771861 -31.301761) (xy 366.82302 -31.230952)
			(xy 366.880181 -31.164894) (xy 366.942907 -31.104094) (xy 367.010714 -31.049019) (xy 367.083082 -31.000092)
			(xy 367.159457 -30.957688) (xy 367.199164 -30.939486) (xy 367.237527 -30.922858) (xy 367.316488 -30.895336)
			(xy 367.397476 -30.874521) (xy 367.479921 -30.860559) (xy 367.563246 -30.853547) (xy 367.605056 -30.853126)
			(xy 367.60531 -30.853126) (xy 367.647892 -30.853573) (xy 367.732746 -30.860833) (xy 367.816672 -30.875301)
			(xy 367.899059 -30.89687) (xy 367.979307 -30.925384) (xy 368.056833 -30.960635) (xy 368.131072 -31.002366)
			(xy 368.201483 -31.050274) (xy 368.267554 -31.104009) (xy 368.298476 -31.133288) (xy 368.304743 -31.137822)
			(xy 368.319221 -31.143249) (xy 368.326924 -31.143956) (xy 369.177062 -31.143956) (xy 369.184428 -31.143448)
			(xy 369.192782 -31.141856) (xy 369.207835 -31.13396) (xy 369.219499 -31.121597) (xy 369.22329 -31.113984)
			(xy 369.232688 -31.09087) (xy 369.23345 -31.08325) (xy 369.23345 -31.082996) (xy 369.234212 -31.07563)
			(xy 369.236369 -31.05777) (xy 369.243621 -31.022533) (xy 369.24869 -31.005272) (xy 369.250214 -30.99816)
			(xy 369.251992 -30.987238) (xy 369.251992 -30.983428) (xy 369.251738 -30.980634) (xy 369.24996 -30.921452)
			(xy 369.24996 -30.92069) (xy 369.250401 -30.878824) (xy 369.257439 -30.795389) (xy 369.271441 -30.712837)
			(xy 369.292307 -30.631747) (xy 369.319891 -30.55269) (xy 369.336574 -30.51429) (xy 369.339622 -30.504638)
			(xy 369.343178 -30.489398) (xy 369.343178 -30.488382) (xy 369.338606 -30.468316) (xy 369.336828 -30.464252)
			(xy 369.320099 -30.425782) (xy 369.292408 -30.346589) (xy 369.271468 -30.265349) (xy 369.257429 -30.182637)
			(xy 369.250389 -30.099038) (xy 369.24996 -30.05709) (xy 369.24996 -30.047946) (xy 369.250976 -30.014926)
			(xy 369.250976 -30.014164) (xy 369.251992 -29.996384) (xy 369.252246 -29.99232) (xy 369.252754 -29.983684)
			(xy 369.25123 -29.979874) (xy 369.244118 -29.96692) (xy 369.238784 -29.9593) (xy 369.229132 -29.947362)
			(xy 369.221766 -29.943298) (xy 369.219988 -29.942536) (xy 369.196112 -29.929836) (xy 369.18646 -29.928566)
			(xy 369.15972 -29.925387) (xy 369.106605 -29.91649) (xy 369.080288 -29.910786) (xy 369.0747 -29.909516)
			(xy 368.985038 -29.909516) (xy 368.943673 -29.909096) (xy 368.861226 -29.902239) (xy 368.779633 -29.888568)
			(xy 368.699454 -29.868177) (xy 368.621242 -29.841208) (xy 368.58321 -29.824934) (xy 368.573558 -29.820616)
			(xy 368.329972 -29.820616) (xy 368.325094 -29.82071) (xy 368.315503 -29.822493) (xy 368.310922 -29.824172)
			(xy 368.302286 -29.827728) (xy 368.29492 -29.83484) (xy 368.264047 -29.863775) (xy 368.198182 -29.916903)
			(xy 368.128051 -29.964257) (xy 368.054158 -30.005496) (xy 367.977037 -30.040325) (xy 367.897241 -30.068491)
			(xy 367.815345 -30.089794) (xy 367.731938 -30.104079) (xy 367.647621 -30.111243) (xy 367.60531 -30.1117)
			(xy 367.55883 -30.111166) (xy 367.466273 -30.102513) (xy 367.374924 -30.085282) (xy 367.285576 -30.059623)
			(xy 367.199003 -30.025758) (xy 367.11596 -29.983981) (xy 367.037165 -29.934655) (xy 366.963305 -29.878208)
			(xy 366.895019 -29.815132) (xy 366.832902 -29.745972) (xy 366.777492 -29.671331) (xy 366.752886 -29.631894)
			(xy 366.750346 -29.62783) (xy 366.7379 -29.614114) (xy 366.734598 -29.611574) (xy 366.71246 -29.593378)
			(xy 366.673365 -29.551481) (xy 366.640965 -29.504216) (xy 366.615986 -29.452643) (xy 366.59899 -29.397917)
			(xy 366.590356 -29.341267) (xy 366.589818 -29.312616) (xy 366.589818 -29.312108) (xy 366.589818 -29.30525)
			(xy 366.590834 -29.283152) (xy 366.594898 -29.249116) (xy 366.596982 -29.237353) (xy 366.602445 -29.214094)
			(xy 366.60582 -29.202634) (xy 366.60582 -29.202126) (xy 366.607598 -29.196284) (xy 366.609884 -29.181552)
			(xy 366.609884 -29.177742) (xy 366.60963 -29.174948) (xy 366.607852 -29.115258) (xy 366.607852 -29.114242)
			(xy 366.608286 -29.072295) (xy 366.615335 -28.988698) (xy 366.629378 -28.905987) (xy 366.650316 -28.824748)
			(xy 366.678001 -28.745554) (xy 366.69472 -28.70708) (xy 366.696498 -28.703016) (xy 366.70107 -28.68295)
			(xy 366.70107 -28.681934) (xy 366.696498 -28.661868) (xy 366.69472 -28.657804) (xy 366.678046 -28.619476)
			(xy 366.650427 -28.540579) (xy 366.62951 -28.459647) (xy 366.615442 -28.377248) (xy 366.608321 -28.293961)
			(xy 366.607852 -28.252166) (xy 366.607852 -28.250642) (xy 366.60963 -28.189936) (xy 366.609884 -28.187142)
			(xy 366.609884 -28.183332) (xy 366.608106 -28.17241) (xy 366.606582 -28.165298) (xy 366.598743 -28.137896)
			(xy 366.59033 -28.081527) (xy 366.589818 -28.05303) (xy 366.589818 -28.04668) (xy 366.590072 -28.038298)
			(xy 366.591342 -28.01874) (xy 366.591342 -28.018486) (xy 366.59185 -28.012898) (xy 366.595521 -27.983489)
			(xy 366.610782 -27.926224) (xy 366.634712 -27.872007) (xy 366.65027 -27.846782) (xy 366.653572 -27.841702)
			(xy 366.670776 -27.816866) (xy 366.711734 -27.772455) (xy 366.735106 -27.75331) (xy 366.740948 -27.747722)
			(xy 366.745774 -27.742388) (xy 366.75187 -27.73426) (xy 366.77487 -27.697232) (xy 366.82638 -27.626901)
			(xy 366.85474 -27.593798) (xy 366.883051 -27.562108) (xy 366.944248 -27.503139) (xy 367.010242 -27.449593)
			(xy 367.080554 -27.401858) (xy 367.154674 -27.360282) (xy 367.232063 -27.325164) (xy 367.312161 -27.296762)
			(xy 367.394386 -27.27528) (xy 367.478141 -27.260875) (xy 367.562818 -27.25365) (xy 367.60531 -27.253184)
			(xy 367.605564 -27.253184) (xy 367.653084 -27.253738) (xy 367.74769 -27.262793) (xy 367.841005 -27.280816)
			(xy 367.93218 -27.307641) (xy 368.020386 -27.343026) (xy 368.104822 -27.38665) (xy 368.14506 -27.411934)
			(xy 368.182996 -27.436962) (xy 368.254611 -27.492928) (xy 368.288062 -27.523694) (xy 368.293396 -27.528774)
			(xy 368.294666 -27.530044) (xy 368.29492 -27.530298) (xy 368.32032 -27.540458) (xy 368.324887 -27.542211)
			(xy 368.33448 -27.544127) (xy 368.33937 -27.544268) (xy 370.430552 -27.544268) (xy 370.473542 -27.544755)
			(xy 370.559199 -27.552223) (xy 370.643896 -27.56703) (xy 370.727005 -27.589066) (xy 370.76761 -27.603196)
			(xy 370.80952 -27.619452) (xy 372.152164 -28.173426) (xy 372.15842 -28.175783) (xy 372.17168 -28.177457)
			(xy 372.178326 -28.176728) (xy 372.19128 -28.17495) (xy 372.202202 -28.166568) (xy 372.222268 -28.151651)
			(xy 372.26556 -28.126634) (xy 372.311748 -28.107484) (xy 372.360041 -28.094528) (xy 372.409612 -28.087988)
			(xy 372.434612 -28.087574) (xy 372.461852 -28.08806) (xy 372.515777 -28.095811) (xy 372.568051 -28.111154)
			(xy 372.617611 -28.133777) (xy 372.625954 -28.139136) (xy 376.698 -28.139136) (xy 376.702071 -28.083514)
			(xy 376.714197 -28.029077) (xy 376.73412 -27.976986) (xy 376.761416 -27.928351) (xy 376.795502 -27.884208)
			(xy 376.835651 -27.845499) (xy 376.881009 -27.813048) (xy 376.930609 -27.787547) (xy 376.983393 -27.76954)
			(xy 377.038236 -27.75941) (xy 377.09397 -27.757373) (xy 377.149407 -27.763473) (xy 377.203364 -27.777579)
			(xy 377.254693 -27.799391) (xy 377.302299 -27.828445) (xy 377.345167 -27.86412) (xy 377.382384 -27.905657)
			(xy 377.413157 -27.95217) (xy 377.436829 -28.002667) (xy 377.452897 -28.056074) (xy 377.461017 -28.11125)
			(xy 377.461526 -28.139136) (xy 377.968 -28.139136) (xy 377.972071 -28.083514) (xy 377.984197 -28.029077)
			(xy 378.00412 -27.976986) (xy 378.031416 -27.928351) (xy 378.065502 -27.884208) (xy 378.105651 -27.845499)
			(xy 378.151009 -27.813048) (xy 378.200609 -27.787547) (xy 378.253393 -27.76954) (xy 378.308236 -27.75941)
			(xy 378.36397 -27.757373) (xy 378.419407 -27.763473) (xy 378.473364 -27.777579) (xy 378.524693 -27.799391)
			(xy 378.572299 -27.828445) (xy 378.615167 -27.86412) (xy 378.652384 -27.905657) (xy 378.683157 -27.95217)
			(xy 378.706829 -28.002667) (xy 378.722897 -28.056074) (xy 378.731017 -28.11125) (xy 378.731526 -28.139136)
			(xy 378.731017 -28.167022) (xy 378.722897 -28.222198) (xy 378.706829 -28.275605) (xy 378.683157 -28.326102)
			(xy 378.652384 -28.372615) (xy 378.615167 -28.414152) (xy 378.572299 -28.449827) (xy 378.524693 -28.478881)
			(xy 378.473364 -28.500693) (xy 378.419407 -28.514799) (xy 378.36397 -28.520899) (xy 378.308236 -28.518862)
			(xy 378.253393 -28.508732) (xy 378.200609 -28.490725) (xy 378.151009 -28.465224) (xy 378.105651 -28.432773)
			(xy 378.065502 -28.394064) (xy 378.031416 -28.349921) (xy 378.00412 -28.301286) (xy 377.984197 -28.249195)
			(xy 377.972071 -28.194758) (xy 377.968 -28.139136) (xy 377.461526 -28.139136) (xy 377.461017 -28.167022)
			(xy 377.452897 -28.222198) (xy 377.436829 -28.275605) (xy 377.413157 -28.326102) (xy 377.382384 -28.372615)
			(xy 377.345167 -28.414152) (xy 377.302299 -28.449827) (xy 377.254693 -28.478881) (xy 377.203364 -28.500693)
			(xy 377.149407 -28.514799) (xy 377.09397 -28.520899) (xy 377.038236 -28.518862) (xy 376.983393 -28.508732)
			(xy 376.930609 -28.490725) (xy 376.881009 -28.465224) (xy 376.835651 -28.432773) (xy 376.795502 -28.394064)
			(xy 376.761416 -28.349921) (xy 376.73412 -28.301286) (xy 376.714197 -28.249195) (xy 376.702071 -28.194758)
			(xy 376.698 -28.139136) (xy 372.625954 -28.139136) (xy 372.663449 -28.16322) (xy 372.704632 -28.198884)
			(xy 372.740324 -28.240043) (xy 372.769798 -28.285861) (xy 372.792455 -28.335405) (xy 372.807834 -28.387669)
			(xy 372.815622 -28.441589) (xy 372.81612 -28.468828) (xy 372.81612 -28.469336) (xy 372.815612 -28.486608)
			(xy 372.846481 -28.511194) (xy 372.904658 -28.564527) (xy 372.958428 -28.622299) (xy 372.983252 -28.652978)
			(xy 373.355302 -29.12237) (xy 382.907032 -29.12237) (xy 382.907032 -28.25877) (xy 382.907522 -28.228802)
			(xy 382.915345 -28.16938) (xy 382.930858 -28.111487) (xy 382.953794 -28.056114) (xy 382.983761 -28.004208)
			(xy 383.020248 -27.956658) (xy 383.062628 -27.914278) (xy 383.110178 -27.877791) (xy 383.162084 -27.847824)
			(xy 383.217457 -27.824888) (xy 383.27535 -27.809375) (xy 383.334772 -27.801552) (xy 383.394708 -27.801552)
			(xy 383.45413 -27.809375) (xy 383.512023 -27.824888) (xy 383.567396 -27.847824) (xy 383.619302 -27.877791)
			(xy 383.666852 -27.914278) (xy 383.709232 -27.956658) (xy 383.745719 -28.004208) (xy 383.775686 -28.056114)
			(xy 383.798622 -28.111487) (xy 383.814135 -28.16938) (xy 383.821958 -28.228802) (xy 383.822448 -28.25877)
			(xy 383.822448 -29.12237) (xy 383.821958 -29.152338) (xy 383.814135 -29.21176) (xy 383.798622 -29.269653)
			(xy 383.775686 -29.325026) (xy 383.745719 -29.376932) (xy 383.709232 -29.424482) (xy 383.666852 -29.466862)
			(xy 383.619302 -29.503349) (xy 383.567396 -29.533316) (xy 383.512023 -29.556252) (xy 383.45413 -29.571765)
			(xy 383.394708 -29.579588) (xy 383.334772 -29.579588) (xy 383.27535 -29.571765) (xy 383.217457 -29.556252)
			(xy 383.162084 -29.533316) (xy 383.110178 -29.503349) (xy 383.062628 -29.466862) (xy 383.020248 -29.424482)
			(xy 382.983761 -29.376932) (xy 382.953794 -29.325026) (xy 382.930858 -29.269653) (xy 382.915345 -29.21176)
			(xy 382.907522 -29.152338) (xy 382.907032 -29.12237) (xy 373.355302 -29.12237) (xy 373.501666 -29.307028)
			(xy 373.567198 -29.389578) (xy 373.574639 -29.396986) (xy 373.593798 -29.405516) (xy 373.604282 -29.406088)
			(xy 373.61114 -29.40558) (xy 373.61241 -29.405326) (xy 373.623483 -29.404123) (xy 373.645722 -29.402852)
			(xy 373.65686 -29.402786) (xy 373.657622 -29.402786) (xy 373.684872 -29.403273) (xy 373.738818 -29.411032)
			(xy 373.791111 -29.426389) (xy 373.840685 -29.449032) (xy 373.886533 -29.478498) (xy 373.927722 -29.51419)
			(xy 373.963411 -29.555379) (xy 373.992876 -29.601229) (xy 374.015516 -29.650805) (xy 374.030871 -29.703098)
			(xy 374.038628 -29.757044) (xy 374.03913 -29.784294) (xy 374.03913 -29.784802) (xy 374.0384 -29.817938)
			(xy 374.026907 -29.883206) (xy 374.01627 -29.914596) (xy 374.015762 -29.916374) (xy 374.012714 -29.933646)
			(xy 374.013002 -29.942228) (xy 374.018582 -29.958455) (xy 374.023636 -29.965396) (xy 374.349829 -30.376876)
			(xy 375.188988 -30.376876) (xy 375.189528 -30.347959) (xy 375.198248 -30.290788) (xy 375.215499 -30.235588)
			(xy 375.240887 -30.183625) (xy 375.273828 -30.136091) (xy 375.313569 -30.094075) (xy 375.336054 -30.075886)
			(xy 375.344867 -30.068285) (xy 375.355045 -30.047379) (xy 375.355612 -30.035754) (xy 375.355612 -29.955998)
			(xy 375.355056 -29.944368) (xy 375.344879 -29.923459) (xy 375.336054 -29.915866) (xy 375.313545 -29.897706)
			(xy 375.273813 -29.855678) (xy 375.240879 -29.808137) (xy 375.215495 -29.756169) (xy 375.198244 -29.700967)
			(xy 375.18952 -29.643794) (xy 375.188988 -29.614876) (xy 375.189474 -29.587625) (xy 375.19723 -29.533677)
			(xy 375.212585 -29.481382) (xy 375.235227 -29.431805) (xy 375.264693 -29.385955) (xy 375.300384 -29.344764)
			(xy 375.341575 -29.309073) (xy 375.387425 -29.279607) (xy 375.437002 -29.256965) (xy 375.489297 -29.24161)
			(xy 375.543245 -29.233854) (xy 375.597747 -29.233854) (xy 375.651695 -29.24161) (xy 375.70399 -29.256965)
			(xy 375.753567 -29.279607) (xy 375.799417 -29.309073) (xy 375.840608 -29.344764) (xy 375.876299 -29.385955)
			(xy 375.905765 -29.431805) (xy 375.928407 -29.481382) (xy 375.943762 -29.533677) (xy 375.951518 -29.587625)
			(xy 375.952004 -29.614876) (xy 375.951505 -29.643794) (xy 375.942777 -29.700968) (xy 375.925518 -29.756169)
			(xy 375.900123 -29.808131) (xy 375.867174 -29.855664) (xy 375.827427 -29.897678) (xy 375.804938 -29.915866)
			(xy 375.796146 -29.923487) (xy 375.785956 -29.944378) (xy 375.78538 -29.955998) (xy 375.78538 -30.035754)
			(xy 375.785909 -30.047387) (xy 375.796106 -30.068296) (xy 375.804938 -30.075886) (xy 375.827423 -30.094075)
			(xy 375.867156 -30.136097) (xy 375.900094 -30.183632) (xy 375.925482 -30.235594) (xy 375.942738 -30.290791)
			(xy 375.951468 -30.34796) (xy 375.952004 -30.376876) (xy 378.229114 -30.376876) (xy 378.229681 -30.347961)
			(xy 378.238399 -30.290792) (xy 378.255647 -30.235594) (xy 378.28103 -30.183632) (xy 378.313965 -30.136096)
			(xy 378.353698 -30.094077) (xy 378.37618 -30.075886) (xy 378.384997 -30.068289) (xy 378.395172 -30.04738)
			(xy 378.395738 -30.035754) (xy 378.395738 -29.955998) (xy 378.395208 -29.944364) (xy 378.385015 -29.923453)
			(xy 378.37618 -29.915866) (xy 378.353676 -29.897699) (xy 378.313943 -29.855674) (xy 378.281007 -29.808134)
			(xy 378.255622 -29.756168) (xy 378.23837 -29.700966) (xy 378.229646 -29.643793) (xy 378.229114 -29.614876)
			(xy 378.2296 -29.587625) (xy 378.237356 -29.533677) (xy 378.252711 -29.481382) (xy 378.275353 -29.431805)
			(xy 378.304819 -29.385955) (xy 378.34051 -29.344764) (xy 378.381701 -29.309073) (xy 378.427551 -29.279607)
			(xy 378.477128 -29.256965) (xy 378.529423 -29.24161) (xy 378.583371 -29.233854) (xy 378.637873 -29.233854)
			(xy 378.691821 -29.24161) (xy 378.744116 -29.256965) (xy 378.793693 -29.279607) (xy 378.839543 -29.309073)
			(xy 378.880734 -29.344764) (xy 378.916425 -29.385955) (xy 378.945891 -29.431805) (xy 378.968533 -29.481382)
			(xy 378.983888 -29.533677) (xy 378.991644 -29.587625) (xy 378.99213 -29.614876) (xy 378.991621 -29.643794)
			(xy 378.982894 -29.700966) (xy 378.965636 -29.756167) (xy 378.940243 -29.808129) (xy 378.907296 -29.855662)
			(xy 378.867551 -29.897677) (xy 378.845064 -29.915866) (xy 378.836276 -29.923492) (xy 378.826083 -29.944379)
			(xy 378.825506 -29.955998) (xy 378.825506 -30.035754) (xy 378.826026 -30.047388) (xy 378.836228 -30.068298)
			(xy 378.845064 -30.075886) (xy 378.867533 -30.094094) (xy 378.907271 -30.136109) (xy 378.940213 -30.18364)
			(xy 378.965604 -30.235598) (xy 378.982863 -30.290793) (xy 378.991594 -30.347961) (xy 378.99213 -30.376876)
			(xy 378.991644 -30.404127) (xy 378.983888 -30.458075) (xy 378.968533 -30.51037) (xy 378.945891 -30.559947)
			(xy 378.916425 -30.605797) (xy 378.880734 -30.646988) (xy 378.839543 -30.682679) (xy 378.793693 -30.712145)
			(xy 378.744116 -30.734787) (xy 378.691821 -30.750142) (xy 378.637873 -30.757898) (xy 378.583371 -30.757898)
			(xy 378.529423 -30.750142) (xy 378.477128 -30.734787) (xy 378.427551 -30.712145) (xy 378.381701 -30.682679)
			(xy 378.34051 -30.646988) (xy 378.304819 -30.605797) (xy 378.275353 -30.559947) (xy 378.252711 -30.51037)
			(xy 378.237356 -30.458075) (xy 378.2296 -30.404127) (xy 378.229114 -30.376876) (xy 375.952004 -30.376876)
			(xy 375.951518 -30.404127) (xy 375.943762 -30.458075) (xy 375.928407 -30.51037) (xy 375.905765 -30.559947)
			(xy 375.876299 -30.605797) (xy 375.840608 -30.646988) (xy 375.799417 -30.682679) (xy 375.753567 -30.712145)
			(xy 375.70399 -30.734787) (xy 375.651695 -30.750142) (xy 375.597747 -30.757898) (xy 375.543245 -30.757898)
			(xy 375.489297 -30.750142) (xy 375.437002 -30.734787) (xy 375.387425 -30.712145) (xy 375.341575 -30.682679)
			(xy 375.300384 -30.646988) (xy 375.264693 -30.605797) (xy 375.235227 -30.559947) (xy 375.212585 -30.51037)
			(xy 375.19723 -30.458075) (xy 375.189474 -30.404127) (xy 375.188988 -30.376876) (xy 374.349829 -30.376876)
			(xy 374.488964 -30.55239) (xy 374.782445 -30.922468) (xy 381.052832 -30.922468) (xy 381.052832 -30.058868)
			(xy 381.053322 -30.0289) (xy 381.061145 -29.969478) (xy 381.076658 -29.911585) (xy 381.099594 -29.856212)
			(xy 381.129561 -29.804306) (xy 381.166048 -29.756756) (xy 381.208428 -29.714376) (xy 381.255978 -29.677889)
			(xy 381.307884 -29.647922) (xy 381.363257 -29.624986) (xy 381.42115 -29.609473) (xy 381.480572 -29.60165)
			(xy 381.540508 -29.60165) (xy 381.59993 -29.609473) (xy 381.657823 -29.624986) (xy 381.713196 -29.647922)
			(xy 381.765102 -29.677889) (xy 381.812652 -29.714376) (xy 381.855032 -29.756756) (xy 381.891519 -29.804306)
			(xy 381.921486 -29.856212) (xy 381.944422 -29.911585) (xy 381.959935 -29.969478) (xy 381.967758 -30.0289)
			(xy 381.968248 -30.058868) (xy 381.968248 -30.922468) (xy 381.967758 -30.952436) (xy 381.959935 -31.011858)
			(xy 381.944422 -31.069751) (xy 381.921486 -31.125124) (xy 381.891519 -31.17703) (xy 381.855032 -31.22458)
			(xy 381.812652 -31.26696) (xy 381.765102 -31.303447) (xy 381.713196 -31.333414) (xy 381.657823 -31.35635)
			(xy 381.59993 -31.371863) (xy 381.540508 -31.379686) (xy 381.480572 -31.379686) (xy 381.42115 -31.371863)
			(xy 381.363257 -31.35635) (xy 381.307884 -31.333414) (xy 381.255978 -31.303447) (xy 381.208428 -31.26696)
			(xy 381.166048 -31.22458) (xy 381.129561 -31.17703) (xy 381.099594 -31.125124) (xy 381.076658 -31.069751)
			(xy 381.061145 -31.011858) (xy 381.053322 -30.952436) (xy 381.052832 -30.922468) (xy 374.782445 -30.922468)
			(xy 374.841262 -30.996636) (xy 374.844056 -30.999938) (xy 374.879108 -31.03499) (xy 375.211086 -31.367222)
			(xy 375.219389 -31.374483) (xy 375.2402 -31.381717) (xy 375.251218 -31.381192) (xy 375.281952 -31.378398)
			(xy 375.28246 -31.378398) (xy 375.291858 -31.377382) (xy 375.296599 -31.377025) (xy 375.306065 -31.377917)
			(xy 375.310654 -31.37916) (xy 375.31294 -31.379668) (xy 375.333768 -31.384748) (xy 375.345198 -31.382462)
			(xy 375.365264 -31.353252) (xy 375.380567 -31.331564) (xy 375.416215 -31.292236) (xy 375.456972 -31.258232)
			(xy 375.502051 -31.230209) (xy 375.550581 -31.208708) (xy 375.601623 -31.194146) (xy 375.654192 -31.186803)
			(xy 375.680732 -31.186374) (xy 375.708472 -31.186874) (xy 375.763367 -31.19491) (xy 375.81652 -31.210808)
			(xy 375.866812 -31.234233) (xy 375.913183 -31.264692) (xy 375.954657 -31.301543) (xy 375.990359 -31.34401)
			(xy 376.019537 -31.391198) (xy 376.041576 -31.442112) (xy 376.056013 -31.495681) (xy 376.0597 -31.523178)
			(xy 376.061224 -31.536894) (xy 376.062971 -31.564301) (xy 376.05953 -31.619111) (xy 376.048275 -31.672863)
			(xy 376.031331 -31.719266) (xy 376.585478 -31.719266) (xy 376.589549 -31.663644) (xy 376.601675 -31.609207)
			(xy 376.621598 -31.557116) (xy 376.648894 -31.508481) (xy 376.68298 -31.464338) (xy 376.723129 -31.425629)
			(xy 376.768487 -31.393178) (xy 376.818087 -31.367677) (xy 376.870871 -31.34967) (xy 376.925714 -31.33954)
			(xy 376.981448 -31.337503) (xy 377.036885 -31.343603) (xy 377.090842 -31.357709) (xy 377.142171 -31.379521)
			(xy 377.189777 -31.408575) (xy 377.232645 -31.44425) (xy 377.269862 -31.485787) (xy 377.300635 -31.5323)
			(xy 377.324307 -31.582797) (xy 377.340375 -31.636204) (xy 377.344525 -31.664402) (xy 377.861066 -31.664402)
			(xy 377.865137 -31.60878) (xy 377.877263 -31.554343) (xy 377.897186 -31.502252) (xy 377.924482 -31.453617)
			(xy 377.958568 -31.409474) (xy 377.998717 -31.370765) (xy 378.044075 -31.338314) (xy 378.093675 -31.312813)
			(xy 378.146459 -31.294806) (xy 378.201302 -31.284676) (xy 378.257036 -31.282639) (xy 378.312473 -31.288739)
			(xy 378.36643 -31.302845) (xy 378.417759 -31.324657) (xy 378.465365 -31.353711) (xy 378.508233 -31.389386)
			(xy 378.54545 -31.430923) (xy 378.576223 -31.477436) (xy 378.599895 -31.527933) (xy 378.615963 -31.58134)
			(xy 378.624083 -31.636516) (xy 378.624592 -31.664402) (xy 378.624083 -31.692288) (xy 378.615963 -31.747464)
			(xy 378.607023 -31.777178) (xy 379.12624 -31.777178) (xy 379.130311 -31.721556) (xy 379.142437 -31.667119)
			(xy 379.16236 -31.615028) (xy 379.189656 -31.566393) (xy 379.223742 -31.52225) (xy 379.263891 -31.483541)
			(xy 379.309249 -31.45109) (xy 379.358849 -31.425589) (xy 379.411633 -31.407582) (xy 379.466476 -31.397452)
			(xy 379.52221 -31.395415) (xy 379.577647 -31.401515) (xy 379.631604 -31.415621) (xy 379.682933 -31.437433)
			(xy 379.730539 -31.466487) (xy 379.773407 -31.502162) (xy 379.810624 -31.543699) (xy 379.841397 -31.590212)
			(xy 379.865069 -31.640709) (xy 379.881137 -31.694116) (xy 379.889257 -31.749292) (xy 379.889766 -31.777178)
			(xy 379.889257 -31.805064) (xy 379.881137 -31.86024) (xy 379.865069 -31.913647) (xy 379.841397 -31.964144)
			(xy 379.810624 -32.010657) (xy 379.773407 -32.052194) (xy 379.730539 -32.087869) (xy 379.682933 -32.116923)
			(xy 379.631604 -32.138735) (xy 379.577647 -32.152841) (xy 379.52221 -32.158941) (xy 379.466476 -32.156904)
			(xy 379.411633 -32.146774) (xy 379.358849 -32.128767) (xy 379.309249 -32.103266) (xy 379.263891 -32.070815)
			(xy 379.223742 -32.032106) (xy 379.189656 -31.987963) (xy 379.16236 -31.939328) (xy 379.142437 -31.887237)
			(xy 379.130311 -31.8328) (xy 379.12624 -31.777178) (xy 378.607023 -31.777178) (xy 378.599895 -31.800871)
			(xy 378.576223 -31.851368) (xy 378.54545 -31.897881) (xy 378.508233 -31.939418) (xy 378.465365 -31.975093)
			(xy 378.417759 -32.004147) (xy 378.36643 -32.025959) (xy 378.312473 -32.040065) (xy 378.257036 -32.046165)
			(xy 378.201302 -32.044128) (xy 378.146459 -32.033998) (xy 378.093675 -32.015991) (xy 378.044075 -31.99049)
			(xy 377.998717 -31.958039) (xy 377.958568 -31.91933) (xy 377.924482 -31.875187) (xy 377.897186 -31.826552)
			(xy 377.877263 -31.774461) (xy 377.865137 -31.720024) (xy 377.861066 -31.664402) (xy 377.344525 -31.664402)
			(xy 377.348495 -31.69138) (xy 377.349004 -31.719266) (xy 377.348495 -31.747152) (xy 377.340375 -31.802328)
			(xy 377.324307 -31.855735) (xy 377.300635 -31.906232) (xy 377.269862 -31.952745) (xy 377.232645 -31.994282)
			(xy 377.189777 -32.029957) (xy 377.142171 -32.059011) (xy 377.090842 -32.080823) (xy 377.036885 -32.094929)
			(xy 376.981448 -32.101029) (xy 376.925714 -32.098992) (xy 376.870871 -32.088862) (xy 376.818087 -32.070855)
			(xy 376.768487 -32.045354) (xy 376.723129 -32.012903) (xy 376.68298 -31.974194) (xy 376.648894 -31.930051)
			(xy 376.621598 -31.881416) (xy 376.601675 -31.829325) (xy 376.589549 -31.774888) (xy 376.585478 -31.719266)
			(xy 376.031331 -31.719266) (xy 376.029438 -31.724449) (xy 376.003408 -31.772806) (xy 375.97072 -31.816936)
			(xy 375.93205 -31.85593) (xy 375.888194 -31.888985) (xy 375.864374 -31.902654) (xy 375.855484 -31.90748)
			(xy 375.835926 -31.931864) (xy 375.832878 -31.93669) (xy 375.832116 -31.938214) (xy 375.8311 -31.939992)
			(xy 375.827798 -31.948628) (xy 375.81078 -32.009588) (xy 375.808452 -32.019863) (xy 375.811352 -32.040708)
			(xy 375.816368 -32.049974) (xy 376.144028 -32.582866) (xy 376.229713 -32.722312) (xy 382.907032 -32.722312)
			(xy 382.907032 -31.858712) (xy 382.907522 -31.828744) (xy 382.915345 -31.769322) (xy 382.930858 -31.711429)
			(xy 382.953794 -31.656056) (xy 382.983761 -31.60415) (xy 383.020248 -31.5566) (xy 383.062628 -31.51422)
			(xy 383.110178 -31.477733) (xy 383.162084 -31.447766) (xy 383.217457 -31.42483) (xy 383.27535 -31.409317)
			(xy 383.334772 -31.401494) (xy 383.394708 -31.401494) (xy 383.45413 -31.409317) (xy 383.512023 -31.42483)
			(xy 383.567396 -31.447766) (xy 383.619302 -31.477733) (xy 383.666852 -31.51422) (xy 383.709232 -31.5566)
			(xy 383.745719 -31.60415) (xy 383.775686 -31.656056) (xy 383.798622 -31.711429) (xy 383.814135 -31.769322)
			(xy 383.821958 -31.828744) (xy 383.822448 -31.858712) (xy 383.822448 -32.722312) (xy 383.821958 -32.75228)
			(xy 383.814135 -32.811702) (xy 383.798622 -32.869595) (xy 383.775686 -32.924968) (xy 383.745719 -32.976874)
			(xy 383.709232 -33.024424) (xy 383.666852 -33.066804) (xy 383.619302 -33.103291) (xy 383.567396 -33.133258)
			(xy 383.512023 -33.156194) (xy 383.45413 -33.171707) (xy 383.394708 -33.17953) (xy 383.334772 -33.17953)
			(xy 383.27535 -33.171707) (xy 383.217457 -33.156194) (xy 383.162084 -33.133258) (xy 383.110178 -33.103291)
			(xy 383.062628 -33.066804) (xy 383.020248 -33.024424) (xy 382.983761 -32.976874) (xy 382.953794 -32.924968)
			(xy 382.930858 -32.869595) (xy 382.915345 -32.811702) (xy 382.907522 -32.75228) (xy 382.907032 -32.722312)
			(xy 376.229713 -32.722312) (xy 376.301508 -32.839152) (xy 376.302778 -32.840676) (xy 376.308112 -32.847534)
			(xy 376.308366 -32.848042) (xy 376.31751 -32.856932) (xy 376.341894 -32.873442) (xy 376.351038 -32.875728)
			(xy 376.380756 -32.883602) (xy 376.39244 -32.887412) (xy 376.4171 -32.89642) (xy 376.463882 -32.920246)
			(xy 376.50696 -32.950257) (xy 376.545519 -32.985886) (xy 376.578834 -33.026461) (xy 376.606276 -33.071219)
			(xy 376.627327 -33.119314) (xy 376.641591 -33.169839) (xy 376.648798 -33.221842) (xy 376.649234 -33.248092)
			(xy 376.649234 -33.252156) (xy 376.64898 -33.259014) (xy 376.649174 -33.267788) (xy 376.654768 -33.284408)
			(xy 376.659902 -33.291526) (xy 377.635497 -34.52241) (xy 381.052832 -34.52241) (xy 381.052832 -33.65881)
			(xy 381.053322 -33.628842) (xy 381.061145 -33.56942) (xy 381.076658 -33.511527) (xy 381.099594 -33.456154)
			(xy 381.129561 -33.404248) (xy 381.166048 -33.356698) (xy 381.208428 -33.314318) (xy 381.255978 -33.277831)
			(xy 381.307884 -33.247864) (xy 381.363257 -33.224928) (xy 381.42115 -33.209415) (xy 381.480572 -33.201592)
			(xy 381.540508 -33.201592) (xy 381.59993 -33.209415) (xy 381.657823 -33.224928) (xy 381.713196 -33.247864)
			(xy 381.765102 -33.277831) (xy 381.812652 -33.314318) (xy 381.855032 -33.356698) (xy 381.891519 -33.404248)
			(xy 381.921486 -33.456154) (xy 381.944422 -33.511527) (xy 381.959935 -33.56942) (xy 381.967758 -33.628842)
			(xy 381.968248 -33.65881) (xy 381.968248 -34.52241) (xy 381.967758 -34.552378) (xy 381.959935 -34.6118)
			(xy 381.944422 -34.669693) (xy 381.921486 -34.725066) (xy 381.891519 -34.776972) (xy 381.855032 -34.824522)
			(xy 381.812652 -34.866902) (xy 381.765102 -34.903389) (xy 381.713196 -34.933356) (xy 381.657823 -34.956292)
			(xy 381.59993 -34.971805) (xy 381.540508 -34.979628) (xy 381.480572 -34.979628) (xy 381.42115 -34.971805)
			(xy 381.363257 -34.956292) (xy 381.307884 -34.933356) (xy 381.255978 -34.903389) (xy 381.208428 -34.866902)
			(xy 381.166048 -34.824522) (xy 381.129561 -34.776972) (xy 381.099594 -34.725066) (xy 381.076658 -34.669693)
			(xy 381.061145 -34.6118) (xy 381.053322 -34.552378) (xy 381.052832 -34.52241) (xy 377.635497 -34.52241)
			(xy 378.084842 -35.089338) (xy 378.091245 -35.096737) (xy 378.108231 -35.106412) (xy 378.117862 -35.108134)
			(xy 378.122434 -35.108388) (xy 378.125736 -35.108642) (xy 378.20854 -35.102292) (xy 378.21235 -35.102038)
			(xy 378.224512 -35.100425) (xy 378.245361 -35.087564) (xy 378.252228 -35.0774) (xy 378.252736 -35.076638)
			(xy 378.252736 -35.076384) (xy 378.267386 -35.051651) (xy 378.302958 -35.006497) (xy 378.344903 -34.967191)
			(xy 378.39227 -34.934624) (xy 378.443988 -34.909533) (xy 378.498885 -34.892486) (xy 378.555718 -34.88387)
			(xy 378.58446 -34.883344) (xy 378.611714 -34.883827) (xy 378.665669 -34.891579) (xy 378.717971 -34.90693)
			(xy 378.767557 -34.929568) (xy 378.813415 -34.959032) (xy 378.854614 -34.994723) (xy 378.890315 -35.035914)
			(xy 378.91979 -35.081766) (xy 378.942439 -35.131346) (xy 378.957803 -35.183645) (xy 378.965567 -35.237598)
			(xy 378.965968 -35.264852) (xy 378.96551 -35.29146) (xy 378.958122 -35.34416) (xy 378.943482 -35.395322)
			(xy 378.921876 -35.443953) (xy 378.893721 -35.48911) (xy 378.859565 -35.529917) (xy 378.82007 -35.565582)
			(xy 378.776002 -35.595413) (xy 378.728216 -35.618831) (xy 378.703078 -35.627564) (xy 378.691902 -35.63112)
			(xy 378.667264 -35.65525) (xy 378.662944 -35.659702) (xy 378.656397 -35.670236) (xy 378.65431 -35.676078)
			(xy 378.632466 -35.744658) (xy 378.629517 -35.755866) (xy 378.632948 -35.778761) (xy 378.63907 -35.7886)
			(xy 379.034075 -36.286948) (xy 379.500382 -36.286948) (xy 379.504453 -36.231326) (xy 379.516579 -36.176889)
			(xy 379.536502 -36.124798) (xy 379.563798 -36.076163) (xy 379.597884 -36.03202) (xy 379.638033 -35.993311)
			(xy 379.683391 -35.96086) (xy 379.732991 -35.935359) (xy 379.785775 -35.917352) (xy 379.840618 -35.907222)
			(xy 379.896352 -35.905185) (xy 379.951789 -35.911285) (xy 380.005746 -35.925391) (xy 380.057075 -35.947203)
			(xy 380.104681 -35.976257) (xy 380.147549 -36.011932) (xy 380.184766 -36.053469) (xy 380.215539 -36.099982)
			(xy 380.239211 -36.150479) (xy 380.255279 -36.203886) (xy 380.263399 -36.259062) (xy 380.263908 -36.286948)
			(xy 380.263399 -36.314834) (xy 380.255279 -36.37001) (xy 380.239211 -36.423417) (xy 380.215539 -36.473914)
			(xy 380.187994 -36.515548) (xy 381.314196 -36.515548) (xy 381.318267 -36.459926) (xy 381.330393 -36.405489)
			(xy 381.350316 -36.353398) (xy 381.377612 -36.304763) (xy 381.411698 -36.26062) (xy 381.451847 -36.221911)
			(xy 381.497205 -36.18946) (xy 381.546805 -36.163959) (xy 381.599589 -36.145952) (xy 381.654432 -36.135822)
			(xy 381.710166 -36.133785) (xy 381.765603 -36.139885) (xy 381.81956 -36.153991) (xy 381.870889 -36.175803)
			(xy 381.918495 -36.204857) (xy 381.961363 -36.240532) (xy 381.99858 -36.282069) (xy 382.029353 -36.328582)
			(xy 382.053025 -36.379079) (xy 382.069093 -36.432486) (xy 382.077213 -36.487662) (xy 382.077722 -36.515548)
			(xy 382.077213 -36.543434) (xy 382.069093 -36.59861) (xy 382.068636 -36.60013) (xy 386.298193 -36.60013)
			(xy 386.302198 -36.512222) (xy 386.314181 -36.425042) (xy 386.334041 -36.339313) (xy 386.361616 -36.255745)
			(xy 386.396675 -36.175031) (xy 386.438928 -36.097839) (xy 386.488026 -36.02481) (xy 386.543562 -35.956548)
			(xy 386.605074 -35.893618) (xy 386.672055 -35.836544) (xy 386.743948 -35.785796) (xy 386.820157 -35.741796)
			(xy 386.900052 -35.704909) (xy 386.982971 -35.67544) (xy 387.068226 -35.653633) (xy 387.15511 -35.639669)
			(xy 387.242904 -35.633663) (xy 387.330881 -35.635667) (xy 387.418311 -35.645662) (xy 387.50447 -35.663566)
			(xy 387.588644 -35.68923) (xy 387.670135 -35.722443) (xy 387.748269 -35.762929) (xy 387.822397 -35.810351)
			(xy 387.891905 -35.864318) (xy 387.905204 -35.876738) (xy 393.017246 -35.876738) (xy 393.021317 -35.821116)
			(xy 393.033443 -35.766679) (xy 393.053366 -35.714588) (xy 393.080662 -35.665953) (xy 393.114748 -35.62181)
			(xy 393.154897 -35.583101) (xy 393.200255 -35.55065) (xy 393.249855 -35.525149) (xy 393.302639 -35.507142)
			(xy 393.357482 -35.497012) (xy 393.413216 -35.494975) (xy 393.468653 -35.501075) (xy 393.52261 -35.515181)
			(xy 393.573939 -35.536993) (xy 393.621545 -35.566047) (xy 393.664413 -35.601722) (xy 393.70163 -35.643259)
			(xy 393.732403 -35.689772) (xy 393.756075 -35.740269) (xy 393.772143 -35.793676) (xy 393.780263 -35.848852)
			(xy 393.780772 -35.876738) (xy 393.780263 -35.904624) (xy 393.772143 -35.9598) (xy 393.756075 -36.013207)
			(xy 393.732403 -36.063704) (xy 393.70163 -36.110217) (xy 393.664413 -36.151754) (xy 393.621545 -36.187429)
			(xy 393.573939 -36.216483) (xy 393.52261 -36.238295) (xy 393.468653 -36.252401) (xy 393.413216 -36.258501)
			(xy 393.357482 -36.256464) (xy 393.302639 -36.246334) (xy 393.249855 -36.228327) (xy 393.200255 -36.202826)
			(xy 393.154897 -36.170375) (xy 393.114748 -36.131666) (xy 393.080662 -36.087523) (xy 393.053366 -36.038888)
			(xy 393.033443 -35.986797) (xy 393.021317 -35.93236) (xy 393.017246 -35.876738) (xy 387.905204 -35.876738)
			(xy 387.956219 -35.924383) (xy 388.014803 -35.990047) (xy 388.067174 -36.060766) (xy 388.112897 -36.135954)
			(xy 388.151594 -36.214989) (xy 388.182943 -36.297215) (xy 388.206685 -36.381951) (xy 388.222623 -36.468495)
			(xy 388.226409 -36.50996) (xy 394.913864 -36.50996) (xy 394.917935 -36.454338) (xy 394.930061 -36.399901)
			(xy 394.949984 -36.34781) (xy 394.97728 -36.299175) (xy 395.011366 -36.255032) (xy 395.051515 -36.216323)
			(xy 395.096873 -36.183872) (xy 395.146473 -36.158371) (xy 395.199257 -36.140364) (xy 395.2541 -36.130234)
			(xy 395.309834 -36.128197) (xy 395.365271 -36.134297) (xy 395.419228 -36.148403) (xy 395.470557 -36.170215)
			(xy 395.518163 -36.199269) (xy 395.561031 -36.234944) (xy 395.598248 -36.276481) (xy 395.629021 -36.322994)
			(xy 395.652693 -36.373491) (xy 395.668761 -36.426898) (xy 395.676881 -36.482074) (xy 395.67739 -36.50996)
			(xy 395.676881 -36.537846) (xy 395.668761 -36.593022) (xy 395.652693 -36.646429) (xy 395.629021 -36.696926)
			(xy 395.598248 -36.743439) (xy 395.561031 -36.784976) (xy 395.518163 -36.820651) (xy 395.470557 -36.849705)
			(xy 395.419228 -36.871517) (xy 395.365271 -36.885623) (xy 395.309834 -36.891723) (xy 395.2541 -36.889686)
			(xy 395.199257 -36.879556) (xy 395.146473 -36.861549) (xy 395.096873 -36.836048) (xy 395.051515 -36.803597)
			(xy 395.011366 -36.764888) (xy 394.97728 -36.720745) (xy 394.949984 -36.67211) (xy 394.930061 -36.620019)
			(xy 394.917935 -36.565582) (xy 394.913864 -36.50996) (xy 388.226409 -36.50996) (xy 388.230625 -36.55613)
			(xy 388.231126 -36.60013) (xy 388.230625 -36.64413) (xy 388.222623 -36.731765) (xy 388.206685 -36.818309)
			(xy 388.182943 -36.903045) (xy 388.151594 -36.985271) (xy 388.112897 -37.064306) (xy 388.067174 -37.139494)
			(xy 388.014803 -37.210213) (xy 387.956219 -37.275877) (xy 387.891905 -37.335942) (xy 387.822397 -37.389909)
			(xy 387.748269 -37.437331) (xy 387.675263 -37.47516) (xy 392.059158 -37.47516) (xy 392.063229 -37.419538)
			(xy 392.075355 -37.365101) (xy 392.095278 -37.31301) (xy 392.122574 -37.264375) (xy 392.15666 -37.220232)
			(xy 392.196809 -37.181523) (xy 392.242167 -37.149072) (xy 392.291767 -37.123571) (xy 392.344551 -37.105564)
			(xy 392.399394 -37.095434) (xy 392.455128 -37.093397) (xy 392.510565 -37.099497) (xy 392.564522 -37.113603)
			(xy 392.615851 -37.135415) (xy 392.663457 -37.164469) (xy 392.706325 -37.200144) (xy 392.743542 -37.241681)
			(xy 392.774315 -37.288194) (xy 392.797987 -37.338691) (xy 392.814055 -37.392098) (xy 392.822175 -37.447274)
			(xy 392.822684 -37.47516) (xy 392.822175 -37.503046) (xy 392.814055 -37.558222) (xy 392.797987 -37.611629)
			(xy 392.774315 -37.662126) (xy 392.774162 -37.662358) (xy 394.248384 -37.662358) (xy 394.252455 -37.606736)
			(xy 394.264581 -37.552299) (xy 394.284504 -37.500208) (xy 394.3118 -37.451573) (xy 394.345886 -37.40743)
			(xy 394.386035 -37.368721) (xy 394.431393 -37.33627) (xy 394.480993 -37.310769) (xy 394.533777 -37.292762)
			(xy 394.58862 -37.282632) (xy 394.644354 -37.280595) (xy 394.699791 -37.286695) (xy 394.753748 -37.300801)
			(xy 394.805077 -37.322613) (xy 394.852683 -37.351667) (xy 394.895551 -37.387342) (xy 394.932768 -37.428879)
			(xy 394.963541 -37.475392) (xy 394.987213 -37.525889) (xy 395.003281 -37.579296) (xy 395.011401 -37.634472)
			(xy 395.01191 -37.662358) (xy 395.011401 -37.690244) (xy 395.003281 -37.74542) (xy 394.987213 -37.798827)
			(xy 394.963541 -37.849324) (xy 394.932768 -37.895837) (xy 394.895551 -37.937374) (xy 394.852683 -37.973049)
			(xy 394.805077 -38.002103) (xy 394.753748 -38.023915) (xy 394.699791 -38.038021) (xy 394.644354 -38.044121)
			(xy 394.58862 -38.042084) (xy 394.533777 -38.031954) (xy 394.480993 -38.013947) (xy 394.431393 -37.988446)
			(xy 394.386035 -37.955995) (xy 394.345886 -37.917286) (xy 394.3118 -37.873143) (xy 394.284504 -37.824508)
			(xy 394.264581 -37.772417) (xy 394.252455 -37.71798) (xy 394.248384 -37.662358) (xy 392.774162 -37.662358)
			(xy 392.743542 -37.708639) (xy 392.706325 -37.750176) (xy 392.663457 -37.785851) (xy 392.615851 -37.814905)
			(xy 392.564522 -37.836717) (xy 392.510565 -37.850823) (xy 392.455128 -37.856923) (xy 392.399394 -37.854886)
			(xy 392.344551 -37.844756) (xy 392.291767 -37.826749) (xy 392.242167 -37.801248) (xy 392.196809 -37.768797)
			(xy 392.15666 -37.730088) (xy 392.122574 -37.685945) (xy 392.095278 -37.63731) (xy 392.075355 -37.585219)
			(xy 392.063229 -37.530782) (xy 392.059158 -37.47516) (xy 387.675263 -37.47516) (xy 387.670135 -37.477817)
			(xy 387.588644 -37.51103) (xy 387.50447 -37.536694) (xy 387.418311 -37.554598) (xy 387.330881 -37.564593)
			(xy 387.242904 -37.566597) (xy 387.15511 -37.560591) (xy 387.068226 -37.546627) (xy 386.982971 -37.52482)
			(xy 386.900052 -37.495351) (xy 386.820157 -37.458464) (xy 386.743948 -37.414464) (xy 386.672055 -37.363716)
			(xy 386.605074 -37.306642) (xy 386.543562 -37.243712) (xy 386.488026 -37.17545) (xy 386.438928 -37.102421)
			(xy 386.396675 -37.025229) (xy 386.361616 -36.944515) (xy 386.334041 -36.860947) (xy 386.314181 -36.775218)
			(xy 386.302198 -36.688038) (xy 386.298193 -36.60013) (xy 382.068636 -36.60013) (xy 382.053025 -36.652017)
			(xy 382.029353 -36.702514) (xy 381.99858 -36.749027) (xy 381.961363 -36.790564) (xy 381.918495 -36.826239)
			(xy 381.870889 -36.855293) (xy 381.81956 -36.877105) (xy 381.765603 -36.891211) (xy 381.710166 -36.897311)
			(xy 381.654432 -36.895274) (xy 381.599589 -36.885144) (xy 381.546805 -36.867137) (xy 381.497205 -36.841636)
			(xy 381.451847 -36.809185) (xy 381.411698 -36.770476) (xy 381.377612 -36.726333) (xy 381.350316 -36.677698)
			(xy 381.330393 -36.625607) (xy 381.318267 -36.57117) (xy 381.314196 -36.515548) (xy 380.187994 -36.515548)
			(xy 380.184766 -36.520427) (xy 380.147549 -36.561964) (xy 380.104681 -36.597639) (xy 380.057075 -36.626693)
			(xy 380.005746 -36.648505) (xy 379.951789 -36.662611) (xy 379.896352 -36.668711) (xy 379.840618 -36.666674)
			(xy 379.785775 -36.656544) (xy 379.732991 -36.638537) (xy 379.683391 -36.613036) (xy 379.638033 -36.580585)
			(xy 379.597884 -36.541876) (xy 379.563798 -36.497733) (xy 379.536502 -36.449098) (xy 379.516579 -36.397007)
			(xy 379.504453 -36.34257) (xy 379.500382 -36.286948) (xy 379.034075 -36.286948) (xy 379.928374 -37.415216)
			(xy 379.935592 -37.422542) (xy 379.954214 -37.431223) (xy 379.974749 -37.431924) (xy 379.984508 -37.428678)
			(xy 379.987302 -37.427408) (xy 380.012355 -37.416424) (xy 380.064818 -37.400935) (xy 380.118955 -37.393097)
			(xy 380.146306 -37.39261) (xy 380.146814 -37.39261) (xy 380.174066 -37.393074) (xy 380.228014 -37.400833)
			(xy 380.280309 -37.41619) (xy 380.329887 -37.438834) (xy 380.375737 -37.468303) (xy 380.416926 -37.503997)
			(xy 380.452617 -37.545189) (xy 380.482081 -37.591042) (xy 380.504721 -37.640621) (xy 380.520074 -37.692917)
			(xy 380.527828 -37.746866) (xy 380.528322 -37.774118) (xy 380.527915 -37.799339) (xy 380.521271 -37.849343)
			(xy 380.5081 -37.898036) (xy 380.488632 -37.94457) (xy 380.463207 -37.988137) (xy 380.448058 -38.008306)
			(xy 380.447804 -38.00856) (xy 380.442796 -38.015514) (xy 380.437332 -38.031744) (xy 380.437136 -38.04031)
			(xy 380.437136 -38.048184) (xy 380.442724 -38.063932) (xy 382.982705 -41.268753) (xy 390.14395 -41.268753)
			(xy 390.14395 -41.214247) (xy 390.151707 -41.160295) (xy 390.167063 -41.107996) (xy 390.189706 -41.058416)
			(xy 390.219174 -41.012562) (xy 390.254869 -40.971369) (xy 390.296062 -40.935674) (xy 390.341916 -40.906206)
			(xy 390.391496 -40.883563) (xy 390.443795 -40.868207) (xy 390.497747 -40.86045) (xy 390.525 -40.859964)
			(xy 390.553738 -40.860497) (xy 390.610565 -40.869119) (xy 390.665455 -40.886167) (xy 390.717167 -40.911257)
			(xy 390.76453 -40.943819) (xy 390.785858 -40.963088) (xy 390.792716 -40.969692) (xy 390.81075 -40.976804)
			(xy 390.89965 -40.976804) (xy 390.917684 -40.969692) (xy 390.924542 -40.963088) (xy 390.945876 -40.943826)
			(xy 390.993235 -40.911256) (xy 391.044945 -40.886161) (xy 391.099835 -40.869109) (xy 391.156661 -40.860485)
			(xy 391.1854 -40.859964) (xy 391.212649 -40.860506) (xy 391.266593 -40.868262) (xy 391.318884 -40.883616)
			(xy 391.368457 -40.906256) (xy 391.414304 -40.93572) (xy 391.455491 -40.971409) (xy 391.49118 -41.012596)
			(xy 391.520644 -41.058443) (xy 391.543284 -41.108016) (xy 391.558638 -41.160307) (xy 391.566394 -41.214251)
			(xy 391.566394 -41.268749) (xy 391.558638 -41.322693) (xy 391.543284 -41.374984) (xy 391.520644 -41.424557)
			(xy 391.49118 -41.470404) (xy 391.455491 -41.511591) (xy 391.414304 -41.54728) (xy 391.368457 -41.576744)
			(xy 391.318884 -41.599384) (xy 391.266593 -41.614738) (xy 391.212649 -41.622494) (xy 391.1854 -41.62298)
			(xy 391.156662 -41.622435) (xy 391.099837 -41.613814) (xy 391.044947 -41.596768) (xy 390.993235 -41.571682)
			(xy 390.945871 -41.539123) (xy 390.924542 -41.519856) (xy 390.917684 -41.513252) (xy 390.89965 -41.50614)
			(xy 390.81075 -41.50614) (xy 390.792716 -41.513252) (xy 390.785858 -41.519856) (xy 390.76453 -41.539126)
			(xy 390.717168 -41.571692) (xy 390.665457 -41.596785) (xy 390.610566 -41.613836) (xy 390.553739 -41.622459)
			(xy 390.525 -41.62298) (xy 390.497747 -41.62255) (xy 390.443795 -41.614793) (xy 390.391496 -41.599437)
			(xy 390.341916 -41.576794) (xy 390.296062 -41.547326) (xy 390.254869 -41.511631) (xy 390.219174 -41.470438)
			(xy 390.189706 -41.424584) (xy 390.167063 -41.375004) (xy 390.151707 -41.322705) (xy 390.14395 -41.268753)
			(xy 382.982705 -41.268753) (xy 384.596709 -43.305222) (xy 392.607292 -43.305222) (xy 392.607773 -43.277852)
			(xy 392.615587 -43.223674) (xy 392.631073 -43.171171) (xy 392.653912 -43.121424) (xy 392.683633 -43.075456)
			(xy 392.701272 -43.054524) (xy 392.701526 -43.05427) (xy 392.707092 -43.04717) (xy 392.71335 -43.030263)
			(xy 392.713718 -43.02125) (xy 392.713718 -42.954194) (xy 392.71336 -42.945177) (xy 392.707113 -42.928261)
			(xy 392.701526 -42.921174) (xy 392.701272 -42.921174) (xy 392.701272 -42.92092) (xy 392.683624 -42.899995)
			(xy 392.653915 -42.85402) (xy 392.631081 -42.80427) (xy 392.615592 -42.751768) (xy 392.607765 -42.697592)
			(xy 392.607292 -42.670222) (xy 392.607831 -42.641484) (xy 392.61645 -42.584657) (xy 392.633497 -42.529767)
			(xy 392.658585 -42.478055) (xy 392.691147 -42.430691) (xy 392.710416 -42.409364) (xy 392.71702 -42.402506)
			(xy 392.724132 -42.384472) (xy 392.724132 -42.295572) (xy 392.71702 -42.277538) (xy 392.710416 -42.27068)
			(xy 392.691167 -42.249334) (xy 392.658602 -42.201975) (xy 392.63351 -42.150266) (xy 392.616459 -42.095378)
			(xy 392.607834 -42.038554) (xy 392.607832 -41.981078) (xy 392.616451 -41.924253) (xy 392.633498 -41.869364)
			(xy 392.658586 -41.817653) (xy 392.691147 -41.770291) (xy 392.710416 -41.748964) (xy 392.71702 -41.742106)
			(xy 392.724132 -41.724072) (xy 392.724132 -41.635172) (xy 392.71702 -41.617138) (xy 392.710416 -41.61028)
			(xy 392.691152 -41.588947) (xy 392.658586 -41.541586) (xy 392.633492 -41.489876) (xy 392.61644 -41.434987)
			(xy 392.607815 -41.378161) (xy 392.607292 -41.349422) (xy 392.607778 -41.322171) (xy 392.615534 -41.268223)
			(xy 392.630889 -41.215928) (xy 392.653531 -41.166351) (xy 392.682997 -41.120501) (xy 392.718688 -41.07931)
			(xy 392.759879 -41.043619) (xy 392.805729 -41.014153) (xy 392.855306 -40.991511) (xy 392.907601 -40.976156)
			(xy 392.961549 -40.9684) (xy 393.016051 -40.9684) (xy 393.069999 -40.976156) (xy 393.122294 -40.991511)
			(xy 393.171871 -41.014153) (xy 393.217721 -41.043619) (xy 393.258912 -41.07931) (xy 393.294603 -41.120501)
			(xy 393.324069 -41.166351) (xy 393.346711 -41.215928) (xy 393.362066 -41.268223) (xy 393.369822 -41.322171)
			(xy 393.370308 -41.349422) (xy 393.369796 -41.378161) (xy 393.36117 -41.434989) (xy 393.344117 -41.48988)
			(xy 393.319023 -41.541591) (xy 393.286456 -41.588953) (xy 393.267184 -41.61028) (xy 393.26058 -41.617138)
			(xy 393.253468 -41.635172) (xy 393.253468 -41.724072) (xy 393.26058 -41.742106) (xy 393.267184 -41.748964)
			(xy 393.286476 -41.770272) (xy 393.31904 -41.817638) (xy 393.34413 -41.869353) (xy 393.361178 -41.924246)
			(xy 393.369798 -41.981076) (xy 393.369796 -42.038556) (xy 393.361171 -42.095385) (xy 393.344118 -42.150277)
			(xy 393.319024 -42.20199) (xy 393.286456 -42.249353) (xy 393.267184 -42.27068) (xy 393.26058 -42.277538)
			(xy 393.253468 -42.295572) (xy 393.253468 -42.384472) (xy 393.26058 -42.402506) (xy 393.267184 -42.409364)
			(xy 393.286469 -42.430679) (xy 393.319032 -42.478045) (xy 393.344122 -42.529759) (xy 393.361169 -42.584653)
			(xy 393.369789 -42.641482) (xy 393.370308 -42.670222) (xy 393.369853 -42.697593) (xy 393.362032 -42.751772)
			(xy 393.34654 -42.804275) (xy 393.325985 -42.849038) (xy 395.191994 -42.849038) (xy 395.196065 -42.793416)
			(xy 395.208191 -42.738979) (xy 395.228114 -42.686888) (xy 395.25541 -42.638253) (xy 395.289496 -42.59411)
			(xy 395.329645 -42.555401) (xy 395.375003 -42.52295) (xy 395.424603 -42.497449) (xy 395.477387 -42.479442)
			(xy 395.53223 -42.469312) (xy 395.587964 -42.467275) (xy 395.643401 -42.473375) (xy 395.697358 -42.487481)
			(xy 395.748687 -42.509293) (xy 395.796293 -42.538347) (xy 395.839161 -42.574022) (xy 395.876378 -42.615559)
			(xy 395.907151 -42.662072) (xy 395.930823 -42.712569) (xy 395.946891 -42.765976) (xy 395.955011 -42.821152)
			(xy 395.95552 -42.849038) (xy 395.955011 -42.876924) (xy 395.946891 -42.9321) (xy 395.930823 -42.985507)
			(xy 395.907151 -43.036004) (xy 395.876378 -43.082517) (xy 395.839161 -43.124054) (xy 395.796293 -43.159729)
			(xy 395.748687 -43.188783) (xy 395.697358 -43.210595) (xy 395.643401 -43.224701) (xy 395.587964 -43.230801)
			(xy 395.53223 -43.228764) (xy 395.477387 -43.218634) (xy 395.424603 -43.200627) (xy 395.375003 -43.175126)
			(xy 395.329645 -43.142675) (xy 395.289496 -43.103966) (xy 395.25541 -43.059823) (xy 395.228114 -43.011188)
			(xy 395.208191 -42.959097) (xy 395.196065 -42.90466) (xy 395.191994 -42.849038) (xy 393.325985 -42.849038)
			(xy 393.323696 -42.854022) (xy 393.29397 -42.899988) (xy 393.276328 -42.92092) (xy 393.276074 -42.921174)
			(xy 393.270489 -42.928262) (xy 393.264242 -42.945178) (xy 393.263882 -42.954194) (xy 393.263882 -43.02125)
			(xy 393.264267 -43.030264) (xy 393.270495 -43.047181) (xy 393.276074 -43.05427) (xy 393.276328 -43.05427)
			(xy 393.276328 -43.054524) (xy 393.293949 -43.07547) (xy 393.323663 -43.12144) (xy 393.346502 -43.171184)
			(xy 393.361997 -43.223681) (xy 393.369831 -43.277854) (xy 393.370308 -43.305222) (xy 393.369822 -43.332473)
			(xy 393.362066 -43.386421) (xy 393.346711 -43.438716) (xy 393.324069 -43.488293) (xy 393.294603 -43.534143)
			(xy 393.258912 -43.575334) (xy 393.217721 -43.611025) (xy 393.171871 -43.640491) (xy 393.122294 -43.663133)
			(xy 393.069999 -43.678488) (xy 393.016051 -43.686244) (xy 392.961549 -43.686244) (xy 392.907601 -43.678488)
			(xy 392.855306 -43.663133) (xy 392.805729 -43.640491) (xy 392.759879 -43.611025) (xy 392.718688 -43.575334)
			(xy 392.682997 -43.534143) (xy 392.653531 -43.488293) (xy 392.630889 -43.438716) (xy 392.615534 -43.386421)
			(xy 392.607778 -43.332473) (xy 392.607292 -43.305222) (xy 384.596709 -43.305222) (xy 384.938328 -43.73626)
			(xy 394.513052 -43.73626) (xy 394.517123 -43.680638) (xy 394.529249 -43.626201) (xy 394.549172 -43.57411)
			(xy 394.576468 -43.525475) (xy 394.610554 -43.481332) (xy 394.650703 -43.442623) (xy 394.696061 -43.410172)
			(xy 394.745661 -43.384671) (xy 394.798445 -43.366664) (xy 394.853288 -43.356534) (xy 394.909022 -43.354497)
			(xy 394.964459 -43.360597) (xy 395.018416 -43.374703) (xy 395.069745 -43.396515) (xy 395.117351 -43.425569)
			(xy 395.160219 -43.461244) (xy 395.197436 -43.502781) (xy 395.228209 -43.549294) (xy 395.236435 -43.566842)
			(xy 397.633442 -43.566842) (xy 397.637513 -43.51122) (xy 397.649639 -43.456783) (xy 397.669562 -43.404692)
			(xy 397.696858 -43.356057) (xy 397.730944 -43.311914) (xy 397.771093 -43.273205) (xy 397.816451 -43.240754)
			(xy 397.866051 -43.215253) (xy 397.918835 -43.197246) (xy 397.973678 -43.187116) (xy 398.029412 -43.185079)
			(xy 398.084849 -43.191179) (xy 398.138806 -43.205285) (xy 398.190135 -43.227097) (xy 398.237741 -43.256151)
			(xy 398.280609 -43.291826) (xy 398.317826 -43.333363) (xy 398.348599 -43.379876) (xy 398.372271 -43.430373)
			(xy 398.388339 -43.48378) (xy 398.396459 -43.538956) (xy 398.396968 -43.566842) (xy 398.396459 -43.594728)
			(xy 398.388339 -43.649904) (xy 398.372271 -43.703311) (xy 398.348599 -43.753808) (xy 398.317826 -43.800321)
			(xy 398.280609 -43.841858) (xy 398.262522 -43.85691) (xy 399.019774 -43.85691) (xy 399.023845 -43.801288)
			(xy 399.035971 -43.746851) (xy 399.055894 -43.69476) (xy 399.08319 -43.646125) (xy 399.117276 -43.601982)
			(xy 399.157425 -43.563273) (xy 399.202783 -43.530822) (xy 399.252383 -43.505321) (xy 399.305167 -43.487314)
			(xy 399.36001 -43.477184) (xy 399.415744 -43.475147) (xy 399.471181 -43.481247) (xy 399.525138 -43.495353)
			(xy 399.576467 -43.517165) (xy 399.624073 -43.546219) (xy 399.666941 -43.581894) (xy 399.704158 -43.623431)
			(xy 399.734931 -43.669944) (xy 399.758603 -43.720441) (xy 399.774671 -43.773848) (xy 399.782791 -43.829024)
			(xy 399.7833 -43.85691) (xy 399.782791 -43.884796) (xy 399.774671 -43.939972) (xy 399.758603 -43.993379)
			(xy 399.734931 -44.043876) (xy 399.704158 -44.090389) (xy 399.666941 -44.131926) (xy 399.624073 -44.167601)
			(xy 399.576467 -44.196655) (xy 399.525138 -44.218467) (xy 399.471181 -44.232573) (xy 399.415744 -44.238673)
			(xy 399.36001 -44.236636) (xy 399.305167 -44.226506) (xy 399.252383 -44.208499) (xy 399.202783 -44.182998)
			(xy 399.157425 -44.150547) (xy 399.117276 -44.111838) (xy 399.08319 -44.067695) (xy 399.055894 -44.01906)
			(xy 399.035971 -43.966969) (xy 399.023845 -43.912532) (xy 399.019774 -43.85691) (xy 398.262522 -43.85691)
			(xy 398.237741 -43.877533) (xy 398.190135 -43.906587) (xy 398.138806 -43.928399) (xy 398.084849 -43.942505)
			(xy 398.029412 -43.948605) (xy 397.973678 -43.946568) (xy 397.918835 -43.936438) (xy 397.866051 -43.918431)
			(xy 397.816451 -43.89293) (xy 397.771093 -43.860479) (xy 397.730944 -43.82177) (xy 397.696858 -43.777627)
			(xy 397.669562 -43.728992) (xy 397.649639 -43.676901) (xy 397.637513 -43.622464) (xy 397.633442 -43.566842)
			(xy 395.236435 -43.566842) (xy 395.251881 -43.599791) (xy 395.267949 -43.653198) (xy 395.276069 -43.708374)
			(xy 395.276578 -43.73626) (xy 395.276069 -43.764146) (xy 395.267949 -43.819322) (xy 395.251881 -43.872729)
			(xy 395.228209 -43.923226) (xy 395.197436 -43.969739) (xy 395.160219 -44.011276) (xy 395.117351 -44.046951)
			(xy 395.069745 -44.076005) (xy 395.018416 -44.097817) (xy 394.964459 -44.111923) (xy 394.909022 -44.118023)
			(xy 394.853288 -44.115986) (xy 394.798445 -44.105856) (xy 394.745661 -44.087849) (xy 394.696061 -44.062348)
			(xy 394.650703 -44.029897) (xy 394.610554 -43.991188) (xy 394.576468 -43.947045) (xy 394.549172 -43.89841)
			(xy 394.529249 -43.846319) (xy 394.517123 -43.791882) (xy 394.513052 -43.73626) (xy 384.938328 -43.73626)
			(xy 385.00939 -43.825922) (xy 385.035759 -43.859888) (xy 385.0832 -43.931616) (xy 385.104132 -43.969178)
			(xy 385.726938 -45.114464) (xy 394.365478 -45.114464) (xy 394.369549 -45.058842) (xy 394.381675 -45.004405)
			(xy 394.401598 -44.952314) (xy 394.428894 -44.903679) (xy 394.46298 -44.859536) (xy 394.503129 -44.820827)
			(xy 394.548487 -44.788376) (xy 394.598087 -44.762875) (xy 394.650871 -44.744868) (xy 394.705714 -44.734738)
			(xy 394.761448 -44.732701) (xy 394.816885 -44.738801) (xy 394.870842 -44.752907) (xy 394.922171 -44.774719)
			(xy 394.969777 -44.803773) (xy 395.012645 -44.839448) (xy 395.042627 -44.87291) (xy 401.23313 -44.87291)
			(xy 401.237201 -44.817288) (xy 401.249327 -44.762851) (xy 401.26925 -44.71076) (xy 401.296546 -44.662125)
			(xy 401.330632 -44.617982) (xy 401.370781 -44.579273) (xy 401.416139 -44.546822) (xy 401.465739 -44.521321)
			(xy 401.518523 -44.503314) (xy 401.573366 -44.493184) (xy 401.6291 -44.491147) (xy 401.684537 -44.497247)
			(xy 401.738494 -44.511353) (xy 401.789823 -44.533165) (xy 401.837429 -44.562219) (xy 401.880297 -44.597894)
			(xy 401.917514 -44.639431) (xy 401.948287 -44.685944) (xy 401.971959 -44.736441) (xy 401.988027 -44.789848)
			(xy 401.996147 -44.845024) (xy 401.996656 -44.87291) (xy 401.996147 -44.900796) (xy 401.988027 -44.955972)
			(xy 401.971959 -45.009379) (xy 401.948287 -45.059876) (xy 401.917514 -45.106389) (xy 401.880297 -45.147926)
			(xy 401.837429 -45.183601) (xy 401.789823 -45.212655) (xy 401.738494 -45.234467) (xy 401.684537 -45.248573)
			(xy 401.6291 -45.254673) (xy 401.573366 -45.252636) (xy 401.518523 -45.242506) (xy 401.465739 -45.224499)
			(xy 401.416139 -45.198998) (xy 401.370781 -45.166547) (xy 401.330632 -45.127838) (xy 401.296546 -45.083695)
			(xy 401.26925 -45.03506) (xy 401.249327 -44.982969) (xy 401.237201 -44.928532) (xy 401.23313 -44.87291)
			(xy 395.042627 -44.87291) (xy 395.049862 -44.880985) (xy 395.080635 -44.927498) (xy 395.104307 -44.977995)
			(xy 395.120375 -45.031402) (xy 395.128495 -45.086578) (xy 395.129004 -45.114464) (xy 395.128495 -45.14235)
			(xy 395.120375 -45.197526) (xy 395.104307 -45.250933) (xy 395.080635 -45.30143) (xy 395.049862 -45.347943)
			(xy 395.04422 -45.35424) (xy 399.003772 -45.35424) (xy 399.007843 -45.298618) (xy 399.019969 -45.244181)
			(xy 399.039892 -45.19209) (xy 399.067188 -45.143455) (xy 399.101274 -45.099312) (xy 399.141423 -45.060603)
			(xy 399.186781 -45.028152) (xy 399.236381 -45.002651) (xy 399.289165 -44.984644) (xy 399.344008 -44.974514)
			(xy 399.399742 -44.972477) (xy 399.455179 -44.978577) (xy 399.509136 -44.992683) (xy 399.560465 -45.014495)
			(xy 399.608071 -45.043549) (xy 399.650939 -45.079224) (xy 399.688156 -45.120761) (xy 399.718929 -45.167274)
			(xy 399.742601 -45.217771) (xy 399.758669 -45.271178) (xy 399.766789 -45.326354) (xy 399.767298 -45.35424)
			(xy 399.766789 -45.382126) (xy 399.758669 -45.437302) (xy 399.742601 -45.490709) (xy 399.718929 -45.541206)
			(xy 399.688156 -45.587719) (xy 399.650939 -45.629256) (xy 399.608071 -45.664931) (xy 399.560465 -45.693985)
			(xy 399.509136 -45.715797) (xy 399.455179 -45.729903) (xy 399.399742 -45.736003) (xy 399.344008 -45.733966)
			(xy 399.289165 -45.723836) (xy 399.236381 -45.705829) (xy 399.186781 -45.680328) (xy 399.141423 -45.647877)
			(xy 399.101274 -45.609168) (xy 399.067188 -45.565025) (xy 399.039892 -45.51639) (xy 399.019969 -45.464299)
			(xy 399.007843 -45.409862) (xy 399.003772 -45.35424) (xy 395.04422 -45.35424) (xy 395.012645 -45.38948)
			(xy 394.969777 -45.425155) (xy 394.922171 -45.454209) (xy 394.870842 -45.476021) (xy 394.816885 -45.490127)
			(xy 394.761448 -45.496227) (xy 394.705714 -45.49419) (xy 394.650871 -45.48406) (xy 394.598087 -45.466053)
			(xy 394.548487 -45.440552) (xy 394.503129 -45.408101) (xy 394.46298 -45.369392) (xy 394.428894 -45.325249)
			(xy 394.401598 -45.276614) (xy 394.381675 -45.224523) (xy 394.369549 -45.170086) (xy 394.365478 -45.114464)
			(xy 385.726938 -45.114464) (xy 386.029708 -45.671232) (xy 386.03301 -45.676058) (xy 386.405621 -46.082204)
			(xy 392.35253 -46.082204) (xy 392.352959 -46.05495) (xy 392.360717 -46.000995) (xy 392.376074 -45.948695)
			(xy 392.398719 -45.899112) (xy 392.42819 -45.853257) (xy 392.463887 -45.812063) (xy 392.505084 -45.77637)
			(xy 392.550942 -45.746903) (xy 392.600526 -45.724262) (xy 392.652829 -45.708909) (xy 392.706783 -45.701157)
			(xy 392.734038 -45.700696) (xy 392.760942 -45.701129) (xy 392.814213 -45.708706) (xy 392.865892 -45.723691)
			(xy 392.914954 -45.745785) (xy 392.960426 -45.774552) (xy 393.001406 -45.809421) (xy 393.037083 -45.8497)
			(xy 393.0523 -45.871892) (xy 393.059412 -45.882814) (xy 393.082272 -45.894752) (xy 393.19454 -45.89272)
			(xy 393.216892 -45.879766) (xy 393.22375 -45.86859) (xy 393.238651 -45.844975) (xy 393.274333 -45.802023)
			(xy 393.315895 -45.764731) (xy 393.362449 -45.733895) (xy 393.413 -45.710174) (xy 393.466468 -45.694074)
			(xy 393.521712 -45.68594) (xy 393.549632 -45.685456) (xy 393.576626 -45.685899) (xy 393.630075 -45.693509)
			(xy 393.681919 -45.708574) (xy 393.731123 -45.730792) (xy 393.776706 -45.75972) (xy 393.797536 -45.776896)
			(xy 393.805664 -45.784008) (xy 393.826238 -45.790104) (xy 393.911582 -45.779182) (xy 393.922127 -45.777409)
			(xy 393.94041 -45.766354) (xy 393.946888 -45.757846) (xy 393.962255 -45.736626) (xy 393.99784 -45.698173)
			(xy 394.038355 -45.664953) (xy 394.083035 -45.637594) (xy 394.131041 -45.616608) (xy 394.181468 -45.602393)
			(xy 394.233366 -45.595215) (xy 394.259562 -45.594778) (xy 394.286816 -45.595267) (xy 394.340769 -45.603019)
			(xy 394.393069 -45.618371) (xy 394.442652 -45.641011) (xy 394.488508 -45.670477) (xy 394.529704 -45.706169)
			(xy 394.565401 -45.747361) (xy 394.594871 -45.793214) (xy 394.617516 -45.842795) (xy 394.632873 -45.895094)
			(xy 394.640631 -45.949046) (xy 394.640631 -46.003554) (xy 394.632873 -46.057506) (xy 394.617516 -46.109805)
			(xy 394.594871 -46.159386) (xy 394.565401 -46.205239) (xy 394.529704 -46.246431) (xy 394.488508 -46.282123)
			(xy 394.442652 -46.311589) (xy 394.393069 -46.334229) (xy 394.340769 -46.349581) (xy 394.286816 -46.357333)
			(xy 394.259562 -46.357794) (xy 394.232568 -46.357343) (xy 394.17912 -46.349733) (xy 394.127277 -46.33467)
			(xy 394.078073 -46.312454) (xy 394.032489 -46.283528) (xy 394.011658 -46.266354) (xy 394.00353 -46.259242)
			(xy 393.982956 -46.253146) (xy 393.897612 -46.264068) (xy 393.887071 -46.265856) (xy 393.868788 -46.276902)
			(xy 393.862306 -46.285404) (xy 393.844689 -46.309701) (xy 393.803096 -46.352963) (xy 393.779502 -46.37151)
			(xy 393.771628 -46.377352) (xy 393.761214 -46.394878) (xy 393.748006 -46.485302) (xy 393.752832 -46.504606)
			(xy 393.758674 -46.51248) (xy 393.758674 -46.512734) (xy 393.776177 -46.537478) (xy 393.80398 -46.591331)
			(xy 393.822916 -46.648903) (xy 393.830119 -46.693836) (xy 398.976342 -46.693836) (xy 398.976828 -46.666585)
			(xy 398.984584 -46.612637) (xy 398.999939 -46.560342) (xy 399.022581 -46.510765) (xy 399.052047 -46.464915)
			(xy 399.087738 -46.423724) (xy 399.128929 -46.388033) (xy 399.174779 -46.358567) (xy 399.224356 -46.335925)
			(xy 399.276651 -46.32057) (xy 399.330599 -46.312814) (xy 399.385101 -46.312814) (xy 399.439049 -46.32057)
			(xy 399.491344 -46.335925) (xy 399.540921 -46.358567) (xy 399.586771 -46.388033) (xy 399.627962 -46.423724)
			(xy 399.663653 -46.464915) (xy 399.693119 -46.510765) (xy 399.715761 -46.560342) (xy 399.731116 -46.612637)
			(xy 399.738872 -46.666585) (xy 399.739358 -46.693836) (xy 399.738891 -46.720264) (xy 399.731581 -46.772612)
			(xy 399.717106 -46.823447) (xy 399.695744 -46.871793) (xy 399.682208 -46.894496) (xy 399.681954 -46.89475)
			(xy 399.676617 -46.904768) (xy 399.67436 -46.927318) (xy 399.677636 -46.938184) (xy 399.703798 -47.01286)
			(xy 399.708161 -47.023386) (xy 399.724264 -47.03947) (xy 399.734786 -47.043848) (xy 399.73504 -47.043848)
			(xy 399.759547 -47.052921) (xy 399.806 -47.076863) (xy 399.848752 -47.106918) (xy 399.887004 -47.142525)
			(xy 399.920041 -47.183017) (xy 399.947245 -47.227638) (xy 399.968107 -47.275553) (xy 399.982237 -47.325866)
			(xy 399.989371 -47.377636) (xy 399.989802 -47.403766) (xy 399.989316 -47.431017) (xy 399.987793 -47.441612)
			(xy 401.261832 -47.441612) (xy 401.265903 -47.38599) (xy 401.278029 -47.331553) (xy 401.297952 -47.279462)
			(xy 401.325248 -47.230827) (xy 401.359334 -47.186684) (xy 401.399483 -47.147975) (xy 401.444841 -47.115524)
			(xy 401.494441 -47.090023) (xy 401.547225 -47.072016) (xy 401.602068 -47.061886) (xy 401.657802 -47.059849)
			(xy 401.713239 -47.065949) (xy 401.767196 -47.080055) (xy 401.818525 -47.101867) (xy 401.866131 -47.130921)
			(xy 401.908999 -47.166596) (xy 401.946216 -47.208133) (xy 401.976989 -47.254646) (xy 402.000661 -47.305143)
			(xy 402.016729 -47.35855) (xy 402.024849 -47.413726) (xy 402.025358 -47.441612) (xy 402.024849 -47.469498)
			(xy 402.016729 -47.524674) (xy 402.000661 -47.578081) (xy 401.976989 -47.628578) (xy 401.946216 -47.675091)
			(xy 401.908999 -47.716628) (xy 401.866131 -47.752303) (xy 401.818525 -47.781357) (xy 401.767196 -47.803169)
			(xy 401.713239 -47.817275) (xy 401.657802 -47.823375) (xy 401.602068 -47.821338) (xy 401.547225 -47.811208)
			(xy 401.494441 -47.793201) (xy 401.444841 -47.7677) (xy 401.399483 -47.735249) (xy 401.359334 -47.69654)
			(xy 401.325248 -47.652397) (xy 401.297952 -47.603762) (xy 401.278029 -47.551671) (xy 401.265903 -47.497234)
			(xy 401.261832 -47.441612) (xy 399.987793 -47.441612) (xy 399.98156 -47.484965) (xy 399.966205 -47.53726)
			(xy 399.943563 -47.586837) (xy 399.914097 -47.632687) (xy 399.878406 -47.673878) (xy 399.837215 -47.709569)
			(xy 399.791365 -47.739035) (xy 399.741788 -47.761677) (xy 399.689493 -47.777032) (xy 399.635545 -47.784788)
			(xy 399.581043 -47.784788) (xy 399.527095 -47.777032) (xy 399.4748 -47.761677) (xy 399.425223 -47.739035)
			(xy 399.379373 -47.709569) (xy 399.338182 -47.673878) (xy 399.302491 -47.632687) (xy 399.273025 -47.586837)
			(xy 399.250383 -47.53726) (xy 399.235028 -47.484965) (xy 399.227272 -47.431017) (xy 399.226786 -47.403766)
			(xy 399.227262 -47.377339) (xy 399.23457 -47.324991) (xy 399.249043 -47.274156) (xy 399.270402 -47.225809)
			(xy 399.283936 -47.203106) (xy 399.28419 -47.202852) (xy 399.289525 -47.192834) (xy 399.291782 -47.170284)
			(xy 399.288508 -47.159418) (xy 399.262346 -47.084742) (xy 399.257962 -47.074227) (xy 399.241873 -47.058138)
			(xy 399.231358 -47.053754) (xy 399.231104 -47.053754) (xy 399.206585 -47.044711) (xy 399.160134 -47.020763)
			(xy 399.117384 -46.990702) (xy 399.079133 -46.955091) (xy 399.046099 -46.914595) (xy 399.018897 -46.869971)
			(xy 398.998036 -46.822054) (xy 398.983907 -46.771739) (xy 398.976773 -46.719967) (xy 398.976342 -46.693836)
			(xy 393.830119 -46.693836) (xy 393.832509 -46.708745) (xy 393.833096 -46.739048) (xy 393.832667 -46.766301)
			(xy 393.824903 -46.820251) (xy 393.809542 -46.872548) (xy 393.786894 -46.922126) (xy 393.757422 -46.967977)
			(xy 393.721724 -47.009167) (xy 393.680529 -47.044858) (xy 393.634673 -47.074323) (xy 393.585092 -47.096963)
			(xy 393.532793 -47.112316) (xy 393.478841 -47.120071) (xy 393.451588 -47.120556) (xy 393.425554 -47.120109)
			(xy 393.373972 -47.113021) (xy 393.32383 -47.098991) (xy 393.276059 -47.07828) (xy 393.231544 -47.051272)
			(xy 393.21105 -47.035212) (xy 393.203285 -47.029483) (xy 393.184881 -47.023734) (xy 393.175236 -47.024036)
			(xy 393.09548 -47.030386) (xy 393.0777 -47.039022) (xy 393.07135 -47.046388) (xy 393.053167 -47.066032)
			(xy 393.01226 -47.100554) (xy 392.966931 -47.129023) (xy 392.91807 -47.150881) (xy 392.866635 -47.165699)
			(xy 392.813634 -47.173186) (xy 392.78687 -47.173642) (xy 392.75962 -47.17315) (xy 392.705674 -47.16539)
			(xy 392.653381 -47.150033) (xy 392.603806 -47.127391) (xy 392.557958 -47.097925) (xy 392.516769 -47.062234)
			(xy 392.481078 -47.021046) (xy 392.451611 -46.975197) (xy 392.428968 -46.925622) (xy 392.41361 -46.87333)
			(xy 392.40585 -46.819384) (xy 392.405362 -46.792134) (xy 392.405897 -46.76336) (xy 392.414547 -46.706467)
			(xy 392.431641 -46.651517) (xy 392.456792 -46.599757) (xy 392.48943 -46.55236) (xy 392.50874 -46.531022)
			(xy 392.516106 -46.523148) (xy 392.523218 -46.503336) (xy 392.515852 -46.40707) (xy 392.505946 -46.388274)
			(xy 392.497564 -46.38167) (xy 392.475388 -46.363434) (xy 392.436176 -46.321503) (xy 392.403688 -46.27417)
			(xy 392.378657 -46.222504) (xy 392.36165 -46.167671) (xy 392.353048 -46.110909) (xy 392.35253 -46.082204)
			(xy 386.405621 -46.082204) (xy 386.46481 -46.14672) (xy 386.49176 -46.176731) (xy 386.54124 -46.240442)
			(xy 386.585364 -46.307972) (xy 386.62384 -46.378873) (xy 386.656412 -46.452672) (xy 386.670042 -46.490636)
			(xy 387.014212 -47.481236) (xy 387.01599 -47.485554) (xy 387.114796 -47.667418) (xy 387.134867 -47.705318)
			(xy 387.169202 -47.783914) (xy 387.183376 -47.82439) (xy 387.346533 -48.30699) (xy 398.853912 -48.30699)
			(xy 398.857983 -48.251368) (xy 398.870109 -48.196931) (xy 398.890032 -48.14484) (xy 398.917328 -48.096205)
			(xy 398.951414 -48.052062) (xy 398.991563 -48.013353) (xy 399.036921 -47.980902) (xy 399.086521 -47.955401)
			(xy 399.139305 -47.937394) (xy 399.194148 -47.927264) (xy 399.249882 -47.925227) (xy 399.305319 -47.931327)
			(xy 399.359276 -47.945433) (xy 399.410605 -47.967245) (xy 399.458211 -47.996299) (xy 399.501079 -48.031974)
			(xy 399.538296 -48.073511) (xy 399.569069 -48.120024) (xy 399.592741 -48.170521) (xy 399.608809 -48.223928)
			(xy 399.616929 -48.279104) (xy 399.617438 -48.30699) (xy 399.616929 -48.334876) (xy 399.608809 -48.390052)
			(xy 399.592741 -48.443459) (xy 399.569069 -48.493956) (xy 399.538296 -48.540469) (xy 399.501079 -48.582006)
			(xy 399.458211 -48.617681) (xy 399.410605 -48.646735) (xy 399.359276 -48.668547) (xy 399.305319 -48.682653)
			(xy 399.249882 -48.688753) (xy 399.194148 -48.686716) (xy 399.139305 -48.676586) (xy 399.086521 -48.658579)
			(xy 399.036921 -48.633078) (xy 398.991563 -48.600627) (xy 398.951414 -48.561918) (xy 398.917328 -48.517775)
			(xy 398.890032 -48.46914) (xy 398.870109 -48.417049) (xy 398.857983 -48.362612) (xy 398.853912 -48.30699)
			(xy 387.346533 -48.30699) (xy 387.497324 -48.753014) (xy 395.468346 -48.753014) (xy 395.472417 -48.697392)
			(xy 395.484543 -48.642955) (xy 395.504466 -48.590864) (xy 395.531762 -48.542229) (xy 395.565848 -48.498086)
			(xy 395.605997 -48.459377) (xy 395.651355 -48.426926) (xy 395.700955 -48.401425) (xy 395.753739 -48.383418)
			(xy 395.808582 -48.373288) (xy 395.864316 -48.371251) (xy 395.919753 -48.377351) (xy 395.97371 -48.391457)
			(xy 396.025039 -48.413269) (xy 396.072645 -48.442323) (xy 396.115513 -48.477998) (xy 396.15273 -48.519535)
			(xy 396.183503 -48.566048) (xy 396.207175 -48.616545) (xy 396.223243 -48.669952) (xy 396.231363 -48.725128)
			(xy 396.231872 -48.753014) (xy 396.231363 -48.7809) (xy 396.223243 -48.836076) (xy 396.207175 -48.889483)
			(xy 396.205779 -48.89246) (xy 397.514062 -48.89246) (xy 397.518133 -48.836838) (xy 397.530259 -48.782401)
			(xy 397.550182 -48.73031) (xy 397.577478 -48.681675) (xy 397.611564 -48.637532) (xy 397.651713 -48.598823)
			(xy 397.697071 -48.566372) (xy 397.746671 -48.540871) (xy 397.799455 -48.522864) (xy 397.854298 -48.512734)
			(xy 397.910032 -48.510697) (xy 397.965469 -48.516797) (xy 398.019426 -48.530903) (xy 398.070755 -48.552715)
			(xy 398.118361 -48.581769) (xy 398.161229 -48.617444) (xy 398.198446 -48.658981) (xy 398.229219 -48.705494)
			(xy 398.252891 -48.755991) (xy 398.268959 -48.809398) (xy 398.277079 -48.864574) (xy 398.277588 -48.89246)
			(xy 398.277079 -48.920346) (xy 398.274641 -48.93691) (xy 401.23313 -48.93691) (xy 401.237201 -48.881288)
			(xy 401.249327 -48.826851) (xy 401.26925 -48.77476) (xy 401.296546 -48.726125) (xy 401.330632 -48.681982)
			(xy 401.370781 -48.643273) (xy 401.416139 -48.610822) (xy 401.465739 -48.585321) (xy 401.518523 -48.567314)
			(xy 401.573366 -48.557184) (xy 401.6291 -48.555147) (xy 401.684537 -48.561247) (xy 401.738494 -48.575353)
			(xy 401.789823 -48.597165) (xy 401.837429 -48.626219) (xy 401.880297 -48.661894) (xy 401.917514 -48.703431)
			(xy 401.948287 -48.749944) (xy 401.971959 -48.800441) (xy 401.988027 -48.853848) (xy 401.996147 -48.909024)
			(xy 401.996656 -48.93691) (xy 401.996147 -48.964796) (xy 401.988027 -49.019972) (xy 401.971959 -49.073379)
			(xy 401.948287 -49.123876) (xy 401.917514 -49.170389) (xy 401.880297 -49.211926) (xy 401.837429 -49.247601)
			(xy 401.789823 -49.276655) (xy 401.738494 -49.298467) (xy 401.684537 -49.312573) (xy 401.6291 -49.318673)
			(xy 401.573366 -49.316636) (xy 401.518523 -49.306506) (xy 401.465739 -49.288499) (xy 401.416139 -49.262998)
			(xy 401.370781 -49.230547) (xy 401.330632 -49.191838) (xy 401.296546 -49.147695) (xy 401.26925 -49.09906)
			(xy 401.249327 -49.046969) (xy 401.237201 -48.992532) (xy 401.23313 -48.93691) (xy 398.274641 -48.93691)
			(xy 398.268959 -48.975522) (xy 398.252891 -49.028929) (xy 398.229219 -49.079426) (xy 398.198446 -49.125939)
			(xy 398.161229 -49.167476) (xy 398.118361 -49.203151) (xy 398.070755 -49.232205) (xy 398.019426 -49.254017)
			(xy 397.965469 -49.268123) (xy 397.910032 -49.274223) (xy 397.854298 -49.272186) (xy 397.799455 -49.262056)
			(xy 397.746671 -49.244049) (xy 397.697071 -49.218548) (xy 397.651713 -49.186097) (xy 397.611564 -49.147388)
			(xy 397.577478 -49.103245) (xy 397.550182 -49.05461) (xy 397.530259 -49.002519) (xy 397.518133 -48.948082)
			(xy 397.514062 -48.89246) (xy 396.205779 -48.89246) (xy 396.183503 -48.93998) (xy 396.15273 -48.986493)
			(xy 396.115513 -49.02803) (xy 396.072645 -49.063705) (xy 396.025039 -49.092759) (xy 395.97371 -49.114571)
			(xy 395.919753 -49.128677) (xy 395.864316 -49.134777) (xy 395.808582 -49.13274) (xy 395.753739 -49.12261)
			(xy 395.700955 -49.104603) (xy 395.651355 -49.079102) (xy 395.605997 -49.046651) (xy 395.565848 -49.007942)
			(xy 395.531762 -48.963799) (xy 395.504466 -48.915164) (xy 395.484543 -48.863073) (xy 395.472417 -48.808636)
			(xy 395.468346 -48.753014) (xy 387.497324 -48.753014) (xy 387.902982 -49.95291) (xy 401.23313 -49.95291)
			(xy 401.237201 -49.897288) (xy 401.249327 -49.842851) (xy 401.26925 -49.79076) (xy 401.296546 -49.742125)
			(xy 401.330632 -49.697982) (xy 401.370781 -49.659273) (xy 401.416139 -49.626822) (xy 401.465739 -49.601321)
			(xy 401.518523 -49.583314) (xy 401.573366 -49.573184) (xy 401.6291 -49.571147) (xy 401.684537 -49.577247)
			(xy 401.738494 -49.591353) (xy 401.789823 -49.613165) (xy 401.837429 -49.642219) (xy 401.880297 -49.677894)
			(xy 401.917514 -49.719431) (xy 401.948287 -49.765944) (xy 401.971959 -49.816441) (xy 401.988027 -49.869848)
			(xy 401.996147 -49.925024) (xy 401.996656 -49.95291) (xy 401.996147 -49.980796) (xy 401.988027 -50.035972)
			(xy 401.971959 -50.089379) (xy 401.948287 -50.139876) (xy 401.917514 -50.186389) (xy 401.880297 -50.227926)
			(xy 401.837429 -50.263601) (xy 401.789823 -50.292655) (xy 401.738494 -50.314467) (xy 401.684537 -50.328573)
			(xy 401.6291 -50.334673) (xy 401.573366 -50.332636) (xy 401.518523 -50.322506) (xy 401.465739 -50.304499)
			(xy 401.416139 -50.278998) (xy 401.370781 -50.246547) (xy 401.330632 -50.207838) (xy 401.296546 -50.163695)
			(xy 401.26925 -50.11506) (xy 401.249327 -50.062969) (xy 401.237201 -50.008532) (xy 401.23313 -49.95291)
			(xy 387.902982 -49.95291) (xy 387.931406 -50.036984) (xy 387.945142 -50.079111) (xy 387.965969 -50.165242)
			(xy 387.979077 -50.252881) (xy 387.982206 -50.29708) (xy 387.993128 -50.480214) (xy 388.025126 -51.019456)
			(xy 399.049492 -51.019456) (xy 399.053563 -50.963834) (xy 399.065689 -50.909397) (xy 399.085612 -50.857306)
			(xy 399.112908 -50.808671) (xy 399.146994 -50.764528) (xy 399.187143 -50.725819) (xy 399.232501 -50.693368)
			(xy 399.282101 -50.667867) (xy 399.334885 -50.64986) (xy 399.389728 -50.63973) (xy 399.445462 -50.637693)
			(xy 399.500899 -50.643793) (xy 399.554856 -50.657899) (xy 399.606185 -50.679711) (xy 399.653791 -50.708765)
			(xy 399.696659 -50.74444) (xy 399.733876 -50.785977) (xy 399.764649 -50.83249) (xy 399.788321 -50.882987)
			(xy 399.804389 -50.936394) (xy 399.812509 -50.99157) (xy 399.813018 -51.019456) (xy 399.812509 -51.047342)
			(xy 399.804389 -51.102518) (xy 399.788321 -51.155925) (xy 399.764649 -51.206422) (xy 399.733876 -51.252935)
			(xy 399.696659 -51.294472) (xy 399.653791 -51.330147) (xy 399.606185 -51.359201) (xy 399.554856 -51.381013)
			(xy 399.500899 -51.395119) (xy 399.445462 -51.401219) (xy 399.389728 -51.399182) (xy 399.334885 -51.389052)
			(xy 399.282101 -51.371045) (xy 399.232501 -51.345544) (xy 399.187143 -51.313093) (xy 399.146994 -51.274384)
			(xy 399.112908 -51.230241) (xy 399.085612 -51.181606) (xy 399.065689 -51.129515) (xy 399.053563 -51.075078)
			(xy 399.049492 -51.019456) (xy 388.025126 -51.019456) (xy 388.032752 -51.14798) (xy 388.085706 -52.035456)
			(xy 401.241258 -52.035456) (xy 401.245329 -51.979834) (xy 401.257455 -51.925397) (xy 401.277378 -51.873306)
			(xy 401.304674 -51.824671) (xy 401.33876 -51.780528) (xy 401.378909 -51.741819) (xy 401.424267 -51.709368)
			(xy 401.473867 -51.683867) (xy 401.526651 -51.66586) (xy 401.581494 -51.65573) (xy 401.637228 -51.653693)
			(xy 401.692665 -51.659793) (xy 401.746622 -51.673899) (xy 401.797951 -51.695711) (xy 401.845557 -51.724765)
			(xy 401.888425 -51.76044) (xy 401.925642 -51.801977) (xy 401.956415 -51.84849) (xy 401.980087 -51.898987)
			(xy 401.996155 -51.952394) (xy 402.004275 -52.00757) (xy 402.004784 -52.035456) (xy 402.004275 -52.063342)
			(xy 401.996155 -52.118518) (xy 401.980087 -52.171925) (xy 401.956415 -52.222422) (xy 401.925642 -52.268935)
			(xy 401.888425 -52.310472) (xy 401.845557 -52.346147) (xy 401.797951 -52.375201) (xy 401.746622 -52.397013)
			(xy 401.692665 -52.411119) (xy 401.637228 -52.417219) (xy 401.581494 -52.415182) (xy 401.526651 -52.405052)
			(xy 401.473867 -52.387045) (xy 401.424267 -52.361544) (xy 401.378909 -52.329093) (xy 401.33876 -52.290384)
			(xy 401.304674 -52.246241) (xy 401.277378 -52.197606) (xy 401.257455 -52.145515) (xy 401.245329 -52.091078)
			(xy 401.241258 -52.035456) (xy 388.085706 -52.035456) (xy 388.107682 -52.403756) (xy 388.10996 -52.415114)
			(xy 388.123058 -52.434192) (xy 388.143161 -52.445656) (xy 388.154672 -52.446936) (xy 388.1628 -52.446936)
			(xy 388.16534 -52.446682) (xy 388.20217 -52.444904) (xy 388.229424 -52.445365) (xy 388.283377 -52.453119)
			(xy 388.335678 -52.468472) (xy 388.385261 -52.491113) (xy 388.431117 -52.520581) (xy 388.472313 -52.556275)
			(xy 388.508008 -52.597468) (xy 388.537478 -52.643323) (xy 388.560121 -52.692905) (xy 388.575477 -52.745205)
			(xy 388.583233 -52.799158) (xy 388.583678 -52.826412) (xy 388.583253 -52.851923) (xy 388.576457 -52.902491)
			(xy 388.562988 -52.951703) (xy 388.543086 -52.998683) (xy 388.517105 -53.042595) (xy 388.501636 -53.062886)
			(xy 388.499096 -53.065934) (xy 388.49808 -53.067458) (xy 388.494778 -53.074062) (xy 388.492435 -53.079285)
			(xy 388.48987 -53.090438) (xy 388.489698 -53.09616) (xy 388.489698 -53.128164) (xy 388.478522 -53.128164)
			(xy 388.478522 -53.178964) (xy 388.478857 -53.187567) (xy 388.484571 -53.203797) (xy 388.489698 -53.210714)
			(xy 388.490968 -53.212238) (xy 388.50836 -53.233115) (xy 388.537676 -53.278866) (xy 388.560202 -53.328314)
			(xy 388.575482 -53.380458) (xy 388.583206 -53.434244) (xy 388.583678 -53.461412) (xy 388.583253 -53.486923)
			(xy 388.576457 -53.537491) (xy 388.562988 -53.586703) (xy 388.543086 -53.633683) (xy 388.517105 -53.677595)
			(xy 388.501636 -53.697886) (xy 388.499096 -53.700934) (xy 388.49808 -53.702458) (xy 388.494778 -53.709062)
			(xy 388.492435 -53.714285) (xy 388.48987 -53.725438) (xy 388.489698 -53.73116) (xy 388.489698 -53.763164)
			(xy 388.478522 -53.763164) (xy 388.478522 -53.813964) (xy 388.478857 -53.822567) (xy 388.484571 -53.838797)
			(xy 388.489698 -53.845714) (xy 388.490968 -53.847238) (xy 388.50836 -53.868115) (xy 388.537676 -53.913866)
			(xy 388.560202 -53.963314) (xy 388.575482 -54.015458) (xy 388.583206 -54.069244) (xy 388.583678 -54.096412)
			(xy 388.583253 -54.121923) (xy 388.576457 -54.172491) (xy 388.562988 -54.221703) (xy 388.543086 -54.268683)
			(xy 388.517105 -54.312595) (xy 388.501636 -54.332886) (xy 388.499096 -54.335934) (xy 388.49808 -54.337458)
			(xy 388.494778 -54.344062) (xy 388.492435 -54.349285) (xy 388.48987 -54.360438) (xy 388.489698 -54.36616)
			(xy 388.489698 -54.398164) (xy 388.478522 -54.398164) (xy 388.478522 -54.448964) (xy 388.478857 -54.457567)
			(xy 388.484571 -54.473797) (xy 388.489698 -54.480714) (xy 388.490968 -54.482238) (xy 388.50836 -54.503115)
			(xy 388.537676 -54.548866) (xy 388.560202 -54.598314) (xy 388.575482 -54.650458) (xy 388.583206 -54.704244)
			(xy 388.583678 -54.731412) (xy 388.583213 -54.75877) (xy 388.578552 -54.791102) (xy 390.476486 -54.791102)
			(xy 390.476957 -54.763732) (xy 390.484774 -54.709553) (xy 390.500262 -54.65705) (xy 390.523103 -54.607303)
			(xy 390.552826 -54.561336) (xy 390.570466 -54.540404) (xy 390.57072 -54.54015) (xy 390.576294 -54.533055)
			(xy 390.582548 -54.516145) (xy 390.582912 -54.50713) (xy 390.582912 -54.440074) (xy 390.582565 -54.431056)
			(xy 390.57631 -54.41414) (xy 390.57072 -54.407054) (xy 390.570466 -54.407054) (xy 390.570466 -54.4068)
			(xy 390.552826 -54.385866) (xy 390.523098 -54.3399) (xy 390.50025 -54.290154) (xy 390.484752 -54.237652)
			(xy 390.476922 -54.183472) (xy 390.476922 -54.128731) (xy 390.484751 -54.074551) (xy 390.500249 -54.022049)
			(xy 390.523096 -53.972303) (xy 390.552824 -53.926336) (xy 390.570466 -53.905404) (xy 390.57072 -53.90515)
			(xy 390.576294 -53.898055) (xy 390.582548 -53.881145) (xy 390.582912 -53.87213) (xy 390.582912 -53.805074)
			(xy 390.582565 -53.796056) (xy 390.57631 -53.77914) (xy 390.57072 -53.772054) (xy 390.570466 -53.772054)
			(xy 390.570466 -53.7718) (xy 390.552826 -53.750866) (xy 390.523098 -53.7049) (xy 390.50025 -53.655154)
			(xy 390.484752 -53.602652) (xy 390.476922 -53.548472) (xy 390.476922 -53.493731) (xy 390.484751 -53.439551)
			(xy 390.500249 -53.387049) (xy 390.523096 -53.337303) (xy 390.552824 -53.291336) (xy 390.570466 -53.270404)
			(xy 390.57072 -53.27015) (xy 390.576294 -53.263055) (xy 390.582548 -53.246145) (xy 390.582912 -53.23713)
			(xy 390.582912 -53.170074) (xy 390.582565 -53.161056) (xy 390.57631 -53.14414) (xy 390.57072 -53.137054)
			(xy 390.570466 -53.137054) (xy 390.570466 -53.1368) (xy 390.552808 -53.115883) (xy 390.5231 -53.069906)
			(xy 390.500269 -53.020154) (xy 390.484782 -52.96765) (xy 390.476958 -52.913472) (xy 390.476486 -52.886102)
			(xy 390.476972 -52.858851) (xy 390.484728 -52.804903) (xy 390.500083 -52.752608) (xy 390.522725 -52.703031)
			(xy 390.552191 -52.657181) (xy 390.587882 -52.61599) (xy 390.629073 -52.580299) (xy 390.674923 -52.550833)
			(xy 390.7245 -52.528191) (xy 390.776795 -52.512836) (xy 390.830743 -52.50508) (xy 390.885245 -52.50508)
			(xy 390.939193 -52.512836) (xy 390.991488 -52.528191) (xy 391.030588 -52.546048) (xy 395.979696 -52.546048)
			(xy 395.979696 -52.491552) (xy 395.987451 -52.437612) (xy 396.002803 -52.385323) (xy 396.025439 -52.335752)
			(xy 396.054899 -52.289906) (xy 396.090584 -52.248719) (xy 396.131766 -52.213029) (xy 396.177608 -52.183563)
			(xy 396.227176 -52.16092) (xy 396.279463 -52.145562) (xy 396.333402 -52.1378) (xy 396.36065 -52.13731)
			(xy 396.388019 -52.137803) (xy 396.442197 -52.145614) (xy 396.4947 -52.161097) (xy 396.544448 -52.183932)
			(xy 396.590415 -52.213651) (xy 396.611348 -52.23129) (xy 396.611602 -52.231544) (xy 396.61868 -52.237143)
			(xy 396.635604 -52.243381) (xy 396.644622 -52.243736) (xy 396.711678 -52.243736) (xy 396.720693 -52.243361)
			(xy 396.737609 -52.237125) (xy 396.744698 -52.231544) (xy 396.744698 -52.23129) (xy 396.744952 -52.23129)
			(xy 396.765885 -52.213649) (xy 396.811853 -52.183925) (xy 396.861599 -52.161079) (xy 396.914101 -52.145583)
			(xy 396.968279 -52.137754) (xy 397.023021 -52.137754) (xy 397.077199 -52.145583) (xy 397.129701 -52.161079)
			(xy 397.179447 -52.183925) (xy 397.225415 -52.213649) (xy 397.246348 -52.23129) (xy 397.246602 -52.231544)
			(xy 397.25368 -52.237143) (xy 397.270604 -52.243381) (xy 397.279622 -52.243736) (xy 397.346678 -52.243736)
			(xy 397.355693 -52.243361) (xy 397.372609 -52.237125) (xy 397.379698 -52.231544) (xy 397.379698 -52.23129)
			(xy 397.379952 -52.23129) (xy 397.40089 -52.213658) (xy 397.446861 -52.183946) (xy 397.496607 -52.161109)
			(xy 397.549107 -52.145616) (xy 397.603281 -52.137785) (xy 397.63065 -52.13731) (xy 397.657906 -52.137733)
			(xy 397.711865 -52.145485) (xy 397.764172 -52.160837) (xy 397.813761 -52.183478) (xy 397.859622 -52.212946)
			(xy 397.900823 -52.248642) (xy 397.936524 -52.289838) (xy 397.965998 -52.335695) (xy 397.988645 -52.385281)
			(xy 398.004004 -52.437586) (xy 398.011763 -52.491544) (xy 398.011763 -52.546056) (xy 398.005818 -52.587398)
			(xy 399.055334 -52.587398) (xy 399.059405 -52.531776) (xy 399.071531 -52.477339) (xy 399.091454 -52.425248)
			(xy 399.11875 -52.376613) (xy 399.152836 -52.33247) (xy 399.192985 -52.293761) (xy 399.238343 -52.26131)
			(xy 399.287943 -52.235809) (xy 399.340727 -52.217802) (xy 399.39557 -52.207672) (xy 399.451304 -52.205635)
			(xy 399.506741 -52.211735) (xy 399.560698 -52.225841) (xy 399.612027 -52.247653) (xy 399.659633 -52.276707)
			(xy 399.702501 -52.312382) (xy 399.739718 -52.353919) (xy 399.770491 -52.400432) (xy 399.794163 -52.450929)
			(xy 399.810231 -52.504336) (xy 399.817827 -52.555948) (xy 406.883902 -52.555948) (xy 406.883902 -52.501452)
			(xy 406.891657 -52.44751) (xy 406.90701 -52.395221) (xy 406.929647 -52.345649) (xy 406.959109 -52.299803)
			(xy 406.994795 -52.258616) (xy 407.035979 -52.222927) (xy 407.081823 -52.193462) (xy 407.131393 -52.17082)
			(xy 407.183681 -52.155464) (xy 407.237622 -52.147704) (xy 407.26487 -52.147216) (xy 407.29224 -52.147696)
			(xy 407.346418 -52.15551) (xy 407.398922 -52.170995) (xy 407.448669 -52.193834) (xy 407.494636 -52.223556)
			(xy 407.515568 -52.241196) (xy 407.515822 -52.24145) (xy 407.522894 -52.247058) (xy 407.539822 -52.253291)
			(xy 407.548842 -52.253642) (xy 407.615898 -52.253642) (xy 407.624916 -52.253296) (xy 407.641834 -52.247042)
			(xy 407.648918 -52.24145) (xy 407.648918 -52.241196) (xy 407.649172 -52.241196) (xy 407.670103 -52.223556)
			(xy 407.716076 -52.193844) (xy 407.765824 -52.171009) (xy 407.818325 -52.155518) (xy 407.872501 -52.14769)
			(xy 407.89987 -52.147216) (xy 407.927126 -52.147629) (xy 407.981084 -52.155383) (xy 408.033388 -52.170737)
			(xy 408.082976 -52.19338) (xy 408.128835 -52.222849) (xy 408.170034 -52.258545) (xy 408.205733 -52.299741)
			(xy 408.235206 -52.345598) (xy 408.257852 -52.395183) (xy 408.273211 -52.447487) (xy 408.280969 -52.501444)
			(xy 408.280969 -52.555956) (xy 408.273211 -52.609913) (xy 408.257852 -52.662217) (xy 408.235206 -52.711802)
			(xy 408.205733 -52.757659) (xy 408.170034 -52.798855) (xy 408.128835 -52.834551) (xy 408.082976 -52.86402)
			(xy 408.033388 -52.886663) (xy 407.981084 -52.902017) (xy 407.927126 -52.909771) (xy 407.89987 -52.910232)
			(xy 407.872498 -52.9098) (xy 407.818317 -52.901977) (xy 407.765813 -52.88648) (xy 407.716067 -52.863631)
			(xy 407.670102 -52.833898) (xy 407.649172 -52.816252) (xy 407.648918 -52.815998) (xy 407.641831 -52.810413)
			(xy 407.624914 -52.804165) (xy 407.615898 -52.803806) (xy 407.548842 -52.803806) (xy 407.539827 -52.804182)
			(xy 407.52291 -52.810416) (xy 407.515822 -52.815998) (xy 407.515822 -52.816252) (xy 407.515568 -52.816252)
			(xy 407.494615 -52.833865) (xy 407.448649 -52.863583) (xy 407.398907 -52.886424) (xy 407.34641 -52.901921)
			(xy 407.292238 -52.909755) (xy 407.26487 -52.910232) (xy 407.237622 -52.909696) (xy 407.183681 -52.901936)
			(xy 407.131393 -52.88658) (xy 407.081823 -52.863938) (xy 407.035979 -52.834473) (xy 406.994795 -52.798784)
			(xy 406.959109 -52.757597) (xy 406.929647 -52.711751) (xy 406.90701 -52.662179) (xy 406.891657 -52.60989)
			(xy 406.883902 -52.555948) (xy 399.817827 -52.555948) (xy 399.818351 -52.559512) (xy 399.81886 -52.587398)
			(xy 399.818351 -52.615284) (xy 399.810231 -52.67046) (xy 399.794163 -52.723867) (xy 399.770491 -52.774364)
			(xy 399.739718 -52.820877) (xy 399.702501 -52.862414) (xy 399.659633 -52.898089) (xy 399.612027 -52.927143)
			(xy 399.560698 -52.948955) (xy 399.506741 -52.963061) (xy 399.451304 -52.969161) (xy 399.39557 -52.967124)
			(xy 399.340727 -52.956994) (xy 399.287943 -52.938987) (xy 399.238343 -52.913486) (xy 399.192985 -52.881035)
			(xy 399.152836 -52.842326) (xy 399.11875 -52.798183) (xy 399.091454 -52.749548) (xy 399.071531 -52.697457)
			(xy 399.059405 -52.64302) (xy 399.055334 -52.587398) (xy 398.005818 -52.587398) (xy 398.004004 -52.600014)
			(xy 397.988645 -52.652319) (xy 397.965998 -52.701905) (xy 397.936524 -52.747762) (xy 397.900823 -52.788958)
			(xy 397.859622 -52.824654) (xy 397.813761 -52.854122) (xy 397.764172 -52.876763) (xy 397.711865 -52.892115)
			(xy 397.657907 -52.899867) (xy 397.63065 -52.900326) (xy 397.60328 -52.899849) (xy 397.549101 -52.892036)
			(xy 397.496597 -52.876551) (xy 397.44685 -52.853711) (xy 397.400883 -52.823987) (xy 397.379952 -52.806346)
			(xy 397.379698 -52.806092) (xy 397.372617 -52.800498) (xy 397.355696 -52.794256) (xy 397.346678 -52.7939)
			(xy 397.279622 -52.7939) (xy 397.270606 -52.794267) (xy 397.253689 -52.800508) (xy 397.246602 -52.806092)
			(xy 397.246348 -52.806346) (xy 397.225415 -52.823987) (xy 397.179447 -52.853711) (xy 397.129701 -52.876557)
			(xy 397.077199 -52.892053) (xy 397.023021 -52.899882) (xy 396.968279 -52.899882) (xy 396.914101 -52.892053)
			(xy 396.861599 -52.876557) (xy 396.811853 -52.853711) (xy 396.765885 -52.823987) (xy 396.744952 -52.806346)
			(xy 396.744698 -52.806092) (xy 396.737617 -52.800498) (xy 396.720696 -52.794256) (xy 396.711678 -52.7939)
			(xy 396.644622 -52.7939) (xy 396.635606 -52.794267) (xy 396.618689 -52.800508) (xy 396.611602 -52.806092)
			(xy 396.611602 -52.806346) (xy 396.611348 -52.806346) (xy 396.590402 -52.823968) (xy 396.544434 -52.853684)
			(xy 396.49469 -52.876524) (xy 396.442192 -52.892019) (xy 396.388018 -52.899851) (xy 396.36065 -52.900326)
			(xy 396.333402 -52.8998) (xy 396.279463 -52.892038) (xy 396.227176 -52.87668) (xy 396.177608 -52.854037)
			(xy 396.131766 -52.824571) (xy 396.090584 -52.788881) (xy 396.054899 -52.747694) (xy 396.025439 -52.701848)
			(xy 396.002803 -52.652277) (xy 395.987451 -52.599988) (xy 395.979696 -52.546048) (xy 391.030588 -52.546048)
			(xy 391.041065 -52.550833) (xy 391.086915 -52.580299) (xy 391.128106 -52.61599) (xy 391.163797 -52.657181)
			(xy 391.193263 -52.703031) (xy 391.215905 -52.752608) (xy 391.23126 -52.804903) (xy 391.239016 -52.858851)
			(xy 391.239502 -52.886102) (xy 391.239037 -52.913472) (xy 391.231219 -52.967651) (xy 391.215729 -53.020154)
			(xy 391.192887 -53.069901) (xy 391.163163 -53.115868) (xy 391.145522 -53.1368) (xy 391.145268 -53.137054)
			(xy 391.139691 -53.144147) (xy 391.13344 -53.161059) (xy 391.133076 -53.170074) (xy 391.133076 -53.23713)
			(xy 391.133424 -53.246148) (xy 391.139678 -53.263064) (xy 391.145268 -53.27015) (xy 391.145522 -53.27015)
			(xy 391.145522 -53.270404) (xy 391.163163 -53.291336) (xy 391.192884 -53.337305) (xy 391.215726 -53.387052)
			(xy 391.23122 -53.439554) (xy 391.239047 -53.493731) (xy 391.239047 -53.548472) (xy 391.231219 -53.602649)
			(xy 391.215725 -53.655151) (xy 391.192882 -53.704897) (xy 391.163161 -53.750866) (xy 391.146592 -53.77053)
			(xy 391.510774 -53.77053) (xy 391.511286 -53.741612) (xy 391.520012 -53.68444) (xy 391.537269 -53.62924)
			(xy 391.562662 -53.577277) (xy 391.595608 -53.529744) (xy 391.635353 -53.487729) (xy 391.65784 -53.46954)
			(xy 391.666626 -53.461912) (xy 391.676819 -53.441027) (xy 391.677398 -53.429408) (xy 391.677398 -53.349652)
			(xy 391.676873 -53.338018) (xy 391.666674 -53.317109) (xy 391.65784 -53.30952) (xy 391.635374 -53.291308)
			(xy 391.595636 -53.249293) (xy 391.562694 -53.201763) (xy 391.537302 -53.149806) (xy 391.520043 -53.094612)
			(xy 391.51131 -53.037445) (xy 391.510774 -53.00853) (xy 391.511283 -52.981279) (xy 391.519036 -52.92733)
			(xy 391.534387 -52.875034) (xy 391.557025 -52.825456) (xy 391.586488 -52.779603) (xy 391.622177 -52.738411)
			(xy 391.663365 -52.702717) (xy 391.709213 -52.673248) (xy 391.758789 -52.650604) (xy 391.811083 -52.635246)
			(xy 391.865031 -52.627487) (xy 391.892282 -52.627022) (xy 391.918596 -52.627494) (xy 391.970724 -52.634727)
			(xy 392.021367 -52.649045) (xy 392.069567 -52.670176) (xy 392.11441 -52.697722) (xy 392.15505 -52.73116)
			(xy 392.173206 -52.750212) (xy 392.180722 -52.75762) (xy 392.200006 -52.766141) (xy 392.210544 -52.766722)
			(xy 392.28522 -52.766722) (xy 392.295765 -52.766157) (xy 392.315061 -52.757646) (xy 392.322558 -52.750212)
			(xy 392.340695 -52.731138) (xy 392.381328 -52.697682) (xy 392.426172 -52.670125) (xy 392.474377 -52.64899)
			(xy 392.525028 -52.634677) (xy 392.577165 -52.627457) (xy 392.603482 -52.627022) (xy 392.630736 -52.627472)
			(xy 392.684689 -52.635227) (xy 392.736989 -52.650583) (xy 392.786571 -52.673225) (xy 392.832425 -52.702694)
			(xy 392.873619 -52.738389) (xy 392.909313 -52.779584) (xy 392.93878 -52.82544) (xy 392.961421 -52.875023)
			(xy 392.976775 -52.927323) (xy 392.984529 -52.981276) (xy 392.98499 -53.00853) (xy 392.984506 -53.036196)
			(xy 392.982275 -53.051456) (xy 401.241258 -53.051456) (xy 401.245329 -52.995834) (xy 401.257455 -52.941397)
			(xy 401.277378 -52.889306) (xy 401.304674 -52.840671) (xy 401.33876 -52.796528) (xy 401.378909 -52.757819)
			(xy 401.424267 -52.725368) (xy 401.473867 -52.699867) (xy 401.526651 -52.68186) (xy 401.581494 -52.67173)
			(xy 401.637228 -52.669693) (xy 401.692665 -52.675793) (xy 401.746622 -52.689899) (xy 401.797951 -52.711711)
			(xy 401.845557 -52.740765) (xy 401.888425 -52.77644) (xy 401.925642 -52.817977) (xy 401.956415 -52.86449)
			(xy 401.980087 -52.914987) (xy 401.996155 -52.968394) (xy 402.004275 -53.02357) (xy 402.004784 -53.051456)
			(xy 402.004275 -53.079342) (xy 401.996155 -53.134518) (xy 401.980087 -53.187925) (xy 401.956415 -53.238422)
			(xy 401.925642 -53.284935) (xy 401.888425 -53.326472) (xy 401.845557 -53.362147) (xy 401.797951 -53.391201)
			(xy 401.746622 -53.413013) (xy 401.692665 -53.427119) (xy 401.637228 -53.433219) (xy 401.581494 -53.431182)
			(xy 401.526651 -53.421052) (xy 401.473867 -53.403045) (xy 401.424267 -53.377544) (xy 401.378909 -53.345093)
			(xy 401.33876 -53.306384) (xy 401.304674 -53.262241) (xy 401.277378 -53.213606) (xy 401.257455 -53.161515)
			(xy 401.245329 -53.107078) (xy 401.241258 -53.051456) (xy 392.982275 -53.051456) (xy 392.976502 -53.090947)
			(xy 392.960681 -53.143969) (xy 392.937373 -53.194154) (xy 392.907068 -53.240449) (xy 392.870398 -53.281886)
			(xy 392.828133 -53.317598) (xy 392.804904 -53.332634) (xy 392.795223 -53.339267) (xy 392.782779 -53.35913)
			(xy 392.781028 -53.370734) (xy 392.773154 -53.450744) (xy 392.772501 -53.462383) (xy 392.780596 -53.484222)
			(xy 392.788648 -53.492654) (xy 392.788902 -53.492908) (xy 392.80747 -53.511002) (xy 392.840049 -53.551331)
			(xy 392.866864 -53.595703) (xy 392.887419 -53.643299) (xy 392.901335 -53.693241) (xy 392.908356 -53.744608)
			(xy 392.90879 -53.77053) (xy 392.90835 -53.797783) (xy 392.900589 -53.851733) (xy 392.885229 -53.90403)
			(xy 392.862583 -53.953608) (xy 392.833112 -53.999459) (xy 392.797416 -54.04065) (xy 392.756221 -54.076341)
			(xy 392.710366 -54.105806) (xy 392.660785 -54.128446) (xy 392.608486 -54.143799) (xy 392.554535 -54.151553)
			(xy 392.527282 -54.152038) (xy 392.499911 -54.151598) (xy 392.44573 -54.143776) (xy 392.393226 -54.128282)
			(xy 392.343479 -54.105434) (xy 392.297514 -54.075703) (xy 392.276584 -54.058058) (xy 392.27633 -54.057804)
			(xy 392.269239 -54.052224) (xy 392.252326 -54.045973) (xy 392.24331 -54.045612) (xy 392.176254 -54.045612)
			(xy 392.167239 -54.045992) (xy 392.150322 -54.052224) (xy 392.143234 -54.057804) (xy 392.143234 -54.058058)
			(xy 392.14298 -54.058058) (xy 392.122023 -54.075667) (xy 392.076058 -54.105384) (xy 392.026317 -54.128227)
			(xy 391.973821 -54.143725) (xy 391.91965 -54.15156) (xy 391.892282 -54.152038) (xy 391.865032 -54.151539)
			(xy 391.811086 -54.143781) (xy 391.758793 -54.128425) (xy 391.709218 -54.105784) (xy 391.663369 -54.076319)
			(xy 391.62218 -54.040629) (xy 391.586489 -53.99944) (xy 391.557022 -53.953593) (xy 391.534379 -53.904018)
			(xy 391.519022 -53.851726) (xy 391.511262 -53.79778) (xy 391.510774 -53.77053) (xy 391.146592 -53.77053)
			(xy 391.145522 -53.7718) (xy 391.145268 -53.772054) (xy 391.139691 -53.779147) (xy 391.13344 -53.796059)
			(xy 391.133076 -53.805074) (xy 391.133076 -53.87213) (xy 391.133424 -53.881148) (xy 391.139678 -53.898064)
			(xy 391.145268 -53.90515) (xy 391.145522 -53.90515) (xy 391.145522 -53.905404) (xy 391.163163 -53.926336)
			(xy 391.192884 -53.972305) (xy 391.215726 -54.022052) (xy 391.23122 -54.074554) (xy 391.239047 -54.128731)
			(xy 391.239047 -54.183472) (xy 391.231219 -54.237649) (xy 391.215725 -54.290151) (xy 391.201933 -54.320186)
			(xy 393.430506 -54.320186) (xy 393.430962 -54.292815) (xy 393.438782 -54.238636) (xy 393.454274 -54.186133)
			(xy 393.477117 -54.136386) (xy 393.506844 -54.090419) (xy 393.524486 -54.069488) (xy 393.52474 -54.069234)
			(xy 393.530323 -54.062145) (xy 393.536571 -54.04523) (xy 393.536932 -54.036214) (xy 393.536932 -53.969158)
			(xy 393.53654 -53.960145) (xy 393.530316 -53.943228) (xy 393.52474 -53.936138) (xy 393.524486 -53.936138)
			(xy 393.524486 -53.935884) (xy 393.506871 -53.914933) (xy 393.477156 -53.868965) (xy 393.454315 -53.819222)
			(xy 393.438819 -53.766726) (xy 393.430984 -53.712554) (xy 393.430506 -53.685186) (xy 393.430992 -53.657935)
			(xy 393.438748 -53.603987) (xy 393.454103 -53.551692) (xy 393.476745 -53.502115) (xy 393.506211 -53.456265)
			(xy 393.541902 -53.415074) (xy 393.583093 -53.379383) (xy 393.628943 -53.349917) (xy 393.67852 -53.327275)
			(xy 393.730815 -53.31192) (xy 393.784763 -53.304164) (xy 393.839265 -53.304164) (xy 393.893213 -53.31192)
			(xy 393.945508 -53.327275) (xy 393.995085 -53.349917) (xy 394.040935 -53.379383) (xy 394.082126 -53.415074)
			(xy 394.117817 -53.456265) (xy 394.14371 -53.496555) (xy 406.433441 -53.496555) (xy 406.433441 -53.442045)
			(xy 406.441199 -53.388089) (xy 406.456557 -53.335787) (xy 406.479202 -53.286203) (xy 406.508674 -53.240347)
			(xy 406.544372 -53.199152) (xy 406.58557 -53.163457) (xy 406.631428 -53.133989) (xy 406.681014 -53.111347)
			(xy 406.733317 -53.095993) (xy 406.787273 -53.088239) (xy 406.814528 -53.087778) (xy 406.8419 -53.088209)
			(xy 406.896081 -53.096032) (xy 406.948585 -53.111528) (xy 406.998332 -53.134379) (xy 407.044296 -53.164112)
			(xy 407.065226 -53.181758) (xy 407.06548 -53.182012) (xy 407.072567 -53.187598) (xy 407.089484 -53.193845)
			(xy 407.0985 -53.194204) (xy 407.165556 -53.194204) (xy 407.174571 -53.193825) (xy 407.191488 -53.187593)
			(xy 407.198576 -53.182012) (xy 407.198576 -53.181758) (xy 407.19883 -53.181758) (xy 407.219772 -53.164131)
			(xy 407.265743 -53.134419) (xy 407.315488 -53.111581) (xy 407.367986 -53.096087) (xy 407.42216 -53.088254)
			(xy 407.449528 -53.087778) (xy 407.476777 -53.088294) (xy 407.53072 -53.096054) (xy 407.583009 -53.111411)
			(xy 407.632581 -53.134052) (xy 407.678426 -53.163518) (xy 407.719611 -53.199209) (xy 407.755298 -53.240396)
			(xy 407.784761 -53.286244) (xy 407.807399 -53.335817) (xy 407.822752 -53.388108) (xy 407.830508 -53.442051)
			(xy 407.830508 -53.496549) (xy 407.822752 -53.550492) (xy 407.807399 -53.602783) (xy 407.784761 -53.652356)
			(xy 407.755298 -53.698204) (xy 407.719611 -53.739391) (xy 407.678426 -53.775082) (xy 407.632581 -53.804548)
			(xy 407.583009 -53.827189) (xy 407.53072 -53.842546) (xy 407.476777 -53.850306) (xy 407.449528 -53.850794)
			(xy 407.422158 -53.850313) (xy 407.36798 -53.842499) (xy 407.315477 -53.827013) (xy 407.26573 -53.804175)
			(xy 407.219762 -53.774454) (xy 407.19883 -53.756814) (xy 407.198576 -53.75656) (xy 407.191504 -53.750952)
			(xy 407.174576 -53.744719) (xy 407.165556 -53.744368) (xy 407.0985 -53.744368) (xy 407.089484 -53.744732)
			(xy 407.072567 -53.750976) (xy 407.06548 -53.75656) (xy 407.06548 -53.756814) (xy 407.065226 -53.756814)
			(xy 407.044297 -53.774457) (xy 406.998323 -53.804167) (xy 406.948575 -53.827002) (xy 406.896073 -53.842493)
			(xy 406.841897 -53.85032) (xy 406.814528 -53.850794) (xy 406.787273 -53.850361) (xy 406.733317 -53.842607)
			(xy 406.681014 -53.827253) (xy 406.631428 -53.804611) (xy 406.58557 -53.775143) (xy 406.544372 -53.739448)
			(xy 406.508674 -53.698253) (xy 406.479202 -53.652397) (xy 406.456557 -53.602813) (xy 406.441199 -53.550511)
			(xy 406.433441 -53.496555) (xy 394.14371 -53.496555) (xy 394.147283 -53.502115) (xy 394.169925 -53.551692)
			(xy 394.18528 -53.603987) (xy 394.193036 -53.657935) (xy 394.193522 -53.685186) (xy 394.193067 -53.712557)
			(xy 394.185249 -53.766737) (xy 394.169759 -53.819241) (xy 394.146914 -53.868988) (xy 394.117186 -53.914953)
			(xy 394.099542 -53.935884) (xy 394.099288 -53.936138) (xy 394.09372 -53.943237) (xy 394.087462 -53.960144)
			(xy 394.087096 -53.969158) (xy 394.087096 -54.036214) (xy 394.087447 -54.045231) (xy 394.093699 -54.062148)
			(xy 394.099288 -54.069234) (xy 394.099542 -54.069234) (xy 394.099542 -54.069488) (xy 394.117196 -54.090408)
			(xy 394.146904 -54.136385) (xy 394.169737 -54.186135) (xy 394.185225 -54.238639) (xy 394.19305 -54.292816)
			(xy 394.193522 -54.320186) (xy 394.193036 -54.347437) (xy 394.18528 -54.401385) (xy 394.169925 -54.45368)
			(xy 394.147283 -54.503257) (xy 394.117817 -54.549107) (xy 394.082126 -54.590298) (xy 394.040935 -54.625989)
			(xy 393.995085 -54.655455) (xy 393.945508 -54.678097) (xy 393.893213 -54.693452) (xy 393.839265 -54.701208)
			(xy 393.784763 -54.701208) (xy 393.730815 -54.693452) (xy 393.67852 -54.678097) (xy 393.628943 -54.655455)
			(xy 393.583093 -54.625989) (xy 393.541902 -54.590298) (xy 393.506211 -54.549107) (xy 393.476745 -54.503257)
			(xy 393.454103 -54.45368) (xy 393.438748 -54.401385) (xy 393.430992 -54.347437) (xy 393.430506 -54.320186)
			(xy 391.201933 -54.320186) (xy 391.192882 -54.339897) (xy 391.163161 -54.385866) (xy 391.145522 -54.4068)
			(xy 391.145268 -54.407054) (xy 391.139691 -54.414147) (xy 391.13344 -54.431059) (xy 391.133076 -54.440074)
			(xy 391.133076 -54.50713) (xy 391.133424 -54.516148) (xy 391.139678 -54.533064) (xy 391.145268 -54.54015)
			(xy 391.145522 -54.54015) (xy 391.145522 -54.540404) (xy 391.16318 -54.561321) (xy 391.192888 -54.607298)
			(xy 391.21572 -54.65705) (xy 391.231207 -54.709554) (xy 391.23903 -54.763732) (xy 391.239147 -54.770528)
			(xy 394.371068 -54.770528) (xy 394.371534 -54.743158) (xy 394.379349 -54.688978) (xy 394.394837 -54.636474)
			(xy 394.41768 -54.586727) (xy 394.447406 -54.540761) (xy 394.465048 -54.51983) (xy 394.465302 -54.519576)
			(xy 394.470905 -54.512501) (xy 394.477142 -54.495575) (xy 394.477494 -54.486556) (xy 394.477494 -54.4195)
			(xy 394.477138 -54.410483) (xy 394.47089 -54.393566) (xy 394.465302 -54.38648) (xy 394.465048 -54.38648)
			(xy 394.465048 -54.386226) (xy 394.447415 -54.365289) (xy 394.417701 -54.319318) (xy 394.394863 -54.269572)
			(xy 394.37937 -54.217072) (xy 394.371542 -54.162897) (xy 394.371068 -54.135528) (xy 394.371554 -54.108277)
			(xy 394.37931 -54.054329) (xy 394.394665 -54.002034) (xy 394.417307 -53.952457) (xy 394.446773 -53.906607)
			(xy 394.482464 -53.865416) (xy 394.523655 -53.829725) (xy 394.569505 -53.800259) (xy 394.619082 -53.777617)
			(xy 394.671377 -53.762262) (xy 394.725325 -53.754506) (xy 394.779827 -53.754506) (xy 394.833775 -53.762262)
			(xy 394.88607 -53.777617) (xy 394.935647 -53.800259) (xy 394.981497 -53.829725) (xy 395.022688 -53.865416)
			(xy 395.058379 -53.906607) (xy 395.087845 -53.952457) (xy 395.09292 -53.96357) (xy 399.072098 -53.96357)
			(xy 399.076169 -53.907948) (xy 399.088295 -53.853511) (xy 399.108218 -53.80142) (xy 399.135514 -53.752785)
			(xy 399.1696 -53.708642) (xy 399.209749 -53.669933) (xy 399.255107 -53.637482) (xy 399.304707 -53.611981)
			(xy 399.357491 -53.593974) (xy 399.412334 -53.583844) (xy 399.468068 -53.581807) (xy 399.523505 -53.587907)
			(xy 399.577462 -53.602013) (xy 399.628791 -53.623825) (xy 399.676397 -53.652879) (xy 399.719265 -53.688554)
			(xy 399.756482 -53.730091) (xy 399.787255 -53.776604) (xy 399.810927 -53.827101) (xy 399.826995 -53.880508)
			(xy 399.835115 -53.935684) (xy 399.835624 -53.96357) (xy 399.835115 -53.991456) (xy 399.826995 -54.046632)
			(xy 399.810927 -54.100039) (xy 399.787255 -54.150536) (xy 399.756482 -54.197049) (xy 399.719265 -54.238586)
			(xy 399.676397 -54.274261) (xy 399.628791 -54.303315) (xy 399.577462 -54.325127) (xy 399.523505 -54.339233)
			(xy 399.468068 -54.345333) (xy 399.412334 -54.343296) (xy 399.357491 -54.333166) (xy 399.304707 -54.315159)
			(xy 399.255107 -54.289658) (xy 399.209749 -54.257207) (xy 399.1696 -54.218498) (xy 399.135514 -54.174355)
			(xy 399.108218 -54.12572) (xy 399.088295 -54.073629) (xy 399.076169 -54.019192) (xy 399.072098 -53.96357)
			(xy 395.09292 -53.96357) (xy 395.110487 -54.002034) (xy 395.125842 -54.054329) (xy 395.133598 -54.108277)
			(xy 395.134084 -54.135528) (xy 395.133638 -54.162899) (xy 395.125816 -54.217079) (xy 395.110322 -54.269583)
			(xy 395.087476 -54.319329) (xy 395.057747 -54.365295) (xy 395.040104 -54.386226) (xy 395.03985 -54.38648)
			(xy 395.03426 -54.393564) (xy 395.028016 -54.410483) (xy 395.027658 -54.4195) (xy 395.027658 -54.486556)
			(xy 395.028023 -54.495572) (xy 395.034264 -54.51249) (xy 395.03985 -54.519576) (xy 395.040104 -54.519576)
			(xy 395.040104 -54.51983) (xy 395.057724 -54.540777) (xy 395.087439 -54.586746) (xy 395.110278 -54.63649)
			(xy 395.125774 -54.688987) (xy 395.133607 -54.74316) (xy 395.134084 -54.770528) (xy 395.133598 -54.797779)
			(xy 395.125842 -54.851727) (xy 395.110487 -54.904022) (xy 395.087845 -54.953599) (xy 395.065059 -54.989055)
			(xy 404.201045 -54.989055) (xy 404.201045 -54.934545) (xy 404.208803 -54.880591) (xy 404.22416 -54.82829)
			(xy 404.246805 -54.778707) (xy 404.276276 -54.732852) (xy 404.311973 -54.691657) (xy 404.353169 -54.655963)
			(xy 404.399026 -54.626494) (xy 404.448611 -54.603853) (xy 404.500913 -54.588498) (xy 404.554867 -54.580743)
			(xy 404.582122 -54.580282) (xy 404.610214 -54.580759) (xy 404.665792 -54.58899) (xy 404.719562 -54.605284)
			(xy 404.770359 -54.629289) (xy 404.817086 -54.660487) (xy 404.85873 -54.698201) (xy 404.894392 -54.741616)
			(xy 404.909274 -54.765448) (xy 404.914608 -54.774338) (xy 404.931626 -54.78653) (xy 405.024844 -54.80685)
			(xy 405.045418 -54.802532) (xy 405.054054 -54.79669) (xy 405.078128 -54.780706) (xy 405.130056 -54.75536)
			(xy 405.185211 -54.73813) (xy 405.242332 -54.72941) (xy 405.271224 -54.728872) (xy 405.298475 -54.729355)
			(xy 405.352422 -54.737115) (xy 405.404715 -54.752472) (xy 405.454291 -54.775114) (xy 405.500141 -54.804581)
			(xy 405.54133 -54.840273) (xy 405.577021 -54.881463) (xy 405.606488 -54.927312) (xy 405.62913 -54.976888)
			(xy 405.644486 -55.029182) (xy 405.652245 -55.083129) (xy 405.652732 -55.11038) (xy 405.652271 -55.137751)
			(xy 405.644454 -55.191931) (xy 405.628965 -55.244434) (xy 405.606122 -55.294181) (xy 405.576395 -55.340147)
			(xy 405.558752 -55.361078) (xy 405.558498 -55.361332) (xy 405.552934 -55.368434) (xy 405.546674 -55.385339)
			(xy 405.546306 -55.394352) (xy 405.546306 -55.461408) (xy 405.546658 -55.470425) (xy 405.552909 -55.487342)
			(xy 405.558498 -55.494428) (xy 405.558752 -55.494428) (xy 405.558752 -55.494682) (xy 405.576374 -55.51563)
			(xy 405.606101 -55.561595) (xy 405.628949 -55.611338) (xy 405.644448 -55.663838) (xy 405.652279 -55.718015)
			(xy 405.652281 -55.772755) (xy 405.644454 -55.826932) (xy 405.62896 -55.879433) (xy 405.606116 -55.929179)
			(xy 405.576392 -55.975146) (xy 405.558752 -55.996078) (xy 405.558498 -55.996332) (xy 405.552934 -56.003434)
			(xy 405.546674 -56.020339) (xy 405.546306 -56.029352) (xy 405.546306 -56.096408) (xy 405.546658 -56.105425)
			(xy 405.552909 -56.122342) (xy 405.558498 -56.129428) (xy 405.558752 -56.129428) (xy 405.558752 -56.129682)
			(xy 405.576389 -56.150616) (xy 405.606103 -56.196588) (xy 405.62894 -56.246335) (xy 405.644431 -56.298835)
			(xy 405.652259 -56.353011) (xy 405.652732 -56.38038) (xy 405.652246 -56.407631) (xy 405.64449 -56.461579)
			(xy 405.629135 -56.513874) (xy 405.606493 -56.563451) (xy 405.577027 -56.609301) (xy 405.541336 -56.650492)
			(xy 405.500145 -56.686183) (xy 405.454295 -56.715649) (xy 405.404718 -56.738291) (xy 405.352423 -56.753646)
			(xy 405.298475 -56.761402) (xy 405.243973 -56.761402) (xy 405.190025 -56.753646) (xy 405.13773 -56.738291)
			(xy 405.088153 -56.715649) (xy 405.042303 -56.686183) (xy 405.001112 -56.650492) (xy 404.965421 -56.609301)
			(xy 404.935955 -56.563451) (xy 404.913313 -56.513874) (xy 404.897958 -56.461579) (xy 404.890202 -56.407631)
			(xy 404.889716 -56.38038) (xy 404.890166 -56.353009) (xy 404.897987 -56.298829) (xy 404.91348 -56.246326)
			(xy 404.936325 -56.196579) (xy 404.966053 -56.150613) (xy 404.983696 -56.129682) (xy 404.98395 -56.129428)
			(xy 404.989537 -56.122342) (xy 404.995782 -56.105425) (xy 404.996142 -56.096408) (xy 404.996142 -56.029352)
			(xy 404.995773 -56.020336) (xy 404.989535 -56.003418) (xy 404.98395 -55.996332) (xy 404.983696 -55.996332)
			(xy 404.983696 -55.996078) (xy 404.966037 -55.975161) (xy 404.936315 -55.929189) (xy 404.913473 -55.87944)
			(xy 404.89798 -55.826936) (xy 404.890154 -55.772756) (xy 404.890156 -55.718014) (xy 404.897986 -55.663834)
			(xy 404.913484 -55.611331) (xy 404.93633 -55.561584) (xy 404.966055 -55.515615) (xy 404.983696 -55.494682)
			(xy 404.98395 -55.494428) (xy 404.989537 -55.487342) (xy 404.995782 -55.470425) (xy 404.996142 -55.461408)
			(xy 404.996142 -55.394352) (xy 404.995773 -55.385336) (xy 404.989535 -55.368418) (xy 404.98395 -55.361332)
			(xy 404.983696 -55.360824) (xy 404.972752 -55.348089) (xy 404.952911 -55.320998) (xy 404.944072 -55.306722)
			(xy 404.938738 -55.297832) (xy 404.92172 -55.28564) (xy 404.828502 -55.26532) (xy 404.807928 -55.269638)
			(xy 404.799292 -55.27548) (xy 404.77523 -55.291483) (xy 404.723298 -55.316826) (xy 404.66814 -55.334051)
			(xy 404.611015 -55.342764) (xy 404.582122 -55.343298) (xy 404.554867 -55.342857) (xy 404.500913 -55.335102)
			(xy 404.448611 -55.319747) (xy 404.399026 -55.297106) (xy 404.353169 -55.267637) (xy 404.311973 -55.231943)
			(xy 404.276276 -55.190748) (xy 404.246805 -55.144893) (xy 404.22416 -55.09531) (xy 404.208803 -55.043009)
			(xy 404.201045 -54.989055) (xy 395.065059 -54.989055) (xy 395.058379 -54.999449) (xy 395.022688 -55.04064)
			(xy 394.981497 -55.076331) (xy 394.935647 -55.105797) (xy 394.88607 -55.128439) (xy 394.833775 -55.143794)
			(xy 394.779827 -55.15155) (xy 394.725325 -55.15155) (xy 394.671377 -55.143794) (xy 394.619082 -55.128439)
			(xy 394.569505 -55.105797) (xy 394.523655 -55.076331) (xy 394.482464 -55.04064) (xy 394.446773 -54.999449)
			(xy 394.417307 -54.953599) (xy 394.394665 -54.904022) (xy 394.37931 -54.851727) (xy 394.371554 -54.797779)
			(xy 394.371068 -54.770528) (xy 391.239147 -54.770528) (xy 391.239502 -54.791102) (xy 391.239016 -54.818353)
			(xy 391.23126 -54.872301) (xy 391.215905 -54.924596) (xy 391.193263 -54.974173) (xy 391.163797 -55.020023)
			(xy 391.128106 -55.061214) (xy 391.086915 -55.096905) (xy 391.041065 -55.126371) (xy 390.991488 -55.149013)
			(xy 390.939193 -55.164368) (xy 390.885245 -55.172124) (xy 390.830743 -55.172124) (xy 390.776795 -55.164368)
			(xy 390.7245 -55.149013) (xy 390.674923 -55.126371) (xy 390.629073 -55.096905) (xy 390.587882 -55.061214)
			(xy 390.552191 -55.020023) (xy 390.522725 -54.974173) (xy 390.500083 -54.924596) (xy 390.484728 -54.872301)
			(xy 390.476972 -54.818353) (xy 390.476486 -54.791102) (xy 388.578552 -54.791102) (xy 388.575406 -54.812927)
			(xy 388.55994 -54.865412) (xy 388.537131 -54.915148) (xy 388.507449 -54.961114) (xy 388.471503 -55.002366)
			(xy 388.43003 -55.038057) (xy 388.383882 -55.067456) (xy 388.334007 -55.089957) (xy 388.307834 -55.097934)
			(xy 388.30504 -55.098696) (xy 388.29536 -55.102596) (xy 388.280022 -55.116716) (xy 388.271571 -55.135774)
			(xy 388.271004 -55.146194) (xy 388.305314 -55.722266) (xy 400.134072 -55.722266) (xy 400.138143 -55.666644)
			(xy 400.150269 -55.612207) (xy 400.170192 -55.560116) (xy 400.197488 -55.511481) (xy 400.231574 -55.467338)
			(xy 400.271723 -55.428629) (xy 400.317081 -55.396178) (xy 400.366681 -55.370677) (xy 400.419465 -55.35267)
			(xy 400.474308 -55.34254) (xy 400.530042 -55.340503) (xy 400.585479 -55.346603) (xy 400.639436 -55.360709)
			(xy 400.690765 -55.382521) (xy 400.738371 -55.411575) (xy 400.749522 -55.420855) (xy 402.524645 -55.420855)
			(xy 402.524645 -55.366345) (xy 402.532403 -55.312391) (xy 402.54776 -55.26009) (xy 402.570405 -55.210507)
			(xy 402.599876 -55.164652) (xy 402.635573 -55.123457) (xy 402.676769 -55.087763) (xy 402.722626 -55.058294)
			(xy 402.772211 -55.035653) (xy 402.824513 -55.020298) (xy 402.878467 -55.012543) (xy 402.905722 -55.012082)
			(xy 402.932036 -55.012541) (xy 402.984165 -55.019778) (xy 403.034808 -55.034099) (xy 403.083006 -55.055233)
			(xy 403.12785 -55.082781) (xy 403.168489 -55.11622) (xy 403.186646 -55.135272) (xy 403.194152 -55.142692)
			(xy 403.213444 -55.151207) (xy 403.223984 -55.151782) (xy 403.29866 -55.151782) (xy 403.30921 -55.15125)
			(xy 403.328505 -55.142718) (xy 403.335998 -55.135272) (xy 403.354156 -55.116219) (xy 403.394786 -55.082763)
			(xy 403.439626 -55.055204) (xy 403.487826 -55.034065) (xy 403.538473 -55.019747) (xy 403.590606 -55.012521)
			(xy 403.616922 -55.012082) (xy 403.644171 -55.01259) (xy 403.698115 -55.020349) (xy 403.750406 -55.035705)
			(xy 403.799979 -55.058347) (xy 403.845825 -55.087813) (xy 403.887012 -55.123504) (xy 403.9227 -55.164692)
			(xy 403.952164 -55.21054) (xy 403.974802 -55.260115) (xy 403.990156 -55.312406) (xy 403.997912 -55.366351)
			(xy 403.997912 -55.420849) (xy 403.990156 -55.474794) (xy 403.974802 -55.527085) (xy 403.952164 -55.57666)
			(xy 403.9227 -55.622508) (xy 403.887012 -55.663696) (xy 403.845826 -55.699387) (xy 403.799979 -55.728853)
			(xy 403.750406 -55.751495) (xy 403.698115 -55.766851) (xy 403.644171 -55.77461) (xy 403.616922 -55.775098)
			(xy 403.590609 -55.774617) (xy 403.538481 -55.767385) (xy 403.487838 -55.753068) (xy 403.439639 -55.731939)
			(xy 403.394795 -55.704395) (xy 403.354155 -55.670959) (xy 403.335998 -55.651908) (xy 403.328478 -55.644505)
			(xy 403.309197 -55.635981) (xy 403.29866 -55.635398) (xy 403.223984 -55.635398) (xy 403.213432 -55.635905)
			(xy 403.194137 -55.644456) (xy 403.186646 -55.651908) (xy 403.168511 -55.670984) (xy 403.127877 -55.704439)
			(xy 403.083032 -55.731995) (xy 403.034827 -55.75313) (xy 402.984176 -55.767443) (xy 402.932039 -55.774662)
			(xy 402.905722 -55.775098) (xy 402.878467 -55.774657) (xy 402.824513 -55.766902) (xy 402.772211 -55.751547)
			(xy 402.722626 -55.728906) (xy 402.676769 -55.699437) (xy 402.635573 -55.663743) (xy 402.599876 -55.622548)
			(xy 402.570405 -55.576693) (xy 402.54776 -55.52711) (xy 402.532403 -55.474809) (xy 402.524645 -55.420855)
			(xy 400.749522 -55.420855) (xy 400.781239 -55.44725) (xy 400.818456 -55.488787) (xy 400.849229 -55.5353)
			(xy 400.872901 -55.585797) (xy 400.888969 -55.639204) (xy 400.897089 -55.69438) (xy 400.897598 -55.722266)
			(xy 400.897089 -55.750152) (xy 400.888969 -55.805328) (xy 400.872901 -55.858735) (xy 400.849229 -55.909232)
			(xy 400.818456 -55.955745) (xy 400.781239 -55.997282) (xy 400.738371 -56.032957) (xy 400.690765 -56.062011)
			(xy 400.639436 -56.083823) (xy 400.585479 -56.097929) (xy 400.530042 -56.104029) (xy 400.474308 -56.101992)
			(xy 400.419465 -56.091862) (xy 400.366681 -56.073855) (xy 400.317081 -56.048354) (xy 400.271723 -56.015903)
			(xy 400.231574 -55.977194) (xy 400.197488 -55.933051) (xy 400.170192 -55.884416) (xy 400.150269 -55.832325)
			(xy 400.138143 -55.777888) (xy 400.134072 -55.722266) (xy 388.305314 -55.722266) (xy 388.348474 -56.446928)
			(xy 388.349657 -56.455289) (xy 388.356785 -56.470587) (xy 388.368517 -56.48272) (xy 388.375906 -56.486806)
			(xy 388.399022 -56.49912) (xy 388.441948 -56.52913) (xy 388.480366 -56.564729) (xy 388.513554 -56.605248)
			(xy 388.540889 -56.649925) (xy 388.561855 -56.697921) (xy 388.576061 -56.748334) (xy 388.583237 -56.800216)
			(xy 388.583678 -56.826404) (xy 388.583678 -56.832754) (xy 388.583261 -56.847824) (xy 388.580337 -56.877831)
			(xy 388.577836 -56.892698) (xy 388.571742 -56.923739) (xy 388.550659 -56.983376) (xy 388.539838 -57.002934)
			(xy 395.863572 -57.002934) (xy 395.864098 -56.974844) (xy 395.872321 -56.919268) (xy 395.888607 -56.8655)
			(xy 395.912604 -56.814703) (xy 395.943794 -56.767976) (xy 395.981501 -56.72633) (xy 396.02491 -56.690666)
			(xy 396.048738 -56.675782) (xy 396.057628 -56.670448) (xy 396.06982 -56.65343) (xy 396.09014 -56.560212)
			(xy 396.085822 -56.539638) (xy 396.07998 -56.531002) (xy 396.063976 -56.506941) (xy 396.038635 -56.455008)
			(xy 396.021411 -56.399849) (xy 396.012696 -56.342725) (xy 396.012162 -56.313832) (xy 396.012685 -56.286581)
			(xy 396.020437 -56.232634) (xy 396.035787 -56.180339) (xy 396.058424 -56.130761) (xy 396.087886 -56.084909)
			(xy 396.123573 -56.043717) (xy 396.16476 -56.008023) (xy 396.210607 -55.978554) (xy 396.260181 -55.955909)
			(xy 396.312473 -55.94055) (xy 396.366419 -55.932789) (xy 396.39367 -55.932324) (xy 396.42104 -55.932802)
			(xy 396.475219 -55.940616) (xy 396.527722 -55.956102) (xy 396.577469 -55.978941) (xy 396.623436 -56.008664)
			(xy 396.644368 -56.026304) (xy 396.644622 -56.026558) (xy 396.651693 -56.032167) (xy 396.668622 -56.038399)
			(xy 396.677642 -56.03875) (xy 396.744698 -56.03875) (xy 396.753716 -56.038403) (xy 396.770633 -56.032149)
			(xy 396.777718 -56.026558) (xy 396.777718 -56.026304) (xy 396.777972 -56.026304) (xy 396.798905 -56.008663)
			(xy 396.844873 -55.978939) (xy 396.894619 -55.956093) (xy 396.947121 -55.940597) (xy 397.001299 -55.932768)
			(xy 397.056041 -55.932768) (xy 397.110219 -55.940597) (xy 397.162721 -55.956093) (xy 397.212467 -55.978939)
			(xy 397.258435 -56.008663) (xy 397.279368 -56.026304) (xy 397.279622 -56.026558) (xy 397.286693 -56.032167)
			(xy 397.303622 -56.038399) (xy 397.312642 -56.03875) (xy 397.379698 -56.03875) (xy 397.388716 -56.038403)
			(xy 397.405633 -56.032149) (xy 397.412718 -56.026558) (xy 397.412718 -56.026304) (xy 397.412972 -56.026304)
			(xy 397.433904 -56.008665) (xy 397.479877 -55.978953) (xy 397.529624 -55.956117) (xy 397.582125 -55.940626)
			(xy 397.636301 -55.932798) (xy 397.66367 -55.932324) (xy 397.690927 -55.932721) (xy 397.744885 -55.940475)
			(xy 397.797191 -55.95583) (xy 397.846779 -55.978472) (xy 397.89264 -56.007942) (xy 397.93384 -56.043639)
			(xy 397.96954 -56.084836) (xy 397.999013 -56.130694) (xy 398.02166 -56.180281) (xy 398.037019 -56.232585)
			(xy 398.044777 -56.286543) (xy 398.044777 -56.297068) (xy 398.386552 -56.297068) (xy 398.390623 -56.241446)
			(xy 398.402749 -56.187009) (xy 398.422672 -56.134918) (xy 398.449968 -56.086283) (xy 398.484054 -56.04214)
			(xy 398.524203 -56.003431) (xy 398.569561 -55.97098) (xy 398.619161 -55.945479) (xy 398.671945 -55.927472)
			(xy 398.726788 -55.917342) (xy 398.782522 -55.915305) (xy 398.837959 -55.921405) (xy 398.891916 -55.935511)
			(xy 398.943245 -55.957323) (xy 398.990851 -55.986377) (xy 399.033719 -56.022052) (xy 399.070936 -56.063589)
			(xy 399.101709 -56.110102) (xy 399.125381 -56.160599) (xy 399.141449 -56.214006) (xy 399.149569 -56.269182)
			(xy 399.150078 -56.297068) (xy 399.149569 -56.324954) (xy 399.141449 -56.38013) (xy 399.125381 -56.433537)
			(xy 399.101709 -56.484034) (xy 399.070936 -56.530547) (xy 399.033719 -56.572084) (xy 398.990851 -56.607759)
			(xy 398.943245 -56.636813) (xy 398.891916 -56.658625) (xy 398.837959 -56.672731) (xy 398.782522 -56.678831)
			(xy 398.726788 -56.676794) (xy 398.671945 -56.666664) (xy 398.619161 -56.648657) (xy 398.569561 -56.623156)
			(xy 398.524203 -56.590705) (xy 398.484054 -56.551996) (xy 398.449968 -56.507853) (xy 398.422672 -56.459218)
			(xy 398.402749 -56.407127) (xy 398.390623 -56.35269) (xy 398.386552 -56.297068) (xy 398.044777 -56.297068)
			(xy 398.044777 -56.341057) (xy 398.037019 -56.395015) (xy 398.02166 -56.447319) (xy 397.999013 -56.496906)
			(xy 397.96954 -56.542764) (xy 397.93384 -56.583961) (xy 397.89264 -56.619658) (xy 397.846779 -56.649128)
			(xy 397.797191 -56.67177) (xy 397.744885 -56.687125) (xy 397.690927 -56.694879) (xy 397.66367 -56.69534)
			(xy 397.636298 -56.694906) (xy 397.582117 -56.687083) (xy 397.529613 -56.671587) (xy 397.479867 -56.648738)
			(xy 397.433902 -56.619005) (xy 397.412972 -56.60136) (xy 397.412718 -56.601106) (xy 397.40563 -56.595521)
			(xy 397.388714 -56.589273) (xy 397.379698 -56.588914) (xy 397.312642 -56.588914) (xy 397.303627 -56.589288)
			(xy 397.28671 -56.595524) (xy 397.279622 -56.601106) (xy 397.279622 -56.60136) (xy 397.279368 -56.60136)
			(xy 397.258435 -56.619001) (xy 397.212467 -56.648725) (xy 397.162721 -56.671571) (xy 397.110219 -56.687067)
			(xy 397.056041 -56.694896) (xy 397.001299 -56.694896) (xy 396.947121 -56.687067) (xy 396.894619 -56.671571)
			(xy 396.844873 -56.648725) (xy 396.798905 -56.619001) (xy 396.777972 -56.60136) (xy 396.777718 -56.601106)
			(xy 396.77063 -56.595521) (xy 396.753714 -56.589273) (xy 396.744698 -56.588914) (xy 396.677642 -56.588914)
			(xy 396.668627 -56.589288) (xy 396.65171 -56.595524) (xy 396.644622 -56.601106) (xy 396.644114 -56.60136)
			(xy 396.631383 -56.612308) (xy 396.604289 -56.632147) (xy 396.590012 -56.640984) (xy 396.581122 -56.646318)
			(xy 396.56893 -56.663336) (xy 396.54861 -56.756554) (xy 396.552928 -56.777128) (xy 396.55877 -56.785764)
			(xy 396.574753 -56.809838) (xy 396.600101 -56.861766) (xy 396.617331 -56.916921) (xy 396.626051 -56.974042)
			(xy 396.626588 -57.002934) (xy 396.626102 -57.030185) (xy 396.618346 -57.084133) (xy 396.602991 -57.136428)
			(xy 396.580349 -57.186005) (xy 396.550883 -57.231855) (xy 396.515192 -57.273046) (xy 396.474001 -57.308737)
			(xy 396.428151 -57.338203) (xy 396.378574 -57.360845) (xy 396.326279 -57.3762) (xy 396.272331 -57.383956)
			(xy 396.217829 -57.383956) (xy 396.163881 -57.3762) (xy 396.111586 -57.360845) (xy 396.062009 -57.338203)
			(xy 396.016159 -57.308737) (xy 395.974968 -57.273046) (xy 395.939277 -57.231855) (xy 395.909811 -57.186005)
			(xy 395.887169 -57.136428) (xy 395.871814 -57.084133) (xy 395.864058 -57.030185) (xy 395.863572 -57.002934)
			(xy 388.539838 -57.002934) (xy 388.520035 -57.038724) (xy 388.500874 -57.063894) (xy 388.49554 -57.070498)
			(xy 388.492238 -57.079642) (xy 388.490714 -57.085484) (xy 388.489698 -57.09539) (xy 388.489698 -57.128156)
			(xy 388.478522 -57.128156) (xy 388.478522 -57.178956) (xy 388.478856 -57.18756) (xy 388.484568 -57.203791)
			(xy 388.489698 -57.210706) (xy 388.490968 -57.21223) (xy 388.508361 -57.233107) (xy 388.537678 -57.278857)
			(xy 388.560205 -57.328305) (xy 388.575485 -57.38045) (xy 388.583211 -57.434235) (xy 388.583678 -57.461404)
			(xy 388.583296 -57.48528) (xy 404.90597 -57.48528) (xy 404.910041 -57.429658) (xy 404.922167 -57.375221)
			(xy 404.94209 -57.32313) (xy 404.969386 -57.274495) (xy 405.003472 -57.230352) (xy 405.043621 -57.191643)
			(xy 405.088979 -57.159192) (xy 405.138579 -57.133691) (xy 405.191363 -57.115684) (xy 405.246206 -57.105554)
			(xy 405.30194 -57.103517) (xy 405.357377 -57.109617) (xy 405.411334 -57.123723) (xy 405.462663 -57.145535)
			(xy 405.510269 -57.174589) (xy 405.553137 -57.210264) (xy 405.590354 -57.251801) (xy 405.621127 -57.298314)
			(xy 405.644799 -57.348811) (xy 405.660867 -57.402218) (xy 405.668987 -57.457394) (xy 405.669496 -57.48528)
			(xy 405.668987 -57.513166) (xy 405.660867 -57.568342) (xy 405.644799 -57.621749) (xy 405.621127 -57.672246)
			(xy 405.590354 -57.718759) (xy 405.553137 -57.760296) (xy 405.510269 -57.795971) (xy 405.462663 -57.825025)
			(xy 405.411334 -57.846837) (xy 405.357377 -57.860943) (xy 405.30194 -57.867043) (xy 405.246206 -57.865006)
			(xy 405.191363 -57.854876) (xy 405.138579 -57.836869) (xy 405.088979 -57.811368) (xy 405.043621 -57.778917)
			(xy 405.003472 -57.740208) (xy 404.969386 -57.696065) (xy 404.94209 -57.64743) (xy 404.922167 -57.595339)
			(xy 404.910041 -57.540902) (xy 404.90597 -57.48528) (xy 388.583296 -57.48528) (xy 388.583268 -57.487021)
			(xy 388.576415 -57.537795) (xy 388.562818 -57.587192) (xy 388.542724 -57.634321) (xy 388.516495 -57.678332)
			(xy 388.500874 -57.69864) (xy 388.50062 -57.698894) (xy 388.499096 -57.700672) (xy 388.494796 -57.7072)
			(xy 388.490004 -57.722071) (xy 388.489698 -57.729882) (xy 388.489698 -57.763156) (xy 388.478522 -57.763156)
			(xy 388.478522 -57.813956) (xy 388.478856 -57.82256) (xy 388.484568 -57.838791) (xy 388.489698 -57.845706)
			(xy 388.490968 -57.84723) (xy 388.508361 -57.868107) (xy 388.537678 -57.913857) (xy 388.560205 -57.963305)
			(xy 388.575485 -58.01545) (xy 388.583211 -58.069235) (xy 388.583678 -58.096404) (xy 388.583268 -58.122021)
			(xy 388.576415 -58.172795) (xy 388.562818 -58.222192) (xy 388.542724 -58.269321) (xy 388.516495 -58.313332)
			(xy 388.500874 -58.33364) (xy 388.50062 -58.333894) (xy 388.499096 -58.335672) (xy 388.494796 -58.3422)
			(xy 388.490004 -58.357071) (xy 388.489698 -58.364882) (xy 388.489698 -58.398156) (xy 388.478522 -58.398156)
			(xy 388.478522 -58.448956) (xy 388.478856 -58.45756) (xy 388.484568 -58.473791) (xy 388.489698 -58.480706)
			(xy 388.490968 -58.48223) (xy 388.508361 -58.503107) (xy 388.537678 -58.548857) (xy 388.560205 -58.598305)
			(xy 388.575485 -58.65045) (xy 388.579634 -58.679334) (xy 396.295372 -58.679334) (xy 396.295804 -58.653019)
			(xy 396.303048 -58.600889) (xy 396.317374 -58.550246) (xy 396.338513 -58.502048) (xy 396.366065 -58.457205)
			(xy 396.399508 -58.416566) (xy 396.418562 -58.39841) (xy 396.425955 -58.390881) (xy 396.434486 -58.371607)
			(xy 396.435072 -58.361072) (xy 396.435072 -58.286396) (xy 396.434567 -58.275843) (xy 396.426016 -58.256548)
			(xy 396.418562 -58.249058) (xy 396.399486 -58.230923) (xy 396.366032 -58.190288) (xy 396.338477 -58.145443)
			(xy 396.317342 -58.097239) (xy 396.303029 -58.046588) (xy 396.295808 -57.994451) (xy 396.295372 -57.968134)
			(xy 396.295858 -57.940883) (xy 396.303614 -57.886935) (xy 396.318969 -57.83464) (xy 396.341611 -57.785063)
			(xy 396.371077 -57.739213) (xy 396.406768 -57.698022) (xy 396.447959 -57.662331) (xy 396.493809 -57.632865)
			(xy 396.543386 -57.610223) (xy 396.595681 -57.594868) (xy 396.649629 -57.587112) (xy 396.704131 -57.587112)
			(xy 396.758079 -57.594868) (xy 396.810374 -57.610223) (xy 396.859951 -57.632865) (xy 396.905801 -57.662331)
			(xy 396.946992 -57.698022) (xy 396.982683 -57.739213) (xy 397.012149 -57.785063) (xy 397.034791 -57.83464)
			(xy 397.050146 -57.886935) (xy 397.057902 -57.940883) (xy 397.058388 -57.968134) (xy 397.057947 -57.994449)
			(xy 397.050707 -58.046579) (xy 397.043439 -58.072274) (xy 400.293584 -58.072274) (xy 400.297655 -58.016652)
			(xy 400.309781 -57.962215) (xy 400.329704 -57.910124) (xy 400.357 -57.861489) (xy 400.391086 -57.817346)
			(xy 400.431235 -57.778637) (xy 400.476593 -57.746186) (xy 400.526193 -57.720685) (xy 400.578977 -57.702678)
			(xy 400.63382 -57.692548) (xy 400.689554 -57.690511) (xy 400.744991 -57.696611) (xy 400.798948 -57.710717)
			(xy 400.850277 -57.732529) (xy 400.897883 -57.761583) (xy 400.940751 -57.797258) (xy 400.977968 -57.838795)
			(xy 401.008741 -57.885308) (xy 401.032413 -57.935805) (xy 401.048481 -57.989212) (xy 401.056601 -58.044388)
			(xy 401.05711 -58.072274) (xy 401.05704 -58.076084) (xy 405.658064 -58.076084) (xy 405.662135 -58.020462)
			(xy 405.674261 -57.966025) (xy 405.694184 -57.913934) (xy 405.72148 -57.865299) (xy 405.755566 -57.821156)
			(xy 405.795715 -57.782447) (xy 405.841073 -57.749996) (xy 405.890673 -57.724495) (xy 405.943457 -57.706488)
			(xy 405.9983 -57.696358) (xy 406.054034 -57.694321) (xy 406.109471 -57.700421) (xy 406.163428 -57.714527)
			(xy 406.214757 -57.736339) (xy 406.262363 -57.765393) (xy 406.305231 -57.801068) (xy 406.342448 -57.842605)
			(xy 406.358784 -57.867296) (xy 407.943048 -57.867296) (xy 407.947119 -57.811674) (xy 407.959245 -57.757237)
			(xy 407.979168 -57.705146) (xy 408.006464 -57.656511) (xy 408.04055 -57.612368) (xy 408.080699 -57.573659)
			(xy 408.126057 -57.541208) (xy 408.175657 -57.515707) (xy 408.228441 -57.4977) (xy 408.283284 -57.48757)
			(xy 408.339018 -57.485533) (xy 408.394455 -57.491633) (xy 408.448412 -57.505739) (xy 408.499741 -57.527551)
			(xy 408.547347 -57.556605) (xy 408.590215 -57.59228) (xy 408.627432 -57.633817) (xy 408.658205 -57.68033)
			(xy 408.681877 -57.730827) (xy 408.697945 -57.784234) (xy 408.706065 -57.83941) (xy 408.706574 -57.867296)
			(xy 408.706065 -57.895182) (xy 408.697945 -57.950358) (xy 408.681877 -58.003765) (xy 408.658205 -58.054262)
			(xy 408.627432 -58.100775) (xy 408.590215 -58.142312) (xy 408.547347 -58.177987) (xy 408.499741 -58.207041)
			(xy 408.448412 -58.228853) (xy 408.394455 -58.242959) (xy 408.339018 -58.249059) (xy 408.283284 -58.247022)
			(xy 408.228441 -58.236892) (xy 408.175657 -58.218885) (xy 408.126057 -58.193384) (xy 408.080699 -58.160933)
			(xy 408.04055 -58.122224) (xy 408.006464 -58.078081) (xy 407.979168 -58.029446) (xy 407.959245 -57.977355)
			(xy 407.947119 -57.922918) (xy 407.943048 -57.867296) (xy 406.358784 -57.867296) (xy 406.373221 -57.889118)
			(xy 406.396893 -57.939615) (xy 406.412961 -57.993022) (xy 406.421081 -58.048198) (xy 406.42159 -58.076084)
			(xy 406.421081 -58.10397) (xy 406.412961 -58.159146) (xy 406.396893 -58.212553) (xy 406.373221 -58.26305)
			(xy 406.342448 -58.309563) (xy 406.305231 -58.3511) (xy 406.262363 -58.386775) (xy 406.214757 -58.415829)
			(xy 406.163428 -58.437641) (xy 406.109471 -58.451747) (xy 406.054034 -58.457847) (xy 405.9983 -58.45581)
			(xy 405.943457 -58.44568) (xy 405.890673 -58.427673) (xy 405.841073 -58.402172) (xy 405.795715 -58.369721)
			(xy 405.755566 -58.331012) (xy 405.72148 -58.286869) (xy 405.694184 -58.238234) (xy 405.674261 -58.186143)
			(xy 405.662135 -58.131706) (xy 405.658064 -58.076084) (xy 401.05704 -58.076084) (xy 401.056601 -58.10016)
			(xy 401.048481 -58.155336) (xy 401.032413 -58.208743) (xy 401.008741 -58.25924) (xy 400.977968 -58.305753)
			(xy 400.940751 -58.34729) (xy 400.897883 -58.382965) (xy 400.850277 -58.412019) (xy 400.798948 -58.433831)
			(xy 400.744991 -58.447937) (xy 400.689554 -58.454037) (xy 400.63382 -58.452) (xy 400.578977 -58.44187)
			(xy 400.526193 -58.423863) (xy 400.476593 -58.398362) (xy 400.431235 -58.365911) (xy 400.391086 -58.327202)
			(xy 400.357 -58.283059) (xy 400.329704 -58.234424) (xy 400.309781 -58.182333) (xy 400.297655 -58.127896)
			(xy 400.293584 -58.072274) (xy 397.043439 -58.072274) (xy 397.036383 -58.097222) (xy 397.015246 -58.145421)
			(xy 396.987695 -58.190264) (xy 396.954252 -58.230902) (xy 396.935198 -58.249058) (xy 396.927813 -58.256593)
			(xy 396.919279 -58.275863) (xy 396.918688 -58.286396) (xy 396.918688 -58.361072) (xy 396.919222 -58.371621)
			(xy 396.927754 -58.390916) (xy 396.935198 -58.39841) (xy 396.954251 -58.416568) (xy 396.987708 -58.457197)
			(xy 397.015268 -58.502037) (xy 397.036407 -58.550237) (xy 397.039513 -58.561224) (xy 406.862278 -58.561224)
			(xy 406.866349 -58.505602) (xy 406.878475 -58.451165) (xy 406.898398 -58.399074) (xy 406.925694 -58.350439)
			(xy 406.95978 -58.306296) (xy 406.999929 -58.267587) (xy 407.045287 -58.235136) (xy 407.094887 -58.209635)
			(xy 407.147671 -58.191628) (xy 407.202514 -58.181498) (xy 407.258248 -58.179461) (xy 407.313685 -58.185561)
			(xy 407.367642 -58.199667) (xy 407.418971 -58.221479) (xy 407.466577 -58.250533) (xy 407.509445 -58.286208)
			(xy 407.546662 -58.327745) (xy 407.577435 -58.374258) (xy 407.601107 -58.424755) (xy 407.617175 -58.478162)
			(xy 407.625295 -58.533338) (xy 407.625804 -58.561224) (xy 407.625295 -58.58911) (xy 407.617175 -58.644286)
			(xy 407.601107 -58.697693) (xy 407.577435 -58.74819) (xy 407.546662 -58.794703) (xy 407.509445 -58.83624)
			(xy 407.466577 -58.871915) (xy 407.418971 -58.900969) (xy 407.367642 -58.922781) (xy 407.313685 -58.936887)
			(xy 407.258248 -58.942987) (xy 407.202514 -58.94095) (xy 407.147671 -58.93082) (xy 407.094887 -58.912813)
			(xy 407.045287 -58.887312) (xy 406.999929 -58.854861) (xy 406.95978 -58.816152) (xy 406.925694 -58.772009)
			(xy 406.898398 -58.723374) (xy 406.878475 -58.671283) (xy 406.866349 -58.616846) (xy 406.862278 -58.561224)
			(xy 397.039513 -58.561224) (xy 397.050724 -58.600884) (xy 397.057949 -58.653018) (xy 397.058388 -58.679334)
			(xy 397.057902 -58.706585) (xy 397.050146 -58.760533) (xy 397.034791 -58.812828) (xy 397.012149 -58.862405)
			(xy 396.982683 -58.908255) (xy 396.946992 -58.949446) (xy 396.905801 -58.985137) (xy 396.859951 -59.014603)
			(xy 396.810374 -59.037245) (xy 396.758079 -59.0526) (xy 396.704131 -59.060356) (xy 396.649629 -59.060356)
			(xy 396.595681 -59.0526) (xy 396.543386 -59.037245) (xy 396.493809 -59.014603) (xy 396.447959 -58.985137)
			(xy 396.406768 -58.949446) (xy 396.371077 -58.908255) (xy 396.341611 -58.862405) (xy 396.318969 -58.812828)
			(xy 396.303614 -58.760533) (xy 396.295858 -58.706585) (xy 396.295372 -58.679334) (xy 388.579634 -58.679334)
			(xy 388.583211 -58.704235) (xy 388.583678 -58.731404) (xy 388.583678 -58.731658) (xy 388.58308 -58.761844)
			(xy 388.573535 -58.821457) (xy 388.554738 -58.878828) (xy 388.527158 -58.932533) (xy 388.509764 -58.95721)
			(xy 388.504176 -58.96483) (xy 388.50189 -58.97245) (xy 388.500718 -58.97673) (xy 388.499689 -58.985542)
			(xy 388.499858 -58.989976) (xy 388.510861 -59.174634) (xy 405.393142 -59.174634) (xy 405.397213 -59.119012)
			(xy 405.409339 -59.064575) (xy 405.429262 -59.012484) (xy 405.456558 -58.963849) (xy 405.490644 -58.919706)
			(xy 405.530793 -58.880997) (xy 405.576151 -58.848546) (xy 405.625751 -58.823045) (xy 405.678535 -58.805038)
			(xy 405.733378 -58.794908) (xy 405.789112 -58.792871) (xy 405.844549 -58.798971) (xy 405.898506 -58.813077)
			(xy 405.949835 -58.834889) (xy 405.997441 -58.863943) (xy 406.040309 -58.899618) (xy 406.077526 -58.941155)
			(xy 406.108299 -58.987668) (xy 406.131971 -59.038165) (xy 406.148039 -59.091572) (xy 406.156159 -59.146748)
			(xy 406.156668 -59.174634) (xy 406.156159 -59.20252) (xy 406.148039 -59.257696) (xy 406.131971 -59.311103)
			(xy 406.108299 -59.3616) (xy 406.077526 -59.408113) (xy 406.040309 -59.44965) (xy 405.997441 -59.485325)
			(xy 405.949835 -59.514379) (xy 405.898506 -59.536191) (xy 405.844549 -59.550297) (xy 405.789112 -59.556397)
			(xy 405.733378 -59.55436) (xy 405.678535 -59.54423) (xy 405.625751 -59.526223) (xy 405.576151 -59.500722)
			(xy 405.530793 -59.468271) (xy 405.490644 -59.429562) (xy 405.456558 -59.385419) (xy 405.429262 -59.336784)
			(xy 405.409339 -59.284693) (xy 405.397213 -59.230256) (xy 405.393142 -59.174634) (xy 388.510861 -59.174634)
			(xy 388.561187 -60.019254) (xy 396.435761 -60.019254) (xy 396.435761 -59.964746) (xy 396.443519 -59.910793)
			(xy 396.458877 -59.858493) (xy 396.481521 -59.808912) (xy 396.510992 -59.763058) (xy 396.546689 -59.721865)
			(xy 396.587885 -59.686172) (xy 396.633742 -59.656705) (xy 396.683325 -59.634065) (xy 396.735626 -59.618712)
			(xy 396.78958 -59.610959) (xy 396.816834 -59.610498) (xy 396.844205 -59.610945) (xy 396.898385 -59.618767)
			(xy 396.950888 -59.634261) (xy 397.000635 -59.657107) (xy 397.046601 -59.686835) (xy 397.067532 -59.704478)
			(xy 397.067786 -59.704732) (xy 397.07487 -59.710322) (xy 397.091789 -59.716566) (xy 397.100806 -59.716924)
			(xy 397.167862 -59.716924) (xy 397.176876 -59.716544) (xy 397.193793 -59.710312) (xy 397.200882 -59.704732)
			(xy 397.200882 -59.704478) (xy 397.201136 -59.704478) (xy 397.222069 -59.686837) (xy 397.268037 -59.657113)
			(xy 397.317783 -59.634267) (xy 397.370285 -59.618771) (xy 397.424463 -59.610942) (xy 397.479205 -59.610942)
			(xy 397.533383 -59.618771) (xy 397.585885 -59.634267) (xy 397.635631 -59.657113) (xy 397.681599 -59.686837)
			(xy 397.702532 -59.704478) (xy 397.702786 -59.704732) (xy 397.70987 -59.710322) (xy 397.726789 -59.716566)
			(xy 397.735806 -59.716924) (xy 397.802862 -59.716924) (xy 397.811876 -59.716544) (xy 397.828793 -59.710312)
			(xy 397.835882 -59.704732) (xy 397.835882 -59.704478) (xy 397.836136 -59.704478) (xy 397.857079 -59.686852)
			(xy 397.903049 -59.657139) (xy 397.952794 -59.634301) (xy 398.005292 -59.618807) (xy 398.059466 -59.610974)
			(xy 398.086834 -59.610498) (xy 398.114084 -59.610974) (xy 398.168029 -59.618735) (xy 398.22032 -59.634093)
			(xy 398.269894 -59.656736) (xy 398.315741 -59.686204) (xy 398.356928 -59.721896) (xy 398.392616 -59.763086)
			(xy 398.42208 -59.808936) (xy 398.444719 -59.858511) (xy 398.460073 -59.910804) (xy 398.467828 -59.96475)
			(xy 398.467828 -60.01925) (xy 398.460073 -60.073196) (xy 398.444719 -60.125489) (xy 398.42208 -60.175064)
			(xy 398.392616 -60.220914) (xy 398.356928 -60.262104) (xy 398.315741 -60.297796) (xy 398.269894 -60.327264)
			(xy 398.22032 -60.349907) (xy 398.168029 -60.365265) (xy 398.114084 -60.373026) (xy 398.086834 -60.373514)
			(xy 398.059465 -60.373025) (xy 398.005287 -60.365212) (xy 397.952784 -60.349728) (xy 397.903037 -60.326892)
			(xy 397.857069 -60.297173) (xy 397.836136 -60.279534) (xy 397.835882 -60.27928) (xy 397.828806 -60.273678)
			(xy 397.811881 -60.267441) (xy 397.802862 -60.267088) (xy 397.735806 -60.267088) (xy 397.72679 -60.267451)
			(xy 397.709873 -60.273695) (xy 397.702786 -60.27928) (xy 397.702532 -60.279534) (xy 397.681599 -60.297175)
			(xy 397.635631 -60.326899) (xy 397.585885 -60.349745) (xy 397.533383 -60.365241) (xy 397.479205 -60.37307)
			(xy 397.424463 -60.37307) (xy 397.370285 -60.365241) (xy 397.317783 -60.349745) (xy 397.268037 -60.326899)
			(xy 397.222069 -60.297175) (xy 397.201136 -60.279534) (xy 397.200882 -60.27928) (xy 397.193806 -60.273678)
			(xy 397.176881 -60.267441) (xy 397.167862 -60.267088) (xy 397.100806 -60.267088) (xy 397.09179 -60.267451)
			(xy 397.074873 -60.273695) (xy 397.067786 -60.27928) (xy 397.067786 -60.279534) (xy 397.067532 -60.279534)
			(xy 397.046603 -60.297177) (xy 397.000629 -60.326887) (xy 396.95088 -60.349722) (xy 396.898379 -60.365212)
			(xy 396.844203 -60.37304) (xy 396.816834 -60.373514) (xy 396.78958 -60.373041) (xy 396.735626 -60.365288)
			(xy 396.683325 -60.349935) (xy 396.633742 -60.327295) (xy 396.587885 -60.297828) (xy 396.546689 -60.262135)
			(xy 396.510992 -60.220942) (xy 396.481521 -60.175088) (xy 396.458877 -60.125507) (xy 396.443519 -60.073207)
			(xy 396.435761 -60.019254) (xy 388.561187 -60.019254) (xy 388.597778 -60.633356) (xy 408.096972 -60.633356)
			(xy 408.101043 -60.577734) (xy 408.113169 -60.523297) (xy 408.133092 -60.471206) (xy 408.160388 -60.422571)
			(xy 408.194474 -60.378428) (xy 408.234623 -60.339719) (xy 408.279981 -60.307268) (xy 408.329581 -60.281767)
			(xy 408.382365 -60.26376) (xy 408.437208 -60.25363) (xy 408.492942 -60.251593) (xy 408.548379 -60.257693)
			(xy 408.602336 -60.271799) (xy 408.653665 -60.293611) (xy 408.701271 -60.322665) (xy 408.744139 -60.35834)
			(xy 408.781356 -60.399877) (xy 408.812129 -60.44639) (xy 408.835801 -60.496887) (xy 408.851869 -60.550294)
			(xy 408.859989 -60.60547) (xy 408.860498 -60.633356) (xy 408.859989 -60.661242) (xy 408.851869 -60.716418)
			(xy 408.835801 -60.769825) (xy 408.812129 -60.820322) (xy 408.781356 -60.866835) (xy 408.744139 -60.908372)
			(xy 408.701271 -60.944047) (xy 408.653665 -60.973101) (xy 408.602336 -60.994913) (xy 408.548379 -61.009019)
			(xy 408.492942 -61.015119) (xy 408.437208 -61.013082) (xy 408.382365 -61.002952) (xy 408.329581 -60.984945)
			(xy 408.279981 -60.959444) (xy 408.234623 -60.926993) (xy 408.194474 -60.888284) (xy 408.160388 -60.844141)
			(xy 408.133092 -60.795506) (xy 408.113169 -60.743415) (xy 408.101043 -60.688978) (xy 408.096972 -60.633356)
			(xy 388.597778 -60.633356) (xy 388.648691 -61.487812) (xy 406.604468 -61.487812) (xy 406.608539 -61.43219)
			(xy 406.620665 -61.377753) (xy 406.640588 -61.325662) (xy 406.667884 -61.277027) (xy 406.70197 -61.232884)
			(xy 406.742119 -61.194175) (xy 406.787477 -61.161724) (xy 406.837077 -61.136223) (xy 406.889861 -61.118216)
			(xy 406.944704 -61.108086) (xy 407.000438 -61.106049) (xy 407.055875 -61.112149) (xy 407.109832 -61.126255)
			(xy 407.161161 -61.148067) (xy 407.208767 -61.177121) (xy 407.251635 -61.212796) (xy 407.288852 -61.254333)
			(xy 407.319625 -61.300846) (xy 407.343297 -61.351343) (xy 407.359365 -61.40475) (xy 407.367485 -61.459926)
			(xy 407.367994 -61.487812) (xy 407.367485 -61.515698) (xy 407.359365 -61.570874) (xy 407.343297 -61.624281)
			(xy 407.319625 -61.674778) (xy 407.288852 -61.721291) (xy 407.251635 -61.762828) (xy 407.208767 -61.798503)
			(xy 407.161161 -61.827557) (xy 407.109832 -61.849369) (xy 407.055875 -61.863475) (xy 407.000438 -61.869575)
			(xy 406.944704 -61.867538) (xy 406.889861 -61.857408) (xy 406.837077 -61.839401) (xy 406.787477 -61.8139)
			(xy 406.742119 -61.781449) (xy 406.70197 -61.74274) (xy 406.667884 -61.698597) (xy 406.640588 -61.649962)
			(xy 406.620665 -61.597871) (xy 406.608539 -61.543434) (xy 406.604468 -61.487812) (xy 388.648691 -61.487812)
			(xy 388.6835 -62.072012) (xy 388.684874 -62.121034) (xy 404.542242 -62.121034) (xy 404.546313 -62.065412)
			(xy 404.558439 -62.010975) (xy 404.578362 -61.958884) (xy 404.605658 -61.910249) (xy 404.639744 -61.866106)
			(xy 404.679893 -61.827397) (xy 404.725251 -61.794946) (xy 404.774851 -61.769445) (xy 404.827635 -61.751438)
			(xy 404.882478 -61.741308) (xy 404.938212 -61.739271) (xy 404.993649 -61.745371) (xy 405.047606 -61.759477)
			(xy 405.098935 -61.781289) (xy 405.146541 -61.810343) (xy 405.189409 -61.846018) (xy 405.226626 -61.887555)
			(xy 405.257399 -61.934068) (xy 405.281071 -61.984565) (xy 405.297139 -62.037972) (xy 405.305259 -62.093148)
			(xy 405.305768 -62.121034) (xy 405.305259 -62.14892) (xy 405.297139 -62.204096) (xy 405.281071 -62.257503)
			(xy 405.257399 -62.308) (xy 405.226626 -62.354513) (xy 405.189409 -62.39605) (xy 405.146541 -62.431725)
			(xy 405.098935 -62.460779) (xy 405.047606 -62.482591) (xy 404.993649 -62.496697) (xy 404.938212 -62.502797)
			(xy 404.882478 -62.50076) (xy 404.827635 -62.49063) (xy 404.774851 -62.472623) (xy 404.725251 -62.447122)
			(xy 404.679893 -62.414671) (xy 404.639744 -62.375962) (xy 404.605658 -62.331819) (xy 404.578362 -62.283184)
			(xy 404.558439 -62.231093) (xy 404.546313 -62.176656) (xy 404.542242 -62.121034) (xy 388.684874 -62.121034)
			(xy 388.685024 -62.126368) (xy 388.689596 -63.02502) (xy 388.689596 -63.026036) (xy 388.690612 -63.074804)
			(xy 388.690612 -63.075566) (xy 388.68985 -63.110364) (xy 388.68985 -63.112396) (xy 388.690348 -63.213554)
			(xy 396.420765 -63.213554) (xy 396.420765 -63.159046) (xy 396.428523 -63.105092) (xy 396.443882 -63.052792)
			(xy 396.466527 -63.00321) (xy 396.495999 -62.957355) (xy 396.531697 -62.916163) (xy 396.572894 -62.88047)
			(xy 396.618752 -62.851004) (xy 396.668337 -62.828365) (xy 396.720639 -62.813013) (xy 396.774594 -62.805262)
			(xy 396.801848 -62.804802) (xy 396.829217 -62.805298) (xy 396.883395 -62.813109) (xy 396.935898 -62.828591)
			(xy 396.985645 -62.851426) (xy 397.031613 -62.881144) (xy 397.052546 -62.898782) (xy 397.0528 -62.899036)
			(xy 397.059879 -62.904633) (xy 397.076802 -62.910872) (xy 397.08582 -62.911228) (xy 397.152876 -62.911228)
			(xy 397.161891 -62.910853) (xy 397.178808 -62.904617) (xy 397.185896 -62.899036) (xy 397.185896 -62.898782)
			(xy 397.18615 -62.898782) (xy 397.207083 -62.881141) (xy 397.253051 -62.851417) (xy 397.302797 -62.828571)
			(xy 397.355299 -62.813075) (xy 397.409477 -62.805246) (xy 397.464219 -62.805246) (xy 397.518397 -62.813075)
			(xy 397.570899 -62.828571) (xy 397.620645 -62.851417) (xy 397.666613 -62.881141) (xy 397.687546 -62.898782)
			(xy 397.6878 -62.899036) (xy 397.694879 -62.904633) (xy 397.711802 -62.910872) (xy 397.72082 -62.911228)
			(xy 397.787876 -62.911228) (xy 397.796891 -62.910853) (xy 397.813808 -62.904617) (xy 397.820896 -62.899036)
			(xy 397.820896 -62.898782) (xy 397.82115 -62.898782) (xy 397.842088 -62.88115) (xy 397.888059 -62.851438)
			(xy 397.937805 -62.828601) (xy 397.990305 -62.813108) (xy 398.044479 -62.805277) (xy 398.071848 -62.804802)
			(xy 398.099098 -62.805271) (xy 398.153042 -62.813033) (xy 398.205332 -62.828393) (xy 398.254905 -62.851038)
			(xy 398.30075 -62.880506) (xy 398.341936 -62.916198) (xy 398.377623 -62.957388) (xy 398.407086 -63.003238)
			(xy 398.429724 -63.052813) (xy 398.439536 -63.086234) (xy 401.687536 -63.086234) (xy 401.691607 -63.030612)
			(xy 401.703733 -62.976175) (xy 401.723656 -62.924084) (xy 401.750952 -62.875449) (xy 401.785038 -62.831306)
			(xy 401.825187 -62.792597) (xy 401.870545 -62.760146) (xy 401.920145 -62.734645) (xy 401.972929 -62.716638)
			(xy 402.027772 -62.706508) (xy 402.083506 -62.704471) (xy 402.138943 -62.710571) (xy 402.1929 -62.724677)
			(xy 402.244229 -62.746489) (xy 402.291835 -62.775543) (xy 402.334703 -62.811218) (xy 402.37192 -62.852755)
			(xy 402.402693 -62.899268) (xy 402.426365 -62.949765) (xy 402.442433 -63.003172) (xy 402.450553 -63.058348)
			(xy 402.451062 -63.086234) (xy 402.450553 -63.11412) (xy 402.442433 -63.169296) (xy 402.426365 -63.222703)
			(xy 402.402693 -63.2732) (xy 402.40254 -63.273432) (xy 403.876762 -63.273432) (xy 403.880833 -63.21781)
			(xy 403.892959 -63.163373) (xy 403.912882 -63.111282) (xy 403.940178 -63.062647) (xy 403.974264 -63.018504)
			(xy 404.014413 -62.979795) (xy 404.059771 -62.947344) (xy 404.109371 -62.921843) (xy 404.162155 -62.903836)
			(xy 404.216998 -62.893706) (xy 404.272732 -62.891669) (xy 404.328169 -62.897769) (xy 404.382126 -62.911875)
			(xy 404.433455 -62.933687) (xy 404.481061 -62.962741) (xy 404.523929 -62.998416) (xy 404.561146 -63.039953)
			(xy 404.591919 -63.086466) (xy 404.615591 -63.136963) (xy 404.631659 -63.19037) (xy 404.639779 -63.245546)
			(xy 404.640288 -63.273432) (xy 404.639779 -63.301318) (xy 404.631659 -63.356494) (xy 404.615591 -63.409901)
			(xy 404.591919 -63.460398) (xy 404.561146 -63.506911) (xy 404.523929 -63.548448) (xy 404.481061 -63.584123)
			(xy 404.433455 -63.613177) (xy 404.382126 -63.634989) (xy 404.328169 -63.649095) (xy 404.272732 -63.655195)
			(xy 404.216998 -63.653158) (xy 404.162155 -63.643028) (xy 404.109371 -63.625021) (xy 404.059771 -63.59952)
			(xy 404.014413 -63.567069) (xy 403.974264 -63.52836) (xy 403.940178 -63.484217) (xy 403.912882 -63.435582)
			(xy 403.892959 -63.383491) (xy 403.880833 -63.329054) (xy 403.876762 -63.273432) (xy 402.40254 -63.273432)
			(xy 402.37192 -63.319713) (xy 402.334703 -63.36125) (xy 402.291835 -63.396925) (xy 402.244229 -63.425979)
			(xy 402.1929 -63.447791) (xy 402.138943 -63.461897) (xy 402.083506 -63.467997) (xy 402.027772 -63.46596)
			(xy 401.972929 -63.45583) (xy 401.920145 -63.437823) (xy 401.870545 -63.412322) (xy 401.825187 -63.379871)
			(xy 401.785038 -63.341162) (xy 401.750952 -63.297019) (xy 401.723656 -63.248384) (xy 401.703733 -63.196293)
			(xy 401.691607 -63.141856) (xy 401.687536 -63.086234) (xy 398.439536 -63.086234) (xy 398.445077 -63.105105)
			(xy 398.452832 -63.15905) (xy 398.452832 -63.21355) (xy 398.445077 -63.267495) (xy 398.429724 -63.319787)
			(xy 398.407086 -63.369362) (xy 398.377623 -63.415212) (xy 398.341936 -63.456402) (xy 398.30075 -63.492094)
			(xy 398.254905 -63.521562) (xy 398.205332 -63.544207) (xy 398.153042 -63.559567) (xy 398.099098 -63.567329)
			(xy 398.071848 -63.567818) (xy 398.044478 -63.567344) (xy 397.990298 -63.559531) (xy 397.937795 -63.544045)
			(xy 397.888047 -63.521204) (xy 397.842081 -63.49148) (xy 397.82115 -63.473838) (xy 397.820896 -63.473584)
			(xy 397.813816 -63.467988) (xy 397.796894 -63.461747) (xy 397.787876 -63.461392) (xy 397.72082 -63.461392)
			(xy 397.711804 -63.46176) (xy 397.694887 -63.468) (xy 397.6878 -63.473584) (xy 397.687546 -63.473838)
			(xy 397.666613 -63.491479) (xy 397.620645 -63.521203) (xy 397.570899 -63.544049) (xy 397.518397 -63.559545)
			(xy 397.464219 -63.567374) (xy 397.409477 -63.567374) (xy 397.355299 -63.559545) (xy 397.302797 -63.544049)
			(xy 397.253051 -63.521203) (xy 397.207083 -63.491479) (xy 397.18615 -63.473838) (xy 397.185896 -63.473584)
			(xy 397.178816 -63.467988) (xy 397.161894 -63.461747) (xy 397.152876 -63.461392) (xy 397.08582 -63.461392)
			(xy 397.076804 -63.46176) (xy 397.059887 -63.468) (xy 397.0528 -63.473584) (xy 397.0528 -63.473838)
			(xy 397.052546 -63.473838) (xy 397.031613 -63.491475) (xy 396.98564 -63.521186) (xy 396.935892 -63.544022)
			(xy 396.883392 -63.559514) (xy 396.829217 -63.567343) (xy 396.801848 -63.567818) (xy 396.774594 -63.567338)
			(xy 396.720639 -63.559587) (xy 396.668337 -63.544235) (xy 396.618752 -63.521596) (xy 396.572894 -63.49213)
			(xy 396.531697 -63.456437) (xy 396.495999 -63.415245) (xy 396.466527 -63.36939) (xy 396.443882 -63.319808)
			(xy 396.428523 -63.267508) (xy 396.420765 -63.213554) (xy 388.690348 -63.213554) (xy 388.695753 -64.312292)
			(xy 407.20594 -64.312292) (xy 407.210011 -64.25667) (xy 407.222137 -64.202233) (xy 407.24206 -64.150142)
			(xy 407.269356 -64.101507) (xy 407.303442 -64.057364) (xy 407.343591 -64.018655) (xy 407.388949 -63.986204)
			(xy 407.438549 -63.960703) (xy 407.491333 -63.942696) (xy 407.546176 -63.932566) (xy 407.60191 -63.930529)
			(xy 407.657347 -63.936629) (xy 407.711304 -63.950735) (xy 407.762633 -63.972547) (xy 407.810239 -64.001601)
			(xy 407.853107 -64.037276) (xy 407.890324 -64.078813) (xy 407.921097 -64.125326) (xy 407.944769 -64.175823)
			(xy 407.960837 -64.22923) (xy 407.968957 -64.284406) (xy 407.969466 -64.312292) (xy 407.968957 -64.340178)
			(xy 407.960837 -64.395354) (xy 407.944769 -64.448761) (xy 407.921097 -64.499258) (xy 407.890324 -64.545771)
			(xy 407.853107 -64.587308) (xy 407.810239 -64.622983) (xy 407.762633 -64.652037) (xy 407.711304 -64.673849)
			(xy 407.657347 -64.687955) (xy 407.60191 -64.694055) (xy 407.546176 -64.692018) (xy 407.491333 -64.681888)
			(xy 407.438549 -64.663881) (xy 407.388949 -64.63838) (xy 407.343591 -64.605929) (xy 407.303442 -64.56722)
			(xy 407.269356 -64.523077) (xy 407.24206 -64.474442) (xy 407.222137 -64.422351) (xy 407.210011 -64.367914)
			(xy 407.20594 -64.312292) (xy 388.695753 -64.312292) (xy 388.699632 -65.100962) (xy 394.432534 -65.100962)
			(xy 394.436605 -65.04534) (xy 394.448731 -64.990903) (xy 394.468654 -64.938812) (xy 394.49595 -64.890177)
			(xy 394.530036 -64.846034) (xy 394.570185 -64.807325) (xy 394.615543 -64.774874) (xy 394.665143 -64.749373)
			(xy 394.717927 -64.731366) (xy 394.77277 -64.721236) (xy 394.828504 -64.719199) (xy 394.883941 -64.725299)
			(xy 394.937898 -64.739405) (xy 394.989227 -64.761217) (xy 395.036833 -64.790271) (xy 395.079701 -64.825946)
			(xy 395.116918 -64.867483) (xy 395.147691 -64.913996) (xy 395.171363 -64.964493) (xy 395.187431 -65.0179)
			(xy 395.195551 -65.073076) (xy 395.19606 -65.100962) (xy 395.195551 -65.128848) (xy 395.187431 -65.184024)
			(xy 395.171363 -65.237431) (xy 395.147691 -65.287928) (xy 395.116918 -65.334441) (xy 395.079701 -65.375978)
			(xy 395.036833 -65.411653) (xy 394.989227 -65.440707) (xy 394.937898 -65.462519) (xy 394.883941 -65.476625)
			(xy 394.828504 -65.482725) (xy 394.77277 -65.480688) (xy 394.717927 -65.470558) (xy 394.665143 -65.452551)
			(xy 394.615543 -65.42705) (xy 394.570185 -65.394599) (xy 394.530036 -65.35589) (xy 394.49595 -65.311747)
			(xy 394.468654 -65.263112) (xy 394.448731 -65.211021) (xy 394.436605 -65.156584) (xy 394.432534 -65.100962)
			(xy 388.699632 -65.100962) (xy 388.700772 -65.33261) (xy 388.702244 -65.344473) (xy 388.714431 -65.365005)
			(xy 388.72414 -65.37198) (xy 388.801864 -65.418208) (xy 388.807417 -65.421078) (xy 388.819495 -65.42429)
			(xy 388.82574 -65.424558) (xy 388.844028 -65.419986) (xy 388.854696 -65.415922) (xy 388.881738 -65.402732)
			(xy 388.938937 -65.384081) (xy 388.998351 -65.374618) (xy 389.028432 -65.374012) (xy 389.031988 -65.374012)
			(xy 389.059085 -65.374721) (xy 389.112676 -65.382855) (xy 389.164577 -65.398493) (xy 389.213741 -65.42132)
			(xy 389.259179 -65.450876) (xy 389.299976 -65.486566) (xy 389.335311 -65.527671) (xy 389.364472 -65.573364)
			(xy 389.386871 -65.622724) (xy 389.402059 -65.674758) (xy 389.409728 -65.728418) (xy 389.410194 -65.75552)
			(xy 389.409706 -65.78277) (xy 389.401947 -65.836715) (xy 389.38659 -65.889006) (xy 389.363948 -65.93858)
			(xy 389.334481 -65.984427) (xy 389.298789 -66.025613) (xy 389.257599 -66.061301) (xy 389.21175 -66.090764)
			(xy 389.162174 -66.113402) (xy 389.109881 -66.128755) (xy 389.055936 -66.136509) (xy 389.028686 -66.137028)
			(xy 389.027924 -66.137028) (xy 388.997693 -66.136434) (xy 388.937993 -66.126852) (xy 388.880558 -66.107958)
			(xy 388.853426 -66.09461) (xy 388.853172 -66.094356) (xy 388.852918 -66.094102) (xy 388.847135 -66.091379)
			(xy 388.834672 -66.088563) (xy 388.82828 -66.088514) (xy 388.815072 -66.089022) (xy 388.768336 -66.11747)
			(xy 388.728966 -66.141346) (xy 388.721737 -66.146234) (xy 388.710834 -66.159842) (xy 388.705109 -66.176313)
			(xy 388.704836 -66.185034) (xy 388.705598 -66.37274) (xy 388.705852 -66.402458) (xy 388.707122 -66.685668)
			(xy 388.708585 -66.697337) (xy 388.720489 -66.71759) (xy 388.729982 -66.72453) (xy 388.732522 -66.726054)
			(xy 388.744968 -66.733166) (xy 388.797546 -66.763392) (xy 388.803424 -66.766532) (xy 388.816286 -66.770002)
			(xy 388.822946 -66.77025) (xy 388.858506 -66.77025) (xy 388.868158 -66.76517) (xy 388.895962 -66.751041)
			(xy 388.955025 -66.731019) (xy 389.016554 -66.720851) (xy 389.047736 -66.720212) (xy 389.073779 -66.720677)
			(xy 389.125375 -66.727806) (xy 389.175523 -66.741885) (xy 389.22329 -66.762652) (xy 389.267789 -66.789722)
			(xy 389.288274 -66.80581) (xy 389.28929 -66.806318) (xy 389.292084 -66.808604) (xy 389.308086 -66.814192)
			(xy 389.349488 -66.814192) (xy 389.349488 -66.826638) (xy 389.399018 -66.826638) (xy 389.403844 -66.826384)
			(xy 389.411254 -66.825411) (xy 389.425065 -66.819721) (xy 389.431022 -66.815208) (xy 389.432038 -66.814192)
			(xy 389.45297 -66.796552) (xy 389.498938 -66.766832) (xy 389.548685 -66.743994) (xy 389.601188 -66.728509)
			(xy 389.655366 -66.720696) (xy 389.682736 -66.720212) (xy 389.709984 -66.720701) (xy 389.763925 -66.728461)
			(xy 389.816213 -66.743818) (xy 389.865783 -66.76646) (xy 389.911626 -66.795926) (xy 389.95281 -66.831616)
			(xy 389.988496 -66.872803) (xy 390.017957 -66.918649) (xy 390.040594 -66.968221) (xy 390.055947 -67.02051)
			(xy 390.063702 -67.074452) (xy 390.063702 -67.128948) (xy 390.055947 -67.18289) (xy 390.040594 -67.235179)
			(xy 390.017957 -67.284751) (xy 389.988496 -67.330597) (xy 389.95281 -67.371784) (xy 389.911626 -67.407474)
			(xy 389.865783 -67.43694) (xy 389.816213 -67.459582) (xy 389.763925 -67.474939) (xy 389.709984 -67.482699)
			(xy 389.682736 -67.483228) (xy 389.656694 -67.482761) (xy 389.605099 -67.47563) (xy 389.554952 -67.461549)
			(xy 389.507186 -67.440781) (xy 389.462688 -67.413711) (xy 389.442198 -67.39763) (xy 389.441182 -67.397122)
			(xy 389.438388 -67.394836) (xy 389.422386 -67.389248) (xy 389.380984 -67.389248) (xy 389.380984 -67.376802)
			(xy 389.331454 -67.376802) (xy 389.326628 -67.377056) (xy 389.319213 -67.378018) (xy 389.305385 -67.383687)
			(xy 389.29945 -67.388232) (xy 389.298434 -67.389248) (xy 389.277504 -67.406894) (xy 389.23154 -67.436628)
			(xy 389.181793 -67.459479) (xy 389.129289 -67.474976) (xy 389.075108 -67.482801) (xy 389.047736 -67.483228)
			(xy 389.047482 -67.483228) (xy 389.015864 -67.482585) (xy 388.953497 -67.472122) (xy 388.893704 -67.451536)
			(xy 388.865618 -67.437) (xy 388.862062 -67.435222) (xy 388.854494 -67.431319) (xy 388.837745 -67.428294)
			(xy 388.820936 -67.430959) (xy 388.813294 -67.434714) (xy 388.734554 -67.48145) (xy 388.72759 -67.486339)
			(xy 388.726255 -67.488054) (xy 393.079222 -67.488054) (xy 393.083293 -67.432432) (xy 393.095419 -67.377995)
			(xy 393.115342 -67.325904) (xy 393.142638 -67.277269) (xy 393.176724 -67.233126) (xy 393.216873 -67.194417)
			(xy 393.262231 -67.161966) (xy 393.311831 -67.136465) (xy 393.364615 -67.118458) (xy 393.419458 -67.108328)
			(xy 393.475192 -67.106291) (xy 393.530629 -67.112391) (xy 393.584586 -67.126497) (xy 393.635915 -67.148309)
			(xy 393.683521 -67.177363) (xy 393.726389 -67.213038) (xy 393.763606 -67.254575) (xy 393.794379 -67.301088)
			(xy 393.818051 -67.351585) (xy 393.834119 -67.404992) (xy 393.842239 -67.460168) (xy 393.842748 -67.488054)
			(xy 393.842239 -67.51594) (xy 393.839054 -67.537584) (xy 394.37132 -67.537584) (xy 394.375391 -67.481962)
			(xy 394.387517 -67.427525) (xy 394.40744 -67.375434) (xy 394.434736 -67.326799) (xy 394.468822 -67.282656)
			(xy 394.508971 -67.243947) (xy 394.554329 -67.211496) (xy 394.603929 -67.185995) (xy 394.656713 -67.167988)
			(xy 394.711556 -67.157858) (xy 394.76729 -67.155821) (xy 394.822727 -67.161921) (xy 394.876684 -67.176027)
			(xy 394.928013 -67.197839) (xy 394.975619 -67.226893) (xy 395.018487 -67.262568) (xy 395.055704 -67.304105)
			(xy 395.086477 -67.350618) (xy 395.110149 -67.401115) (xy 395.126217 -67.454522) (xy 395.134337 -67.509698)
			(xy 395.134846 -67.537584) (xy 395.134337 -67.56547) (xy 395.130292 -67.592956) (xy 395.645384 -67.592956)
			(xy 395.649455 -67.537334) (xy 395.661581 -67.482897) (xy 395.681504 -67.430806) (xy 395.7088 -67.382171)
			(xy 395.742886 -67.338028) (xy 395.783035 -67.299319) (xy 395.828393 -67.266868) (xy 395.877993 -67.241367)
			(xy 395.930777 -67.22336) (xy 395.98562 -67.21323) (xy 396.041354 -67.211193) (xy 396.096791 -67.217293)
			(xy 396.150748 -67.231399) (xy 396.202077 -67.253211) (xy 396.249683 -67.282265) (xy 396.292551 -67.31794)
			(xy 396.329768 -67.359477) (xy 396.360541 -67.40599) (xy 396.384213 -67.456487) (xy 396.400281 -67.509894)
			(xy 396.408398 -67.565051) (xy 398.746693 -67.565051) (xy 398.746693 -67.510549) (xy 398.75445 -67.456601)
			(xy 398.769806 -67.404306) (xy 398.792448 -67.354729) (xy 398.821916 -67.308879) (xy 398.857609 -67.26769)
			(xy 398.8988 -67.232) (xy 398.944652 -67.202536) (xy 398.994231 -67.179897) (xy 399.046526 -67.164545)
			(xy 399.100475 -67.156791) (xy 399.127726 -67.15633) (xy 399.155097 -67.156774) (xy 399.209277 -67.164596)
			(xy 399.261781 -67.18009) (xy 399.311528 -67.202937) (xy 399.357493 -67.232666) (xy 399.378424 -67.25031)
			(xy 399.378678 -67.250564) (xy 399.385761 -67.256155) (xy 399.402681 -67.262397) (xy 399.411698 -67.262756)
			(xy 399.478754 -67.262756) (xy 399.48777 -67.262387) (xy 399.504687 -67.256149) (xy 399.511774 -67.250564)
			(xy 399.511774 -67.25031) (xy 399.512028 -67.25031) (xy 399.532978 -67.232693) (xy 399.578945 -67.202977)
			(xy 399.628689 -67.180137) (xy 399.681185 -67.164641) (xy 399.735358 -67.156807) (xy 399.762726 -67.15633)
			(xy 399.789979 -67.156742) (xy 399.843929 -67.164502) (xy 399.896226 -67.179861) (xy 399.945805 -67.202506)
			(xy 399.991656 -67.231976) (xy 400.032848 -67.267671) (xy 400.06854 -67.308864) (xy 400.098007 -67.354718)
			(xy 400.120648 -67.404299) (xy 400.136004 -67.456596) (xy 400.14376 -67.510547) (xy 400.14376 -67.565053)
			(xy 400.136004 -67.619004) (xy 400.120648 -67.671301) (xy 400.098007 -67.720882) (xy 400.06854 -67.766736)
			(xy 400.032848 -67.807929) (xy 399.991656 -67.843624) (xy 399.945805 -67.873094) (xy 399.896226 -67.895739)
			(xy 399.843929 -67.911098) (xy 399.789979 -67.918858) (xy 399.762726 -67.919346) (xy 399.735356 -67.918878)
			(xy 399.681176 -67.911063) (xy 399.628673 -67.895575) (xy 399.578926 -67.872733) (xy 399.532959 -67.843008)
			(xy 399.512028 -67.825366) (xy 399.511774 -67.825112) (xy 399.504669 -67.819552) (xy 399.487767 -67.813289)
			(xy 399.478754 -67.81292) (xy 399.411698 -67.81292) (xy 399.40268 -67.813272) (xy 399.385763 -67.819522)
			(xy 399.378678 -67.825112) (xy 399.378678 -67.825366) (xy 399.378424 -67.825366) (xy 399.357489 -67.843002)
			(xy 399.311518 -67.872715) (xy 399.261771 -67.895553) (xy 399.209271 -67.911044) (xy 399.155095 -67.918872)
			(xy 399.127726 -67.919346) (xy 399.100475 -67.918809) (xy 399.046526 -67.911055) (xy 398.994231 -67.895703)
			(xy 398.944652 -67.873064) (xy 398.8988 -67.8436) (xy 398.857609 -67.80791) (xy 398.821916 -67.766721)
			(xy 398.792448 -67.720871) (xy 398.769806 -67.671294) (xy 398.75445 -67.618999) (xy 398.746693 -67.565051)
			(xy 396.408398 -67.565051) (xy 396.408401 -67.56507) (xy 396.40891 -67.592956) (xy 396.408401 -67.620842)
			(xy 396.400281 -67.676018) (xy 396.384213 -67.729425) (xy 396.360541 -67.779922) (xy 396.329768 -67.826435)
			(xy 396.292551 -67.867972) (xy 396.249683 -67.903647) (xy 396.202077 -67.932701) (xy 396.150748 -67.954513)
			(xy 396.096791 -67.968619) (xy 396.041354 -67.974719) (xy 395.98562 -67.972682) (xy 395.930777 -67.962552)
			(xy 395.877993 -67.944545) (xy 395.828393 -67.919044) (xy 395.783035 -67.886593) (xy 395.742886 -67.847884)
			(xy 395.7088 -67.803741) (xy 395.681504 -67.755106) (xy 395.661581 -67.703015) (xy 395.649455 -67.648578)
			(xy 395.645384 -67.592956) (xy 395.130292 -67.592956) (xy 395.126217 -67.620646) (xy 395.110149 -67.674053)
			(xy 395.086477 -67.72455) (xy 395.055704 -67.771063) (xy 395.018487 -67.8126) (xy 394.975619 -67.848275)
			(xy 394.928013 -67.877329) (xy 394.876684 -67.899141) (xy 394.822727 -67.913247) (xy 394.76729 -67.919347)
			(xy 394.711556 -67.91731) (xy 394.656713 -67.90718) (xy 394.603929 -67.889173) (xy 394.554329 -67.863672)
			(xy 394.508971 -67.831221) (xy 394.468822 -67.792512) (xy 394.434736 -67.748369) (xy 394.40744 -67.699734)
			(xy 394.387517 -67.647643) (xy 394.375391 -67.593206) (xy 394.37132 -67.537584) (xy 393.839054 -67.537584)
			(xy 393.834119 -67.571116) (xy 393.818051 -67.624523) (xy 393.794379 -67.67502) (xy 393.763606 -67.721533)
			(xy 393.726389 -67.76307) (xy 393.683521 -67.798745) (xy 393.635915 -67.827799) (xy 393.584586 -67.849611)
			(xy 393.530629 -67.863717) (xy 393.475192 -67.869817) (xy 393.419458 -67.86778) (xy 393.364615 -67.85765)
			(xy 393.311831 -67.839643) (xy 393.262231 -67.814142) (xy 393.216873 -67.781691) (xy 393.176724 -67.742982)
			(xy 393.142638 -67.698839) (xy 393.115342 -67.650204) (xy 393.095419 -67.598113) (xy 393.083293 -67.543676)
			(xy 393.079222 -67.488054) (xy 388.726255 -67.488054) (xy 388.717144 -67.499759) (xy 388.711697 -67.51587)
			(xy 388.71144 -67.524376) (xy 388.716576 -68.586604) (xy 390.925304 -68.586604) (xy 390.925771 -68.559234)
			(xy 390.933589 -68.505055) (xy 390.949077 -68.452552) (xy 390.971919 -68.402805) (xy 391.001643 -68.356838)
			(xy 391.019284 -68.335906) (xy 391.019538 -68.335652) (xy 391.025113 -68.328558) (xy 391.031366 -68.311647)
			(xy 391.03173 -68.302632) (xy 391.03173 -68.235576) (xy 391.031378 -68.226559) (xy 391.025126 -68.209642)
			(xy 391.019538 -68.202556) (xy 391.019284 -68.202556) (xy 391.019284 -68.202302) (xy 391.00163 -68.181382)
			(xy 390.971921 -68.135406) (xy 390.949088 -68.085655) (xy 390.9336 -68.033152) (xy 390.925776 -67.978974)
			(xy 390.925304 -67.951604) (xy 390.925759 -67.924351) (xy 390.933516 -67.870399) (xy 390.948872 -67.8181)
			(xy 390.971515 -67.768519) (xy 391.000984 -67.722666) (xy 391.036678 -67.681472) (xy 391.077872 -67.645779)
			(xy 391.123726 -67.616311) (xy 391.173308 -67.593669) (xy 391.225607 -67.578314) (xy 391.279559 -67.570559)
			(xy 391.306812 -67.570096) (xy 391.333126 -67.570557) (xy 391.385255 -67.577793) (xy 391.435898 -67.592114)
			(xy 391.484097 -67.613247) (xy 391.52894 -67.640795) (xy 391.569579 -67.674234) (xy 391.587736 -67.693286)
			(xy 391.595244 -67.700703) (xy 391.614534 -67.709219) (xy 391.625074 -67.709796) (xy 391.69975 -67.709796)
			(xy 391.710298 -67.709255) (xy 391.729594 -67.700728) (xy 391.737088 -67.693286) (xy 391.755254 -67.674241)
			(xy 391.795882 -67.640783) (xy 391.84072 -67.613223) (xy 391.888919 -67.592083) (xy 391.939564 -67.577763)
			(xy 391.991696 -67.570536) (xy 392.018012 -67.570096) (xy 392.045382 -67.570556) (xy 392.099562 -67.578375)
			(xy 392.152065 -67.593866) (xy 392.201812 -67.616709) (xy 392.247778 -67.646434) (xy 392.26871 -67.664076)
			(xy 392.268964 -67.66433) (xy 392.276054 -67.669911) (xy 392.292968 -67.67616) (xy 392.301984 -67.676522)
			(xy 392.36904 -67.676522) (xy 392.378058 -67.676179) (xy 392.394975 -67.669921) (xy 392.40206 -67.66433)
			(xy 392.40206 -67.664076) (xy 392.402314 -67.664076) (xy 392.423265 -67.64646) (xy 392.469233 -67.616746)
			(xy 392.518976 -67.593906) (xy 392.571472 -67.578409) (xy 392.625644 -67.570574) (xy 392.653012 -67.570096)
			(xy 392.680264 -67.570567) (xy 392.734212 -67.578325) (xy 392.786507 -67.593682) (xy 392.836085 -67.616325)
			(xy 392.881936 -67.645792) (xy 392.923126 -67.681486) (xy 392.958817 -67.722677) (xy 392.988283 -67.768529)
			(xy 393.010924 -67.818108) (xy 393.026279 -67.870403) (xy 393.034035 -67.924352) (xy 393.03452 -67.951604)
			(xy 393.034076 -67.978975) (xy 393.026256 -68.033156) (xy 393.010763 -68.08566) (xy 392.987915 -68.135407)
			(xy 392.958185 -68.181372) (xy 392.94054 -68.202302) (xy 392.940286 -68.202556) (xy 392.93471 -68.20965)
			(xy 392.928457 -68.226561) (xy 392.928094 -68.235576) (xy 392.928094 -68.302632) (xy 392.928437 -68.31165)
			(xy 392.934695 -68.328567) (xy 392.940286 -68.335652) (xy 392.94054 -68.335652) (xy 392.94054 -68.335906)
			(xy 392.958202 -68.35682) (xy 392.987909 -68.402798) (xy 393.01074 -68.45255) (xy 393.026226 -68.505055)
			(xy 393.034049 -68.559234) (xy 393.03452 -68.586604) (xy 393.034026 -68.613855) (xy 393.026269 -68.667802)
			(xy 393.010914 -68.720095) (xy 392.994275 -68.75653) (xy 396.470378 -68.75653) (xy 396.470843 -68.729159)
			(xy 396.478658 -68.67498) (xy 396.494146 -68.622476) (xy 396.516989 -68.572729) (xy 396.546715 -68.526763)
			(xy 396.564358 -68.505832) (xy 396.564612 -68.505578) (xy 396.570215 -68.498503) (xy 396.576452 -68.481577)
			(xy 396.576804 -68.472558) (xy 396.576804 -68.405502) (xy 396.576445 -68.396485) (xy 396.570199 -68.379568)
			(xy 396.564612 -68.372482) (xy 396.564358 -68.372482) (xy 396.564358 -68.372228) (xy 396.546712 -68.351302)
			(xy 396.517002 -68.305327) (xy 396.494168 -68.255578) (xy 396.478679 -68.203076) (xy 396.470851 -68.148899)
			(xy 396.470378 -68.12153) (xy 396.470883 -68.094279) (xy 396.478636 -68.04033) (xy 396.493987 -67.988034)
			(xy 396.516625 -67.938455) (xy 396.546089 -67.892602) (xy 396.581778 -67.851409) (xy 396.622967 -67.815715)
			(xy 396.668816 -67.786246) (xy 396.718392 -67.763603) (xy 396.770687 -67.748245) (xy 396.824635 -67.740486)
			(xy 396.851886 -67.740022) (xy 396.879256 -67.740491) (xy 396.933435 -67.748307) (xy 396.985939 -67.763795)
			(xy 397.035686 -67.786637) (xy 397.081652 -67.816361) (xy 397.102584 -67.834002) (xy 397.102838 -67.834256)
			(xy 397.109933 -67.839829) (xy 397.126844 -67.846083) (xy 397.135858 -67.846448) (xy 397.202914 -67.846448)
			(xy 397.211933 -67.846109) (xy 397.22885 -67.83985) (xy 397.235934 -67.834256) (xy 397.235934 -67.834002)
			(xy 397.236188 -67.834002) (xy 397.257114 -67.816355) (xy 397.303088 -67.786645) (xy 397.352837 -67.76381)
			(xy 397.40534 -67.748321) (xy 397.459516 -67.740495) (xy 397.486886 -67.740022) (xy 397.5132 -67.740492)
			(xy 397.565329 -67.747725) (xy 397.615972 -67.762043) (xy 397.664171 -67.783175) (xy 397.709014 -67.810721)
			(xy 397.749654 -67.84416) (xy 397.76781 -67.863212) (xy 397.775324 -67.870622) (xy 397.79461 -67.879141)
			(xy 397.805148 -67.879722) (xy 397.879824 -67.879722) (xy 397.89037 -67.879159) (xy 397.909665 -67.870647)
			(xy 397.917162 -67.863212) (xy 397.935297 -67.844136) (xy 397.975931 -67.81068) (xy 398.020775 -67.783123)
			(xy 398.06898 -67.761988) (xy 398.119631 -67.747676) (xy 398.171769 -67.740457) (xy 398.198086 -67.740022)
			(xy 398.22534 -67.740468) (xy 398.279293 -67.748224) (xy 398.331593 -67.76358) (xy 398.381175 -67.786223)
			(xy 398.42703 -67.815692) (xy 398.468223 -67.851388) (xy 398.503917 -67.892583) (xy 398.533385 -67.938439)
			(xy 398.556026 -67.988022) (xy 398.571379 -68.040323) (xy 398.579133 -68.094276) (xy 398.579594 -68.12153)
			(xy 398.579147 -68.148901) (xy 398.571325 -68.203081) (xy 398.555831 -68.255584) (xy 398.532985 -68.305331)
			(xy 398.503257 -68.351297) (xy 398.485614 -68.372228) (xy 398.48536 -68.372482) (xy 398.47977 -68.379566)
			(xy 398.473526 -68.396485) (xy 398.473168 -68.405502) (xy 398.473168 -68.472558) (xy 398.473552 -68.481572)
			(xy 398.479782 -68.498489) (xy 398.48536 -68.505578) (xy 398.485614 -68.505578) (xy 398.485614 -68.505832)
			(xy 398.503237 -68.526777) (xy 398.532951 -68.572747) (xy 398.555789 -68.622491) (xy 398.571284 -68.674988)
			(xy 398.579117 -68.729162) (xy 398.579594 -68.75653) (xy 398.57915 -68.783783) (xy 398.571389 -68.837733)
			(xy 398.556029 -68.890029) (xy 398.533384 -68.939607) (xy 398.503913 -68.985458) (xy 398.468217 -69.026648)
			(xy 398.427023 -69.062339) (xy 398.381169 -69.091805) (xy 398.331588 -69.114445) (xy 398.27929 -69.129798)
			(xy 398.225339 -69.137553) (xy 398.198086 -69.138038) (xy 398.171771 -69.1376) (xy 398.11964 -69.130362)
			(xy 398.068996 -69.116038) (xy 398.020797 -69.0949) (xy 397.975954 -69.067348) (xy 397.935317 -69.033903)
			(xy 397.917162 -69.014848) (xy 397.90965 -69.007435) (xy 397.890363 -68.998916) (xy 397.879824 -68.998338)
			(xy 397.805148 -68.998338) (xy 397.794598 -68.998868) (xy 397.775302 -69.007402) (xy 397.76781 -69.014848)
			(xy 397.749652 -69.033901) (xy 397.709022 -69.067356) (xy 397.664182 -69.094915) (xy 397.615982 -69.116053)
			(xy 397.565335 -69.130371) (xy 397.513202 -69.137598) (xy 397.486886 -69.138038) (xy 397.459515 -69.137595)
			(xy 397.405334 -69.129774) (xy 397.35283 -69.11428) (xy 397.303084 -69.091433) (xy 397.257118 -69.061702)
			(xy 397.236188 -69.044058) (xy 397.235934 -69.043804) (xy 397.228842 -69.038226) (xy 397.211929 -69.031974)
			(xy 397.202914 -69.031612) (xy 397.135858 -69.031612) (xy 397.126844 -69.031994) (xy 397.109926 -69.038224)
			(xy 397.102838 -69.043804) (xy 397.102838 -69.044058) (xy 397.102584 -69.044058) (xy 397.081626 -69.061665)
			(xy 397.035661 -69.091383) (xy 396.98592 -69.114226) (xy 396.933425 -69.129724) (xy 396.879253 -69.13756)
			(xy 396.851886 -69.138038) (xy 396.824636 -69.137535) (xy 396.77069 -69.129778) (xy 396.718398 -69.114422)
			(xy 396.668822 -69.091782) (xy 396.622973 -69.062317) (xy 396.581784 -69.026627) (xy 396.546093 -68.985439)
			(xy 396.516626 -68.939592) (xy 396.493983 -68.890017) (xy 396.478626 -68.837725) (xy 396.470866 -68.78378)
			(xy 396.470378 -68.75653) (xy 392.994275 -68.75653) (xy 392.988273 -68.769672) (xy 392.958808 -68.815522)
			(xy 392.923117 -68.856712) (xy 392.881928 -68.892403) (xy 392.836079 -68.92187) (xy 392.786503 -68.944511)
			(xy 392.734209 -68.959868) (xy 392.680263 -68.967625) (xy 392.653012 -68.968112) (xy 392.625642 -68.967636)
			(xy 392.571464 -68.95982) (xy 392.518961 -68.944333) (xy 392.469214 -68.921494) (xy 392.423246 -68.891772)
			(xy 392.402314 -68.874132) (xy 392.40206 -68.873878) (xy 392.394962 -68.868308) (xy 392.378054 -68.862052)
			(xy 392.36904 -68.861686) (xy 392.301984 -68.861686) (xy 392.292967 -68.862039) (xy 392.27605 -68.86829)
			(xy 392.268964 -68.873878) (xy 392.268964 -68.874132) (xy 392.26871 -68.874132) (xy 392.247789 -68.891785)
			(xy 392.201813 -68.921494) (xy 392.152062 -68.944326) (xy 392.099559 -68.959814) (xy 392.045382 -68.967639)
			(xy 392.018012 -68.968112) (xy 391.991698 -68.967633) (xy 391.939571 -68.9604) (xy 391.888928 -68.946083)
			(xy 391.840729 -68.924952) (xy 391.795886 -68.897409) (xy 391.755245 -68.863972) (xy 391.737088 -68.844922)
			(xy 391.72957 -68.837516) (xy 391.710287 -68.828993) (xy 391.69975 -68.828412) (xy 391.625074 -68.828412)
			(xy 391.614527 -68.828964) (xy 391.595231 -68.837483) (xy 391.587736 -68.844922) (xy 391.569609 -68.864006)
			(xy 391.528973 -68.89746) (xy 391.484126 -68.925014) (xy 391.43592 -68.946148) (xy 391.385268 -68.960459)
			(xy 391.33313 -68.967677) (xy 391.306812 -68.968112) (xy 391.27956 -68.967634) (xy 391.225609 -68.959878)
			(xy 391.173312 -68.944524) (xy 391.123732 -68.921883) (xy 391.077879 -68.892417) (xy 391.036687 -68.856725)
			(xy 391.000993 -68.815533) (xy 390.971525 -68.769682) (xy 390.948882 -68.720103) (xy 390.933525 -68.667806)
			(xy 390.925768 -68.613856) (xy 390.925304 -68.586604) (xy 388.716576 -68.586604) (xy 388.730932 -71.555864)
			(xy 393.494512 -71.555864) (xy 393.498583 -71.500242) (xy 393.510709 -71.445805) (xy 393.530632 -71.393714)
			(xy 393.557928 -71.345079) (xy 393.592014 -71.300936) (xy 393.632163 -71.262227) (xy 393.677521 -71.229776)
			(xy 393.727121 -71.204275) (xy 393.779905 -71.186268) (xy 393.834748 -71.176138) (xy 393.890482 -71.174101)
			(xy 393.945919 -71.180201) (xy 393.999876 -71.194307) (xy 394.051205 -71.216119) (xy 394.098811 -71.245173)
			(xy 394.141679 -71.280848) (xy 394.178896 -71.322385) (xy 394.209669 -71.368898) (xy 394.233341 -71.419395)
			(xy 394.249409 -71.472802) (xy 394.257529 -71.527978) (xy 394.258038 -71.555864) (xy 394.257529 -71.58375)
			(xy 394.25169 -71.623428) (xy 395.003526 -71.623428) (xy 395.007597 -71.567806) (xy 395.019723 -71.513369)
			(xy 395.039646 -71.461278) (xy 395.066942 -71.412643) (xy 395.101028 -71.3685) (xy 395.141177 -71.329791)
			(xy 395.186535 -71.29734) (xy 395.236135 -71.271839) (xy 395.288919 -71.253832) (xy 395.343762 -71.243702)
			(xy 395.399496 -71.241665) (xy 395.454933 -71.247765) (xy 395.50889 -71.261871) (xy 395.560219 -71.283683)
			(xy 395.607825 -71.312737) (xy 395.650693 -71.348412) (xy 395.68791 -71.389949) (xy 395.718683 -71.436462)
			(xy 395.742355 -71.486959) (xy 395.758423 -71.540366) (xy 395.766543 -71.595542) (xy 395.767052 -71.623428)
			(xy 395.766543 -71.651314) (xy 395.758423 -71.70649) (xy 395.742355 -71.759897) (xy 395.718683 -71.810394)
			(xy 395.68791 -71.856907) (xy 395.650693 -71.898444) (xy 395.607825 -71.934119) (xy 395.560219 -71.963173)
			(xy 395.50889 -71.984985) (xy 395.454933 -71.999091) (xy 395.399496 -72.005191) (xy 395.343762 -72.003154)
			(xy 395.288919 -71.993024) (xy 395.236135 -71.975017) (xy 395.186535 -71.949516) (xy 395.141177 -71.917065)
			(xy 395.101028 -71.878356) (xy 395.066942 -71.834213) (xy 395.039646 -71.785578) (xy 395.019723 -71.733487)
			(xy 395.007597 -71.67905) (xy 395.003526 -71.623428) (xy 394.25169 -71.623428) (xy 394.249409 -71.638926)
			(xy 394.233341 -71.692333) (xy 394.209669 -71.74283) (xy 394.178896 -71.789343) (xy 394.141679 -71.83088)
			(xy 394.098811 -71.866555) (xy 394.051205 -71.895609) (xy 393.999876 -71.917421) (xy 393.945919 -71.931527)
			(xy 393.890482 -71.937627) (xy 393.834748 -71.93559) (xy 393.779905 -71.92546) (xy 393.727121 -71.907453)
			(xy 393.677521 -71.881952) (xy 393.632163 -71.849501) (xy 393.592014 -71.810792) (xy 393.557928 -71.766649)
			(xy 393.530632 -71.718014) (xy 393.510709 -71.665923) (xy 393.498583 -71.611486) (xy 393.494512 -71.555864)
			(xy 388.730932 -71.555864) (xy 388.759719 -77.509624) (xy 391.980926 -77.509624) (xy 391.984997 -77.454002)
			(xy 391.997123 -77.399565) (xy 392.017046 -77.347474) (xy 392.044342 -77.298839) (xy 392.078428 -77.254696)
			(xy 392.118577 -77.215987) (xy 392.163935 -77.183536) (xy 392.213535 -77.158035) (xy 392.266319 -77.140028)
			(xy 392.321162 -77.129898) (xy 392.376896 -77.127861) (xy 392.432333 -77.133961) (xy 392.48629 -77.148067)
			(xy 392.537619 -77.169879) (xy 392.585225 -77.198933) (xy 392.628093 -77.234608) (xy 392.66531 -77.276145)
			(xy 392.696083 -77.322658) (xy 392.719755 -77.373155) (xy 392.735823 -77.426562) (xy 392.743943 -77.481738)
			(xy 392.744452 -77.509624) (xy 392.744443 -77.510132) (xy 393.554456 -77.510132) (xy 393.558527 -77.45451)
			(xy 393.570653 -77.400073) (xy 393.590576 -77.347982) (xy 393.617872 -77.299347) (xy 393.651958 -77.255204)
			(xy 393.692107 -77.216495) (xy 393.737465 -77.184044) (xy 393.787065 -77.158543) (xy 393.839849 -77.140536)
			(xy 393.894692 -77.130406) (xy 393.950426 -77.128369) (xy 394.005863 -77.134469) (xy 394.05982 -77.148575)
			(xy 394.111149 -77.170387) (xy 394.158755 -77.199441) (xy 394.201623 -77.235116) (xy 394.23884 -77.276653)
			(xy 394.269613 -77.323166) (xy 394.293285 -77.373663) (xy 394.309353 -77.42707) (xy 394.317473 -77.482246)
			(xy 394.317982 -77.510132) (xy 394.317473 -77.538018) (xy 394.309353 -77.593194) (xy 394.293285 -77.646601)
			(xy 394.269613 -77.697098) (xy 394.23884 -77.743611) (xy 394.201623 -77.785148) (xy 394.158755 -77.820823)
			(xy 394.111149 -77.849877) (xy 394.05982 -77.871689) (xy 394.005863 -77.885795) (xy 393.950426 -77.891895)
			(xy 393.894692 -77.889858) (xy 393.839849 -77.879728) (xy 393.787065 -77.861721) (xy 393.737465 -77.83622)
			(xy 393.692107 -77.803769) (xy 393.651958 -77.76506) (xy 393.617872 -77.720917) (xy 393.590576 -77.672282)
			(xy 393.570653 -77.620191) (xy 393.558527 -77.565754) (xy 393.554456 -77.510132) (xy 392.744443 -77.510132)
			(xy 392.743943 -77.53751) (xy 392.735823 -77.592686) (xy 392.719755 -77.646093) (xy 392.696083 -77.69659)
			(xy 392.66531 -77.743103) (xy 392.628093 -77.78464) (xy 392.585225 -77.820315) (xy 392.537619 -77.849369)
			(xy 392.48629 -77.871181) (xy 392.432333 -77.885287) (xy 392.376896 -77.891387) (xy 392.321162 -77.88935)
			(xy 392.266319 -77.87922) (xy 392.213535 -77.861213) (xy 392.163935 -77.835712) (xy 392.118577 -77.803261)
			(xy 392.078428 -77.764552) (xy 392.044342 -77.720409) (xy 392.017046 -77.671774) (xy 391.997123 -77.619683)
			(xy 391.984997 -77.565246) (xy 391.980926 -77.509624) (xy 388.759719 -77.509624) (xy 388.773482 -80.356202)
			(xy 392.196064 -80.356202) (xy 392.200135 -80.30058) (xy 392.212261 -80.246143) (xy 392.232184 -80.194052)
			(xy 392.25948 -80.145417) (xy 392.293566 -80.101274) (xy 392.333715 -80.062565) (xy 392.379073 -80.030114)
			(xy 392.428673 -80.004613) (xy 392.481457 -79.986606) (xy 392.5363 -79.976476) (xy 392.592034 -79.974439)
			(xy 392.647471 -79.980539) (xy 392.701428 -79.994645) (xy 392.752757 -80.016457) (xy 392.800363 -80.045511)
			(xy 392.843231 -80.081186) (xy 392.880448 -80.122723) (xy 392.911221 -80.169236) (xy 392.934893 -80.219733)
			(xy 392.950961 -80.27314) (xy 392.959081 -80.328316) (xy 392.95959 -80.356202) (xy 394.436344 -80.356202)
			(xy 394.440415 -80.30058) (xy 394.452541 -80.246143) (xy 394.472464 -80.194052) (xy 394.49976 -80.145417)
			(xy 394.533846 -80.101274) (xy 394.573995 -80.062565) (xy 394.619353 -80.030114) (xy 394.668953 -80.004613)
			(xy 394.721737 -79.986606) (xy 394.77658 -79.976476) (xy 394.832314 -79.974439) (xy 394.887751 -79.980539)
			(xy 394.941708 -79.994645) (xy 394.993037 -80.016457) (xy 395.040643 -80.045511) (xy 395.083511 -80.081186)
			(xy 395.120728 -80.122723) (xy 395.151501 -80.169236) (xy 395.175173 -80.219733) (xy 395.191241 -80.27314)
			(xy 395.199361 -80.328316) (xy 395.19987 -80.356202) (xy 396.84274 -80.356202) (xy 396.846811 -80.30058)
			(xy 396.858937 -80.246143) (xy 396.87886 -80.194052) (xy 396.906156 -80.145417) (xy 396.940242 -80.101274)
			(xy 396.980391 -80.062565) (xy 397.025749 -80.030114) (xy 397.075349 -80.004613) (xy 397.128133 -79.986606)
			(xy 397.182976 -79.976476) (xy 397.23871 -79.974439) (xy 397.294147 -79.980539) (xy 397.348104 -79.994645)
			(xy 397.399433 -80.016457) (xy 397.447039 -80.045511) (xy 397.489907 -80.081186) (xy 397.527124 -80.122723)
			(xy 397.557897 -80.169236) (xy 397.581569 -80.219733) (xy 397.597637 -80.27314) (xy 397.605757 -80.328316)
			(xy 397.606266 -80.356202) (xy 397.605757 -80.384088) (xy 397.597637 -80.439264) (xy 397.581569 -80.492671)
			(xy 397.557897 -80.543168) (xy 397.527124 -80.589681) (xy 397.489907 -80.631218) (xy 397.447039 -80.666893)
			(xy 397.399433 -80.695947) (xy 397.348104 -80.717759) (xy 397.294147 -80.731865) (xy 397.23871 -80.737965)
			(xy 397.182976 -80.735928) (xy 397.128133 -80.725798) (xy 397.075349 -80.707791) (xy 397.025749 -80.68229)
			(xy 396.980391 -80.649839) (xy 396.940242 -80.61113) (xy 396.906156 -80.566987) (xy 396.87886 -80.518352)
			(xy 396.858937 -80.466261) (xy 396.846811 -80.411824) (xy 396.84274 -80.356202) (xy 395.19987 -80.356202)
			(xy 395.199361 -80.384088) (xy 395.191241 -80.439264) (xy 395.175173 -80.492671) (xy 395.151501 -80.543168)
			(xy 395.120728 -80.589681) (xy 395.083511 -80.631218) (xy 395.040643 -80.666893) (xy 394.993037 -80.695947)
			(xy 394.941708 -80.717759) (xy 394.887751 -80.731865) (xy 394.832314 -80.737965) (xy 394.77658 -80.735928)
			(xy 394.721737 -80.725798) (xy 394.668953 -80.707791) (xy 394.619353 -80.68229) (xy 394.573995 -80.649839)
			(xy 394.533846 -80.61113) (xy 394.49976 -80.566987) (xy 394.472464 -80.518352) (xy 394.452541 -80.466261)
			(xy 394.440415 -80.411824) (xy 394.436344 -80.356202) (xy 392.95959 -80.356202) (xy 392.959081 -80.384088)
			(xy 392.950961 -80.439264) (xy 392.934893 -80.492671) (xy 392.911221 -80.543168) (xy 392.880448 -80.589681)
			(xy 392.843231 -80.631218) (xy 392.800363 -80.666893) (xy 392.752757 -80.695947) (xy 392.701428 -80.717759)
			(xy 392.647471 -80.731865) (xy 392.592034 -80.737965) (xy 392.5363 -80.735928) (xy 392.481457 -80.725798)
			(xy 392.428673 -80.707791) (xy 392.379073 -80.68229) (xy 392.333715 -80.649839) (xy 392.293566 -80.61113)
			(xy 392.25948 -80.566987) (xy 392.232184 -80.518352) (xy 392.212261 -80.466261) (xy 392.200135 -80.411824)
			(xy 392.196064 -80.356202) (xy 388.773482 -80.356202) (xy 388.779008 -81.499202) (xy 390.559542 -81.499202)
			(xy 390.563613 -81.44358) (xy 390.575739 -81.389143) (xy 390.595662 -81.337052) (xy 390.622958 -81.288417)
			(xy 390.657044 -81.244274) (xy 390.697193 -81.205565) (xy 390.742551 -81.173114) (xy 390.792151 -81.147613)
			(xy 390.844935 -81.129606) (xy 390.899778 -81.119476) (xy 390.955512 -81.117439) (xy 391.010949 -81.123539)
			(xy 391.064906 -81.137645) (xy 391.116235 -81.159457) (xy 391.163841 -81.188511) (xy 391.206709 -81.224186)
			(xy 391.243926 -81.265723) (xy 391.274699 -81.312236) (xy 391.298371 -81.362733) (xy 391.314439 -81.41614)
			(xy 391.322559 -81.471316) (xy 391.323068 -81.499202) (xy 391.322559 -81.527088) (xy 391.314439 -81.582264)
			(xy 391.298371 -81.635671) (xy 391.274699 -81.686168) (xy 391.243926 -81.732681) (xy 391.206709 -81.774218)
			(xy 391.163841 -81.809893) (xy 391.116235 -81.838947) (xy 391.064906 -81.860759) (xy 391.010949 -81.874865)
			(xy 390.955512 -81.880965) (xy 390.899778 -81.878928) (xy 390.844935 -81.868798) (xy 390.792151 -81.850791)
			(xy 390.742551 -81.82529) (xy 390.697193 -81.792839) (xy 390.657044 -81.75413) (xy 390.622958 -81.709987)
			(xy 390.595662 -81.661352) (xy 390.575739 -81.609261) (xy 390.563613 -81.554824) (xy 390.559542 -81.499202)
			(xy 388.779008 -81.499202) (xy 388.784535 -82.642202) (xy 392.209526 -82.642202) (xy 392.213597 -82.58658)
			(xy 392.225723 -82.532143) (xy 392.245646 -82.480052) (xy 392.272942 -82.431417) (xy 392.307028 -82.387274)
			(xy 392.347177 -82.348565) (xy 392.392535 -82.316114) (xy 392.442135 -82.290613) (xy 392.494919 -82.272606)
			(xy 392.549762 -82.262476) (xy 392.605496 -82.260439) (xy 392.660933 -82.266539) (xy 392.71489 -82.280645)
			(xy 392.766219 -82.302457) (xy 392.813825 -82.331511) (xy 392.856693 -82.367186) (xy 392.89391 -82.408723)
			(xy 392.924683 -82.455236) (xy 392.948355 -82.505733) (xy 392.964423 -82.55914) (xy 392.972543 -82.614316)
			(xy 392.973052 -82.642202) (xy 396.84274 -82.642202) (xy 396.846811 -82.58658) (xy 396.858937 -82.532143)
			(xy 396.87886 -82.480052) (xy 396.906156 -82.431417) (xy 396.940242 -82.387274) (xy 396.980391 -82.348565)
			(xy 397.025749 -82.316114) (xy 397.075349 -82.290613) (xy 397.128133 -82.272606) (xy 397.182976 -82.262476)
			(xy 397.23871 -82.260439) (xy 397.294147 -82.266539) (xy 397.348104 -82.280645) (xy 397.399433 -82.302457)
			(xy 397.447039 -82.331511) (xy 397.489907 -82.367186) (xy 397.527124 -82.408723) (xy 397.557897 -82.455236)
			(xy 397.581569 -82.505733) (xy 397.597637 -82.55914) (xy 397.605757 -82.614316) (xy 397.606266 -82.642202)
			(xy 397.605757 -82.670088) (xy 397.597637 -82.725264) (xy 397.581569 -82.778671) (xy 397.557897 -82.829168)
			(xy 397.527124 -82.875681) (xy 397.489907 -82.917218) (xy 397.447039 -82.952893) (xy 397.399433 -82.981947)
			(xy 397.348104 -83.003759) (xy 397.294147 -83.017865) (xy 397.23871 -83.023965) (xy 397.182976 -83.021928)
			(xy 397.128133 -83.011798) (xy 397.075349 -82.993791) (xy 397.025749 -82.96829) (xy 396.980391 -82.935839)
			(xy 396.940242 -82.89713) (xy 396.906156 -82.852987) (xy 396.87886 -82.804352) (xy 396.858937 -82.752261)
			(xy 396.846811 -82.697824) (xy 396.84274 -82.642202) (xy 392.973052 -82.642202) (xy 392.972543 -82.670088)
			(xy 392.964423 -82.725264) (xy 392.948355 -82.778671) (xy 392.924683 -82.829168) (xy 392.89391 -82.875681)
			(xy 392.856693 -82.917218) (xy 392.813825 -82.952893) (xy 392.766219 -82.981947) (xy 392.71489 -83.003759)
			(xy 392.660933 -83.017865) (xy 392.605496 -83.023965) (xy 392.549762 -83.021928) (xy 392.494919 -83.011798)
			(xy 392.442135 -82.993791) (xy 392.392535 -82.96829) (xy 392.347177 -82.935839) (xy 392.307028 -82.89713)
			(xy 392.272942 -82.852987) (xy 392.245646 -82.804352) (xy 392.225723 -82.752261) (xy 392.213597 -82.697824)
			(xy 392.209526 -82.642202) (xy 388.784535 -82.642202) (xy 388.786959 -83.143598) (xy 394.215618 -83.143598)
			(xy 394.219689 -83.087976) (xy 394.231815 -83.033539) (xy 394.251738 -82.981448) (xy 394.279034 -82.932813)
			(xy 394.31312 -82.88867) (xy 394.353269 -82.849961) (xy 394.398627 -82.81751) (xy 394.448227 -82.792009)
			(xy 394.501011 -82.774002) (xy 394.555854 -82.763872) (xy 394.611588 -82.761835) (xy 394.667025 -82.767935)
			(xy 394.720982 -82.782041) (xy 394.772311 -82.803853) (xy 394.819917 -82.832907) (xy 394.862785 -82.868582)
			(xy 394.900002 -82.910119) (xy 394.930775 -82.956632) (xy 394.954447 -83.007129) (xy 394.970515 -83.060536)
			(xy 394.978635 -83.115712) (xy 394.979144 -83.143598) (xy 394.978635 -83.171484) (xy 394.970515 -83.22666)
			(xy 394.954447 -83.280067) (xy 394.930775 -83.330564) (xy 394.900002 -83.377077) (xy 394.862785 -83.418614)
			(xy 394.819917 -83.454289) (xy 394.772311 -83.483343) (xy 394.720982 -83.505155) (xy 394.667025 -83.519261)
			(xy 394.611588 -83.525361) (xy 394.555854 -83.523324) (xy 394.501011 -83.513194) (xy 394.448227 -83.495187)
			(xy 394.398627 -83.469686) (xy 394.353269 -83.437235) (xy 394.31312 -83.398526) (xy 394.279034 -83.354383)
			(xy 394.251738 -83.305748) (xy 394.231815 -83.253657) (xy 394.219689 -83.19922) (xy 394.215618 -83.143598)
			(xy 388.786959 -83.143598) (xy 388.790061 -83.785202) (xy 391.48842 -83.785202) (xy 391.492491 -83.72958)
			(xy 391.504617 -83.675143) (xy 391.52454 -83.623052) (xy 391.551836 -83.574417) (xy 391.585922 -83.530274)
			(xy 391.626071 -83.491565) (xy 391.671429 -83.459114) (xy 391.721029 -83.433613) (xy 391.773813 -83.415606)
			(xy 391.828656 -83.405476) (xy 391.88439 -83.403439) (xy 391.939827 -83.409539) (xy 391.993784 -83.423645)
			(xy 392.045113 -83.445457) (xy 392.092719 -83.474511) (xy 392.135587 -83.510186) (xy 392.172804 -83.551723)
			(xy 392.203577 -83.598236) (xy 392.227249 -83.648733) (xy 392.243317 -83.70214) (xy 392.251437 -83.757316)
			(xy 392.251946 -83.785202) (xy 396.84274 -83.785202) (xy 396.846811 -83.72958) (xy 396.858937 -83.675143)
			(xy 396.87886 -83.623052) (xy 396.906156 -83.574417) (xy 396.940242 -83.530274) (xy 396.980391 -83.491565)
			(xy 397.025749 -83.459114) (xy 397.075349 -83.433613) (xy 397.128133 -83.415606) (xy 397.182976 -83.405476)
			(xy 397.23871 -83.403439) (xy 397.294147 -83.409539) (xy 397.348104 -83.423645) (xy 397.399433 -83.445457)
			(xy 397.447039 -83.474511) (xy 397.489907 -83.510186) (xy 397.527124 -83.551723) (xy 397.557897 -83.598236)
			(xy 397.581569 -83.648733) (xy 397.597637 -83.70214) (xy 397.605757 -83.757316) (xy 397.606266 -83.785202)
			(xy 397.605757 -83.813088) (xy 397.597637 -83.868264) (xy 397.581569 -83.921671) (xy 397.557897 -83.972168)
			(xy 397.527124 -84.018681) (xy 397.489907 -84.060218) (xy 397.447039 -84.095893) (xy 397.399433 -84.124947)
			(xy 397.348104 -84.146759) (xy 397.294147 -84.160865) (xy 397.23871 -84.166965) (xy 397.182976 -84.164928)
			(xy 397.128133 -84.154798) (xy 397.075349 -84.136791) (xy 397.025749 -84.11129) (xy 396.980391 -84.078839)
			(xy 396.940242 -84.04013) (xy 396.906156 -83.995987) (xy 396.87886 -83.947352) (xy 396.858937 -83.895261)
			(xy 396.846811 -83.840824) (xy 396.84274 -83.785202) (xy 392.251946 -83.785202) (xy 392.251437 -83.813088)
			(xy 392.243317 -83.868264) (xy 392.227249 -83.921671) (xy 392.203577 -83.972168) (xy 392.172804 -84.018681)
			(xy 392.135587 -84.060218) (xy 392.092719 -84.095893) (xy 392.045113 -84.124947) (xy 391.993784 -84.146759)
			(xy 391.939827 -84.160865) (xy 391.88439 -84.166965) (xy 391.828656 -84.164928) (xy 391.773813 -84.154798)
			(xy 391.721029 -84.136791) (xy 391.671429 -84.11129) (xy 391.626071 -84.078839) (xy 391.585922 -84.04013)
			(xy 391.551836 -83.995987) (xy 391.52454 -83.947352) (xy 391.504617 -83.895261) (xy 391.492491 -83.840824)
			(xy 391.48842 -83.785202) (xy 388.790061 -83.785202) (xy 388.792437 -84.276692) (xy 394.311122 -84.276692)
			(xy 394.315193 -84.22107) (xy 394.327319 -84.166633) (xy 394.347242 -84.114542) (xy 394.374538 -84.065907)
			(xy 394.408624 -84.021764) (xy 394.448773 -83.983055) (xy 394.494131 -83.950604) (xy 394.543731 -83.925103)
			(xy 394.596515 -83.907096) (xy 394.651358 -83.896966) (xy 394.707092 -83.894929) (xy 394.762529 -83.901029)
			(xy 394.816486 -83.915135) (xy 394.867815 -83.936947) (xy 394.915421 -83.966001) (xy 394.958289 -84.001676)
			(xy 394.995506 -84.043213) (xy 395.026279 -84.089726) (xy 395.049951 -84.140223) (xy 395.066019 -84.19363)
			(xy 395.074139 -84.248806) (xy 395.074648 -84.276692) (xy 395.074139 -84.304578) (xy 395.066019 -84.359754)
			(xy 395.049951 -84.413161) (xy 395.026279 -84.463658) (xy 394.995506 -84.510171) (xy 394.958289 -84.551708)
			(xy 394.915421 -84.587383) (xy 394.867815 -84.616437) (xy 394.816486 -84.638249) (xy 394.762529 -84.652355)
			(xy 394.707092 -84.658455) (xy 394.651358 -84.656418) (xy 394.596515 -84.646288) (xy 394.543731 -84.628281)
			(xy 394.494131 -84.60278) (xy 394.448773 -84.570329) (xy 394.408624 -84.53162) (xy 394.374538 -84.487477)
			(xy 394.347242 -84.438842) (xy 394.327319 -84.386751) (xy 394.315193 -84.332314) (xy 394.311122 -84.276692)
			(xy 388.792437 -84.276692) (xy 388.795587 -84.928202) (xy 392.262866 -84.928202) (xy 392.266937 -84.87258)
			(xy 392.279063 -84.818143) (xy 392.298986 -84.766052) (xy 392.326282 -84.717417) (xy 392.360368 -84.673274)
			(xy 392.400517 -84.634565) (xy 392.445875 -84.602114) (xy 392.495475 -84.576613) (xy 392.548259 -84.558606)
			(xy 392.603102 -84.548476) (xy 392.658836 -84.546439) (xy 392.714273 -84.552539) (xy 392.76823 -84.566645)
			(xy 392.819559 -84.588457) (xy 392.867165 -84.617511) (xy 392.910033 -84.653186) (xy 392.94725 -84.694723)
			(xy 392.978023 -84.741236) (xy 393.001695 -84.791733) (xy 393.017763 -84.84514) (xy 393.025883 -84.900316)
			(xy 393.026392 -84.928202) (xy 396.84274 -84.928202) (xy 396.846811 -84.87258) (xy 396.858937 -84.818143)
			(xy 396.87886 -84.766052) (xy 396.906156 -84.717417) (xy 396.940242 -84.673274) (xy 396.980391 -84.634565)
			(xy 397.025749 -84.602114) (xy 397.075349 -84.576613) (xy 397.128133 -84.558606) (xy 397.182976 -84.548476)
			(xy 397.23871 -84.546439) (xy 397.294147 -84.552539) (xy 397.348104 -84.566645) (xy 397.399433 -84.588457)
			(xy 397.447039 -84.617511) (xy 397.489907 -84.653186) (xy 397.527124 -84.694723) (xy 397.544804 -84.721446)
			(xy 399.610832 -84.721446) (xy 399.614903 -84.665824) (xy 399.627029 -84.611387) (xy 399.646952 -84.559296)
			(xy 399.674248 -84.510661) (xy 399.708334 -84.466518) (xy 399.748483 -84.427809) (xy 399.793841 -84.395358)
			(xy 399.843441 -84.369857) (xy 399.896225 -84.35185) (xy 399.951068 -84.34172) (xy 400.006802 -84.339683)
			(xy 400.062239 -84.345783) (xy 400.116196 -84.359889) (xy 400.167525 -84.381701) (xy 400.215131 -84.410755)
			(xy 400.257999 -84.44643) (xy 400.295216 -84.487967) (xy 400.325989 -84.53448) (xy 400.349661 -84.584977)
			(xy 400.365729 -84.638384) (xy 400.373849 -84.69356) (xy 400.374358 -84.721446) (xy 400.373849 -84.749332)
			(xy 400.365729 -84.804508) (xy 400.349661 -84.857915) (xy 400.325989 -84.908412) (xy 400.295216 -84.954925)
			(xy 400.257999 -84.996462) (xy 400.215131 -85.032137) (xy 400.167525 -85.061191) (xy 400.116196 -85.083003)
			(xy 400.062239 -85.097109) (xy 400.006802 -85.103209) (xy 399.951068 -85.101172) (xy 399.896225 -85.091042)
			(xy 399.843441 -85.073035) (xy 399.793841 -85.047534) (xy 399.748483 -85.015083) (xy 399.708334 -84.976374)
			(xy 399.674248 -84.932231) (xy 399.646952 -84.883596) (xy 399.627029 -84.831505) (xy 399.614903 -84.777068)
			(xy 399.610832 -84.721446) (xy 397.544804 -84.721446) (xy 397.557897 -84.741236) (xy 397.581569 -84.791733)
			(xy 397.597637 -84.84514) (xy 397.605757 -84.900316) (xy 397.606266 -84.928202) (xy 397.605757 -84.956088)
			(xy 397.597637 -85.011264) (xy 397.581569 -85.064671) (xy 397.557897 -85.115168) (xy 397.527124 -85.161681)
			(xy 397.489907 -85.203218) (xy 397.447039 -85.238893) (xy 397.399433 -85.267947) (xy 397.348104 -85.289759)
			(xy 397.294147 -85.303865) (xy 397.23871 -85.309965) (xy 397.182976 -85.307928) (xy 397.128133 -85.297798)
			(xy 397.075349 -85.279791) (xy 397.025749 -85.25429) (xy 396.980391 -85.221839) (xy 396.940242 -85.18313)
			(xy 396.906156 -85.138987) (xy 396.87886 -85.090352) (xy 396.858937 -85.038261) (xy 396.846811 -84.983824)
			(xy 396.84274 -84.928202) (xy 393.026392 -84.928202) (xy 393.025883 -84.956088) (xy 393.017763 -85.011264)
			(xy 393.001695 -85.064671) (xy 392.978023 -85.115168) (xy 392.94725 -85.161681) (xy 392.910033 -85.203218)
			(xy 392.867165 -85.238893) (xy 392.819559 -85.267947) (xy 392.76823 -85.289759) (xy 392.714273 -85.303865)
			(xy 392.658836 -85.309965) (xy 392.603102 -85.307928) (xy 392.548259 -85.297798) (xy 392.495475 -85.279791)
			(xy 392.445875 -85.25429) (xy 392.400517 -85.221839) (xy 392.360368 -85.18313) (xy 392.326282 -85.138987)
			(xy 392.298986 -85.090352) (xy 392.279063 -85.038261) (xy 392.266937 -84.983824) (xy 392.262866 -84.928202)
			(xy 388.795587 -84.928202) (xy 388.798336 -85.496654) (xy 394.23162 -85.496654) (xy 394.235691 -85.441032)
			(xy 394.247817 -85.386595) (xy 394.26774 -85.334504) (xy 394.295036 -85.285869) (xy 394.329122 -85.241726)
			(xy 394.369271 -85.203017) (xy 394.414629 -85.170566) (xy 394.464229 -85.145065) (xy 394.517013 -85.127058)
			(xy 394.571856 -85.116928) (xy 394.62759 -85.114891) (xy 394.683027 -85.120991) (xy 394.736984 -85.135097)
			(xy 394.788313 -85.156909) (xy 394.835919 -85.185963) (xy 394.878787 -85.221638) (xy 394.916004 -85.263175)
			(xy 394.946777 -85.309688) (xy 394.970449 -85.360185) (xy 394.986517 -85.413592) (xy 394.994637 -85.468768)
			(xy 394.995146 -85.496654) (xy 394.994637 -85.52454) (xy 394.986517 -85.579716) (xy 394.970449 -85.633123)
			(xy 394.946777 -85.68362) (xy 394.916004 -85.730133) (xy 394.878787 -85.77167) (xy 394.835919 -85.807345)
			(xy 394.788313 -85.836399) (xy 394.736984 -85.858211) (xy 394.683027 -85.872317) (xy 394.62759 -85.878417)
			(xy 394.571856 -85.87638) (xy 394.517013 -85.86625) (xy 394.464229 -85.848243) (xy 394.414629 -85.822742)
			(xy 394.369271 -85.790291) (xy 394.329122 -85.751582) (xy 394.295036 -85.707439) (xy 394.26774 -85.658804)
			(xy 394.247817 -85.606713) (xy 394.235691 -85.552276) (xy 394.23162 -85.496654) (xy 388.798336 -85.496654)
			(xy 388.80664 -87.214202) (xy 392.035536 -87.214202) (xy 392.039607 -87.15858) (xy 392.051733 -87.104143)
			(xy 392.071656 -87.052052) (xy 392.098952 -87.003417) (xy 392.133038 -86.959274) (xy 392.173187 -86.920565)
			(xy 392.218545 -86.888114) (xy 392.268145 -86.862613) (xy 392.320929 -86.844606) (xy 392.375772 -86.834476)
			(xy 392.431506 -86.832439) (xy 392.486943 -86.838539) (xy 392.5409 -86.852645) (xy 392.592229 -86.874457)
			(xy 392.639835 -86.903511) (xy 392.682703 -86.939186) (xy 392.71992 -86.980723) (xy 392.750693 -87.027236)
			(xy 392.774365 -87.077733) (xy 392.790433 -87.13114) (xy 392.798553 -87.186316) (xy 392.799062 -87.214202)
			(xy 396.84274 -87.214202) (xy 396.846811 -87.15858) (xy 396.858937 -87.104143) (xy 396.87886 -87.052052)
			(xy 396.906156 -87.003417) (xy 396.940242 -86.959274) (xy 396.980391 -86.920565) (xy 397.025749 -86.888114)
			(xy 397.075349 -86.862613) (xy 397.128133 -86.844606) (xy 397.182976 -86.834476) (xy 397.23871 -86.832439)
			(xy 397.294147 -86.838539) (xy 397.348104 -86.852645) (xy 397.399433 -86.874457) (xy 397.447039 -86.903511)
			(xy 397.489907 -86.939186) (xy 397.527124 -86.980723) (xy 397.557897 -87.027236) (xy 397.581569 -87.077733)
			(xy 397.597637 -87.13114) (xy 397.605757 -87.186316) (xy 397.606266 -87.214202) (xy 397.605757 -87.242088)
			(xy 397.597637 -87.297264) (xy 397.581569 -87.350671) (xy 397.557897 -87.401168) (xy 397.534488 -87.436551)
			(xy 398.811752 -87.436551) (xy 398.811752 -87.382049) (xy 398.819507 -87.328102) (xy 398.834861 -87.275808)
			(xy 398.8575 -87.226231) (xy 398.886964 -87.180379) (xy 398.922652 -87.139188) (xy 398.963839 -87.103494)
			(xy 399.009687 -87.074024) (xy 399.059261 -87.051379) (xy 399.111553 -87.036018) (xy 399.165499 -87.028255)
			(xy 399.19275 -87.027766) (xy 399.219314 -87.028244) (xy 399.271928 -87.035605) (xy 399.323014 -87.050191)
			(xy 399.371583 -87.07172) (xy 399.416698 -87.099777) (xy 399.457486 -87.133819) (xy 399.493159 -87.173188)
			(xy 399.508472 -87.194898) (xy 399.516806 -87.206378) (xy 399.53855 -87.224582) (xy 399.564463 -87.2361)
			(xy 399.592546 -87.24004) (xy 399.620629 -87.2361) (xy 399.646542 -87.224582) (xy 399.668286 -87.206378)
			(xy 399.67662 -87.194898) (xy 399.69188 -87.173054) (xy 399.727531 -87.133451) (xy 399.768349 -87.099197)
			(xy 399.813537 -87.070959) (xy 399.862216 -87.049286) (xy 399.913439 -87.034601) (xy 399.966207 -87.02719)
			(xy 399.99285 -87.02675) (xy 400.020102 -87.027294) (xy 400.074053 -87.035044) (xy 400.126351 -87.050394)
			(xy 400.175932 -87.073031) (xy 400.221786 -87.102495) (xy 400.26298 -87.138184) (xy 400.298675 -87.179374)
			(xy 400.328145 -87.225224) (xy 400.350788 -87.274802) (xy 400.366145 -87.327098) (xy 400.373903 -87.381048)
			(xy 400.373903 -87.435552) (xy 400.366145 -87.489502) (xy 400.350788 -87.541798) (xy 400.328145 -87.591376)
			(xy 400.298675 -87.637226) (xy 400.26298 -87.678416) (xy 400.221786 -87.714105) (xy 400.175932 -87.743569)
			(xy 400.126351 -87.766206) (xy 400.074053 -87.781556) (xy 400.020102 -87.789306) (xy 399.99285 -87.789766)
			(xy 399.966287 -87.789274) (xy 399.913673 -87.781914) (xy 399.862589 -87.767329) (xy 399.81402 -87.745802)
			(xy 399.768905 -87.717748) (xy 399.728117 -87.683709) (xy 399.692442 -87.644343) (xy 399.677128 -87.622634)
			(xy 399.668794 -87.611154) (xy 399.64705 -87.59295) (xy 399.621137 -87.581432) (xy 399.593054 -87.577492)
			(xy 399.564971 -87.581432) (xy 399.539058 -87.59295) (xy 399.517314 -87.611154) (xy 399.50898 -87.622634)
			(xy 399.49373 -87.644485) (xy 399.458076 -87.684086) (xy 399.417256 -87.718339) (xy 399.372066 -87.746576)
			(xy 399.323386 -87.768247) (xy 399.272162 -87.782931) (xy 399.219393 -87.790342) (xy 399.19275 -87.790782)
			(xy 399.165499 -87.790345) (xy 399.111553 -87.782582) (xy 399.059261 -87.767221) (xy 399.009687 -87.744576)
			(xy 398.963839 -87.715106) (xy 398.922652 -87.679412) (xy 398.886964 -87.638221) (xy 398.8575 -87.592369)
			(xy 398.834861 -87.542792) (xy 398.819507 -87.490498) (xy 398.811752 -87.436551) (xy 397.534488 -87.436551)
			(xy 397.527124 -87.447681) (xy 397.489907 -87.489218) (xy 397.447039 -87.524893) (xy 397.399433 -87.553947)
			(xy 397.348104 -87.575759) (xy 397.294147 -87.589865) (xy 397.23871 -87.595965) (xy 397.182976 -87.593928)
			(xy 397.128133 -87.583798) (xy 397.075349 -87.565791) (xy 397.025749 -87.54029) (xy 396.980391 -87.507839)
			(xy 396.940242 -87.46913) (xy 396.906156 -87.424987) (xy 396.87886 -87.376352) (xy 396.858937 -87.324261)
			(xy 396.846811 -87.269824) (xy 396.84274 -87.214202) (xy 392.799062 -87.214202) (xy 392.798553 -87.242088)
			(xy 392.790433 -87.297264) (xy 392.774365 -87.350671) (xy 392.750693 -87.401168) (xy 392.71992 -87.447681)
			(xy 392.682703 -87.489218) (xy 392.639835 -87.524893) (xy 392.592229 -87.553947) (xy 392.5409 -87.575759)
			(xy 392.486943 -87.589865) (xy 392.431506 -87.595965) (xy 392.375772 -87.593928) (xy 392.320929 -87.583798)
			(xy 392.268145 -87.565791) (xy 392.218545 -87.54029) (xy 392.173187 -87.507839) (xy 392.133038 -87.46913)
			(xy 392.098952 -87.424987) (xy 392.071656 -87.376352) (xy 392.051733 -87.324261) (xy 392.039607 -87.269824)
			(xy 392.035536 -87.214202) (xy 388.80664 -87.214202) (xy 388.808487 -87.596218) (xy 394.29893 -87.596218)
			(xy 394.303001 -87.540596) (xy 394.315127 -87.486159) (xy 394.33505 -87.434068) (xy 394.362346 -87.385433)
			(xy 394.396432 -87.34129) (xy 394.436581 -87.302581) (xy 394.481939 -87.27013) (xy 394.531539 -87.244629)
			(xy 394.584323 -87.226622) (xy 394.639166 -87.216492) (xy 394.6949 -87.214455) (xy 394.750337 -87.220555)
			(xy 394.804294 -87.234661) (xy 394.855623 -87.256473) (xy 394.903229 -87.285527) (xy 394.946097 -87.321202)
			(xy 394.983314 -87.362739) (xy 395.014087 -87.409252) (xy 395.037759 -87.459749) (xy 395.053827 -87.513156)
			(xy 395.061947 -87.568332) (xy 395.062456 -87.596218) (xy 395.061947 -87.624104) (xy 395.053827 -87.67928)
			(xy 395.037759 -87.732687) (xy 395.014087 -87.783184) (xy 394.983314 -87.829697) (xy 394.946097 -87.871234)
			(xy 394.903229 -87.906909) (xy 394.855623 -87.935963) (xy 394.804294 -87.957775) (xy 394.750337 -87.971881)
			(xy 394.6949 -87.977981) (xy 394.639166 -87.975944) (xy 394.584323 -87.965814) (xy 394.531539 -87.947807)
			(xy 394.481939 -87.922306) (xy 394.436581 -87.889855) (xy 394.396432 -87.851146) (xy 394.362346 -87.807003)
			(xy 394.33505 -87.758368) (xy 394.315127 -87.706277) (xy 394.303001 -87.65184) (xy 394.29893 -87.596218)
			(xy 388.808487 -87.596218) (xy 388.811454 -88.209882) (xy 393.616432 -88.209882) (xy 393.620503 -88.15426)
			(xy 393.632629 -88.099823) (xy 393.652552 -88.047732) (xy 393.679848 -87.999097) (xy 393.713934 -87.954954)
			(xy 393.754083 -87.916245) (xy 393.799441 -87.883794) (xy 393.849041 -87.858293) (xy 393.901825 -87.840286)
			(xy 393.956668 -87.830156) (xy 394.012402 -87.828119) (xy 394.067839 -87.834219) (xy 394.121796 -87.848325)
			(xy 394.173125 -87.870137) (xy 394.220731 -87.899191) (xy 394.263599 -87.934866) (xy 394.300816 -87.976403)
			(xy 394.331589 -88.022916) (xy 394.355261 -88.073413) (xy 394.371329 -88.12682) (xy 394.379449 -88.181996)
			(xy 394.379958 -88.209882) (xy 394.379449 -88.237768) (xy 394.371329 -88.292944) (xy 394.355261 -88.346351)
			(xy 394.331589 -88.396848) (xy 394.300816 -88.443361) (xy 394.263599 -88.484898) (xy 394.220731 -88.520573)
			(xy 394.173125 -88.549627) (xy 394.121796 -88.571439) (xy 394.067839 -88.585545) (xy 394.012402 -88.591645)
			(xy 393.956668 -88.589608) (xy 393.901825 -88.579478) (xy 393.849041 -88.561471) (xy 393.799441 -88.53597)
			(xy 393.754083 -88.503519) (xy 393.713934 -88.46481) (xy 393.679848 -88.420667) (xy 393.652552 -88.372032)
			(xy 393.632629 -88.319941) (xy 393.620503 -88.265504) (xy 393.616432 -88.209882) (xy 388.811454 -88.209882)
			(xy 388.817693 -89.500202) (xy 392.158218 -89.500202) (xy 392.162289 -89.44458) (xy 392.174415 -89.390143)
			(xy 392.194338 -89.338052) (xy 392.221634 -89.289417) (xy 392.25572 -89.245274) (xy 392.295869 -89.206565)
			(xy 392.341227 -89.174114) (xy 392.390827 -89.148613) (xy 392.443611 -89.130606) (xy 392.498454 -89.120476)
			(xy 392.554188 -89.118439) (xy 392.609625 -89.124539) (xy 392.663582 -89.138645) (xy 392.714911 -89.160457)
			(xy 392.762517 -89.189511) (xy 392.805385 -89.225186) (xy 392.842602 -89.266723) (xy 392.873375 -89.313236)
			(xy 392.897047 -89.363733) (xy 392.913115 -89.41714) (xy 392.921235 -89.472316) (xy 392.921744 -89.500202)
			(xy 396.84274 -89.500202) (xy 396.846811 -89.44458) (xy 396.858937 -89.390143) (xy 396.87886 -89.338052)
			(xy 396.906156 -89.289417) (xy 396.940242 -89.245274) (xy 396.980391 -89.206565) (xy 397.025749 -89.174114)
			(xy 397.075349 -89.148613) (xy 397.128133 -89.130606) (xy 397.182976 -89.120476) (xy 397.23871 -89.118439)
			(xy 397.294147 -89.124539) (xy 397.348104 -89.138645) (xy 397.399433 -89.160457) (xy 397.447039 -89.189511)
			(xy 397.489907 -89.225186) (xy 397.527124 -89.266723) (xy 397.557897 -89.313236) (xy 397.581569 -89.363733)
			(xy 397.597637 -89.41714) (xy 397.605757 -89.472316) (xy 397.606266 -89.500202) (xy 397.605757 -89.528088)
			(xy 397.597637 -89.583264) (xy 397.581569 -89.636671) (xy 397.557897 -89.687168) (xy 397.527124 -89.733681)
			(xy 397.489907 -89.775218) (xy 397.447039 -89.810893) (xy 397.399433 -89.839947) (xy 397.348104 -89.861759)
			(xy 397.294147 -89.875865) (xy 397.23871 -89.881965) (xy 397.182976 -89.879928) (xy 397.128133 -89.869798)
			(xy 397.075349 -89.851791) (xy 397.025749 -89.82629) (xy 396.980391 -89.793839) (xy 396.940242 -89.75513)
			(xy 396.906156 -89.710987) (xy 396.87886 -89.662352) (xy 396.858937 -89.610261) (xy 396.846811 -89.555824)
			(xy 396.84274 -89.500202) (xy 392.921744 -89.500202) (xy 392.921235 -89.528088) (xy 392.913115 -89.583264)
			(xy 392.897047 -89.636671) (xy 392.873375 -89.687168) (xy 392.842602 -89.733681) (xy 392.805385 -89.775218)
			(xy 392.762517 -89.810893) (xy 392.714911 -89.839947) (xy 392.663582 -89.861759) (xy 392.609625 -89.875865)
			(xy 392.554188 -89.881965) (xy 392.498454 -89.879928) (xy 392.443611 -89.869798) (xy 392.390827 -89.851791)
			(xy 392.341227 -89.82629) (xy 392.295869 -89.793839) (xy 392.25572 -89.75513) (xy 392.221634 -89.710987)
			(xy 392.194338 -89.662352) (xy 392.174415 -89.610261) (xy 392.162289 -89.555824) (xy 392.158218 -89.500202)
			(xy 388.817693 -89.500202) (xy 388.820382 -90.056462) (xy 390.303764 -90.056462) (xy 390.307835 -90.00084)
			(xy 390.319961 -89.946403) (xy 390.339884 -89.894312) (xy 390.36718 -89.845677) (xy 390.401266 -89.801534)
			(xy 390.441415 -89.762825) (xy 390.486773 -89.730374) (xy 390.536373 -89.704873) (xy 390.589157 -89.686866)
			(xy 390.644 -89.676736) (xy 390.699734 -89.674699) (xy 390.755171 -89.680799) (xy 390.809128 -89.694905)
			(xy 390.860457 -89.716717) (xy 390.908063 -89.745771) (xy 390.950931 -89.781446) (xy 390.988148 -89.822983)
			(xy 391.018921 -89.869496) (xy 391.042593 -89.919993) (xy 391.058661 -89.9734) (xy 391.066781 -90.028576)
			(xy 391.06729 -90.056462) (xy 391.066781 -90.084348) (xy 391.058661 -90.139524) (xy 391.042593 -90.192931)
			(xy 391.018921 -90.243428) (xy 390.988148 -90.289941) (xy 390.950931 -90.331478) (xy 390.908063 -90.367153)
			(xy 390.860457 -90.396207) (xy 390.809128 -90.418019) (xy 390.755171 -90.432125) (xy 390.699734 -90.438225)
			(xy 390.644 -90.436188) (xy 390.589157 -90.426058) (xy 390.536373 -90.408051) (xy 390.486773 -90.38255)
			(xy 390.441415 -90.350099) (xy 390.401266 -90.31139) (xy 390.36718 -90.267247) (xy 390.339884 -90.218612)
			(xy 390.319961 -90.166521) (xy 390.307835 -90.112084) (xy 390.303764 -90.056462) (xy 388.820382 -90.056462)
			(xy 388.891526 -104.770936) (xy 388.891526 -104.771952) (xy 389.039862 -111.735362) (xy 389.040116 -111.75619)
			(xy 389.040116 -111.757714) (xy 389.039608 -111.789464) (xy 389.039608 -111.791242) (xy 389.038084 -111.812578)
			(xy 389.038084 -111.812832) (xy 388.933944 -113.536984) (xy 388.933944 -113.540286) (xy 388.939532 -114.718592)
			(xy 388.988808 -124.865384) (xy 389.04164 -135.811768) (xy 389.042402 -135.965438) (xy 389.042402 -135.967978)
			(xy 389.042656 -135.97255) (xy 389.042402 -135.976614) (xy 389.042656 -136.014206) (xy 389.042656 -136.01446)
			(xy 389.042656 -136.015476) (xy 389.042656 -136.018016) (xy 389.0391 -136.053576) (xy 389.0391 -136.054084)
			(xy 389.03783 -136.068054) (xy 389.029448 -136.152128) (xy 389.029194 -136.157716) (xy 389.031988 -136.354566)
			(xy 389.031988 -136.36879) (xy 389.03163 -136.405828) (xy 389.026034 -136.479694) (xy 389.020812 -136.516364)
			(xy 389.010906 -136.572244) (xy 388.968488 -136.774682) (xy 388.967726 -136.78027) (xy 388.912608 -137.338562)
			(xy 388.66191 -139.879832) (xy 388.623302 -140.271754) (xy 388.574026 -140.772388) (xy 388.573772 -140.777976)
			(xy 388.581138 -140.80363) (xy 388.582154 -140.805154) (xy 388.584186 -140.807948) (xy 388.585202 -140.809472)
			(xy 388.587488 -140.812774) (xy 388.603379 -140.836772) (xy 388.628533 -140.88854) (xy 388.645622 -140.9435)
			(xy 388.654258 -141.000404) (xy 388.654798 -141.029182) (xy 388.654798 -141.029436) (xy 388.654354 -141.055448)
			(xy 388.64728 -141.106988) (xy 388.633267 -141.157089) (xy 388.612576 -141.204821) (xy 388.585591 -141.249298)
			(xy 388.552812 -141.289696) (xy 388.534148 -141.30782) (xy 388.533386 -141.308582) (xy 388.527789 -141.314335)
			(xy 388.52014 -141.328434) (xy 388.5184 -141.336268) (xy 388.500874 -141.515592) (xy 388.413498 -142.402052)
			(xy 388.413222 -142.411369) (xy 388.418573 -142.429208) (xy 388.423912 -142.43685) (xy 388.43077 -142.443708)
			(xy 388.434834 -142.447264) (xy 388.457394 -142.465463) (xy 388.497274 -142.507521) (xy 388.530339 -142.555125)
			(xy 388.555827 -142.607179) (xy 388.573154 -142.662489) (xy 388.581921 -142.719782) (xy 388.582408 -142.748762)
			(xy 388.581949 -142.77528) (xy 388.5746 -142.827806) (xy 388.560051 -142.878808) (xy 388.538584 -142.927307)
			(xy 388.510611 -142.972367) (xy 388.47667 -143.013122) (xy 388.437415 -143.048787) (xy 388.393602 -143.078675)
			(xy 388.370064 -143.0909) (xy 388.36981 -143.0909) (xy 388.364022 -143.093916) (xy 388.354117 -143.102405)
			(xy 388.350252 -143.107664) (xy 388.346696 -143.112998) (xy 388.344664 -143.118078) (xy 388.341616 -143.131032)
			(xy 388.142988 -145.146268) (xy 388.136384 -145.213832) (xy 388.13613 -145.22196) (xy 389.32104 -164.701474)
			(xy 389.590534 -169.132758) (xy 389.672322 -170.478704) (xy 390.400794 -182.450994) (xy 390.402101 -182.465071)
			(xy 390.411463 -182.491735) (xy 390.427775 -182.514812) (xy 390.449788 -182.532534) (xy 390.475815 -182.543544)
			(xy 390.503863 -182.546998) (xy 390.517888 -182.545228) (xy 391.539222 -182.386478) (xy 391.542524 -182.385716)
			(xy 391.543032 -182.385716) (xy 391.553796 -182.382586) (xy 391.571344 -182.36868) (xy 391.581318 -182.348635)
			(xy 391.582148 -182.337456) (xy 391.38098 -176.69383) (xy 391.18921 -171.312586) (xy 391.18921 -171.312332)
			(xy 390.999218 -165.979094) (xy 390.99871 -165.96614) (xy 390.993122 -165.808914) (xy 390.993122 -165.80866)
			(xy 389.817864 -147.54606) (xy 389.816915 -147.530266) (xy 389.815899 -147.498637) (xy 389.815832 -147.482814)
			(xy 389.815832 -147.481798) (xy 389.816086 -147.449794) (xy 389.816086 -147.448016) (xy 389.816848 -147.433792)
			(xy 389.816848 -147.433538) (xy 389.823452 -147.299426) (xy 389.832088 -147.12188) (xy 389.832088 -147.115784)
			(xy 389.81634 -146.882358) (xy 389.816086 -146.877786) (xy 389.816086 -146.877532) (xy 389.814308 -146.850354)
			(xy 389.814308 -146.848322) (xy 389.814308 -146.814794) (xy 389.821928 -117.287294) (xy 389.822182 -116.33073)
			(xy 389.822182 -116.330476) (xy 389.822182 -116.32946) (xy 389.822182 -116.325142) (xy 389.823198 -116.320316)
			(xy 389.843264 -116.22532) (xy 389.843264 -116.224812) (xy 389.843518 -116.223796) (xy 390.121394 -114.90706)
			(xy 390.12368 -114.896646) (xy 390.12368 -114.896392) (xy 390.147556 -114.783362) (xy 390.15924 -114.728244)
			(xy 390.160256 -114.723418) (xy 390.16051 -114.722148) (xy 390.161272 -114.718846) (xy 390.258046 -114.574066)
			(xy 390.2583 -114.573812) (xy 390.2583 -114.573558) (xy 390.25957 -114.57178) (xy 390.261094 -114.56924)
			(xy 390.261348 -114.568986) (xy 390.268206 -114.558572) (xy 391.813288 -112.248442) (xy 391.813288 -112.247934)
			(xy 391.819892 -112.238282) (xy 391.820146 -112.238028) (xy 391.86993 -112.16386) (xy 391.87374 -112.16005)
			(xy 391.931398 -112.103154) (xy 391.931652 -112.1029) (xy 391.94232 -112.092232) (xy 392.664442 -111.380778)
			(xy 392.935968 -111.112808) (xy 392.938704 -111.1096) (xy 392.943173 -111.102449) (xy 392.944858 -111.098584)
			(xy 393.738862 -108.578904) (xy 395.20876 -103.868728) (xy 395.319758 -103.513128) (xy 395.386306 -103.299768)
			(xy 395.42212 -103.184706) (xy 395.423591 -103.178239) (xy 395.423461 -103.164982) (xy 395.421866 -103.158544)
			(xy 395.419834 -103.151686) (xy 395.412214 -103.139494) (xy 395.406372 -103.134414) (xy 395.386325 -103.116203)
			(xy 395.351064 -103.075095) (xy 395.321966 -103.029417) (xy 395.299615 -102.980085) (xy 395.284461 -102.928089)
			(xy 395.276808 -102.874474) (xy 395.276324 -102.847394) (xy 395.276826 -102.819608) (xy 395.28489 -102.764625)
			(xy 395.300847 -102.711394) (xy 395.324358 -102.661041) (xy 395.354927 -102.614632) (xy 395.391905 -102.57315)
			(xy 395.434511 -102.537472) (xy 395.481843 -102.508354) (xy 395.532899 -102.486411) (xy 395.586599 -102.472109)
			(xy 395.614144 -102.468426) (xy 395.626844 -102.466902) (xy 395.629384 -102.466648) (xy 395.64056 -102.457504)
			(xy 395.644624 -102.453694) (xy 395.648063 -102.450009) (xy 395.653564 -102.441564) (xy 395.655546 -102.43693)
			(xy 395.737842 -102.173786) (xy 396.00759 -101.308916) (xy 396.008098 -101.307138) (xy 396.360904 -100.010976)
			(xy 396.472156 -99.602798) (xy 396.472156 -99.60229) (xy 396.506954 -99.469194) (xy 397.346424 -96.240854)
			(xy 397.348127 -96.233408) (xy 397.347484 -96.218155) (xy 397.345154 -96.210882) (xy 397.342614 -96.20377)
			(xy 397.333978 -96.192086) (xy 397.327628 -96.18726) (xy 397.250666 -96.129856) (xy 397.243498 -96.125253)
			(xy 397.227104 -96.120665) (xy 397.210114 -96.121749) (xy 397.202152 -96.124776) (xy 397.194532 -96.128586)
			(xy 397.193516 -96.129348) (xy 397.191992 -96.130364) (xy 397.191484 -96.130618) (xy 397.189198 -96.132142)
			(xy 397.18488 -96.134682) (xy 397.180054 -96.137476) (xy 397.177768 -96.138746) (xy 397.173196 -96.14154)
			(xy 397.132393 -96.16433) (xy 397.047536 -96.20351) (xy 396.959578 -96.235123) (xy 396.869193 -96.258926)
			(xy 396.777074 -96.274737) (xy 396.683925 -96.282435) (xy 396.59046 -96.281962) (xy 396.497394 -96.27332)
			(xy 396.405439 -96.256576) (xy 396.315301 -96.231858) (xy 396.227667 -96.199356) (xy 396.143211 -96.159318)
			(xy 396.062577 -96.11205) (xy 395.986384 -96.057916) (xy 395.915215 -95.997328) (xy 395.849614 -95.930751)
			(xy 395.790084 -95.858694) (xy 395.737081 -95.78171) (xy 395.691009 -95.700387) (xy 395.652223 -95.615349)
			(xy 395.621019 -95.527245) (xy 395.597635 -95.436751) (xy 395.582251 -95.344559) (xy 395.574985 -95.251376)
			(xy 395.575892 -95.157914) (xy 395.584965 -95.064889) (xy 395.593062 -95.01886) (xy 395.601977 -94.973833)
			(xy 395.626526 -94.885378) (xy 395.658578 -94.799358) (xy 395.697898 -94.716407) (xy 395.744194 -94.637139)
			(xy 395.797125 -94.562138) (xy 395.8563 -94.491958) (xy 395.921282 -94.427119) (xy 395.99159 -94.368098)
			(xy 396.066707 -94.315331) (xy 396.146077 -94.269208) (xy 396.229113 -94.230071) (xy 396.315203 -94.198207)
			(xy 396.403711 -94.173852) (xy 396.493984 -94.157186) (xy 396.585353 -94.148332) (xy 396.677146 -94.147356)
			(xy 396.768683 -94.154264) (xy 396.85929 -94.169006) (xy 396.948296 -94.191473) (xy 397.035044 -94.221499)
			(xy 397.118894 -94.258861) (xy 397.199227 -94.303285) (xy 397.275449 -94.354442) (xy 397.346997 -94.411955)
			(xy 397.413343 -94.475398) (xy 397.473998 -94.544302) (xy 397.528512 -94.618161) (xy 397.576484 -94.696426)
			(xy 397.617558 -94.778522) (xy 397.634968 -94.820994) (xy 397.637 -94.82582) (xy 397.641617 -94.833776)
			(xy 397.655353 -94.845992) (xy 397.672515 -94.852577) (xy 397.681704 -94.852998) (xy 397.682466 -94.852998)
			(xy 397.718534 -94.852744) (xy 397.757396 -94.85249) (xy 397.766291 -94.851626) (xy 397.78267 -94.844506)
			(xy 397.795583 -94.832167) (xy 397.799814 -94.824296) (xy 400.708876 -87.140288) (xy 400.710849 -87.133672)
			(xy 400.711482 -87.119885) (xy 400.710146 -87.11311) (xy 400.708622 -87.106252) (xy 400.70151 -87.093806)
			(xy 400.695668 -87.087964) (xy 400.677654 -87.069927) (xy 400.646086 -87.0299) (xy 400.620132 -86.986024)
			(xy 400.600254 -86.939083) (xy 400.586807 -86.889911) (xy 400.580029 -86.839387) (xy 400.57959 -86.813898)
			(xy 400.57959 -86.80577) (xy 400.579844 -86.79815) (xy 400.581535 -86.769879) (xy 400.592222 -86.714263)
			(xy 400.61101 -86.660836) (xy 400.637486 -86.610772) (xy 400.671069 -86.56517) (xy 400.711022 -86.52503)
			(xy 400.756468 -86.491235) (xy 400.806408 -86.464526) (xy 400.859747 -86.44549) (xy 400.915313 -86.434544)
			(xy 400.943572 -86.432644) (xy 400.946112 -86.432644) (xy 400.953023 -86.431841) (xy 400.966041 -86.426946)
			(xy 400.971766 -86.422992) (xy 400.9771 -86.419182) (xy 400.981418 -86.41334) (xy 400.983592 -86.410403)
			(xy 400.987161 -86.404028) (xy 400.98853 -86.40064) (xy 400.997674 -86.376764) (xy 401.000094 -86.367688)
			(xy 400.998794 -86.348963) (xy 400.990813 -86.331974) (xy 400.977229 -86.31902) (xy 400.968718 -86.315042)
			(xy 400.95678 -86.310216) (xy 400.951954 -86.31047) (xy 400.926046 -86.311994) (xy 400.917664 -86.311994)
			(xy 400.890461 -86.311437) (xy 400.836627 -86.303561) (xy 400.784457 -86.288116) (xy 400.735011 -86.265416)
			(xy 400.689291 -86.235921) (xy 400.648226 -86.20023) (xy 400.612648 -86.159067) (xy 400.583279 -86.113267)
			(xy 400.560716 -86.063758) (xy 400.545414 -86.011546) (xy 400.537687 -85.95769) (xy 400.537172 -85.930486)
			(xy 400.537659 -85.903235) (xy 400.545417 -85.849288) (xy 400.560773 -85.796993) (xy 400.583415 -85.747417)
			(xy 400.612881 -85.701567) (xy 400.648572 -85.660376) (xy 400.689762 -85.624684) (xy 400.735611 -85.595217)
			(xy 400.785188 -85.572575) (xy 400.837482 -85.557218) (xy 400.891429 -85.549459) (xy 400.91868 -85.548978)
			(xy 400.94432 -85.549391) (xy 400.995139 -85.55625) (xy 401.044584 -85.569848) (xy 401.091764 -85.589939)
			(xy 401.135832 -85.616163) (xy 401.15617 -85.631782) (xy 401.156424 -85.632036) (xy 401.160996 -85.635592)
			(xy 401.175474 -85.64245) (xy 401.182596 -85.645081) (xy 401.197704 -85.646499) (xy 401.205192 -85.645244)
			(xy 401.258532 -85.631274) (xy 401.268637 -85.627691) (xy 401.284914 -85.613774) (xy 401.290028 -85.60435)
			(xy 402.269198 -83.01736) (xy 405.318722 -74.961496) (xy 405.321789 -74.952102) (xy 405.321248 -74.932369)
			(xy 405.317706 -74.923142) (xy 405.309578 -74.9046) (xy 405.300688 -74.901044) (xy 405.290274 -74.896726)
			(xy 405.264292 -74.885589) (xy 405.215661 -74.856776) (xy 405.171809 -74.821106) (xy 405.133698 -74.779359)
			(xy 405.102159 -74.732449) (xy 405.077883 -74.681401) (xy 405.061399 -74.627331) (xy 405.05307 -74.571421)
			(xy 405.05253 -74.543158) (xy 405.053002 -74.516138) (xy 405.060633 -74.462638) (xy 405.075735 -74.410751)
			(xy 405.098008 -74.361514) (xy 405.127004 -74.315911) (xy 405.162145 -74.274856) (xy 405.202727 -74.23917)
			(xy 405.247938 -74.209566) (xy 405.296873 -74.186638) (xy 405.348554 -74.170843) (xy 405.401947 -74.162498)
			(xy 405.428958 -74.16165) (xy 405.434546 -74.16165) (xy 405.462517 -74.162141) (xy 405.51786 -74.170301)
			(xy 405.544782 -74.177906) (xy 405.553926 -74.1807) (xy 405.563324 -74.179938) (xy 405.568207 -74.179484)
			(xy 405.577672 -74.176923) (xy 405.58212 -74.174858) (xy 405.606504 -74.162666) (xy 405.614967 -74.158079)
			(xy 405.627901 -74.143846) (xy 405.63165 -74.13498) (xy 405.632412 -74.133202) (xy 405.75103 -73.819512)
			(xy 405.88946 -73.45426) (xy 405.891821 -73.444804) (xy 405.889999 -73.425416) (xy 405.881053 -73.40812)
			(xy 405.873966 -73.401428) (xy 405.80183 -73.33869) (xy 405.795736 -73.333784) (xy 405.781384 -73.327577)
			(xy 405.773636 -73.326498) (xy 405.76627 -73.325736) (xy 405.75103 -73.328784) (xy 405.743918 -73.332848)
			(xy 405.715496 -73.347773) (xy 405.654896 -73.36894) (xy 405.591609 -73.379676) (xy 405.559514 -73.380346)
			(xy 405.532258 -73.379884) (xy 405.4783 -73.372128) (xy 405.425995 -73.356772) (xy 405.376408 -73.334128)
			(xy 405.330549 -73.304657) (xy 405.28935 -73.26896) (xy 405.253651 -73.227763) (xy 405.224179 -73.181904)
			(xy 405.201533 -73.132318) (xy 405.186175 -73.080014) (xy 405.178417 -73.026056) (xy 405.178417 -72.971544)
			(xy 405.186175 -72.917586) (xy 405.201533 -72.865282) (xy 405.224179 -72.815696) (xy 405.253651 -72.769837)
			(xy 405.28935 -72.72864) (xy 405.330549 -72.692943) (xy 405.376408 -72.663472) (xy 405.425995 -72.640828)
			(xy 405.4783 -72.625472) (xy 405.532258 -72.617716) (xy 405.559514 -72.61733) (xy 405.588827 -72.617867)
			(xy 405.646762 -72.626836) (xy 405.702643 -72.644561) (xy 405.755156 -72.670624) (xy 405.803065 -72.704413)
			(xy 405.845241 -72.745132) (xy 405.880694 -72.791823) (xy 405.908587 -72.843387) (xy 405.918924 -72.870822)
			(xy 405.921464 -72.878188) (xy 405.930862 -72.890634) (xy 405.937212 -72.894952) (xy 405.943672 -72.899273)
			(xy 405.958408 -72.90419) (xy 405.966168 -72.904604) (xy 405.970994 -72.904604) (xy 406.061418 -72.90562)
			(xy 406.062942 -72.90562) (xy 406.069635 -72.905267) (xy 406.082505 -72.901546) (xy 406.088342 -72.898254)
			(xy 406.09539 -72.893613) (xy 406.106166 -72.880638) (xy 406.109424 -72.872854) (xy 406.170638 -72.711056)
			(xy 407.594054 -68.951348) (xy 407.898346 -68.147184) (xy 407.89987 -68.141088) (xy 407.89987 -68.14058)
			(xy 408.459178 -65.09131) (xy 408.930856 -62.520322) (xy 408.931559 -62.51083) (xy 408.926731 -62.492432)
			(xy 408.921458 -62.484508) (xy 408.89682 -62.450472) (xy 408.896566 -62.449964) (xy 408.890605 -62.442596)
			(xy 408.874557 -62.432539) (xy 408.865324 -62.430406) (xy 408.862022 -62.429898) (xy 408.855164 -62.428882)
			(xy 408.854656 -62.428882) (xy 408.850084 -62.42812) (xy 408.849068 -62.42812) (xy 408.817826 -62.421262)
			(xy 408.817572 -62.421262) (xy 408.810714 -62.419484) (xy 408.79649 -62.419992) (xy 408.79014 -62.422024)
			(xy 408.783506 -62.424346) (xy 408.771787 -62.432092) (xy 408.767026 -62.437264) (xy 408.763978 -62.44082)
			(xy 408.71013 -62.503304) (xy 408.705108 -62.510189) (xy 408.699538 -62.526284) (xy 408.699208 -62.5348)
			(xy 408.699208 -62.54877) (xy 408.702002 -62.563248) (xy 408.704542 -62.57163) (xy 408.70505 -62.573154)
			(xy 408.716151 -62.605173) (xy 408.728155 -62.671862) (xy 408.728926 -62.705742) (xy 408.728418 -62.71641)
			(xy 408.727229 -62.743158) (xy 408.718287 -62.795947) (xy 408.702053 -62.846967) (xy 408.678845 -62.895217)
			(xy 408.649121 -62.939749) (xy 408.613463 -62.979688) (xy 408.572571 -63.01425) (xy 408.52725 -63.042757)
			(xy 408.478388 -63.064647) (xy 408.426946 -63.079492) (xy 408.373934 -63.087) (xy 408.347164 -63.087504)
			(xy 408.319915 -63.087016) (xy 408.265971 -63.079255) (xy 408.213682 -63.063897) (xy 408.164109 -63.041254)
			(xy 408.118264 -63.011787) (xy 408.077078 -62.976096) (xy 408.041391 -62.934907) (xy 408.011929 -62.889059)
			(xy 407.98929 -62.839485) (xy 407.973937 -62.787193) (xy 407.966182 -62.733249) (xy 407.966182 -62.678751)
			(xy 407.973937 -62.624807) (xy 407.98929 -62.572515) (xy 408.011929 -62.522941) (xy 408.041391 -62.477093)
			(xy 408.077078 -62.435904) (xy 408.118264 -62.400213) (xy 408.164109 -62.370746) (xy 408.213682 -62.348103)
			(xy 408.265971 -62.332745) (xy 408.319915 -62.324984) (xy 408.347164 -62.324488) (xy 408.347926 -62.324488)
			(xy 408.370495 -62.324836) (xy 408.415317 -62.330182) (xy 408.437334 -62.335156) (xy 408.440636 -62.335918)
			(xy 408.450542 -62.336934) (xy 408.462179 -62.337054) (xy 408.483606 -62.328038) (xy 408.49169 -62.319662)
			(xy 408.526488 -62.279276) (xy 408.546554 -62.255908) (xy 408.552203 -62.248841) (xy 408.558586 -62.231925)
			(xy 408.559 -62.222888) (xy 408.559 -62.198758) (xy 408.55519 -62.189614) (xy 408.546979 -62.167514)
			(xy 408.535447 -62.121799) (xy 408.529634 -62.075012) (xy 408.529282 -62.051438) (xy 408.52979 -62.03061)
			(xy 408.530552 -62.022228) (xy 408.533256 -61.993826) (xy 408.546027 -61.938224) (xy 408.566937 -61.885143)
			(xy 408.59552 -61.835769) (xy 408.631137 -61.791203) (xy 408.672994 -61.752438) (xy 408.720157 -61.720339)
			(xy 408.771575 -61.695622) (xy 408.826101 -61.678839) (xy 408.882519 -61.670363) (xy 408.911044 -61.66993)
			(xy 408.911806 -61.66993) (xy 408.933201 -61.67026) (xy 408.975719 -61.6751) (xy 408.996642 -61.679582)
			(xy 409.001722 -61.680852) (xy 409.01028 -61.682194) (xy 409.027413 -61.679719) (xy 409.03525 -61.676026)
			(xy 409.039568 -61.673486) (xy 409.074366 -61.650372) (xy 409.082708 -61.644305) (xy 409.094116 -61.627142)
			(xy 409.096464 -61.617098) (xy 409.222448 -60.930282) (xy 409.22321 -60.920884) (xy 409.210764 -60.887864)
			(xy 409.204922 -60.88126) (xy 409.187749 -60.860429) (xy 409.158828 -60.814845) (xy 409.136618 -60.76564)
			(xy 409.121563 -60.713796) (xy 409.113962 -60.660349) (xy 409.113482 -60.633356) (xy 409.114042 -60.604136)
			(xy 409.122957 -60.546378) (xy 409.140571 -60.490655) (xy 409.166474 -60.438268) (xy 409.200059 -60.390441)
			(xy 409.240541 -60.348292) (xy 409.286976 -60.312806) (xy 409.312364 -60.29833) (xy 409.312618 -60.298076)
			(xy 409.320592 -60.293184) (xy 409.332615 -60.278872) (xy 409.338709 -60.261202) (xy 409.33878 -60.251848)
			(xy 409.332684 -60.155328) (xy 409.315412 -59.88304) (xy 409.243276 -58.759344) (xy 409.242878 -58.754617)
			(xy 409.240577 -58.745414) (xy 409.238704 -58.741056) (xy 409.234894 -58.732928) (xy 409.227782 -58.72607)
			(xy 409.215013 -58.713589) (xy 409.191607 -58.68662) (xy 409.181046 -58.672222) (xy 409.180538 -58.671714)
			(xy 409.178506 -58.668666) (xy 409.17114 -58.658252) (xy 409.156478 -58.634877) (xy 409.133309 -58.584801)
			(xy 409.117594 -58.531909) (xy 409.10966 -58.477306) (xy 409.109164 -58.449718) (xy 409.109569 -58.424426)
			(xy 409.116246 -58.374285) (xy 409.129499 -58.325469) (xy 409.149094 -58.278835) (xy 409.174688 -58.235204)
			(xy 409.189936 -58.215022) (xy 409.195016 -58.208418) (xy 409.205938 -58.17743) (xy 409.205938 -58.174128)
			(xy 409.19273 -57.967372) (xy 409.179776 -57.76595) (xy 408.980132 -54.642004) (xy 408.97846 -54.632678)
			(xy 408.969368 -54.616075) (xy 408.954892 -54.603877) (xy 408.946096 -54.600348) (xy 408.945842 -54.600348)
			(xy 408.920507 -54.591298) (xy 408.872467 -54.567084) (xy 408.828301 -54.536366) (xy 408.788886 -54.499752)
			(xy 408.755001 -54.457967) (xy 408.727319 -54.411838) (xy 408.706386 -54.36228) (xy 408.692619 -54.310274)
			(xy 408.689048 -54.28361) (xy 408.688032 -54.274466) (xy 408.686508 -54.238906) (xy 408.686978 -54.21227)
			(xy 408.694399 -54.159516) (xy 408.709084 -54.108308) (xy 408.730747 -54.059638) (xy 408.758968 -54.014455)
			(xy 408.793198 -53.973634) (xy 408.832772 -53.937971) (xy 408.876921 -53.908157) (xy 408.90063 -53.896006)
			(xy 408.903678 -53.894482) (xy 408.911662 -53.889345) (xy 408.923532 -53.874551) (xy 408.929276 -53.856473)
			(xy 408.929078 -53.846984) (xy 408.796998 -51.781964) (xy 408.795688 -51.770822) (xy 408.784874 -51.751198)
			(xy 408.77617 -51.744118) (xy 408.74442 -51.721004) (xy 408.7114 -51.697128) (xy 408.70223 -51.691677)
			(xy 408.681239 -51.688014) (xy 408.67076 -51.690016) (xy 408.670506 -51.690016) (xy 408.647462 -51.695486)
			(xy 408.600462 -51.701342) (xy 408.57678 -51.7017) (xy 408.549332 -51.701237) (xy 408.494999 -51.6934)
			(xy 408.442348 -51.677863) (xy 408.392465 -51.654946) (xy 408.346378 -51.62512) (xy 408.305039 -51.589002)
			(xy 408.269298 -51.547335) (xy 408.2542 -51.524408) (xy 408.25293 -51.522122) (xy 408.252422 -51.521614)
			(xy 408.251406 -51.520344) (xy 408.250898 -51.519582) (xy 408.246326 -51.513994) (xy 408.239813 -51.507526)
			(xy 408.223404 -51.499331) (xy 408.214322 -51.497992) (xy 408.174698 -51.493928) (xy 408.17419 -51.493928)
			(xy 408.150568 -51.491388) (xy 408.15006 -51.491388) (xy 408.134312 -51.489864) (xy 408.122682 -51.489279)
			(xy 408.100871 -51.497363) (xy 408.092402 -51.505358) (xy 408.092148 -51.505612) (xy 408.074052 -51.524176)
			(xy 408.033714 -51.55674) (xy 407.98934 -51.583544) (xy 407.941746 -51.604096) (xy 407.891809 -51.618017)
			(xy 407.840447 -51.62505) (xy 407.814526 -51.6255) (xy 407.787272 -51.625038) (xy 407.733319 -51.617284)
			(xy 407.681018 -51.601931) (xy 407.631435 -51.579289) (xy 407.58558 -51.549822) (xy 407.544385 -51.514128)
			(xy 407.508689 -51.472935) (xy 407.479219 -51.42708) (xy 407.456576 -51.377499) (xy 407.441219 -51.325199)
			(xy 407.433463 -51.271246) (xy 407.433018 -51.243992) (xy 407.433443 -51.218481) (xy 407.440238 -51.167913)
			(xy 407.453707 -51.1187) (xy 407.473608 -51.071719) (xy 407.499589 -51.027807) (xy 407.51506 -51.007518)
			(xy 407.5176 -51.00447) (xy 407.518616 -51.002946) (xy 407.521918 -50.996342) (xy 407.524262 -50.991119)
			(xy 407.526827 -50.979966) (xy 407.526998 -50.974244) (xy 407.526998 -50.94224) (xy 407.538174 -50.94224)
			(xy 407.538174 -50.89144) (xy 407.537839 -50.882836) (xy 407.532126 -50.866606) (xy 407.526998 -50.85969)
			(xy 407.525728 -50.858166) (xy 407.508336 -50.837289) (xy 407.47902 -50.791538) (xy 407.456493 -50.74209)
			(xy 407.441213 -50.689946) (xy 407.433488 -50.63616) (xy 407.433018 -50.608992) (xy 407.433482 -50.58174)
			(xy 407.44124 -50.527792) (xy 407.456597 -50.475496) (xy 407.47924 -50.425919) (xy 407.508709 -50.380068)
			(xy 407.544403 -50.338879) (xy 407.585596 -50.303188) (xy 407.631449 -50.273724) (xy 407.681028 -50.251085)
			(xy 407.733325 -50.235733) (xy 407.787274 -50.227979) (xy 407.814526 -50.227484) (xy 407.842567 -50.227982)
			(xy 407.898043 -50.236197) (xy 407.951718 -50.252448) (xy 408.002434 -50.276383) (xy 408.049099 -50.307487)
			(xy 408.090707 -50.345089) (xy 408.108912 -50.366422) (xy 408.109166 -50.366676) (xy 408.116024 -50.374804)
			(xy 408.139646 -50.386488) (xy 408.145996 -50.389536) (xy 408.150888 -50.391611) (xy 408.16126 -50.393907)
			(xy 408.16657 -50.394108) (xy 408.223974 -50.394108) (xy 408.229698 -50.393957) (xy 408.240855 -50.391389)
			(xy 408.246072 -50.389028) (xy 408.26436 -50.380138) (xy 408.274266 -50.373788) (xy 408.278076 -50.37074)
			(xy 408.281632 -50.366676) (xy 408.302036 -50.342892) (xy 408.349225 -50.301669) (xy 408.402504 -50.26869)
			(xy 408.431238 -50.256186) (xy 408.441336 -50.252051) (xy 408.461924 -50.244809) (xy 408.472386 -50.241708)
			(xy 408.482546 -50.238914) (xy 408.490674 -50.23231) (xy 408.494514 -50.228958) (xy 408.500918 -50.221028)
			(xy 408.503374 -50.216562) (xy 408.520646 -50.183288) (xy 408.525037 -50.173924) (xy 408.526628 -50.153326)
			(xy 408.523694 -50.14341) (xy 408.428952 -49.86782) (xy 408.425025 -49.858038) (xy 408.410754 -49.842558)
			(xy 408.391473 -49.834099) (xy 408.380946 -49.83353) (xy 408.375104 -49.83353) (xy 408.37062 -49.833668)
			(xy 408.361803 -49.835323) (xy 408.357578 -49.836832) (xy 408.3304 -49.848008) (xy 408.323542 -49.854358)
			(xy 408.30224 -49.873388) (xy 408.255041 -49.905557) (xy 408.203576 -49.930336) (xy 408.148994 -49.947172)
			(xy 408.092514 -49.955689) (xy 408.063954 -49.956212) (xy 408.038444 -49.955784) (xy 407.987878 -49.948985)
			(xy 407.938667 -49.935513) (xy 407.891689 -49.91561) (xy 407.847778 -49.889628) (xy 407.82748 -49.87417)
			(xy 407.824432 -49.87163) (xy 407.822908 -49.870614) (xy 407.816304 -49.867312) (xy 407.811081 -49.864971)
			(xy 407.799927 -49.862412) (xy 407.794206 -49.862232) (xy 407.762202 -49.862232) (xy 407.762202 -49.851056)
			(xy 407.711402 -49.851056) (xy 407.702801 -49.851397) (xy 407.68658 -49.857122) (xy 407.679652 -49.862232)
			(xy 407.678128 -49.863502) (xy 407.657251 -49.880895) (xy 407.611501 -49.910212) (xy 407.562053 -49.932737)
			(xy 407.509908 -49.948015) (xy 407.456122 -49.955736) (xy 407.428954 -49.956212) (xy 407.403444 -49.955784)
			(xy 407.352878 -49.948985) (xy 407.303667 -49.935513) (xy 407.256689 -49.91561) (xy 407.212778 -49.889628)
			(xy 407.19248 -49.87417) (xy 407.189432 -49.87163) (xy 407.187908 -49.870614) (xy 407.181304 -49.867312)
			(xy 407.176081 -49.864971) (xy 407.164927 -49.862412) (xy 407.159206 -49.862232) (xy 407.127202 -49.862232)
			(xy 407.127202 -49.851056) (xy 407.076402 -49.851056) (xy 407.067801 -49.851397) (xy 407.05158 -49.857122)
			(xy 407.044652 -49.862232) (xy 407.043128 -49.863502) (xy 407.022251 -49.880895) (xy 406.976501 -49.910212)
			(xy 406.927053 -49.932737) (xy 406.874908 -49.948015) (xy 406.821122 -49.955736) (xy 406.793954 -49.956212)
			(xy 406.766705 -49.955723) (xy 406.712761 -49.947961) (xy 406.660472 -49.932602) (xy 406.6109 -49.909958)
			(xy 406.565054 -49.88049) (xy 406.523869 -49.844798) (xy 406.488182 -49.803609) (xy 406.45872 -49.75776)
			(xy 406.436082 -49.708185) (xy 406.420729 -49.655894) (xy 406.412974 -49.601949) (xy 406.412974 -49.547451)
			(xy 406.420729 -49.493506) (xy 406.436082 -49.441215) (xy 406.45872 -49.39164) (xy 406.488182 -49.345791)
			(xy 406.523869 -49.304602) (xy 406.565054 -49.26891) (xy 406.6109 -49.239442) (xy 406.660472 -49.216798)
			(xy 406.712761 -49.201439) (xy 406.766705 -49.193677) (xy 406.793954 -49.193196) (xy 406.819464 -49.193624)
			(xy 406.87003 -49.200425) (xy 406.919239 -49.213897) (xy 406.966217 -49.233802) (xy 407.010126 -49.259785)
			(xy 407.030428 -49.275238) (xy 407.033476 -49.277778) (xy 407.035 -49.278794) (xy 407.041604 -49.282096)
			(xy 407.046827 -49.284436) (xy 407.057981 -49.286993) (xy 407.063702 -49.287176) (xy 407.095706 -49.287176)
			(xy 407.095706 -49.298352) (xy 407.146506 -49.298352) (xy 407.155106 -49.29801) (xy 407.171326 -49.292283)
			(xy 407.178256 -49.287176) (xy 407.17978 -49.285906) (xy 407.200657 -49.268513) (xy 407.246407 -49.239197)
			(xy 407.295855 -49.216672) (xy 407.348 -49.201394) (xy 407.401786 -49.193674) (xy 407.428954 -49.193196)
			(xy 407.454464 -49.193624) (xy 407.50503 -49.200425) (xy 407.554239 -49.213897) (xy 407.601217 -49.233802)
			(xy 407.645126 -49.259785) (xy 407.665428 -49.275238) (xy 407.668476 -49.277778) (xy 407.67 -49.278794)
			(xy 407.676604 -49.282096) (xy 407.681827 -49.284436) (xy 407.692981 -49.286993) (xy 407.698702 -49.287176)
			(xy 407.730706 -49.287176) (xy 407.730706 -49.298352) (xy 407.781506 -49.298352) (xy 407.790106 -49.29801)
			(xy 407.806326 -49.292283) (xy 407.813256 -49.287176) (xy 407.81478 -49.285906) (xy 407.822146 -49.279302)
			(xy 407.823162 -49.278794) (xy 407.824432 -49.277778) (xy 407.82494 -49.27727) (xy 407.847038 -49.26076)
			(xy 407.879042 -49.240948) (xy 407.879296 -49.240948) (xy 407.87955 -49.240694) (xy 407.884348 -49.237839)
			(xy 407.892678 -49.230405) (xy 407.89606 -49.225962) (xy 407.899616 -49.221136) (xy 407.903934 -49.210468)
			(xy 407.90876 -49.18075) (xy 407.90876 -49.180242) (xy 407.91257 -49.156112) (xy 407.91257 -49.155604)
			(xy 407.913224 -49.150581) (xy 407.91272 -49.140467) (xy 407.911554 -49.135538) (xy 407.910792 -49.132744)
			(xy 407.909482 -49.128877) (xy 407.905786 -49.121598) (xy 407.903426 -49.118266) (xy 407.731722 -48.895508)
			(xy 407.728928 -48.892206) (xy 402.169376 -42.831766) (xy 402.160996 -42.82344) (xy 402.13902 -42.814853)
			(xy 402.127212 -42.815256) (xy 402.116036 -42.817542) (xy 402.065744 -42.834052) (xy 402.065236 -42.834052)
			(xy 402.051266 -42.83837) (xy 402.047122 -42.839754) (xy 402.039334 -42.843713) (xy 402.035772 -42.846244)
			(xy 402.027602 -42.853036) (xy 402.017219 -42.871543) (xy 402.015706 -42.882058) (xy 402.012169 -42.911429)
			(xy 401.997586 -42.968761) (xy 401.974768 -43.023341) (xy 401.944207 -43.073992) (xy 401.906561 -43.119626)
			(xy 401.862642 -43.159257) (xy 401.813394 -43.192033) (xy 401.759879 -43.217248) (xy 401.70325 -43.234358)
			(xy 401.644727 -43.242994) (xy 401.615148 -43.2435) (xy 401.586386 -43.243015) (xy 401.529447 -43.234834)
			(xy 401.474252 -43.218633) (xy 401.421925 -43.194742) (xy 401.373531 -43.163646) (xy 401.330055 -43.125979)
			(xy 401.292383 -43.082508) (xy 401.261281 -43.034117) (xy 401.237383 -42.981793) (xy 401.221176 -42.9266)
			(xy 401.212989 -42.869662) (xy 401.212989 -42.812138) (xy 401.221176 -42.7552) (xy 401.237383 -42.700007)
			(xy 401.261281 -42.647683) (xy 401.292383 -42.599292) (xy 401.330055 -42.555821) (xy 401.373531 -42.518154)
			(xy 401.421925 -42.487058) (xy 401.474252 -42.463167) (xy 401.529447 -42.446966) (xy 401.586386 -42.438785)
			(xy 401.615148 -42.43832) (xy 401.615402 -42.43832) (xy 401.634313 -42.438554) (xy 401.671967 -42.442112)
			(xy 401.690586 -42.445432) (xy 401.702524 -42.447718) (xy 401.725638 -42.441114) (xy 401.770596 -42.399712)
			(xy 401.762722 -42.388536) (xy 401.709382 -42.330624) (xy 401.709128 -42.330116) (xy 401.706588 -42.327322)
			(xy 401.704048 -42.324782) (xy 401.666882 -42.284225) (xy 401.600813 -42.196264) (xy 401.572222 -42.149268)
			(xy 401.063714 -41.28897) (xy 401.055332 -41.282874) (xy 401.038401 -41.270582) (xy 401.007081 -41.242837)
			(xy 400.992848 -41.227502) (xy 400.971272 -41.20263) (xy 400.93615 -41.146943) (xy 400.922998 -41.116758)
			(xy 400.92249 -41.115234) (xy 400.921474 -41.11244) (xy 400.913828 -41.092531) (xy 400.902498 -41.051414)
			(xy 400.898868 -41.030398) (xy 400.898868 -41.02989) (xy 400.896836 -41.01465) (xy 400.895566 -41.003728)
			(xy 400.51736 -40.36314) (xy 400.512017 -40.356074) (xy 400.497589 -40.345821) (xy 400.489166 -40.343074)
			(xy 400.487896 -40.34282) (xy 400.487642 -40.34282) (xy 400.483832 -40.341804) (xy 400.456832 -40.334442)
			(xy 400.405184 -40.312891) (xy 400.357239 -40.284026) (xy 400.314027 -40.248464) (xy 400.276475 -40.20697)
			(xy 400.245389 -40.160434) (xy 400.221436 -40.109856) (xy 400.205131 -40.05632) (xy 400.196824 -40.000977)
			(xy 400.196304 -39.972996) (xy 400.196304 -39.968424) (xy 400.196812 -39.95166) (xy 400.198136 -39.931532)
			(xy 400.204504 -39.891698) (xy 400.209512 -39.872158) (xy 400.212306 -39.861998) (xy 400.211036 -39.852092)
			(xy 400.210293 -39.84694) (xy 400.206968 -39.837079) (xy 400.204432 -39.832534) (xy 399.932652 -39.37254)
			(xy 399.681954 -38.947344) (xy 399.677068 -38.940358) (xy 399.663657 -38.929849) (xy 399.647547 -38.924302)
			(xy 399.639028 -38.923976) (xy 399.565876 -38.923722) (xy 399.551906 -38.9255) (xy 399.546064 -38.927278)
			(xy 399.540476 -38.930326) (xy 399.539968 -38.930326) (xy 399.516346 -38.943788) (xy 399.512801 -38.946286)
			(xy 399.506543 -38.952288) (xy 399.5039 -38.955726) (xy 399.502122 -38.958266) (xy 399.486968 -38.980786)
			(xy 399.4513 -39.0217) (xy 399.410188 -39.05714) (xy 399.364464 -39.08639) (xy 399.315053 -39.108856)
			(xy 399.262954 -39.124085) (xy 399.209222 -39.131769) (xy 399.182082 -39.132256) (xy 399.16297 -39.132084)
			(xy 399.124926 -39.128389) (xy 399.106136 -39.12489) (xy 399.101056 -39.12362) (xy 399.08576 -39.120134)
			(xy 399.055749 -39.11098) (xy 399.041112 -39.105332) (xy 399.013497 -39.09372) (xy 398.961976 -39.063157)
			(xy 398.915865 -39.024917) (xy 398.876297 -38.979941) (xy 398.859756 -38.954964) (xy 398.857978 -38.952424)
			(xy 398.854168 -38.947852) (xy 398.851647 -38.945011) (xy 398.84591 -38.940034) (xy 398.842738 -38.937946)
			(xy 398.823434 -38.926262) (xy 398.818615 -38.923502) (xy 398.808106 -38.919919) (xy 398.802606 -38.91915)
			(xy 398.80032 -38.918896) (xy 398.800066 -38.918896) (xy 398.729708 -38.914324) (xy 398.718864 -38.914103)
			(xy 398.698581 -38.921723) (xy 398.690592 -38.929056) (xy 398.686782 -38.932866) (xy 398.685004 -38.935152)
			(xy 398.684242 -38.936168) (xy 398.66603 -38.958794) (xy 398.623924 -38.998797) (xy 398.576248 -39.031966)
			(xy 398.524101 -39.057537) (xy 398.468685 -39.07492) (xy 398.411275 -39.083716) (xy 398.382236 -39.08425)
			(xy 398.381982 -39.08425) (xy 398.354729 -39.083763) (xy 398.300777 -39.076003) (xy 398.248479 -39.060645)
			(xy 398.198898 -39.038) (xy 398.153045 -39.00853) (xy 398.111852 -38.972835) (xy 398.076159 -38.931641)
			(xy 398.046691 -38.885786) (xy 398.024049 -38.836205) (xy 398.008693 -38.783906) (xy 398.000936 -38.729953)
			(xy 398.000936 -38.675447) (xy 398.008693 -38.621494) (xy 398.024049 -38.569195) (xy 398.046691 -38.519614)
			(xy 398.076159 -38.473759) (xy 398.111852 -38.432565) (xy 398.153045 -38.39687) (xy 398.198898 -38.3674)
			(xy 398.248479 -38.344755) (xy 398.300777 -38.329397) (xy 398.354729 -38.321637) (xy 398.381982 -38.321234)
			(xy 398.409467 -38.321711) (xy 398.463869 -38.329588) (xy 398.51658 -38.345182) (xy 398.566511 -38.368171)
			(xy 398.612631 -38.39808) (xy 398.653987 -38.434292) (xy 398.689726 -38.476058) (xy 398.704816 -38.499034)
			(xy 398.704816 -38.499288) (xy 398.707356 -38.503352) (xy 398.708118 -38.504368) (xy 398.712182 -38.508432)
			(xy 398.721072 -38.515036) (xy 398.74063 -38.527228) (xy 398.746007 -38.530313) (xy 398.757824 -38.534046)
			(xy 398.763998 -38.534594) (xy 398.834864 -38.539166) (xy 398.838166 -38.539166) (xy 398.868138 -38.524434)
			(xy 398.87301 -38.521851) (xy 398.881589 -38.514925) (xy 398.885156 -38.510718) (xy 398.904241 -38.488055)
			(xy 398.94822 -38.448354) (xy 398.99782 -38.41595) (xy 399.024602 -38.403276) (xy 399.037363 -38.397622)
			(xy 399.063552 -38.387963) (xy 399.076926 -38.383972) (xy 399.078704 -38.383464) (xy 399.093218 -38.379534)
			(xy 399.122716 -38.373685) (xy 399.137632 -38.37178) (xy 399.166842 -38.369494) (xy 399.180304 -38.368986)
			(xy 399.191734 -38.361874) (xy 399.197099 -38.358277) (xy 399.205967 -38.348889) (xy 399.20926 -38.343332)
			(xy 399.222468 -38.31971) (xy 399.222468 -38.319202) (xy 399.251424 -38.265354) (xy 399.254992 -38.25768)
			(xy 399.257345 -38.24093) (xy 399.254097 -38.22433) (xy 399.250154 -38.21684) (xy 399.169382 -38.080188)
			(xy 398.986756 -37.77107) (xy 398.97812 -37.76472) (xy 398.944981 -37.740449) (xy 398.882413 -37.687216)
			(xy 398.824473 -37.628981) (xy 398.771559 -37.566143) (xy 398.724036 -37.499135) (xy 398.702784 -37.463984)
			(xy 398.47774 -37.083238) (xy 398.455495 -37.044638) (xy 398.41725 -36.964166) (xy 398.38641 -36.880576)
			(xy 398.363225 -36.794549) (xy 398.355058 -36.750752) (xy 398.353534 -36.744402) (xy 398.35152 -36.73857)
			(xy 398.345092 -36.728041) (xy 398.340834 -36.723574) (xy 398.324675 -36.70691) (xy 398.296092 -36.670336)
			(xy 398.272146 -36.630571) (xy 398.262348 -36.609528) (xy 398.251426 -36.58235) (xy 398.247616 -36.571682)
			(xy 397.828008 -36.145724) (xy 397.820584 -36.138773) (xy 397.801847 -36.130909) (xy 397.791686 -36.130484)
			(xy 397.777716 -36.130484) (xy 397.767755 -36.130973) (xy 397.749334 -36.138564) (xy 397.741902 -36.145216)
			(xy 397.741648 -36.14547) (xy 397.720023 -36.166448) (xy 397.671388 -36.202005) (xy 397.617771 -36.229479)
			(xy 397.560503 -36.248188) (xy 397.501007 -36.257666) (xy 397.470884 -36.258246) (xy 397.44315 -36.25774)
			(xy 397.388267 -36.249694) (xy 397.335128 -36.233787) (xy 397.284852 -36.210355) (xy 397.238497 -36.179892)
			(xy 397.19704 -36.143038) (xy 397.161355 -36.100572) (xy 397.132193 -36.053387) (xy 397.11017 -36.002478)
			(xy 397.095748 -35.948917) (xy 397.091916 -35.921442) (xy 397.090392 -35.907726) (xy 397.088605 -35.879671)
			(xy 397.092307 -35.823578) (xy 397.104205 -35.768636) (xy 397.124042 -35.716037) (xy 397.151387 -35.666921)
			(xy 397.168116 -35.644328) (xy 397.173253 -35.637093) (xy 397.178582 -35.620181) (xy 397.17853 -35.611308)
			(xy 397.17726 -35.581336) (xy 397.17651 -35.571887) (xy 397.168958 -35.554516) (xy 397.162528 -35.547554)
			(xy 397.103092 -35.488372) (xy 396.978124 -35.363404) (xy 396.944596 -35.328098) (xy 396.944088 -35.32759)
			(xy 396.94358 -35.326828) (xy 396.940278 -35.323526) (xy 396.93977 -35.32251) (xy 396.937992 -35.320732)
			(xy 396.93596 -35.318446) (xy 396.928848 -35.312096) (xy 396.921482 -35.308794) (xy 396.917774 -35.307228)
			(xy 396.909988 -35.305183) (xy 396.905988 -35.30473) (xy 396.889224 -35.302952) (xy 396.884356 -35.302571)
			(xy 396.874634 -35.303457) (xy 396.86992 -35.30473) (xy 396.86103 -35.30727) (xy 396.853156 -35.313112)
			(xy 396.815884 -35.340948) (xy 396.737049 -35.390344) (xy 396.653957 -35.432186) (xy 396.567331 -35.466109)
			(xy 396.477922 -35.49182) (xy 396.386507 -35.509093) (xy 396.293882 -35.51778) (xy 396.247366 -35.518344)
			(xy 396.247112 -35.518344) (xy 396.191584 -35.517586) (xy 396.081216 -35.505239) (xy 396.026894 -35.493706)
			(xy 395.985589 -35.483872) (xy 395.904684 -35.458088) (xy 395.826267 -35.425513) (xy 395.788388 -35.40633)
			(xy 395.748199 -35.384952) (xy 395.67151 -35.335898) (xy 395.599615 -35.280054) (xy 395.533112 -35.217886)
			(xy 395.472556 -35.149912) (xy 395.418451 -35.076699) (xy 395.394434 -35.03803) (xy 395.391894 -35.033712)
			(xy 395.383004 -35.023806) (xy 395.376654 -35.017964) (xy 395.354482 -34.999742) (xy 395.315336 -34.957778)
			(xy 395.28291 -34.910428) (xy 395.257933 -34.858761) (xy 395.240967 -34.803937) (xy 395.232396 -34.747192)
			(xy 395.231874 -34.718498) (xy 395.231874 -34.718244) (xy 395.232378 -34.689809) (xy 395.240795 -34.633567)
			(xy 395.248638 -34.60623) (xy 395.250162 -34.599118) (xy 395.25194 -34.588196) (xy 395.25194 -34.584386)
			(xy 395.251686 -34.581592) (xy 395.249908 -34.52114) (xy 395.249908 -34.502852) (xy 395.249908 -34.50082)
			(xy 395.25067 -34.481008) (xy 395.251681 -34.458462) (xy 395.255494 -34.413487) (xy 395.25829 -34.391092)
			(xy 395.265143 -34.343493) (xy 395.286826 -34.249797) (xy 395.317427 -34.158622) (xy 395.336522 -34.114486)
			(xy 395.33957 -34.104834) (xy 395.343126 -34.089594) (xy 395.343126 -34.088578) (xy 395.33957 -34.073338)
			(xy 395.336522 -34.063686) (xy 395.319843 -34.025283) (xy 395.292234 -33.946233) (xy 395.271356 -33.865144)
			(xy 395.257355 -33.78259) (xy 395.25033 -33.699152) (xy 395.249908 -33.657286) (xy 395.25194 -33.595564)
			(xy 395.252702 -33.585404) (xy 395.252702 -33.58388) (xy 395.25194 -33.581594) (xy 395.251432 -33.58007)
			(xy 395.25067 -33.578038) (xy 395.242034 -33.563814) (xy 395.23543 -33.554924) (xy 395.193774 -33.510982)
			(xy 395.186504 -33.504641) (xy 395.168613 -33.497469) (xy 395.158976 -33.497012) (xy 394.51915 -33.497012)
			(xy 394.481181 -33.496657) (xy 394.405464 -33.49088) (xy 394.330407 -33.479357) (xy 394.293344 -33.471104)
			(xy 394.286232 -33.469326) (xy 394.276326 -33.46831) (xy 394.244068 -33.480248) (xy 394.240004 -33.48355)
			(xy 394.206529 -33.510547) (xy 394.135693 -33.559324) (xy 394.060924 -33.601827) (xy 393.982775 -33.637738)
			(xy 393.901826 -33.666794) (xy 393.818678 -33.688777) (xy 393.733947 -33.703526) (xy 393.648261 -33.71093)
			(xy 393.605258 -33.711388) (xy 393.605258 -33.711642) (xy 393.558777 -33.71111) (xy 393.466217 -33.702462)
			(xy 393.374864 -33.685235) (xy 393.285511 -33.659579) (xy 393.198935 -33.625718) (xy 393.115886 -33.583944)
			(xy 393.037087 -33.534621) (xy 392.963221 -33.478177) (xy 392.89493 -33.415102) (xy 392.832807 -33.345945)
			(xy 392.777391 -33.271304) (xy 392.752834 -33.231836) (xy 392.750294 -33.227772) (xy 392.737848 -33.214056)
			(xy 392.734546 -33.211516) (xy 392.712728 -33.193615) (xy 392.674095 -33.152476) (xy 392.641933 -33.106103)
			(xy 392.61694 -33.055504) (xy 392.599662 -33.001779) (xy 392.590473 -32.946098) (xy 392.589512 -32.917892)
			(xy 392.589766 -32.903922) (xy 392.590692 -32.877213) (xy 392.599103 -32.824438) (xy 392.60653 -32.798766)
			(xy 392.608054 -32.791654) (xy 392.609832 -32.780732) (xy 392.609832 -32.776922) (xy 392.609578 -32.774128)
			(xy 392.6078 -32.714692) (xy 392.6078 -32.707326) (xy 392.608399 -32.670113) (xy 392.614457 -32.595927)
			(xy 392.626032 -32.522399) (xy 392.634216 -32.486092) (xy 392.645581 -32.440144) (xy 392.675857 -32.350457)
			(xy 392.694668 -32.307022) (xy 392.696446 -32.302958) (xy 392.701018 -32.282892) (xy 392.701018 -32.281876)
			(xy 392.696446 -32.26181) (xy 392.695176 -32.259016) (xy 392.679053 -32.222083) (xy 392.652116 -32.146124)
			(xy 392.631389 -32.068242) (xy 392.617005 -31.988942) (xy 392.612626 -31.948882) (xy 392.610362 -31.924434)
			(xy 392.607949 -31.87539) (xy 392.6078 -31.850838) (xy 392.6078 -31.850584) (xy 392.609578 -31.789878)
			(xy 392.609832 -31.78683) (xy 392.609832 -31.78302) (xy 392.608054 -31.772098) (xy 392.60653 -31.76524)
			(xy 392.598702 -31.7379) (xy 392.590281 -31.68166) (xy 392.589766 -31.653226) (xy 392.589766 -31.652972)
			(xy 392.590311 -31.623901) (xy 392.599121 -31.566432) (xy 392.616532 -31.510959) (xy 392.642144 -31.458763)
			(xy 392.675365 -31.411048) (xy 392.715429 -31.368914) (xy 392.738102 -31.350712) (xy 392.743182 -31.34614)
			(xy 392.749024 -31.339028) (xy 392.771808 -31.30176) (xy 392.822966 -31.230949) (xy 392.880126 -31.164888)
			(xy 392.942849 -31.104086) (xy 393.010655 -31.049007) (xy 393.083022 -31.000076) (xy 393.159395 -30.957669)
			(xy 393.199112 -30.939486) (xy 393.237476 -30.92286) (xy 393.316437 -30.895342) (xy 393.397425 -30.874531)
			(xy 393.47987 -30.860572) (xy 393.563195 -30.853565) (xy 393.605004 -30.853126) (xy 393.605258 -30.853126)
			(xy 393.647839 -30.853575) (xy 393.732691 -30.860839) (xy 393.816615 -30.87531) (xy 393.899 -30.896883)
			(xy 393.979246 -30.925399) (xy 394.056769 -30.960653) (xy 394.131005 -31.002386) (xy 394.201413 -31.050296)
			(xy 394.26748 -31.104033) (xy 394.298424 -31.133288) (xy 394.304689 -31.137829) (xy 394.319166 -31.14327)
			(xy 394.326872 -31.143956) (xy 395.17701 -31.143956) (xy 395.184376 -31.143448) (xy 395.192725 -31.141849)
			(xy 395.207766 -31.133946) (xy 395.219419 -31.121581) (xy 395.223238 -31.113984) (xy 395.232636 -31.09087)
			(xy 395.233398 -31.08325) (xy 395.233398 -31.082996) (xy 395.23416 -31.07563) (xy 395.236318 -31.057771)
			(xy 395.243571 -31.022533) (xy 395.248638 -31.005272) (xy 395.250162 -30.99816) (xy 395.25194 -30.987238)
			(xy 395.25194 -30.983428) (xy 395.251686 -30.980634) (xy 395.249908 -30.921452) (xy 395.249908 -30.92069)
			(xy 395.250349 -30.878825) (xy 395.257388 -30.79539) (xy 395.27139 -30.712838) (xy 395.292257 -30.631748)
			(xy 395.319842 -30.552691) (xy 395.336522 -30.51429) (xy 395.33957 -30.504638) (xy 395.343126 -30.489398)
			(xy 395.343126 -30.488382) (xy 395.33957 -30.473142) (xy 395.336522 -30.46349) (xy 395.320384 -30.426347)
			(xy 395.293469 -30.349961) (xy 395.272833 -30.271644) (xy 395.258613 -30.191913) (xy 395.250901 -30.111291)
			(xy 395.249908 -30.070806) (xy 395.249908 -30.056836) (xy 395.250162 -30.034738) (xy 395.250416 -30.03042)
			(xy 395.250416 -30.029912) (xy 395.25067 -30.021784) (xy 395.25067 -30.019752) (xy 395.24686 -30.0101)
			(xy 395.244888 -30.005619) (xy 395.23952 -29.997435) (xy 395.236192 -29.993844) (xy 395.191996 -29.948632)
			(xy 395.184759 -29.942384) (xy 395.167004 -29.935333) (xy 395.157452 -29.934916) (xy 395.145768 -29.934916)
			(xy 395.099046 -29.934341) (xy 395.006026 -29.925457) (xy 394.91426 -29.907828) (xy 394.824569 -29.881612)
			(xy 394.737755 -29.847043) (xy 394.695934 -29.826204) (xy 394.690507 -29.823623) (xy 394.678827 -29.820804)
			(xy 394.67282 -29.820616) (xy 394.339318 -29.820616) (xy 394.334428 -29.820756) (xy 394.324838 -29.82268)
			(xy 394.320268 -29.824426) (xy 394.295122 -29.834586) (xy 394.28801 -29.84119) (xy 394.253516 -29.872857)
			(xy 394.179551 -29.930291) (xy 394.100531 -29.980542) (xy 394.017149 -30.023169) (xy 393.930141 -30.057795)
			(xy 393.84027 -30.084116) (xy 393.748329 -30.101901) (xy 393.655127 -30.110994) (xy 393.608306 -30.1117)
			(xy 393.5984 -30.1117) (xy 393.551571 -30.110837) (xy 393.458379 -30.101402) (xy 393.366482 -30.083273)
			(xy 393.276689 -30.056608) (xy 393.189791 -30.021643) (xy 393.106554 -29.978686) (xy 393.02771 -29.928115)
			(xy 392.953954 -29.870376) (xy 392.885935 -29.805976) (xy 392.854688 -29.771086) (xy 392.826617 -29.738272)
			(xy 392.775622 -29.668575) (xy 392.752834 -29.631894) (xy 392.750294 -29.62783) (xy 392.737848 -29.614114)
			(xy 392.734546 -29.611574) (xy 392.712405 -29.59338) (xy 392.673306 -29.551485) (xy 392.640902 -29.50422)
			(xy 392.61592 -29.452646) (xy 392.598921 -29.39792) (xy 392.590286 -29.341268) (xy 392.589766 -29.312616)
			(xy 392.589766 -29.312108) (xy 392.589766 -29.30525) (xy 392.590782 -29.283152) (xy 392.594846 -29.249116)
			(xy 392.59693 -29.237353) (xy 392.602394 -29.214094) (xy 392.605768 -29.202634) (xy 392.605768 -29.202126)
			(xy 392.607546 -29.196284) (xy 392.609832 -29.181552) (xy 392.609832 -29.177742) (xy 392.609578 -29.174948)
			(xy 392.6078 -29.115258) (xy 392.6078 -29.114242) (xy 392.608234 -29.072295) (xy 392.615283 -28.988697)
			(xy 392.629325 -28.905987) (xy 392.650262 -28.824747) (xy 392.677946 -28.745552) (xy 392.694668 -28.70708)
			(xy 392.696446 -28.703016) (xy 392.701018 -28.68295) (xy 392.701018 -28.681934) (xy 392.696446 -28.661868)
			(xy 392.694668 -28.657804) (xy 392.677993 -28.619476) (xy 392.650373 -28.54058) (xy 392.629455 -28.459648)
			(xy 392.615386 -28.377249) (xy 392.608265 -28.293961) (xy 392.6078 -28.252166) (xy 392.6078 -28.250642)
			(xy 392.609578 -28.189936) (xy 392.609832 -28.187142) (xy 392.609832 -28.183332) (xy 392.608054 -28.17241)
			(xy 392.60653 -28.165298) (xy 392.59869 -28.137896) (xy 392.590276 -28.081527) (xy 392.589766 -28.05303)
			(xy 392.589766 -28.04668) (xy 392.59002 -28.038298) (xy 392.59129 -28.01874) (xy 392.59129 -28.018486)
			(xy 392.591798 -28.012898) (xy 392.595468 -27.983489) (xy 392.610728 -27.926223) (xy 392.634655 -27.872004)
			(xy 392.650218 -27.846782) (xy 392.65352 -27.841702) (xy 392.670726 -27.816868) (xy 392.711687 -27.772461)
			(xy 392.735054 -27.75331) (xy 392.740896 -27.747722) (xy 392.745722 -27.742388) (xy 392.751818 -27.73426)
			(xy 392.774819 -27.697232) (xy 392.82633 -27.626903) (xy 392.854688 -27.593798) (xy 392.882999 -27.562107)
			(xy 392.944195 -27.503134) (xy 393.010188 -27.449585) (xy 393.080499 -27.401846) (xy 393.154618 -27.360266)
			(xy 393.232008 -27.325145) (xy 393.312106 -27.296738) (xy 393.394331 -27.275252) (xy 393.478087 -27.260842)
			(xy 393.562765 -27.253614) (xy 393.605258 -27.253184) (xy 393.605512 -27.253184) (xy 393.653031 -27.25374)
			(xy 393.747636 -27.2628) (xy 393.840949 -27.280826) (xy 393.932121 -27.307655) (xy 394.020324 -27.343044)
			(xy 394.104758 -27.38667) (xy 394.145008 -27.411934) (xy 394.182942 -27.436963) (xy 394.254556 -27.492932)
			(xy 394.28801 -27.523694) (xy 394.293344 -27.528774) (xy 394.294614 -27.530044) (xy 394.294868 -27.530298)
			(xy 394.320268 -27.540458) (xy 394.324834 -27.542216) (xy 394.334427 -27.544141) (xy 394.339318 -27.544268)
			(xy 396.240508 -27.544268) (xy 396.285973 -27.544792) (xy 396.37652 -27.553116) (xy 396.465933 -27.569656)
			(xy 396.553466 -27.594276) (xy 396.596108 -27.610054) (xy 396.622524 -27.620722) (xy 397.988282 -28.189428)
			(xy 398.010553 -28.198783) (xy 398.054261 -28.219364) (xy 398.075658 -28.230576) (xy 398.087088 -28.235148)
			(xy 398.088104 -28.235402) (xy 398.096528 -28.237178) (xy 398.11366 -28.235607) (xy 398.121632 -28.232354)
			(xy 398.143476 -28.222194) (xy 398.150588 -28.21432) (xy 398.168753 -28.19474) (xy 398.209613 -28.160347)
			(xy 398.25487 -28.131987) (xy 398.30364 -28.110216) (xy 398.35497 -28.09546) (xy 398.407856 -28.088006)
			(xy 398.43456 -28.087574) (xy 398.461815 -28.088034) (xy 398.515771 -28.095786) (xy 398.568075 -28.111139)
			(xy 398.617662 -28.133779) (xy 398.625999 -28.139136) (xy 402.697948 -28.139136) (xy 402.702019 -28.083514)
			(xy 402.714145 -28.029077) (xy 402.734068 -27.976986) (xy 402.761364 -27.928351) (xy 402.79545 -27.884208)
			(xy 402.835599 -27.845499) (xy 402.880957 -27.813048) (xy 402.930557 -27.787547) (xy 402.983341 -27.76954)
			(xy 403.038184 -27.75941) (xy 403.093918 -27.757373) (xy 403.149355 -27.763473) (xy 403.203312 -27.777579)
			(xy 403.254641 -27.799391) (xy 403.302247 -27.828445) (xy 403.345115 -27.86412) (xy 403.382332 -27.905657)
			(xy 403.413105 -27.95217) (xy 403.436777 -28.002667) (xy 403.452845 -28.056074) (xy 403.460965 -28.11125)
			(xy 403.461474 -28.139136) (xy 403.967948 -28.139136) (xy 403.972019 -28.083514) (xy 403.984145 -28.029077)
			(xy 404.004068 -27.976986) (xy 404.031364 -27.928351) (xy 404.06545 -27.884208) (xy 404.105599 -27.845499)
			(xy 404.150957 -27.813048) (xy 404.200557 -27.787547) (xy 404.253341 -27.76954) (xy 404.308184 -27.75941)
			(xy 404.363918 -27.757373) (xy 404.419355 -27.763473) (xy 404.473312 -27.777579) (xy 404.524641 -27.799391)
			(xy 404.572247 -27.828445) (xy 404.615115 -27.86412) (xy 404.652332 -27.905657) (xy 404.683105 -27.95217)
			(xy 404.706777 -28.002667) (xy 404.722845 -28.056074) (xy 404.730965 -28.11125) (xy 404.731474 -28.139136)
			(xy 404.730965 -28.167022) (xy 404.722845 -28.222198) (xy 404.706777 -28.275605) (xy 404.683105 -28.326102)
			(xy 404.652332 -28.372615) (xy 404.615115 -28.414152) (xy 404.572247 -28.449827) (xy 404.524641 -28.478881)
			(xy 404.473312 -28.500693) (xy 404.419355 -28.514799) (xy 404.363918 -28.520899) (xy 404.308184 -28.518862)
			(xy 404.253341 -28.508732) (xy 404.200557 -28.490725) (xy 404.150957 -28.465224) (xy 404.105599 -28.432773)
			(xy 404.06545 -28.394064) (xy 404.031364 -28.349921) (xy 404.004068 -28.301286) (xy 403.984145 -28.249195)
			(xy 403.972019 -28.194758) (xy 403.967948 -28.139136) (xy 403.461474 -28.139136) (xy 403.460965 -28.167022)
			(xy 403.452845 -28.222198) (xy 403.436777 -28.275605) (xy 403.413105 -28.326102) (xy 403.382332 -28.372615)
			(xy 403.345115 -28.414152) (xy 403.302247 -28.449827) (xy 403.254641 -28.478881) (xy 403.203312 -28.500693)
			(xy 403.149355 -28.514799) (xy 403.093918 -28.520899) (xy 403.038184 -28.518862) (xy 402.983341 -28.508732)
			(xy 402.930557 -28.490725) (xy 402.880957 -28.465224) (xy 402.835599 -28.432773) (xy 402.79545 -28.394064)
			(xy 402.761364 -28.349921) (xy 402.734068 -28.301286) (xy 402.714145 -28.249195) (xy 402.702019 -28.194758)
			(xy 402.697948 -28.139136) (xy 398.625999 -28.139136) (xy 398.663521 -28.163245) (xy 398.70472 -28.198939)
			(xy 398.74042 -28.240132) (xy 398.769893 -28.285987) (xy 398.792541 -28.33557) (xy 398.807901 -28.387872)
			(xy 398.815662 -28.441827) (xy 398.816068 -28.469082) (xy 398.816322 -28.469082) (xy 398.815864 -28.495947)
			(xy 398.808326 -28.549145) (xy 398.793397 -28.600759) (xy 398.771373 -28.649767) (xy 398.742688 -28.695199)
			(xy 398.725644 -28.71597) (xy 398.723358 -28.71851) (xy 398.718984 -28.725084) (xy 398.714079 -28.740086)
			(xy 398.713706 -28.747974) (xy 398.713706 -28.750768) (xy 398.71523 -28.78201) (xy 398.715484 -28.788614)
			(xy 398.715738 -28.7909) (xy 398.716923 -28.799723) (xy 398.72445 -28.81584) (xy 398.73047 -28.822396)
			(xy 398.817084 -28.908502) (xy 399.032418 -29.12237) (xy 408.90698 -29.12237) (xy 408.90698 -28.25877)
			(xy 408.90747 -28.228802) (xy 408.915293 -28.16938) (xy 408.930806 -28.111487) (xy 408.953742 -28.056114)
			(xy 408.983709 -28.004208) (xy 409.020196 -27.956658) (xy 409.062576 -27.914278) (xy 409.110126 -27.877791)
			(xy 409.162032 -27.847824) (xy 409.217405 -27.824888) (xy 409.275298 -27.809375) (xy 409.33472 -27.801552)
			(xy 409.394656 -27.801552) (xy 409.454078 -27.809375) (xy 409.511971 -27.824888) (xy 409.567344 -27.847824)
			(xy 409.61925 -27.877791) (xy 409.6668 -27.914278) (xy 409.70918 -27.956658) (xy 409.745667 -28.004208)
			(xy 409.775634 -28.056114) (xy 409.79857 -28.111487) (xy 409.814083 -28.16938) (xy 409.821906 -28.228802)
			(xy 409.822396 -28.25877) (xy 409.822396 -29.12237) (xy 409.821906 -29.152338) (xy 409.814083 -29.21176)
			(xy 409.79857 -29.269653) (xy 409.775634 -29.325026) (xy 409.745667 -29.376932) (xy 409.70918 -29.424482)
			(xy 409.6668 -29.466862) (xy 409.61925 -29.503349) (xy 409.567344 -29.533316) (xy 409.511971 -29.556252)
			(xy 409.454078 -29.571765) (xy 409.394656 -29.579588) (xy 409.33472 -29.579588) (xy 409.275298 -29.571765)
			(xy 409.217405 -29.556252) (xy 409.162032 -29.533316) (xy 409.110126 -29.503349) (xy 409.062576 -29.466862)
			(xy 409.020196 -29.424482) (xy 408.983709 -29.376932) (xy 408.953742 -29.325026) (xy 408.930806 -29.269653)
			(xy 408.915293 -29.21176) (xy 408.90747 -29.152338) (xy 408.90698 -29.12237) (xy 399.032418 -29.12237)
			(xy 399.376646 -29.464254) (xy 399.383055 -29.470126) (xy 399.398771 -29.477525) (xy 399.40738 -29.478732)
			(xy 399.416016 -29.479494) (xy 399.433034 -29.475176) (xy 399.440908 -29.469842) (xy 399.44802 -29.465016)
			(xy 399.448528 -29.465016) (xy 399.457926 -29.45892) (xy 399.45818 -29.45892) (xy 399.458942 -29.458412)
			(xy 399.46961 -29.452316) (xy 399.497678 -29.437165) (xy 399.557628 -29.415397) (xy 399.620359 -29.403882)
			(xy 399.652236 -29.402786) (xy 399.664174 -29.402786) (xy 399.69082 -29.403689) (xy 399.743479 -29.412019)
			(xy 399.794466 -29.427598) (xy 399.842788 -29.450124) (xy 399.887504 -29.479156) (xy 399.927743 -29.514131)
			(xy 399.962722 -29.554367) (xy 399.991759 -29.59908) (xy 400.014289 -29.6474) (xy 400.029873 -29.698385)
			(xy 400.038208 -29.751044) (xy 400.039078 -29.77769) (xy 400.039078 -29.786326) (xy 400.038578 -29.810484)
			(xy 400.032208 -29.858381) (xy 400.026378 -29.88183) (xy 400.017521 -29.912914) (xy 399.990829 -29.971773)
			(xy 399.973292 -29.998924) (xy 399.968466 -30.005782) (xy 399.962878 -30.014418) (xy 399.964656 -30.032198)
			(xy 399.965892 -30.040892) (xy 399.973419 -30.056745) (xy 399.979388 -30.063186) (xy 400.294984 -30.376876)
			(xy 401.188936 -30.376876) (xy 401.189496 -30.34796) (xy 401.198214 -30.290791) (xy 401.215463 -30.235592)
			(xy 401.240847 -30.18363) (xy 401.273784 -30.136095) (xy 401.313519 -30.094077) (xy 401.336002 -30.075886)
			(xy 401.344806 -30.068275) (xy 401.354991 -30.047377) (xy 401.35556 -30.035754) (xy 401.35556 -29.955998)
			(xy 401.355022 -29.944366) (xy 401.344834 -29.923455) (xy 401.336002 -29.915866) (xy 401.313503 -29.897694)
			(xy 401.273768 -29.85567) (xy 401.240831 -29.808131) (xy 401.215445 -29.756166) (xy 401.198193 -29.700965)
			(xy 401.189468 -29.643793) (xy 401.188936 -29.614876) (xy 401.189422 -29.587625) (xy 401.197178 -29.533677)
			(xy 401.212533 -29.481382) (xy 401.235175 -29.431805) (xy 401.264641 -29.385955) (xy 401.300332 -29.344764)
			(xy 401.341523 -29.309073) (xy 401.387373 -29.279607) (xy 401.43695 -29.256965) (xy 401.489245 -29.24161)
			(xy 401.543193 -29.233854) (xy 401.597695 -29.233854) (xy 401.651643 -29.24161) (xy 401.703938 -29.256965)
			(xy 401.753515 -29.279607) (xy 401.799365 -29.309073) (xy 401.840556 -29.344764) (xy 401.876247 -29.385955)
			(xy 401.905713 -29.431805) (xy 401.928355 -29.481382) (xy 401.94371 -29.533677) (xy 401.951466 -29.587625)
			(xy 401.951952 -29.614876) (xy 401.951435 -29.643793) (xy 401.942708 -29.700965) (xy 401.925451 -29.756165)
			(xy 401.900059 -29.808127) (xy 401.867115 -29.855661) (xy 401.827372 -29.897677) (xy 401.804886 -29.915866)
			(xy 401.796102 -29.923496) (xy 401.785906 -29.944379) (xy 401.785328 -29.955998) (xy 401.785328 -30.035754)
			(xy 401.785841 -30.047389) (xy 401.796047 -30.068299) (xy 401.804886 -30.075886) (xy 401.82736 -30.094088)
			(xy 401.867096 -30.136105) (xy 401.900037 -30.183638) (xy 401.925427 -30.235597) (xy 401.942685 -30.290793)
			(xy 401.951416 -30.347961) (xy 401.951952 -30.376876) (xy 404.229062 -30.376876) (xy 404.229612 -30.34796)
			(xy 404.238331 -30.290789) (xy 404.255581 -30.23559) (xy 404.280967 -30.183628) (xy 404.313906 -30.136093)
			(xy 404.353644 -30.094076) (xy 404.376128 -30.075886) (xy 404.384936 -30.06828) (xy 404.395118 -30.047378)
			(xy 404.395686 -30.035754) (xy 404.395686 -29.955998) (xy 404.395138 -29.944367) (xy 404.384956 -29.923457)
			(xy 404.376128 -29.915866) (xy 404.353634 -29.897687) (xy 404.313898 -29.855666) (xy 404.28096 -29.808129)
			(xy 404.255573 -29.756165) (xy 404.238319 -29.700965) (xy 404.229594 -29.643793) (xy 404.229062 -29.614876)
			(xy 404.229548 -29.587625) (xy 404.237304 -29.533677) (xy 404.252659 -29.481382) (xy 404.275301 -29.431805)
			(xy 404.304767 -29.385955) (xy 404.340458 -29.344764) (xy 404.381649 -29.309073) (xy 404.427499 -29.279607)
			(xy 404.477076 -29.256965) (xy 404.529371 -29.24161) (xy 404.583319 -29.233854) (xy 404.637821 -29.233854)
			(xy 404.691769 -29.24161) (xy 404.744064 -29.256965) (xy 404.793641 -29.279607) (xy 404.839491 -29.309073)
			(xy 404.880682 -29.344764) (xy 404.916373 -29.385955) (xy 404.945839 -29.431805) (xy 404.968481 -29.481382)
			(xy 404.983836 -29.533677) (xy 404.991592 -29.587625) (xy 404.992078 -29.614876) (xy 404.991551 -29.643793)
			(xy 404.982825 -29.700964) (xy 404.965569 -29.756163) (xy 404.940179 -29.808125) (xy 404.907237 -29.855659)
			(xy 404.867497 -29.897676) (xy 404.845012 -29.915866) (xy 404.836232 -29.9235) (xy 404.826033 -29.94438)
			(xy 404.825454 -29.955998) (xy 404.825454 -30.035754) (xy 404.825957 -30.047391) (xy 404.83617 -30.068301)
			(xy 404.845012 -30.075886) (xy 404.867491 -30.094082) (xy 404.907226 -30.136101) (xy 404.940165 -30.183635)
			(xy 404.965554 -30.235595) (xy 404.982812 -30.290792) (xy 404.991542 -30.34796) (xy 404.992078 -30.376876)
			(xy 404.991592 -30.404127) (xy 404.983836 -30.458075) (xy 404.968481 -30.51037) (xy 404.945839 -30.559947)
			(xy 404.916373 -30.605797) (xy 404.880682 -30.646988) (xy 404.839491 -30.682679) (xy 404.793641 -30.712145)
			(xy 404.744064 -30.734787) (xy 404.691769 -30.750142) (xy 404.637821 -30.757898) (xy 404.583319 -30.757898)
			(xy 404.529371 -30.750142) (xy 404.477076 -30.734787) (xy 404.427499 -30.712145) (xy 404.381649 -30.682679)
			(xy 404.340458 -30.646988) (xy 404.304767 -30.605797) (xy 404.275301 -30.559947) (xy 404.252659 -30.51037)
			(xy 404.237304 -30.458075) (xy 404.229548 -30.404127) (xy 404.229062 -30.376876) (xy 401.951952 -30.376876)
			(xy 401.951466 -30.404127) (xy 401.94371 -30.458075) (xy 401.928355 -30.51037) (xy 401.905713 -30.559947)
			(xy 401.876247 -30.605797) (xy 401.840556 -30.646988) (xy 401.799365 -30.682679) (xy 401.753515 -30.712145)
			(xy 401.703938 -30.734787) (xy 401.651643 -30.750142) (xy 401.597695 -30.757898) (xy 401.543193 -30.757898)
			(xy 401.489245 -30.750142) (xy 401.43695 -30.734787) (xy 401.387373 -30.712145) (xy 401.341523 -30.682679)
			(xy 401.300332 -30.646988) (xy 401.264641 -30.605797) (xy 401.235175 -30.559947) (xy 401.212533 -30.51037)
			(xy 401.197178 -30.458075) (xy 401.189422 -30.404127) (xy 401.188936 -30.376876) (xy 400.294984 -30.376876)
			(xy 400.84389 -30.922468) (xy 407.05278 -30.922468) (xy 407.05278 -30.058868) (xy 407.05327 -30.0289)
			(xy 407.061093 -29.969478) (xy 407.076606 -29.911585) (xy 407.099542 -29.856212) (xy 407.129509 -29.804306)
			(xy 407.165996 -29.756756) (xy 407.208376 -29.714376) (xy 407.255926 -29.677889) (xy 407.307832 -29.647922)
			(xy 407.363205 -29.624986) (xy 407.421098 -29.609473) (xy 407.48052 -29.60165) (xy 407.540456 -29.60165)
			(xy 407.599878 -29.609473) (xy 407.657771 -29.624986) (xy 407.713144 -29.647922) (xy 407.76505 -29.677889)
			(xy 407.8126 -29.714376) (xy 407.85498 -29.756756) (xy 407.891467 -29.804306) (xy 407.921434 -29.856212)
			(xy 407.94437 -29.911585) (xy 407.959883 -29.969478) (xy 407.967706 -30.0289) (xy 407.968196 -30.058868)
			(xy 407.968196 -30.922468) (xy 407.967706 -30.952436) (xy 407.959883 -31.011858) (xy 407.94437 -31.069751)
			(xy 407.921434 -31.125124) (xy 407.891467 -31.17703) (xy 407.85498 -31.22458) (xy 407.8126 -31.26696)
			(xy 407.76505 -31.303447) (xy 407.713144 -31.333414) (xy 407.657771 -31.35635) (xy 407.599878 -31.371863)
			(xy 407.540456 -31.379686) (xy 407.48052 -31.379686) (xy 407.421098 -31.371863) (xy 407.363205 -31.35635)
			(xy 407.307832 -31.333414) (xy 407.255926 -31.303447) (xy 407.208376 -31.26696) (xy 407.165996 -31.22458)
			(xy 407.129509 -31.17703) (xy 407.099542 -31.125124) (xy 407.076606 -31.069751) (xy 407.061093 -31.011858)
			(xy 407.05327 -30.952436) (xy 407.05278 -30.922468) (xy 400.84389 -30.922468) (xy 401.073112 -31.150306)
			(xy 401.101144 -31.178678) (xy 401.153094 -31.239206) (xy 401.200045 -31.303689) (xy 401.221194 -31.337504)
			(xy 401.222972 -31.340298) (xy 401.232878 -31.3563) (xy 401.239969 -31.366193) (xy 401.260919 -31.378514)
			(xy 401.27301 -31.379922) (xy 401.32 -31.380684) (xy 401.328223 -31.380043) (xy 401.343648 -31.374227)
			(xy 401.350226 -31.369254) (xy 401.350988 -31.368746) (xy 401.354036 -31.365952) (xy 401.36191 -31.358078)
			(xy 401.364704 -31.354014) (xy 401.364704 -31.35376) (xy 401.380018 -31.332042) (xy 401.415689 -31.292654)
			(xy 401.456473 -31.258588) (xy 401.501584 -31.230501) (xy 401.55015 -31.208933) (xy 401.601236 -31.194302)
			(xy 401.653857 -31.186888) (xy 401.680426 -31.186374) (xy 401.680934 -31.186374) (xy 401.717002 -31.187898)
			(xy 401.725384 -31.188914) (xy 401.752878 -31.192653) (xy 401.806461 -31.207055) (xy 401.857392 -31.229069)
			(xy 401.904596 -31.258231) (xy 401.947076 -31.293925) (xy 401.983936 -31.335397) (xy 402.014397 -31.381773)
			(xy 402.037817 -31.432073) (xy 402.053701 -31.485236) (xy 402.061715 -31.540139) (xy 402.062188 -31.567882)
			(xy 402.061686 -31.595679) (xy 402.053617 -31.650685) (xy 402.037647 -31.703937) (xy 402.030485 -31.719266)
			(xy 402.585426 -31.719266) (xy 402.589497 -31.663644) (xy 402.601623 -31.609207) (xy 402.621546 -31.557116)
			(xy 402.648842 -31.508481) (xy 402.682928 -31.464338) (xy 402.723077 -31.425629) (xy 402.768435 -31.393178)
			(xy 402.818035 -31.367677) (xy 402.870819 -31.34967) (xy 402.925662 -31.33954) (xy 402.981396 -31.337503)
			(xy 403.036833 -31.343603) (xy 403.09079 -31.357709) (xy 403.142119 -31.379521) (xy 403.189725 -31.408575)
			(xy 403.232593 -31.44425) (xy 403.26981 -31.485787) (xy 403.300583 -31.5323) (xy 403.324255 -31.582797)
			(xy 403.340323 -31.636204) (xy 403.344473 -31.664402) (xy 403.861014 -31.664402) (xy 403.865085 -31.60878)
			(xy 403.877211 -31.554343) (xy 403.897134 -31.502252) (xy 403.92443 -31.453617) (xy 403.958516 -31.409474)
			(xy 403.998665 -31.370765) (xy 404.044023 -31.338314) (xy 404.093623 -31.312813) (xy 404.146407 -31.294806)
			(xy 404.20125 -31.284676) (xy 404.256984 -31.282639) (xy 404.312421 -31.288739) (xy 404.366378 -31.302845)
			(xy 404.417707 -31.324657) (xy 404.465313 -31.353711) (xy 404.508181 -31.389386) (xy 404.545398 -31.430923)
			(xy 404.576171 -31.477436) (xy 404.599843 -31.527933) (xy 404.615911 -31.58134) (xy 404.624031 -31.636516)
			(xy 404.62454 -31.664402) (xy 404.624031 -31.692288) (xy 404.615911 -31.747464) (xy 404.606971 -31.777178)
			(xy 405.126188 -31.777178) (xy 405.130259 -31.721556) (xy 405.142385 -31.667119) (xy 405.162308 -31.615028)
			(xy 405.189604 -31.566393) (xy 405.22369 -31.52225) (xy 405.263839 -31.483541) (xy 405.309197 -31.45109)
			(xy 405.358797 -31.425589) (xy 405.411581 -31.407582) (xy 405.466424 -31.397452) (xy 405.522158 -31.395415)
			(xy 405.577595 -31.401515) (xy 405.631552 -31.415621) (xy 405.682881 -31.437433) (xy 405.730487 -31.466487)
			(xy 405.773355 -31.502162) (xy 405.810572 -31.543699) (xy 405.841345 -31.590212) (xy 405.865017 -31.640709)
			(xy 405.881085 -31.694116) (xy 405.889205 -31.749292) (xy 405.889714 -31.777178) (xy 405.889205 -31.805064)
			(xy 405.881085 -31.86024) (xy 405.865017 -31.913647) (xy 405.841345 -31.964144) (xy 405.810572 -32.010657)
			(xy 405.773355 -32.052194) (xy 405.730487 -32.087869) (xy 405.682881 -32.116923) (xy 405.631552 -32.138735)
			(xy 405.577595 -32.152841) (xy 405.522158 -32.158941) (xy 405.466424 -32.156904) (xy 405.411581 -32.146774)
			(xy 405.358797 -32.128767) (xy 405.309197 -32.103266) (xy 405.263839 -32.070815) (xy 405.22369 -32.032106)
			(xy 405.189604 -31.987963) (xy 405.162308 -31.939328) (xy 405.142385 -31.887237) (xy 405.130259 -31.8328)
			(xy 405.126188 -31.777178) (xy 404.606971 -31.777178) (xy 404.599843 -31.800871) (xy 404.576171 -31.851368)
			(xy 404.545398 -31.897881) (xy 404.508181 -31.939418) (xy 404.465313 -31.975093) (xy 404.417707 -32.004147)
			(xy 404.366378 -32.025959) (xy 404.312421 -32.040065) (xy 404.256984 -32.046165) (xy 404.20125 -32.044128)
			(xy 404.146407 -32.033998) (xy 404.093623 -32.015991) (xy 404.044023 -31.99049) (xy 403.998665 -31.958039)
			(xy 403.958516 -31.91933) (xy 403.92443 -31.875187) (xy 403.897134 -31.826552) (xy 403.877211 -31.774461)
			(xy 403.865085 -31.720024) (xy 403.861014 -31.664402) (xy 403.344473 -31.664402) (xy 403.348443 -31.69138)
			(xy 403.348952 -31.719266) (xy 403.348443 -31.747152) (xy 403.340323 -31.802328) (xy 403.324255 -31.855735)
			(xy 403.300583 -31.906232) (xy 403.26981 -31.952745) (xy 403.232593 -31.994282) (xy 403.189725 -32.029957)
			(xy 403.142119 -32.059011) (xy 403.09079 -32.080823) (xy 403.036833 -32.094929) (xy 402.981396 -32.101029)
			(xy 402.925662 -32.098992) (xy 402.870819 -32.088862) (xy 402.818035 -32.070855) (xy 402.768435 -32.045354)
			(xy 402.723077 -32.012903) (xy 402.682928 -31.974194) (xy 402.648842 -31.930051) (xy 402.621546 -31.881416)
			(xy 402.601623 -31.829325) (xy 402.589497 -31.774888) (xy 402.585426 -31.719266) (xy 402.030485 -31.719266)
			(xy 402.014115 -31.754306) (xy 401.983519 -31.800724) (xy 401.946508 -31.842209) (xy 401.903866 -31.87788)
			(xy 401.856497 -31.906982) (xy 401.805404 -31.928898) (xy 401.751671 -31.943164) (xy 401.724114 -31.94685)
			(xy 401.722082 -31.947104) (xy 401.710541 -31.94952) (xy 401.691352 -31.963173) (xy 401.685252 -31.973266)
			(xy 401.66544 -32.013652) (xy 401.6629 -32.018986) (xy 401.658996 -32.029583) (xy 401.659781 -32.052126)
			(xy 401.664424 -32.06242) (xy 402.067935 -32.722312) (xy 408.90698 -32.722312) (xy 408.90698 -31.858712)
			(xy 408.90747 -31.828744) (xy 408.915293 -31.769322) (xy 408.930806 -31.711429) (xy 408.953742 -31.656056)
			(xy 408.983709 -31.60415) (xy 409.020196 -31.5566) (xy 409.062576 -31.51422) (xy 409.110126 -31.477733)
			(xy 409.162032 -31.447766) (xy 409.217405 -31.42483) (xy 409.275298 -31.409317) (xy 409.33472 -31.401494)
			(xy 409.394656 -31.401494) (xy 409.454078 -31.409317) (xy 409.511971 -31.42483) (xy 409.567344 -31.447766)
			(xy 409.61925 -31.477733) (xy 409.6668 -31.51422) (xy 409.70918 -31.5566) (xy 409.745667 -31.60415)
			(xy 409.775634 -31.656056) (xy 409.79857 -31.711429) (xy 409.814083 -31.769322) (xy 409.821906 -31.828744)
			(xy 409.822396 -31.858712) (xy 409.822396 -32.722312) (xy 409.821906 -32.75228) (xy 409.814083 -32.811702)
			(xy 409.79857 -32.869595) (xy 409.775634 -32.924968) (xy 409.745667 -32.976874) (xy 409.70918 -33.024424)
			(xy 409.6668 -33.066804) (xy 409.61925 -33.103291) (xy 409.567344 -33.133258) (xy 409.511971 -33.156194)
			(xy 409.454078 -33.171707) (xy 409.394656 -33.17953) (xy 409.33472 -33.17953) (xy 409.275298 -33.171707)
			(xy 409.217405 -33.156194) (xy 409.162032 -33.133258) (xy 409.110126 -33.103291) (xy 409.062576 -33.066804)
			(xy 409.020196 -33.024424) (xy 408.983709 -32.976874) (xy 408.953742 -32.924968) (xy 408.930806 -32.869595)
			(xy 408.915293 -32.811702) (xy 408.90747 -32.75228) (xy 408.90698 -32.722312) (xy 402.067935 -32.722312)
			(xy 402.717 -33.783778) (xy 402.719966 -33.788338) (xy 402.727525 -33.796159) (xy 402.731986 -33.799272)
			(xy 402.740114 -33.80486) (xy 402.75129 -33.806892) (xy 402.777931 -33.812036) (xy 402.829516 -33.828857)
			(xy 402.878199 -33.852811) (xy 402.923002 -33.883415) (xy 402.96302 -33.920054) (xy 402.997449 -33.961989)
			(xy 403.025595 -34.008376) (xy 403.04689 -34.05828) (xy 403.060907 -34.110696) (xy 403.067362 -34.164568)
			(xy 403.067266 -34.191702) (xy 403.066758 -34.202116) (xy 403.065795 -34.217806) (xy 403.061596 -34.24896)
			(xy 403.058376 -34.264346) (xy 403.056531 -34.275587) (xy 403.061662 -34.29775) (xy 403.068282 -34.307018)
			(xy 403.240009 -34.52241) (xy 407.05278 -34.52241) (xy 407.05278 -33.65881) (xy 407.05327 -33.628842)
			(xy 407.061093 -33.56942) (xy 407.076606 -33.511527) (xy 407.099542 -33.456154) (xy 407.129509 -33.404248)
			(xy 407.165996 -33.356698) (xy 407.208376 -33.314318) (xy 407.255926 -33.277831) (xy 407.307832 -33.247864)
			(xy 407.363205 -33.224928) (xy 407.421098 -33.209415) (xy 407.48052 -33.201592) (xy 407.540456 -33.201592)
			(xy 407.599878 -33.209415) (xy 407.657771 -33.224928) (xy 407.713144 -33.247864) (xy 407.76505 -33.277831)
			(xy 407.8126 -33.314318) (xy 407.85498 -33.356698) (xy 407.891467 -33.404248) (xy 407.921434 -33.456154)
			(xy 407.94437 -33.511527) (xy 407.959883 -33.56942) (xy 407.967706 -33.628842) (xy 407.968196 -33.65881)
			(xy 407.968196 -34.52241) (xy 407.967706 -34.552378) (xy 407.959883 -34.6118) (xy 407.94437 -34.669693)
			(xy 407.921434 -34.725066) (xy 407.891467 -34.776972) (xy 407.85498 -34.824522) (xy 407.8126 -34.866902)
			(xy 407.76505 -34.903389) (xy 407.713144 -34.933356) (xy 407.657771 -34.956292) (xy 407.599878 -34.971805)
			(xy 407.540456 -34.979628) (xy 407.48052 -34.979628) (xy 407.421098 -34.971805) (xy 407.363205 -34.956292)
			(xy 407.307832 -34.933356) (xy 407.255926 -34.903389) (xy 407.208376 -34.866902) (xy 407.165996 -34.824522)
			(xy 407.129509 -34.776972) (xy 407.099542 -34.725066) (xy 407.076606 -34.669693) (xy 407.061093 -34.6118)
			(xy 407.05327 -34.552378) (xy 407.05278 -34.52241) (xy 403.240009 -34.52241) (xy 403.831941 -35.264852)
			(xy 404.20239 -35.264852) (xy 404.206461 -35.20923) (xy 404.218587 -35.154793) (xy 404.23851 -35.102702)
			(xy 404.265806 -35.054067) (xy 404.299892 -35.009924) (xy 404.340041 -34.971215) (xy 404.385399 -34.938764)
			(xy 404.434999 -34.913263) (xy 404.487783 -34.895256) (xy 404.542626 -34.885126) (xy 404.59836 -34.883089)
			(xy 404.653797 -34.889189) (xy 404.707754 -34.903295) (xy 404.759083 -34.925107) (xy 404.806689 -34.954161)
			(xy 404.849557 -34.989836) (xy 404.886774 -35.031373) (xy 404.917547 -35.077886) (xy 404.941219 -35.128383)
			(xy 404.957287 -35.18179) (xy 404.965407 -35.236966) (xy 404.965916 -35.264852) (xy 404.965407 -35.292738)
			(xy 404.957287 -35.347914) (xy 404.941219 -35.401321) (xy 404.917547 -35.451818) (xy 404.886774 -35.498331)
			(xy 404.849557 -35.539868) (xy 404.806689 -35.575543) (xy 404.759083 -35.604597) (xy 404.707754 -35.626409)
			(xy 404.653797 -35.640515) (xy 404.59836 -35.646615) (xy 404.542626 -35.644578) (xy 404.487783 -35.634448)
			(xy 404.434999 -35.616441) (xy 404.385399 -35.59094) (xy 404.340041 -35.558489) (xy 404.299892 -35.51978)
			(xy 404.265806 -35.475637) (xy 404.23851 -35.427002) (xy 404.218587 -35.374911) (xy 404.206461 -35.320474)
			(xy 404.20239 -35.264852) (xy 403.831941 -35.264852) (xy 404.646835 -36.286948) (xy 405.50033 -36.286948)
			(xy 405.504401 -36.231326) (xy 405.516527 -36.176889) (xy 405.53645 -36.124798) (xy 405.563746 -36.076163)
			(xy 405.597832 -36.03202) (xy 405.637981 -35.993311) (xy 405.683339 -35.96086) (xy 405.732939 -35.935359)
			(xy 405.785723 -35.917352) (xy 405.840566 -35.907222) (xy 405.8963 -35.905185) (xy 405.951737 -35.911285)
			(xy 406.005694 -35.925391) (xy 406.057023 -35.947203) (xy 406.104629 -35.976257) (xy 406.147497 -36.011932)
			(xy 406.184714 -36.053469) (xy 406.215487 -36.099982) (xy 406.239159 -36.150479) (xy 406.255227 -36.203886)
			(xy 406.263347 -36.259062) (xy 406.263856 -36.286948) (xy 406.263347 -36.314834) (xy 406.255227 -36.37001)
			(xy 406.239159 -36.423417) (xy 406.215487 -36.473914) (xy 406.187942 -36.515548) (xy 407.314144 -36.515548)
			(xy 407.318215 -36.459926) (xy 407.330341 -36.405489) (xy 407.350264 -36.353398) (xy 407.37756 -36.304763)
			(xy 407.411646 -36.26062) (xy 407.451795 -36.221911) (xy 407.497153 -36.18946) (xy 407.546753 -36.163959)
			(xy 407.599537 -36.145952) (xy 407.65438 -36.135822) (xy 407.710114 -36.133785) (xy 407.765551 -36.139885)
			(xy 407.819508 -36.153991) (xy 407.870837 -36.175803) (xy 407.918443 -36.204857) (xy 407.961311 -36.240532)
			(xy 407.998528 -36.282069) (xy 408.029301 -36.328582) (xy 408.052973 -36.379079) (xy 408.069041 -36.432486)
			(xy 408.077161 -36.487662) (xy 408.07767 -36.515548) (xy 408.077161 -36.543434) (xy 408.069041 -36.59861)
			(xy 408.068584 -36.60013) (xy 412.298649 -36.60013) (xy 412.302653 -36.512245) (xy 412.314633 -36.425088)
			(xy 412.334488 -36.339381) (xy 412.362055 -36.255836) (xy 412.397105 -36.175143) (xy 412.439347 -36.097971)
			(xy 412.488432 -36.024961) (xy 412.543953 -35.956717) (xy 412.60545 -35.893804) (xy 412.672412 -35.836744)
			(xy 412.744286 -35.78601) (xy 412.820476 -35.742022) (xy 412.90035 -35.705144) (xy 412.983247 -35.675683)
			(xy 413.068479 -35.653881) (xy 413.155341 -35.639921) (xy 413.243112 -35.633917) (xy 413.331066 -35.63592)
			(xy 413.418473 -35.645912) (xy 413.504609 -35.663812) (xy 413.588761 -35.68947) (xy 413.670231 -35.722674)
			(xy 413.748344 -35.763148) (xy 413.822452 -35.810559) (xy 413.891943 -35.864512) (xy 413.905034 -35.876738)
			(xy 419.017194 -35.876738) (xy 419.021265 -35.821116) (xy 419.033391 -35.766679) (xy 419.053314 -35.714588)
			(xy 419.08061 -35.665953) (xy 419.114696 -35.62181) (xy 419.154845 -35.583101) (xy 419.200203 -35.55065)
			(xy 419.249803 -35.525149) (xy 419.302587 -35.507142) (xy 419.35743 -35.497012) (xy 419.413164 -35.494975)
			(xy 419.468601 -35.501075) (xy 419.522558 -35.515181) (xy 419.573887 -35.536993) (xy 419.621493 -35.566047)
			(xy 419.664361 -35.601722) (xy 419.701578 -35.643259) (xy 419.732351 -35.689772) (xy 419.756023 -35.740269)
			(xy 419.772091 -35.793676) (xy 419.780211 -35.848852) (xy 419.78072 -35.876738) (xy 419.780211 -35.904624)
			(xy 419.772091 -35.9598) (xy 419.756023 -36.013207) (xy 419.732351 -36.063704) (xy 419.701578 -36.110217)
			(xy 419.664361 -36.151754) (xy 419.621493 -36.187429) (xy 419.573887 -36.216483) (xy 419.522558 -36.238295)
			(xy 419.468601 -36.252401) (xy 419.413164 -36.258501) (xy 419.35743 -36.256464) (xy 419.302587 -36.246334)
			(xy 419.249803 -36.228327) (xy 419.200203 -36.202826) (xy 419.154845 -36.170375) (xy 419.114696 -36.131666)
			(xy 419.08061 -36.087523) (xy 419.053314 -36.038888) (xy 419.033391 -35.986797) (xy 419.021265 -35.93236)
			(xy 419.017194 -35.876738) (xy 413.905034 -35.876738) (xy 413.956239 -35.92456) (xy 414.014808 -35.990207)
			(xy 414.067165 -36.060907) (xy 414.112877 -36.136076) (xy 414.151563 -36.21509) (xy 414.182904 -36.297295)
			(xy 414.206639 -36.382009) (xy 414.222573 -36.46853) (xy 414.226356 -36.50996) (xy 420.913812 -36.50996)
			(xy 420.917883 -36.454338) (xy 420.930009 -36.399901) (xy 420.949932 -36.34781) (xy 420.977228 -36.299175)
			(xy 421.011314 -36.255032) (xy 421.051463 -36.216323) (xy 421.096821 -36.183872) (xy 421.146421 -36.158371)
			(xy 421.199205 -36.140364) (xy 421.254048 -36.130234) (xy 421.309782 -36.128197) (xy 421.365219 -36.134297)
			(xy 421.419176 -36.148403) (xy 421.470505 -36.170215) (xy 421.518111 -36.199269) (xy 421.560979 -36.234944)
			(xy 421.598196 -36.276481) (xy 421.628969 -36.322994) (xy 421.652641 -36.373491) (xy 421.668709 -36.426898)
			(xy 421.676829 -36.482074) (xy 421.677338 -36.50996) (xy 421.676829 -36.537846) (xy 421.668709 -36.593022)
			(xy 421.652641 -36.646429) (xy 421.628969 -36.696926) (xy 421.598196 -36.743439) (xy 421.560979 -36.784976)
			(xy 421.518111 -36.820651) (xy 421.470505 -36.849705) (xy 421.419176 -36.871517) (xy 421.365219 -36.885623)
			(xy 421.309782 -36.891723) (xy 421.254048 -36.889686) (xy 421.199205 -36.879556) (xy 421.146421 -36.861549)
			(xy 421.096821 -36.836048) (xy 421.051463 -36.803597) (xy 421.011314 -36.764888) (xy 420.977228 -36.720745)
			(xy 420.949932 -36.67211) (xy 420.930009 -36.620019) (xy 420.917883 -36.565582) (xy 420.913812 -36.50996)
			(xy 414.226356 -36.50996) (xy 414.230573 -36.556142) (xy 414.231074 -36.60013) (xy 414.230573 -36.644118)
			(xy 414.222573 -36.73173) (xy 414.206639 -36.818251) (xy 414.182904 -36.902965) (xy 414.151563 -36.98517)
			(xy 414.112877 -37.064184) (xy 414.067165 -37.139353) (xy 414.014808 -37.210053) (xy 413.956239 -37.2757)
			(xy 413.891943 -37.335748) (xy 413.822452 -37.389701) (xy 413.748344 -37.437112) (xy 413.674913 -37.47516)
			(xy 418.059106 -37.47516) (xy 418.063177 -37.419538) (xy 418.075303 -37.365101) (xy 418.095226 -37.31301)
			(xy 418.122522 -37.264375) (xy 418.156608 -37.220232) (xy 418.196757 -37.181523) (xy 418.242115 -37.149072)
			(xy 418.291715 -37.123571) (xy 418.344499 -37.105564) (xy 418.399342 -37.095434) (xy 418.455076 -37.093397)
			(xy 418.510513 -37.099497) (xy 418.56447 -37.113603) (xy 418.615799 -37.135415) (xy 418.663405 -37.164469)
			(xy 418.706273 -37.200144) (xy 418.74349 -37.241681) (xy 418.774263 -37.288194) (xy 418.797935 -37.338691)
			(xy 418.814003 -37.392098) (xy 418.822123 -37.447274) (xy 418.822632 -37.47516) (xy 418.822123 -37.503046)
			(xy 418.814003 -37.558222) (xy 418.797935 -37.611629) (xy 418.774263 -37.662126) (xy 418.77411 -37.662358)
			(xy 420.248332 -37.662358) (xy 420.252403 -37.606736) (xy 420.264529 -37.552299) (xy 420.284452 -37.500208)
			(xy 420.311748 -37.451573) (xy 420.345834 -37.40743) (xy 420.385983 -37.368721) (xy 420.431341 -37.33627)
			(xy 420.480941 -37.310769) (xy 420.533725 -37.292762) (xy 420.588568 -37.282632) (xy 420.644302 -37.280595)
			(xy 420.699739 -37.286695) (xy 420.753696 -37.300801) (xy 420.805025 -37.322613) (xy 420.852631 -37.351667)
			(xy 420.895499 -37.387342) (xy 420.932716 -37.428879) (xy 420.963489 -37.475392) (xy 420.987161 -37.525889)
			(xy 421.003229 -37.579296) (xy 421.011349 -37.634472) (xy 421.011858 -37.662358) (xy 421.011349 -37.690244)
			(xy 421.003229 -37.74542) (xy 420.987161 -37.798827) (xy 420.963489 -37.849324) (xy 420.932716 -37.895837)
			(xy 420.895499 -37.937374) (xy 420.852631 -37.973049) (xy 420.805025 -38.002103) (xy 420.753696 -38.023915)
			(xy 420.699739 -38.038021) (xy 420.644302 -38.044121) (xy 420.588568 -38.042084) (xy 420.533725 -38.031954)
			(xy 420.480941 -38.013947) (xy 420.431341 -37.988446) (xy 420.385983 -37.955995) (xy 420.345834 -37.917286)
			(xy 420.311748 -37.873143) (xy 420.284452 -37.824508) (xy 420.264529 -37.772417) (xy 420.252403 -37.71798)
			(xy 420.248332 -37.662358) (xy 418.77411 -37.662358) (xy 418.74349 -37.708639) (xy 418.706273 -37.750176)
			(xy 418.663405 -37.785851) (xy 418.615799 -37.814905) (xy 418.56447 -37.836717) (xy 418.510513 -37.850823)
			(xy 418.455076 -37.856923) (xy 418.399342 -37.854886) (xy 418.344499 -37.844756) (xy 418.291715 -37.826749)
			(xy 418.242115 -37.801248) (xy 418.196757 -37.768797) (xy 418.156608 -37.730088) (xy 418.122522 -37.685945)
			(xy 418.095226 -37.63731) (xy 418.075303 -37.585219) (xy 418.063177 -37.530782) (xy 418.059106 -37.47516)
			(xy 413.674913 -37.47516) (xy 413.670231 -37.477586) (xy 413.588761 -37.51079) (xy 413.504609 -37.536448)
			(xy 413.418473 -37.554348) (xy 413.331066 -37.56434) (xy 413.243112 -37.566343) (xy 413.155341 -37.560339)
			(xy 413.068479 -37.546379) (xy 412.983247 -37.524577) (xy 412.90035 -37.495116) (xy 412.820476 -37.458238)
			(xy 412.744286 -37.41425) (xy 412.672412 -37.363516) (xy 412.60545 -37.306456) (xy 412.543953 -37.243543)
			(xy 412.488432 -37.175299) (xy 412.439347 -37.102289) (xy 412.397105 -37.025117) (xy 412.362055 -36.944424)
			(xy 412.334488 -36.860879) (xy 412.314633 -36.775172) (xy 412.302653 -36.688015) (xy 412.298649 -36.60013)
			(xy 408.068584 -36.60013) (xy 408.052973 -36.652017) (xy 408.029301 -36.702514) (xy 407.998528 -36.749027)
			(xy 407.961311 -36.790564) (xy 407.918443 -36.826239) (xy 407.870837 -36.855293) (xy 407.819508 -36.877105)
			(xy 407.765551 -36.891211) (xy 407.710114 -36.897311) (xy 407.65438 -36.895274) (xy 407.599537 -36.885144)
			(xy 407.546753 -36.867137) (xy 407.497153 -36.841636) (xy 407.451795 -36.809185) (xy 407.411646 -36.770476)
			(xy 407.37756 -36.726333) (xy 407.350264 -36.677698) (xy 407.330341 -36.625607) (xy 407.318215 -36.57117)
			(xy 407.314144 -36.515548) (xy 406.187942 -36.515548) (xy 406.184714 -36.520427) (xy 406.147497 -36.561964)
			(xy 406.104629 -36.597639) (xy 406.057023 -36.626693) (xy 406.005694 -36.648505) (xy 405.951737 -36.662611)
			(xy 405.8963 -36.668711) (xy 405.840566 -36.666674) (xy 405.785723 -36.656544) (xy 405.732939 -36.638537)
			(xy 405.683339 -36.613036) (xy 405.637981 -36.580585) (xy 405.597832 -36.541876) (xy 405.563746 -36.497733)
			(xy 405.53645 -36.449098) (xy 405.516527 -36.397007) (xy 405.504401 -36.34257) (xy 405.50033 -36.286948)
			(xy 404.646835 -36.286948) (xy 405.53767 -37.404294) (xy 405.667464 -37.566854) (xy 405.675424 -37.57565)
			(xy 405.697004 -37.585439) (xy 405.708866 -37.58565) (xy 405.781256 -37.582856) (xy 405.791416 -37.582602)
			(xy 405.802854 -37.581442) (xy 405.822954 -37.570331) (xy 405.830024 -37.561266) (xy 405.845296 -37.539365)
			(xy 405.880983 -37.499651) (xy 405.921854 -37.465297) (xy 405.967113 -37.436971) (xy 406.015877 -37.415227)
			(xy 406.067195 -37.40049) (xy 406.120066 -37.393046) (xy 406.146762 -37.39261) (xy 406.174016 -37.393071)
			(xy 406.22797 -37.400823) (xy 406.280272 -37.416176) (xy 406.329855 -37.438817) (xy 406.375712 -37.468284)
			(xy 406.416908 -37.503978) (xy 406.452604 -37.545172) (xy 406.482073 -37.591027) (xy 406.504717 -37.64061)
			(xy 406.520072 -37.69291) (xy 406.527828 -37.746864) (xy 406.52827 -37.774118) (xy 406.527756 -37.802749)
			(xy 406.519194 -37.859368) (xy 406.502266 -37.914071) (xy 406.477352 -37.96563) (xy 406.445011 -38.012885)
			(xy 406.40597 -38.054776) (xy 406.361106 -38.090361) (xy 406.311428 -38.11884) (xy 406.284938 -38.129718)
			(xy 406.282144 -38.130734) (xy 406.272161 -38.135999) (xy 406.257669 -38.153266) (xy 406.254204 -38.164008)
			(xy 406.232868 -38.242748) (xy 406.231852 -38.246812) (xy 406.230387 -38.25767) (xy 406.235775 -38.278881)
			(xy 406.242266 -38.287706) (xy 408.619003 -41.268757) (xy 416.143827 -41.268757) (xy 416.143827 -41.214243)
			(xy 416.151586 -41.160284) (xy 416.166945 -41.107978) (xy 416.189593 -41.058391) (xy 416.219068 -41.012532)
			(xy 416.254769 -40.971335) (xy 416.295971 -40.935639) (xy 416.341833 -40.90617) (xy 416.391423 -40.883529)
			(xy 416.443731 -40.868176) (xy 416.497691 -40.860424) (xy 416.524948 -40.859964) (xy 416.553688 -40.860468)
			(xy 416.610515 -40.869097) (xy 416.665406 -40.886152) (xy 416.717117 -40.911248) (xy 416.764479 -40.943816)
			(xy 416.785806 -40.963088) (xy 416.792664 -40.969692) (xy 416.810698 -40.976804) (xy 416.899598 -40.976804)
			(xy 416.917632 -40.969692) (xy 416.92449 -40.963088) (xy 416.945805 -40.943803) (xy 416.993169 -40.911237)
			(xy 417.044884 -40.886146) (xy 417.099778 -40.869099) (xy 417.156608 -40.860482) (xy 417.185348 -40.859964)
			(xy 417.212595 -40.860509) (xy 417.266533 -40.868271) (xy 417.318819 -40.883629) (xy 417.368386 -40.906271)
			(xy 417.414227 -40.935737) (xy 417.455408 -40.971426) (xy 417.491092 -41.012611) (xy 417.520552 -41.058456)
			(xy 417.543188 -41.108026) (xy 417.558539 -41.160313) (xy 417.566294 -41.214253) (xy 417.566294 -41.268747)
			(xy 417.558539 -41.322687) (xy 417.543188 -41.374974) (xy 417.520552 -41.424544) (xy 417.491092 -41.470389)
			(xy 417.455408 -41.511574) (xy 417.414227 -41.547263) (xy 417.368386 -41.576729) (xy 417.318819 -41.599371)
			(xy 417.266533 -41.614729) (xy 417.212595 -41.622491) (xy 417.185348 -41.62298) (xy 417.156609 -41.622467)
			(xy 417.099782 -41.613838) (xy 417.044892 -41.596784) (xy 416.993181 -41.571691) (xy 416.945818 -41.539126)
			(xy 416.92449 -41.519856) (xy 416.917632 -41.513252) (xy 416.899598 -41.50614) (xy 416.810698 -41.50614)
			(xy 416.792664 -41.513252) (xy 416.785806 -41.519856) (xy 416.764499 -41.53915) (xy 416.717132 -41.571714)
			(xy 416.665415 -41.596802) (xy 416.61052 -41.613847) (xy 416.553688 -41.622463) (xy 416.524948 -41.62298)
			(xy 416.497691 -41.622576) (xy 416.443731 -41.614824) (xy 416.391423 -41.599471) (xy 416.341833 -41.57683)
			(xy 416.295971 -41.547361) (xy 416.254769 -41.511665) (xy 416.219068 -41.470468) (xy 416.189593 -41.424609)
			(xy 416.166945 -41.375022) (xy 416.151586 -41.322716) (xy 416.143827 -41.268757) (xy 408.619003 -41.268757)
			(xy 410.242639 -43.305222) (xy 418.60724 -43.305222) (xy 418.607709 -43.277852) (xy 418.615525 -43.223672)
			(xy 418.631013 -43.171169) (xy 418.653854 -43.121422) (xy 418.683579 -43.075455) (xy 418.70122 -43.054524)
			(xy 418.701474 -43.05427) (xy 418.707046 -43.047174) (xy 418.7133 -43.030264) (xy 418.713666 -43.02125)
			(xy 418.713666 -42.954194) (xy 418.713319 -42.945176) (xy 418.707066 -42.928259) (xy 418.701474 -42.921174)
			(xy 418.70122 -42.921174) (xy 418.70122 -42.92092) (xy 418.68358 -42.899989) (xy 418.653868 -42.854016)
			(xy 418.631031 -42.804268) (xy 418.615541 -42.751767) (xy 418.607713 -42.697591) (xy 418.60724 -42.670222)
			(xy 418.607793 -42.641484) (xy 418.616411 -42.584659) (xy 418.633455 -42.529769) (xy 418.65854 -42.478057)
			(xy 418.691097 -42.430693) (xy 418.710364 -42.409364) (xy 418.716968 -42.402506) (xy 418.72408 -42.384472)
			(xy 418.72408 -42.295572) (xy 418.716968 -42.277538) (xy 418.710364 -42.27068) (xy 418.691113 -42.249335)
			(xy 418.658544 -42.201977) (xy 418.633448 -42.150268) (xy 418.616395 -42.09538) (xy 418.607769 -42.038554)
			(xy 418.607767 -41.981078) (xy 418.616388 -41.924251) (xy 418.633437 -41.869361) (xy 418.658528 -41.817651)
			(xy 418.691093 -41.77029) (xy 418.710364 -41.748964) (xy 418.716968 -41.742106) (xy 418.72408 -41.724072)
			(xy 418.72408 -41.635172) (xy 418.716968 -41.617138) (xy 418.710364 -41.61028) (xy 418.691108 -41.58894)
			(xy 418.658539 -41.541582) (xy 418.633443 -41.489874) (xy 418.616389 -41.434986) (xy 418.607763 -41.37816)
			(xy 418.60724 -41.349422) (xy 418.607726 -41.322171) (xy 418.615482 -41.268223) (xy 418.630837 -41.215928)
			(xy 418.653479 -41.166351) (xy 418.682945 -41.120501) (xy 418.718636 -41.07931) (xy 418.759827 -41.043619)
			(xy 418.805677 -41.014153) (xy 418.855254 -40.991511) (xy 418.907549 -40.976156) (xy 418.961497 -40.9684)
			(xy 419.015999 -40.9684) (xy 419.069947 -40.976156) (xy 419.122242 -40.991511) (xy 419.171819 -41.014153)
			(xy 419.217669 -41.043619) (xy 419.25886 -41.07931) (xy 419.294551 -41.120501) (xy 419.324017 -41.166351)
			(xy 419.346659 -41.215928) (xy 419.362014 -41.268223) (xy 419.36977 -41.322171) (xy 419.370256 -41.349422)
			(xy 419.369731 -41.378161) (xy 419.361106 -41.434987) (xy 419.344056 -41.489877) (xy 419.318965 -41.541589)
			(xy 419.286402 -41.588952) (xy 419.267132 -41.61028) (xy 419.260528 -41.617138) (xy 419.253416 -41.635172)
			(xy 419.253416 -41.724072) (xy 419.260528 -41.742106) (xy 419.267132 -41.748964) (xy 419.286422 -41.770273)
			(xy 419.318982 -41.81764) (xy 419.344069 -41.869355) (xy 419.361114 -41.924248) (xy 419.369733 -41.981077)
			(xy 419.369731 -42.038555) (xy 419.361107 -42.095383) (xy 419.344057 -42.150275) (xy 419.318966 -42.201988)
			(xy 419.286402 -42.249352) (xy 419.267132 -42.27068) (xy 419.260528 -42.277538) (xy 419.253416 -42.295572)
			(xy 419.253416 -42.384472) (xy 419.260528 -42.402506) (xy 419.267132 -42.409364) (xy 419.286408 -42.430686)
			(xy 419.318975 -42.478049) (xy 419.344067 -42.529762) (xy 419.361116 -42.584654) (xy 419.369737 -42.641483)
			(xy 419.370256 -42.670222) (xy 419.369814 -42.697593) (xy 419.361992 -42.751774) (xy 419.346498 -42.804278)
			(xy 419.32594 -42.849038) (xy 421.191942 -42.849038) (xy 421.196013 -42.793416) (xy 421.208139 -42.738979)
			(xy 421.228062 -42.686888) (xy 421.255358 -42.638253) (xy 421.289444 -42.59411) (xy 421.329593 -42.555401)
			(xy 421.374951 -42.52295) (xy 421.424551 -42.497449) (xy 421.477335 -42.479442) (xy 421.532178 -42.469312)
			(xy 421.587912 -42.467275) (xy 421.643349 -42.473375) (xy 421.697306 -42.487481) (xy 421.748635 -42.509293)
			(xy 421.796241 -42.538347) (xy 421.839109 -42.574022) (xy 421.876326 -42.615559) (xy 421.907099 -42.662072)
			(xy 421.930771 -42.712569) (xy 421.946839 -42.765976) (xy 421.954959 -42.821152) (xy 421.955468 -42.849038)
			(xy 421.954959 -42.876924) (xy 421.946839 -42.9321) (xy 421.930771 -42.985507) (xy 421.907099 -43.036004)
			(xy 421.876326 -43.082517) (xy 421.839109 -43.124054) (xy 421.796241 -43.159729) (xy 421.748635 -43.188783)
			(xy 421.697306 -43.210595) (xy 421.643349 -43.224701) (xy 421.587912 -43.230801) (xy 421.532178 -43.228764)
			(xy 421.477335 -43.218634) (xy 421.424551 -43.200627) (xy 421.374951 -43.175126) (xy 421.329593 -43.142675)
			(xy 421.289444 -43.103966) (xy 421.255358 -43.059823) (xy 421.228062 -43.011188) (xy 421.208139 -42.959097)
			(xy 421.196013 -42.90466) (xy 421.191942 -42.849038) (xy 419.32594 -42.849038) (xy 419.32365 -42.854024)
			(xy 419.29392 -42.899989) (xy 419.276276 -42.92092) (xy 419.276022 -42.921174) (xy 419.270431 -42.928257)
			(xy 419.264189 -42.945177) (xy 419.26383 -42.954194) (xy 419.26383 -43.02125) (xy 419.264204 -43.030265)
			(xy 419.270439 -43.047183) (xy 419.276022 -43.05427) (xy 419.276276 -43.05427) (xy 419.276276 -43.054524)
			(xy 419.293889 -43.075477) (xy 419.323606 -43.121444) (xy 419.346447 -43.171186) (xy 419.361944 -43.223682)
			(xy 419.369779 -43.277854) (xy 419.370256 -43.305222) (xy 419.36977 -43.332473) (xy 419.362014 -43.386421)
			(xy 419.346659 -43.438716) (xy 419.324017 -43.488293) (xy 419.294551 -43.534143) (xy 419.25886 -43.575334)
			(xy 419.217669 -43.611025) (xy 419.171819 -43.640491) (xy 419.122242 -43.663133) (xy 419.069947 -43.678488)
			(xy 419.015999 -43.686244) (xy 418.961497 -43.686244) (xy 418.907549 -43.678488) (xy 418.855254 -43.663133)
			(xy 418.805677 -43.640491) (xy 418.759827 -43.611025) (xy 418.718636 -43.575334) (xy 418.682945 -43.534143)
			(xy 418.653479 -43.488293) (xy 418.630837 -43.438716) (xy 418.615482 -43.386421) (xy 418.607726 -43.332473)
			(xy 418.60724 -43.305222) (xy 410.242639 -43.305222) (xy 410.586298 -43.73626) (xy 420.513 -43.73626)
			(xy 420.517071 -43.680638) (xy 420.529197 -43.626201) (xy 420.54912 -43.57411) (xy 420.576416 -43.525475)
			(xy 420.610502 -43.481332) (xy 420.650651 -43.442623) (xy 420.696009 -43.410172) (xy 420.745609 -43.384671)
			(xy 420.798393 -43.366664) (xy 420.853236 -43.356534) (xy 420.90897 -43.354497) (xy 420.964407 -43.360597)
			(xy 421.018364 -43.374703) (xy 421.069693 -43.396515) (xy 421.117299 -43.425569) (xy 421.160167 -43.461244)
			(xy 421.197384 -43.502781) (xy 421.228157 -43.549294) (xy 421.236383 -43.566842) (xy 423.63339 -43.566842)
			(xy 423.637461 -43.51122) (xy 423.649587 -43.456783) (xy 423.66951 -43.404692) (xy 423.696806 -43.356057)
			(xy 423.730892 -43.311914) (xy 423.771041 -43.273205) (xy 423.816399 -43.240754) (xy 423.865999 -43.215253)
			(xy 423.918783 -43.197246) (xy 423.973626 -43.187116) (xy 424.02936 -43.185079) (xy 424.084797 -43.191179)
			(xy 424.138754 -43.205285) (xy 424.190083 -43.227097) (xy 424.237689 -43.256151) (xy 424.280557 -43.291826)
			(xy 424.317774 -43.333363) (xy 424.348547 -43.379876) (xy 424.372219 -43.430373) (xy 424.388287 -43.48378)
			(xy 424.396407 -43.538956) (xy 424.396916 -43.566842) (xy 424.396407 -43.594728) (xy 424.388287 -43.649904)
			(xy 424.372219 -43.703311) (xy 424.348547 -43.753808) (xy 424.317774 -43.800321) (xy 424.280557 -43.841858)
			(xy 424.26247 -43.85691) (xy 425.019722 -43.85691) (xy 425.023793 -43.801288) (xy 425.035919 -43.746851)
			(xy 425.055842 -43.69476) (xy 425.083138 -43.646125) (xy 425.117224 -43.601982) (xy 425.157373 -43.563273)
			(xy 425.202731 -43.530822) (xy 425.252331 -43.505321) (xy 425.305115 -43.487314) (xy 425.359958 -43.477184)
			(xy 425.415692 -43.475147) (xy 425.471129 -43.481247) (xy 425.525086 -43.495353) (xy 425.576415 -43.517165)
			(xy 425.624021 -43.546219) (xy 425.666889 -43.581894) (xy 425.704106 -43.623431) (xy 425.734879 -43.669944)
			(xy 425.758551 -43.720441) (xy 425.774619 -43.773848) (xy 425.782739 -43.829024) (xy 425.783248 -43.85691)
			(xy 425.782739 -43.884796) (xy 425.774619 -43.939972) (xy 425.758551 -43.993379) (xy 425.734879 -44.043876)
			(xy 425.704106 -44.090389) (xy 425.666889 -44.131926) (xy 425.624021 -44.167601) (xy 425.576415 -44.196655)
			(xy 425.525086 -44.218467) (xy 425.471129 -44.232573) (xy 425.415692 -44.238673) (xy 425.359958 -44.236636)
			(xy 425.305115 -44.226506) (xy 425.252331 -44.208499) (xy 425.202731 -44.182998) (xy 425.157373 -44.150547)
			(xy 425.117224 -44.111838) (xy 425.083138 -44.067695) (xy 425.055842 -44.01906) (xy 425.035919 -43.966969)
			(xy 425.023793 -43.912532) (xy 425.019722 -43.85691) (xy 424.26247 -43.85691) (xy 424.237689 -43.877533)
			(xy 424.190083 -43.906587) (xy 424.138754 -43.928399) (xy 424.084797 -43.942505) (xy 424.02936 -43.948605)
			(xy 423.973626 -43.946568) (xy 423.918783 -43.936438) (xy 423.865999 -43.918431) (xy 423.816399 -43.89293)
			(xy 423.771041 -43.860479) (xy 423.730892 -43.82177) (xy 423.696806 -43.777627) (xy 423.66951 -43.728992)
			(xy 423.649587 -43.676901) (xy 423.637461 -43.622464) (xy 423.63339 -43.566842) (xy 421.236383 -43.566842)
			(xy 421.251829 -43.599791) (xy 421.267897 -43.653198) (xy 421.276017 -43.708374) (xy 421.276526 -43.73626)
			(xy 421.276017 -43.764146) (xy 421.267897 -43.819322) (xy 421.251829 -43.872729) (xy 421.228157 -43.923226)
			(xy 421.197384 -43.969739) (xy 421.160167 -44.011276) (xy 421.117299 -44.046951) (xy 421.069693 -44.076005)
			(xy 421.018364 -44.097817) (xy 420.964407 -44.111923) (xy 420.90897 -44.118023) (xy 420.853236 -44.115986)
			(xy 420.798393 -44.105856) (xy 420.745609 -44.087849) (xy 420.696009 -44.062348) (xy 420.650651 -44.029897)
			(xy 420.610502 -43.991188) (xy 420.576416 -43.947045) (xy 420.54912 -43.89841) (xy 420.529197 -43.846319)
			(xy 420.517071 -43.791882) (xy 420.513 -43.73626) (xy 410.586298 -43.73626) (xy 411.685114 -45.114464)
			(xy 420.365426 -45.114464) (xy 420.369497 -45.058842) (xy 420.381623 -45.004405) (xy 420.401546 -44.952314)
			(xy 420.428842 -44.903679) (xy 420.462928 -44.859536) (xy 420.503077 -44.820827) (xy 420.548435 -44.788376)
			(xy 420.598035 -44.762875) (xy 420.650819 -44.744868) (xy 420.705662 -44.734738) (xy 420.761396 -44.732701)
			(xy 420.816833 -44.738801) (xy 420.87079 -44.752907) (xy 420.922119 -44.774719) (xy 420.969725 -44.803773)
			(xy 421.012593 -44.839448) (xy 421.042575 -44.87291) (xy 427.233078 -44.87291) (xy 427.237149 -44.817288)
			(xy 427.249275 -44.762851) (xy 427.269198 -44.71076) (xy 427.296494 -44.662125) (xy 427.33058 -44.617982)
			(xy 427.370729 -44.579273) (xy 427.416087 -44.546822) (xy 427.465687 -44.521321) (xy 427.518471 -44.503314)
			(xy 427.573314 -44.493184) (xy 427.629048 -44.491147) (xy 427.684485 -44.497247) (xy 427.738442 -44.511353)
			(xy 427.789771 -44.533165) (xy 427.837377 -44.562219) (xy 427.880245 -44.597894) (xy 427.917462 -44.639431)
			(xy 427.948235 -44.685944) (xy 427.971907 -44.736441) (xy 427.987975 -44.789848) (xy 427.996095 -44.845024)
			(xy 427.996604 -44.87291) (xy 427.996095 -44.900796) (xy 427.987975 -44.955972) (xy 427.971907 -45.009379)
			(xy 427.948235 -45.059876) (xy 427.917462 -45.106389) (xy 427.880245 -45.147926) (xy 427.837377 -45.183601)
			(xy 427.789771 -45.212655) (xy 427.738442 -45.234467) (xy 427.684485 -45.248573) (xy 427.629048 -45.254673)
			(xy 427.573314 -45.252636) (xy 427.518471 -45.242506) (xy 427.465687 -45.224499) (xy 427.416087 -45.198998)
			(xy 427.370729 -45.166547) (xy 427.33058 -45.127838) (xy 427.296494 -45.083695) (xy 427.269198 -45.03506)
			(xy 427.249275 -44.982969) (xy 427.237149 -44.928532) (xy 427.233078 -44.87291) (xy 421.042575 -44.87291)
			(xy 421.04981 -44.880985) (xy 421.080583 -44.927498) (xy 421.104255 -44.977995) (xy 421.120323 -45.031402)
			(xy 421.128443 -45.086578) (xy 421.128952 -45.114464) (xy 421.128443 -45.14235) (xy 421.120323 -45.197526)
			(xy 421.104255 -45.250933) (xy 421.080583 -45.30143) (xy 421.04981 -45.347943) (xy 421.044168 -45.35424)
			(xy 425.00372 -45.35424) (xy 425.007791 -45.298618) (xy 425.019917 -45.244181) (xy 425.03984 -45.19209)
			(xy 425.067136 -45.143455) (xy 425.101222 -45.099312) (xy 425.141371 -45.060603) (xy 425.186729 -45.028152)
			(xy 425.236329 -45.002651) (xy 425.289113 -44.984644) (xy 425.343956 -44.974514) (xy 425.39969 -44.972477)
			(xy 425.455127 -44.978577) (xy 425.509084 -44.992683) (xy 425.560413 -45.014495) (xy 425.608019 -45.043549)
			(xy 425.650887 -45.079224) (xy 425.688104 -45.120761) (xy 425.718877 -45.167274) (xy 425.742549 -45.217771)
			(xy 425.758617 -45.271178) (xy 425.766737 -45.326354) (xy 425.767246 -45.35424) (xy 425.766737 -45.382126)
			(xy 425.758617 -45.437302) (xy 425.742549 -45.490709) (xy 425.718877 -45.541206) (xy 425.688104 -45.587719)
			(xy 425.650887 -45.629256) (xy 425.608019 -45.664931) (xy 425.560413 -45.693985) (xy 425.509084 -45.715797)
			(xy 425.455127 -45.729903) (xy 425.39969 -45.736003) (xy 425.343956 -45.733966) (xy 425.289113 -45.723836)
			(xy 425.236329 -45.705829) (xy 425.186729 -45.680328) (xy 425.141371 -45.647877) (xy 425.101222 -45.609168)
			(xy 425.067136 -45.565025) (xy 425.03984 -45.51639) (xy 425.019917 -45.464299) (xy 425.007791 -45.409862)
			(xy 425.00372 -45.35424) (xy 421.044168 -45.35424) (xy 421.012593 -45.38948) (xy 420.969725 -45.425155)
			(xy 420.922119 -45.454209) (xy 420.87079 -45.476021) (xy 420.816833 -45.490127) (xy 420.761396 -45.496227)
			(xy 420.705662 -45.49419) (xy 420.650819 -45.48406) (xy 420.598035 -45.466053) (xy 420.548435 -45.440552)
			(xy 420.503077 -45.408101) (xy 420.462928 -45.369392) (xy 420.428842 -45.325249) (xy 420.401546 -45.276614)
			(xy 420.381623 -45.224523) (xy 420.369497 -45.170086) (xy 420.365426 -45.114464) (xy 411.685114 -45.114464)
			(xy 412.456675 -46.082204) (xy 418.352478 -46.082204) (xy 418.352981 -46.054953) (xy 418.360737 -46.001007)
			(xy 418.376091 -45.948714) (xy 418.398731 -45.899137) (xy 418.428195 -45.853288) (xy 418.463885 -45.812098)
			(xy 418.505073 -45.776406) (xy 418.550921 -45.746939) (xy 418.600497 -45.724297) (xy 418.65279 -45.708941)
			(xy 418.706736 -45.701183) (xy 418.733986 -45.700696) (xy 418.760888 -45.701169) (xy 418.814158 -45.708739)
			(xy 418.865836 -45.723716) (xy 418.914897 -45.745805) (xy 418.96037 -45.774565) (xy 419.001352 -45.809429)
			(xy 419.03703 -45.849703) (xy 419.052248 -45.871892) (xy 419.05936 -45.882814) (xy 419.08222 -45.894752)
			(xy 419.194488 -45.89272) (xy 419.21684 -45.879766) (xy 419.223698 -45.86859) (xy 419.238634 -45.844998)
			(xy 419.274311 -45.802047) (xy 419.315867 -45.764753) (xy 419.362414 -45.733915) (xy 419.412959 -45.71019)
			(xy 419.466422 -45.694085) (xy 419.521662 -45.685944) (xy 419.54958 -45.685456) (xy 419.576573 -45.685929)
			(xy 419.630021 -45.693532) (xy 419.681864 -45.708589) (xy 419.731069 -45.730801) (xy 419.776653 -45.759723)
			(xy 419.797484 -45.776896) (xy 419.805612 -45.784008) (xy 419.826186 -45.790104) (xy 419.91153 -45.779182)
			(xy 419.922081 -45.777432) (xy 419.940361 -45.76636) (xy 419.946836 -45.757846) (xy 419.962173 -45.736603)
			(xy 419.997763 -45.698151) (xy 420.038283 -45.664933) (xy 420.082969 -45.637576) (xy 420.130979 -45.616595)
			(xy 420.181411 -45.602384) (xy 420.233312 -45.595212) (xy 420.25951 -45.594778) (xy 420.28676 -45.595293)
			(xy 420.340704 -45.60305) (xy 420.392996 -45.618406) (xy 420.44257 -45.641047) (xy 420.488417 -45.670512)
			(xy 420.529605 -45.706202) (xy 420.565294 -45.747391) (xy 420.594758 -45.793239) (xy 420.617398 -45.842813)
			(xy 420.632752 -45.895105) (xy 420.640508 -45.94905) (xy 420.640508 -46.00355) (xy 420.632752 -46.057495)
			(xy 420.617398 -46.109787) (xy 420.594758 -46.159361) (xy 420.565294 -46.205209) (xy 420.529605 -46.246398)
			(xy 420.488417 -46.282088) (xy 420.44257 -46.311553) (xy 420.392996 -46.334194) (xy 420.340704 -46.34955)
			(xy 420.28676 -46.357307) (xy 420.25951 -46.357794) (xy 420.232517 -46.357315) (xy 420.179071 -46.349712)
			(xy 420.127228 -46.334655) (xy 420.078023 -46.312445) (xy 420.032437 -46.283526) (xy 420.011606 -46.266354)
			(xy 420.003478 -46.259242) (xy 419.982904 -46.253146) (xy 419.89756 -46.264068) (xy 419.887025 -46.26588)
			(xy 419.868739 -46.276909) (xy 419.862254 -46.285404) (xy 419.844644 -46.309707) (xy 419.803047 -46.352965)
			(xy 419.77945 -46.37151) (xy 419.771576 -46.377352) (xy 419.761162 -46.394878) (xy 419.747954 -46.485302)
			(xy 419.75278 -46.504606) (xy 419.758622 -46.51248) (xy 419.758622 -46.512734) (xy 419.776119 -46.537483)
			(xy 419.803924 -46.591333) (xy 419.822862 -46.648904) (xy 419.830066 -46.693836) (xy 424.97629 -46.693836)
			(xy 424.976776 -46.666585) (xy 424.984532 -46.612637) (xy 424.999887 -46.560342) (xy 425.022529 -46.510765)
			(xy 425.051995 -46.464915) (xy 425.087686 -46.423724) (xy 425.128877 -46.388033) (xy 425.174727 -46.358567)
			(xy 425.224304 -46.335925) (xy 425.276599 -46.32057) (xy 425.330547 -46.312814) (xy 425.385049 -46.312814)
			(xy 425.438997 -46.32057) (xy 425.491292 -46.335925) (xy 425.540869 -46.358567) (xy 425.586719 -46.388033)
			(xy 425.62791 -46.423724) (xy 425.663601 -46.464915) (xy 425.693067 -46.510765) (xy 425.715709 -46.560342)
			(xy 425.731064 -46.612637) (xy 425.73882 -46.666585) (xy 425.739306 -46.693836) (xy 425.738832 -46.720264)
			(xy 425.731523 -46.772611) (xy 425.71705 -46.823446) (xy 425.695691 -46.871793) (xy 425.682156 -46.894496)
			(xy 425.681902 -46.89475) (xy 425.676565 -46.904768) (xy 425.674306 -46.927319) (xy 425.677584 -46.938184)
			(xy 425.703746 -47.01286) (xy 425.708133 -47.023374) (xy 425.724219 -47.039463) (xy 425.734734 -47.043848)
			(xy 425.734988 -47.043848) (xy 425.759506 -47.052894) (xy 425.805957 -47.076841) (xy 425.848708 -47.106901)
			(xy 425.886958 -47.142512) (xy 425.919993 -47.183008) (xy 425.947196 -47.227631) (xy 425.968056 -47.275549)
			(xy 425.982186 -47.325864) (xy 425.989319 -47.377635) (xy 425.98975 -47.403766) (xy 425.989264 -47.431017)
			(xy 425.987741 -47.441612) (xy 427.26178 -47.441612) (xy 427.265851 -47.38599) (xy 427.277977 -47.331553)
			(xy 427.2979 -47.279462) (xy 427.325196 -47.230827) (xy 427.359282 -47.186684) (xy 427.399431 -47.147975)
			(xy 427.444789 -47.115524) (xy 427.494389 -47.090023) (xy 427.547173 -47.072016) (xy 427.602016 -47.061886)
			(xy 427.65775 -47.059849) (xy 427.713187 -47.065949) (xy 427.767144 -47.080055) (xy 427.818473 -47.101867)
			(xy 427.866079 -47.130921) (xy 427.908947 -47.166596) (xy 427.946164 -47.208133) (xy 427.976937 -47.254646)
			(xy 428.000609 -47.305143) (xy 428.016677 -47.35855) (xy 428.024797 -47.413726) (xy 428.025306 -47.441612)
			(xy 428.024797 -47.469498) (xy 428.016677 -47.524674) (xy 428.000609 -47.578081) (xy 427.976937 -47.628578)
			(xy 427.946164 -47.675091) (xy 427.908947 -47.716628) (xy 427.866079 -47.752303) (xy 427.818473 -47.781357)
			(xy 427.767144 -47.803169) (xy 427.713187 -47.817275) (xy 427.65775 -47.823375) (xy 427.602016 -47.821338)
			(xy 427.547173 -47.811208) (xy 427.494389 -47.793201) (xy 427.444789 -47.7677) (xy 427.399431 -47.735249)
			(xy 427.359282 -47.69654) (xy 427.325196 -47.652397) (xy 427.2979 -47.603762) (xy 427.277977 -47.551671)
			(xy 427.265851 -47.497234) (xy 427.26178 -47.441612) (xy 425.987741 -47.441612) (xy 425.981508 -47.484965)
			(xy 425.966153 -47.53726) (xy 425.943511 -47.586837) (xy 425.914045 -47.632687) (xy 425.878354 -47.673878)
			(xy 425.837163 -47.709569) (xy 425.791313 -47.739035) (xy 425.741736 -47.761677) (xy 425.689441 -47.777032)
			(xy 425.635493 -47.784788) (xy 425.580991 -47.784788) (xy 425.527043 -47.777032) (xy 425.474748 -47.761677)
			(xy 425.425171 -47.739035) (xy 425.379321 -47.709569) (xy 425.33813 -47.673878) (xy 425.302439 -47.632687)
			(xy 425.272973 -47.586837) (xy 425.250331 -47.53726) (xy 425.234976 -47.484965) (xy 425.22722 -47.431017)
			(xy 425.226734 -47.403766) (xy 425.227203 -47.377338) (xy 425.234513 -47.324991) (xy 425.248987 -47.274156)
			(xy 425.270349 -47.225809) (xy 425.283884 -47.203106) (xy 425.284138 -47.202852) (xy 425.289473 -47.192833)
			(xy 425.291732 -47.170283) (xy 425.288456 -47.159418) (xy 425.262294 -47.084742) (xy 425.257934 -47.074214)
			(xy 425.241829 -47.058131) (xy 425.231306 -47.053754) (xy 425.231052 -47.053754) (xy 425.206544 -47.044684)
			(xy 425.160091 -47.020741) (xy 425.117339 -46.990685) (xy 425.079087 -46.955078) (xy 425.046051 -46.914585)
			(xy 425.018847 -46.869964) (xy 424.997985 -46.822049) (xy 424.983855 -46.771736) (xy 424.976721 -46.719966)
			(xy 424.97629 -46.693836) (xy 419.830066 -46.693836) (xy 419.832456 -46.708745) (xy 419.833044 -46.739048)
			(xy 419.832567 -46.766299) (xy 419.824805 -46.820245) (xy 419.809445 -46.872538) (xy 419.786801 -46.922113)
			(xy 419.757333 -46.967961) (xy 419.721641 -47.00915) (xy 419.680451 -47.044841) (xy 419.634602 -47.074307)
			(xy 419.585026 -47.09695) (xy 419.532733 -47.112307) (xy 419.478787 -47.120068) (xy 419.451536 -47.120556)
			(xy 419.425503 -47.120081) (xy 419.373922 -47.113) (xy 419.323781 -47.098976) (xy 419.276009 -47.078272)
			(xy 419.231493 -47.051269) (xy 419.210998 -47.035212) (xy 419.203248 -47.029459) (xy 419.184832 -47.023725)
			(xy 419.175184 -47.024036) (xy 419.095428 -47.030386) (xy 419.077648 -47.039022) (xy 419.071298 -47.046388)
			(xy 419.053141 -47.066057) (xy 419.012228 -47.100577) (xy 418.966894 -47.129043) (xy 418.918028 -47.150897)
			(xy 418.866588 -47.165709) (xy 418.813583 -47.17319) (xy 418.786818 -47.173642) (xy 418.759569 -47.173105)
			(xy 418.705625 -47.165352) (xy 418.653333 -47.150001) (xy 418.603758 -47.127364) (xy 418.557909 -47.097903)
			(xy 418.51672 -47.062217) (xy 418.481028 -47.021032) (xy 418.451561 -46.975187) (xy 418.428917 -46.925616)
			(xy 418.413559 -46.873326) (xy 418.405799 -46.819383) (xy 418.40531 -46.792134) (xy 418.405832 -46.76336)
			(xy 418.414483 -46.706465) (xy 418.43158 -46.651515) (xy 418.456734 -46.599755) (xy 418.489375 -46.552359)
			(xy 418.508688 -46.531022) (xy 418.516054 -46.523148) (xy 418.523166 -46.503336) (xy 418.5158 -46.40707)
			(xy 418.505894 -46.388274) (xy 418.497512 -46.38167) (xy 418.475326 -46.363447) (xy 418.436116 -46.321511)
			(xy 418.403631 -46.274175) (xy 418.378603 -46.222507) (xy 418.361597 -46.167672) (xy 418.352996 -46.110909)
			(xy 418.352478 -46.082204) (xy 412.456675 -46.082204) (xy 412.633668 -46.3042) (xy 412.659478 -46.337246)
			(xy 412.706081 -46.406959) (xy 412.746662 -46.480342) (xy 412.780934 -46.556875) (xy 412.795212 -46.5963)
			(xy 413.394606 -48.30699) (xy 424.85386 -48.30699) (xy 424.857931 -48.251368) (xy 424.870057 -48.196931)
			(xy 424.88998 -48.14484) (xy 424.917276 -48.096205) (xy 424.951362 -48.052062) (xy 424.991511 -48.013353)
			(xy 425.036869 -47.980902) (xy 425.086469 -47.955401) (xy 425.139253 -47.937394) (xy 425.194096 -47.927264)
			(xy 425.24983 -47.925227) (xy 425.305267 -47.931327) (xy 425.359224 -47.945433) (xy 425.410553 -47.967245)
			(xy 425.458159 -47.996299) (xy 425.501027 -48.031974) (xy 425.538244 -48.073511) (xy 425.569017 -48.120024)
			(xy 425.592689 -48.170521) (xy 425.608757 -48.223928) (xy 425.616877 -48.279104) (xy 425.617386 -48.30699)
			(xy 425.616877 -48.334876) (xy 425.608757 -48.390052) (xy 425.592689 -48.443459) (xy 425.569017 -48.493956)
			(xy 425.538244 -48.540469) (xy 425.501027 -48.582006) (xy 425.458159 -48.617681) (xy 425.410553 -48.646735)
			(xy 425.359224 -48.668547) (xy 425.305267 -48.682653) (xy 425.24983 -48.688753) (xy 425.194096 -48.686716)
			(xy 425.139253 -48.676586) (xy 425.086469 -48.658579) (xy 425.036869 -48.633078) (xy 424.991511 -48.600627)
			(xy 424.951362 -48.561918) (xy 424.917276 -48.517775) (xy 424.88998 -48.46914) (xy 424.870057 -48.417049)
			(xy 424.857931 -48.362612) (xy 424.85386 -48.30699) (xy 413.394606 -48.30699) (xy 413.550885 -48.753014)
			(xy 421.468294 -48.753014) (xy 421.472365 -48.697392) (xy 421.484491 -48.642955) (xy 421.504414 -48.590864)
			(xy 421.53171 -48.542229) (xy 421.565796 -48.498086) (xy 421.605945 -48.459377) (xy 421.651303 -48.426926)
			(xy 421.700903 -48.401425) (xy 421.753687 -48.383418) (xy 421.80853 -48.373288) (xy 421.864264 -48.371251)
			(xy 421.919701 -48.377351) (xy 421.973658 -48.391457) (xy 422.024987 -48.413269) (xy 422.072593 -48.442323)
			(xy 422.115461 -48.477998) (xy 422.152678 -48.519535) (xy 422.183451 -48.566048) (xy 422.207123 -48.616545)
			(xy 422.223191 -48.669952) (xy 422.231311 -48.725128) (xy 422.23182 -48.753014) (xy 422.231311 -48.7809)
			(xy 422.223191 -48.836076) (xy 422.220747 -48.8442) (xy 422.487342 -48.8442) (xy 422.491413 -48.788578)
			(xy 422.503539 -48.734141) (xy 422.523462 -48.68205) (xy 422.550758 -48.633415) (xy 422.584844 -48.589272)
			(xy 422.624993 -48.550563) (xy 422.670351 -48.518112) (xy 422.719951 -48.492611) (xy 422.772735 -48.474604)
			(xy 422.827578 -48.464474) (xy 422.883312 -48.462437) (xy 422.938749 -48.468537) (xy 422.992706 -48.482643)
			(xy 423.044035 -48.504455) (xy 423.091641 -48.533509) (xy 423.134509 -48.569184) (xy 423.171726 -48.610721)
			(xy 423.202499 -48.657234) (xy 423.226171 -48.707731) (xy 423.242239 -48.761138) (xy 423.250359 -48.816314)
			(xy 423.250868 -48.8442) (xy 423.250359 -48.872086) (xy 423.247361 -48.89246) (xy 423.51401 -48.89246)
			(xy 423.518081 -48.836838) (xy 423.530207 -48.782401) (xy 423.55013 -48.73031) (xy 423.577426 -48.681675)
			(xy 423.611512 -48.637532) (xy 423.651661 -48.598823) (xy 423.697019 -48.566372) (xy 423.746619 -48.540871)
			(xy 423.799403 -48.522864) (xy 423.854246 -48.512734) (xy 423.90998 -48.510697) (xy 423.965417 -48.516797)
			(xy 424.019374 -48.530903) (xy 424.070703 -48.552715) (xy 424.118309 -48.581769) (xy 424.161177 -48.617444)
			(xy 424.198394 -48.658981) (xy 424.229167 -48.705494) (xy 424.252839 -48.755991) (xy 424.268907 -48.809398)
			(xy 424.277027 -48.864574) (xy 424.277536 -48.89246) (xy 424.277027 -48.920346) (xy 424.274589 -48.93691)
			(xy 427.233078 -48.93691) (xy 427.237149 -48.881288) (xy 427.249275 -48.826851) (xy 427.269198 -48.77476)
			(xy 427.296494 -48.726125) (xy 427.33058 -48.681982) (xy 427.370729 -48.643273) (xy 427.416087 -48.610822)
			(xy 427.465687 -48.585321) (xy 427.518471 -48.567314) (xy 427.573314 -48.557184) (xy 427.629048 -48.555147)
			(xy 427.684485 -48.561247) (xy 427.738442 -48.575353) (xy 427.789771 -48.597165) (xy 427.837377 -48.626219)
			(xy 427.880245 -48.661894) (xy 427.917462 -48.703431) (xy 427.948235 -48.749944) (xy 427.971907 -48.800441)
			(xy 427.987975 -48.853848) (xy 427.996095 -48.909024) (xy 427.996604 -48.93691) (xy 427.996095 -48.964796)
			(xy 427.987975 -49.019972) (xy 427.971907 -49.073379) (xy 427.948235 -49.123876) (xy 427.917462 -49.170389)
			(xy 427.880245 -49.211926) (xy 427.837377 -49.247601) (xy 427.789771 -49.276655) (xy 427.738442 -49.298467)
			(xy 427.684485 -49.312573) (xy 427.629048 -49.318673) (xy 427.573314 -49.316636) (xy 427.518471 -49.306506)
			(xy 427.465687 -49.288499) (xy 427.416087 -49.262998) (xy 427.370729 -49.230547) (xy 427.33058 -49.191838)
			(xy 427.296494 -49.147695) (xy 427.269198 -49.09906) (xy 427.249275 -49.046969) (xy 427.237149 -48.992532)
			(xy 427.233078 -48.93691) (xy 424.274589 -48.93691) (xy 424.268907 -48.975522) (xy 424.252839 -49.028929)
			(xy 424.229167 -49.079426) (xy 424.198394 -49.125939) (xy 424.161177 -49.167476) (xy 424.118309 -49.203151)
			(xy 424.070703 -49.232205) (xy 424.019374 -49.254017) (xy 423.965417 -49.268123) (xy 423.90998 -49.274223)
			(xy 423.854246 -49.272186) (xy 423.799403 -49.262056) (xy 423.746619 -49.244049) (xy 423.697019 -49.218548)
			(xy 423.651661 -49.186097) (xy 423.611512 -49.147388) (xy 423.577426 -49.103245) (xy 423.55013 -49.05461)
			(xy 423.530207 -49.002519) (xy 423.518081 -48.948082) (xy 423.51401 -48.89246) (xy 423.247361 -48.89246)
			(xy 423.242239 -48.927262) (xy 423.226171 -48.980669) (xy 423.202499 -49.031166) (xy 423.171726 -49.077679)
			(xy 423.134509 -49.119216) (xy 423.091641 -49.154891) (xy 423.044035 -49.183945) (xy 422.992706 -49.205757)
			(xy 422.938749 -49.219863) (xy 422.883312 -49.225963) (xy 422.827578 -49.223926) (xy 422.772735 -49.213796)
			(xy 422.719951 -49.195789) (xy 422.670351 -49.170288) (xy 422.624993 -49.137837) (xy 422.584844 -49.099128)
			(xy 422.550758 -49.054985) (xy 422.523462 -49.00635) (xy 422.503539 -48.954259) (xy 422.491413 -48.899822)
			(xy 422.487342 -48.8442) (xy 422.220747 -48.8442) (xy 422.207123 -48.889483) (xy 422.183451 -48.93998)
			(xy 422.152678 -48.986493) (xy 422.115461 -49.02803) (xy 422.072593 -49.063705) (xy 422.024987 -49.092759)
			(xy 421.973658 -49.114571) (xy 421.919701 -49.128677) (xy 421.864264 -49.134777) (xy 421.80853 -49.13274)
			(xy 421.753687 -49.12261) (xy 421.700903 -49.104603) (xy 421.651303 -49.079102) (xy 421.605945 -49.046651)
			(xy 421.565796 -49.007942) (xy 421.53171 -48.963799) (xy 421.504414 -48.915164) (xy 421.484491 -48.863073)
			(xy 421.472365 -48.808636) (xy 421.468294 -48.753014) (xy 413.550885 -48.753014) (xy 413.82188 -49.526444)
			(xy 413.836494 -49.569763) (xy 413.858673 -49.658462) (xy 413.872646 -49.748818) (xy 413.875982 -49.794414)
			(xy 413.919837 -50.502312) (xy 423.116754 -50.502312) (xy 423.120825 -50.44669) (xy 423.132951 -50.392253)
			(xy 423.152874 -50.340162) (xy 423.18017 -50.291527) (xy 423.214256 -50.247384) (xy 423.254405 -50.208675)
			(xy 423.299763 -50.176224) (xy 423.349363 -50.150723) (xy 423.402147 -50.132716) (xy 423.45699 -50.122586)
			(xy 423.512724 -50.120549) (xy 423.568161 -50.126649) (xy 423.622118 -50.140755) (xy 423.673447 -50.162567)
			(xy 423.721053 -50.191621) (xy 423.763921 -50.227296) (xy 423.801138 -50.268833) (xy 423.831911 -50.315346)
			(xy 423.855583 -50.365843) (xy 423.871651 -50.41925) (xy 423.879771 -50.474426) (xy 423.88028 -50.502312)
			(xy 423.879771 -50.530198) (xy 423.871651 -50.585374) (xy 423.855583 -50.638781) (xy 423.831911 -50.689278)
			(xy 423.801138 -50.735791) (xy 423.763921 -50.777328) (xy 423.721053 -50.813003) (xy 423.673447 -50.842057)
			(xy 423.622118 -50.863869) (xy 423.568161 -50.877975) (xy 423.512724 -50.884075) (xy 423.45699 -50.882038)
			(xy 423.402147 -50.871908) (xy 423.349363 -50.853901) (xy 423.299763 -50.8284) (xy 423.254405 -50.795949)
			(xy 423.214256 -50.75724) (xy 423.18017 -50.713097) (xy 423.152874 -50.664462) (xy 423.132951 -50.612371)
			(xy 423.120825 -50.557934) (xy 423.116754 -50.502312) (xy 413.919837 -50.502312) (xy 413.951875 -51.019456)
			(xy 425.04944 -51.019456) (xy 425.053511 -50.963834) (xy 425.065637 -50.909397) (xy 425.08556 -50.857306)
			(xy 425.112856 -50.808671) (xy 425.146942 -50.764528) (xy 425.187091 -50.725819) (xy 425.232449 -50.693368)
			(xy 425.282049 -50.667867) (xy 425.334833 -50.64986) (xy 425.389676 -50.63973) (xy 425.44541 -50.637693)
			(xy 425.500847 -50.643793) (xy 425.554804 -50.657899) (xy 425.606133 -50.679711) (xy 425.653739 -50.708765)
			(xy 425.696607 -50.74444) (xy 425.733824 -50.785977) (xy 425.764597 -50.83249) (xy 425.788269 -50.882987)
			(xy 425.804337 -50.936394) (xy 425.812457 -50.99157) (xy 425.812966 -51.019456) (xy 425.812457 -51.047342)
			(xy 425.804337 -51.102518) (xy 425.788269 -51.155925) (xy 425.764597 -51.206422) (xy 425.733824 -51.252935)
			(xy 425.696607 -51.294472) (xy 425.653739 -51.330147) (xy 425.606133 -51.359201) (xy 425.554804 -51.381013)
			(xy 425.500847 -51.395119) (xy 425.44541 -51.401219) (xy 425.389676 -51.399182) (xy 425.334833 -51.389052)
			(xy 425.282049 -51.371045) (xy 425.232449 -51.345544) (xy 425.187091 -51.313093) (xy 425.146942 -51.274384)
			(xy 425.112856 -51.230241) (xy 425.08556 -51.181606) (xy 425.065637 -51.129515) (xy 425.053511 -51.075078)
			(xy 425.04944 -51.019456) (xy 413.951875 -51.019456) (xy 414.014817 -52.035456) (xy 427.241206 -52.035456)
			(xy 427.245277 -51.979834) (xy 427.257403 -51.925397) (xy 427.277326 -51.873306) (xy 427.304622 -51.824671)
			(xy 427.338708 -51.780528) (xy 427.378857 -51.741819) (xy 427.424215 -51.709368) (xy 427.473815 -51.683867)
			(xy 427.526599 -51.66586) (xy 427.581442 -51.65573) (xy 427.637176 -51.653693) (xy 427.692613 -51.659793)
			(xy 427.74657 -51.673899) (xy 427.797899 -51.695711) (xy 427.845505 -51.724765) (xy 427.888373 -51.76044)
			(xy 427.92559 -51.801977) (xy 427.956363 -51.84849) (xy 427.980035 -51.898987) (xy 427.996103 -51.952394)
			(xy 428.004223 -52.00757) (xy 428.004732 -52.035456) (xy 428.004223 -52.063342) (xy 427.996103 -52.118518)
			(xy 427.980035 -52.171925) (xy 427.956363 -52.222422) (xy 427.92559 -52.268935) (xy 427.888373 -52.310472)
			(xy 427.845505 -52.346147) (xy 427.797899 -52.375201) (xy 427.74657 -52.397013) (xy 427.692613 -52.411119)
			(xy 427.637176 -52.417219) (xy 427.581442 -52.415182) (xy 427.526599 -52.405052) (xy 427.473815 -52.387045)
			(xy 427.424215 -52.361544) (xy 427.378857 -52.329093) (xy 427.338708 -52.290384) (xy 427.304622 -52.246241)
			(xy 427.277326 -52.197606) (xy 427.257403 -52.145515) (xy 427.245277 -52.091078) (xy 427.241206 -52.035456)
			(xy 414.014817 -52.035456) (xy 414.035494 -52.369212) (xy 414.036607 -52.379842) (xy 414.046474 -52.39878)
			(xy 414.054544 -52.405788) (xy 414.097216 -52.439824) (xy 414.10451 -52.445198) (xy 414.121685 -52.450928)
			(xy 414.130744 -52.451) (xy 414.136332 -52.450492) (xy 414.137348 -52.450492) (xy 414.137602 -52.450238)
			(xy 414.137856 -52.450238) (xy 414.139126 -52.449984) (xy 414.154574 -52.447606) (xy 414.185727 -52.445066)
			(xy 414.201356 -52.444904) (xy 414.202118 -52.444904) (xy 414.229368 -52.445392) (xy 414.283313 -52.45315)
			(xy 414.335605 -52.468507) (xy 414.385179 -52.491149) (xy 414.431026 -52.520616) (xy 414.472213 -52.556308)
			(xy 414.507902 -52.597498) (xy 414.537365 -52.643347) (xy 414.560004 -52.692923) (xy 414.575356 -52.745216)
			(xy 414.583111 -52.799162) (xy 414.583626 -52.826412) (xy 414.583201 -52.851923) (xy 414.576406 -52.902491)
			(xy 414.562938 -52.951705) (xy 414.543038 -52.998686) (xy 414.517059 -53.0426) (xy 414.501584 -53.062886)
			(xy 414.499044 -53.065934) (xy 414.498028 -53.067458) (xy 414.494726 -53.074062) (xy 414.492381 -53.079284)
			(xy 414.489814 -53.090438) (xy 414.489646 -53.09616) (xy 414.489646 -53.128164) (xy 414.47847 -53.128164)
			(xy 414.47847 -53.178964) (xy 414.478806 -53.187567) (xy 414.484524 -53.203794) (xy 414.489646 -53.210714)
			(xy 414.490916 -53.212238) (xy 414.508311 -53.233114) (xy 414.53763 -53.278864) (xy 414.560159 -53.328312)
			(xy 414.575441 -53.380457) (xy 414.583167 -53.434243) (xy 414.583626 -53.461412) (xy 414.583201 -53.486923)
			(xy 414.576406 -53.537491) (xy 414.562938 -53.586705) (xy 414.543038 -53.633686) (xy 414.517059 -53.6776)
			(xy 414.501584 -53.697886) (xy 414.499044 -53.700934) (xy 414.498028 -53.702458) (xy 414.494726 -53.709062)
			(xy 414.492381 -53.714284) (xy 414.489814 -53.725438) (xy 414.489646 -53.73116) (xy 414.489646 -53.763164)
			(xy 414.47847 -53.763164) (xy 414.47847 -53.813964) (xy 414.478806 -53.822567) (xy 414.484524 -53.838794)
			(xy 414.489646 -53.845714) (xy 414.490916 -53.847238) (xy 414.508311 -53.868114) (xy 414.53763 -53.913864)
			(xy 414.560159 -53.963312) (xy 414.575441 -54.015457) (xy 414.583167 -54.069243) (xy 414.583626 -54.096412)
			(xy 414.583201 -54.121923) (xy 414.576406 -54.172491) (xy 414.562938 -54.221705) (xy 414.543038 -54.268686)
			(xy 414.517059 -54.3126) (xy 414.501584 -54.332886) (xy 414.499044 -54.335934) (xy 414.498028 -54.337458)
			(xy 414.494726 -54.344062) (xy 414.492381 -54.349284) (xy 414.489814 -54.360438) (xy 414.489646 -54.36616)
			(xy 414.489646 -54.398164) (xy 414.47847 -54.398164) (xy 414.47847 -54.448964) (xy 414.478806 -54.457567)
			(xy 414.484524 -54.473794) (xy 414.489646 -54.480714) (xy 414.490916 -54.482238) (xy 414.508311 -54.503114)
			(xy 414.53763 -54.548864) (xy 414.560159 -54.598312) (xy 414.575441 -54.650457) (xy 414.583167 -54.704243)
			(xy 414.583626 -54.731412) (xy 414.583149 -54.758856) (xy 414.57848 -54.791102) (xy 416.476434 -54.791102)
			(xy 416.476893 -54.763731) (xy 416.484711 -54.709552) (xy 416.500202 -54.657048) (xy 416.523045 -54.607301)
			(xy 416.552772 -54.561335) (xy 416.570414 -54.540404) (xy 416.570668 -54.54015) (xy 416.576248 -54.533059)
			(xy 416.582497 -54.516145) (xy 416.58286 -54.50713) (xy 416.58286 -54.440074) (xy 416.582524 -54.431055)
			(xy 416.576263 -54.414137) (xy 416.570668 -54.407054) (xy 416.570414 -54.407054) (xy 416.570414 -54.4068)
			(xy 416.552776 -54.385865) (xy 416.523052 -54.339898) (xy 416.500207 -54.290152) (xy 416.484711 -54.23765)
			(xy 416.476883 -54.183472) (xy 416.476883 -54.128731) (xy 416.484711 -54.074553) (xy 416.500206 -54.022051)
			(xy 416.52305 -53.972305) (xy 416.552774 -53.926337) (xy 416.570414 -53.905404) (xy 416.570668 -53.90515)
			(xy 416.576248 -53.898059) (xy 416.582497 -53.881145) (xy 416.58286 -53.87213) (xy 416.58286 -53.805074)
			(xy 416.582524 -53.796055) (xy 416.576263 -53.779137) (xy 416.570668 -53.772054) (xy 416.570414 -53.772054)
			(xy 416.570414 -53.7718) (xy 416.552776 -53.750865) (xy 416.523052 -53.704898) (xy 416.500207 -53.655152)
			(xy 416.484711 -53.60265) (xy 416.476883 -53.548472) (xy 416.476883 -53.493731) (xy 416.484711 -53.439553)
			(xy 416.500206 -53.387051) (xy 416.52305 -53.337305) (xy 416.552774 -53.291337) (xy 416.570414 -53.270404)
			(xy 416.570668 -53.27015) (xy 416.576248 -53.263059) (xy 416.582497 -53.246145) (xy 416.58286 -53.23713)
			(xy 416.58286 -53.170074) (xy 416.582524 -53.161055) (xy 416.576263 -53.144137) (xy 416.570668 -53.137054)
			(xy 416.570414 -53.137054) (xy 416.570414 -53.1368) (xy 416.552764 -53.115877) (xy 416.523053 -53.069902)
			(xy 416.500219 -53.020152) (xy 416.484731 -52.967649) (xy 416.476906 -52.913472) (xy 416.476434 -52.886102)
			(xy 416.47692 -52.858851) (xy 416.484676 -52.804903) (xy 416.500031 -52.752608) (xy 416.522673 -52.703031)
			(xy 416.552139 -52.657181) (xy 416.58783 -52.61599) (xy 416.629021 -52.580299) (xy 416.674871 -52.550833)
			(xy 416.724448 -52.528191) (xy 416.776743 -52.512836) (xy 416.830691 -52.50508) (xy 416.885193 -52.50508)
			(xy 416.939141 -52.512836) (xy 416.991436 -52.528191) (xy 417.03054 -52.54605) (xy 421.979596 -52.54605)
			(xy 421.979596 -52.49155) (xy 421.987352 -52.437605) (xy 422.002707 -52.385313) (xy 422.025347 -52.335738)
			(xy 422.054811 -52.28989) (xy 422.090501 -52.248702) (xy 422.131689 -52.213012) (xy 422.177537 -52.183547)
			(xy 422.227111 -52.160907) (xy 422.279403 -52.145553) (xy 422.333348 -52.137796) (xy 422.360598 -52.13731)
			(xy 422.387968 -52.137775) (xy 422.442148 -52.145593) (xy 422.494651 -52.161082) (xy 422.544398 -52.183924)
			(xy 422.590364 -52.213649) (xy 422.611296 -52.23129) (xy 422.61155 -52.231544) (xy 422.618643 -52.237121)
			(xy 422.635555 -52.243372) (xy 422.64457 -52.243736) (xy 422.711626 -52.243736) (xy 422.720643 -52.243384)
			(xy 422.73756 -52.237132) (xy 422.744646 -52.231544) (xy 422.744646 -52.23129) (xy 422.7449 -52.23129)
			(xy 422.765833 -52.213649) (xy 422.811801 -52.183925) (xy 422.861547 -52.161079) (xy 422.914049 -52.145583)
			(xy 422.968227 -52.137754) (xy 423.022969 -52.137754) (xy 423.077147 -52.145583) (xy 423.129649 -52.161079)
			(xy 423.179395 -52.183925) (xy 423.225363 -52.213649) (xy 423.246296 -52.23129) (xy 423.24655 -52.231544)
			(xy 423.253643 -52.237121) (xy 423.270555 -52.243372) (xy 423.27957 -52.243736) (xy 423.346626 -52.243736)
			(xy 423.355643 -52.243384) (xy 423.37256 -52.237132) (xy 423.379646 -52.231544) (xy 423.379646 -52.23129)
			(xy 423.3799 -52.23129) (xy 423.40082 -52.213636) (xy 423.446796 -52.183927) (xy 423.496547 -52.161094)
			(xy 423.54905 -52.145606) (xy 423.603228 -52.137782) (xy 423.630598 -52.13731) (xy 423.657852 -52.137737)
			(xy 423.711806 -52.145494) (xy 423.764107 -52.16085) (xy 423.813689 -52.183494) (xy 423.859545 -52.212963)
			(xy 423.90074 -52.248659) (xy 423.936435 -52.289853) (xy 423.965905 -52.335709) (xy 423.988549 -52.385292)
			(xy 424.003906 -52.437592) (xy 424.011663 -52.491546) (xy 424.011663 -52.546054) (xy 424.005719 -52.587398)
			(xy 425.055282 -52.587398) (xy 425.059353 -52.531776) (xy 425.071479 -52.477339) (xy 425.091402 -52.425248)
			(xy 425.118698 -52.376613) (xy 425.152784 -52.33247) (xy 425.192933 -52.293761) (xy 425.238291 -52.26131)
			(xy 425.287891 -52.235809) (xy 425.340675 -52.217802) (xy 425.395518 -52.207672) (xy 425.451252 -52.205635)
			(xy 425.506689 -52.211735) (xy 425.560646 -52.225841) (xy 425.611975 -52.247653) (xy 425.659581 -52.276707)
			(xy 425.702449 -52.312382) (xy 425.739666 -52.353919) (xy 425.770439 -52.400432) (xy 425.794111 -52.450929)
			(xy 425.810179 -52.504336) (xy 425.817775 -52.555952) (xy 432.883779 -52.555952) (xy 432.883779 -52.501448)
			(xy 432.891536 -52.447499) (xy 432.906892 -52.395203) (xy 432.929535 -52.345625) (xy 432.959002 -52.299774)
			(xy 432.994696 -52.258583) (xy 433.035888 -52.222892) (xy 433.081741 -52.193426) (xy 433.13132 -52.170786)
			(xy 433.183617 -52.155432) (xy 433.237566 -52.147678) (xy 433.264818 -52.147216) (xy 433.292189 -52.147668)
			(xy 433.346369 -52.155488) (xy 433.398872 -52.170981) (xy 433.448619 -52.193826) (xy 433.494585 -52.223553)
			(xy 433.515516 -52.241196) (xy 433.51577 -52.24145) (xy 433.522857 -52.247036) (xy 433.539774 -52.253282)
			(xy 433.54879 -52.253642) (xy 433.615846 -52.253642) (xy 433.624862 -52.253272) (xy 433.64178 -52.247035)
			(xy 433.648866 -52.24145) (xy 433.648866 -52.241196) (xy 433.64912 -52.241196) (xy 433.670071 -52.22358)
			(xy 433.716039 -52.193865) (xy 433.765781 -52.171025) (xy 433.818278 -52.155528) (xy 433.87245 -52.147694)
			(xy 433.899818 -52.147216) (xy 433.92707 -52.147655) (xy 433.981019 -52.155414) (xy 434.033315 -52.170772)
			(xy 434.082893 -52.193415) (xy 434.128744 -52.222884) (xy 434.169935 -52.258578) (xy 434.205627 -52.29977)
			(xy 434.235093 -52.345623) (xy 434.257734 -52.395202) (xy 434.27309 -52.447498) (xy 434.280846 -52.501448)
			(xy 434.280846 -52.555952) (xy 434.27309 -52.609902) (xy 434.257734 -52.662198) (xy 434.235093 -52.711777)
			(xy 434.205627 -52.75763) (xy 434.169935 -52.798822) (xy 434.128744 -52.834516) (xy 434.082893 -52.863985)
			(xy 434.033315 -52.886628) (xy 433.981019 -52.901986) (xy 433.92707 -52.909745) (xy 433.899818 -52.910232)
			(xy 433.872447 -52.909772) (xy 433.818267 -52.901955) (xy 433.765764 -52.886466) (xy 433.716017 -52.863622)
			(xy 433.670051 -52.833895) (xy 433.64912 -52.816252) (xy 433.648866 -52.815998) (xy 433.641765 -52.810433)
			(xy 433.624859 -52.804173) (xy 433.615846 -52.803806) (xy 433.54879 -52.803806) (xy 433.539772 -52.804157)
			(xy 433.522856 -52.810409) (xy 433.51577 -52.815998) (xy 433.51577 -52.816252) (xy 433.515516 -52.816252)
			(xy 433.494583 -52.83389) (xy 433.448611 -52.863603) (xy 433.398864 -52.88644) (xy 433.346363 -52.901932)
			(xy 433.292187 -52.909759) (xy 433.264818 -52.910232) (xy 433.237566 -52.909722) (xy 433.183617 -52.901968)
			(xy 433.13132 -52.886614) (xy 433.081741 -52.863974) (xy 433.035888 -52.834508) (xy 432.994696 -52.798817)
			(xy 432.959002 -52.757626) (xy 432.929535 -52.711775) (xy 432.906892 -52.662197) (xy 432.891536 -52.609901)
			(xy 432.883779 -52.555952) (xy 425.817775 -52.555952) (xy 425.818299 -52.559512) (xy 425.818808 -52.587398)
			(xy 425.818299 -52.615284) (xy 425.810179 -52.67046) (xy 425.794111 -52.723867) (xy 425.770439 -52.774364)
			(xy 425.739666 -52.820877) (xy 425.702449 -52.862414) (xy 425.659581 -52.898089) (xy 425.611975 -52.927143)
			(xy 425.560646 -52.948955) (xy 425.506689 -52.963061) (xy 425.451252 -52.969161) (xy 425.395518 -52.967124)
			(xy 425.340675 -52.956994) (xy 425.287891 -52.938987) (xy 425.238291 -52.913486) (xy 425.192933 -52.881035)
			(xy 425.152784 -52.842326) (xy 425.118698 -52.798183) (xy 425.091402 -52.749548) (xy 425.071479 -52.697457)
			(xy 425.059353 -52.64302) (xy 425.055282 -52.587398) (xy 424.005719 -52.587398) (xy 424.003906 -52.600008)
			(xy 423.988549 -52.652308) (xy 423.965905 -52.701891) (xy 423.936435 -52.747747) (xy 423.90074 -52.788941)
			(xy 423.859545 -52.824637) (xy 423.813689 -52.854106) (xy 423.764107 -52.87675) (xy 423.711806 -52.892106)
			(xy 423.657852 -52.899863) (xy 423.630598 -52.900326) (xy 423.603227 -52.899879) (xy 423.549046 -52.892059)
			(xy 423.496542 -52.876567) (xy 423.446796 -52.85372) (xy 423.40083 -52.82399) (xy 423.3799 -52.806346)
			(xy 423.379646 -52.806092) (xy 423.372551 -52.800518) (xy 423.355641 -52.794264) (xy 423.346626 -52.7939)
			(xy 423.27957 -52.7939) (xy 423.270552 -52.794243) (xy 423.253635 -52.8005) (xy 423.24655 -52.806092)
			(xy 423.246296 -52.806346) (xy 423.225363 -52.823987) (xy 423.179395 -52.853711) (xy 423.129649 -52.876557)
			(xy 423.077147 -52.892053) (xy 423.022969 -52.899882) (xy 422.968227 -52.899882) (xy 422.914049 -52.892053)
			(xy 422.861547 -52.876557) (xy 422.811801 -52.853711) (xy 422.765833 -52.823987) (xy 422.7449 -52.806346)
			(xy 422.744646 -52.806092) (xy 422.737551 -52.800518) (xy 422.720641 -52.794264) (xy 422.711626 -52.7939)
			(xy 422.64457 -52.7939) (xy 422.635552 -52.794243) (xy 422.618635 -52.8005) (xy 422.61155 -52.806092)
			(xy 422.61155 -52.806346) (xy 422.611296 -52.806346) (xy 422.590369 -52.823992) (xy 422.544396 -52.853705)
			(xy 422.494647 -52.87654) (xy 422.442145 -52.892029) (xy 422.387968 -52.899854) (xy 422.360598 -52.900326)
			(xy 422.333348 -52.899804) (xy 422.279403 -52.892047) (xy 422.227111 -52.876693) (xy 422.177537 -52.854053)
			(xy 422.131689 -52.824588) (xy 422.090501 -52.788898) (xy 422.054811 -52.74771) (xy 422.025347 -52.701862)
			(xy 422.002707 -52.652287) (xy 421.987352 -52.599995) (xy 421.979596 -52.54605) (xy 417.03054 -52.54605)
			(xy 417.041013 -52.550833) (xy 417.086863 -52.580299) (xy 417.128054 -52.61599) (xy 417.163745 -52.657181)
			(xy 417.193211 -52.703031) (xy 417.215853 -52.752608) (xy 417.231208 -52.804903) (xy 417.238964 -52.858851)
			(xy 417.23945 -52.886102) (xy 417.238997 -52.913473) (xy 417.231178 -52.967653) (xy 417.215687 -53.020157)
			(xy 417.192842 -53.069903) (xy 417.163113 -53.115869) (xy 417.14547 -53.1368) (xy 417.145216 -53.137054)
			(xy 417.139644 -53.144151) (xy 417.133388 -53.16106) (xy 417.133024 -53.170074) (xy 417.133024 -53.23713)
			(xy 417.133361 -53.246149) (xy 417.139622 -53.263066) (xy 417.145216 -53.27015) (xy 417.14547 -53.27015)
			(xy 417.14547 -53.270404) (xy 417.163113 -53.291335) (xy 417.192838 -53.337303) (xy 417.215683 -53.38705)
			(xy 417.231179 -53.439552) (xy 417.239008 -53.493731) (xy 417.239008 -53.548472) (xy 417.231179 -53.602651)
			(xy 417.215682 -53.655153) (xy 417.192836 -53.7049) (xy 417.163111 -53.750867) (xy 417.14654 -53.77053)
			(xy 417.510722 -53.77053) (xy 417.511254 -53.741613) (xy 417.519979 -53.684443) (xy 417.537233 -53.629244)
			(xy 417.562623 -53.577282) (xy 417.595564 -53.529747) (xy 417.635303 -53.48773) (xy 417.657788 -53.46954)
			(xy 417.666565 -53.461904) (xy 417.676766 -53.441025) (xy 417.677346 -53.429408) (xy 417.677346 -53.349652)
			(xy 417.676839 -53.338016) (xy 417.666629 -53.317105) (xy 417.657788 -53.30952) (xy 417.635312 -53.291321)
			(xy 417.595577 -53.249302) (xy 417.562637 -53.201769) (xy 417.537248 -53.149809) (xy 417.51999 -53.094614)
			(xy 417.511258 -53.037445) (xy 417.510722 -53.00853) (xy 417.511183 -52.981277) (xy 417.518937 -52.927324)
			(xy 417.534291 -52.875024) (xy 417.556932 -52.825442) (xy 417.5864 -52.779587) (xy 417.622094 -52.738394)
			(xy 417.663287 -52.7027) (xy 417.709142 -52.673232) (xy 417.758724 -52.650591) (xy 417.811024 -52.635237)
			(xy 417.864977 -52.627483) (xy 417.89223 -52.627022) (xy 417.918545 -52.627462) (xy 417.970675 -52.634702)
			(xy 418.021318 -52.649026) (xy 418.069517 -52.670163) (xy 418.11436 -52.697714) (xy 418.154998 -52.731158)
			(xy 418.173154 -52.750212) (xy 418.180652 -52.757641) (xy 418.19995 -52.76615) (xy 418.210492 -52.766722)
			(xy 418.285168 -52.766722) (xy 418.295716 -52.766182) (xy 418.315011 -52.757654) (xy 418.322506 -52.750212)
			(xy 418.340668 -52.731163) (xy 418.381296 -52.697705) (xy 418.426135 -52.670144) (xy 418.474334 -52.649005)
			(xy 418.524981 -52.634686) (xy 418.577114 -52.627461) (xy 418.60343 -52.627022) (xy 418.630683 -52.62745)
			(xy 418.684635 -52.635211) (xy 418.736932 -52.650572) (xy 418.786512 -52.673219) (xy 418.832363 -52.702691)
			(xy 418.873554 -52.738388) (xy 418.909245 -52.779585) (xy 418.93871 -52.825441) (xy 418.961349 -52.875024)
			(xy 418.976701 -52.927324) (xy 418.984454 -52.981277) (xy 418.984938 -53.00853) (xy 418.984478 -53.036197)
			(xy 418.982247 -53.051456) (xy 427.241206 -53.051456) (xy 427.245277 -52.995834) (xy 427.257403 -52.941397)
			(xy 427.277326 -52.889306) (xy 427.304622 -52.840671) (xy 427.338708 -52.796528) (xy 427.378857 -52.757819)
			(xy 427.424215 -52.725368) (xy 427.473815 -52.699867) (xy 427.526599 -52.68186) (xy 427.581442 -52.67173)
			(xy 427.637176 -52.669693) (xy 427.692613 -52.675793) (xy 427.74657 -52.689899) (xy 427.797899 -52.711711)
			(xy 427.845505 -52.740765) (xy 427.888373 -52.77644) (xy 427.92559 -52.817977) (xy 427.956363 -52.86449)
			(xy 427.980035 -52.914987) (xy 427.996103 -52.968394) (xy 428.004223 -53.02357) (xy 428.004732 -53.051456)
			(xy 428.004223 -53.079342) (xy 427.996103 -53.134518) (xy 427.980035 -53.187925) (xy 427.956363 -53.238422)
			(xy 427.92559 -53.284935) (xy 427.888373 -53.326472) (xy 427.845505 -53.362147) (xy 427.797899 -53.391201)
			(xy 427.74657 -53.413013) (xy 427.692613 -53.427119) (xy 427.637176 -53.433219) (xy 427.581442 -53.431182)
			(xy 427.526599 -53.421052) (xy 427.473815 -53.403045) (xy 427.424215 -53.377544) (xy 427.378857 -53.345093)
			(xy 427.338708 -53.306384) (xy 427.304622 -53.262241) (xy 427.277326 -53.213606) (xy 427.257403 -53.161515)
			(xy 427.245277 -53.107078) (xy 427.241206 -53.051456) (xy 418.982247 -53.051456) (xy 418.976473 -53.09095)
			(xy 418.960649 -53.143974) (xy 418.937338 -53.194159) (xy 418.907028 -53.240455) (xy 418.870354 -53.28189)
			(xy 418.828083 -53.317599) (xy 418.804852 -53.332634) (xy 418.795162 -53.339255) (xy 418.782724 -53.359128)
			(xy 418.780976 -53.370734) (xy 418.773102 -53.450744) (xy 418.772465 -53.462382) (xy 418.78055 -53.484219)
			(xy 418.788596 -53.492654) (xy 418.78885 -53.492908) (xy 418.807408 -53.511012) (xy 418.83999 -53.551338)
			(xy 418.866808 -53.595707) (xy 418.887365 -53.643301) (xy 418.901283 -53.693242) (xy 418.908304 -53.744608)
			(xy 418.908738 -53.77053) (xy 418.90825 -53.797781) (xy 418.90049 -53.851727) (xy 418.885133 -53.90402)
			(xy 418.862491 -53.953595) (xy 418.833024 -53.999444) (xy 418.797333 -54.040633) (xy 418.756144 -54.076324)
			(xy 418.710295 -54.105791) (xy 418.66072 -54.128433) (xy 418.608427 -54.14379) (xy 418.554481 -54.15155)
			(xy 418.52723 -54.152038) (xy 418.49986 -54.151569) (xy 418.44568 -54.143755) (xy 418.393176 -54.128267)
			(xy 418.343429 -54.105425) (xy 418.297463 -54.0757) (xy 418.276532 -54.058058) (xy 418.276278 -54.057804)
			(xy 418.269202 -54.052203) (xy 418.252277 -54.045965) (xy 418.243258 -54.045612) (xy 418.176202 -54.045612)
			(xy 418.167185 -54.045967) (xy 418.150268 -54.052216) (xy 418.143182 -54.057804) (xy 418.143182 -54.058058)
			(xy 418.142928 -54.058058) (xy 418.121991 -54.075691) (xy 418.07602 -54.105405) (xy 418.026274 -54.128243)
			(xy 417.973774 -54.143735) (xy 417.919599 -54.151564) (xy 417.89223 -54.152038) (xy 417.864981 -54.151494)
			(xy 417.811037 -54.143742) (xy 417.758745 -54.128392) (xy 417.70917 -54.105757) (xy 417.663321 -54.076297)
			(xy 417.622131 -54.040611) (xy 417.586439 -53.999427) (xy 417.556972 -53.953583) (xy 417.534328 -53.904011)
			(xy 417.51897 -53.851722) (xy 417.51121 -53.797779) (xy 417.510722 -53.77053) (xy 417.14654 -53.77053)
			(xy 417.14547 -53.7718) (xy 417.145216 -53.772054) (xy 417.139644 -53.779151) (xy 417.133388 -53.79606)
			(xy 417.133024 -53.805074) (xy 417.133024 -53.87213) (xy 417.133361 -53.881149) (xy 417.139622 -53.898066)
			(xy 417.145216 -53.90515) (xy 417.14547 -53.90515) (xy 417.14547 -53.905404) (xy 417.163113 -53.926335)
			(xy 417.192838 -53.972303) (xy 417.215683 -54.02205) (xy 417.231179 -54.074552) (xy 417.239008 -54.128731)
			(xy 417.239008 -54.183472) (xy 417.231179 -54.237651) (xy 417.215682 -54.290153) (xy 417.20189 -54.320186)
			(xy 419.430454 -54.320186) (xy 419.430899 -54.292815) (xy 419.43872 -54.238634) (xy 419.454213 -54.18613)
			(xy 419.47706 -54.136384) (xy 419.50679 -54.090418) (xy 419.524434 -54.069488) (xy 419.524688 -54.069234)
			(xy 419.530265 -54.062141) (xy 419.536518 -54.045229) (xy 419.53688 -54.036214) (xy 419.53688 -53.969158)
			(xy 419.536499 -53.960143) (xy 419.530269 -53.943226) (xy 419.524688 -53.936138) (xy 419.524434 -53.936138)
			(xy 419.524434 -53.935884) (xy 419.506826 -53.914927) (xy 419.477108 -53.868961) (xy 419.454266 -53.81922)
			(xy 419.438768 -53.766725) (xy 419.430932 -53.712554) (xy 419.430454 -53.685186) (xy 419.43094 -53.657935)
			(xy 419.438696 -53.603987) (xy 419.454051 -53.551692) (xy 419.476693 -53.502115) (xy 419.506159 -53.456265)
			(xy 419.54185 -53.415074) (xy 419.583041 -53.379383) (xy 419.628891 -53.349917) (xy 419.678468 -53.327275)
			(xy 419.730763 -53.31192) (xy 419.784711 -53.304164) (xy 419.839213 -53.304164) (xy 419.893161 -53.31192)
			(xy 419.945456 -53.327275) (xy 419.995033 -53.349917) (xy 420.040883 -53.379383) (xy 420.082074 -53.415074)
			(xy 420.117765 -53.456265) (xy 420.143655 -53.496551) (xy 432.433464 -53.496551) (xy 432.433464 -53.442049)
			(xy 432.44122 -53.388101) (xy 432.456574 -53.335806) (xy 432.479215 -53.286229) (xy 432.50868 -53.240378)
			(xy 432.54437 -53.199187) (xy 432.585559 -53.163494) (xy 432.631408 -53.134026) (xy 432.680984 -53.111383)
			(xy 432.733278 -53.096025) (xy 432.787225 -53.088265) (xy 432.814476 -53.087778) (xy 432.841847 -53.088239)
			(xy 432.896027 -53.096055) (xy 432.948531 -53.111544) (xy 432.998277 -53.134388) (xy 433.044243 -53.164115)
			(xy 433.065174 -53.181758) (xy 433.065428 -53.182012) (xy 433.07253 -53.187576) (xy 433.089435 -53.193836)
			(xy 433.098448 -53.194204) (xy 433.165504 -53.194204) (xy 433.174521 -53.193848) (xy 433.191438 -53.1876)
			(xy 433.198524 -53.182012) (xy 433.198524 -53.181758) (xy 433.198778 -53.181758) (xy 433.219702 -53.164109)
			(xy 433.265678 -53.1344) (xy 433.315427 -53.111566) (xy 433.367929 -53.096077) (xy 433.422106 -53.088251)
			(xy 433.449476 -53.087778) (xy 433.476729 -53.088268) (xy 433.530681 -53.096022) (xy 433.582979 -53.111375)
			(xy 433.632561 -53.134015) (xy 433.678415 -53.163482) (xy 433.719609 -53.199174) (xy 433.755304 -53.240366)
			(xy 433.784773 -53.286218) (xy 433.807417 -53.335798) (xy 433.822773 -53.388096) (xy 433.830531 -53.442047)
			(xy 433.830531 -53.496553) (xy 433.822773 -53.550504) (xy 433.807417 -53.602802) (xy 433.784773 -53.652382)
			(xy 433.755304 -53.698234) (xy 433.719609 -53.739426) (xy 433.678415 -53.775118) (xy 433.632561 -53.804585)
			(xy 433.582979 -53.827225) (xy 433.530681 -53.842578) (xy 433.476729 -53.850332) (xy 433.449476 -53.850794)
			(xy 433.422105 -53.850343) (xy 433.367925 -53.842522) (xy 433.315422 -53.827029) (xy 433.265675 -53.804184)
			(xy 433.219709 -53.774457) (xy 433.198778 -53.756814) (xy 433.198524 -53.75656) (xy 433.191438 -53.750972)
			(xy 433.174521 -53.744727) (xy 433.165504 -53.744368) (xy 433.098448 -53.744368) (xy 433.089434 -53.744755)
			(xy 433.072517 -53.750982) (xy 433.065428 -53.75656) (xy 433.065428 -53.756814) (xy 433.065174 -53.756814)
			(xy 433.044227 -53.774434) (xy 432.998258 -53.804148) (xy 432.948514 -53.826988) (xy 432.896017 -53.842483)
			(xy 432.841844 -53.850317) (xy 432.814476 -53.850794) (xy 432.787225 -53.850335) (xy 432.733278 -53.842575)
			(xy 432.680984 -53.827217) (xy 432.631408 -53.804574) (xy 432.585559 -53.775106) (xy 432.54437 -53.739413)
			(xy 432.50868 -53.698222) (xy 432.479215 -53.652371) (xy 432.456574 -53.602794) (xy 432.44122 -53.550499)
			(xy 432.433464 -53.496551) (xy 420.143655 -53.496551) (xy 420.147231 -53.502115) (xy 420.169873 -53.551692)
			(xy 420.185228 -53.603987) (xy 420.192984 -53.657935) (xy 420.19347 -53.685186) (xy 420.193003 -53.712556)
			(xy 420.185187 -53.766736) (xy 420.169698 -53.819239) (xy 420.146856 -53.868986) (xy 420.117132 -53.914953)
			(xy 420.09949 -53.935884) (xy 420.099236 -53.936138) (xy 420.093662 -53.943233) (xy 420.087409 -53.960143)
			(xy 420.087044 -53.969158) (xy 420.087044 -54.036214) (xy 420.087385 -54.045233) (xy 420.093642 -54.06215)
			(xy 420.099236 -54.069234) (xy 420.09949 -54.069234) (xy 420.09949 -54.069488) (xy 420.117135 -54.090415)
			(xy 420.146847 -54.136389) (xy 420.169682 -54.186138) (xy 420.185171 -54.23864) (xy 420.192997 -54.292816)
			(xy 420.19347 -54.320186) (xy 420.192984 -54.347437) (xy 420.185228 -54.401385) (xy 420.169873 -54.45368)
			(xy 420.147231 -54.503257) (xy 420.117765 -54.549107) (xy 420.082074 -54.590298) (xy 420.040883 -54.625989)
			(xy 419.995033 -54.655455) (xy 419.945456 -54.678097) (xy 419.893161 -54.693452) (xy 419.839213 -54.701208)
			(xy 419.784711 -54.701208) (xy 419.730763 -54.693452) (xy 419.678468 -54.678097) (xy 419.628891 -54.655455)
			(xy 419.583041 -54.625989) (xy 419.54185 -54.590298) (xy 419.506159 -54.549107) (xy 419.476693 -54.503257)
			(xy 419.454051 -54.45368) (xy 419.438696 -54.401385) (xy 419.43094 -54.347437) (xy 419.430454 -54.320186)
			(xy 417.20189 -54.320186) (xy 417.192836 -54.3399) (xy 417.163111 -54.385867) (xy 417.14547 -54.4068)
			(xy 417.145216 -54.407054) (xy 417.139644 -54.414151) (xy 417.133388 -54.43106) (xy 417.133024 -54.440074)
			(xy 417.133024 -54.50713) (xy 417.133361 -54.516149) (xy 417.139622 -54.533066) (xy 417.145216 -54.54015)
			(xy 417.14547 -54.54015) (xy 417.14547 -54.540404) (xy 417.16312 -54.561328) (xy 417.192831 -54.607302)
			(xy 417.215665 -54.657052) (xy 417.231154 -54.709555) (xy 417.238978 -54.763732) (xy 417.239095 -54.770528)
			(xy 420.371016 -54.770528) (xy 420.371495 -54.743158) (xy 420.379309 -54.688979) (xy 420.394795 -54.636476)
			(xy 420.417634 -54.586729) (xy 420.447356 -54.540762) (xy 420.464996 -54.51983) (xy 420.46525 -54.519576)
			(xy 420.470859 -54.512505) (xy 420.477091 -54.495576) (xy 420.477442 -54.486556) (xy 420.477442 -54.4195)
			(xy 420.477097 -54.410482) (xy 420.470843 -54.393564) (xy 420.46525 -54.38648) (xy 420.464996 -54.38648)
			(xy 420.464996 -54.386226) (xy 420.447355 -54.365295) (xy 420.417644 -54.319322) (xy 420.394808 -54.269574)
			(xy 420.379317 -54.217073) (xy 420.37149 -54.162897) (xy 420.371016 -54.135528) (xy 420.371502 -54.108277)
			(xy 420.379258 -54.054329) (xy 420.394613 -54.002034) (xy 420.417255 -53.952457) (xy 420.446721 -53.906607)
			(xy 420.482412 -53.865416) (xy 420.523603 -53.829725) (xy 420.569453 -53.800259) (xy 420.61903 -53.777617)
			(xy 420.671325 -53.762262) (xy 420.725273 -53.754506) (xy 420.779775 -53.754506) (xy 420.833723 -53.762262)
			(xy 420.886018 -53.777617) (xy 420.935595 -53.800259) (xy 420.981445 -53.829725) (xy 421.022636 -53.865416)
			(xy 421.058327 -53.906607) (xy 421.087793 -53.952457) (xy 421.092868 -53.96357) (xy 425.072046 -53.96357)
			(xy 425.076117 -53.907948) (xy 425.088243 -53.853511) (xy 425.108166 -53.80142) (xy 425.135462 -53.752785)
			(xy 425.169548 -53.708642) (xy 425.209697 -53.669933) (xy 425.255055 -53.637482) (xy 425.304655 -53.611981)
			(xy 425.357439 -53.593974) (xy 425.412282 -53.583844) (xy 425.468016 -53.581807) (xy 425.523453 -53.587907)
			(xy 425.57741 -53.602013) (xy 425.628739 -53.623825) (xy 425.676345 -53.652879) (xy 425.719213 -53.688554)
			(xy 425.75643 -53.730091) (xy 425.787203 -53.776604) (xy 425.810875 -53.827101) (xy 425.826943 -53.880508)
			(xy 425.835063 -53.935684) (xy 425.835572 -53.96357) (xy 425.835063 -53.991456) (xy 425.826943 -54.046632)
			(xy 425.810875 -54.100039) (xy 425.787203 -54.150536) (xy 425.75643 -54.197049) (xy 425.719213 -54.238586)
			(xy 425.676345 -54.274261) (xy 425.628739 -54.303315) (xy 425.57741 -54.325127) (xy 425.523453 -54.339233)
			(xy 425.468016 -54.345333) (xy 425.412282 -54.343296) (xy 425.357439 -54.333166) (xy 425.304655 -54.315159)
			(xy 425.255055 -54.289658) (xy 425.209697 -54.257207) (xy 425.169548 -54.218498) (xy 425.135462 -54.174355)
			(xy 425.108166 -54.12572) (xy 425.088243 -54.073629) (xy 425.076117 -54.019192) (xy 425.072046 -53.96357)
			(xy 421.092868 -53.96357) (xy 421.110435 -54.002034) (xy 421.12579 -54.054329) (xy 421.133546 -54.108277)
			(xy 421.134032 -54.135528) (xy 421.133599 -54.1629) (xy 421.125776 -54.217081) (xy 421.11028 -54.269585)
			(xy 421.08743 -54.319331) (xy 421.057697 -54.365296) (xy 421.040052 -54.386226) (xy 421.039798 -54.38648)
			(xy 421.034213 -54.393568) (xy 421.027966 -54.410484) (xy 421.027606 -54.4195) (xy 421.027606 -54.486556)
			(xy 421.027983 -54.495571) (xy 421.034217 -54.512488) (xy 421.039798 -54.519576) (xy 421.040052 -54.519576)
			(xy 421.040052 -54.51983) (xy 421.057664 -54.540784) (xy 421.087382 -54.58675) (xy 421.110224 -54.636492)
			(xy 421.125721 -54.688988) (xy 421.133555 -54.74316) (xy 421.134032 -54.770528) (xy 421.133546 -54.797779)
			(xy 421.12579 -54.851727) (xy 421.110435 -54.904022) (xy 421.087793 -54.953599) (xy 421.065009 -54.989051)
			(xy 430.201068 -54.989051) (xy 430.201068 -54.934549) (xy 430.208824 -54.880603) (xy 430.224178 -54.828309)
			(xy 430.246817 -54.778733) (xy 430.276281 -54.732882) (xy 430.311971 -54.691692) (xy 430.353158 -54.655999)
			(xy 430.399006 -54.626532) (xy 430.448581 -54.603888) (xy 430.500874 -54.58853) (xy 430.554819 -54.58077)
			(xy 430.58207 -54.580282) (xy 430.610161 -54.580801) (xy 430.665737 -54.589023) (xy 430.719505 -54.60531)
			(xy 430.770303 -54.629309) (xy 430.81703 -54.6605) (xy 430.858675 -54.698209) (xy 430.894339 -54.741619)
			(xy 430.909222 -54.765448) (xy 430.914556 -54.774338) (xy 430.931574 -54.78653) (xy 431.024792 -54.80685)
			(xy 431.045366 -54.802532) (xy 431.054002 -54.79669) (xy 431.078063 -54.780686) (xy 431.129996 -54.755344)
			(xy 431.185154 -54.73812) (xy 431.242279 -54.729406) (xy 431.271172 -54.728872) (xy 431.298423 -54.729381)
			(xy 431.352371 -54.737134) (xy 431.404667 -54.752485) (xy 431.454246 -54.775123) (xy 431.500098 -54.804586)
			(xy 431.541291 -54.840275) (xy 431.576985 -54.881463) (xy 431.606454 -54.927312) (xy 431.629098 -54.976888)
			(xy 431.644456 -55.029182) (xy 431.652215 -55.083129) (xy 431.65268 -55.11038) (xy 431.652207 -55.13775)
			(xy 431.644392 -55.191929) (xy 431.628904 -55.244432) (xy 431.606064 -55.294179) (xy 431.576341 -55.340146)
			(xy 431.5587 -55.361078) (xy 431.558446 -55.361332) (xy 431.552875 -55.368429) (xy 431.54662 -55.385338)
			(xy 431.546254 -55.394352) (xy 431.546254 -55.461408) (xy 431.546596 -55.470427) (xy 431.552853 -55.487344)
			(xy 431.558446 -55.494428) (xy 431.5587 -55.494428) (xy 431.5587 -55.494682) (xy 431.57632 -55.515631)
			(xy 431.606044 -55.561597) (xy 431.628888 -55.61134) (xy 431.644385 -55.66384) (xy 431.652215 -55.718016)
			(xy 431.652217 -55.772754) (xy 431.644392 -55.826931) (xy 431.628899 -55.879431) (xy 431.606058 -55.929177)
			(xy 431.576338 -55.975145) (xy 431.5587 -55.996078) (xy 431.558446 -55.996332) (xy 431.552875 -56.003429)
			(xy 431.54662 -56.020338) (xy 431.546254 -56.029352) (xy 431.546254 -56.096408) (xy 431.546596 -56.105427)
			(xy 431.552853 -56.122344) (xy 431.558446 -56.129428) (xy 431.5587 -56.129428) (xy 431.5587 -56.129682)
			(xy 431.576344 -56.15061) (xy 431.606055 -56.196584) (xy 431.62889 -56.246332) (xy 431.64438 -56.298834)
			(xy 431.652207 -56.353011) (xy 431.65268 -56.38038) (xy 431.652194 -56.407631) (xy 431.644438 -56.461579)
			(xy 431.629083 -56.513874) (xy 431.606441 -56.563451) (xy 431.576975 -56.609301) (xy 431.541284 -56.650492)
			(xy 431.500093 -56.686183) (xy 431.454243 -56.715649) (xy 431.404666 -56.738291) (xy 431.352371 -56.753646)
			(xy 431.298423 -56.761402) (xy 431.243921 -56.761402) (xy 431.189973 -56.753646) (xy 431.137678 -56.738291)
			(xy 431.088101 -56.715649) (xy 431.042251 -56.686183) (xy 431.00106 -56.650492) (xy 430.965369 -56.609301)
			(xy 430.935903 -56.563451) (xy 430.913261 -56.513874) (xy 430.897906 -56.461579) (xy 430.89015 -56.407631)
			(xy 430.889664 -56.38038) (xy 430.890103 -56.353009) (xy 430.897925 -56.298828) (xy 430.913419 -56.246324)
			(xy 430.936268 -56.196577) (xy 430.965999 -56.150612) (xy 430.983644 -56.129682) (xy 430.983898 -56.129428)
			(xy 430.989479 -56.122337) (xy 430.995729 -56.105424) (xy 430.99609 -56.096408) (xy 430.99609 -56.029352)
			(xy 430.99571 -56.020337) (xy 430.989479 -56.00342) (xy 430.983898 -55.996332) (xy 430.983644 -55.996332)
			(xy 430.983644 -55.996078) (xy 430.965983 -55.975161) (xy 430.936258 -55.929191) (xy 430.913412 -55.879442)
			(xy 430.897917 -55.826938) (xy 430.89009 -55.772757) (xy 430.890092 -55.718013) (xy 430.897923 -55.663833)
			(xy 430.913423 -55.611329) (xy 430.936272 -55.561582) (xy 430.966001 -55.515614) (xy 430.983644 -55.494682)
			(xy 430.983898 -55.494428) (xy 430.989479 -55.487337) (xy 430.995729 -55.470424) (xy 430.99609 -55.461408)
			(xy 430.99609 -55.394352) (xy 430.99571 -55.385337) (xy 430.989479 -55.36842) (xy 430.983898 -55.361332)
			(xy 430.983644 -55.360824) (xy 430.972697 -55.348092) (xy 430.952858 -55.320999) (xy 430.94402 -55.306722)
			(xy 430.938686 -55.297832) (xy 430.921668 -55.28564) (xy 430.82845 -55.26532) (xy 430.807876 -55.269638)
			(xy 430.79924 -55.27548) (xy 430.775165 -55.291463) (xy 430.723238 -55.31681) (xy 430.668083 -55.334041)
			(xy 430.610962 -55.342761) (xy 430.58207 -55.343298) (xy 430.554819 -55.34283) (xy 430.500874 -55.33507)
			(xy 430.448581 -55.319712) (xy 430.399006 -55.297068) (xy 430.353158 -55.267601) (xy 430.311971 -55.231908)
			(xy 430.276281 -55.190718) (xy 430.246817 -55.144867) (xy 430.224178 -55.095291) (xy 430.208824 -55.042997)
			(xy 430.201068 -54.989051) (xy 421.065009 -54.989051) (xy 421.058327 -54.999449) (xy 421.022636 -55.04064)
			(xy 420.981445 -55.076331) (xy 420.935595 -55.105797) (xy 420.886018 -55.128439) (xy 420.833723 -55.143794)
			(xy 420.779775 -55.15155) (xy 420.725273 -55.15155) (xy 420.671325 -55.143794) (xy 420.61903 -55.128439)
			(xy 420.569453 -55.105797) (xy 420.523603 -55.076331) (xy 420.482412 -55.04064) (xy 420.446721 -54.999449)
			(xy 420.417255 -54.953599) (xy 420.394613 -54.904022) (xy 420.379258 -54.851727) (xy 420.371502 -54.797779)
			(xy 420.371016 -54.770528) (xy 417.239095 -54.770528) (xy 417.23945 -54.791102) (xy 417.238964 -54.818353)
			(xy 417.231208 -54.872301) (xy 417.215853 -54.924596) (xy 417.193211 -54.974173) (xy 417.163745 -55.020023)
			(xy 417.128054 -55.061214) (xy 417.086863 -55.096905) (xy 417.041013 -55.126371) (xy 416.991436 -55.149013)
			(xy 416.939141 -55.164368) (xy 416.885193 -55.172124) (xy 416.830691 -55.172124) (xy 416.776743 -55.164368)
			(xy 416.724448 -55.149013) (xy 416.674871 -55.126371) (xy 416.629021 -55.096905) (xy 416.58783 -55.061214)
			(xy 416.552139 -55.020023) (xy 416.522673 -54.974173) (xy 416.500031 -54.924596) (xy 416.484676 -54.872301)
			(xy 416.47692 -54.818353) (xy 416.476434 -54.791102) (xy 414.57848 -54.791102) (xy 414.575283 -54.813179)
			(xy 414.559717 -54.865814) (xy 414.53677 -54.915676) (xy 414.506916 -54.961736) (xy 414.470771 -55.003044)
			(xy 414.429082 -55.038747) (xy 414.382707 -55.06811) (xy 414.332604 -55.090525) (xy 414.279806 -55.105532)
			(xy 414.252664 -55.109618) (xy 414.246568 -55.11038) (xy 414.242758 -55.110888) (xy 414.226248 -55.120286)
			(xy 414.220152 -55.127652) (xy 414.214413 -55.135276) (xy 414.208538 -55.153417) (xy 414.208722 -55.162958)
			(xy 414.243266 -55.721758) (xy 414.243297 -55.722266) (xy 426.13402 -55.722266) (xy 426.138091 -55.666644)
			(xy 426.150217 -55.612207) (xy 426.17014 -55.560116) (xy 426.197436 -55.511481) (xy 426.231522 -55.467338)
			(xy 426.271671 -55.428629) (xy 426.317029 -55.396178) (xy 426.366629 -55.370677) (xy 426.419413 -55.35267)
			(xy 426.474256 -55.34254) (xy 426.52999 -55.340503) (xy 426.585427 -55.346603) (xy 426.639384 -55.360709)
			(xy 426.690713 -55.382521) (xy 426.738319 -55.411575) (xy 426.749465 -55.420851) (xy 428.524668 -55.420851)
			(xy 428.524668 -55.366349) (xy 428.532424 -55.312403) (xy 428.547778 -55.260109) (xy 428.570417 -55.210533)
			(xy 428.599881 -55.164682) (xy 428.635571 -55.123492) (xy 428.676758 -55.087799) (xy 428.722606 -55.058332)
			(xy 428.772181 -55.035688) (xy 428.824474 -55.02033) (xy 428.878419 -55.01257) (xy 428.90567 -55.012082)
			(xy 428.931985 -55.012509) (xy 428.984115 -55.019753) (xy 429.034759 -55.03408) (xy 429.082957 -55.05522)
			(xy 429.1278 -55.082773) (xy 429.168438 -55.116218) (xy 429.186594 -55.135272) (xy 429.19412 -55.142669)
			(xy 429.213396 -55.151197) (xy 429.223932 -55.151782) (xy 429.298608 -55.151782) (xy 429.30916 -55.151276)
			(xy 429.328456 -55.142725) (xy 429.335946 -55.135272) (xy 429.354081 -55.116196) (xy 429.394716 -55.082742)
			(xy 429.43956 -55.055186) (xy 429.487765 -55.034051) (xy 429.538416 -55.019738) (xy 429.590553 -55.012518)
			(xy 429.61687 -55.012082) (xy 429.644124 -55.012563) (xy 429.698076 -55.020317) (xy 429.750376 -55.03567)
			(xy 429.799959 -55.05831) (xy 429.845815 -55.087776) (xy 429.88701 -55.123469) (xy 429.922706 -55.164661)
			(xy 429.952176 -55.210515) (xy 429.97482 -55.260095) (xy 429.990177 -55.312394) (xy 429.997935 -55.366347)
			(xy 429.997935 -55.420854) (xy 429.990177 -55.474806) (xy 429.97482 -55.527105) (xy 429.952176 -55.576685)
			(xy 429.922706 -55.622539) (xy 429.88701 -55.663731) (xy 429.845815 -55.699424) (xy 429.799959 -55.72889)
			(xy 429.750376 -55.75153) (xy 429.698076 -55.766883) (xy 429.644124 -55.774637) (xy 429.61687 -55.775098)
			(xy 429.590555 -55.774651) (xy 429.538426 -55.767412) (xy 429.487783 -55.753089) (xy 429.439584 -55.731953)
			(xy 429.394741 -55.704403) (xy 429.354102 -55.670961) (xy 429.335946 -55.651908) (xy 429.328445 -55.644482)
			(xy 429.309149 -55.635971) (xy 429.298608 -55.635398) (xy 429.223932 -55.635398) (xy 429.213383 -55.635932)
			(xy 429.194087 -55.644464) (xy 429.186594 -55.651908) (xy 429.168436 -55.670961) (xy 429.127807 -55.704418)
			(xy 429.082967 -55.731977) (xy 429.034767 -55.753116) (xy 428.98412 -55.767434) (xy 428.931986 -55.774659)
			(xy 428.90567 -55.775098) (xy 428.878419 -55.77463) (xy 428.824474 -55.76687) (xy 428.772181 -55.751512)
			(xy 428.722606 -55.728868) (xy 428.676758 -55.699401) (xy 428.635571 -55.663708) (xy 428.599881 -55.622518)
			(xy 428.570417 -55.576667) (xy 428.547778 -55.527091) (xy 428.532424 -55.474797) (xy 428.524668 -55.420851)
			(xy 426.749465 -55.420851) (xy 426.781187 -55.44725) (xy 426.818404 -55.488787) (xy 426.849177 -55.5353)
			(xy 426.872849 -55.585797) (xy 426.888917 -55.639204) (xy 426.897037 -55.69438) (xy 426.897546 -55.722266)
			(xy 426.897037 -55.750152) (xy 426.888917 -55.805328) (xy 426.872849 -55.858735) (xy 426.849177 -55.909232)
			(xy 426.818404 -55.955745) (xy 426.781187 -55.997282) (xy 426.738319 -56.032957) (xy 426.690713 -56.062011)
			(xy 426.639384 -56.083823) (xy 426.585427 -56.097929) (xy 426.52999 -56.104029) (xy 426.474256 -56.101992)
			(xy 426.419413 -56.091862) (xy 426.366629 -56.073855) (xy 426.317029 -56.048354) (xy 426.271671 -56.015903)
			(xy 426.231522 -55.977194) (xy 426.197436 -55.933051) (xy 426.17014 -55.884416) (xy 426.150217 -55.832325)
			(xy 426.138091 -55.777888) (xy 426.13402 -55.722266) (xy 414.243297 -55.722266) (xy 414.268666 -56.133746)
			(xy 414.286192 -56.416448) (xy 414.287124 -56.423836) (xy 414.292677 -56.437646) (xy 414.297114 -56.443626)
			(xy 414.301686 -56.449214) (xy 414.323022 -56.464454) (xy 414.32988 -56.466994) (xy 414.357329 -56.477325)
			(xy 414.408931 -56.505197) (xy 414.455662 -56.540635) (xy 414.496422 -56.582805) (xy 414.530251 -56.630713)
			(xy 414.556353 -56.683232) (xy 414.574114 -56.739127) (xy 414.583116 -56.79708) (xy 414.583626 -56.826404)
			(xy 414.583626 -56.832754) (xy 414.583209 -56.847824) (xy 414.580284 -56.877831) (xy 414.577784 -56.892698)
			(xy 414.571691 -56.923739) (xy 414.55061 -56.983378) (xy 414.539791 -57.002934) (xy 421.86352 -57.002934)
			(xy 421.864023 -56.974843) (xy 421.872247 -56.919265) (xy 421.888535 -56.865495) (xy 421.912536 -56.814697)
			(xy 421.94373 -56.76797) (xy 421.981442 -56.726325) (xy 422.024855 -56.690664) (xy 422.048686 -56.675782)
			(xy 422.057576 -56.670448) (xy 422.069768 -56.65343) (xy 422.090088 -56.560212) (xy 422.08577 -56.539638)
			(xy 422.079928 -56.531002) (xy 422.06393 -56.506937) (xy 422.038586 -56.455006) (xy 422.02136 -56.399849)
			(xy 422.012644 -56.342724) (xy 422.01211 -56.313832) (xy 422.012585 -56.286579) (xy 422.020338 -56.232628)
			(xy 422.035691 -56.180329) (xy 422.058331 -56.130748) (xy 422.087798 -56.084894) (xy 422.12349 -56.0437)
			(xy 422.164682 -56.008006) (xy 422.210535 -55.978538) (xy 422.260116 -55.955896) (xy 422.312414 -55.940541)
			(xy 422.366365 -55.932786) (xy 422.393618 -55.932324) (xy 422.420989 -55.932774) (xy 422.475169 -55.940595)
			(xy 422.527672 -55.956087) (xy 422.577419 -55.978933) (xy 422.623385 -56.008661) (xy 422.644316 -56.026304)
			(xy 422.64457 -56.026558) (xy 422.651656 -56.032145) (xy 422.668573 -56.03839) (xy 422.67759 -56.03875)
			(xy 422.744646 -56.03875) (xy 422.753662 -56.038378) (xy 422.770579 -56.032142) (xy 422.777666 -56.026558)
			(xy 422.777666 -56.026304) (xy 422.77792 -56.026304) (xy 422.798853 -56.008663) (xy 422.844821 -55.978939)
			(xy 422.894567 -55.956093) (xy 422.947069 -55.940597) (xy 423.001247 -55.932768) (xy 423.055989 -55.932768)
			(xy 423.110167 -55.940597) (xy 423.162669 -55.956093) (xy 423.212415 -55.978939) (xy 423.258383 -56.008663)
			(xy 423.279316 -56.026304) (xy 423.27957 -56.026558) (xy 423.286656 -56.032145) (xy 423.303573 -56.03839)
			(xy 423.31259 -56.03875) (xy 423.379646 -56.03875) (xy 423.388662 -56.038378) (xy 423.405579 -56.032142)
			(xy 423.412666 -56.026558) (xy 423.412666 -56.026304) (xy 423.41292 -56.026304) (xy 423.433872 -56.00869)
			(xy 423.479839 -55.978974) (xy 423.529582 -55.956133) (xy 423.582078 -55.940636) (xy 423.63625 -55.932802)
			(xy 423.663618 -55.932324) (xy 423.690871 -55.932747) (xy 423.744821 -55.940506) (xy 423.797118 -55.955864)
			(xy 423.846697 -55.978508) (xy 423.892549 -56.007978) (xy 423.933741 -56.043672) (xy 423.969433 -56.084865)
			(xy 423.9989 -56.130719) (xy 424.021542 -56.180299) (xy 424.036897 -56.232597) (xy 424.044654 -56.286547)
			(xy 424.044654 -56.297068) (xy 424.3865 -56.297068) (xy 424.390571 -56.241446) (xy 424.402697 -56.187009)
			(xy 424.42262 -56.134918) (xy 424.449916 -56.086283) (xy 424.484002 -56.04214) (xy 424.524151 -56.003431)
			(xy 424.569509 -55.97098) (xy 424.619109 -55.945479) (xy 424.671893 -55.927472) (xy 424.726736 -55.917342)
			(xy 424.78247 -55.915305) (xy 424.837907 -55.921405) (xy 424.891864 -55.935511) (xy 424.943193 -55.957323)
			(xy 424.990799 -55.986377) (xy 425.033667 -56.022052) (xy 425.070884 -56.063589) (xy 425.101657 -56.110102)
			(xy 425.125329 -56.160599) (xy 425.141397 -56.214006) (xy 425.149517 -56.269182) (xy 425.150026 -56.297068)
			(xy 425.149517 -56.324954) (xy 425.141397 -56.38013) (xy 425.125329 -56.433537) (xy 425.101657 -56.484034)
			(xy 425.070884 -56.530547) (xy 425.033667 -56.572084) (xy 424.990799 -56.607759) (xy 424.943193 -56.636813)
			(xy 424.891864 -56.658625) (xy 424.837907 -56.672731) (xy 424.78247 -56.678831) (xy 424.726736 -56.676794)
			(xy 424.671893 -56.666664) (xy 424.619109 -56.648657) (xy 424.569509 -56.623156) (xy 424.524151 -56.590705)
			(xy 424.484002 -56.551996) (xy 424.449916 -56.507853) (xy 424.42262 -56.459218) (xy 424.402697 -56.407127)
			(xy 424.390571 -56.35269) (xy 424.3865 -56.297068) (xy 424.044654 -56.297068) (xy 424.044654 -56.341053)
			(xy 424.036897 -56.395003) (xy 424.021542 -56.447301) (xy 423.9989 -56.496881) (xy 423.969433 -56.542735)
			(xy 423.933741 -56.583928) (xy 423.892549 -56.619622) (xy 423.846697 -56.649092) (xy 423.797118 -56.671736)
			(xy 423.744821 -56.687094) (xy 423.690871 -56.694853) (xy 423.663618 -56.69534) (xy 423.636247 -56.694878)
			(xy 423.582068 -56.687061) (xy 423.529564 -56.671572) (xy 423.479817 -56.648729) (xy 423.433851 -56.619003)
			(xy 423.41292 -56.60136) (xy 423.412666 -56.601106) (xy 423.405564 -56.595542) (xy 423.388659 -56.589281)
			(xy 423.379646 -56.588914) (xy 423.31259 -56.588914) (xy 423.303572 -56.589263) (xy 423.286655 -56.595516)
			(xy 423.27957 -56.601106) (xy 423.27957 -56.60136) (xy 423.279316 -56.60136) (xy 423.258383 -56.619001)
			(xy 423.212415 -56.648725) (xy 423.162669 -56.671571) (xy 423.110167 -56.687067) (xy 423.055989 -56.694896)
			(xy 423.001247 -56.694896) (xy 422.947069 -56.687067) (xy 422.894567 -56.671571) (xy 422.844821 -56.648725)
			(xy 422.798853 -56.619001) (xy 422.77792 -56.60136) (xy 422.777666 -56.601106) (xy 422.770564 -56.595542)
			(xy 422.753659 -56.589281) (xy 422.744646 -56.588914) (xy 422.67759 -56.588914) (xy 422.668572 -56.589263)
			(xy 422.651655 -56.595516) (xy 422.64457 -56.601106) (xy 422.644062 -56.60136) (xy 422.631328 -56.612304)
			(xy 422.604236 -56.632145) (xy 422.58996 -56.640984) (xy 422.58107 -56.646318) (xy 422.568878 -56.663336)
			(xy 422.548558 -56.756554) (xy 422.552876 -56.777128) (xy 422.558718 -56.785764) (xy 422.574707 -56.809835)
			(xy 422.600052 -56.861764) (xy 422.61728 -56.91692) (xy 422.625999 -56.974042) (xy 422.626536 -57.002934)
			(xy 422.62605 -57.030185) (xy 422.618294 -57.084133) (xy 422.602939 -57.136428) (xy 422.580297 -57.186005)
			(xy 422.550831 -57.231855) (xy 422.51514 -57.273046) (xy 422.473949 -57.308737) (xy 422.428099 -57.338203)
			(xy 422.378522 -57.360845) (xy 422.326227 -57.3762) (xy 422.272279 -57.383956) (xy 422.217777 -57.383956)
			(xy 422.163829 -57.3762) (xy 422.111534 -57.360845) (xy 422.061957 -57.338203) (xy 422.016107 -57.308737)
			(xy 421.974916 -57.273046) (xy 421.939225 -57.231855) (xy 421.909759 -57.186005) (xy 421.887117 -57.136428)
			(xy 421.871762 -57.084133) (xy 421.864006 -57.030185) (xy 421.86352 -57.002934) (xy 414.539791 -57.002934)
			(xy 414.51999 -57.038728) (xy 414.500822 -57.063894) (xy 414.495488 -57.070498) (xy 414.492186 -57.079642)
			(xy 414.490662 -57.085484) (xy 414.489646 -57.09539) (xy 414.489646 -57.128156) (xy 414.47847 -57.128156)
			(xy 414.47847 -57.178956) (xy 414.478804 -57.187559) (xy 414.484521 -57.203788) (xy 414.489646 -57.210706)
			(xy 414.490916 -57.21223) (xy 414.508311 -57.233106) (xy 414.537632 -57.278855) (xy 414.560162 -57.328303)
			(xy 414.575445 -57.380448) (xy 414.583171 -57.434235) (xy 414.583626 -57.461404) (xy 414.583244 -57.48528)
			(xy 430.905918 -57.48528) (xy 430.909989 -57.429658) (xy 430.922115 -57.375221) (xy 430.942038 -57.32313)
			(xy 430.969334 -57.274495) (xy 431.00342 -57.230352) (xy 431.043569 -57.191643) (xy 431.088927 -57.159192)
			(xy 431.138527 -57.133691) (xy 431.191311 -57.115684) (xy 431.246154 -57.105554) (xy 431.301888 -57.103517)
			(xy 431.357325 -57.109617) (xy 431.411282 -57.123723) (xy 431.462611 -57.145535) (xy 431.510217 -57.174589)
			(xy 431.553085 -57.210264) (xy 431.590302 -57.251801) (xy 431.621075 -57.298314) (xy 431.644747 -57.348811)
			(xy 431.660815 -57.402218) (xy 431.668935 -57.457394) (xy 431.669444 -57.48528) (xy 431.668935 -57.513166)
			(xy 431.660815 -57.568342) (xy 431.644747 -57.621749) (xy 431.621075 -57.672246) (xy 431.590302 -57.718759)
			(xy 431.553085 -57.760296) (xy 431.510217 -57.795971) (xy 431.462611 -57.825025) (xy 431.411282 -57.846837)
			(xy 431.357325 -57.860943) (xy 431.301888 -57.867043) (xy 431.246154 -57.865006) (xy 431.191311 -57.854876)
			(xy 431.138527 -57.836869) (xy 431.088927 -57.811368) (xy 431.043569 -57.778917) (xy 431.00342 -57.740208)
			(xy 430.969334 -57.696065) (xy 430.942038 -57.64743) (xy 430.922115 -57.595339) (xy 430.909989 -57.540902)
			(xy 430.905918 -57.48528) (xy 414.583244 -57.48528) (xy 414.583216 -57.487021) (xy 414.576363 -57.537796)
			(xy 414.562768 -57.587194) (xy 414.542676 -57.634324) (xy 414.51645 -57.678338) (xy 414.500822 -57.69864)
			(xy 414.500568 -57.698894) (xy 414.499044 -57.700672) (xy 414.49474 -57.707199) (xy 414.489944 -57.72207)
			(xy 414.489646 -57.729882) (xy 414.489646 -57.763156) (xy 414.47847 -57.763156) (xy 414.47847 -57.813956)
			(xy 414.478804 -57.822559) (xy 414.484521 -57.838788) (xy 414.489646 -57.845706) (xy 414.490916 -57.84723)
			(xy 414.508311 -57.868106) (xy 414.537632 -57.913855) (xy 414.560162 -57.963303) (xy 414.575445 -58.015448)
			(xy 414.583171 -58.069235) (xy 414.583626 -58.096404) (xy 414.583216 -58.122021) (xy 414.576363 -58.172796)
			(xy 414.562768 -58.222194) (xy 414.542676 -58.269324) (xy 414.51645 -58.313338) (xy 414.500822 -58.33364)
			(xy 414.500568 -58.333894) (xy 414.499044 -58.335672) (xy 414.49474 -58.342199) (xy 414.489944 -58.35707)
			(xy 414.489646 -58.364882) (xy 414.489646 -58.398156) (xy 414.47847 -58.398156) (xy 414.47847 -58.448956)
			(xy 414.478804 -58.457559) (xy 414.484521 -58.473788) (xy 414.489646 -58.480706) (xy 414.490916 -58.48223)
			(xy 414.508311 -58.503106) (xy 414.537632 -58.548855) (xy 414.560162 -58.598303) (xy 414.575445 -58.650448)
			(xy 414.579594 -58.679334) (xy 422.29532 -58.679334) (xy 422.295737 -58.653018) (xy 422.302981 -58.600887)
			(xy 422.31731 -58.550243) (xy 422.338452 -58.502044) (xy 422.366007 -58.457202) (xy 422.399454 -58.416565)
			(xy 422.41851 -58.39841) (xy 422.425911 -58.390888) (xy 422.434435 -58.371608) (xy 422.43502 -58.361072)
			(xy 422.43502 -58.286396) (xy 422.434501 -58.275845) (xy 422.425958 -58.25655) (xy 422.41851 -58.249058)
			(xy 422.399443 -58.230914) (xy 422.365986 -58.190282) (xy 422.338429 -58.145439) (xy 422.317292 -58.097236)
			(xy 422.302978 -58.046587) (xy 422.295756 -57.994451) (xy 422.29532 -57.968134) (xy 422.295806 -57.940883)
			(xy 422.303562 -57.886935) (xy 422.318917 -57.83464) (xy 422.341559 -57.785063) (xy 422.371025 -57.739213)
			(xy 422.406716 -57.698022) (xy 422.447907 -57.662331) (xy 422.493757 -57.632865) (xy 422.543334 -57.610223)
			(xy 422.595629 -57.594868) (xy 422.649577 -57.587112) (xy 422.704079 -57.587112) (xy 422.758027 -57.594868)
			(xy 422.810322 -57.610223) (xy 422.859899 -57.632865) (xy 422.905749 -57.662331) (xy 422.94694 -57.698022)
			(xy 422.982631 -57.739213) (xy 423.012097 -57.785063) (xy 423.034739 -57.83464) (xy 423.050094 -57.886935)
			(xy 423.05785 -57.940883) (xy 423.058336 -57.968134) (xy 423.05788 -57.994448) (xy 423.050641 -58.046577)
			(xy 423.043374 -58.072274) (xy 426.293532 -58.072274) (xy 426.297603 -58.016652) (xy 426.309729 -57.962215)
			(xy 426.329652 -57.910124) (xy 426.356948 -57.861489) (xy 426.391034 -57.817346) (xy 426.431183 -57.778637)
			(xy 426.476541 -57.746186) (xy 426.526141 -57.720685) (xy 426.578925 -57.702678) (xy 426.633768 -57.692548)
			(xy 426.689502 -57.690511) (xy 426.744939 -57.696611) (xy 426.798896 -57.710717) (xy 426.850225 -57.732529)
			(xy 426.897831 -57.761583) (xy 426.940699 -57.797258) (xy 426.977916 -57.838795) (xy 427.008689 -57.885308)
			(xy 427.032361 -57.935805) (xy 427.048429 -57.989212) (xy 427.056549 -58.044388) (xy 427.057058 -58.072274)
			(xy 427.056988 -58.076084) (xy 431.658012 -58.076084) (xy 431.662083 -58.020462) (xy 431.674209 -57.966025)
			(xy 431.694132 -57.913934) (xy 431.721428 -57.865299) (xy 431.755514 -57.821156) (xy 431.795663 -57.782447)
			(xy 431.841021 -57.749996) (xy 431.890621 -57.724495) (xy 431.943405 -57.706488) (xy 431.998248 -57.696358)
			(xy 432.053982 -57.694321) (xy 432.109419 -57.700421) (xy 432.163376 -57.714527) (xy 432.214705 -57.736339)
			(xy 432.262311 -57.765393) (xy 432.305179 -57.801068) (xy 432.342396 -57.842605) (xy 432.373169 -57.889118)
			(xy 432.396841 -57.939615) (xy 432.412909 -57.993022) (xy 432.421029 -58.048198) (xy 432.421538 -58.076084)
			(xy 432.42107 -58.101738) (xy 433.942996 -58.101738) (xy 433.947067 -58.046116) (xy 433.959193 -57.991679)
			(xy 433.979116 -57.939588) (xy 434.006412 -57.890953) (xy 434.040498 -57.84681) (xy 434.080647 -57.808101)
			(xy 434.126005 -57.77565) (xy 434.175605 -57.750149) (xy 434.228389 -57.732142) (xy 434.283232 -57.722012)
			(xy 434.338966 -57.719975) (xy 434.394403 -57.726075) (xy 434.44836 -57.740181) (xy 434.499689 -57.761993)
			(xy 434.547295 -57.791047) (xy 434.590163 -57.826722) (xy 434.62738 -57.868259) (xy 434.658153 -57.914772)
			(xy 434.681825 -57.965269) (xy 434.697893 -58.018676) (xy 434.706013 -58.073852) (xy 434.706522 -58.101738)
			(xy 434.706013 -58.129624) (xy 434.697893 -58.1848) (xy 434.681825 -58.238207) (xy 434.658153 -58.288704)
			(xy 434.62738 -58.335217) (xy 434.590163 -58.376754) (xy 434.547295 -58.412429) (xy 434.499689 -58.441483)
			(xy 434.44836 -58.463295) (xy 434.394403 -58.477401) (xy 434.338966 -58.483501) (xy 434.283232 -58.481464)
			(xy 434.228389 -58.471334) (xy 434.175605 -58.453327) (xy 434.126005 -58.427826) (xy 434.080647 -58.395375)
			(xy 434.040498 -58.356666) (xy 434.006412 -58.312523) (xy 433.979116 -58.263888) (xy 433.959193 -58.211797)
			(xy 433.947067 -58.15736) (xy 433.942996 -58.101738) (xy 432.42107 -58.101738) (xy 432.421029 -58.10397)
			(xy 432.412909 -58.159146) (xy 432.396841 -58.212553) (xy 432.373169 -58.26305) (xy 432.342396 -58.309563)
			(xy 432.305179 -58.3511) (xy 432.262311 -58.386775) (xy 432.214705 -58.415829) (xy 432.163376 -58.437641)
			(xy 432.109419 -58.451747) (xy 432.053982 -58.457847) (xy 431.998248 -58.45581) (xy 431.943405 -58.44568)
			(xy 431.890621 -58.427673) (xy 431.841021 -58.402172) (xy 431.795663 -58.369721) (xy 431.755514 -58.331012)
			(xy 431.721428 -58.286869) (xy 431.694132 -58.238234) (xy 431.674209 -58.186143) (xy 431.662083 -58.131706)
			(xy 431.658012 -58.076084) (xy 427.056988 -58.076084) (xy 427.056549 -58.10016) (xy 427.048429 -58.155336)
			(xy 427.032361 -58.208743) (xy 427.008689 -58.25924) (xy 426.977916 -58.305753) (xy 426.940699 -58.34729)
			(xy 426.897831 -58.382965) (xy 426.850225 -58.412019) (xy 426.798896 -58.433831) (xy 426.744939 -58.447937)
			(xy 426.689502 -58.454037) (xy 426.633768 -58.452) (xy 426.578925 -58.44187) (xy 426.526141 -58.423863)
			(xy 426.476541 -58.398362) (xy 426.431183 -58.365911) (xy 426.391034 -58.327202) (xy 426.356948 -58.283059)
			(xy 426.329652 -58.234424) (xy 426.309729 -58.182333) (xy 426.297603 -58.127896) (xy 426.293532 -58.072274)
			(xy 423.043374 -58.072274) (xy 423.036319 -58.097219) (xy 423.015184 -58.145418) (xy 422.987637 -58.190261)
			(xy 422.954198 -58.230901) (xy 422.935146 -58.249058) (xy 422.927768 -58.2566) (xy 422.919229 -58.275864)
			(xy 422.918636 -58.286396) (xy 422.918636 -58.361072) (xy 422.919156 -58.371623) (xy 422.927697 -58.390919)
			(xy 422.935146 -58.39841) (xy 422.954208 -58.416559) (xy 422.987663 -58.457191) (xy 423.01522 -58.502033)
			(xy 423.036357 -58.550235) (xy 423.039463 -58.561224) (xy 432.862226 -58.561224) (xy 432.866297 -58.505602)
			(xy 432.878423 -58.451165) (xy 432.898346 -58.399074) (xy 432.925642 -58.350439) (xy 432.959728 -58.306296)
			(xy 432.999877 -58.267587) (xy 433.045235 -58.235136) (xy 433.094835 -58.209635) (xy 433.147619 -58.191628)
			(xy 433.202462 -58.181498) (xy 433.258196 -58.179461) (xy 433.313633 -58.185561) (xy 433.36759 -58.199667)
			(xy 433.418919 -58.221479) (xy 433.466525 -58.250533) (xy 433.509393 -58.286208) (xy 433.54661 -58.327745)
			(xy 433.577383 -58.374258) (xy 433.601055 -58.424755) (xy 433.617123 -58.478162) (xy 433.625243 -58.533338)
			(xy 433.625752 -58.561224) (xy 433.625243 -58.58911) (xy 433.617123 -58.644286) (xy 433.601055 -58.697693)
			(xy 433.577383 -58.74819) (xy 433.54661 -58.794703) (xy 433.509393 -58.83624) (xy 433.466525 -58.871915)
			(xy 433.418919 -58.900969) (xy 433.36759 -58.922781) (xy 433.313633 -58.936887) (xy 433.258196 -58.942987)
			(xy 433.202462 -58.94095) (xy 433.147619 -58.93082) (xy 433.094835 -58.912813) (xy 433.045235 -58.887312)
			(xy 432.999877 -58.854861) (xy 432.959728 -58.816152) (xy 432.925642 -58.772009) (xy 432.898346 -58.723374)
			(xy 432.878423 -58.671283) (xy 432.866297 -58.616846) (xy 432.862226 -58.561224) (xy 423.039463 -58.561224)
			(xy 423.050673 -58.600883) (xy 423.057898 -58.653018) (xy 423.058336 -58.679334) (xy 423.05785 -58.706585)
			(xy 423.050094 -58.760533) (xy 423.034739 -58.812828) (xy 423.012097 -58.862405) (xy 422.982631 -58.908255)
			(xy 422.94694 -58.949446) (xy 422.905749 -58.985137) (xy 422.859899 -59.014603) (xy 422.810322 -59.037245)
			(xy 422.758027 -59.0526) (xy 422.704079 -59.060356) (xy 422.649577 -59.060356) (xy 422.595629 -59.0526)
			(xy 422.543334 -59.037245) (xy 422.493757 -59.014603) (xy 422.447907 -58.985137) (xy 422.406716 -58.949446)
			(xy 422.371025 -58.908255) (xy 422.341559 -58.862405) (xy 422.318917 -58.812828) (xy 422.303562 -58.760533)
			(xy 422.295806 -58.706585) (xy 422.29532 -58.679334) (xy 414.579594 -58.679334) (xy 414.583171 -58.704235)
			(xy 414.583626 -58.731404) (xy 414.583626 -58.739024) (xy 414.58245 -58.769202) (xy 414.571751 -58.828639)
			(xy 414.551826 -58.885649) (xy 414.523172 -58.938811) (xy 414.486505 -58.986797) (xy 414.465008 -59.00801)
			(xy 414.462214 -59.01055) (xy 414.455736 -59.01843) (xy 414.449058 -59.037688) (xy 414.44926 -59.047888)
			(xy 414.457095 -59.174634) (xy 431.39309 -59.174634) (xy 431.397161 -59.119012) (xy 431.409287 -59.064575)
			(xy 431.42921 -59.012484) (xy 431.456506 -58.963849) (xy 431.490592 -58.919706) (xy 431.530741 -58.880997)
			(xy 431.576099 -58.848546) (xy 431.625699 -58.823045) (xy 431.678483 -58.805038) (xy 431.733326 -58.794908)
			(xy 431.78906 -58.792871) (xy 431.844497 -58.798971) (xy 431.898454 -58.813077) (xy 431.949783 -58.834889)
			(xy 431.997389 -58.863943) (xy 432.040257 -58.899618) (xy 432.077474 -58.941155) (xy 432.108247 -58.987668)
			(xy 432.131919 -59.038165) (xy 432.147987 -59.091572) (xy 432.156107 -59.146748) (xy 432.156616 -59.174634)
			(xy 432.156107 -59.20252) (xy 432.147987 -59.257696) (xy 432.131919 -59.311103) (xy 432.108247 -59.3616)
			(xy 432.077474 -59.408113) (xy 432.040257 -59.44965) (xy 431.997389 -59.485325) (xy 431.949783 -59.514379)
			(xy 431.898454 -59.536191) (xy 431.844497 -59.550297) (xy 431.78906 -59.556397) (xy 431.733326 -59.55436)
			(xy 431.678483 -59.54423) (xy 431.625699 -59.526223) (xy 431.576099 -59.500722) (xy 431.530741 -59.468271)
			(xy 431.490592 -59.429562) (xy 431.456506 -59.385419) (xy 431.42921 -59.336784) (xy 431.409287 -59.284693)
			(xy 431.397161 -59.230256) (xy 431.39309 -59.174634) (xy 414.457095 -59.174634) (xy 414.50931 -60.01925)
			(xy 422.435784 -60.01925) (xy 422.435784 -59.96475) (xy 422.44354 -59.910805) (xy 422.458894 -59.858512)
			(xy 422.481533 -59.808937) (xy 422.510997 -59.763088) (xy 422.546686 -59.721899) (xy 422.587874 -59.686208)
			(xy 422.633721 -59.656742) (xy 422.683295 -59.6341) (xy 422.735587 -59.618743) (xy 422.789532 -59.610985)
			(xy 422.816782 -59.610498) (xy 422.844152 -59.610975) (xy 422.89833 -59.61879) (xy 422.950833 -59.634277)
			(xy 423.00058 -59.657116) (xy 423.046548 -59.686838) (xy 423.06748 -59.704478) (xy 423.067734 -59.704732)
			(xy 423.074833 -59.710301) (xy 423.09174 -59.716557) (xy 423.100754 -59.716924) (xy 423.16781 -59.716924)
			(xy 423.176827 -59.716566) (xy 423.193743 -59.710319) (xy 423.20083 -59.704732) (xy 423.20083 -59.704478)
			(xy 423.201084 -59.704478) (xy 423.222017 -59.686837) (xy 423.267985 -59.657113) (xy 423.317731 -59.634267)
			(xy 423.370233 -59.618771) (xy 423.424411 -59.610942) (xy 423.479153 -59.610942) (xy 423.533331 -59.618771)
			(xy 423.585833 -59.634267) (xy 423.635579 -59.657113) (xy 423.681547 -59.686837) (xy 423.70248 -59.704478)
			(xy 423.702734 -59.704732) (xy 423.709833 -59.710301) (xy 423.72674 -59.716557) (xy 423.735754 -59.716924)
			(xy 423.80281 -59.716924) (xy 423.811827 -59.716566) (xy 423.828743 -59.710319) (xy 423.83583 -59.704732)
			(xy 423.83583 -59.704478) (xy 423.836084 -59.704478) (xy 423.857008 -59.68683) (xy 423.902984 -59.65712)
			(xy 423.952733 -59.634286) (xy 424.005235 -59.618797) (xy 424.059412 -59.610971) (xy 424.086782 -59.610498)
			(xy 424.114036 -59.610948) (xy 424.16799 -59.618703) (xy 424.220291 -59.634058) (xy 424.269874 -59.6567)
			(xy 424.31573 -59.686168) (xy 424.356925 -59.721862) (xy 424.392622 -59.763056) (xy 424.422092 -59.80891)
			(xy 424.444736 -59.858492) (xy 424.460093 -59.910793) (xy 424.467851 -59.964746) (xy 424.467851 -60.019254)
			(xy 424.460093 -60.073207) (xy 424.444736 -60.125508) (xy 424.422092 -60.17509) (xy 424.392622 -60.220944)
			(xy 424.356925 -60.262138) (xy 424.31573 -60.297832) (xy 424.269874 -60.3273) (xy 424.220291 -60.349942)
			(xy 424.16799 -60.365297) (xy 424.114036 -60.373052) (xy 424.086782 -60.373514) (xy 424.059412 -60.373055)
			(xy 424.005232 -60.365235) (xy 423.952729 -60.349744) (xy 423.902983 -60.326901) (xy 423.857016 -60.297175)
			(xy 423.836084 -60.279534) (xy 423.83583 -60.27928) (xy 423.828741 -60.273698) (xy 423.811826 -60.267449)
			(xy 423.80281 -60.267088) (xy 423.735754 -60.267088) (xy 423.72674 -60.267473) (xy 423.709823 -60.273701)
			(xy 423.702734 -60.27928) (xy 423.70248 -60.279534) (xy 423.681547 -60.297175) (xy 423.635579 -60.326899)
			(xy 423.585833 -60.349745) (xy 423.533331 -60.365241) (xy 423.479153 -60.37307) (xy 423.424411 -60.37307)
			(xy 423.370233 -60.365241) (xy 423.317731 -60.349745) (xy 423.267985 -60.326899) (xy 423.222017 -60.297175)
			(xy 423.201084 -60.279534) (xy 423.20083 -60.27928) (xy 423.193741 -60.273698) (xy 423.176826 -60.267449)
			(xy 423.16781 -60.267088) (xy 423.100754 -60.267088) (xy 423.09174 -60.267473) (xy 423.074823 -60.273701)
			(xy 423.067734 -60.27928) (xy 423.067734 -60.279534) (xy 423.06748 -60.279534) (xy 423.046533 -60.297154)
			(xy 423.000564 -60.326868) (xy 422.95082 -60.349707) (xy 422.898323 -60.365202) (xy 422.84415 -60.373037)
			(xy 422.816782 -60.373514) (xy 422.789532 -60.373015) (xy 422.735587 -60.365257) (xy 422.683295 -60.3499)
			(xy 422.633721 -60.327258) (xy 422.587874 -60.297792) (xy 422.546686 -60.262101) (xy 422.510997 -60.220912)
			(xy 422.481533 -60.175063) (xy 422.458894 -60.125488) (xy 422.44354 -60.073195) (xy 422.435784 -60.01925)
			(xy 414.50931 -60.01925) (xy 414.541716 -60.54344) (xy 414.543748 -60.604908) (xy 414.543748 -60.605416)
			(xy 414.542993 -60.633356) (xy 434.09692 -60.633356) (xy 434.100991 -60.577734) (xy 434.113117 -60.523297)
			(xy 434.13304 -60.471206) (xy 434.160336 -60.422571) (xy 434.194422 -60.378428) (xy 434.234571 -60.339719)
			(xy 434.279929 -60.307268) (xy 434.329529 -60.281767) (xy 434.382313 -60.26376) (xy 434.437156 -60.25363)
			(xy 434.49289 -60.251593) (xy 434.548327 -60.257693) (xy 434.602284 -60.271799) (xy 434.653613 -60.293611)
			(xy 434.701219 -60.322665) (xy 434.744087 -60.35834) (xy 434.781304 -60.399877) (xy 434.812077 -60.44639)
			(xy 434.835749 -60.496887) (xy 434.851817 -60.550294) (xy 434.859937 -60.60547) (xy 434.860446 -60.633356)
			(xy 434.859937 -60.661242) (xy 434.851817 -60.716418) (xy 434.835749 -60.769825) (xy 434.812077 -60.820322)
			(xy 434.781304 -60.866835) (xy 434.744087 -60.908372) (xy 434.701219 -60.944047) (xy 434.653613 -60.973101)
			(xy 434.602284 -60.994913) (xy 434.548327 -61.009019) (xy 434.49289 -61.015119) (xy 434.437156 -61.013082)
			(xy 434.382313 -61.002952) (xy 434.329529 -60.984945) (xy 434.279929 -60.959444) (xy 434.234571 -60.926993)
			(xy 434.194422 -60.888284) (xy 434.160336 -60.844141) (xy 434.13304 -60.795506) (xy 434.113117 -60.743415)
			(xy 434.100991 -60.688978) (xy 434.09692 -60.633356) (xy 414.542993 -60.633356) (xy 414.542478 -60.652406)
			(xy 414.502809 -61.487812) (xy 432.604416 -61.487812) (xy 432.608487 -61.43219) (xy 432.620613 -61.377753)
			(xy 432.640536 -61.325662) (xy 432.667832 -61.277027) (xy 432.701918 -61.232884) (xy 432.742067 -61.194175)
			(xy 432.787425 -61.161724) (xy 432.837025 -61.136223) (xy 432.889809 -61.118216) (xy 432.944652 -61.108086)
			(xy 433.000386 -61.106049) (xy 433.055823 -61.112149) (xy 433.10978 -61.126255) (xy 433.161109 -61.148067)
			(xy 433.208715 -61.177121) (xy 433.251583 -61.212796) (xy 433.2888 -61.254333) (xy 433.319573 -61.300846)
			(xy 433.343245 -61.351343) (xy 433.359313 -61.40475) (xy 433.367433 -61.459926) (xy 433.367942 -61.487812)
			(xy 433.367433 -61.515698) (xy 433.359313 -61.570874) (xy 433.343245 -61.624281) (xy 433.319573 -61.674778)
			(xy 433.2888 -61.721291) (xy 433.251583 -61.762828) (xy 433.208715 -61.798503) (xy 433.161109 -61.827557)
			(xy 433.10978 -61.849369) (xy 433.055823 -61.863475) (xy 433.000386 -61.869575) (xy 432.944652 -61.867538)
			(xy 432.889809 -61.857408) (xy 432.837025 -61.839401) (xy 432.787425 -61.8139) (xy 432.742067 -61.781449)
			(xy 432.701918 -61.74274) (xy 432.667832 -61.698597) (xy 432.640536 -61.649962) (xy 432.620613 -61.597871)
			(xy 432.608487 -61.543434) (xy 432.604416 -61.487812) (xy 414.502809 -61.487812) (xy 414.472741 -62.121034)
			(xy 430.54219 -62.121034) (xy 430.546261 -62.065412) (xy 430.558387 -62.010975) (xy 430.57831 -61.958884)
			(xy 430.605606 -61.910249) (xy 430.639692 -61.866106) (xy 430.679841 -61.827397) (xy 430.725199 -61.794946)
			(xy 430.774799 -61.769445) (xy 430.827583 -61.751438) (xy 430.882426 -61.741308) (xy 430.93816 -61.739271)
			(xy 430.993597 -61.745371) (xy 431.047554 -61.759477) (xy 431.098883 -61.781289) (xy 431.146489 -61.810343)
			(xy 431.189357 -61.846018) (xy 431.226574 -61.887555) (xy 431.257347 -61.934068) (xy 431.281019 -61.984565)
			(xy 431.297087 -62.037972) (xy 431.305207 -62.093148) (xy 431.305716 -62.121034) (xy 431.305207 -62.14892)
			(xy 431.297087 -62.204096) (xy 431.281019 -62.257503) (xy 431.257347 -62.308) (xy 431.226574 -62.354513)
			(xy 431.189357 -62.39605) (xy 431.146489 -62.431725) (xy 431.098883 -62.460779) (xy 431.047554 -62.482591)
			(xy 430.993597 -62.496697) (xy 430.93816 -62.502797) (xy 430.882426 -62.50076) (xy 430.827583 -62.49063)
			(xy 430.774799 -62.472623) (xy 430.725199 -62.447122) (xy 430.679841 -62.414671) (xy 430.639692 -62.375962)
			(xy 430.605606 -62.331819) (xy 430.57831 -62.283184) (xy 430.558387 -62.231093) (xy 430.546261 -62.176656)
			(xy 430.54219 -62.121034) (xy 414.472741 -62.121034) (xy 414.420863 -63.21355) (xy 422.420788 -63.21355)
			(xy 422.420788 -63.15905) (xy 422.428544 -63.105104) (xy 422.443899 -63.052811) (xy 422.466539 -63.003235)
			(xy 422.496004 -62.957386) (xy 422.531694 -62.916197) (xy 422.572883 -62.880507) (xy 422.618732 -62.851041)
			(xy 422.668307 -62.8284) (xy 422.7206 -62.813045) (xy 422.774546 -62.805289) (xy 422.801796 -62.804802)
			(xy 422.829166 -62.80527) (xy 422.883345 -62.813087) (xy 422.935848 -62.828576) (xy 422.985595 -62.851417)
			(xy 423.031562 -62.881141) (xy 423.052494 -62.898782) (xy 423.052748 -62.899036) (xy 423.059842 -62.904611)
			(xy 423.076753 -62.910864) (xy 423.085768 -62.911228) (xy 423.152824 -62.911228) (xy 423.161841 -62.910877)
			(xy 423.178758 -62.904625) (xy 423.185844 -62.899036) (xy 423.185844 -62.898782) (xy 423.186098 -62.898782)
			(xy 423.207031 -62.881141) (xy 423.252999 -62.851417) (xy 423.302745 -62.828571) (xy 423.355247 -62.813075)
			(xy 423.409425 -62.805246) (xy 423.464167 -62.805246) (xy 423.518345 -62.813075) (xy 423.570847 -62.828571)
			(xy 423.620593 -62.851417) (xy 423.666561 -62.881141) (xy 423.687494 -62.898782) (xy 423.687748 -62.899036)
			(xy 423.694842 -62.904611) (xy 423.711753 -62.910864) (xy 423.720768 -62.911228) (xy 423.787824 -62.911228)
			(xy 423.796841 -62.910877) (xy 423.813758 -62.904625) (xy 423.820844 -62.899036) (xy 423.820844 -62.898782)
			(xy 423.821098 -62.898782) (xy 423.842018 -62.881128) (xy 423.887994 -62.851419) (xy 423.937745 -62.828586)
			(xy 423.990248 -62.813098) (xy 424.044426 -62.805274) (xy 424.071796 -62.804802) (xy 424.09905 -62.805245)
			(xy 424.153003 -62.813001) (xy 424.205302 -62.828357) (xy 424.254884 -62.851) (xy 424.300739 -62.880469)
			(xy 424.341934 -62.916164) (xy 424.377629 -62.957358) (xy 424.407098 -63.003212) (xy 424.429741 -63.052794)
			(xy 424.43956 -63.086234) (xy 427.687484 -63.086234) (xy 427.691555 -63.030612) (xy 427.703681 -62.976175)
			(xy 427.723604 -62.924084) (xy 427.7509 -62.875449) (xy 427.784986 -62.831306) (xy 427.825135 -62.792597)
			(xy 427.870493 -62.760146) (xy 427.920093 -62.734645) (xy 427.972877 -62.716638) (xy 428.02772 -62.706508)
			(xy 428.083454 -62.704471) (xy 428.138891 -62.710571) (xy 428.192848 -62.724677) (xy 428.244177 -62.746489)
			(xy 428.291783 -62.775543) (xy 428.334651 -62.811218) (xy 428.371868 -62.852755) (xy 428.402641 -62.899268)
			(xy 428.426313 -62.949765) (xy 428.442381 -63.003172) (xy 428.450501 -63.058348) (xy 428.45101 -63.086234)
			(xy 428.450501 -63.11412) (xy 428.442381 -63.169296) (xy 428.426313 -63.222703) (xy 428.402641 -63.2732)
			(xy 428.402488 -63.273432) (xy 429.87671 -63.273432) (xy 429.880781 -63.21781) (xy 429.892907 -63.163373)
			(xy 429.91283 -63.111282) (xy 429.940126 -63.062647) (xy 429.974212 -63.018504) (xy 430.014361 -62.979795)
			(xy 430.059719 -62.947344) (xy 430.109319 -62.921843) (xy 430.162103 -62.903836) (xy 430.216946 -62.893706)
			(xy 430.27268 -62.891669) (xy 430.328117 -62.897769) (xy 430.382074 -62.911875) (xy 430.433403 -62.933687)
			(xy 430.481009 -62.962741) (xy 430.523877 -62.998416) (xy 430.561094 -63.039953) (xy 430.591867 -63.086466)
			(xy 430.615539 -63.136963) (xy 430.631607 -63.19037) (xy 430.639727 -63.245546) (xy 430.640236 -63.273432)
			(xy 430.639727 -63.301318) (xy 430.631607 -63.356494) (xy 430.615539 -63.409901) (xy 430.591867 -63.460398)
			(xy 430.561094 -63.506911) (xy 430.523877 -63.548448) (xy 430.481009 -63.584123) (xy 430.433403 -63.613177)
			(xy 430.382074 -63.634989) (xy 430.328117 -63.649095) (xy 430.27268 -63.655195) (xy 430.216946 -63.653158)
			(xy 430.162103 -63.643028) (xy 430.109319 -63.625021) (xy 430.059719 -63.59952) (xy 430.014361 -63.567069)
			(xy 429.974212 -63.52836) (xy 429.940126 -63.484217) (xy 429.91283 -63.435582) (xy 429.892907 -63.383491)
			(xy 429.880781 -63.329054) (xy 429.87671 -63.273432) (xy 428.402488 -63.273432) (xy 428.371868 -63.319713)
			(xy 428.334651 -63.36125) (xy 428.291783 -63.396925) (xy 428.244177 -63.425979) (xy 428.192848 -63.447791)
			(xy 428.138891 -63.461897) (xy 428.083454 -63.467997) (xy 428.02772 -63.46596) (xy 427.972877 -63.45583)
			(xy 427.920093 -63.437823) (xy 427.870493 -63.412322) (xy 427.825135 -63.379871) (xy 427.784986 -63.341162)
			(xy 427.7509 -63.297019) (xy 427.723604 -63.248384) (xy 427.703681 -63.196293) (xy 427.691555 -63.141856)
			(xy 427.687484 -63.086234) (xy 424.43956 -63.086234) (xy 424.445098 -63.105093) (xy 424.452855 -63.159046)
			(xy 424.452855 -63.213554) (xy 424.445098 -63.267507) (xy 424.429741 -63.319806) (xy 424.407098 -63.369388)
			(xy 424.377629 -63.415242) (xy 424.341934 -63.456436) (xy 424.300739 -63.492131) (xy 424.254884 -63.5216)
			(xy 424.205302 -63.544243) (xy 424.153003 -63.559599) (xy 424.09905 -63.567355) (xy 424.071796 -63.567818)
			(xy 424.044425 -63.567374) (xy 423.990244 -63.559554) (xy 423.93774 -63.544061) (xy 423.887993 -63.521214)
			(xy 423.842028 -63.491483) (xy 423.821098 -63.473838) (xy 423.820844 -63.473584) (xy 423.81375 -63.468008)
			(xy 423.796839 -63.461755) (xy 423.787824 -63.461392) (xy 423.720768 -63.461392) (xy 423.71175 -63.461736)
			(xy 423.694833 -63.467993) (xy 423.687748 -63.473584) (xy 423.687494 -63.473838) (xy 423.666561 -63.491479)
			(xy 423.620593 -63.521203) (xy 423.570847 -63.544049) (xy 423.518345 -63.559545) (xy 423.464167 -63.567374)
			(xy 423.409425 -63.567374) (xy 423.355247 -63.559545) (xy 423.302745 -63.544049) (xy 423.252999 -63.521203)
			(xy 423.207031 -63.491479) (xy 423.186098 -63.473838) (xy 423.185844 -63.473584) (xy 423.17875 -63.468008)
			(xy 423.161839 -63.461755) (xy 423.152824 -63.461392) (xy 423.085768 -63.461392) (xy 423.07675 -63.461736)
			(xy 423.059833 -63.467993) (xy 423.052748 -63.473584) (xy 423.052748 -63.473838) (xy 423.052494 -63.473838)
			(xy 423.03158 -63.4915) (xy 422.985602 -63.521207) (xy 422.93585 -63.544038) (xy 422.883345 -63.559524)
			(xy 422.829166 -63.567347) (xy 422.801796 -63.567818) (xy 422.774546 -63.567311) (xy 422.7206 -63.559555)
			(xy 422.668307 -63.5442) (xy 422.618732 -63.521559) (xy 422.572883 -63.492093) (xy 422.531694 -63.456403)
			(xy 422.496004 -63.415214) (xy 422.466539 -63.369365) (xy 422.443899 -63.319789) (xy 422.428544 -63.267496)
			(xy 422.420788 -63.21355) (xy 414.420863 -63.21355) (xy 414.33124 -65.100962) (xy 420.432482 -65.100962)
			(xy 420.436553 -65.04534) (xy 420.448679 -64.990903) (xy 420.468602 -64.938812) (xy 420.495898 -64.890177)
			(xy 420.529984 -64.846034) (xy 420.570133 -64.807325) (xy 420.615491 -64.774874) (xy 420.665091 -64.749373)
			(xy 420.717875 -64.731366) (xy 420.772718 -64.721236) (xy 420.828452 -64.719199) (xy 420.883889 -64.725299)
			(xy 420.937846 -64.739405) (xy 420.989175 -64.761217) (xy 421.036781 -64.790271) (xy 421.079649 -64.825946)
			(xy 421.116866 -64.867483) (xy 421.147639 -64.913996) (xy 421.171311 -64.964493) (xy 421.187379 -65.0179)
			(xy 421.195499 -65.073076) (xy 421.196008 -65.100962) (xy 421.195499 -65.128848) (xy 421.187379 -65.184024)
			(xy 421.171311 -65.237431) (xy 421.147639 -65.287928) (xy 421.116866 -65.334441) (xy 421.079649 -65.375978)
			(xy 421.036781 -65.411653) (xy 420.989175 -65.440707) (xy 420.937846 -65.462519) (xy 420.883889 -65.476625)
			(xy 420.828452 -65.482725) (xy 420.772718 -65.480688) (xy 420.717875 -65.470558) (xy 420.665091 -65.452551)
			(xy 420.615491 -65.42705) (xy 420.570133 -65.394599) (xy 420.529984 -65.35589) (xy 420.495898 -65.311747)
			(xy 420.468602 -65.263112) (xy 420.448679 -65.211021) (xy 420.436553 -65.156584) (xy 420.432482 -65.100962)
			(xy 414.33124 -65.100962) (xy 414.300159 -65.75552) (xy 414.646616 -65.75552) (xy 414.650687 -65.699898)
			(xy 414.662813 -65.645461) (xy 414.682736 -65.59337) (xy 414.710032 -65.544735) (xy 414.744118 -65.500592)
			(xy 414.784267 -65.461883) (xy 414.829625 -65.429432) (xy 414.879225 -65.403931) (xy 414.932009 -65.385924)
			(xy 414.986852 -65.375794) (xy 415.042586 -65.373757) (xy 415.098023 -65.379857) (xy 415.15198 -65.393963)
			(xy 415.203309 -65.415775) (xy 415.250915 -65.444829) (xy 415.293783 -65.480504) (xy 415.331 -65.522041)
			(xy 415.361773 -65.568554) (xy 415.385445 -65.619051) (xy 415.401513 -65.672458) (xy 415.409633 -65.727634)
			(xy 415.410142 -65.75552) (xy 415.409633 -65.783406) (xy 415.401513 -65.838582) (xy 415.385445 -65.891989)
			(xy 415.361773 -65.942486) (xy 415.331 -65.988999) (xy 415.293783 -66.030536) (xy 415.250915 -66.066211)
			(xy 415.203309 -66.095265) (xy 415.15198 -66.117077) (xy 415.098023 -66.131183) (xy 415.042586 -66.137283)
			(xy 414.986852 -66.135246) (xy 414.932009 -66.125116) (xy 414.879225 -66.107109) (xy 414.829625 -66.081608)
			(xy 414.784267 -66.049157) (xy 414.744118 -66.010448) (xy 414.710032 -65.966305) (xy 414.682736 -65.91767)
			(xy 414.662813 -65.865579) (xy 414.650687 -65.811142) (xy 414.646616 -65.75552) (xy 414.300159 -65.75552)
			(xy 414.234942 -67.128949) (xy 414.666698 -67.128949) (xy 414.666698 -67.074451) (xy 414.674454 -67.020508)
			(xy 414.689807 -66.968217) (xy 414.712446 -66.918643) (xy 414.741909 -66.872796) (xy 414.777597 -66.831609)
			(xy 414.818783 -66.795919) (xy 414.864629 -66.766454) (xy 414.914202 -66.743813) (xy 414.966492 -66.728457)
			(xy 415.020435 -66.720699) (xy 415.047684 -66.720212) (xy 415.075054 -66.720685) (xy 415.129233 -66.7285)
			(xy 415.181736 -66.743988) (xy 415.231483 -66.766828) (xy 415.27745 -66.796551) (xy 415.298382 -66.814192)
			(xy 415.298636 -66.814446) (xy 415.305733 -66.820017) (xy 415.322642 -66.826272) (xy 415.331656 -66.826638)
			(xy 415.398712 -66.826638) (xy 415.407728 -66.826279) (xy 415.424645 -66.820032) (xy 415.431732 -66.814446)
			(xy 415.431732 -66.814192) (xy 415.431986 -66.814192) (xy 415.452911 -66.796545) (xy 415.498886 -66.766834)
			(xy 415.548635 -66.744) (xy 415.601138 -66.728511) (xy 415.655314 -66.720685) (xy 415.682684 -66.720212)
			(xy 415.709939 -66.720634) (xy 415.763895 -66.728389) (xy 415.816197 -66.743745) (xy 415.865782 -66.766388)
			(xy 415.91164 -66.795857) (xy 415.952836 -66.831552) (xy 415.988534 -66.872748) (xy 416.018005 -66.918604)
			(xy 416.04065 -66.968188) (xy 416.056007 -67.02049) (xy 416.063765 -67.074445) (xy 416.063765 -67.128955)
			(xy 416.056007 -67.18291) (xy 416.04065 -67.235212) (xy 416.018005 -67.284796) (xy 415.988534 -67.330652)
			(xy 415.952836 -67.371848) (xy 415.91164 -67.407543) (xy 415.865782 -67.437012) (xy 415.816197 -67.459655)
			(xy 415.763895 -67.475011) (xy 415.709939 -67.482766) (xy 415.682684 -67.483228) (xy 415.655313 -67.482789)
			(xy 415.601132 -67.474967) (xy 415.548628 -67.459473) (xy 415.498881 -67.436625) (xy 415.452916 -67.406893)
			(xy 415.431986 -67.389248) (xy 415.431732 -67.388994) (xy 415.424641 -67.383414) (xy 415.407728 -67.377164)
			(xy 415.398712 -67.376802) (xy 415.331656 -67.376802) (xy 415.322642 -67.377186) (xy 415.305725 -67.383415)
			(xy 415.298636 -67.388994) (xy 415.298636 -67.389248) (xy 415.298382 -67.389248) (xy 415.277423 -67.406854)
			(xy 415.231459 -67.436573) (xy 415.181718 -67.459416) (xy 415.129223 -67.474914) (xy 415.075051 -67.48275)
			(xy 415.047684 -67.483228) (xy 415.020435 -67.482701) (xy 414.966492 -67.474943) (xy 414.914202 -67.459587)
			(xy 414.864629 -67.436946) (xy 414.818783 -67.407481) (xy 414.777597 -67.371791) (xy 414.741909 -67.330604)
			(xy 414.712446 -67.284757) (xy 414.689807 -67.235183) (xy 414.674454 -67.182892) (xy 414.666698 -67.128949)
			(xy 414.234942 -67.128949) (xy 414.21789 -67.488054) (xy 419.07917 -67.488054) (xy 419.083241 -67.432432)
			(xy 419.095367 -67.377995) (xy 419.11529 -67.325904) (xy 419.142586 -67.277269) (xy 419.176672 -67.233126)
			(xy 419.216821 -67.194417) (xy 419.262179 -67.161966) (xy 419.311779 -67.136465) (xy 419.364563 -67.118458)
			(xy 419.419406 -67.108328) (xy 419.47514 -67.106291) (xy 419.530577 -67.112391) (xy 419.584534 -67.126497)
			(xy 419.635863 -67.148309) (xy 419.683469 -67.177363) (xy 419.726337 -67.213038) (xy 419.763554 -67.254575)
			(xy 419.794327 -67.301088) (xy 419.817999 -67.351585) (xy 419.834067 -67.404992) (xy 419.842187 -67.460168)
			(xy 419.842696 -67.488054) (xy 419.842187 -67.51594) (xy 419.839002 -67.537584) (xy 420.371268 -67.537584)
			(xy 420.375339 -67.481962) (xy 420.387465 -67.427525) (xy 420.407388 -67.375434) (xy 420.434684 -67.326799)
			(xy 420.46877 -67.282656) (xy 420.508919 -67.243947) (xy 420.554277 -67.211496) (xy 420.603877 -67.185995)
			(xy 420.656661 -67.167988) (xy 420.711504 -67.157858) (xy 420.767238 -67.155821) (xy 420.822675 -67.161921)
			(xy 420.876632 -67.176027) (xy 420.927961 -67.197839) (xy 420.975567 -67.226893) (xy 421.018435 -67.262568)
			(xy 421.055652 -67.304105) (xy 421.086425 -67.350618) (xy 421.110097 -67.401115) (xy 421.126165 -67.454522)
			(xy 421.134285 -67.509698) (xy 421.134794 -67.537584) (xy 421.134285 -67.56547) (xy 421.13024 -67.592956)
			(xy 421.645332 -67.592956) (xy 421.649403 -67.537334) (xy 421.661529 -67.482897) (xy 421.681452 -67.430806)
			(xy 421.708748 -67.382171) (xy 421.742834 -67.338028) (xy 421.782983 -67.299319) (xy 421.828341 -67.266868)
			(xy 421.877941 -67.241367) (xy 421.930725 -67.22336) (xy 421.985568 -67.21323) (xy 422.041302 -67.211193)
			(xy 422.096739 -67.217293) (xy 422.150696 -67.231399) (xy 422.202025 -67.253211) (xy 422.249631 -67.282265)
			(xy 422.292499 -67.31794) (xy 422.329716 -67.359477) (xy 422.360489 -67.40599) (xy 422.384161 -67.456487)
			(xy 422.400229 -67.509894) (xy 422.408346 -67.565047) (xy 424.746716 -67.565047) (xy 424.746716 -67.510553)
			(xy 424.754471 -67.456613) (xy 424.769823 -67.404325) (xy 424.79246 -67.354755) (xy 424.821921 -67.30891)
			(xy 424.857606 -67.267725) (xy 424.898789 -67.232037) (xy 424.944632 -67.202573) (xy 424.994201 -67.179933)
			(xy 425.046487 -67.164577) (xy 425.100427 -67.156818) (xy 425.127674 -67.15633) (xy 425.155044 -67.156804)
			(xy 425.209223 -67.164619) (xy 425.261726 -67.180106) (xy 425.311473 -67.202946) (xy 425.35744 -67.232669)
			(xy 425.378372 -67.25031) (xy 425.378626 -67.250564) (xy 425.385724 -67.256133) (xy 425.402632 -67.262389)
			(xy 425.411646 -67.262756) (xy 425.478702 -67.262756) (xy 425.48772 -67.262409) (xy 425.504637 -67.256155)
			(xy 425.511722 -67.250564) (xy 425.511722 -67.25031) (xy 425.511976 -67.25031) (xy 425.532908 -67.23267)
			(xy 425.57888 -67.202958) (xy 425.628628 -67.180122) (xy 425.681129 -67.164631) (xy 425.735305 -67.156804)
			(xy 425.762674 -67.15633) (xy 425.789931 -67.156715) (xy 425.84389 -67.16447) (xy 425.896196 -67.179825)
			(xy 425.945785 -67.202469) (xy 425.991646 -67.231939) (xy 426.032846 -67.267636) (xy 426.068546 -67.308834)
			(xy 426.098019 -67.354693) (xy 426.120666 -67.404279) (xy 426.136025 -67.456585) (xy 426.143783 -67.510543)
			(xy 426.143783 -67.565057) (xy 426.136025 -67.619015) (xy 426.120666 -67.671321) (xy 426.098019 -67.720907)
			(xy 426.068546 -67.766766) (xy 426.032846 -67.807964) (xy 425.991646 -67.843661) (xy 425.945785 -67.873131)
			(xy 425.896196 -67.895775) (xy 425.84389 -67.91113) (xy 425.789931 -67.918885) (xy 425.762674 -67.919346)
			(xy 425.735303 -67.918908) (xy 425.681122 -67.911086) (xy 425.628618 -67.895591) (xy 425.578871 -67.872742)
			(xy 425.532906 -67.843011) (xy 425.511976 -67.825366) (xy 425.511722 -67.825112) (xy 425.504632 -67.81953)
			(xy 425.487718 -67.81328) (xy 425.478702 -67.81292) (xy 425.411646 -67.81292) (xy 425.402631 -67.813295)
			(xy 425.385714 -67.81953) (xy 425.378626 -67.825112) (xy 425.378626 -67.825366) (xy 425.378372 -67.825366)
			(xy 425.357419 -67.84298) (xy 425.311453 -67.872696) (xy 425.26171 -67.895538) (xy 425.209214 -67.911035)
			(xy 425.155042 -67.918869) (xy 425.127674 -67.919346) (xy 425.100427 -67.918782) (xy 425.046487 -67.911023)
			(xy 424.994201 -67.895667) (xy 424.944632 -67.873027) (xy 424.898789 -67.843563) (xy 424.857606 -67.807875)
			(xy 424.821921 -67.76669) (xy 424.79246 -67.720845) (xy 424.769823 -67.671275) (xy 424.754471 -67.618987)
			(xy 424.746716 -67.565047) (xy 422.408346 -67.565047) (xy 422.408349 -67.56507) (xy 422.408858 -67.592956)
			(xy 422.408349 -67.620842) (xy 422.400229 -67.676018) (xy 422.384161 -67.729425) (xy 422.360489 -67.779922)
			(xy 422.329716 -67.826435) (xy 422.292499 -67.867972) (xy 422.249631 -67.903647) (xy 422.202025 -67.932701)
			(xy 422.150696 -67.954513) (xy 422.096739 -67.968619) (xy 422.041302 -67.974719) (xy 421.985568 -67.972682)
			(xy 421.930725 -67.962552) (xy 421.877941 -67.944545) (xy 421.828341 -67.919044) (xy 421.782983 -67.886593)
			(xy 421.742834 -67.847884) (xy 421.708748 -67.803741) (xy 421.681452 -67.755106) (xy 421.661529 -67.703015)
			(xy 421.649403 -67.648578) (xy 421.645332 -67.592956) (xy 421.13024 -67.592956) (xy 421.126165 -67.620646)
			(xy 421.110097 -67.674053) (xy 421.086425 -67.72455) (xy 421.055652 -67.771063) (xy 421.018435 -67.8126)
			(xy 420.975567 -67.848275) (xy 420.927961 -67.877329) (xy 420.876632 -67.899141) (xy 420.822675 -67.913247)
			(xy 420.767238 -67.919347) (xy 420.711504 -67.91731) (xy 420.656661 -67.90718) (xy 420.603877 -67.889173)
			(xy 420.554277 -67.863672) (xy 420.508919 -67.831221) (xy 420.46877 -67.792512) (xy 420.434684 -67.748369)
			(xy 420.407388 -67.699734) (xy 420.387465 -67.647643) (xy 420.375339 -67.593206) (xy 420.371268 -67.537584)
			(xy 419.839002 -67.537584) (xy 419.834067 -67.571116) (xy 419.817999 -67.624523) (xy 419.794327 -67.67502)
			(xy 419.763554 -67.721533) (xy 419.726337 -67.76307) (xy 419.683469 -67.798745) (xy 419.635863 -67.827799)
			(xy 419.584534 -67.849611) (xy 419.530577 -67.863717) (xy 419.47514 -67.869817) (xy 419.419406 -67.86778)
			(xy 419.364563 -67.85765) (xy 419.311779 -67.839643) (xy 419.262179 -67.814142) (xy 419.216821 -67.781691)
			(xy 419.176672 -67.742982) (xy 419.142586 -67.698839) (xy 419.11529 -67.650204) (xy 419.095367 -67.598113)
			(xy 419.083241 -67.543676) (xy 419.07917 -67.488054) (xy 414.21789 -67.488054) (xy 414.165726 -68.586604)
			(xy 416.925252 -68.586604) (xy 416.925708 -68.559233) (xy 416.933526 -68.505053) (xy 416.949017 -68.45255)
			(xy 416.971861 -68.402803) (xy 417.001589 -68.356837) (xy 417.019232 -68.335906) (xy 417.019486 -68.335652)
			(xy 417.025055 -68.328554) (xy 417.031313 -68.311646) (xy 417.031678 -68.302632) (xy 417.031678 -68.235576)
			(xy 417.031337 -68.226557) (xy 417.025079 -68.20964) (xy 417.019486 -68.202556) (xy 417.019232 -68.202556)
			(xy 417.019232 -68.202302) (xy 417.001585 -68.181376) (xy 416.971874 -68.135402) (xy 416.949039 -68.085653)
			(xy 416.933549 -68.033151) (xy 416.925724 -67.978974) (xy 416.925252 -67.951604) (xy 416.925781 -67.924355)
			(xy 416.933536 -67.870411) (xy 416.948889 -67.818119) (xy 416.971527 -67.768545) (xy 417.000989 -67.722696)
			(xy 417.036676 -67.681507) (xy 417.077861 -67.645815) (xy 417.123706 -67.616348) (xy 417.173278 -67.593704)
			(xy 417.225568 -67.578346) (xy 417.279511 -67.570585) (xy 417.30676 -67.570096) (xy 417.333075 -67.570525)
			(xy 417.385205 -67.577768) (xy 417.435849 -67.592094) (xy 417.484048 -67.613234) (xy 417.52889 -67.640787)
			(xy 417.569528 -67.674232) (xy 417.587684 -67.693286) (xy 417.595212 -67.70068) (xy 417.614487 -67.709209)
			(xy 417.625022 -67.709796) (xy 417.699698 -67.709796) (xy 417.710249 -67.70928) (xy 417.729544 -67.700736)
			(xy 417.737036 -67.693286) (xy 417.755178 -67.674217) (xy 417.795811 -67.640762) (xy 417.840654 -67.613205)
			(xy 417.888858 -67.592069) (xy 417.939507 -67.577754) (xy 417.991643 -67.570533) (xy 418.01796 -67.570096)
			(xy 418.045329 -67.570586) (xy 418.099507 -67.578399) (xy 418.15201 -67.593882) (xy 418.201757 -67.616718)
			(xy 418.247725 -67.646437) (xy 418.268658 -67.664076) (xy 418.268912 -67.66433) (xy 418.275988 -67.669931)
			(xy 418.292913 -67.676168) (xy 418.301932 -67.676522) (xy 418.368988 -67.676522) (xy 418.378004 -67.676154)
			(xy 418.39492 -67.669914) (xy 418.402008 -67.66433) (xy 418.402008 -67.664076) (xy 418.402262 -67.664076)
			(xy 418.423194 -67.646438) (xy 418.469168 -67.616726) (xy 418.518915 -67.593891) (xy 418.571415 -67.578399)
			(xy 418.625591 -67.570571) (xy 418.65296 -67.570096) (xy 418.680212 -67.570593) (xy 418.734162 -67.578344)
			(xy 418.786459 -67.593695) (xy 418.83604 -67.616333) (xy 418.881893 -67.645798) (xy 418.923086 -67.681488)
			(xy 418.958781 -67.722678) (xy 418.988249 -67.768529) (xy 419.010892 -67.818107) (xy 419.026248 -67.870403)
			(xy 419.034005 -67.924352) (xy 419.034468 -67.951604) (xy 419.034012 -67.978975) (xy 419.026193 -68.033155)
			(xy 419.010702 -68.085658) (xy 418.987858 -68.135405) (xy 418.958131 -68.181371) (xy 418.940488 -68.202302)
			(xy 418.940234 -68.202556) (xy 418.934652 -68.209645) (xy 418.928404 -68.22656) (xy 418.928042 -68.235576)
			(xy 418.928042 -68.302632) (xy 418.928375 -68.311652) (xy 418.934638 -68.328569) (xy 418.940234 -68.335652)
			(xy 418.940488 -68.335652) (xy 418.940488 -68.335906) (xy 418.958141 -68.356827) (xy 418.987852 -68.402802)
			(xy 419.010685 -68.452553) (xy 419.026173 -68.505056) (xy 419.033996 -68.559234) (xy 419.034468 -68.586604)
			(xy 419.034048 -68.613859) (xy 419.02629 -68.667813) (xy 419.010931 -68.720114) (xy 418.994299 -68.75653)
			(xy 422.470326 -68.75653) (xy 422.470803 -68.72916) (xy 422.478617 -68.674981) (xy 422.494104 -68.622478)
			(xy 422.516943 -68.572731) (xy 422.546666 -68.526764) (xy 422.564306 -68.505832) (xy 422.56456 -68.505578)
			(xy 422.570169 -68.498507) (xy 422.576401 -68.481578) (xy 422.576752 -68.472558) (xy 422.576752 -68.405502)
			(xy 422.576404 -68.396484) (xy 422.570151 -68.379567) (xy 422.56456 -68.372482) (xy 422.564306 -68.372482)
			(xy 422.564306 -68.372228) (xy 422.546668 -68.351295) (xy 422.516955 -68.305323) (xy 422.494119 -68.255575)
			(xy 422.478628 -68.203075) (xy 422.4708 -68.148899) (xy 422.470326 -68.12153) (xy 422.470783 -68.094276)
			(xy 422.478537 -68.040323) (xy 422.493891 -67.988023) (xy 422.516533 -67.938441) (xy 422.546001 -67.892586)
			(xy 422.581695 -67.851392) (xy 422.622889 -67.815698) (xy 422.668745 -67.786231) (xy 422.718327 -67.76359)
			(xy 422.770627 -67.748236) (xy 422.82458 -67.740483) (xy 422.851834 -67.740022) (xy 422.879205 -67.740463)
			(xy 422.933386 -67.748286) (xy 422.985889 -67.763781) (xy 423.035636 -67.786628) (xy 423.081601 -67.816358)
			(xy 423.102532 -67.834002) (xy 423.102786 -67.834256) (xy 423.109868 -67.83985) (xy 423.126788 -67.846091)
			(xy 423.135806 -67.846448) (xy 423.202862 -67.846448) (xy 423.211878 -67.846084) (xy 423.228796 -67.839843)
			(xy 423.235882 -67.834256) (xy 423.235882 -67.834002) (xy 423.236136 -67.834002) (xy 423.257082 -67.81638)
			(xy 423.303051 -67.786665) (xy 423.352795 -67.763826) (xy 423.405292 -67.748331) (xy 423.459466 -67.740498)
			(xy 423.486834 -67.740022) (xy 423.513149 -67.74046) (xy 423.565279 -67.7477) (xy 423.615923 -67.762024)
			(xy 423.664122 -67.783162) (xy 423.708964 -67.810714) (xy 423.749603 -67.844158) (xy 423.767758 -67.863212)
			(xy 423.775292 -67.870599) (xy 423.794563 -67.879131) (xy 423.805096 -67.879722) (xy 423.879772 -67.879722)
			(xy 423.890321 -67.879185) (xy 423.909615 -67.870654) (xy 423.91711 -67.863212) (xy 423.93527 -67.844161)
			(xy 423.975899 -67.810703) (xy 424.020738 -67.783143) (xy 424.068938 -67.762004) (xy 424.119585 -67.747686)
			(xy 424.171718 -67.740461) (xy 424.198034 -67.740022) (xy 424.225287 -67.740446) (xy 424.279239 -67.748208)
			(xy 424.331537 -67.763569) (xy 424.381116 -67.786216) (xy 424.426968 -67.815689) (xy 424.468158 -67.851387)
			(xy 424.503849 -67.892584) (xy 424.533314 -67.93844) (xy 424.555953 -67.988023) (xy 424.571305 -68.040324)
			(xy 424.579058 -68.094276) (xy 424.579542 -68.12153) (xy 424.579108 -68.148902) (xy 424.571284 -68.203083)
			(xy 424.555789 -68.255587) (xy 424.532939 -68.305333) (xy 424.503207 -68.351298) (xy 424.485562 -68.372228)
			(xy 424.485308 -68.372482) (xy 424.479724 -68.37957) (xy 424.473475 -68.396486) (xy 424.473116 -68.405502)
			(xy 424.473116 -68.472558) (xy 424.47349 -68.481573) (xy 424.479725 -68.49849) (xy 424.485308 -68.505578)
			(xy 424.485562 -68.505578) (xy 424.485562 -68.505832) (xy 424.503177 -68.526784) (xy 424.532894 -68.572751)
			(xy 424.555735 -68.622493) (xy 424.571231 -68.67499) (xy 424.579065 -68.729162) (xy 424.579542 -68.75653)
			(xy 424.57905 -68.78378) (xy 424.57129 -68.837726) (xy 424.555933 -68.890019) (xy 424.533291 -68.939594)
			(xy 424.503825 -68.985442) (xy 424.468134 -69.026631) (xy 424.426946 -69.062322) (xy 424.381097 -69.091789)
			(xy 424.331522 -69.114432) (xy 424.27923 -69.12979) (xy 424.225284 -69.13755) (xy 424.198034 -69.138038)
			(xy 424.171718 -69.137634) (xy 424.119586 -69.130389) (xy 424.068941 -69.116059) (xy 424.020742 -69.094915)
			(xy 423.9759 -69.067356) (xy 423.935264 -69.033906) (xy 423.91711 -69.014848) (xy 423.90958 -69.007456)
			(xy 423.890307 -68.998925) (xy 423.879772 -68.998338) (xy 423.805096 -68.998338) (xy 423.794543 -68.99884)
			(xy 423.775247 -69.007393) (xy 423.767758 -69.014848) (xy 423.749625 -69.033926) (xy 423.70899 -69.067379)
			(xy 423.664144 -69.094934) (xy 423.615939 -69.116068) (xy 423.565288 -69.130381) (xy 423.513151 -69.137602)
			(xy 423.486834 -69.138038) (xy 423.459464 -69.137567) (xy 423.405284 -69.129753) (xy 423.352781 -69.114266)
			(xy 423.303034 -69.091425) (xy 423.257067 -69.0617) (xy 423.236136 -69.044058) (xy 423.235882 -69.043804)
			(xy 423.228804 -69.038204) (xy 423.211881 -69.031965) (xy 423.202862 -69.031612) (xy 423.135806 -69.031612)
			(xy 423.126789 -69.031969) (xy 423.109872 -69.038216) (xy 423.102786 -69.043804) (xy 423.102786 -69.044058)
			(xy 423.102532 -69.044058) (xy 423.081593 -69.061689) (xy 423.035623 -69.091404) (xy 422.985877 -69.114242)
			(xy 422.933378 -69.129734) (xy 422.879203 -69.137564) (xy 422.851834 -69.138038) (xy 422.824583 -69.137513)
			(xy 422.770636 -69.129762) (xy 422.718341 -69.114411) (xy 422.668763 -69.091775) (xy 422.622911 -69.062313)
			(xy 422.581719 -69.026626) (xy 422.546025 -68.98544) (xy 422.516556 -68.939593) (xy 422.493911 -68.890019)
			(xy 422.478552 -68.837726) (xy 422.470791 -68.783781) (xy 422.470326 -68.75653) (xy 418.994299 -68.75653)
			(xy 418.988285 -68.769697) (xy 418.958813 -68.815552) (xy 418.923115 -68.856746) (xy 418.881917 -68.89244)
			(xy 418.836059 -68.921906) (xy 418.786473 -68.944547) (xy 418.73417 -68.959899) (xy 418.680215 -68.967651)
			(xy 418.65296 -68.968112) (xy 418.625591 -68.967608) (xy 418.571414 -68.959799) (xy 418.518911 -68.944318)
			(xy 418.469164 -68.921485) (xy 418.423195 -68.891769) (xy 418.402262 -68.874132) (xy 418.402008 -68.873878)
			(xy 418.394925 -68.868286) (xy 418.378005 -68.862043) (xy 418.368988 -68.861686) (xy 418.301932 -68.861686)
			(xy 418.292917 -68.862061) (xy 418.276 -68.868296) (xy 418.268912 -68.873878) (xy 418.268912 -68.874132)
			(xy 418.268658 -68.874132) (xy 418.247719 -68.891762) (xy 418.201748 -68.921474) (xy 418.152002 -68.944312)
			(xy 418.099503 -68.959805) (xy 418.045329 -68.967636) (xy 418.01796 -68.968112) (xy 417.991645 -68.967667)
			(xy 417.939516 -68.960427) (xy 417.888873 -68.946104) (xy 417.840674 -68.924967) (xy 417.795831 -68.897417)
			(xy 417.755192 -68.863975) (xy 417.737036 -68.844922) (xy 417.7295 -68.837537) (xy 417.710231 -68.829003)
			(xy 417.699698 -68.828412) (xy 417.625022 -68.828412) (xy 417.614472 -68.828936) (xy 417.595176 -68.837474)
			(xy 417.587684 -68.844922) (xy 417.569534 -68.863983) (xy 417.528902 -68.897438) (xy 417.484061 -68.924996)
			(xy 417.435859 -68.946134) (xy 417.385211 -68.96045) (xy 417.333076 -68.967674) (xy 417.30676 -68.968112)
			(xy 417.279508 -68.967659) (xy 417.225559 -68.959898) (xy 417.173264 -68.944538) (xy 417.123687 -68.921892)
			(xy 417.077837 -68.892422) (xy 417.036647 -68.856727) (xy 417.000956 -68.815534) (xy 416.971491 -68.769681)
			(xy 416.94885 -68.720102) (xy 416.933495 -68.667806) (xy 416.925738 -68.613856) (xy 416.925252 -68.586604)
			(xy 414.165726 -68.586604) (xy 414.115504 -69.64426) (xy 414.114337 -69.666429) (xy 414.11027 -69.710642)
			(xy 414.107376 -69.732652) (xy 414.105598 -69.745606) (xy 414.101788 -69.771514) (xy 414.101788 -69.771768)
			(xy 414.101026 -69.775832) (xy 414.101026 -69.77634) (xy 413.848652 -71.555864) (xy 419.49446 -71.555864)
			(xy 419.498531 -71.500242) (xy 419.510657 -71.445805) (xy 419.53058 -71.393714) (xy 419.557876 -71.345079)
			(xy 419.591962 -71.300936) (xy 419.632111 -71.262227) (xy 419.677469 -71.229776) (xy 419.727069 -71.204275)
			(xy 419.779853 -71.186268) (xy 419.834696 -71.176138) (xy 419.89043 -71.174101) (xy 419.945867 -71.180201)
			(xy 419.999824 -71.194307) (xy 420.051153 -71.216119) (xy 420.098759 -71.245173) (xy 420.141627 -71.280848)
			(xy 420.178844 -71.322385) (xy 420.209617 -71.368898) (xy 420.233289 -71.419395) (xy 420.249357 -71.472802)
			(xy 420.257477 -71.527978) (xy 420.257986 -71.555864) (xy 420.257477 -71.58375) (xy 420.251638 -71.623428)
			(xy 421.003474 -71.623428) (xy 421.007545 -71.567806) (xy 421.019671 -71.513369) (xy 421.039594 -71.461278)
			(xy 421.06689 -71.412643) (xy 421.100976 -71.3685) (xy 421.141125 -71.329791) (xy 421.186483 -71.29734)
			(xy 421.236083 -71.271839) (xy 421.288867 -71.253832) (xy 421.34371 -71.243702) (xy 421.399444 -71.241665)
			(xy 421.454881 -71.247765) (xy 421.508838 -71.261871) (xy 421.560167 -71.283683) (xy 421.607773 -71.312737)
			(xy 421.650641 -71.348412) (xy 421.687858 -71.389949) (xy 421.718631 -71.436462) (xy 421.742303 -71.486959)
			(xy 421.758371 -71.540366) (xy 421.766491 -71.595542) (xy 421.767 -71.623428) (xy 421.766491 -71.651314)
			(xy 421.758371 -71.70649) (xy 421.742303 -71.759897) (xy 421.718631 -71.810394) (xy 421.687858 -71.856907)
			(xy 421.650641 -71.898444) (xy 421.607773 -71.934119) (xy 421.560167 -71.963173) (xy 421.508838 -71.984985)
			(xy 421.454881 -71.999091) (xy 421.399444 -72.005191) (xy 421.34371 -72.003154) (xy 421.288867 -71.993024)
			(xy 421.236083 -71.975017) (xy 421.186483 -71.949516) (xy 421.141125 -71.917065) (xy 421.100976 -71.878356)
			(xy 421.06689 -71.834213) (xy 421.039594 -71.785578) (xy 421.019671 -71.733487) (xy 421.007545 -71.67905)
			(xy 421.003474 -71.623428) (xy 420.251638 -71.623428) (xy 420.249357 -71.638926) (xy 420.233289 -71.692333)
			(xy 420.209617 -71.74283) (xy 420.178844 -71.789343) (xy 420.141627 -71.83088) (xy 420.098759 -71.866555)
			(xy 420.051153 -71.895609) (xy 419.999824 -71.917421) (xy 419.945867 -71.931527) (xy 419.89043 -71.937627)
			(xy 419.834696 -71.93559) (xy 419.779853 -71.92546) (xy 419.727069 -71.907453) (xy 419.677469 -71.881952)
			(xy 419.632111 -71.849501) (xy 419.591962 -71.810792) (xy 419.557876 -71.766649) (xy 419.53058 -71.718014)
			(xy 419.510657 -71.665923) (xy 419.498531 -71.611486) (xy 419.49446 -71.555864) (xy 413.848652 -71.555864)
			(xy 413.639 -73.034144) (xy 411.951617 -84.938108) (xy 413.4612 -84.938108) (xy 413.461671 -84.910698)
			(xy 413.469516 -84.856442) (xy 413.485047 -84.803868) (xy 413.507942 -84.754058) (xy 413.537732 -84.708038)
			(xy 413.573801 -84.666755) (xy 413.594296 -84.648548) (xy 413.601528 -84.641675) (xy 413.610541 -84.623898)
			(xy 413.611822 -84.614004) (xy 413.618426 -84.532216) (xy 413.61233 -84.51342) (xy 413.605726 -84.505546)
			(xy 413.588681 -84.484776) (xy 413.559995 -84.439344) (xy 413.537969 -84.390336) (xy 413.52304 -84.338722)
			(xy 413.515504 -84.285523) (xy 413.515048 -84.258658) (xy 413.515656 -84.228536) (xy 413.525128 -84.169042)
			(xy 413.54383 -84.111774) (xy 413.571298 -84.058156) (xy 413.606849 -84.00952) (xy 413.627824 -83.987894)
			(xy 413.628078 -83.98764) (xy 413.634653 -83.980391) (xy 413.642222 -83.962358) (xy 413.64281 -83.952588)
			(xy 413.643826 -83.871562) (xy 413.636714 -83.853274) (xy 413.629856 -83.845908) (xy 413.610269 -83.8245)
			(xy 413.577154 -83.776856) (xy 413.551627 -83.724751) (xy 413.534274 -83.669384) (xy 413.525495 -83.612029)
			(xy 413.524954 -83.583018) (xy 413.52544 -83.555767) (xy 413.533196 -83.501819) (xy 413.548551 -83.449524)
			(xy 413.571193 -83.399947) (xy 413.600659 -83.354097) (xy 413.63635 -83.312906) (xy 413.677541 -83.277215)
			(xy 413.723391 -83.247749) (xy 413.772968 -83.225107) (xy 413.825263 -83.209752) (xy 413.879211 -83.201996)
			(xy 413.933713 -83.201996) (xy 413.987661 -83.209752) (xy 414.039956 -83.225107) (xy 414.089533 -83.247749)
			(xy 414.135383 -83.277215) (xy 414.176574 -83.312906) (xy 414.212265 -83.354097) (xy 414.241731 -83.399947)
			(xy 414.264373 -83.449524) (xy 414.279728 -83.501819) (xy 414.287484 -83.555767) (xy 414.28797 -83.583018)
			(xy 414.287405 -83.613142) (xy 414.277922 -83.672638) (xy 414.259209 -83.729906) (xy 414.231732 -83.783523)
			(xy 414.196173 -83.832157) (xy 414.175194 -83.853782) (xy 414.17494 -83.854036) (xy 414.168377 -83.861295)
			(xy 414.160801 -83.87932) (xy 414.160208 -83.889088) (xy 414.159192 -83.970114) (xy 414.166304 -83.988402)
			(xy 414.173162 -83.995768) (xy 414.192741 -84.017183) (xy 414.225856 -84.064826) (xy 414.251385 -84.116929)
			(xy 414.26874 -84.172294) (xy 414.277521 -84.229647) (xy 414.278064 -84.258658) (xy 414.277583 -84.286068)
			(xy 414.269741 -84.340324) (xy 414.254214 -84.392898) (xy 414.23132 -84.442709) (xy 414.201532 -84.488729)
			(xy 414.165463 -84.530011) (xy 414.144968 -84.548218) (xy 414.137744 -84.555097) (xy 414.128727 -84.57287)
			(xy 414.127442 -84.582762) (xy 414.120838 -84.66455) (xy 414.126934 -84.683346) (xy 414.133538 -84.69122)
			(xy 414.150577 -84.711995) (xy 414.179262 -84.757426) (xy 414.201288 -84.806433) (xy 414.216218 -84.858046)
			(xy 414.223758 -84.911243) (xy 414.224216 -84.938108) (xy 414.22373 -84.965359) (xy 414.215974 -85.019307)
			(xy 414.200619 -85.071602) (xy 414.177977 -85.121179) (xy 414.148511 -85.167029) (xy 414.11282 -85.20822)
			(xy 414.071629 -85.243911) (xy 414.025779 -85.273377) (xy 413.976202 -85.296019) (xy 413.923907 -85.311374)
			(xy 413.869959 -85.31913) (xy 413.815457 -85.31913) (xy 413.761509 -85.311374) (xy 413.709214 -85.296019)
			(xy 413.659637 -85.273377) (xy 413.613787 -85.243911) (xy 413.572596 -85.20822) (xy 413.536905 -85.167029)
			(xy 413.507439 -85.121179) (xy 413.484797 -85.071602) (xy 413.469442 -85.019307) (xy 413.461686 -84.965359)
			(xy 413.4612 -84.938108) (xy 411.951617 -84.938108) (xy 411.352828 -89.162382) (xy 412.65932 -89.162382)
			(xy 412.663391 -89.10676) (xy 412.675517 -89.052323) (xy 412.69544 -89.000232) (xy 412.722736 -88.951597)
			(xy 412.756822 -88.907454) (xy 412.796971 -88.868745) (xy 412.842329 -88.836294) (xy 412.891929 -88.810793)
			(xy 412.944713 -88.792786) (xy 412.999556 -88.782656) (xy 413.05529 -88.780619) (xy 413.110727 -88.786719)
			(xy 413.164684 -88.800825) (xy 413.216013 -88.822637) (xy 413.263619 -88.851691) (xy 413.306487 -88.887366)
			(xy 413.343704 -88.928903) (xy 413.374477 -88.975416) (xy 413.398149 -89.025913) (xy 413.414217 -89.07932)
			(xy 413.422337 -89.134496) (xy 413.422846 -89.162382) (xy 413.422337 -89.190268) (xy 413.414217 -89.245444)
			(xy 413.398149 -89.298851) (xy 413.374477 -89.349348) (xy 413.343704 -89.395861) (xy 413.306487 -89.437398)
			(xy 413.263619 -89.473073) (xy 413.216013 -89.502127) (xy 413.164684 -89.523939) (xy 413.110727 -89.538045)
			(xy 413.05529 -89.544145) (xy 412.999556 -89.542108) (xy 412.944713 -89.531978) (xy 412.891929 -89.513971)
			(xy 412.842329 -89.48847) (xy 412.796971 -89.456019) (xy 412.756822 -89.41731) (xy 412.722736 -89.373167)
			(xy 412.69544 -89.324532) (xy 412.675517 -89.272441) (xy 412.663391 -89.218004) (xy 412.65932 -89.162382)
			(xy 411.352828 -89.162382) (xy 411.042866 -91.349068) (xy 411.041904 -91.359527) (xy 411.04755 -91.379734)
			(xy 411.053788 -91.388184) (xy 411.05455 -91.388946) (xy 411.058076 -91.393016) (xy 411.06653 -91.399683)
			(xy 411.071314 -91.402154) (xy 411.080712 -91.406726) (xy 411.602428 -91.415108) (xy 412.357824 -91.427046)
			(xy 412.369749 -91.426646) (xy 412.391213 -91.4163) (xy 412.398972 -91.407234) (xy 412.74619 -90.95486)
			(xy 413.935926 -89.40546) (xy 413.941213 -89.397874) (xy 413.946442 -89.380154) (xy 413.946086 -89.370916)
			(xy 413.945578 -89.361772) (xy 413.937704 -89.345008) (xy 413.9311 -89.338404) (xy 413.909915 -89.316763)
			(xy 413.873978 -89.26802) (xy 413.846191 -89.214213) (xy 413.827251 -89.156693) (xy 413.817635 -89.096903)
			(xy 413.817054 -89.066624) (xy 413.817054 -89.05113) (xy 413.818546 -89.024798) (xy 413.827877 -88.972887)
			(xy 413.844265 -88.922756) (xy 413.867398 -88.875358) (xy 413.896836 -88.831596) (xy 413.932018 -88.792303)
			(xy 413.972274 -88.758227) (xy 413.994346 -88.74379) (xy 414.005014 -88.737186) (xy 414.005776 -88.736678)
			(xy 414.012126 -88.725502) (xy 414.015107 -88.719719) (xy 414.01832 -88.707115) (xy 414.018476 -88.70061)
			(xy 414.017968 -88.614504) (xy 414.017738 -88.608131) (xy 414.014527 -88.595794) (xy 414.011618 -88.59012)
			(xy 414.00857 -88.584532) (xy 413.99968 -88.575134) (xy 413.994092 -88.571832) (xy 413.970863 -88.556796)
			(xy 413.928599 -88.521084) (xy 413.89193 -88.479646) (xy 413.861625 -88.433351) (xy 413.838318 -88.383167)
			(xy 413.822497 -88.330144) (xy 413.814493 -88.275394) (xy 413.814006 -88.247728) (xy 413.814492 -88.220477)
			(xy 413.822248 -88.166529) (xy 413.837603 -88.114234) (xy 413.860245 -88.064657) (xy 413.889711 -88.018807)
			(xy 413.925402 -87.977616) (xy 413.966593 -87.941925) (xy 414.012443 -87.912459) (xy 414.06202 -87.889817)
			(xy 414.114315 -87.874462) (xy 414.168263 -87.866706) (xy 414.222765 -87.866706) (xy 414.276713 -87.874462)
			(xy 414.329008 -87.889817) (xy 414.378585 -87.912459) (xy 414.424435 -87.941925) (xy 414.465626 -87.977616)
			(xy 414.501317 -88.018807) (xy 414.530783 -88.064657) (xy 414.553425 -88.114234) (xy 414.56878 -88.166529)
			(xy 414.576536 -88.220477) (xy 414.577022 -88.247728) (xy 414.576587 -88.274004) (xy 414.569383 -88.32606)
			(xy 414.555099 -88.376635) (xy 414.534008 -88.424769) (xy 414.506508 -88.469552) (xy 414.473121 -88.510136)
			(xy 414.434478 -88.545752) (xy 414.391312 -88.575725) (xy 414.344439 -88.599489) (xy 414.31972 -88.608408)
			(xy 414.309903 -88.612352) (xy 414.294379 -88.626693) (xy 414.285932 -88.646065) (xy 414.285987 -88.667199)
			(xy 414.294536 -88.686527) (xy 414.310135 -88.700786) (xy 414.319974 -88.704674) (xy 414.338796 -88.71124)
			(xy 414.375068 -88.727783) (xy 414.392364 -88.737694) (xy 414.40059 -88.742092) (xy 414.418961 -88.745221)
			(xy 414.428178 -88.74379) (xy 414.437068 -88.742012) (xy 414.452308 -88.732614) (xy 415.343594 -87.572088)
			(xy 415.345118 -87.569802) (xy 415.346134 -87.568278) (xy 415.353236 -87.557873) (xy 415.368614 -87.537917)
			(xy 415.376868 -87.5284) (xy 415.37763 -87.527638) (xy 415.378392 -87.526622) (xy 415.38017 -87.524336)
			(xy 415.3916 -87.50935) (xy 415.395754 -87.503232) (xy 415.400664 -87.489289) (xy 415.401252 -87.481918)
			(xy 415.403538 -87.416894) (xy 415.403601 -87.412376) (xy 415.40233 -87.403431) (xy 415.400998 -87.399114)
			(xy 415.39795 -87.38997) (xy 415.396934 -87.3887) (xy 415.379668 -87.367853) (xy 415.350579 -87.322205)
			(xy 415.328236 -87.272903) (xy 415.313087 -87.220938) (xy 415.305437 -87.167352) (xy 415.304986 -87.140288)
			(xy 415.305473 -87.113037) (xy 415.31323 -87.05909) (xy 415.328587 -87.006797) (xy 415.351228 -86.957221)
			(xy 415.380695 -86.911371) (xy 415.416386 -86.870182) (xy 415.457576 -86.834491) (xy 415.503426 -86.805025)
			(xy 415.553002 -86.782384) (xy 415.605296 -86.767029) (xy 415.659243 -86.759272) (xy 415.686494 -86.75878)
			(xy 415.687002 -86.75878) (xy 415.711548 -86.759174) (xy 415.760231 -86.7655) (xy 415.8077 -86.778022)
			(xy 415.853169 -86.796533) (xy 415.874708 -86.80831) (xy 415.877502 -86.809834) (xy 415.885147 -86.813263)
			(xy 415.901742 -86.815478) (xy 415.910014 -86.814152) (xy 415.918904 -86.812374) (xy 415.926524 -86.807548)
			(xy 415.930272 -86.805098) (xy 415.93691 -86.799088) (xy 415.939732 -86.79561) (xy 416.046412 -86.656418)
			(xy 416.731958 -85.763862) (xy 416.734498 -85.760052) (xy 416.735006 -85.759036) (xy 416.742286 -85.746183)
			(xy 416.749876 -85.717648) (xy 416.749031 -85.688133) (xy 416.744912 -85.673946) (xy 416.739876 -85.660499)
			(xy 416.723534 -85.636905) (xy 416.701283 -85.618775) (xy 416.674874 -85.607537) (xy 416.646382 -85.604074)
			(xy 416.632136 -85.605874) (xy 416.630358 -85.606128) (xy 416.614848 -85.60852) (xy 416.583567 -85.611067)
			(xy 416.567874 -85.611208) (xy 416.563048 -85.611208) (xy 416.536009 -85.610414) (xy 416.482553 -85.602136)
			(xy 416.430803 -85.58639) (xy 416.381795 -85.563493) (xy 416.336512 -85.533903) (xy 416.295863 -85.498215)
			(xy 416.260661 -85.457142) (xy 416.231614 -85.41151) (xy 416.209303 -85.362232) (xy 416.194176 -85.310297)
			(xy 416.186536 -85.256747) (xy 416.186112 -85.2297) (xy 416.186575 -85.202448) (xy 416.194332 -85.148498)
			(xy 416.209689 -85.096201) (xy 416.232331 -85.046622) (xy 416.2618 -85.000771) (xy 416.297494 -84.95958)
			(xy 416.338687 -84.923888) (xy 416.38454 -84.894422) (xy 416.43412 -84.871782) (xy 416.486417 -84.856428)
			(xy 416.540368 -84.848674) (xy 416.56762 -84.848192) (xy 416.595824 -84.848693) (xy 416.651618 -84.856985)
			(xy 416.705584 -84.873399) (xy 416.756545 -84.897579) (xy 416.803393 -84.928997) (xy 416.845105 -84.966969)
			(xy 416.880772 -85.010668) (xy 416.909619 -85.059141) (xy 416.931016 -85.111332) (xy 416.944497 -85.166104)
			(xy 416.947604 -85.19414) (xy 416.949462 -85.208758) (xy 416.960448 -85.236087) (xy 416.97877 -85.259149)
			(xy 417.002909 -85.276028) (xy 417.030858 -85.285322) (xy 417.060298 -85.286261) (xy 417.088782 -85.278765)
			(xy 417.113946 -85.263457) (xy 417.124134 -85.252814) (xy 417.126674 -85.249766) (xy 419.71087 -81.884266)
			(xy 420.899082 -80.336644) (xy 420.904113 -80.329426) (xy 420.909452 -80.312675) (xy 420.909496 -80.303878)
			(xy 420.909242 -80.295496) (xy 420.902638 -80.278986) (xy 420.896796 -80.272382) (xy 420.878898 -80.251363)
			(xy 420.848716 -80.205139) (xy 420.82551 -80.155049) (xy 420.809765 -80.102137) (xy 420.801809 -80.047508)
			(xy 420.801292 -80.019906) (xy 420.801755 -79.992653) (xy 420.809511 -79.938701) (xy 420.824867 -79.886403)
			(xy 420.847509 -79.836822) (xy 420.876977 -79.790968) (xy 420.91267 -79.749775) (xy 420.953863 -79.71408)
			(xy 420.999717 -79.684612) (xy 421.049297 -79.661969) (xy 421.101595 -79.646612) (xy 421.155547 -79.638855)
			(xy 421.1828 -79.638398) (xy 421.183308 -79.638398) (xy 421.212632 -79.638949) (xy 421.270587 -79.647947)
			(xy 421.326484 -79.665699) (xy 421.35298 -79.678276) (xy 421.353234 -79.67853) (xy 421.353742 -79.678784)
			(xy 421.361729 -79.682213) (xy 421.379002 -79.684044) (xy 421.387524 -79.68234) (xy 421.395398 -79.680562)
			(xy 421.40251 -79.67599) (xy 421.406098 -79.673552) (xy 421.412487 -79.667683) (xy 421.41521 -79.664306)
			(xy 432.42992 -65.318894) (xy 432.433768 -65.313519) (xy 432.438779 -65.301291) (xy 432.439826 -65.294764)
			(xy 432.441604 -65.28181) (xy 432.43627 -65.26911) (xy 432.427272 -65.246089) (xy 432.414614 -65.19831)
			(xy 432.408225 -65.149298) (xy 432.407822 -65.124584) (xy 432.407822 -65.115948) (xy 432.40885 -65.089075)
			(xy 432.417525 -65.036003) (xy 432.433568 -64.984675) (xy 432.45666 -64.936109) (xy 432.486345 -64.891267)
			(xy 432.522033 -64.851039) (xy 432.563017 -64.816222) (xy 432.608485 -64.787507) (xy 432.657535 -64.765461)
			(xy 432.709195 -64.750523) (xy 432.762442 -64.742988) (xy 432.78933 -64.742568) (xy 432.79314 -64.742568)
			(xy 432.804475 -64.742742) (xy 432.827096 -64.744265) (xy 432.838352 -64.745616) (xy 432.839114 -64.745616)
			(xy 432.845634 -64.746265) (xy 432.858623 -64.744589) (xy 432.864768 -64.742314) (xy 432.870102 -64.740028)
			(xy 432.880516 -64.732154) (xy 433.312824 -64.169036) (xy 433.419504 -64.030098) (xy 433.796186 -63.538862)
			(xy 433.80025 -63.53302) (xy 433.833778 -63.473584) (xy 434.050948 -63.088012) (xy 434.083206 -63.0301)
			(xy 434.087835 -63.019622) (xy 434.088102 -62.996739) (xy 434.083714 -62.986158) (xy 434.080158 -62.978538)
			(xy 434.073808 -62.972188) (xy 434.053634 -62.950689) (xy 434.019485 -62.902631) (xy 433.993136 -62.849892)
			(xy 433.975214 -62.793727) (xy 433.966145 -62.735473) (xy 433.965604 -62.705996) (xy 433.966068 -62.678744)
			(xy 433.973825 -62.624794) (xy 433.989182 -62.572497) (xy 434.011825 -62.522918) (xy 434.041293 -62.477067)
			(xy 434.076987 -62.435875) (xy 434.118179 -62.400183) (xy 434.164032 -62.370717) (xy 434.213612 -62.348076)
			(xy 434.265909 -62.332722) (xy 434.31986 -62.324966) (xy 434.347112 -62.324488) (xy 434.369025 -62.324767)
			(xy 434.412567 -62.329735) (xy 434.43398 -62.334394) (xy 434.444785 -62.33634) (xy 434.466273 -62.331947)
			(xy 434.484011 -62.319047) (xy 434.48986 -62.309756) (xy 434.524912 -62.247526) (xy 434.544724 -62.21222)
			(xy 434.548401 -62.205118) (xy 434.551623 -62.189465) (xy 434.551074 -62.181486) (xy 434.550312 -62.175898)
			(xy 434.548788 -62.171326) (xy 434.541778 -62.14902) (xy 434.532607 -62.103172) (xy 434.5305 -62.079886)
			(xy 434.529484 -62.055502) (xy 434.529484 -62.051438) (xy 434.529979 -62.023715) (xy 434.538001 -61.968853)
			(xy 434.553883 -61.915731) (xy 434.577289 -61.865468) (xy 434.607725 -61.819123) (xy 434.644552 -61.777674)
			(xy 434.686991 -61.741994) (xy 434.73415 -61.712834) (xy 434.785034 -61.69081) (xy 434.811678 -61.683138)
			(xy 434.811932 -61.683138) (xy 434.814726 -61.682376) (xy 434.823543 -61.678982) (xy 434.838127 -61.666996)
			(xy 434.843174 -61.659008) (xy 434.871368 -61.60262) (xy 434.874924 -61.592968) (xy 434.930804 -61.382148)
			(xy 434.94071 -61.34481) (xy 435.116478 -60.682124) (xy 435.115462 -60.672726) (xy 435.113938 -60.654184)
			(xy 435.113684 -60.650374) (xy 435.113176 -60.63361) (xy 435.113176 -60.633102) (xy 435.113787 -60.603382)
			(xy 435.123081 -60.544671) (xy 435.141352 -60.488107) (xy 435.168158 -60.435053) (xy 435.185058 -60.410598)
			(xy 435.187691 -60.406752) (xy 435.19165 -60.398315) (xy 435.192932 -60.393834) (xy 435.216046 -60.30595)
			(xy 435.28107 -60.060332) (xy 435.295802 -60.004706) (xy 435.29758 -59.991752) (xy 435.29758 -58.819288)
			(xy 435.297406 -58.813136) (xy 435.294444 -58.801194) (xy 435.291738 -58.795666) (xy 435.27853 -58.77052)
			(xy 435.270656 -58.76163) (xy 435.266084 -58.758328) (xy 435.242247 -58.740187) (xy 435.199987 -58.697736)
			(xy 435.164864 -58.649216) (xy 435.137737 -58.595812) (xy 435.119268 -58.538831) (xy 435.10991 -58.479667)
			(xy 435.109366 -58.449718) (xy 435.109814 -58.423574) (xy 435.116987 -58.37178) (xy 435.131161 -58.32145)
			(xy 435.15207 -58.273524) (xy 435.179322 -58.228899) (xy 435.212409 -58.188411) (xy 435.231286 -58.170318)
			(xy 435.231794 -58.16981) (xy 435.232048 -58.169556) (xy 435.236075 -58.16553) (xy 435.242364 -58.156041)
			(xy 435.244494 -58.15076) (xy 435.246526 -58.145426) (xy 435.248304 -58.133742) (xy 434.959252 -55.372762)
			(xy 434.877718 -54.592474) (xy 434.876964 -54.586971) (xy 434.873368 -54.576465) (xy 434.870606 -54.571646)
			(xy 434.867662 -54.566962) (xy 434.860097 -54.558894) (xy 434.85562 -54.555644) (xy 434.855366 -54.555644)
			(xy 434.833443 -54.540386) (xy 434.793684 -54.504721) (xy 434.759286 -54.46386) (xy 434.730921 -54.418602)
			(xy 434.709144 -54.369831) (xy 434.694381 -54.3185) (xy 434.686919 -54.265612) (xy 434.686456 -54.238906)
			(xy 434.687001 -54.209465) (xy 434.696047 -54.15128) (xy 434.713924 -54.095177) (xy 434.740208 -54.042486)
			(xy 434.774275 -53.994458) (xy 434.794406 -53.972968) (xy 434.79847 -53.968904) (xy 434.804058 -53.959506)
			(xy 434.80609 -53.954172) (xy 434.807793 -53.948887) (xy 434.809083 -53.937862) (xy 434.80863 -53.932328)
			(xy 434.803296 -53.881528) (xy 434.650134 -52.416964) (xy 434.579522 -51.742086) (xy 434.577359 -51.731466)
			(xy 434.565506 -51.713345) (xy 434.54724 -51.701717) (xy 434.536596 -51.699668) (xy 434.534564 -51.699414)
			(xy 434.506018 -51.695727) (xy 434.45041 -51.680876) (xy 434.397661 -51.657847) (xy 434.348966 -51.627162)
			(xy 434.305428 -51.589517) (xy 434.268033 -51.545763) (xy 434.25237 -51.521614) (xy 434.251354 -51.520344)
			(xy 434.24462 -51.511334) (xy 434.225383 -51.499729) (xy 434.21427 -51.497992) (xy 434.174646 -51.493928)
			(xy 434.174138 -51.493928) (xy 434.150516 -51.491388) (xy 434.150008 -51.491388) (xy 434.13426 -51.489864)
			(xy 434.122626 -51.489269) (xy 434.100799 -51.497339) (xy 434.09235 -51.505358) (xy 434.092096 -51.505612)
			(xy 434.074001 -51.524178) (xy 434.033665 -51.556747) (xy 433.989291 -51.583557) (xy 433.941697 -51.604115)
			(xy 433.891759 -51.618042) (xy 433.840396 -51.625082) (xy 433.814474 -51.6255) (xy 433.787224 -51.625012)
			(xy 433.73328 -51.617253) (xy 433.680988 -51.601895) (xy 433.631415 -51.579253) (xy 433.585568 -51.549786)
			(xy 433.544382 -51.514094) (xy 433.508694 -51.472904) (xy 433.479231 -51.427055) (xy 433.456593 -51.37748)
			(xy 433.44124 -51.325187) (xy 433.433485 -51.271242) (xy 433.432966 -51.243992) (xy 433.433391 -51.218481)
			(xy 433.440187 -51.167914) (xy 433.453657 -51.118702) (xy 433.473561 -51.071722) (xy 433.499544 -51.027812)
			(xy 433.515008 -51.007518) (xy 433.517548 -51.00447) (xy 433.518564 -51.002946) (xy 433.521866 -50.996342)
			(xy 433.524212 -50.99112) (xy 433.52678 -50.979966) (xy 433.526946 -50.974244) (xy 433.526946 -50.94224)
			(xy 433.538122 -50.94224) (xy 433.538122 -50.89144) (xy 433.537788 -50.882836) (xy 433.53208 -50.866602)
			(xy 433.526946 -50.85969) (xy 433.525676 -50.858166) (xy 433.508282 -50.83729) (xy 433.478962 -50.79154)
			(xy 433.456433 -50.742092) (xy 433.441151 -50.689947) (xy 433.433425 -50.636161) (xy 433.432966 -50.608992)
			(xy 433.433452 -50.58174) (xy 433.44121 -50.527792) (xy 433.456565 -50.475497) (xy 433.479206 -50.425919)
			(xy 433.508672 -50.380068) (xy 433.544364 -50.338876) (xy 433.585553 -50.303183) (xy 433.631403 -50.273715)
			(xy 433.68098 -50.251071) (xy 433.733275 -50.235713) (xy 433.787222 -50.227954) (xy 433.814474 -50.227484)
			(xy 433.842513 -50.227985) (xy 433.897985 -50.236207) (xy 433.951656 -50.252463) (xy 434.002367 -50.276402)
			(xy 434.049027 -50.307509) (xy 434.090629 -50.345112) (xy 434.10886 -50.366422) (xy 434.109114 -50.366676)
			(xy 434.115972 -50.374804) (xy 434.139594 -50.386488) (xy 434.145944 -50.389536) (xy 434.150835 -50.391616)
			(xy 434.161207 -50.393922) (xy 434.166518 -50.394108) (xy 434.223922 -50.394108) (xy 434.229297 -50.393941)
			(xy 434.239796 -50.391628) (xy 434.24475 -50.389536) (xy 434.2511 -50.386488) (xy 434.26507 -50.379884)
			(xy 434.269486 -50.377589) (xy 434.277415 -50.371577) (xy 434.280818 -50.367946) (xy 434.281834 -50.366676)
			(xy 434.30698 -50.33899) (xy 434.326668 -50.319964) (xy 434.370525 -50.287191) (xy 434.394356 -50.273712)
			(xy 434.402738 -50.269394) (xy 434.407818 -50.2666) (xy 434.41493 -50.25263) (xy 434.418151 -50.245932)
			(xy 434.420976 -50.231347) (xy 434.420518 -50.223928) (xy 434.39588 -49.98847) (xy 434.393922 -49.976034)
			(xy 434.379805 -49.955229) (xy 434.368956 -49.948846) (xy 434.331618 -49.929288) (xy 434.293264 -49.908968)
			(xy 434.281999 -49.903955) (xy 434.257372 -49.904358) (xy 434.246274 -49.90973) (xy 434.218118 -49.924339)
			(xy 434.158164 -49.945046) (xy 434.095616 -49.955576) (xy 434.063902 -49.956212) (xy 434.03839 -49.955788)
			(xy 433.987822 -49.948994) (xy 433.938608 -49.935528) (xy 433.891625 -49.915628) (xy 433.84771 -49.88965)
			(xy 433.827428 -49.87417) (xy 433.82438 -49.87163) (xy 433.822856 -49.870614) (xy 433.816252 -49.867312)
			(xy 433.81103 -49.864966) (xy 433.799876 -49.862397) (xy 433.794154 -49.862232) (xy 433.76215 -49.862232)
			(xy 433.76215 -49.851056) (xy 433.71135 -49.851056) (xy 433.702746 -49.851389) (xy 433.686516 -49.857103)
			(xy 433.6796 -49.862232) (xy 433.678076 -49.863502) (xy 433.657198 -49.880892) (xy 433.611447 -49.910203)
			(xy 433.561999 -49.932721) (xy 433.509854 -49.947992) (xy 433.456069 -49.955706) (xy 433.428902 -49.956212)
			(xy 433.40339 -49.955788) (xy 433.352822 -49.948994) (xy 433.303608 -49.935528) (xy 433.256625 -49.915628)
			(xy 433.21271 -49.88965) (xy 433.192428 -49.87417) (xy 433.18938 -49.87163) (xy 433.187856 -49.870614)
			(xy 433.181252 -49.867312) (xy 433.17603 -49.864966) (xy 433.164876 -49.862397) (xy 433.159154 -49.862232)
			(xy 433.12715 -49.862232) (xy 433.12715 -49.851056) (xy 433.07635 -49.851056) (xy 433.067746 -49.851389)
			(xy 433.051516 -49.857103) (xy 433.0446 -49.862232) (xy 433.043076 -49.863502) (xy 433.022198 -49.880892)
			(xy 432.976447 -49.910203) (xy 432.926999 -49.932721) (xy 432.874854 -49.947992) (xy 432.821069 -49.955706)
			(xy 432.793902 -49.956212) (xy 432.766649 -49.955749) (xy 432.712697 -49.947992) (xy 432.660398 -49.932636)
			(xy 432.610818 -49.909993) (xy 432.564964 -49.880525) (xy 432.52377 -49.844831) (xy 432.488076 -49.803638)
			(xy 432.458608 -49.757784) (xy 432.435965 -49.708203) (xy 432.420608 -49.655905) (xy 432.412851 -49.601953)
			(xy 432.412851 -49.547447) (xy 432.420608 -49.493495) (xy 432.435965 -49.441197) (xy 432.458608 -49.391616)
			(xy 432.488076 -49.345762) (xy 432.52377 -49.304569) (xy 432.564964 -49.268875) (xy 432.610818 -49.239407)
			(xy 432.660398 -49.216764) (xy 432.712697 -49.201408) (xy 432.766649 -49.193651) (xy 432.793902 -49.193196)
			(xy 432.819413 -49.193621) (xy 432.869982 -49.200415) (xy 432.919195 -49.213882) (xy 432.966178 -49.233782)
			(xy 433.010091 -49.259761) (xy 433.030376 -49.275238) (xy 433.033424 -49.277778) (xy 433.034948 -49.278794)
			(xy 433.041552 -49.282096) (xy 433.046774 -49.284441) (xy 433.057928 -49.287009) (xy 433.06365 -49.287176)
			(xy 433.095654 -49.287176) (xy 433.095654 -49.298352) (xy 433.146454 -49.298352) (xy 433.155058 -49.298018)
			(xy 433.171288 -49.292305) (xy 433.178204 -49.287176) (xy 433.179728 -49.285906) (xy 433.200604 -49.26851)
			(xy 433.246352 -49.239187) (xy 433.2958 -49.216656) (xy 433.347946 -49.201372) (xy 433.401733 -49.193644)
			(xy 433.428902 -49.193196) (xy 433.454413 -49.193621) (xy 433.504982 -49.200415) (xy 433.554195 -49.213882)
			(xy 433.601178 -49.233782) (xy 433.645091 -49.259761) (xy 433.665376 -49.275238) (xy 433.668424 -49.277778)
			(xy 433.669948 -49.278794) (xy 433.676552 -49.282096) (xy 433.681774 -49.284441) (xy 433.692928 -49.287009)
			(xy 433.69865 -49.287176) (xy 433.730654 -49.287176) (xy 433.730654 -49.298352) (xy 433.781454 -49.298352)
			(xy 433.790058 -49.298018) (xy 433.806288 -49.292305) (xy 433.813204 -49.287176) (xy 433.814728 -49.285906)
			(xy 433.822094 -49.279302) (xy 433.82311 -49.278794) (xy 433.82438 -49.277778) (xy 433.824888 -49.27727)
			(xy 433.846986 -49.26076) (xy 433.87899 -49.240948) (xy 433.879244 -49.240948) (xy 433.879498 -49.240694)
			(xy 433.8843 -49.237842) (xy 433.892636 -49.230413) (xy 433.896008 -49.225962) (xy 433.899564 -49.221136)
			(xy 433.903882 -49.210468) (xy 433.91582 -49.13503) (xy 433.916437 -49.12437) (xy 433.909999 -49.104036)
			(xy 433.903374 -49.09566) (xy 428.077884 -42.736516) (xy 428.070694 -42.729966) (xy 428.052802 -42.722383)
			(xy 428.033373 -42.722039) (xy 428.015223 -42.728983) (xy 428.00778 -42.735246) (xy 428.004224 -42.738548)
			(xy 427.998128 -42.744136) (xy 427.989746 -42.768012) (xy 427.991778 -42.780712) (xy 427.993962 -42.79522)
			(xy 427.996378 -42.824462) (xy 427.996604 -42.839132) (xy 427.996604 -42.84091) (xy 427.996118 -42.868161)
			(xy 427.98836 -42.922107) (xy 427.973004 -42.974401) (xy 427.950362 -43.023977) (xy 427.920895 -43.069825)
			(xy 427.885203 -43.111014) (xy 427.844013 -43.146704) (xy 427.798163 -43.176169) (xy 427.748586 -43.198809)
			(xy 427.696292 -43.214163) (xy 427.642345 -43.221919) (xy 427.587844 -43.221918) (xy 427.533897 -43.214161)
			(xy 427.481604 -43.198805) (xy 427.432028 -43.176164) (xy 427.386178 -43.146698) (xy 427.344989 -43.111007)
			(xy 427.309299 -43.069817) (xy 427.279833 -43.023967) (xy 427.257193 -42.974391) (xy 427.241838 -42.922097)
			(xy 427.234082 -42.86815) (xy 427.234082 -42.813649) (xy 427.241838 -42.759702) (xy 427.257193 -42.707408)
			(xy 427.279834 -42.657832) (xy 427.309299 -42.611982) (xy 427.34499 -42.570792) (xy 427.386179 -42.535101)
			(xy 427.432029 -42.505635) (xy 427.481605 -42.482994) (xy 427.533899 -42.467639) (xy 427.587845 -42.459882)
			(xy 427.615096 -42.459402) (xy 427.63819 -42.459755) (xy 427.684036 -42.465361) (xy 427.706536 -42.470578)
			(xy 427.714156 -42.472356) (xy 427.729142 -42.471594) (xy 427.743112 -42.466514) (xy 427.75505 -42.45737)
			(xy 427.75759 -42.453814) (xy 427.797468 -42.39895) (xy 427.803051 -42.390615) (xy 427.80777 -42.371134)
			(xy 427.804618 -42.351338) (xy 427.799754 -42.342562) (xy 427.459902 -41.787064) (xy 427.199044 -41.360344)
			(xy 427.19647 -41.356348) (xy 427.190079 -41.349314) (xy 427.186344 -41.346374) (xy 427.178978 -41.340786)
			(xy 427.169834 -41.338246) (xy 427.143407 -41.33008) (xy 427.093059 -41.307184) (xy 427.046543 -41.277259)
			(xy 427.004834 -41.240932) (xy 426.968807 -41.198965) (xy 426.939215 -41.152236) (xy 426.927518 -41.127172)
			(xy 426.917363 -41.103353) (xy 426.902865 -41.053646) (xy 426.895242 -41.002432) (xy 426.894498 -40.97655)
			(xy 426.894498 -40.968422) (xy 426.894752 -40.953182) (xy 426.894752 -40.951404) (xy 426.895616 -40.938299)
			(xy 426.898923 -40.912241) (xy 426.901356 -40.899334) (xy 426.903134 -40.89019) (xy 426.90161 -40.881046)
			(xy 426.900637 -40.876408) (xy 426.897191 -40.867583) (xy 426.894752 -40.86352) (xy 426.759878 -40.643302)
			(xy 426.597064 -40.37711) (xy 426.593689 -40.371992) (xy 426.584964 -40.363383) (xy 426.579792 -40.360092)
			(xy 426.569124 -40.353742) (xy 426.562266 -40.353234) (xy 426.556424 -40.35298) (xy 426.527906 -40.350877)
			(xy 426.47193 -40.339205) (xy 426.418321 -40.319312) (xy 426.368281 -40.291642) (xy 426.32293 -40.256815)
			(xy 426.283283 -40.21561) (xy 426.250229 -40.168951) (xy 426.224507 -40.117883) (xy 426.206693 -40.063548)
			(xy 426.197186 -40.007163) (xy 426.196252 -39.978584) (xy 426.196252 -39.971472) (xy 426.196687 -39.946615)
			(xy 426.203212 -39.89733) (xy 426.216083 -39.84931) (xy 426.225208 -39.826184) (xy 426.229018 -39.816786)
			(xy 426.231558 -39.811452) (xy 426.23359 -39.79926) (xy 426.233336 -39.793418) (xy 426.232691 -39.787443)
			(xy 426.228971 -39.776018) (xy 426.22597 -39.770812) (xy 425.868084 -39.186104) (xy 425.859448 -39.180008)
			(xy 425.821189 -39.152733) (xy 425.749434 -39.092061) (xy 425.683691 -39.024922) (xy 425.653708 -38.988746)
			(xy 425.6532 -38.988238) (xy 425.649898 -38.984174) (xy 425.641262 -38.977316) (xy 425.617386 -38.965886)
			(xy 425.612061 -38.963423) (xy 425.600645 -38.960725) (xy 425.59478 -38.960552) (xy 425.526454 -38.961314)
			(xy 425.52051 -38.961509) (xy 425.508962 -38.964341) (xy 425.503594 -38.966902) (xy 425.50334 -38.966902)
			(xy 425.498419 -38.969658) (xy 425.489828 -38.976962) (xy 425.486322 -38.98138) (xy 425.486068 -38.981634)
			(xy 425.470263 -39.001752) (xy 425.434142 -39.037985) (xy 425.393503 -39.069065) (xy 425.349075 -39.094436)
			(xy 425.301655 -39.113641) (xy 425.252094 -39.126337) (xy 425.226734 -39.129716) (xy 425.218098 -39.130732)
			(xy 425.18203 -39.132256) (xy 425.154545 -39.13178) (xy 425.100142 -39.123904) (xy 425.04743 -39.108311)
			(xy 424.997498 -39.085323) (xy 424.951378 -39.055414) (xy 424.910021 -39.019202) (xy 424.874282 -38.977435)
			(xy 424.859196 -38.954456) (xy 424.859196 -38.954202) (xy 424.856656 -38.950138) (xy 424.855894 -38.949122)
			(xy 424.85183 -38.945058) (xy 424.84294 -38.938454) (xy 424.823382 -38.926262) (xy 424.818055 -38.923222)
			(xy 424.806372 -38.919496) (xy 424.800268 -38.918896) (xy 424.729656 -38.914324) (xy 424.718817 -38.914114)
			(xy 424.698549 -38.921749) (xy 424.69054 -38.929056) (xy 424.68673 -38.932866) (xy 424.684952 -38.935152)
			(xy 424.68419 -38.936168) (xy 424.665977 -38.958791) (xy 424.623869 -38.998788) (xy 424.576193 -39.031951)
			(xy 424.524045 -39.057515) (xy 424.46863 -39.074891) (xy 424.411222 -39.083679) (xy 424.382184 -39.08425)
			(xy 424.38193 -39.08425) (xy 424.354673 -39.083789) (xy 424.300713 -39.076035) (xy 424.248405 -39.06068)
			(xy 424.198816 -39.038036) (xy 424.152954 -39.008566) (xy 424.111753 -38.972868) (xy 424.076052 -38.93167)
			(xy 424.046578 -38.88581) (xy 424.023931 -38.836223) (xy 424.008572 -38.783917) (xy 424.000813 -38.729957)
			(xy 424.000813 -38.675443) (xy 424.008572 -38.621483) (xy 424.023931 -38.569177) (xy 424.046578 -38.519589)
			(xy 424.076052 -38.47373) (xy 424.111753 -38.432532) (xy 424.152954 -38.396834) (xy 424.198816 -38.367364)
			(xy 424.248405 -38.34472) (xy 424.300713 -38.329365) (xy 424.354673 -38.321611) (xy 424.38193 -38.321234)
			(xy 424.409413 -38.321714) (xy 424.463811 -38.329597) (xy 424.516517 -38.345196) (xy 424.566443 -38.368189)
			(xy 424.612558 -38.398101) (xy 424.653909 -38.434313) (xy 424.689642 -38.47608) (xy 424.704764 -38.499034)
			(xy 424.704764 -38.499288) (xy 424.707304 -38.503352) (xy 424.708066 -38.504368) (xy 424.71213 -38.508432)
			(xy 424.72102 -38.515036) (xy 424.740578 -38.527228) (xy 424.745956 -38.530308) (xy 424.757774 -38.53403)
			(xy 424.763946 -38.534594) (xy 424.834812 -38.539166) (xy 424.838114 -38.539166) (xy 424.878246 -38.519608)
			(xy 424.880024 -38.517322) (xy 424.897682 -38.495332) (xy 424.938379 -38.456293) (xy 424.984373 -38.423659)
			(xy 425.034663 -38.39814) (xy 425.088158 -38.380289) (xy 425.143696 -38.370495) (xy 425.17187 -38.36924)
			(xy 425.178474 -38.368986) (xy 425.188888 -38.363652) (xy 425.19427 -38.360682) (xy 425.203518 -38.35259)
			(xy 425.207176 -38.34765) (xy 425.22521 -38.321996) (xy 425.228004 -38.317678) (xy 425.232592 -38.308397)
			(xy 425.234684 -38.287818) (xy 425.232068 -38.2778) (xy 425.222404 -38.250424) (xy 425.205883 -38.194763)
			(xy 425.199048 -38.166548) (xy 425.197524 -38.159436) (xy 425.19727 -38.158674) (xy 425.180252 -38.130988)
			(xy 425.174156 -38.125654) (xy 425.141136 -38.096444) (xy 425.108014 -38.065097) (xy 425.047006 -37.997304)
			(xy 424.992431 -37.924234) (xy 424.968162 -37.885624) (xy 424.709336 -37.462968) (xy 424.69347 -37.43665)
			(xy 424.66462 -37.382383) (xy 424.651678 -37.35451) (xy 424.635422 -37.31641) (xy 424.633898 -37.3126)
			(xy 424.545252 -37.168328) (xy 424.523719 -37.132478) (xy 424.486077 -37.057791) (xy 424.454872 -36.980194)
			(xy 424.430328 -36.900241) (xy 424.421046 -36.859464) (xy 424.41241 -36.814252) (xy 424.410886 -36.8046)
			(xy 424.384216 -36.760912) (xy 424.37685 -36.755324) (xy 424.356709 -36.739193) (xy 424.32054 -36.702389)
			(xy 424.289673 -36.661038) (xy 424.264673 -36.615896) (xy 424.25493 -36.592002) (xy 424.25112 -36.582096)
			(xy 423.816018 -36.143438) (xy 423.808771 -36.13754) (xy 423.791318 -36.130906) (xy 423.781982 -36.130484)
			(xy 423.777664 -36.130484) (xy 423.767699 -36.130965) (xy 423.749266 -36.138543) (xy 423.74185 -36.145216)
			(xy 423.741596 -36.14547) (xy 423.719972 -36.166451) (xy 423.671339 -36.202014) (xy 423.617722 -36.229495)
			(xy 423.560454 -36.248211) (xy 423.500956 -36.257697) (xy 423.470832 -36.258246) (xy 423.443578 -36.257762)
			(xy 423.389625 -36.25001) (xy 423.337324 -36.234658) (xy 423.287741 -36.212019) (xy 423.241883 -36.182554)
			(xy 423.200686 -36.146863) (xy 423.164988 -36.105673) (xy 423.135515 -36.059821) (xy 423.112867 -36.010241)
			(xy 423.097505 -35.957943) (xy 423.089743 -35.903992) (xy 423.089324 -35.876738) (xy 423.089324 -35.876484)
			(xy 423.089748 -35.851359) (xy 423.09638 -35.801546) (xy 423.109474 -35.753031) (xy 423.128806 -35.706646)
			(xy 423.154042 -35.663191) (xy 423.16908 -35.643058) (xy 423.173531 -35.636318) (xy 423.178338 -35.620907)
			(xy 423.178478 -35.612832) (xy 423.178224 -35.605212) (xy 423.177208 -35.58159) (xy 423.176455 -35.572422)
			(xy 423.169299 -35.55549) (xy 423.163238 -35.54857) (xy 422.977818 -35.363404) (xy 422.94048 -35.32378)
			(xy 422.938448 -35.321494) (xy 422.932098 -35.314382) (xy 422.923716 -35.310064) (xy 422.91929 -35.307872)
			(xy 422.909824 -35.30506) (xy 422.90492 -35.304476) (xy 422.887902 -35.302952) (xy 422.883351 -35.302686)
			(xy 422.874278 -35.303574) (xy 422.869868 -35.30473) (xy 422.861232 -35.307016) (xy 422.853104 -35.313366)
			(xy 422.815824 -35.341181) (xy 422.736978 -35.390535) (xy 422.65388 -35.432337) (xy 422.567252 -35.466223)
			(xy 422.477847 -35.491898) (xy 422.386439 -35.509141) (xy 422.293824 -35.5178) (xy 422.247314 -35.518344)
			(xy 422.224454 -35.51809) (xy 422.223692 -35.51809) (xy 422.183644 -35.516721) (xy 422.103944 -35.508358)
			(xy 422.025172 -35.493625) (xy 421.947837 -35.472615) (xy 421.910002 -35.459416) (xy 421.87021 -35.444654)
			(xy 421.793055 -35.409274) (xy 421.719185 -35.367466) (xy 421.649136 -35.319532) (xy 421.583414 -35.265818)
			(xy 421.522494 -35.206713) (xy 421.466818 -35.142645) (xy 421.416787 -35.074077) (xy 421.394382 -35.03803)
			(xy 421.391842 -35.033712) (xy 421.382952 -35.023806) (xy 421.376602 -35.017964) (xy 421.354428 -34.999744)
			(xy 421.315277 -34.957781) (xy 421.282846 -34.910433) (xy 421.257866 -34.858764) (xy 421.240898 -34.80394)
			(xy 421.232326 -34.747193) (xy 421.231822 -34.718498) (xy 421.231822 -34.718244) (xy 421.232326 -34.689809)
			(xy 421.240741 -34.633566) (xy 421.248586 -34.60623) (xy 421.25011 -34.599118) (xy 421.251888 -34.588196)
			(xy 421.251888 -34.584386) (xy 421.251634 -34.581592) (xy 421.249856 -34.52114) (xy 421.249856 -34.502852)
			(xy 421.249856 -34.50082) (xy 421.250618 -34.481008) (xy 421.251629 -34.458462) (xy 421.255442 -34.413487)
			(xy 421.258238 -34.391092) (xy 421.265091 -34.343493) (xy 421.286775 -34.249797) (xy 421.317377 -34.158623)
			(xy 421.33647 -34.114486) (xy 421.339518 -34.104834) (xy 421.343074 -34.089594) (xy 421.343074 -34.088578)
			(xy 421.339518 -34.073338) (xy 421.33647 -34.063686) (xy 421.31979 -34.025283) (xy 421.29218 -33.946233)
			(xy 421.271301 -33.865145) (xy 421.257299 -33.782591) (xy 421.250274 -33.699153) (xy 421.249856 -33.657286)
			(xy 421.251888 -33.595564) (xy 421.25265 -33.584134) (xy 421.25011 -33.576006) (xy 421.248159 -33.571241)
			(xy 421.242657 -33.562539) (xy 421.239188 -33.558734) (xy 421.21963 -33.53816) (xy 421.215566 -33.53435)
			(xy 421.209377 -33.529549) (xy 421.194896 -33.523595) (xy 421.187118 -33.522666) (xy 421.1828 -33.522412)
			(xy 420.801292 -33.522412) (xy 420.755665 -33.521851) (xy 420.664801 -33.513419) (xy 420.575086 -33.496725)
			(xy 420.531036 -33.48482) (xy 420.493112 -33.473753) (xy 420.418982 -33.446418) (xy 420.382954 -33.43021)
			(xy 420.372794 -33.425638) (xy 420.362634 -33.420812) (xy 420.329614 -33.420812) (xy 420.319979 -33.421274)
			(xy 420.30209 -33.428448) (xy 420.294816 -33.434782) (xy 420.263958 -33.463683) (xy 420.198129 -33.516746)
			(xy 420.128042 -33.564043) (xy 420.054202 -33.605235) (xy 419.977139 -33.640026) (xy 419.897406 -33.668165)
			(xy 419.815576 -33.689451) (xy 419.732238 -33.70373) (xy 419.64799 -33.710901) (xy 419.605714 -33.711388)
			(xy 419.60546 -33.711388) (xy 419.60546 -33.711642) (xy 419.605206 -33.711642) (xy 419.558726 -33.711107)
			(xy 419.466169 -33.702455) (xy 419.374819 -33.685224) (xy 419.28547 -33.659565) (xy 419.198897 -33.625701)
			(xy 419.115852 -33.583925) (xy 419.037057 -33.5346) (xy 418.963194 -33.478155) (xy 418.894907 -33.415079)
			(xy 418.832788 -33.345921) (xy 418.777376 -33.271281) (xy 418.752782 -33.231836) (xy 418.750242 -33.227772)
			(xy 418.737796 -33.214056) (xy 418.734494 -33.211516) (xy 418.712674 -33.193616) (xy 418.674037 -33.152479)
			(xy 418.64187 -33.106107) (xy 418.616875 -33.055508) (xy 418.599594 -33.001782) (xy 418.590403 -32.946099)
			(xy 418.58946 -32.917892) (xy 418.589714 -32.903922) (xy 418.59064 -32.877213) (xy 418.599052 -32.824438)
			(xy 418.606478 -32.798766) (xy 418.608002 -32.791654) (xy 418.60978 -32.780732) (xy 418.60978 -32.776922)
			(xy 418.609526 -32.774128) (xy 418.607748 -32.714692) (xy 418.607748 -32.707326) (xy 418.608347 -32.670113)
			(xy 418.614405 -32.595927) (xy 418.625981 -32.522399) (xy 418.634164 -32.486092) (xy 418.64553 -32.440144)
			(xy 418.675807 -32.350457) (xy 418.694616 -32.307022) (xy 418.696394 -32.302958) (xy 418.700966 -32.282892)
			(xy 418.700966 -32.281876) (xy 418.696394 -32.26181) (xy 418.695124 -32.259016) (xy 418.679 -32.222083)
			(xy 418.652062 -32.146125) (xy 418.631334 -32.068242) (xy 418.616949 -31.988943) (xy 418.612574 -31.948882)
			(xy 418.61031 -31.924434) (xy 418.607897 -31.87539) (xy 418.607748 -31.850838) (xy 418.607748 -31.850584)
			(xy 418.609526 -31.789878) (xy 418.60978 -31.78683) (xy 418.60978 -31.78302) (xy 418.608002 -31.772098)
			(xy 418.606478 -31.76524) (xy 418.598651 -31.7379) (xy 418.590231 -31.68166) (xy 418.589714 -31.653226)
			(xy 418.589714 -31.652972) (xy 418.590259 -31.623902) (xy 418.599069 -31.566433) (xy 418.616482 -31.510962)
			(xy 418.642096 -31.458768) (xy 418.67532 -31.411056) (xy 418.715387 -31.368927) (xy 418.73805 -31.350712)
			(xy 418.74313 -31.34614) (xy 418.748972 -31.339028) (xy 418.771757 -31.301761) (xy 418.822916 -31.230952)
			(xy 418.880077 -31.164894) (xy 418.942802 -31.104094) (xy 419.010609 -31.049018) (xy 419.082978 -31.000091)
			(xy 419.159352 -30.957686) (xy 419.19906 -30.939486) (xy 419.237423 -30.922858) (xy 419.316384 -30.895336)
			(xy 419.397371 -30.874521) (xy 419.479817 -30.860558) (xy 419.563142 -30.853546) (xy 419.604952 -30.853126)
			(xy 419.605206 -30.853126) (xy 419.647788 -30.853572) (xy 419.732642 -30.860833) (xy 419.816568 -30.8753)
			(xy 419.898955 -30.896869) (xy 419.979204 -30.925383) (xy 420.05673 -30.960633) (xy 420.130969 -31.002364)
			(xy 420.201381 -31.050272) (xy 420.267452 -31.104008) (xy 420.298372 -31.133288) (xy 420.304639 -31.137823)
			(xy 420.319117 -31.143251) (xy 420.32682 -31.143956) (xy 421.176958 -31.143956) (xy 421.184324 -31.143448)
			(xy 421.192679 -31.141857) (xy 421.207732 -31.133962) (xy 421.219398 -31.121599) (xy 421.223186 -31.113984)
			(xy 421.232584 -31.09087) (xy 421.233346 -31.08325) (xy 421.233346 -31.082996) (xy 421.234108 -31.07563)
			(xy 421.236265 -31.05777) (xy 421.243517 -31.022533) (xy 421.248586 -31.005272) (xy 421.25011 -30.99816)
			(xy 421.251888 -30.987238) (xy 421.251888 -30.983428) (xy 421.251634 -30.980634) (xy 421.249856 -30.921452)
			(xy 421.249856 -30.92069) (xy 421.250297 -30.878824) (xy 421.257335 -30.795389) (xy 421.271337 -30.712837)
			(xy 421.292203 -30.631747) (xy 421.319787 -30.55269) (xy 421.33647 -30.51429) (xy 421.339518 -30.504638)
			(xy 421.343074 -30.489398) (xy 421.343074 -30.488382) (xy 421.339518 -30.473142) (xy 421.33647 -30.46349)
			(xy 421.320333 -30.426347) (xy 421.293419 -30.34996) (xy 421.272785 -30.271644) (xy 421.258565 -30.191912)
			(xy 421.250853 -30.111291) (xy 421.249856 -30.070806) (xy 421.249856 -30.056836) (xy 421.25011 -30.034738)
			(xy 421.250364 -30.03042) (xy 421.250364 -30.029912) (xy 421.250618 -30.021784) (xy 421.250618 -30.019752)
			(xy 421.246808 -30.0101) (xy 421.244837 -30.005459) (xy 421.239337 -29.997011) (xy 421.235886 -29.993336)
			(xy 421.22852 -29.98597) (xy 421.193468 -29.950156) (xy 421.188896 -29.946092) (xy 421.183358 -29.94192)
			(xy 421.170599 -29.936504) (xy 421.16375 -29.935424) (xy 421.157146 -29.934916) (xy 420.78275 -29.934916)
			(xy 420.734528 -29.934353) (xy 420.638533 -29.925045) (xy 420.543886 -29.906511) (xy 420.451472 -29.878925)
			(xy 420.362152 -29.842543) (xy 420.3192 -29.820616) (xy 420.30904 -29.820616) (xy 420.277958 -29.850943)
			(xy 420.211359 -29.906683) (xy 420.140166 -29.956421) (xy 420.064918 -29.99978) (xy 419.986185 -30.036433)
			(xy 419.904563 -30.066101) (xy 419.820671 -30.088561) (xy 419.735144 -30.10364) (xy 419.648629 -30.111227)
			(xy 419.605206 -30.1117) (xy 419.562713 -30.111257) (xy 419.478036 -30.104025) (xy 419.394282 -30.089614)
			(xy 419.312058 -30.068128) (xy 419.23196 -30.039722) (xy 419.154571 -30.004604) (xy 419.08045 -29.963026)
			(xy 419.010137 -29.915293) (xy 418.944141 -29.861748) (xy 418.882941 -29.802782) (xy 418.854636 -29.771086)
			(xy 418.826564 -29.738272) (xy 418.775567 -29.668577) (xy 418.752782 -29.631894) (xy 418.750242 -29.62783)
			(xy 418.737796 -29.614114) (xy 418.734494 -29.611574) (xy 418.712356 -29.593378) (xy 418.673261 -29.551481)
			(xy 418.640862 -29.504216) (xy 418.615884 -29.452642) (xy 418.598887 -29.397917) (xy 418.590253 -29.341267)
			(xy 418.589714 -29.312616) (xy 418.589714 -29.312108) (xy 418.589714 -29.30525) (xy 418.59073 -29.283152)
			(xy 418.594794 -29.249116) (xy 418.596878 -29.237353) (xy 418.602341 -29.214094) (xy 418.605716 -29.202634)
			(xy 418.605716 -29.202126) (xy 418.607494 -29.196284) (xy 418.60978 -29.181552) (xy 418.60978 -29.177742)
			(xy 418.609526 -29.174948) (xy 418.607748 -29.115258) (xy 418.607748 -29.114242) (xy 418.608182 -29.072295)
			(xy 418.615231 -28.988698) (xy 418.629274 -28.905987) (xy 418.650212 -28.824748) (xy 418.677897 -28.745554)
			(xy 418.694616 -28.70708) (xy 418.696394 -28.703016) (xy 418.700966 -28.68295) (xy 418.700966 -28.681934)
			(xy 418.696394 -28.661868) (xy 418.694616 -28.657804) (xy 418.677942 -28.619476) (xy 418.650323 -28.540579)
			(xy 418.629406 -28.459647) (xy 418.615338 -28.377248) (xy 418.608218 -28.293961) (xy 418.607748 -28.252166)
			(xy 418.607748 -28.250642) (xy 418.609526 -28.189936) (xy 418.60978 -28.187142) (xy 418.60978 -28.183332)
			(xy 418.608002 -28.17241) (xy 418.606478 -28.165298) (xy 418.598639 -28.137896) (xy 418.590226 -28.081527)
			(xy 418.589714 -28.05303) (xy 418.589714 -28.04668) (xy 418.589968 -28.038298) (xy 418.591238 -28.01874)
			(xy 418.591238 -28.018486) (xy 418.591746 -28.012898) (xy 418.595417 -27.983489) (xy 418.610678 -27.926224)
			(xy 418.634608 -27.872007) (xy 418.650166 -27.846782) (xy 418.653468 -27.841702) (xy 418.670672 -27.816866)
			(xy 418.711629 -27.772454) (xy 418.735002 -27.75331) (xy 418.740844 -27.747722) (xy 418.74567 -27.742388)
			(xy 418.751766 -27.73426) (xy 418.774766 -27.697232) (xy 418.826275 -27.626901) (xy 418.854636 -27.593798)
			(xy 418.882947 -27.562108) (xy 418.944144 -27.503139) (xy 419.010138 -27.449592) (xy 419.08045 -27.401857)
			(xy 419.15457 -27.36028) (xy 419.231959 -27.325163) (xy 419.312057 -27.29676) (xy 419.394282 -27.275278)
			(xy 419.478037 -27.260872) (xy 419.562714 -27.253648) (xy 419.605206 -27.253184) (xy 419.60546 -27.253184)
			(xy 419.65298 -27.253737) (xy 419.747587 -27.262793) (xy 419.840901 -27.280815) (xy 419.932076 -27.30764)
			(xy 420.020283 -27.343025) (xy 420.104719 -27.386648) (xy 420.144956 -27.411934) (xy 420.182892 -27.436962)
			(xy 420.254507 -27.492928) (xy 420.287958 -27.523694) (xy 420.293292 -27.528774) (xy 420.294562 -27.530044)
			(xy 420.294816 -27.530298) (xy 420.320216 -27.540458) (xy 420.324783 -27.542212) (xy 420.334376 -27.544128)
			(xy 420.339266 -27.544268) (xy 422.272968 -27.544268) (xy 422.321883 -27.544893) (xy 422.419239 -27.554524)
			(xy 422.515185 -27.573638) (xy 422.6088 -27.60205) (xy 422.654222 -27.620214) (xy 424.10126 -28.220924)
			(xy 424.110733 -28.223957) (xy 424.130592 -28.223298) (xy 424.1487 -28.215119) (xy 424.15587 -28.208224)
			(xy 424.156124 -28.20797) (xy 424.174248 -28.189319) (xy 424.21467 -28.156599) (xy 424.259158 -28.129665)
			(xy 424.306889 -28.109017) (xy 424.35698 -28.095036) (xy 424.408505 -28.087981) (xy 424.434508 -28.087574)
			(xy 424.461759 -28.08806) (xy 424.515707 -28.095818) (xy 424.568002 -28.111173) (xy 424.617579 -28.133815)
			(xy 424.625859 -28.139136) (xy 428.697896 -28.139136) (xy 428.701967 -28.083514) (xy 428.714093 -28.029077)
			(xy 428.734016 -27.976986) (xy 428.761312 -27.928351) (xy 428.795398 -27.884208) (xy 428.835547 -27.845499)
			(xy 428.880905 -27.813048) (xy 428.930505 -27.787547) (xy 428.983289 -27.76954) (xy 429.038132 -27.75941)
			(xy 429.093866 -27.757373) (xy 429.149303 -27.763473) (xy 429.20326 -27.777579) (xy 429.254589 -27.799391)
			(xy 429.302195 -27.828445) (xy 429.345063 -27.86412) (xy 429.38228 -27.905657) (xy 429.413053 -27.95217)
			(xy 429.436725 -28.002667) (xy 429.452793 -28.056074) (xy 429.460913 -28.11125) (xy 429.461422 -28.139136)
			(xy 429.967896 -28.139136) (xy 429.971967 -28.083514) (xy 429.984093 -28.029077) (xy 430.004016 -27.976986)
			(xy 430.031312 -27.928351) (xy 430.065398 -27.884208) (xy 430.105547 -27.845499) (xy 430.150905 -27.813048)
			(xy 430.200505 -27.787547) (xy 430.253289 -27.76954) (xy 430.308132 -27.75941) (xy 430.363866 -27.757373)
			(xy 430.419303 -27.763473) (xy 430.47326 -27.777579) (xy 430.524589 -27.799391) (xy 430.572195 -27.828445)
			(xy 430.615063 -27.86412) (xy 430.65228 -27.905657) (xy 430.683053 -27.95217) (xy 430.706725 -28.002667)
			(xy 430.722793 -28.056074) (xy 430.730913 -28.11125) (xy 430.731422 -28.139136) (xy 430.730913 -28.167022)
			(xy 430.722793 -28.222198) (xy 430.706725 -28.275605) (xy 430.683053 -28.326102) (xy 430.65228 -28.372615)
			(xy 430.615063 -28.414152) (xy 430.572195 -28.449827) (xy 430.524589 -28.478881) (xy 430.47326 -28.500693)
			(xy 430.419303 -28.514799) (xy 430.363866 -28.520899) (xy 430.308132 -28.518862) (xy 430.253289 -28.508732)
			(xy 430.200505 -28.490725) (xy 430.150905 -28.465224) (xy 430.105547 -28.432773) (xy 430.065398 -28.394064)
			(xy 430.031312 -28.349921) (xy 430.004016 -28.301286) (xy 429.984093 -28.249195) (xy 429.971967 -28.194758)
			(xy 429.967896 -28.139136) (xy 429.461422 -28.139136) (xy 429.460913 -28.167022) (xy 429.452793 -28.222198)
			(xy 429.436725 -28.275605) (xy 429.413053 -28.326102) (xy 429.38228 -28.372615) (xy 429.345063 -28.414152)
			(xy 429.302195 -28.449827) (xy 429.254589 -28.478881) (xy 429.20326 -28.500693) (xy 429.149303 -28.514799)
			(xy 429.093866 -28.520899) (xy 429.038132 -28.518862) (xy 428.983289 -28.508732) (xy 428.930505 -28.490725)
			(xy 428.880905 -28.465224) (xy 428.835547 -28.432773) (xy 428.795398 -28.394064) (xy 428.761312 -28.349921)
			(xy 428.734016 -28.301286) (xy 428.714093 -28.249195) (xy 428.701967 -28.194758) (xy 428.697896 -28.139136)
			(xy 424.625859 -28.139136) (xy 424.66343 -28.163281) (xy 424.704621 -28.198972) (xy 424.740313 -28.240162)
			(xy 424.769781 -28.286012) (xy 424.792423 -28.335589) (xy 424.80778 -28.387883) (xy 424.815539 -28.441831)
			(xy 424.816016 -28.469082) (xy 424.816016 -28.480004) (xy 424.814638 -28.509045) (xy 424.804175 -28.566233)
			(xy 424.785153 -28.62117) (xy 424.772074 -28.647136) (xy 424.768361 -28.656645) (xy 424.768013 -28.677039)
			(xy 424.775633 -28.695959) (xy 424.782488 -28.703524) (xy 425.201334 -29.12237) (xy 434.906928 -29.12237)
			(xy 434.906928 -28.25877) (xy 434.907418 -28.228802) (xy 434.915241 -28.16938) (xy 434.930754 -28.111487)
			(xy 434.95369 -28.056114) (xy 434.983657 -28.004208) (xy 435.020144 -27.956658) (xy 435.062524 -27.914278)
			(xy 435.110074 -27.877791) (xy 435.16198 -27.847824) (xy 435.217353 -27.824888) (xy 435.275246 -27.809375)
			(xy 435.334668 -27.801552) (xy 435.394604 -27.801552) (xy 435.454026 -27.809375) (xy 435.511919 -27.824888)
			(xy 435.567292 -27.847824) (xy 435.619198 -27.877791) (xy 435.666748 -27.914278) (xy 435.709128 -27.956658)
			(xy 435.745615 -28.004208) (xy 435.775582 -28.056114) (xy 435.798518 -28.111487) (xy 435.814031 -28.16938)
			(xy 435.821854 -28.228802) (xy 435.822344 -28.25877) (xy 435.822344 -29.12237) (xy 435.821854 -29.152338)
			(xy 435.814031 -29.21176) (xy 435.798518 -29.269653) (xy 435.775582 -29.325026) (xy 435.745615 -29.376932)
			(xy 435.709128 -29.424482) (xy 435.666748 -29.466862) (xy 435.619198 -29.503349) (xy 435.567292 -29.533316)
			(xy 435.511919 -29.556252) (xy 435.454026 -29.571765) (xy 435.394604 -29.579588) (xy 435.334668 -29.579588)
			(xy 435.275246 -29.571765) (xy 435.217353 -29.556252) (xy 435.16198 -29.533316) (xy 435.110074 -29.503349)
			(xy 435.062524 -29.466862) (xy 435.020144 -29.424482) (xy 434.983657 -29.376932) (xy 434.95369 -29.325026)
			(xy 434.930754 -29.269653) (xy 434.915241 -29.21176) (xy 434.907418 -29.152338) (xy 434.906928 -29.12237)
			(xy 425.201334 -29.12237) (xy 425.4881 -29.409136) (xy 425.488608 -29.409644) (xy 425.48937 -29.410406)
			(xy 425.496239 -29.416274) (xy 425.512927 -29.423162) (xy 425.530969 -29.423793) (xy 425.539662 -29.421328)
			(xy 425.540678 -29.421074) (xy 425.541694 -29.420566) (xy 425.56826 -29.412663) (xy 425.62296 -29.403737)
			(xy 425.65066 -29.402786) (xy 425.664122 -29.402786) (xy 425.690765 -29.403692) (xy 425.74342 -29.412027)
			(xy 425.794401 -29.427611) (xy 425.842717 -29.450139) (xy 425.887427 -29.479173) (xy 425.927661 -29.514148)
			(xy 425.962634 -29.554382) (xy 425.991667 -29.599093) (xy 426.014193 -29.64741) (xy 426.029775 -29.698392)
			(xy 426.038109 -29.751047) (xy 426.039026 -29.77769) (xy 426.039026 -29.784802) (xy 426.038443 -29.814703)
			(xy 426.02913 -29.873775) (xy 426.020484 -29.902404) (xy 426.018452 -29.909008) (xy 426.01769 -29.922724)
			(xy 426.019468 -29.929836) (xy 426.021296 -29.936607) (xy 426.02814 -29.948841) (xy 426.03293 -29.953966)
			(xy 426.455752 -30.376876) (xy 427.188884 -30.376876) (xy 427.189425 -30.34796) (xy 427.198145 -30.290788)
			(xy 427.215396 -30.235588) (xy 427.240784 -30.183626) (xy 427.273725 -30.136092) (xy 427.313465 -30.094076)
			(xy 427.33595 -30.075886) (xy 427.344762 -30.068284) (xy 427.354941 -30.047379) (xy 427.355508 -30.035754)
			(xy 427.355508 -29.955998) (xy 427.354953 -29.944368) (xy 427.344775 -29.923459) (xy 427.33595 -29.915866)
			(xy 427.31344 -29.897707) (xy 427.273709 -29.855679) (xy 427.240774 -29.808137) (xy 427.215391 -29.75617)
			(xy 427.19814 -29.700967) (xy 427.189416 -29.643794) (xy 427.188884 -29.614876) (xy 427.18937 -29.587625)
			(xy 427.197126 -29.533677) (xy 427.212481 -29.481382) (xy 427.235123 -29.431805) (xy 427.264589 -29.385955)
			(xy 427.30028 -29.344764) (xy 427.341471 -29.309073) (xy 427.387321 -29.279607) (xy 427.436898 -29.256965)
			(xy 427.489193 -29.24161) (xy 427.543141 -29.233854) (xy 427.597643 -29.233854) (xy 427.651591 -29.24161)
			(xy 427.703886 -29.256965) (xy 427.753463 -29.279607) (xy 427.799313 -29.309073) (xy 427.840504 -29.344764)
			(xy 427.876195 -29.385955) (xy 427.905661 -29.431805) (xy 427.928303 -29.481382) (xy 427.943658 -29.533677)
			(xy 427.951414 -29.587625) (xy 427.9519 -29.614876) (xy 427.951364 -29.643792) (xy 427.942639 -29.700963)
			(xy 427.925384 -29.756161) (xy 427.899996 -29.808123) (xy 427.867056 -29.855657) (xy 427.827318 -29.897675)
			(xy 427.804834 -29.915866) (xy 427.796041 -29.923486) (xy 427.785852 -29.944378) (xy 427.785276 -29.955998)
			(xy 427.785276 -30.035754) (xy 427.785772 -30.047392) (xy 427.795988 -30.068303) (xy 427.804834 -30.075886)
			(xy 427.827318 -30.094076) (xy 427.867051 -30.136097) (xy 427.899989 -30.183633) (xy 427.925377 -30.235594)
			(xy 427.942634 -30.290791) (xy 427.951364 -30.34796) (xy 427.9519 -30.376876) (xy 430.22901 -30.376876)
			(xy 430.229579 -30.347961) (xy 430.238297 -30.290792) (xy 430.255545 -30.235594) (xy 430.280927 -30.183632)
			(xy 430.313861 -30.136097) (xy 430.353594 -30.094078) (xy 430.376076 -30.075886) (xy 430.384892 -30.068288)
			(xy 430.395068 -30.04738) (xy 430.395634 -30.035754) (xy 430.395634 -29.955998) (xy 430.395105 -29.944364)
			(xy 430.384912 -29.923453) (xy 430.376076 -29.915866) (xy 430.353571 -29.8977) (xy 430.313838 -29.855675)
			(xy 430.280903 -29.808134) (xy 430.255518 -29.756168) (xy 430.238266 -29.700966) (xy 430.229542 -29.643793)
			(xy 430.22901 -29.614876) (xy 430.229496 -29.587625) (xy 430.237252 -29.533677) (xy 430.252607 -29.481382)
			(xy 430.275249 -29.431805) (xy 430.304715 -29.385955) (xy 430.340406 -29.344764) (xy 430.381597 -29.309073)
			(xy 430.427447 -29.279607) (xy 430.477024 -29.256965) (xy 430.529319 -29.24161) (xy 430.583267 -29.233854)
			(xy 430.637769 -29.233854) (xy 430.691717 -29.24161) (xy 430.744012 -29.256965) (xy 430.793589 -29.279607)
			(xy 430.839439 -29.309073) (xy 430.88063 -29.344764) (xy 430.916321 -29.385955) (xy 430.945787 -29.431805)
			(xy 430.968429 -29.481382) (xy 430.983784 -29.533677) (xy 430.99154 -29.587625) (xy 430.992026 -29.614876)
			(xy 430.991519 -29.643794) (xy 430.982791 -29.700967) (xy 430.965533 -29.756167) (xy 430.94014 -29.808129)
			(xy 430.907193 -29.855663) (xy 430.867448 -29.897678) (xy 430.84496 -29.915866) (xy 430.836172 -29.923491)
			(xy 430.825979 -29.944378) (xy 430.825402 -29.955998) (xy 430.825402 -30.035754) (xy 430.825924 -30.047388)
			(xy 430.836125 -30.068297) (xy 430.84496 -30.075886) (xy 430.867428 -30.094095) (xy 430.907166 -30.13611)
			(xy 430.940108 -30.183641) (xy 430.9655 -30.235599) (xy 430.982759 -30.290793) (xy 430.99149 -30.347961)
			(xy 430.992026 -30.376876) (xy 430.99154 -30.404127) (xy 430.983784 -30.458075) (xy 430.968429 -30.51037)
			(xy 430.945787 -30.559947) (xy 430.916321 -30.605797) (xy 430.88063 -30.646988) (xy 430.839439 -30.682679)
			(xy 430.793589 -30.712145) (xy 430.744012 -30.734787) (xy 430.691717 -30.750142) (xy 430.637769 -30.757898)
			(xy 430.583267 -30.757898) (xy 430.529319 -30.750142) (xy 430.477024 -30.734787) (xy 430.427447 -30.712145)
			(xy 430.381597 -30.682679) (xy 430.340406 -30.646988) (xy 430.304715 -30.605797) (xy 430.275249 -30.559947)
			(xy 430.252607 -30.51037) (xy 430.237252 -30.458075) (xy 430.229496 -30.404127) (xy 430.22901 -30.376876)
			(xy 427.9519 -30.376876) (xy 427.951414 -30.404127) (xy 427.943658 -30.458075) (xy 427.928303 -30.51037)
			(xy 427.905661 -30.559947) (xy 427.876195 -30.605797) (xy 427.840504 -30.646988) (xy 427.799313 -30.682679)
			(xy 427.753463 -30.712145) (xy 427.703886 -30.734787) (xy 427.651591 -30.750142) (xy 427.597643 -30.757898)
			(xy 427.543141 -30.757898) (xy 427.489193 -30.750142) (xy 427.436898 -30.734787) (xy 427.387321 -30.712145)
			(xy 427.341471 -30.682679) (xy 427.30028 -30.646988) (xy 427.264589 -30.605797) (xy 427.235123 -30.559947)
			(xy 427.212481 -30.51037) (xy 427.197126 -30.458075) (xy 427.18937 -30.404127) (xy 427.188884 -30.376876)
			(xy 426.455752 -30.376876) (xy 427.001231 -30.922468) (xy 433.052728 -30.922468) (xy 433.052728 -30.058868)
			(xy 433.053218 -30.0289) (xy 433.061041 -29.969478) (xy 433.076554 -29.911585) (xy 433.09949 -29.856212)
			(xy 433.129457 -29.804306) (xy 433.165944 -29.756756) (xy 433.208324 -29.714376) (xy 433.255874 -29.677889)
			(xy 433.30778 -29.647922) (xy 433.363153 -29.624986) (xy 433.421046 -29.609473) (xy 433.480468 -29.60165)
			(xy 433.540404 -29.60165) (xy 433.599826 -29.609473) (xy 433.657719 -29.624986) (xy 433.713092 -29.647922)
			(xy 433.764998 -29.677889) (xy 433.812548 -29.714376) (xy 433.854928 -29.756756) (xy 433.891415 -29.804306)
			(xy 433.921382 -29.856212) (xy 433.944318 -29.911585) (xy 433.959831 -29.969478) (xy 433.967654 -30.0289)
			(xy 433.968144 -30.058868) (xy 433.968144 -30.922468) (xy 433.967654 -30.952436) (xy 433.959831 -31.011858)
			(xy 433.944318 -31.069751) (xy 433.921382 -31.125124) (xy 433.891415 -31.17703) (xy 433.854928 -31.22458)
			(xy 433.812548 -31.26696) (xy 433.764998 -31.303447) (xy 433.713092 -31.333414) (xy 433.657719 -31.35635)
			(xy 433.599826 -31.371863) (xy 433.540404 -31.379686) (xy 433.480468 -31.379686) (xy 433.421046 -31.371863)
			(xy 433.363153 -31.35635) (xy 433.30778 -31.333414) (xy 433.255874 -31.303447) (xy 433.208324 -31.26696)
			(xy 433.165944 -31.22458) (xy 433.129457 -31.17703) (xy 433.09949 -31.125124) (xy 433.076554 -31.069751)
			(xy 433.061041 -31.011858) (xy 433.053218 -30.952436) (xy 433.052728 -30.922468) (xy 427.001231 -30.922468)
			(xy 427.259242 -31.180532) (xy 427.273212 -31.194756) (xy 427.284549 -31.206692) (xy 427.306525 -31.231208)
			(xy 427.317154 -31.243778) (xy 427.323758 -31.251398) (xy 427.331378 -31.255462) (xy 427.335715 -31.257778)
			(xy 427.345056 -31.260842) (xy 427.34992 -31.261558) (xy 427.419008 -31.269432) (xy 427.423928 -31.269886)
			(xy 427.433778 -31.269125) (xy 427.438566 -31.267908) (xy 427.44263 -31.266892) (xy 427.450758 -31.263336)
			(xy 427.454822 -31.260288) (xy 427.479528 -31.242877) (xy 427.533285 -31.215257) (xy 427.590724 -31.196457)
			(xy 427.650409 -31.186948) (xy 427.680628 -31.186374) (xy 427.707878 -31.186862) (xy 427.761824 -31.194621)
			(xy 427.814116 -31.209979) (xy 427.863691 -31.232621) (xy 427.90954 -31.262088) (xy 427.950728 -31.297779)
			(xy 427.986418 -31.338968) (xy 428.015884 -31.384817) (xy 428.038525 -31.434393) (xy 428.053881 -31.486686)
			(xy 428.061639 -31.540632) (xy 428.062136 -31.567882) (xy 428.06239 -31.567882) (xy 428.061866 -31.596582)
			(xy 428.053259 -31.653332) (xy 428.036252 -31.708154) (xy 428.030869 -31.719266) (xy 428.585374 -31.719266)
			(xy 428.589445 -31.663644) (xy 428.601571 -31.609207) (xy 428.621494 -31.557116) (xy 428.64879 -31.508481)
			(xy 428.682876 -31.464338) (xy 428.723025 -31.425629) (xy 428.768383 -31.393178) (xy 428.817983 -31.367677)
			(xy 428.870767 -31.34967) (xy 428.92561 -31.33954) (xy 428.981344 -31.337503) (xy 429.036781 -31.343603)
			(xy 429.090738 -31.357709) (xy 429.142067 -31.379521) (xy 429.189673 -31.408575) (xy 429.232541 -31.44425)
			(xy 429.269758 -31.485787) (xy 429.300531 -31.5323) (xy 429.324203 -31.582797) (xy 429.340271 -31.636204)
			(xy 429.344421 -31.664402) (xy 429.860962 -31.664402) (xy 429.865033 -31.60878) (xy 429.877159 -31.554343)
			(xy 429.897082 -31.502252) (xy 429.924378 -31.453617) (xy 429.958464 -31.409474) (xy 429.998613 -31.370765)
			(xy 430.043971 -31.338314) (xy 430.093571 -31.312813) (xy 430.146355 -31.294806) (xy 430.201198 -31.284676)
			(xy 430.256932 -31.282639) (xy 430.312369 -31.288739) (xy 430.366326 -31.302845) (xy 430.417655 -31.324657)
			(xy 430.465261 -31.353711) (xy 430.508129 -31.389386) (xy 430.545346 -31.430923) (xy 430.576119 -31.477436)
			(xy 430.599791 -31.527933) (xy 430.615859 -31.58134) (xy 430.623979 -31.636516) (xy 430.624488 -31.664402)
			(xy 430.623979 -31.692288) (xy 430.615859 -31.747464) (xy 430.606919 -31.777178) (xy 431.126136 -31.777178)
			(xy 431.130207 -31.721556) (xy 431.142333 -31.667119) (xy 431.162256 -31.615028) (xy 431.189552 -31.566393)
			(xy 431.223638 -31.52225) (xy 431.263787 -31.483541) (xy 431.309145 -31.45109) (xy 431.358745 -31.425589)
			(xy 431.411529 -31.407582) (xy 431.466372 -31.397452) (xy 431.522106 -31.395415) (xy 431.577543 -31.401515)
			(xy 431.6315 -31.415621) (xy 431.682829 -31.437433) (xy 431.730435 -31.466487) (xy 431.773303 -31.502162)
			(xy 431.81052 -31.543699) (xy 431.841293 -31.590212) (xy 431.864965 -31.640709) (xy 431.881033 -31.694116)
			(xy 431.889153 -31.749292) (xy 431.889662 -31.777178) (xy 431.889153 -31.805064) (xy 431.881033 -31.86024)
			(xy 431.864965 -31.913647) (xy 431.841293 -31.964144) (xy 431.81052 -32.010657) (xy 431.773303 -32.052194)
			(xy 431.730435 -32.087869) (xy 431.682829 -32.116923) (xy 431.6315 -32.138735) (xy 431.577543 -32.152841)
			(xy 431.522106 -32.158941) (xy 431.466372 -32.156904) (xy 431.411529 -32.146774) (xy 431.358745 -32.128767)
			(xy 431.309145 -32.103266) (xy 431.263787 -32.070815) (xy 431.223638 -32.032106) (xy 431.189552 -31.987963)
			(xy 431.162256 -31.939328) (xy 431.142333 -31.887237) (xy 431.130207 -31.8328) (xy 431.126136 -31.777178)
			(xy 430.606919 -31.777178) (xy 430.599791 -31.800871) (xy 430.576119 -31.851368) (xy 430.545346 -31.897881)
			(xy 430.508129 -31.939418) (xy 430.465261 -31.975093) (xy 430.417655 -32.004147) (xy 430.366326 -32.025959)
			(xy 430.312369 -32.040065) (xy 430.256932 -32.046165) (xy 430.201198 -32.044128) (xy 430.146355 -32.033998)
			(xy 430.093571 -32.015991) (xy 430.043971 -31.99049) (xy 429.998613 -31.958039) (xy 429.958464 -31.91933)
			(xy 429.924378 -31.875187) (xy 429.897082 -31.826552) (xy 429.877159 -31.774461) (xy 429.865033 -31.720024)
			(xy 429.860962 -31.664402) (xy 429.344421 -31.664402) (xy 429.348391 -31.69138) (xy 429.3489 -31.719266)
			(xy 429.348391 -31.747152) (xy 429.340271 -31.802328) (xy 429.324203 -31.855735) (xy 429.300531 -31.906232)
			(xy 429.269758 -31.952745) (xy 429.232541 -31.994282) (xy 429.189673 -32.029957) (xy 429.142067 -32.059011)
			(xy 429.090738 -32.080823) (xy 429.036781 -32.094929) (xy 428.981344 -32.101029) (xy 428.92561 -32.098992)
			(xy 428.870767 -32.088862) (xy 428.817983 -32.070855) (xy 428.768383 -32.045354) (xy 428.723025 -32.012903)
			(xy 428.682876 -31.974194) (xy 428.64879 -31.930051) (xy 428.621494 -31.881416) (xy 428.601571 -31.829325)
			(xy 428.589445 -31.774888) (xy 428.585374 -31.719266) (xy 428.030869 -31.719266) (xy 428.011227 -31.759811)
			(xy 427.978749 -31.807138) (xy 427.939551 -31.849069) (xy 427.894516 -31.884658) (xy 427.869858 -31.899352)
			(xy 427.86046 -31.904686) (xy 427.854618 -31.912306) (xy 427.851701 -31.916411) (xy 427.847353 -31.925494)
			(xy 427.845982 -31.93034) (xy 427.827694 -32.002476) (xy 427.826221 -32.010995) (xy 427.828437 -32.028131)
			(xy 427.832012 -32.036004) (xy 428.269046 -32.722312) (xy 434.906928 -32.722312) (xy 434.906928 -31.858712)
			(xy 434.907418 -31.828744) (xy 434.915241 -31.769322) (xy 434.930754 -31.711429) (xy 434.95369 -31.656056)
			(xy 434.983657 -31.60415) (xy 435.020144 -31.5566) (xy 435.062524 -31.51422) (xy 435.110074 -31.477733)
			(xy 435.16198 -31.447766) (xy 435.217353 -31.42483) (xy 435.275246 -31.409317) (xy 435.334668 -31.401494)
			(xy 435.394604 -31.401494) (xy 435.454026 -31.409317) (xy 435.511919 -31.42483) (xy 435.567292 -31.447766)
			(xy 435.619198 -31.477733) (xy 435.666748 -31.51422) (xy 435.709128 -31.5566) (xy 435.745615 -31.60415)
			(xy 435.775582 -31.656056) (xy 435.798518 -31.711429) (xy 435.814031 -31.769322) (xy 435.821854 -31.828744)
			(xy 435.822344 -31.858712) (xy 435.822344 -32.722312) (xy 435.821854 -32.75228) (xy 435.814031 -32.811702)
			(xy 435.798518 -32.869595) (xy 435.775582 -32.924968) (xy 435.745615 -32.976874) (xy 435.709128 -33.024424)
			(xy 435.666748 -33.066804) (xy 435.619198 -33.103291) (xy 435.567292 -33.133258) (xy 435.511919 -33.156194)
			(xy 435.454026 -33.171707) (xy 435.394604 -33.17953) (xy 435.334668 -33.17953) (xy 435.275246 -33.171707)
			(xy 435.217353 -33.156194) (xy 435.16198 -33.133258) (xy 435.110074 -33.103291) (xy 435.062524 -33.066804)
			(xy 435.020144 -33.024424) (xy 434.983657 -32.976874) (xy 434.95369 -32.924968) (xy 434.930754 -32.869595)
			(xy 434.915241 -32.811702) (xy 434.907418 -32.75228) (xy 434.906928 -32.722312) (xy 428.269046 -32.722312)
			(xy 428.349918 -32.849312) (xy 428.352581 -32.853242) (xy 428.359101 -32.860143) (xy 428.362872 -32.863028)
			(xy 428.384716 -32.87903) (xy 428.393352 -32.88157) (xy 428.419495 -32.889609) (xy 428.469335 -32.912132)
			(xy 428.515449 -32.941542) (xy 428.55689 -32.977236) (xy 428.592809 -33.018481) (xy 428.62247 -33.064433)
			(xy 428.645265 -33.11415) (xy 428.660727 -33.166612) (xy 428.668538 -33.220745) (xy 428.668942 -33.248092)
			(xy 428.66876 -33.265141) (xy 428.665707 -33.299102) (xy 428.662846 -33.31591) (xy 428.661068 -33.325562)
			(xy 428.662846 -33.334452) (xy 428.66382 -33.339089) (xy 428.667269 -33.347913) (xy 428.669704 -33.351978)
			(xy 429.414999 -34.52241) (xy 433.052728 -34.52241) (xy 433.052728 -33.65881) (xy 433.053218 -33.628842)
			(xy 433.061041 -33.56942) (xy 433.076554 -33.511527) (xy 433.09949 -33.456154) (xy 433.129457 -33.404248)
			(xy 433.165944 -33.356698) (xy 433.208324 -33.314318) (xy 433.255874 -33.277831) (xy 433.30778 -33.247864)
			(xy 433.363153 -33.224928) (xy 433.421046 -33.209415) (xy 433.480468 -33.201592) (xy 433.540404 -33.201592)
			(xy 433.599826 -33.209415) (xy 433.657719 -33.224928) (xy 433.713092 -33.247864) (xy 433.764998 -33.277831)
			(xy 433.812548 -33.314318) (xy 433.854928 -33.356698) (xy 433.891415 -33.404248) (xy 433.921382 -33.456154)
			(xy 433.944318 -33.511527) (xy 433.959831 -33.56942) (xy 433.967654 -33.628842) (xy 433.968144 -33.65881)
			(xy 433.968144 -34.52241) (xy 433.967654 -34.552378) (xy 433.959831 -34.6118) (xy 433.944318 -34.669693)
			(xy 433.921382 -34.725066) (xy 433.891415 -34.776972) (xy 433.854928 -34.824522) (xy 433.812548 -34.866902)
			(xy 433.764998 -34.903389) (xy 433.713092 -34.933356) (xy 433.657719 -34.956292) (xy 433.599826 -34.971805)
			(xy 433.540404 -34.979628) (xy 433.480468 -34.979628) (xy 433.421046 -34.971805) (xy 433.363153 -34.956292)
			(xy 433.30778 -34.933356) (xy 433.255874 -34.903389) (xy 433.208324 -34.866902) (xy 433.165944 -34.824522)
			(xy 433.129457 -34.776972) (xy 433.09949 -34.725066) (xy 433.076554 -34.669693) (xy 433.061041 -34.6118)
			(xy 433.053218 -34.552378) (xy 433.052728 -34.52241) (xy 429.414999 -34.52241) (xy 429.887763 -35.264852)
			(xy 430.202338 -35.264852) (xy 430.206409 -35.20923) (xy 430.218535 -35.154793) (xy 430.238458 -35.102702)
			(xy 430.265754 -35.054067) (xy 430.29984 -35.009924) (xy 430.339989 -34.971215) (xy 430.385347 -34.938764)
			(xy 430.434947 -34.913263) (xy 430.487731 -34.895256) (xy 430.542574 -34.885126) (xy 430.598308 -34.883089)
			(xy 430.653745 -34.889189) (xy 430.707702 -34.903295) (xy 430.759031 -34.925107) (xy 430.806637 -34.954161)
			(xy 430.849505 -34.989836) (xy 430.886722 -35.031373) (xy 430.917495 -35.077886) (xy 430.941167 -35.128383)
			(xy 430.957235 -35.18179) (xy 430.965355 -35.236966) (xy 430.965864 -35.264852) (xy 430.965355 -35.292738)
			(xy 430.957235 -35.347914) (xy 430.941167 -35.401321) (xy 430.917495 -35.451818) (xy 430.886722 -35.498331)
			(xy 430.849505 -35.539868) (xy 430.806637 -35.575543) (xy 430.759031 -35.604597) (xy 430.707702 -35.626409)
			(xy 430.653745 -35.640515) (xy 430.598308 -35.646615) (xy 430.542574 -35.644578) (xy 430.487731 -35.634448)
			(xy 430.434947 -35.616441) (xy 430.385347 -35.59094) (xy 430.339989 -35.558489) (xy 430.29984 -35.51978)
			(xy 430.265754 -35.475637) (xy 430.238458 -35.427002) (xy 430.218535 -35.374911) (xy 430.206409 -35.320474)
			(xy 430.202338 -35.264852) (xy 429.887763 -35.264852) (xy 430.538603 -36.286948) (xy 431.500278 -36.286948)
			(xy 431.504349 -36.231326) (xy 431.516475 -36.176889) (xy 431.536398 -36.124798) (xy 431.563694 -36.076163)
			(xy 431.59778 -36.03202) (xy 431.637929 -35.993311) (xy 431.683287 -35.96086) (xy 431.732887 -35.935359)
			(xy 431.785671 -35.917352) (xy 431.840514 -35.907222) (xy 431.896248 -35.905185) (xy 431.951685 -35.911285)
			(xy 432.005642 -35.925391) (xy 432.056971 -35.947203) (xy 432.104577 -35.976257) (xy 432.147445 -36.011932)
			(xy 432.184662 -36.053469) (xy 432.215435 -36.099982) (xy 432.239107 -36.150479) (xy 432.255175 -36.203886)
			(xy 432.263295 -36.259062) (xy 432.263804 -36.286948) (xy 432.263295 -36.314834) (xy 432.255175 -36.37001)
			(xy 432.239107 -36.423417) (xy 432.215435 -36.473914) (xy 432.18789 -36.515548) (xy 433.314092 -36.515548)
			(xy 433.318163 -36.459926) (xy 433.330289 -36.405489) (xy 433.350212 -36.353398) (xy 433.377508 -36.304763)
			(xy 433.411594 -36.26062) (xy 433.451743 -36.221911) (xy 433.497101 -36.18946) (xy 433.546701 -36.163959)
			(xy 433.599485 -36.145952) (xy 433.654328 -36.135822) (xy 433.710062 -36.133785) (xy 433.765499 -36.139885)
			(xy 433.819456 -36.153991) (xy 433.870785 -36.175803) (xy 433.918391 -36.204857) (xy 433.961259 -36.240532)
			(xy 433.998476 -36.282069) (xy 434.029249 -36.328582) (xy 434.052921 -36.379079) (xy 434.068989 -36.432486)
			(xy 434.077109 -36.487662) (xy 434.077618 -36.515548) (xy 434.077109 -36.543434) (xy 434.068989 -36.59861)
			(xy 434.068532 -36.60013) (xy 438.298597 -36.60013) (xy 438.302601 -36.512245) (xy 438.314581 -36.425088)
			(xy 438.334436 -36.339381) (xy 438.362003 -36.255836) (xy 438.397053 -36.175143) (xy 438.439295 -36.097971)
			(xy 438.48838 -36.024961) (xy 438.543901 -35.956717) (xy 438.605398 -35.893804) (xy 438.67236 -35.836744)
			(xy 438.744234 -35.78601) (xy 438.820424 -35.742022) (xy 438.900298 -35.705144) (xy 438.983195 -35.675683)
			(xy 439.068427 -35.653881) (xy 439.155289 -35.639921) (xy 439.24306 -35.633917) (xy 439.331014 -35.63592)
			(xy 439.418421 -35.645912) (xy 439.504557 -35.663812) (xy 439.588709 -35.68947) (xy 439.670179 -35.722674)
			(xy 439.748292 -35.763148) (xy 439.8224 -35.810559) (xy 439.891891 -35.864512) (xy 439.956187 -35.92456)
			(xy 440.014756 -35.990207) (xy 440.067113 -36.060907) (xy 440.112825 -36.136076) (xy 440.151511 -36.21509)
			(xy 440.182852 -36.297295) (xy 440.206587 -36.382009) (xy 440.222521 -36.46853) (xy 440.230521 -36.556142)
			(xy 440.231022 -36.60013) (xy 440.230521 -36.644118) (xy 440.222521 -36.73173) (xy 440.206587 -36.818251)
			(xy 440.182852 -36.902965) (xy 440.151511 -36.98517) (xy 440.112825 -37.064184) (xy 440.067113 -37.139353)
			(xy 440.014756 -37.210053) (xy 439.956187 -37.2757) (xy 439.891891 -37.335748) (xy 439.8224 -37.389701)
			(xy 439.748292 -37.437112) (xy 439.670179 -37.477586) (xy 439.588709 -37.51079) (xy 439.504557 -37.536448)
			(xy 439.418421 -37.554348) (xy 439.331014 -37.56434) (xy 439.24306 -37.566343) (xy 439.155289 -37.560339)
			(xy 439.068427 -37.546379) (xy 438.983195 -37.524577) (xy 438.900298 -37.495116) (xy 438.820424 -37.458238)
			(xy 438.744234 -37.41425) (xy 438.67236 -37.363516) (xy 438.605398 -37.306456) (xy 438.543901 -37.243543)
			(xy 438.48838 -37.175299) (xy 438.439295 -37.102289) (xy 438.397053 -37.025117) (xy 438.362003 -36.944424)
			(xy 438.334436 -36.860879) (xy 438.314581 -36.775172) (xy 438.302601 -36.688015) (xy 438.298597 -36.60013)
			(xy 434.068532 -36.60013) (xy 434.052921 -36.652017) (xy 434.029249 -36.702514) (xy 433.998476 -36.749027)
			(xy 433.961259 -36.790564) (xy 433.918391 -36.826239) (xy 433.870785 -36.855293) (xy 433.819456 -36.877105)
			(xy 433.765499 -36.891211) (xy 433.710062 -36.897311) (xy 433.654328 -36.895274) (xy 433.599485 -36.885144)
			(xy 433.546701 -36.867137) (xy 433.497101 -36.841636) (xy 433.451743 -36.809185) (xy 433.411594 -36.770476)
			(xy 433.377508 -36.726333) (xy 433.350212 -36.677698) (xy 433.330289 -36.625607) (xy 433.318163 -36.57117)
			(xy 433.314092 -36.515548) (xy 432.18789 -36.515548) (xy 432.184662 -36.520427) (xy 432.147445 -36.561964)
			(xy 432.104577 -36.597639) (xy 432.056971 -36.626693) (xy 432.005642 -36.648505) (xy 431.951685 -36.662611)
			(xy 431.896248 -36.668711) (xy 431.840514 -36.666674) (xy 431.785671 -36.656544) (xy 431.732887 -36.638537)
			(xy 431.683287 -36.613036) (xy 431.637929 -36.580585) (xy 431.59778 -36.541876) (xy 431.563694 -36.497733)
			(xy 431.536398 -36.449098) (xy 431.516475 -36.397007) (xy 431.504349 -36.34257) (xy 431.500278 -36.286948)
			(xy 430.538603 -36.286948) (xy 431.242978 -37.393118) (xy 431.48556 -37.774118) (xy 431.764692 -37.774118)
			(xy 431.768763 -37.718496) (xy 431.780889 -37.664059) (xy 431.800812 -37.611968) (xy 431.828108 -37.563333)
			(xy 431.862194 -37.51919) (xy 431.902343 -37.480481) (xy 431.947701 -37.44803) (xy 431.997301 -37.422529)
			(xy 432.050085 -37.404522) (xy 432.104928 -37.394392) (xy 432.160662 -37.392355) (xy 432.216099 -37.398455)
			(xy 432.270056 -37.412561) (xy 432.321385 -37.434373) (xy 432.368991 -37.463427) (xy 432.411859 -37.499102)
			(xy 432.449076 -37.540639) (xy 432.479849 -37.587152) (xy 432.503521 -37.637649) (xy 432.519589 -37.691056)
			(xy 432.527709 -37.746232) (xy 432.528218 -37.774118) (xy 432.527709 -37.802004) (xy 432.519589 -37.85718)
			(xy 432.503521 -37.910587) (xy 432.479849 -37.961084) (xy 432.449076 -38.007597) (xy 432.411859 -38.049134)
			(xy 432.368991 -38.084809) (xy 432.321385 -38.113863) (xy 432.270056 -38.135675) (xy 432.216099 -38.149781)
			(xy 432.160662 -38.155881) (xy 432.104928 -38.153844) (xy 432.050085 -38.143714) (xy 431.997301 -38.125707)
			(xy 431.947701 -38.100206) (xy 431.902343 -38.067755) (xy 431.862194 -38.029046) (xy 431.828108 -37.984903)
			(xy 431.800812 -37.936268) (xy 431.780889 -37.884177) (xy 431.768763 -37.82974) (xy 431.764692 -37.774118)
			(xy 431.48556 -37.774118) (xy 432.345592 -39.12489) (xy 432.350164 -39.130986) (xy 434.221934 -41.268753)
			(xy 442.14385 -41.268753) (xy 442.14385 -41.214247) (xy 442.151607 -41.160296) (xy 442.166963 -41.107997)
			(xy 442.189605 -41.058417) (xy 442.219073 -41.012563) (xy 442.254767 -40.97137) (xy 442.29596 -40.935676)
			(xy 442.341813 -40.906207) (xy 442.391394 -40.883564) (xy 442.443692 -40.868208) (xy 442.497643 -40.86045)
			(xy 442.524896 -40.859964) (xy 442.553634 -40.8605) (xy 442.610461 -40.869121) (xy 442.665351 -40.886169)
			(xy 442.717063 -40.911257) (xy 442.764426 -40.943819) (xy 442.785754 -40.963088) (xy 442.792612 -40.969692)
			(xy 442.810646 -40.976804) (xy 442.899546 -40.976804) (xy 442.91758 -40.969692) (xy 442.924438 -40.963088)
			(xy 442.945774 -40.943827) (xy 442.993133 -40.911258) (xy 443.044842 -40.886163) (xy 443.099731 -40.86911)
			(xy 443.156557 -40.860485) (xy 443.185296 -40.859964) (xy 443.212547 -40.860483) (xy 443.266494 -40.868239)
			(xy 443.318789 -40.883593) (xy 443.368366 -40.906234) (xy 443.414216 -40.9357) (xy 443.455406 -40.971391)
			(xy 443.491098 -41.012581) (xy 443.520564 -41.058431) (xy 443.543205 -41.108007) (xy 443.55856 -41.160302)
			(xy 443.566317 -41.214249) (xy 443.566317 -41.268751) (xy 443.55856 -41.322698) (xy 443.543205 -41.374993)
			(xy 443.520564 -41.424569) (xy 443.491098 -41.470419) (xy 443.455406 -41.511609) (xy 443.414216 -41.5473)
			(xy 443.368366 -41.576766) (xy 443.318789 -41.599407) (xy 443.266494 -41.614761) (xy 443.212547 -41.622517)
			(xy 443.185296 -41.62298) (xy 443.156558 -41.622437) (xy 443.099732 -41.613816) (xy 443.044843 -41.596769)
			(xy 442.993131 -41.571683) (xy 442.945767 -41.539123) (xy 442.924438 -41.519856) (xy 442.91758 -41.513252)
			(xy 442.899546 -41.50614) (xy 442.810646 -41.50614) (xy 442.792612 -41.513252) (xy 442.785754 -41.519856)
			(xy 442.764428 -41.539128) (xy 442.717066 -41.571694) (xy 442.665354 -41.596786) (xy 442.610463 -41.613837)
			(xy 442.553635 -41.622459) (xy 442.524896 -41.62298) (xy 442.497643 -41.62255) (xy 442.443692 -41.614792)
			(xy 442.391394 -41.599436) (xy 442.341813 -41.576793) (xy 442.29596 -41.547324) (xy 442.254767 -41.51163)
			(xy 442.219073 -41.470437) (xy 442.189605 -41.424583) (xy 442.166963 -41.375003) (xy 442.151607 -41.322704)
			(xy 442.14385 -41.268753) (xy 434.221934 -41.268753) (xy 436.00501 -43.305222) (xy 444.607188 -43.305222)
			(xy 444.60767 -43.277852) (xy 444.615484 -43.223674) (xy 444.63097 -43.171171) (xy 444.653808 -43.121424)
			(xy 444.683529 -43.075456) (xy 444.701168 -43.054524) (xy 444.701422 -43.05427) (xy 444.706988 -43.047169)
			(xy 444.713246 -43.030263) (xy 444.713614 -43.02125) (xy 444.713614 -42.954194) (xy 444.713257 -42.945177)
			(xy 444.707009 -42.92826) (xy 444.701422 -42.921174) (xy 444.701168 -42.921174) (xy 444.701168 -42.92092)
			(xy 444.68352 -42.899995) (xy 444.65381 -42.85402) (xy 444.630977 -42.804271) (xy 444.615488 -42.751768)
			(xy 444.607661 -42.697592) (xy 444.607188 -42.670222) (xy 444.607728 -42.641484) (xy 444.616347 -42.584657)
			(xy 444.633394 -42.529767) (xy 444.658482 -42.478055) (xy 444.691043 -42.430691) (xy 444.710312 -42.409364)
			(xy 444.716916 -42.402506) (xy 444.724028 -42.384472) (xy 444.724028 -42.295572) (xy 444.716916 -42.277538)
			(xy 444.710312 -42.27068) (xy 444.691064 -42.249334) (xy 444.658499 -42.201975) (xy 444.633407 -42.150266)
			(xy 444.616356 -42.095378) (xy 444.607731 -42.038554) (xy 444.607729 -41.981078) (xy 444.616348 -41.924253)
			(xy 444.633395 -41.869364) (xy 444.658482 -41.817653) (xy 444.691043 -41.770291) (xy 444.710312 -41.748964)
			(xy 444.716916 -41.742106) (xy 444.724028 -41.724072) (xy 444.724028 -41.635172) (xy 444.716916 -41.617138)
			(xy 444.710312 -41.61028) (xy 444.691047 -41.588948) (xy 444.658481 -41.541587) (xy 444.633388 -41.489876)
			(xy 444.616336 -41.434987) (xy 444.607711 -41.378161) (xy 444.607188 -41.349422) (xy 444.607674 -41.322171)
			(xy 444.61543 -41.268223) (xy 444.630785 -41.215928) (xy 444.653427 -41.166351) (xy 444.682893 -41.120501)
			(xy 444.718584 -41.07931) (xy 444.759775 -41.043619) (xy 444.805625 -41.014153) (xy 444.855202 -40.991511)
			(xy 444.907497 -40.976156) (xy 444.961445 -40.9684) (xy 445.015947 -40.9684) (xy 445.069895 -40.976156)
			(xy 445.12219 -40.991511) (xy 445.171767 -41.014153) (xy 445.217617 -41.043619) (xy 445.258808 -41.07931)
			(xy 445.294499 -41.120501) (xy 445.323965 -41.166351) (xy 445.346607 -41.215928) (xy 445.361962 -41.268223)
			(xy 445.369718 -41.322171) (xy 445.370204 -41.349422) (xy 445.369693 -41.378161) (xy 445.361067 -41.434989)
			(xy 445.344014 -41.48988) (xy 445.31892 -41.541592) (xy 445.286352 -41.588954) (xy 445.26708 -41.61028)
			(xy 445.260476 -41.617138) (xy 445.253364 -41.635172) (xy 445.253364 -41.724072) (xy 445.260476 -41.742106)
			(xy 445.26708 -41.748964) (xy 445.286372 -41.770272) (xy 445.318937 -41.817638) (xy 445.344027 -41.869353)
			(xy 445.361075 -41.924246) (xy 445.369695 -41.981076) (xy 445.369693 -42.038556) (xy 445.361068 -42.095385)
			(xy 445.344015 -42.150277) (xy 445.31892 -42.20199) (xy 445.286352 -42.249353) (xy 445.26708 -42.27068)
			(xy 445.260476 -42.277538) (xy 445.253364 -42.295572) (xy 445.253364 -42.384472) (xy 445.260476 -42.402506)
			(xy 445.26708 -42.409364) (xy 445.286364 -42.430679) (xy 445.318928 -42.478045) (xy 445.344017 -42.52976)
			(xy 445.361065 -42.584653) (xy 445.369685 -42.641482) (xy 445.370204 -42.670222) (xy 445.36975 -42.697593)
			(xy 445.361929 -42.751772) (xy 445.346437 -42.804275) (xy 445.325882 -42.849038) (xy 447.19189 -42.849038)
			(xy 447.195961 -42.793416) (xy 447.208087 -42.738979) (xy 447.22801 -42.686888) (xy 447.255306 -42.638253)
			(xy 447.289392 -42.59411) (xy 447.329541 -42.555401) (xy 447.374899 -42.52295) (xy 447.424499 -42.497449)
			(xy 447.477283 -42.479442) (xy 447.532126 -42.469312) (xy 447.58786 -42.467275) (xy 447.643297 -42.473375)
			(xy 447.697254 -42.487481) (xy 447.748583 -42.509293) (xy 447.796189 -42.538347) (xy 447.839057 -42.574022)
			(xy 447.876274 -42.615559) (xy 447.907047 -42.662072) (xy 447.930719 -42.712569) (xy 447.946787 -42.765976)
			(xy 447.954907 -42.821152) (xy 447.955416 -42.849038) (xy 447.954907 -42.876924) (xy 447.946787 -42.9321)
			(xy 447.930719 -42.985507) (xy 447.907047 -43.036004) (xy 447.876274 -43.082517) (xy 447.839057 -43.124054)
			(xy 447.796189 -43.159729) (xy 447.748583 -43.188783) (xy 447.697254 -43.210595) (xy 447.643297 -43.224701)
			(xy 447.58786 -43.230801) (xy 447.532126 -43.228764) (xy 447.477283 -43.218634) (xy 447.424499 -43.200627)
			(xy 447.374899 -43.175126) (xy 447.329541 -43.142675) (xy 447.289392 -43.103966) (xy 447.255306 -43.059823)
			(xy 447.22801 -43.011188) (xy 447.208087 -42.959097) (xy 447.195961 -42.90466) (xy 447.19189 -42.849038)
			(xy 445.325882 -42.849038) (xy 445.323593 -42.854022) (xy 445.293866 -42.899989) (xy 445.276224 -42.92092)
			(xy 445.27597 -42.921174) (xy 445.270385 -42.928261) (xy 445.264138 -42.945178) (xy 445.263778 -42.954194)
			(xy 445.263778 -43.02125) (xy 445.264164 -43.030264) (xy 445.270392 -43.047181) (xy 445.27597 -43.05427)
			(xy 445.276224 -43.05427) (xy 445.276224 -43.054524) (xy 445.293845 -43.075471) (xy 445.323558 -43.12144)
			(xy 445.346398 -43.171184) (xy 445.361893 -43.223681) (xy 445.369727 -43.277854) (xy 445.370204 -43.305222)
			(xy 445.369718 -43.332473) (xy 445.361962 -43.386421) (xy 445.346607 -43.438716) (xy 445.323965 -43.488293)
			(xy 445.294499 -43.534143) (xy 445.258808 -43.575334) (xy 445.217617 -43.611025) (xy 445.171767 -43.640491)
			(xy 445.12219 -43.663133) (xy 445.069895 -43.678488) (xy 445.015947 -43.686244) (xy 444.961445 -43.686244)
			(xy 444.907497 -43.678488) (xy 444.855202 -43.663133) (xy 444.805625 -43.640491) (xy 444.759775 -43.611025)
			(xy 444.718584 -43.575334) (xy 444.682893 -43.534143) (xy 444.653427 -43.488293) (xy 444.630785 -43.438716)
			(xy 444.61543 -43.386421) (xy 444.607674 -43.332473) (xy 444.607188 -43.305222) (xy 436.00501 -43.305222)
			(xy 436.382415 -43.73626) (xy 446.512948 -43.73626) (xy 446.517019 -43.680638) (xy 446.529145 -43.626201)
			(xy 446.549068 -43.57411) (xy 446.576364 -43.525475) (xy 446.61045 -43.481332) (xy 446.650599 -43.442623)
			(xy 446.695957 -43.410172) (xy 446.745557 -43.384671) (xy 446.798341 -43.366664) (xy 446.853184 -43.356534)
			(xy 446.908918 -43.354497) (xy 446.964355 -43.360597) (xy 447.018312 -43.374703) (xy 447.069641 -43.396515)
			(xy 447.117247 -43.425569) (xy 447.160115 -43.461244) (xy 447.197332 -43.502781) (xy 447.228105 -43.549294)
			(xy 447.236331 -43.566842) (xy 449.633338 -43.566842) (xy 449.637409 -43.51122) (xy 449.649535 -43.456783)
			(xy 449.669458 -43.404692) (xy 449.696754 -43.356057) (xy 449.73084 -43.311914) (xy 449.770989 -43.273205)
			(xy 449.816347 -43.240754) (xy 449.865947 -43.215253) (xy 449.918731 -43.197246) (xy 449.973574 -43.187116)
			(xy 450.029308 -43.185079) (xy 450.084745 -43.191179) (xy 450.138702 -43.205285) (xy 450.190031 -43.227097)
			(xy 450.237637 -43.256151) (xy 450.280505 -43.291826) (xy 450.317722 -43.333363) (xy 450.348495 -43.379876)
			(xy 450.372167 -43.430373) (xy 450.388235 -43.48378) (xy 450.396355 -43.538956) (xy 450.396864 -43.566842)
			(xy 450.396355 -43.594728) (xy 450.388235 -43.649904) (xy 450.372167 -43.703311) (xy 450.348495 -43.753808)
			(xy 450.317722 -43.800321) (xy 450.280505 -43.841858) (xy 450.262418 -43.85691) (xy 451.01967 -43.85691)
			(xy 451.023741 -43.801288) (xy 451.035867 -43.746851) (xy 451.05579 -43.69476) (xy 451.083086 -43.646125)
			(xy 451.117172 -43.601982) (xy 451.157321 -43.563273) (xy 451.202679 -43.530822) (xy 451.252279 -43.505321)
			(xy 451.305063 -43.487314) (xy 451.359906 -43.477184) (xy 451.41564 -43.475147) (xy 451.471077 -43.481247)
			(xy 451.525034 -43.495353) (xy 451.576363 -43.517165) (xy 451.623969 -43.546219) (xy 451.666837 -43.581894)
			(xy 451.704054 -43.623431) (xy 451.734827 -43.669944) (xy 451.758499 -43.720441) (xy 451.774567 -43.773848)
			(xy 451.782687 -43.829024) (xy 451.783196 -43.85691) (xy 451.782687 -43.884796) (xy 451.774567 -43.939972)
			(xy 451.758499 -43.993379) (xy 451.734827 -44.043876) (xy 451.704054 -44.090389) (xy 451.666837 -44.131926)
			(xy 451.623969 -44.167601) (xy 451.576363 -44.196655) (xy 451.525034 -44.218467) (xy 451.471077 -44.232573)
			(xy 451.41564 -44.238673) (xy 451.359906 -44.236636) (xy 451.305063 -44.226506) (xy 451.252279 -44.208499)
			(xy 451.202679 -44.182998) (xy 451.157321 -44.150547) (xy 451.117172 -44.111838) (xy 451.083086 -44.067695)
			(xy 451.05579 -44.01906) (xy 451.035867 -43.966969) (xy 451.023741 -43.912532) (xy 451.01967 -43.85691)
			(xy 450.262418 -43.85691) (xy 450.237637 -43.877533) (xy 450.190031 -43.906587) (xy 450.138702 -43.928399)
			(xy 450.084745 -43.942505) (xy 450.029308 -43.948605) (xy 449.973574 -43.946568) (xy 449.918731 -43.936438)
			(xy 449.865947 -43.918431) (xy 449.816347 -43.89293) (xy 449.770989 -43.860479) (xy 449.73084 -43.82177)
			(xy 449.696754 -43.777627) (xy 449.669458 -43.728992) (xy 449.649535 -43.676901) (xy 449.637409 -43.622464)
			(xy 449.633338 -43.566842) (xy 447.236331 -43.566842) (xy 447.251777 -43.599791) (xy 447.267845 -43.653198)
			(xy 447.275965 -43.708374) (xy 447.276474 -43.73626) (xy 447.275965 -43.764146) (xy 447.267845 -43.819322)
			(xy 447.251777 -43.872729) (xy 447.228105 -43.923226) (xy 447.197332 -43.969739) (xy 447.160115 -44.011276)
			(xy 447.117247 -44.046951) (xy 447.069641 -44.076005) (xy 447.018312 -44.097817) (xy 446.964355 -44.111923)
			(xy 446.908918 -44.118023) (xy 446.853184 -44.115986) (xy 446.798341 -44.105856) (xy 446.745557 -44.087849)
			(xy 446.695957 -44.062348) (xy 446.650599 -44.029897) (xy 446.61045 -43.991188) (xy 446.576364 -43.947045)
			(xy 446.549068 -43.89841) (xy 446.529145 -43.846319) (xy 446.517019 -43.791882) (xy 446.512948 -43.73626)
			(xy 436.382415 -43.73626) (xy 437.589132 -45.114464) (xy 446.365374 -45.114464) (xy 446.369445 -45.058842)
			(xy 446.381571 -45.004405) (xy 446.401494 -44.952314) (xy 446.42879 -44.903679) (xy 446.462876 -44.859536)
			(xy 446.503025 -44.820827) (xy 446.548383 -44.788376) (xy 446.597983 -44.762875) (xy 446.650767 -44.744868)
			(xy 446.70561 -44.734738) (xy 446.761344 -44.732701) (xy 446.816781 -44.738801) (xy 446.870738 -44.752907)
			(xy 446.922067 -44.774719) (xy 446.969673 -44.803773) (xy 447.012541 -44.839448) (xy 447.049758 -44.880985)
			(xy 447.080531 -44.927498) (xy 447.104203 -44.977995) (xy 447.120271 -45.031402) (xy 447.128391 -45.086578)
			(xy 447.1289 -45.114464) (xy 447.128391 -45.14235) (xy 447.120271 -45.197526) (xy 447.104203 -45.250933)
			(xy 447.080531 -45.30143) (xy 447.049758 -45.347943) (xy 447.044116 -45.35424) (xy 451.003668 -45.35424)
			(xy 451.007739 -45.298618) (xy 451.019865 -45.244181) (xy 451.039788 -45.19209) (xy 451.067084 -45.143455)
			(xy 451.10117 -45.099312) (xy 451.141319 -45.060603) (xy 451.186677 -45.028152) (xy 451.236277 -45.002651)
			(xy 451.289061 -44.984644) (xy 451.343904 -44.974514) (xy 451.399638 -44.972477) (xy 451.455075 -44.978577)
			(xy 451.509032 -44.992683) (xy 451.560361 -45.014495) (xy 451.607967 -45.043549) (xy 451.650835 -45.079224)
			(xy 451.688052 -45.120761) (xy 451.718825 -45.167274) (xy 451.742497 -45.217771) (xy 451.758565 -45.271178)
			(xy 451.766685 -45.326354) (xy 451.767194 -45.35424) (xy 451.766685 -45.382126) (xy 451.758565 -45.437302)
			(xy 451.742497 -45.490709) (xy 451.718825 -45.541206) (xy 451.688052 -45.587719) (xy 451.650835 -45.629256)
			(xy 451.607967 -45.664931) (xy 451.560361 -45.693985) (xy 451.509032 -45.715797) (xy 451.455075 -45.729903)
			(xy 451.399638 -45.736003) (xy 451.343904 -45.733966) (xy 451.289061 -45.723836) (xy 451.236277 -45.705829)
			(xy 451.186677 -45.680328) (xy 451.141319 -45.647877) (xy 451.10117 -45.609168) (xy 451.067084 -45.565025)
			(xy 451.039788 -45.51639) (xy 451.019865 -45.464299) (xy 451.007739 -45.409862) (xy 451.003668 -45.35424)
			(xy 447.044116 -45.35424) (xy 447.012541 -45.38948) (xy 446.969673 -45.425155) (xy 446.922067 -45.454209)
			(xy 446.870738 -45.476021) (xy 446.816781 -45.490127) (xy 446.761344 -45.496227) (xy 446.70561 -45.49419)
			(xy 446.650767 -45.48406) (xy 446.597983 -45.466053) (xy 446.548383 -45.440552) (xy 446.503025 -45.408101)
			(xy 446.462876 -45.369392) (xy 446.42879 -45.325249) (xy 446.401494 -45.276614) (xy 446.381571 -45.224523)
			(xy 446.369445 -45.170086) (xy 446.365374 -45.114464) (xy 437.589132 -45.114464) (xy 438.436459 -46.082204)
			(xy 444.352426 -46.082204) (xy 444.352859 -46.05495) (xy 444.360616 -46.000996) (xy 444.375974 -45.948695)
			(xy 444.398618 -45.899113) (xy 444.428089 -45.853258) (xy 444.463786 -45.812065) (xy 444.504982 -45.776371)
			(xy 444.550839 -45.746904) (xy 444.600424 -45.724263) (xy 444.652725 -45.70891) (xy 444.70668 -45.701157)
			(xy 444.733934 -45.700696) (xy 444.760837 -45.701132) (xy 444.814109 -45.708709) (xy 444.865787 -45.723693)
			(xy 444.914849 -45.745787) (xy 444.960321 -45.774553) (xy 445.001302 -45.809422) (xy 445.036979 -45.849701)
			(xy 445.052196 -45.871892) (xy 445.059308 -45.882814) (xy 445.082168 -45.894752) (xy 445.194436 -45.89272)
			(xy 445.216788 -45.879766) (xy 445.223646 -45.86859) (xy 445.23855 -45.844977) (xy 445.274232 -45.802025)
			(xy 445.315793 -45.764733) (xy 445.362346 -45.733897) (xy 445.412896 -45.710175) (xy 445.466364 -45.694075)
			(xy 445.521608 -45.68594) (xy 445.549528 -45.685456) (xy 445.576522 -45.685901) (xy 445.629971 -45.693511)
			(xy 445.681814 -45.708575) (xy 445.731019 -45.730792) (xy 445.776602 -45.75972) (xy 445.797432 -45.776896)
			(xy 445.80556 -45.784008) (xy 445.826134 -45.790104) (xy 445.911478 -45.779182) (xy 445.922022 -45.777407)
			(xy 445.940305 -45.766353) (xy 445.946784 -45.757846) (xy 445.962154 -45.736628) (xy 445.997738 -45.698175)
			(xy 446.038252 -45.664955) (xy 446.082933 -45.637595) (xy 446.130938 -45.616609) (xy 446.181364 -45.602394)
			(xy 446.233262 -45.595215) (xy 446.259458 -45.594778) (xy 446.286712 -45.595266) (xy 446.340665 -45.603018)
			(xy 446.392966 -45.61837) (xy 446.44255 -45.641009) (xy 446.488407 -45.670475) (xy 446.529603 -45.706168)
			(xy 446.5653 -45.74736) (xy 446.59477 -45.793213) (xy 446.617415 -45.842794) (xy 446.632773 -45.895094)
			(xy 446.640531 -45.949046) (xy 446.640531 -46.003554) (xy 446.632773 -46.057506) (xy 446.617415 -46.109806)
			(xy 446.59477 -46.159387) (xy 446.5653 -46.20524) (xy 446.529603 -46.246432) (xy 446.488407 -46.282125)
			(xy 446.44255 -46.311591) (xy 446.392966 -46.33423) (xy 446.340665 -46.349582) (xy 446.286712 -46.357334)
			(xy 446.259458 -46.357794) (xy 446.232464 -46.357345) (xy 446.179016 -46.349735) (xy 446.127173 -46.334671)
			(xy 446.077969 -46.312454) (xy 446.032385 -46.283528) (xy 446.011554 -46.266354) (xy 446.003426 -46.259242)
			(xy 445.982852 -46.253146) (xy 445.897508 -46.264068) (xy 445.886967 -46.265854) (xy 445.868684 -46.276901)
			(xy 445.862202 -46.285404) (xy 445.844586 -46.309702) (xy 445.802992 -46.352963) (xy 445.779398 -46.37151)
			(xy 445.771524 -46.377352) (xy 445.76111 -46.394878) (xy 445.747902 -46.485302) (xy 445.752728 -46.504606)
			(xy 445.75857 -46.51248) (xy 445.75857 -46.512734) (xy 445.776072 -46.537479) (xy 445.803875 -46.591331)
			(xy 445.822812 -46.648903) (xy 445.830015 -46.693836) (xy 450.976238 -46.693836) (xy 450.976724 -46.666585)
			(xy 450.98448 -46.612637) (xy 450.999835 -46.560342) (xy 451.022477 -46.510765) (xy 451.051943 -46.464915)
			(xy 451.087634 -46.423724) (xy 451.128825 -46.388033) (xy 451.174675 -46.358567) (xy 451.224252 -46.335925)
			(xy 451.276547 -46.32057) (xy 451.330495 -46.312814) (xy 451.384997 -46.312814) (xy 451.438945 -46.32057)
			(xy 451.49124 -46.335925) (xy 451.540817 -46.358567) (xy 451.586667 -46.388033) (xy 451.627858 -46.423724)
			(xy 451.663549 -46.464915) (xy 451.693015 -46.510765) (xy 451.715657 -46.560342) (xy 451.731012 -46.612637)
			(xy 451.738768 -46.666585) (xy 451.739254 -46.693836) (xy 451.738788 -46.720264) (xy 451.731477 -46.772612)
			(xy 451.717002 -46.823447) (xy 451.69564 -46.871793) (xy 451.682104 -46.894496) (xy 451.68185 -46.89475)
			(xy 451.676513 -46.904768) (xy 451.674256 -46.927318) (xy 451.677532 -46.938184) (xy 451.703694 -47.01286)
			(xy 451.708059 -47.023385) (xy 451.724161 -47.03947) (xy 451.734682 -47.043848) (xy 451.734936 -47.043848)
			(xy 451.759443 -47.052923) (xy 451.805895 -47.076865) (xy 451.848648 -47.106919) (xy 451.8869 -47.142526)
			(xy 451.919937 -47.183018) (xy 451.947141 -47.227638) (xy 451.968003 -47.275553) (xy 451.982133 -47.325866)
			(xy 451.989267 -47.377636) (xy 451.989698 -47.403766) (xy 451.989212 -47.431017) (xy 451.981456 -47.484965)
			(xy 451.966101 -47.53726) (xy 451.943459 -47.586837) (xy 451.913993 -47.632687) (xy 451.878302 -47.673878)
			(xy 451.837111 -47.709569) (xy 451.791261 -47.739035) (xy 451.741684 -47.761677) (xy 451.689389 -47.777032)
			(xy 451.635441 -47.784788) (xy 451.580939 -47.784788) (xy 451.526991 -47.777032) (xy 451.474696 -47.761677)
			(xy 451.425119 -47.739035) (xy 451.379269 -47.709569) (xy 451.338078 -47.673878) (xy 451.302387 -47.632687)
			(xy 451.272921 -47.586837) (xy 451.250279 -47.53726) (xy 451.234924 -47.484965) (xy 451.227168 -47.431017)
			(xy 451.226682 -47.403766) (xy 451.227158 -47.377339) (xy 451.234467 -47.324991) (xy 451.248939 -47.274157)
			(xy 451.270298 -47.225809) (xy 451.283832 -47.203106) (xy 451.284086 -47.202852) (xy 451.289421 -47.192834)
			(xy 451.291678 -47.170284) (xy 451.288404 -47.159418) (xy 451.262242 -47.084742) (xy 451.25786 -47.074226)
			(xy 451.24177 -47.058137) (xy 451.231254 -47.053754) (xy 451.231 -47.053754) (xy 451.206502 -47.044657)
			(xy 451.160048 -47.02072) (xy 451.117295 -46.990669) (xy 451.079041 -46.955066) (xy 451.046003 -46.914576)
			(xy 451.018798 -46.869958) (xy 450.997935 -46.822045) (xy 450.983804 -46.771734) (xy 450.976669 -46.719965)
			(xy 450.976238 -46.693836) (xy 445.830015 -46.693836) (xy 445.832405 -46.708745) (xy 445.832992 -46.739048)
			(xy 445.832567 -46.766301) (xy 445.824803 -46.820252) (xy 445.809441 -46.872549) (xy 445.786793 -46.922127)
			(xy 445.757321 -46.967978) (xy 445.721623 -47.009168) (xy 445.680427 -47.044859) (xy 445.634571 -47.074324)
			(xy 445.584989 -47.096964) (xy 445.532689 -47.112317) (xy 445.478737 -47.120071) (xy 445.451484 -47.120556)
			(xy 445.42545 -47.120111) (xy 445.373868 -47.113022) (xy 445.323726 -47.098992) (xy 445.275955 -47.078281)
			(xy 445.23144 -47.051272) (xy 445.210946 -47.035212) (xy 445.203182 -47.029481) (xy 445.184777 -47.023734)
			(xy 445.175132 -47.024036) (xy 445.095376 -47.030386) (xy 445.077596 -47.039022) (xy 445.071246 -47.046388)
			(xy 445.053065 -47.066034) (xy 445.012157 -47.100556) (xy 444.966828 -47.129025) (xy 444.917967 -47.150882)
			(xy 444.866531 -47.1657) (xy 444.81353 -47.173187) (xy 444.786766 -47.173642) (xy 444.759515 -47.173154)
			(xy 444.70557 -47.165394) (xy 444.653277 -47.150036) (xy 444.603702 -47.127393) (xy 444.557853 -47.097927)
			(xy 444.516664 -47.062236) (xy 444.480973 -47.021047) (xy 444.451507 -46.975198) (xy 444.428864 -46.925623)
			(xy 444.413506 -46.87333) (xy 444.405746 -46.819385) (xy 444.405258 -46.792134) (xy 444.405794 -46.763361)
			(xy 444.414444 -46.706467) (xy 444.431538 -46.651517) (xy 444.456689 -46.599757) (xy 444.489326 -46.55236)
			(xy 444.508636 -46.531022) (xy 444.516002 -46.523148) (xy 444.523114 -46.503336) (xy 444.515748 -46.40707)
			(xy 444.505842 -46.388274) (xy 444.49746 -46.38167) (xy 444.475284 -46.363435) (xy 444.436071 -46.321503)
			(xy 444.403583 -46.27417) (xy 444.378553 -46.222504) (xy 444.361546 -46.167671) (xy 444.352944 -46.110909)
			(xy 444.352426 -46.082204) (xy 438.436459 -46.082204) (xy 439.197496 -46.951392) (xy 439.226033 -46.984709)
			(xy 439.2778 -47.055538) (xy 439.323144 -47.130642) (xy 439.361715 -47.209439) (xy 439.393213 -47.29132)
			(xy 439.417396 -47.375651) (xy 439.434076 -47.461781) (xy 439.43905 -47.505366) (xy 439.460894 -47.713646)
			(xy 439.52262 -48.30699) (xy 450.853808 -48.30699) (xy 450.857879 -48.251368) (xy 450.870005 -48.196931)
			(xy 450.889928 -48.14484) (xy 450.917224 -48.096205) (xy 450.95131 -48.052062) (xy 450.991459 -48.013353)
			(xy 451.036817 -47.980902) (xy 451.086417 -47.955401) (xy 451.139201 -47.937394) (xy 451.194044 -47.927264)
			(xy 451.249778 -47.925227) (xy 451.305215 -47.931327) (xy 451.359172 -47.945433) (xy 451.410501 -47.967245)
			(xy 451.458107 -47.996299) (xy 451.500975 -48.031974) (xy 451.538192 -48.073511) (xy 451.568965 -48.120024)
			(xy 451.592637 -48.170521) (xy 451.608705 -48.223928) (xy 451.616825 -48.279104) (xy 451.617334 -48.30699)
			(xy 451.616825 -48.334876) (xy 451.608705 -48.390052) (xy 451.592637 -48.443459) (xy 451.568965 -48.493956)
			(xy 451.538192 -48.540469) (xy 451.500975 -48.582006) (xy 451.458107 -48.617681) (xy 451.410501 -48.646735)
			(xy 451.359172 -48.668547) (xy 451.305215 -48.682653) (xy 451.249778 -48.688753) (xy 451.194044 -48.686716)
			(xy 451.139201 -48.676586) (xy 451.086417 -48.658579) (xy 451.036817 -48.633078) (xy 450.991459 -48.600627)
			(xy 450.95131 -48.561918) (xy 450.917224 -48.517775) (xy 450.889928 -48.46914) (xy 450.870005 -48.417049)
			(xy 450.857879 -48.362612) (xy 450.853808 -48.30699) (xy 439.52262 -48.30699) (xy 439.550048 -48.570642)
			(xy 439.569071 -48.753014) (xy 447.468242 -48.753014) (xy 447.472313 -48.697392) (xy 447.484439 -48.642955)
			(xy 447.504362 -48.590864) (xy 447.531658 -48.542229) (xy 447.565744 -48.498086) (xy 447.605893 -48.459377)
			(xy 447.651251 -48.426926) (xy 447.700851 -48.401425) (xy 447.753635 -48.383418) (xy 447.808478 -48.373288)
			(xy 447.864212 -48.371251) (xy 447.919649 -48.377351) (xy 447.973606 -48.391457) (xy 448.024935 -48.413269)
			(xy 448.072541 -48.442323) (xy 448.115409 -48.477998) (xy 448.152626 -48.519535) (xy 448.183399 -48.566048)
			(xy 448.207071 -48.616545) (xy 448.223139 -48.669952) (xy 448.231259 -48.725128) (xy 448.231768 -48.753014)
			(xy 448.231259 -48.7809) (xy 448.223139 -48.836076) (xy 448.220695 -48.8442) (xy 448.48729 -48.8442)
			(xy 448.491361 -48.788578) (xy 448.503487 -48.734141) (xy 448.52341 -48.68205) (xy 448.550706 -48.633415)
			(xy 448.584792 -48.589272) (xy 448.624941 -48.550563) (xy 448.670299 -48.518112) (xy 448.719899 -48.492611)
			(xy 448.772683 -48.474604) (xy 448.827526 -48.464474) (xy 448.88326 -48.462437) (xy 448.938697 -48.468537)
			(xy 448.992654 -48.482643) (xy 449.043983 -48.504455) (xy 449.091589 -48.533509) (xy 449.134457 -48.569184)
			(xy 449.171674 -48.610721) (xy 449.202447 -48.657234) (xy 449.226119 -48.707731) (xy 449.242187 -48.761138)
			(xy 449.250307 -48.816314) (xy 449.250816 -48.8442) (xy 449.250307 -48.872086) (xy 449.247309 -48.89246)
			(xy 449.513958 -48.89246) (xy 449.518029 -48.836838) (xy 449.530155 -48.782401) (xy 449.550078 -48.73031)
			(xy 449.577374 -48.681675) (xy 449.61146 -48.637532) (xy 449.651609 -48.598823) (xy 449.696967 -48.566372)
			(xy 449.746567 -48.540871) (xy 449.799351 -48.522864) (xy 449.854194 -48.512734) (xy 449.909928 -48.510697)
			(xy 449.965365 -48.516797) (xy 450.019322 -48.530903) (xy 450.070651 -48.552715) (xy 450.118257 -48.581769)
			(xy 450.161125 -48.617444) (xy 450.198342 -48.658981) (xy 450.229115 -48.705494) (xy 450.252787 -48.755991)
			(xy 450.268855 -48.809398) (xy 450.276975 -48.864574) (xy 450.277484 -48.89246) (xy 450.276975 -48.920346)
			(xy 450.268855 -48.975522) (xy 450.252787 -49.028929) (xy 450.229115 -49.079426) (xy 450.198342 -49.125939)
			(xy 450.161125 -49.167476) (xy 450.118257 -49.203151) (xy 450.070651 -49.232205) (xy 450.019322 -49.254017)
			(xy 449.965365 -49.268123) (xy 449.909928 -49.274223) (xy 449.854194 -49.272186) (xy 449.799351 -49.262056)
			(xy 449.746567 -49.244049) (xy 449.696967 -49.218548) (xy 449.651609 -49.186097) (xy 449.61146 -49.147388)
			(xy 449.577374 -49.103245) (xy 449.550078 -49.05461) (xy 449.530155 -49.002519) (xy 449.518029 -48.948082)
			(xy 449.513958 -48.89246) (xy 449.247309 -48.89246) (xy 449.242187 -48.927262) (xy 449.226119 -48.980669)
			(xy 449.202447 -49.031166) (xy 449.171674 -49.077679) (xy 449.134457 -49.119216) (xy 449.091589 -49.154891)
			(xy 449.043983 -49.183945) (xy 448.992654 -49.205757) (xy 448.938697 -49.219863) (xy 448.88326 -49.225963)
			(xy 448.827526 -49.223926) (xy 448.772683 -49.213796) (xy 448.719899 -49.195789) (xy 448.670299 -49.170288)
			(xy 448.624941 -49.137837) (xy 448.584792 -49.099128) (xy 448.550706 -49.054985) (xy 448.52341 -49.00635)
			(xy 448.503487 -48.954259) (xy 448.491361 -48.899822) (xy 448.48729 -48.8442) (xy 448.220695 -48.8442)
			(xy 448.207071 -48.889483) (xy 448.183399 -48.93998) (xy 448.152626 -48.986493) (xy 448.115409 -49.02803)
			(xy 448.072541 -49.063705) (xy 448.024935 -49.092759) (xy 447.973606 -49.114571) (xy 447.919649 -49.128677)
			(xy 447.864212 -49.134777) (xy 447.808478 -49.13274) (xy 447.753635 -49.12261) (xy 447.700851 -49.104603)
			(xy 447.651251 -49.079102) (xy 447.605893 -49.046651) (xy 447.565744 -49.007942) (xy 447.531658 -48.963799)
			(xy 447.504362 -48.915164) (xy 447.484439 -48.863073) (xy 447.472313 -48.808636) (xy 447.468242 -48.753014)
			(xy 439.569071 -48.753014) (xy 439.617104 -49.213516) (xy 439.619644 -49.224946) (xy 439.822844 -49.81067)
			(xy 439.837069 -49.853106) (xy 439.858694 -49.939961) (xy 439.872367 -50.028418) (xy 439.875676 -50.073052)
			(xy 439.884312 -50.210212) (xy 439.935081 -51.019456) (xy 451.049388 -51.019456) (xy 451.053459 -50.963834)
			(xy 451.065585 -50.909397) (xy 451.085508 -50.857306) (xy 451.112804 -50.808671) (xy 451.14689 -50.764528)
			(xy 451.187039 -50.725819) (xy 451.232397 -50.693368) (xy 451.281997 -50.667867) (xy 451.334781 -50.64986)
			(xy 451.389624 -50.63973) (xy 451.445358 -50.637693) (xy 451.500795 -50.643793) (xy 451.554752 -50.657899)
			(xy 451.606081 -50.679711) (xy 451.653687 -50.708765) (xy 451.696555 -50.74444) (xy 451.733772 -50.785977)
			(xy 451.764545 -50.83249) (xy 451.788217 -50.882987) (xy 451.804285 -50.936394) (xy 451.812405 -50.99157)
			(xy 451.812914 -51.019456) (xy 451.812405 -51.047342) (xy 451.804285 -51.102518) (xy 451.788217 -51.155925)
			(xy 451.764545 -51.206422) (xy 451.733772 -51.252935) (xy 451.696555 -51.294472) (xy 451.653687 -51.330147)
			(xy 451.606081 -51.359201) (xy 451.554752 -51.381013) (xy 451.500795 -51.395119) (xy 451.445358 -51.401219)
			(xy 451.389624 -51.399182) (xy 451.334781 -51.389052) (xy 451.281997 -51.371045) (xy 451.232397 -51.345544)
			(xy 451.187039 -51.313093) (xy 451.14689 -51.274384) (xy 451.112804 -51.230241) (xy 451.085508 -51.181606)
			(xy 451.065585 -51.129515) (xy 451.053459 -51.075078) (xy 451.049388 -51.019456) (xy 439.935081 -51.019456)
			(xy 440.018932 -52.356004) (xy 440.020456 -52.36591) (xy 440.022909 -52.373766) (xy 440.031979 -52.387488)
			(xy 440.038236 -52.392834) (xy 440.059064 -52.409344) (xy 440.06897 -52.415694) (xy 440.076973 -52.419071)
			(xy 440.094248 -52.420764) (xy 440.102752 -52.418996) (xy 440.127137 -52.413423) (xy 440.176801 -52.407433)
			(xy 440.201812 -52.407058) (xy 440.202066 -52.407058) (xy 440.232024 -52.407565) (xy 440.29133 -52.416087)
			(xy 440.348819 -52.432964) (xy 440.403321 -52.457851) (xy 440.453726 -52.490241) (xy 440.499008 -52.529476)
			(xy 440.538246 -52.574756) (xy 440.570639 -52.62516) (xy 440.595529 -52.67966) (xy 440.612408 -52.737149)
			(xy 440.620934 -52.796454) (xy 440.62142 -52.826412) (xy 440.620972 -52.853854) (xy 440.613813 -52.90827)
			(xy 440.599619 -52.961288) (xy 440.578632 -53.012001) (xy 440.551211 -53.059545) (xy 440.517824 -53.103107)
			(xy 440.498738 -53.12283) (xy 440.493912 -53.12791) (xy 440.478418 -53.164232) (xy 440.478418 -53.178964)
			(xy 440.478785 -53.186999) (xy 440.48384 -53.202258) (xy 440.488324 -53.208936) (xy 440.490864 -53.211984)
			(xy 440.508263 -53.232856) (xy 440.537587 -53.278602) (xy 440.560111 -53.328051) (xy 440.575379 -53.3802)
			(xy 440.58308 -53.433989) (xy 440.583574 -53.461158) (xy 440.583574 -53.461412) (xy 440.583149 -53.486923)
			(xy 440.576353 -53.537491) (xy 440.562884 -53.586703) (xy 440.542981 -53.633683) (xy 440.517 -53.677595)
			(xy 440.501532 -53.697886) (xy 440.498992 -53.700934) (xy 440.497976 -53.702458) (xy 440.494674 -53.709062)
			(xy 440.492331 -53.714285) (xy 440.489767 -53.725438) (xy 440.489594 -53.73116) (xy 440.489594 -53.763164)
			(xy 440.478418 -53.763164) (xy 440.478418 -53.813964) (xy 440.478753 -53.822567) (xy 440.484466 -53.838797)
			(xy 440.489594 -53.845714) (xy 440.490864 -53.847238) (xy 440.508257 -53.868115) (xy 440.537573 -53.913866)
			(xy 440.560099 -53.963314) (xy 440.575379 -54.015458) (xy 440.583103 -54.069244) (xy 440.583574 -54.096412)
			(xy 440.583149 -54.121923) (xy 440.576353 -54.172491) (xy 440.562884 -54.221703) (xy 440.542981 -54.268683)
			(xy 440.517 -54.312595) (xy 440.501532 -54.332886) (xy 440.498992 -54.335934) (xy 440.497976 -54.337458)
			(xy 440.494674 -54.344062) (xy 440.492331 -54.349285) (xy 440.489767 -54.360438) (xy 440.489594 -54.36616)
			(xy 440.489594 -54.398164) (xy 440.478418 -54.398164) (xy 440.478418 -54.448964) (xy 440.478753 -54.457567)
			(xy 440.484466 -54.473797) (xy 440.489594 -54.480714) (xy 440.490864 -54.482238) (xy 440.508257 -54.503115)
			(xy 440.537573 -54.548866) (xy 440.560099 -54.598314) (xy 440.575379 -54.650458) (xy 440.583103 -54.704244)
			(xy 440.583574 -54.731412) (xy 440.583021 -54.760556) (xy 440.578319 -54.791102) (xy 442.476382 -54.791102)
			(xy 442.476829 -54.763731) (xy 442.484649 -54.70955) (xy 442.500141 -54.657046) (xy 442.522987 -54.607299)
			(xy 442.552718 -54.561334) (xy 442.570362 -54.540404) (xy 442.570616 -54.54015) (xy 442.57619 -54.533055)
			(xy 442.582444 -54.516145) (xy 442.582808 -54.50713) (xy 442.582808 -54.440074) (xy 442.582461 -54.431056)
			(xy 442.576206 -54.414139) (xy 442.570616 -54.407054) (xy 442.570362 -54.407054) (xy 442.570362 -54.4068)
			(xy 442.552722 -54.385866) (xy 442.522994 -54.3399) (xy 442.500147 -54.290154) (xy 442.484649 -54.237651)
			(xy 442.476819 -54.183472) (xy 442.476819 -54.128731) (xy 442.484648 -54.074551) (xy 442.500146 -54.022049)
			(xy 442.522993 -53.972303) (xy 442.55272 -53.926336) (xy 442.570362 -53.905404) (xy 442.570616 -53.90515)
			(xy 442.57619 -53.898055) (xy 442.582444 -53.881145) (xy 442.582808 -53.87213) (xy 442.582808 -53.805074)
			(xy 442.582461 -53.796056) (xy 442.576206 -53.779139) (xy 442.570616 -53.772054) (xy 442.570362 -53.772054)
			(xy 442.570362 -53.7718) (xy 442.552722 -53.750866) (xy 442.522994 -53.7049) (xy 442.500147 -53.655154)
			(xy 442.484649 -53.602651) (xy 442.476819 -53.548472) (xy 442.476819 -53.493731) (xy 442.484648 -53.439551)
			(xy 442.500146 -53.387049) (xy 442.522993 -53.337303) (xy 442.55272 -53.291336) (xy 442.570362 -53.270404)
			(xy 442.570616 -53.27015) (xy 442.57619 -53.263055) (xy 442.582444 -53.246145) (xy 442.582808 -53.23713)
			(xy 442.582808 -53.170074) (xy 442.582461 -53.161056) (xy 442.576206 -53.144139) (xy 442.570616 -53.137054)
			(xy 442.570362 -53.137054) (xy 442.570362 -53.1368) (xy 442.552703 -53.115884) (xy 442.522995 -53.069906)
			(xy 442.500164 -53.020155) (xy 442.484677 -52.967651) (xy 442.476853 -52.913472) (xy 442.476382 -52.886102)
			(xy 442.476868 -52.858851) (xy 442.484624 -52.804903) (xy 442.499979 -52.752608) (xy 442.522621 -52.703031)
			(xy 442.552087 -52.657181) (xy 442.587778 -52.61599) (xy 442.628969 -52.580299) (xy 442.674819 -52.550833)
			(xy 442.724396 -52.528191) (xy 442.776691 -52.512836) (xy 442.830639 -52.50508) (xy 442.885141 -52.50508)
			(xy 442.939089 -52.512836) (xy 442.991384 -52.528191) (xy 443.030497 -52.546054) (xy 447.979473 -52.546054)
			(xy 447.979473 -52.491546) (xy 447.987231 -52.437594) (xy 448.002589 -52.385295) (xy 448.025234 -52.335714)
			(xy 448.054705 -52.289861) (xy 448.090401 -52.248669) (xy 448.131598 -52.212977) (xy 448.177454 -52.183512)
			(xy 448.227038 -52.160873) (xy 448.279339 -52.145521) (xy 448.333292 -52.13777) (xy 448.360546 -52.13731)
			(xy 448.387915 -52.137805) (xy 448.442093 -52.145616) (xy 448.494596 -52.161098) (xy 448.544343 -52.183933)
			(xy 448.590311 -52.213652) (xy 448.611244 -52.23129) (xy 448.611498 -52.231544) (xy 448.618577 -52.237141)
			(xy 448.6355 -52.24338) (xy 448.644518 -52.243736) (xy 448.711574 -52.243736) (xy 448.720589 -52.243359)
			(xy 448.737505 -52.237124) (xy 448.744594 -52.231544) (xy 448.744594 -52.23129) (xy 448.744848 -52.23129)
			(xy 448.765781 -52.213649) (xy 448.811749 -52.183925) (xy 448.861495 -52.161079) (xy 448.913997 -52.145583)
			(xy 448.968175 -52.137754) (xy 449.022917 -52.137754) (xy 449.077095 -52.145583) (xy 449.129597 -52.161079)
			(xy 449.179343 -52.183925) (xy 449.225311 -52.213649) (xy 449.246244 -52.23129) (xy 449.246498 -52.231544)
			(xy 449.253577 -52.237141) (xy 449.2705 -52.24338) (xy 449.279518 -52.243736) (xy 449.346574 -52.243736)
			(xy 449.355589 -52.243359) (xy 449.372505 -52.237124) (xy 449.379594 -52.231544) (xy 449.379594 -52.23129)
			(xy 449.379848 -52.23129) (xy 449.400788 -52.21366) (xy 449.446758 -52.183947) (xy 449.496504 -52.16111)
			(xy 449.549003 -52.145616) (xy 449.603177 -52.137786) (xy 449.630546 -52.13731) (xy 449.657796 -52.137763)
			(xy 449.711742 -52.145525) (xy 449.764033 -52.160885) (xy 449.813607 -52.18353) (xy 449.859454 -52.212999)
			(xy 449.900641 -52.248692) (xy 449.936329 -52.289883) (xy 449.965792 -52.335733) (xy 449.988431 -52.38531)
			(xy 450.003785 -52.437603) (xy 450.01154 -52.49155) (xy 450.01154 -52.54605) (xy 450.005596 -52.587398)
			(xy 451.05523 -52.587398) (xy 451.059301 -52.531776) (xy 451.071427 -52.477339) (xy 451.09135 -52.425248)
			(xy 451.118646 -52.376613) (xy 451.152732 -52.33247) (xy 451.192881 -52.293761) (xy 451.238239 -52.26131)
			(xy 451.287839 -52.235809) (xy 451.340623 -52.217802) (xy 451.395466 -52.207672) (xy 451.4512 -52.205635)
			(xy 451.506637 -52.211735) (xy 451.560594 -52.225841) (xy 451.611923 -52.247653) (xy 451.659529 -52.276707)
			(xy 451.702397 -52.312382) (xy 451.739614 -52.353919) (xy 451.770387 -52.400432) (xy 451.794059 -52.450929)
			(xy 451.810127 -52.504336) (xy 451.818247 -52.559512) (xy 451.818756 -52.587398) (xy 451.818247 -52.615284)
			(xy 451.810127 -52.67046) (xy 451.794059 -52.723867) (xy 451.770387 -52.774364) (xy 451.739614 -52.820877)
			(xy 451.702397 -52.862414) (xy 451.659529 -52.898089) (xy 451.611923 -52.927143) (xy 451.560594 -52.948955)
			(xy 451.506637 -52.963061) (xy 451.4512 -52.969161) (xy 451.395466 -52.967124) (xy 451.340623 -52.956994)
			(xy 451.287839 -52.938987) (xy 451.238239 -52.913486) (xy 451.192881 -52.881035) (xy 451.152732 -52.842326)
			(xy 451.118646 -52.798183) (xy 451.09135 -52.749548) (xy 451.071427 -52.697457) (xy 451.059301 -52.64302)
			(xy 451.05523 -52.587398) (xy 450.005596 -52.587398) (xy 450.003785 -52.599997) (xy 449.988431 -52.65229)
			(xy 449.965792 -52.701867) (xy 449.936329 -52.747717) (xy 449.900641 -52.788908) (xy 449.859454 -52.824601)
			(xy 449.813607 -52.85407) (xy 449.764033 -52.876715) (xy 449.711742 -52.892075) (xy 449.657796 -52.899837)
			(xy 449.630546 -52.900326) (xy 449.603176 -52.899851) (xy 449.548996 -52.892038) (xy 449.496493 -52.876552)
			(xy 449.446746 -52.853712) (xy 449.400779 -52.823988) (xy 449.379848 -52.806346) (xy 449.379594 -52.806092)
			(xy 449.372514 -52.800496) (xy 449.355592 -52.794255) (xy 449.346574 -52.7939) (xy 449.279518 -52.7939)
			(xy 449.270502 -52.794266) (xy 449.253585 -52.800507) (xy 449.246498 -52.806092) (xy 449.246244 -52.806346)
			(xy 449.225311 -52.823987) (xy 449.179343 -52.853711) (xy 449.129597 -52.876557) (xy 449.077095 -52.892053)
			(xy 449.022917 -52.899882) (xy 448.968175 -52.899882) (xy 448.913997 -52.892053) (xy 448.861495 -52.876557)
			(xy 448.811749 -52.853711) (xy 448.765781 -52.823987) (xy 448.744848 -52.806346) (xy 448.744594 -52.806092)
			(xy 448.737514 -52.800496) (xy 448.720592 -52.794255) (xy 448.711574 -52.7939) (xy 448.644518 -52.7939)
			(xy 448.635502 -52.794266) (xy 448.618585 -52.800507) (xy 448.611498 -52.806092) (xy 448.611498 -52.806346)
			(xy 448.611244 -52.806346) (xy 448.590299 -52.82397) (xy 448.544331 -52.853686) (xy 448.494587 -52.876525)
			(xy 448.442088 -52.89202) (xy 448.387914 -52.899851) (xy 448.360546 -52.900326) (xy 448.333292 -52.89983)
			(xy 448.279339 -52.892079) (xy 448.227038 -52.876727) (xy 448.177454 -52.854088) (xy 448.131598 -52.824623)
			(xy 448.090401 -52.788931) (xy 448.054705 -52.747739) (xy 448.025234 -52.701886) (xy 448.002589 -52.652305)
			(xy 447.987231 -52.600006) (xy 447.979473 -52.546054) (xy 443.030497 -52.546054) (xy 443.040961 -52.550833)
			(xy 443.086811 -52.580299) (xy 443.128002 -52.61599) (xy 443.163693 -52.657181) (xy 443.193159 -52.703031)
			(xy 443.215801 -52.752608) (xy 443.231156 -52.804903) (xy 443.238912 -52.858851) (xy 443.239398 -52.886102)
			(xy 443.238934 -52.913472) (xy 443.231115 -52.967651) (xy 443.215626 -53.020155) (xy 443.192784 -53.069901)
			(xy 443.163059 -53.115868) (xy 443.145418 -53.1368) (xy 443.145164 -53.137054) (xy 443.139587 -53.144147)
			(xy 443.133335 -53.161059) (xy 443.132972 -53.170074) (xy 443.132972 -53.23713) (xy 443.133321 -53.246148)
			(xy 443.139575 -53.263064) (xy 443.145164 -53.27015) (xy 443.145418 -53.27015) (xy 443.145418 -53.270404)
			(xy 443.163059 -53.291336) (xy 443.19278 -53.337305) (xy 443.215623 -53.387052) (xy 443.231117 -53.439553)
			(xy 443.238944 -53.493731) (xy 443.238944 -53.548472) (xy 443.231116 -53.602649) (xy 443.215621 -53.655151)
			(xy 443.192779 -53.704898) (xy 443.163057 -53.750866) (xy 443.146488 -53.77053) (xy 443.51067 -53.77053)
			(xy 443.511183 -53.741613) (xy 443.51991 -53.68444) (xy 443.537167 -53.62924) (xy 443.562559 -53.577278)
			(xy 443.595505 -53.529744) (xy 443.635249 -53.487729) (xy 443.657736 -53.46954) (xy 443.666521 -53.461912)
			(xy 443.676715 -53.441027) (xy 443.677294 -53.429408) (xy 443.677294 -53.349652) (xy 443.67677 -53.338018)
			(xy 443.666571 -53.317109) (xy 443.657736 -53.30952) (xy 443.63527 -53.291309) (xy 443.595532 -53.249294)
			(xy 443.56259 -53.201764) (xy 443.537198 -53.149806) (xy 443.519938 -53.094612) (xy 443.511206 -53.037445)
			(xy 443.51067 -53.00853) (xy 443.511183 -52.981279) (xy 443.518935 -52.927331) (xy 443.534287 -52.875035)
			(xy 443.556924 -52.825457) (xy 443.586387 -52.779605) (xy 443.622075 -52.738412) (xy 443.663263 -52.702718)
			(xy 443.709111 -52.673249) (xy 443.758687 -52.650605) (xy 443.81098 -52.635247) (xy 443.864927 -52.627487)
			(xy 443.892178 -52.627022) (xy 443.918492 -52.627497) (xy 443.97062 -52.634729) (xy 444.021263 -52.649046)
			(xy 444.069462 -52.670177) (xy 444.114306 -52.697723) (xy 444.154946 -52.731161) (xy 444.173102 -52.750212)
			(xy 444.180619 -52.757618) (xy 444.199903 -52.76614) (xy 444.21044 -52.766722) (xy 444.285116 -52.766722)
			(xy 444.295667 -52.766208) (xy 444.314962 -52.757662) (xy 444.322454 -52.750212) (xy 444.340593 -52.73114)
			(xy 444.381226 -52.697683) (xy 444.426069 -52.670126) (xy 444.474274 -52.648991) (xy 444.524924 -52.634677)
			(xy 444.577061 -52.627458) (xy 444.603378 -52.627022) (xy 444.630632 -52.627476) (xy 444.684585 -52.635231)
			(xy 444.736884 -52.650585) (xy 444.786466 -52.673228) (xy 444.832321 -52.702696) (xy 444.873515 -52.738391)
			(xy 444.909209 -52.779585) (xy 444.938676 -52.825441) (xy 444.961317 -52.875023) (xy 444.976671 -52.927323)
			(xy 444.984425 -52.981276) (xy 444.984886 -53.00853) (xy 444.984404 -53.036196) (xy 444.9764 -53.090947)
			(xy 444.960578 -53.14397) (xy 444.937271 -53.194154) (xy 444.906965 -53.240449) (xy 444.870295 -53.281887)
			(xy 444.828029 -53.317598) (xy 444.8048 -53.332634) (xy 444.795119 -53.339266) (xy 444.782674 -53.35913)
			(xy 444.780924 -53.370734) (xy 444.77305 -53.450744) (xy 444.772399 -53.462383) (xy 444.780492 -53.484221)
			(xy 444.788544 -53.492654) (xy 444.788798 -53.492908) (xy 444.807365 -53.511003) (xy 444.839945 -53.551332)
			(xy 444.86676 -53.595703) (xy 444.887315 -53.643299) (xy 444.901231 -53.693241) (xy 444.908252 -53.744608)
			(xy 444.908686 -53.77053) (xy 444.90825 -53.797783) (xy 444.900489 -53.851734) (xy 444.885129 -53.904031)
			(xy 444.862483 -53.953609) (xy 444.833011 -53.999461) (xy 444.797314 -54.040651) (xy 444.756119 -54.076342)
			(xy 444.710264 -54.105808) (xy 444.660682 -54.128447) (xy 444.608383 -54.1438) (xy 444.554431 -54.151554)
			(xy 444.527178 -54.152038) (xy 444.499807 -54.1516) (xy 444.445626 -54.143778) (xy 444.393122 -54.128283)
			(xy 444.343375 -54.105435) (xy 444.29741 -54.075703) (xy 444.27648 -54.058058) (xy 444.276226 -54.057804)
			(xy 444.269136 -54.052223) (xy 444.252222 -54.045973) (xy 444.243206 -54.045612) (xy 444.17615 -54.045612)
			(xy 444.167135 -54.045991) (xy 444.150218 -54.052223) (xy 444.14313 -54.057804) (xy 444.14313 -54.058058)
			(xy 444.142876 -54.058058) (xy 444.121921 -54.075668) (xy 444.075955 -54.105386) (xy 444.026213 -54.128228)
			(xy 443.973718 -54.143726) (xy 443.919546 -54.151561) (xy 443.892178 -54.152038) (xy 443.864928 -54.151543)
			(xy 443.810982 -54.143784) (xy 443.758689 -54.128428) (xy 443.709114 -54.105786) (xy 443.663265 -54.07632)
			(xy 443.622076 -54.04063) (xy 443.586384 -53.999442) (xy 443.556918 -53.953593) (xy 443.534275 -53.904018)
			(xy 443.518918 -53.851726) (xy 443.511158 -53.79778) (xy 443.51067 -53.77053) (xy 443.146488 -53.77053)
			(xy 443.145418 -53.7718) (xy 443.145164 -53.772054) (xy 443.139587 -53.779147) (xy 443.133335 -53.796059)
			(xy 443.132972 -53.805074) (xy 443.132972 -53.87213) (xy 443.133321 -53.881148) (xy 443.139575 -53.898064)
			(xy 443.145164 -53.90515) (xy 443.145418 -53.90515) (xy 443.145418 -53.905404) (xy 443.163059 -53.926336)
			(xy 443.19278 -53.972305) (xy 443.215623 -54.022052) (xy 443.231117 -54.074553) (xy 443.238944 -54.128731)
			(xy 443.238944 -54.183472) (xy 443.231116 -54.237649) (xy 443.215621 -54.290151) (xy 443.20183 -54.320186)
			(xy 445.430402 -54.320186) (xy 445.430859 -54.292815) (xy 445.438679 -54.238636) (xy 445.45417 -54.186133)
			(xy 445.477014 -54.136386) (xy 445.50674 -54.09042) (xy 445.524382 -54.069488) (xy 445.524636 -54.069234)
			(xy 445.530218 -54.062145) (xy 445.536467 -54.04523) (xy 445.536828 -54.036214) (xy 445.536828 -53.969158)
			(xy 445.536437 -53.960145) (xy 445.530212 -53.943228) (xy 445.524636 -53.936138) (xy 445.524382 -53.936138)
			(xy 445.524382 -53.935884) (xy 445.506766 -53.914933) (xy 445.477051 -53.868965) (xy 445.454211 -53.819223)
			(xy 445.438715 -53.766726) (xy 445.43088 -53.712554) (xy 445.430402 -53.685186) (xy 445.430888 -53.657935)
			(xy 445.438644 -53.603987) (xy 445.453999 -53.551692) (xy 445.476641 -53.502115) (xy 445.506107 -53.456265)
			(xy 445.541798 -53.415074) (xy 445.582989 -53.379383) (xy 445.628839 -53.349917) (xy 445.678416 -53.327275)
			(xy 445.730711 -53.31192) (xy 445.784659 -53.304164) (xy 445.839161 -53.304164) (xy 445.893109 -53.31192)
			(xy 445.945404 -53.327275) (xy 445.994981 -53.349917) (xy 446.040831 -53.379383) (xy 446.082022 -53.415074)
			(xy 446.117713 -53.456265) (xy 446.147179 -53.502115) (xy 446.169821 -53.551692) (xy 446.185176 -53.603987)
			(xy 446.192932 -53.657935) (xy 446.193418 -53.685186) (xy 446.192964 -53.712557) (xy 446.185146 -53.766737)
			(xy 446.169655 -53.819241) (xy 446.14681 -53.868988) (xy 446.117082 -53.914954) (xy 446.099438 -53.935884)
			(xy 446.099184 -53.936138) (xy 446.093615 -53.943237) (xy 446.087358 -53.960144) (xy 446.086992 -53.969158)
			(xy 446.086992 -54.036214) (xy 446.087344 -54.045231) (xy 446.093595 -54.062148) (xy 446.099184 -54.069234)
			(xy 446.099438 -54.069234) (xy 446.099438 -54.069488) (xy 446.117091 -54.090409) (xy 446.1468 -54.136385)
			(xy 446.169632 -54.186136) (xy 446.18512 -54.238639) (xy 446.192946 -54.292816) (xy 446.193418 -54.320186)
			(xy 446.192932 -54.347437) (xy 446.185176 -54.401385) (xy 446.169821 -54.45368) (xy 446.147179 -54.503257)
			(xy 446.117713 -54.549107) (xy 446.082022 -54.590298) (xy 446.040831 -54.625989) (xy 445.994981 -54.655455)
			(xy 445.945404 -54.678097) (xy 445.893109 -54.693452) (xy 445.839161 -54.701208) (xy 445.784659 -54.701208)
			(xy 445.730711 -54.693452) (xy 445.678416 -54.678097) (xy 445.628839 -54.655455) (xy 445.582989 -54.625989)
			(xy 445.541798 -54.590298) (xy 445.506107 -54.549107) (xy 445.476641 -54.503257) (xy 445.453999 -54.45368)
			(xy 445.438644 -54.401385) (xy 445.430888 -54.347437) (xy 445.430402 -54.320186) (xy 443.20183 -54.320186)
			(xy 443.192779 -54.339898) (xy 443.163057 -54.385866) (xy 443.145418 -54.4068) (xy 443.145164 -54.407054)
			(xy 443.139587 -54.414147) (xy 443.133335 -54.431059) (xy 443.132972 -54.440074) (xy 443.132972 -54.50713)
			(xy 443.133321 -54.516148) (xy 443.139575 -54.533064) (xy 443.145164 -54.54015) (xy 443.145418 -54.54015)
			(xy 443.145418 -54.540404) (xy 443.163075 -54.561321) (xy 443.192784 -54.607299) (xy 443.215616 -54.65705)
			(xy 443.231103 -54.709554) (xy 443.238926 -54.763732) (xy 443.239043 -54.770528) (xy 446.370964 -54.770528)
			(xy 446.371431 -54.743158) (xy 446.379246 -54.688978) (xy 446.394734 -54.636474) (xy 446.417576 -54.586727)
			(xy 446.447302 -54.540761) (xy 446.464944 -54.51983) (xy 446.465198 -54.519576) (xy 446.470801 -54.5125)
			(xy 446.477038 -54.495575) (xy 446.47739 -54.486556) (xy 446.47739 -54.4195) (xy 446.477035 -54.410483)
			(xy 446.470786 -54.393566) (xy 446.465198 -54.38648) (xy 446.464944 -54.38648) (xy 446.464944 -54.386226)
			(xy 446.44731 -54.365289) (xy 446.417596 -54.319318) (xy 446.394759 -54.269572) (xy 446.379266 -54.217072)
			(xy 446.371438 -54.162897) (xy 446.370964 -54.135528) (xy 446.37145 -54.108277) (xy 446.379206 -54.054329)
			(xy 446.394561 -54.002034) (xy 446.417203 -53.952457) (xy 446.446669 -53.906607) (xy 446.48236 -53.865416)
			(xy 446.523551 -53.829725) (xy 446.569401 -53.800259) (xy 446.618978 -53.777617) (xy 446.671273 -53.762262)
			(xy 446.725221 -53.754506) (xy 446.779723 -53.754506) (xy 446.833671 -53.762262) (xy 446.885966 -53.777617)
			(xy 446.935543 -53.800259) (xy 446.981393 -53.829725) (xy 447.022584 -53.865416) (xy 447.058275 -53.906607)
			(xy 447.087741 -53.952457) (xy 447.092816 -53.96357) (xy 451.071994 -53.96357) (xy 451.076065 -53.907948)
			(xy 451.088191 -53.853511) (xy 451.108114 -53.80142) (xy 451.13541 -53.752785) (xy 451.169496 -53.708642)
			(xy 451.209645 -53.669933) (xy 451.255003 -53.637482) (xy 451.304603 -53.611981) (xy 451.357387 -53.593974)
			(xy 451.41223 -53.583844) (xy 451.467964 -53.581807) (xy 451.523401 -53.587907) (xy 451.577358 -53.602013)
			(xy 451.628687 -53.623825) (xy 451.676293 -53.652879) (xy 451.719161 -53.688554) (xy 451.756378 -53.730091)
			(xy 451.787151 -53.776604) (xy 451.810823 -53.827101) (xy 451.826891 -53.880508) (xy 451.835011 -53.935684)
			(xy 451.83552 -53.96357) (xy 451.835011 -53.991456) (xy 451.826891 -54.046632) (xy 451.810823 -54.100039)
			(xy 451.787151 -54.150536) (xy 451.756378 -54.197049) (xy 451.719161 -54.238586) (xy 451.676293 -54.274261)
			(xy 451.628687 -54.303315) (xy 451.577358 -54.325127) (xy 451.523401 -54.339233) (xy 451.467964 -54.345333)
			(xy 451.41223 -54.343296) (xy 451.357387 -54.333166) (xy 451.304603 -54.315159) (xy 451.255003 -54.289658)
			(xy 451.209645 -54.257207) (xy 451.169496 -54.218498) (xy 451.13541 -54.174355) (xy 451.108114 -54.12572)
			(xy 451.088191 -54.073629) (xy 451.076065 -54.019192) (xy 451.071994 -53.96357) (xy 447.092816 -53.96357)
			(xy 447.110383 -54.002034) (xy 447.125738 -54.054329) (xy 447.133494 -54.108277) (xy 447.13398 -54.135528)
			(xy 447.133535 -54.162899) (xy 447.125713 -54.217079) (xy 447.110219 -54.269583) (xy 447.087373 -54.319329)
			(xy 447.057643 -54.365295) (xy 447.04 -54.386226) (xy 447.039746 -54.38648) (xy 447.034155 -54.393563)
			(xy 447.027912 -54.410483) (xy 447.027554 -54.4195) (xy 447.027554 -54.486556) (xy 447.02792 -54.495572)
			(xy 447.03416 -54.51249) (xy 447.039746 -54.519576) (xy 447.04 -54.519576) (xy 447.04 -54.51983)
			(xy 447.05762 -54.540778) (xy 447.087334 -54.586746) (xy 447.110174 -54.63649) (xy 447.12567 -54.688987)
			(xy 447.133503 -54.74316) (xy 447.13398 -54.770528) (xy 447.133494 -54.797779) (xy 447.125738 -54.851727)
			(xy 447.110383 -54.904022) (xy 447.087741 -54.953599) (xy 447.058275 -54.999449) (xy 447.022584 -55.04064)
			(xy 446.981393 -55.076331) (xy 446.935543 -55.105797) (xy 446.885966 -55.128439) (xy 446.833671 -55.143794)
			(xy 446.779723 -55.15155) (xy 446.725221 -55.15155) (xy 446.671273 -55.143794) (xy 446.618978 -55.128439)
			(xy 446.569401 -55.105797) (xy 446.523551 -55.076331) (xy 446.48236 -55.04064) (xy 446.446669 -54.999449)
			(xy 446.417203 -54.953599) (xy 446.394561 -54.904022) (xy 446.379206 -54.851727) (xy 446.37145 -54.797779)
			(xy 446.370964 -54.770528) (xy 443.239043 -54.770528) (xy 443.239398 -54.791102) (xy 443.238912 -54.818353)
			(xy 443.231156 -54.872301) (xy 443.215801 -54.924596) (xy 443.193159 -54.974173) (xy 443.163693 -55.020023)
			(xy 443.128002 -55.061214) (xy 443.086811 -55.096905) (xy 443.040961 -55.126371) (xy 442.991384 -55.149013)
			(xy 442.939089 -55.164368) (xy 442.885141 -55.172124) (xy 442.830639 -55.172124) (xy 442.776691 -55.164368)
			(xy 442.724396 -55.149013) (xy 442.674819 -55.126371) (xy 442.628969 -55.096905) (xy 442.587778 -55.061214)
			(xy 442.552087 -55.020023) (xy 442.522621 -54.974173) (xy 442.499979 -54.924596) (xy 442.484624 -54.872301)
			(xy 442.476868 -54.818353) (xy 442.476382 -54.791102) (xy 440.578319 -54.791102) (xy 440.574152 -54.818167)
			(xy 440.556622 -54.873757) (xy 440.530838 -54.926033) (xy 440.497402 -54.973779) (xy 440.457092 -55.015882)
			(xy 440.410846 -55.051363) (xy 440.35974 -55.079395) (xy 440.304965 -55.099327) (xy 440.276488 -55.105554)
			(xy 440.274202 -55.106062) (xy 440.265434 -55.108631) (xy 440.250377 -55.118954) (xy 440.239879 -55.133891)
			(xy 440.235266 -55.151556) (xy 440.235848 -55.160672) (xy 440.294292 -55.722266) (xy 452.133968 -55.722266)
			(xy 452.138039 -55.666644) (xy 452.150165 -55.612207) (xy 452.170088 -55.560116) (xy 452.197384 -55.511481)
			(xy 452.23147 -55.467338) (xy 452.271619 -55.428629) (xy 452.316977 -55.396178) (xy 452.366577 -55.370677)
			(xy 452.419361 -55.35267) (xy 452.474204 -55.34254) (xy 452.529938 -55.340503) (xy 452.585375 -55.346603)
			(xy 452.639332 -55.360709) (xy 452.690661 -55.382521) (xy 452.738267 -55.411575) (xy 452.781135 -55.44725)
			(xy 452.818352 -55.488787) (xy 452.849125 -55.5353) (xy 452.872797 -55.585797) (xy 452.888865 -55.639204)
			(xy 452.896985 -55.69438) (xy 452.897494 -55.722266) (xy 452.896985 -55.750152) (xy 452.888865 -55.805328)
			(xy 452.872797 -55.858735) (xy 452.849125 -55.909232) (xy 452.818352 -55.955745) (xy 452.781135 -55.997282)
			(xy 452.738267 -56.032957) (xy 452.690661 -56.062011) (xy 452.639332 -56.083823) (xy 452.585375 -56.097929)
			(xy 452.529938 -56.104029) (xy 452.474204 -56.101992) (xy 452.419361 -56.091862) (xy 452.366577 -56.073855)
			(xy 452.316977 -56.048354) (xy 452.271619 -56.015903) (xy 452.23147 -55.977194) (xy 452.197384 -55.933051)
			(xy 452.170088 -55.884416) (xy 452.150165 -55.832325) (xy 452.138039 -55.777888) (xy 452.133968 -55.722266)
			(xy 440.294292 -55.722266) (xy 440.370976 -56.45912) (xy 440.371738 -56.464976) (xy 440.375592 -56.476134)
			(xy 440.378596 -56.481218) (xy 440.381644 -56.486044) (xy 440.39028 -56.494172) (xy 440.395614 -56.497474)
			(xy 440.419791 -56.512276) (xy 440.463882 -56.547905) (xy 440.502216 -56.589666) (xy 440.533947 -56.63664)
			(xy 440.558378 -56.687793) (xy 440.57497 -56.741997) (xy 440.583358 -56.79806) (xy 440.583828 -56.826404)
			(xy 440.583828 -56.83377) (xy 440.583066 -56.847232) (xy 440.582091 -56.861954) (xy 440.578151 -56.891197)
			(xy 440.575192 -56.905652) (xy 440.568568 -56.934324) (xy 440.547694 -56.989341) (xy 440.539971 -57.002934)
			(xy 447.863468 -57.002934) (xy 447.863996 -56.974844) (xy 447.872218 -56.919268) (xy 447.888504 -56.865501)
			(xy 447.912501 -56.814703) (xy 447.943691 -56.767976) (xy 447.981398 -56.72633) (xy 448.024806 -56.690666)
			(xy 448.048634 -56.675782) (xy 448.057524 -56.670448) (xy 448.069716 -56.65343) (xy 448.090036 -56.560212)
			(xy 448.085718 -56.539638) (xy 448.079876 -56.531002) (xy 448.063872 -56.506941) (xy 448.038531 -56.455008)
			(xy 448.021306 -56.399849) (xy 448.012592 -56.342725) (xy 448.012058 -56.313832) (xy 448.012608 -56.286583)
			(xy 448.020359 -56.232639) (xy 448.035709 -56.180348) (xy 448.058343 -56.130773) (xy 448.087803 -56.084924)
			(xy 448.123488 -56.043735) (xy 448.164672 -56.008043) (xy 448.210515 -55.978575) (xy 448.260086 -55.955932)
			(xy 448.312375 -55.940573) (xy 448.366317 -55.932813) (xy 448.393566 -55.932324) (xy 448.420936 -55.932804)
			(xy 448.475115 -55.940618) (xy 448.527618 -55.956103) (xy 448.577365 -55.978942) (xy 448.623332 -56.008664)
			(xy 448.644264 -56.026304) (xy 448.644518 -56.026558) (xy 448.65159 -56.032165) (xy 448.668518 -56.038398)
			(xy 448.677538 -56.03875) (xy 448.744594 -56.03875) (xy 448.753612 -56.038401) (xy 448.770529 -56.032149)
			(xy 448.777614 -56.026558) (xy 448.777614 -56.026304) (xy 448.777868 -56.026304) (xy 448.798801 -56.008663)
			(xy 448.844769 -55.978939) (xy 448.894515 -55.956093) (xy 448.947017 -55.940597) (xy 449.001195 -55.932768)
			(xy 449.055937 -55.932768) (xy 449.110115 -55.940597) (xy 449.162617 -55.956093) (xy 449.212363 -55.978939)
			(xy 449.258331 -56.008663) (xy 449.279264 -56.026304) (xy 449.279518 -56.026558) (xy 449.28659 -56.032165)
			(xy 449.303518 -56.038398) (xy 449.312538 -56.03875) (xy 449.379594 -56.03875) (xy 449.388612 -56.038401)
			(xy 449.405529 -56.032149) (xy 449.412614 -56.026558) (xy 449.412614 -56.026304) (xy 449.412868 -56.026304)
			(xy 449.433802 -56.008667) (xy 449.479774 -55.978955) (xy 449.529521 -55.956118) (xy 449.582021 -55.940627)
			(xy 449.636197 -55.932798) (xy 449.663566 -55.932324) (xy 449.690823 -55.932721) (xy 449.744782 -55.940474)
			(xy 449.797088 -55.955829) (xy 449.846677 -55.978471) (xy 449.892538 -56.007941) (xy 449.933738 -56.043637)
			(xy 449.969439 -56.084835) (xy 449.998913 -56.130693) (xy 450.021559 -56.18028) (xy 450.036918 -56.232585)
			(xy 450.044677 -56.286543) (xy 450.044677 -56.297068) (xy 450.386448 -56.297068) (xy 450.390519 -56.241446)
			(xy 450.402645 -56.187009) (xy 450.422568 -56.134918) (xy 450.449864 -56.086283) (xy 450.48395 -56.04214)
			(xy 450.524099 -56.003431) (xy 450.569457 -55.97098) (xy 450.619057 -55.945479) (xy 450.671841 -55.927472)
			(xy 450.726684 -55.917342) (xy 450.782418 -55.915305) (xy 450.837855 -55.921405) (xy 450.891812 -55.935511)
			(xy 450.943141 -55.957323) (xy 450.990747 -55.986377) (xy 451.033615 -56.022052) (xy 451.070832 -56.063589)
			(xy 451.101605 -56.110102) (xy 451.125277 -56.160599) (xy 451.141345 -56.214006) (xy 451.149465 -56.269182)
			(xy 451.149974 -56.297068) (xy 451.149465 -56.324954) (xy 451.141345 -56.38013) (xy 451.125277 -56.433537)
			(xy 451.101605 -56.484034) (xy 451.070832 -56.530547) (xy 451.033615 -56.572084) (xy 450.990747 -56.607759)
			(xy 450.943141 -56.636813) (xy 450.891812 -56.658625) (xy 450.837855 -56.672731) (xy 450.782418 -56.678831)
			(xy 450.726684 -56.676794) (xy 450.671841 -56.666664) (xy 450.619057 -56.648657) (xy 450.569457 -56.623156)
			(xy 450.524099 -56.590705) (xy 450.48395 -56.551996) (xy 450.449864 -56.507853) (xy 450.422568 -56.459218)
			(xy 450.402645 -56.407127) (xy 450.390519 -56.35269) (xy 450.386448 -56.297068) (xy 450.044677 -56.297068)
			(xy 450.044677 -56.341057) (xy 450.036918 -56.395015) (xy 450.021559 -56.44732) (xy 449.998913 -56.496907)
			(xy 449.969439 -56.542765) (xy 449.933738 -56.583963) (xy 449.892538 -56.619659) (xy 449.846677 -56.649129)
			(xy 449.797088 -56.671771) (xy 449.744782 -56.687126) (xy 449.690823 -56.694879) (xy 449.663566 -56.69534)
			(xy 449.636194 -56.694908) (xy 449.582013 -56.687085) (xy 449.529509 -56.671588) (xy 449.479763 -56.648738)
			(xy 449.433798 -56.619005) (xy 449.412868 -56.60136) (xy 449.412614 -56.601106) (xy 449.405527 -56.59552)
			(xy 449.388611 -56.589273) (xy 449.379594 -56.588914) (xy 449.312538 -56.588914) (xy 449.303523 -56.589286)
			(xy 449.286605 -56.595523) (xy 449.279518 -56.601106) (xy 449.279518 -56.60136) (xy 449.279264 -56.60136)
			(xy 449.258331 -56.619001) (xy 449.212363 -56.648725) (xy 449.162617 -56.671571) (xy 449.110115 -56.687067)
			(xy 449.055937 -56.694896) (xy 449.001195 -56.694896) (xy 448.947017 -56.687067) (xy 448.894515 -56.671571)
			(xy 448.844769 -56.648725) (xy 448.798801 -56.619001) (xy 448.777868 -56.60136) (xy 448.777614 -56.601106)
			(xy 448.770527 -56.59552) (xy 448.753611 -56.589273) (xy 448.744594 -56.588914) (xy 448.677538 -56.588914)
			(xy 448.668523 -56.589286) (xy 448.651605 -56.595523) (xy 448.644518 -56.601106) (xy 448.64401 -56.60136)
			(xy 448.631279 -56.612308) (xy 448.604185 -56.632147) (xy 448.589908 -56.640984) (xy 448.581018 -56.646318)
			(xy 448.568826 -56.663336) (xy 448.548506 -56.756554) (xy 448.552824 -56.777128) (xy 448.558666 -56.785764)
			(xy 448.574649 -56.809839) (xy 448.599997 -56.861766) (xy 448.617227 -56.916921) (xy 448.625947 -56.974042)
			(xy 448.626484 -57.002934) (xy 448.625998 -57.030185) (xy 448.618242 -57.084133) (xy 448.602887 -57.136428)
			(xy 448.580245 -57.186005) (xy 448.550779 -57.231855) (xy 448.515088 -57.273046) (xy 448.473897 -57.308737)
			(xy 448.428047 -57.338203) (xy 448.37847 -57.360845) (xy 448.326175 -57.3762) (xy 448.272227 -57.383956)
			(xy 448.217725 -57.383956) (xy 448.163777 -57.3762) (xy 448.111482 -57.360845) (xy 448.061905 -57.338203)
			(xy 448.016055 -57.308737) (xy 447.974864 -57.273046) (xy 447.939173 -57.231855) (xy 447.909707 -57.186005)
			(xy 447.887065 -57.136428) (xy 447.87171 -57.084133) (xy 447.863954 -57.030185) (xy 447.863468 -57.002934)
			(xy 440.539971 -57.002934) (xy 440.518625 -57.040503) (xy 440.50077 -57.063894) (xy 440.495436 -57.070498)
			(xy 440.492134 -57.079642) (xy 440.49061 -57.085484) (xy 440.489594 -57.09539) (xy 440.489594 -57.128156)
			(xy 440.478418 -57.128156) (xy 440.478418 -57.178956) (xy 440.478752 -57.18756) (xy 440.484463 -57.203792)
			(xy 440.489594 -57.210706) (xy 440.490864 -57.21223) (xy 440.508257 -57.233107) (xy 440.537574 -57.278857)
			(xy 440.560101 -57.328305) (xy 440.575382 -57.38045) (xy 440.583108 -57.434235) (xy 440.583574 -57.461404)
			(xy 440.582998 -57.491232) (xy 440.573716 -57.550161) (xy 440.555379 -57.606928) (xy 440.528433 -57.660151)
			(xy 440.511438 -57.68467) (xy 440.50585 -57.69229) (xy 440.503564 -57.70118) (xy 440.502414 -57.705721)
			(xy 440.501638 -57.715055) (xy 440.50204 -57.719722) (xy 440.518296 -57.87517) (xy 440.51922 -57.880002)
			(xy 440.522667 -57.889214) (xy 440.525154 -57.893458) (xy 440.525408 -57.893966) (xy 440.539199 -57.916819)
			(xy 440.560951 -57.965561) (xy 440.575688 -58.016861) (xy 440.583122 -58.069716) (xy 440.583574 -58.096404)
			(xy 440.582842 -58.129944) (xy 440.571082 -58.195986) (xy 440.560206 -58.227722) (xy 440.556142 -58.238898)
			(xy 440.566048 -58.33491) (xy 440.570112 -58.383678) (xy 440.571636 -58.438034) (xy 440.571636 -58.636154)
			(xy 440.57189 -58.637678) (xy 440.57316 -58.64225) (xy 440.578072 -58.664209) (xy 440.57984 -58.679334)
			(xy 448.295268 -58.679334) (xy 448.295702 -58.653019) (xy 448.302945 -58.600889) (xy 448.317271 -58.550246)
			(xy 448.33841 -58.502048) (xy 448.365962 -58.457205) (xy 448.399405 -58.416566) (xy 448.418458 -58.39841)
			(xy 448.425851 -58.390881) (xy 448.434382 -58.371607) (xy 448.434968 -58.361072) (xy 448.434968 -58.286396)
			(xy 448.434464 -58.275843) (xy 448.425912 -58.256548) (xy 448.418458 -58.249058) (xy 448.399381 -58.230924)
			(xy 448.365927 -58.190289) (xy 448.338372 -58.145444) (xy 448.317238 -58.097239) (xy 448.302925 -58.046588)
			(xy 448.295704 -57.994451) (xy 448.295268 -57.968134) (xy 448.295754 -57.940883) (xy 448.30351 -57.886935)
			(xy 448.318865 -57.83464) (xy 448.341507 -57.785063) (xy 448.370973 -57.739213) (xy 448.406664 -57.698022)
			(xy 448.447855 -57.662331) (xy 448.493705 -57.632865) (xy 448.543282 -57.610223) (xy 448.595577 -57.594868)
			(xy 448.649525 -57.587112) (xy 448.704027 -57.587112) (xy 448.757975 -57.594868) (xy 448.81027 -57.610223)
			(xy 448.859847 -57.632865) (xy 448.905697 -57.662331) (xy 448.946888 -57.698022) (xy 448.982579 -57.739213)
			(xy 449.012045 -57.785063) (xy 449.034687 -57.83464) (xy 449.050042 -57.886935) (xy 449.057798 -57.940883)
			(xy 449.058284 -57.968134) (xy 449.057844 -57.994449) (xy 449.050605 -58.046579) (xy 449.043337 -58.072274)
			(xy 452.29348 -58.072274) (xy 452.297551 -58.016652) (xy 452.309677 -57.962215) (xy 452.3296 -57.910124)
			(xy 452.356896 -57.861489) (xy 452.390982 -57.817346) (xy 452.431131 -57.778637) (xy 452.476489 -57.746186)
			(xy 452.526089 -57.720685) (xy 452.578873 -57.702678) (xy 452.633716 -57.692548) (xy 452.68945 -57.690511)
			(xy 452.744887 -57.696611) (xy 452.798844 -57.710717) (xy 452.850173 -57.732529) (xy 452.897779 -57.761583)
			(xy 452.940647 -57.797258) (xy 452.977864 -57.838795) (xy 453.008637 -57.885308) (xy 453.032309 -57.935805)
			(xy 453.048377 -57.989212) (xy 453.056497 -58.044388) (xy 453.057006 -58.072274) (xy 453.056497 -58.10016)
			(xy 453.048377 -58.155336) (xy 453.032309 -58.208743) (xy 453.008637 -58.25924) (xy 452.977864 -58.305753)
			(xy 452.940647 -58.34729) (xy 452.897779 -58.382965) (xy 452.850173 -58.412019) (xy 452.798844 -58.433831)
			(xy 452.744887 -58.447937) (xy 452.68945 -58.454037) (xy 452.633716 -58.452) (xy 452.578873 -58.44187)
			(xy 452.526089 -58.423863) (xy 452.476489 -58.398362) (xy 452.431131 -58.365911) (xy 452.390982 -58.327202)
			(xy 452.356896 -58.283059) (xy 452.3296 -58.234424) (xy 452.309677 -58.182333) (xy 452.297551 -58.127896)
			(xy 452.29348 -58.072274) (xy 449.043337 -58.072274) (xy 449.03628 -58.097222) (xy 449.015143 -58.145421)
			(xy 448.987592 -58.190264) (xy 448.954148 -58.230902) (xy 448.935094 -58.249058) (xy 448.927708 -58.256593)
			(xy 448.919175 -58.275863) (xy 448.918584 -58.286396) (xy 448.918584 -58.361072) (xy 448.91912 -58.371621)
			(xy 448.927651 -58.390916) (xy 448.935094 -58.39841) (xy 448.954146 -58.416569) (xy 448.987604 -58.457198)
			(xy 449.015164 -58.502037) (xy 449.036303 -58.550237) (xy 449.05062 -58.600884) (xy 449.057845 -58.653018)
			(xy 449.058284 -58.679334) (xy 449.057798 -58.706585) (xy 449.050042 -58.760533) (xy 449.034687 -58.812828)
			(xy 449.012045 -58.862405) (xy 448.982579 -58.908255) (xy 448.946888 -58.949446) (xy 448.905697 -58.985137)
			(xy 448.859847 -59.014603) (xy 448.81027 -59.037245) (xy 448.757975 -59.0526) (xy 448.704027 -59.060356)
			(xy 448.649525 -59.060356) (xy 448.595577 -59.0526) (xy 448.543282 -59.037245) (xy 448.493705 -59.014603)
			(xy 448.447855 -58.985137) (xy 448.406664 -58.949446) (xy 448.370973 -58.908255) (xy 448.341507 -58.862405)
			(xy 448.318865 -58.812828) (xy 448.30351 -58.760533) (xy 448.295754 -58.706585) (xy 448.295268 -58.679334)
			(xy 440.57984 -58.679334) (xy 440.583296 -58.708904) (xy 440.583574 -58.731404) (xy 440.583274 -58.753903)
			(xy 440.578053 -58.798596) (xy 440.57316 -58.820558) (xy 440.57189 -58.82513) (xy 440.571636 -58.826654)
			(xy 440.571636 -60.019254) (xy 448.435661 -60.019254) (xy 448.435661 -59.964746) (xy 448.443419 -59.910794)
			(xy 448.458776 -59.858494) (xy 448.481421 -59.808913) (xy 448.510891 -59.763059) (xy 448.546587 -59.721866)
			(xy 448.587783 -59.686173) (xy 448.633639 -59.656706) (xy 448.683222 -59.634066) (xy 448.735523 -59.618713)
			(xy 448.789476 -59.610959) (xy 448.81673 -59.610498) (xy 448.844101 -59.610947) (xy 448.898281 -59.618769)
			(xy 448.950784 -59.634262) (xy 449.00053 -59.657108) (xy 449.046497 -59.686835) (xy 449.067428 -59.704478)
			(xy 449.067682 -59.704732) (xy 449.074767 -59.710321) (xy 449.091685 -59.716565) (xy 449.100702 -59.716924)
			(xy 449.167758 -59.716924) (xy 449.176772 -59.716542) (xy 449.193689 -59.710311) (xy 449.200778 -59.704732)
			(xy 449.200778 -59.704478) (xy 449.201032 -59.704478) (xy 449.221965 -59.686837) (xy 449.267933 -59.657113)
			(xy 449.317679 -59.634267) (xy 449.370181 -59.618771) (xy 449.424359 -59.610942) (xy 449.479101 -59.610942)
			(xy 449.533279 -59.618771) (xy 449.585781 -59.634267) (xy 449.635527 -59.657113) (xy 449.681495 -59.686837)
			(xy 449.702428 -59.704478) (xy 449.702682 -59.704732) (xy 449.709767 -59.710321) (xy 449.726685 -59.716565)
			(xy 449.735702 -59.716924) (xy 449.802758 -59.716924) (xy 449.811772 -59.716542) (xy 449.828689 -59.710311)
			(xy 449.835778 -59.704732) (xy 449.835778 -59.704478) (xy 449.836032 -59.704478) (xy 449.856976 -59.686854)
			(xy 449.902946 -59.657141) (xy 449.95269 -59.634302) (xy 450.005188 -59.618807) (xy 450.059362 -59.610975)
			(xy 450.08673 -59.610498) (xy 450.11398 -59.610974) (xy 450.167926 -59.618734) (xy 450.220218 -59.634092)
			(xy 450.269792 -59.656735) (xy 450.315639 -59.686203) (xy 450.356826 -59.721895) (xy 450.392515 -59.763085)
			(xy 450.421979 -59.808935) (xy 450.444619 -59.858511) (xy 450.459972 -59.910804) (xy 450.467728 -59.96475)
			(xy 450.467728 -60.01925) (xy 450.459972 -60.073196) (xy 450.444619 -60.125489) (xy 450.421979 -60.175065)
			(xy 450.392515 -60.220915) (xy 450.356826 -60.262105) (xy 450.315639 -60.297797) (xy 450.269792 -60.327265)
			(xy 450.220218 -60.349908) (xy 450.167926 -60.365266) (xy 450.11398 -60.373026) (xy 450.08673 -60.373514)
			(xy 450.059361 -60.373027) (xy 450.005183 -60.365214) (xy 449.95268 -60.349729) (xy 449.902933 -60.326892)
			(xy 449.856965 -60.297173) (xy 449.836032 -60.279534) (xy 449.835778 -60.27928) (xy 449.828704 -60.273676)
			(xy 449.811777 -60.26744) (xy 449.802758 -60.267088) (xy 449.735702 -60.267088) (xy 449.726686 -60.267449)
			(xy 449.709769 -60.273694) (xy 449.702682 -60.27928) (xy 449.702428 -60.279534) (xy 449.681495 -60.297175)
			(xy 449.635527 -60.326899) (xy 449.585781 -60.349745) (xy 449.533279 -60.365241) (xy 449.479101 -60.37307)
			(xy 449.424359 -60.37307) (xy 449.370181 -60.365241) (xy 449.317679 -60.349745) (xy 449.267933 -60.326899)
			(xy 449.221965 -60.297175) (xy 449.201032 -60.279534) (xy 449.200778 -60.27928) (xy 449.193704 -60.273676)
			(xy 449.176777 -60.26744) (xy 449.167758 -60.267088) (xy 449.100702 -60.267088) (xy 449.091686 -60.267449)
			(xy 449.074769 -60.273694) (xy 449.067682 -60.27928) (xy 449.067682 -60.279534) (xy 449.067428 -60.279534)
			(xy 449.046501 -60.297179) (xy 449.000526 -60.326889) (xy 448.950777 -60.349723) (xy 448.898276 -60.365213)
			(xy 448.844099 -60.37304) (xy 448.81673 -60.373514) (xy 448.789476 -60.373041) (xy 448.735523 -60.365287)
			(xy 448.683222 -60.349934) (xy 448.633639 -60.327294) (xy 448.587783 -60.297827) (xy 448.546587 -60.262134)
			(xy 448.510891 -60.220941) (xy 448.481421 -60.175087) (xy 448.458776 -60.125506) (xy 448.443419 -60.073206)
			(xy 448.435661 -60.019254) (xy 440.571636 -60.019254) (xy 440.571636 -60.59424) (xy 440.571147 -60.637887)
			(xy 440.563477 -60.724844) (xy 440.548241 -60.810798) (xy 440.537346 -60.853066) (xy 439.902712 -63.213554)
			(xy 448.420665 -63.213554) (xy 448.420665 -63.159046) (xy 448.428423 -63.105092) (xy 448.443781 -63.052793)
			(xy 448.466426 -63.003211) (xy 448.495898 -62.957357) (xy 448.531595 -62.916164) (xy 448.572792 -62.880471)
			(xy 448.618649 -62.851005) (xy 448.668234 -62.828366) (xy 448.720536 -62.813014) (xy 448.77449 -62.805262)
			(xy 448.801744 -62.804802) (xy 448.829113 -62.8053) (xy 448.883291 -62.81311) (xy 448.935794 -62.828592)
			(xy 448.985541 -62.851426) (xy 449.031509 -62.881144) (xy 449.052442 -62.898782) (xy 449.052696 -62.899036)
			(xy 449.059777 -62.904631) (xy 449.076698 -62.910872) (xy 449.085716 -62.911228) (xy 449.152772 -62.911228)
			(xy 449.161787 -62.910851) (xy 449.178704 -62.904617) (xy 449.185792 -62.899036) (xy 449.185792 -62.898782)
			(xy 449.186046 -62.898782) (xy 449.206979 -62.881141) (xy 449.252947 -62.851417) (xy 449.302693 -62.828571)
			(xy 449.355195 -62.813075) (xy 449.409373 -62.805246) (xy 449.464115 -62.805246) (xy 449.518293 -62.813075)
			(xy 449.570795 -62.828571) (xy 449.620541 -62.851417) (xy 449.666509 -62.881141) (xy 449.687442 -62.898782)
			(xy 449.687696 -62.899036) (xy 449.694777 -62.904631) (xy 449.711698 -62.910872) (xy 449.720716 -62.911228)
			(xy 449.787772 -62.911228) (xy 449.796787 -62.910851) (xy 449.813704 -62.904617) (xy 449.820792 -62.899036)
			(xy 449.820792 -62.898782) (xy 449.821046 -62.898782) (xy 449.841985 -62.881152) (xy 449.887956 -62.851439)
			(xy 449.937702 -62.828602) (xy 449.990201 -62.813109) (xy 450.044375 -62.805278) (xy 450.071744 -62.804802)
			(xy 450.098994 -62.805271) (xy 450.152938 -62.813033) (xy 450.205229 -62.828392) (xy 450.254802 -62.851036)
			(xy 450.300648 -62.880504) (xy 450.341834 -62.916197) (xy 450.377522 -62.957387) (xy 450.406985 -63.003237)
			(xy 450.429623 -63.052812) (xy 450.444977 -63.105105) (xy 450.452732 -63.15905) (xy 450.452732 -63.21355)
			(xy 450.444977 -63.267495) (xy 450.429623 -63.319788) (xy 450.406985 -63.369363) (xy 450.377522 -63.415213)
			(xy 450.341834 -63.456403) (xy 450.300648 -63.492096) (xy 450.254802 -63.521564) (xy 450.205229 -63.544208)
			(xy 450.152938 -63.559567) (xy 450.098994 -63.567329) (xy 450.071744 -63.567818) (xy 450.044374 -63.567346)
			(xy 449.990194 -63.559533) (xy 449.93769 -63.544046) (xy 449.887943 -63.521205) (xy 449.841977 -63.49148)
			(xy 449.821046 -63.473838) (xy 449.820792 -63.473584) (xy 449.813713 -63.467986) (xy 449.79679 -63.461747)
			(xy 449.787772 -63.461392) (xy 449.720716 -63.461392) (xy 449.7117 -63.461758) (xy 449.694783 -63.468)
			(xy 449.687696 -63.473584) (xy 449.687442 -63.473838) (xy 449.666509 -63.491479) (xy 449.620541 -63.521203)
			(xy 449.570795 -63.544049) (xy 449.518293 -63.559545) (xy 449.464115 -63.567374) (xy 449.409373 -63.567374)
			(xy 449.355195 -63.559545) (xy 449.302693 -63.544049) (xy 449.252947 -63.521203) (xy 449.206979 -63.491479)
			(xy 449.186046 -63.473838) (xy 449.185792 -63.473584) (xy 449.178713 -63.467986) (xy 449.16179 -63.461747)
			(xy 449.152772 -63.461392) (xy 449.085716 -63.461392) (xy 449.0767 -63.461758) (xy 449.059783 -63.468)
			(xy 449.052696 -63.473584) (xy 449.052696 -63.473838) (xy 449.052442 -63.473838) (xy 449.03151 -63.491477)
			(xy 448.985537 -63.521188) (xy 448.935789 -63.544023) (xy 448.883289 -63.559515) (xy 448.829113 -63.567344)
			(xy 448.801744 -63.567818) (xy 448.77449 -63.567338) (xy 448.720536 -63.559586) (xy 448.668234 -63.544234)
			(xy 448.618649 -63.521595) (xy 448.572792 -63.492129) (xy 448.531595 -63.456436) (xy 448.495898 -63.415243)
			(xy 448.466426 -63.369389) (xy 448.443781 -63.319807) (xy 448.428423 -63.267508) (xy 448.420665 -63.213554)
			(xy 439.902712 -63.213554) (xy 439.890916 -63.25743) (xy 439.877544 -63.304892) (xy 439.842685 -63.397139)
			(xy 439.82132 -63.44158) (xy 438.998561 -65.100962) (xy 446.43243 -65.100962) (xy 446.436501 -65.04534)
			(xy 446.448627 -64.990903) (xy 446.46855 -64.938812) (xy 446.495846 -64.890177) (xy 446.529932 -64.846034)
			(xy 446.570081 -64.807325) (xy 446.615439 -64.774874) (xy 446.665039 -64.749373) (xy 446.717823 -64.731366)
			(xy 446.772666 -64.721236) (xy 446.8284 -64.719199) (xy 446.883837 -64.725299) (xy 446.937794 -64.739405)
			(xy 446.989123 -64.761217) (xy 447.036729 -64.790271) (xy 447.079597 -64.825946) (xy 447.116814 -64.867483)
			(xy 447.147587 -64.913996) (xy 447.171259 -64.964493) (xy 447.187327 -65.0179) (xy 447.195447 -65.073076)
			(xy 447.195956 -65.100962) (xy 447.195447 -65.128848) (xy 447.187327 -65.184024) (xy 447.171259 -65.237431)
			(xy 447.147587 -65.287928) (xy 447.116814 -65.334441) (xy 447.079597 -65.375978) (xy 447.036729 -65.411653)
			(xy 446.989123 -65.440707) (xy 446.937794 -65.462519) (xy 446.883837 -65.476625) (xy 446.8284 -65.482725)
			(xy 446.772666 -65.480688) (xy 446.717823 -65.470558) (xy 446.665039 -65.452551) (xy 446.615439 -65.42705)
			(xy 446.570081 -65.394599) (xy 446.529932 -65.35589) (xy 446.495846 -65.311747) (xy 446.46855 -65.263112)
			(xy 446.448627 -65.211021) (xy 446.436501 -65.156584) (xy 446.43243 -65.100962) (xy 438.998561 -65.100962)
			(xy 438.826402 -65.44818) (xy 438.8045 -65.491087) (xy 438.753607 -65.572888) (xy 438.724802 -65.611502)
			(xy 438.614552 -65.75552) (xy 440.646564 -65.75552) (xy 440.650635 -65.699898) (xy 440.662761 -65.645461)
			(xy 440.682684 -65.59337) (xy 440.70998 -65.544735) (xy 440.744066 -65.500592) (xy 440.784215 -65.461883)
			(xy 440.829573 -65.429432) (xy 440.879173 -65.403931) (xy 440.931957 -65.385924) (xy 440.9868 -65.375794)
			(xy 441.042534 -65.373757) (xy 441.097971 -65.379857) (xy 441.151928 -65.393963) (xy 441.203257 -65.415775)
			(xy 441.250863 -65.444829) (xy 441.293731 -65.480504) (xy 441.330948 -65.522041) (xy 441.361721 -65.568554)
			(xy 441.385393 -65.619051) (xy 441.401461 -65.672458) (xy 441.409581 -65.727634) (xy 441.41009 -65.75552)
			(xy 441.409581 -65.783406) (xy 441.401461 -65.838582) (xy 441.385393 -65.891989) (xy 441.361721 -65.942486)
			(xy 441.330948 -65.988999) (xy 441.293731 -66.030536) (xy 441.250863 -66.066211) (xy 441.203257 -66.095265)
			(xy 441.151928 -66.117077) (xy 441.097971 -66.131183) (xy 441.042534 -66.137283) (xy 440.9868 -66.135246)
			(xy 440.931957 -66.125116) (xy 440.879173 -66.107109) (xy 440.829573 -66.081608) (xy 440.784215 -66.049157)
			(xy 440.744066 -66.010448) (xy 440.70998 -65.966305) (xy 440.682684 -65.91767) (xy 440.662761 -65.865579)
			(xy 440.650635 -65.811142) (xy 440.646564 -65.75552) (xy 438.614552 -65.75552) (xy 437.563144 -67.128953)
			(xy 440.666575 -67.128953) (xy 440.666575 -67.074447) (xy 440.674333 -67.020496) (xy 440.68969 -66.968199)
			(xy 440.712333 -66.918619) (xy 440.741803 -66.872767) (xy 440.777498 -66.831575) (xy 440.818692 -66.795883)
			(xy 440.864547 -66.766418) (xy 440.914129 -66.743778) (xy 440.966428 -66.728426) (xy 441.020379 -66.720673)
			(xy 441.047632 -66.720212) (xy 441.075003 -66.720656) (xy 441.129183 -66.728479) (xy 441.181687 -66.743973)
			(xy 441.231433 -66.76682) (xy 441.277399 -66.796549) (xy 441.29833 -66.814192) (xy 441.298584 -66.814446)
			(xy 441.305667 -66.820038) (xy 441.322587 -66.82628) (xy 441.331604 -66.826638) (xy 441.39866 -66.826638)
			(xy 441.407674 -66.826254) (xy 441.424591 -66.820024) (xy 441.43168 -66.814446) (xy 441.43168 -66.814192)
			(xy 441.431934 -66.814192) (xy 441.452879 -66.796569) (xy 441.498848 -66.766855) (xy 441.548593 -66.744016)
			(xy 441.60109 -66.728521) (xy 441.655264 -66.720689) (xy 441.682632 -66.720212) (xy 441.709883 -66.72066)
			(xy 441.76383 -66.728421) (xy 441.816124 -66.743779) (xy 441.8657 -66.766423) (xy 441.911549 -66.795892)
			(xy 441.952737 -66.831586) (xy 441.988427 -66.872777) (xy 442.017892 -66.918628) (xy 442.040532 -66.968206)
			(xy 442.055886 -67.020501) (xy 442.063642 -67.074449) (xy 442.063642 -67.128951) (xy 442.055886 -67.182899)
			(xy 442.040532 -67.235194) (xy 442.017892 -67.284772) (xy 441.988427 -67.330623) (xy 441.952737 -67.371814)
			(xy 441.911549 -67.407508) (xy 441.8657 -67.436977) (xy 441.816124 -67.459621) (xy 441.76383 -67.474979)
			(xy 441.709883 -67.48274) (xy 441.682632 -67.483228) (xy 441.655262 -67.482761) (xy 441.601082 -67.474946)
			(xy 441.548578 -67.459458) (xy 441.498831 -67.436616) (xy 441.452865 -67.40689) (xy 441.431934 -67.389248)
			(xy 441.43168 -67.388994) (xy 441.424604 -67.383392) (xy 441.407679 -67.377155) (xy 441.39866 -67.376802)
			(xy 441.331604 -67.376802) (xy 441.322587 -67.37716) (xy 441.30567 -67.383407) (xy 441.298584 -67.388994)
			(xy 441.298584 -67.389248) (xy 441.29833 -67.389248) (xy 441.277391 -67.406878) (xy 441.231421 -67.436593)
			(xy 441.181675 -67.459432) (xy 441.129176 -67.474925) (xy 441.075001 -67.482754) (xy 441.047632 -67.483228)
			(xy 441.020379 -67.482727) (xy 440.966428 -67.474974) (xy 440.914129 -67.459622) (xy 440.864547 -67.436982)
			(xy 440.818692 -67.407516) (xy 440.777498 -67.371825) (xy 440.741803 -67.330633) (xy 440.712333 -67.284781)
			(xy 440.68969 -67.235201) (xy 440.674333 -67.182904) (xy 440.666575 -67.128953) (xy 437.563144 -67.128953)
			(xy 437.288241 -67.488054) (xy 445.079118 -67.488054) (xy 445.083189 -67.432432) (xy 445.095315 -67.377995)
			(xy 445.115238 -67.325904) (xy 445.142534 -67.277269) (xy 445.17662 -67.233126) (xy 445.216769 -67.194417)
			(xy 445.262127 -67.161966) (xy 445.311727 -67.136465) (xy 445.364511 -67.118458) (xy 445.419354 -67.108328)
			(xy 445.475088 -67.106291) (xy 445.530525 -67.112391) (xy 445.584482 -67.126497) (xy 445.635811 -67.148309)
			(xy 445.683417 -67.177363) (xy 445.726285 -67.213038) (xy 445.763502 -67.254575) (xy 445.794275 -67.301088)
			(xy 445.817947 -67.351585) (xy 445.834015 -67.404992) (xy 445.842135 -67.460168) (xy 445.842644 -67.488054)
			(xy 445.842135 -67.51594) (xy 445.83895 -67.537584) (xy 446.371216 -67.537584) (xy 446.375287 -67.481962)
			(xy 446.387413 -67.427525) (xy 446.407336 -67.375434) (xy 446.434632 -67.326799) (xy 446.468718 -67.282656)
			(xy 446.508867 -67.243947) (xy 446.554225 -67.211496) (xy 446.603825 -67.185995) (xy 446.656609 -67.167988)
			(xy 446.711452 -67.157858) (xy 446.767186 -67.155821) (xy 446.822623 -67.161921) (xy 446.87658 -67.176027)
			(xy 446.927909 -67.197839) (xy 446.975515 -67.226893) (xy 447.018383 -67.262568) (xy 447.0556 -67.304105)
			(xy 447.086373 -67.350618) (xy 447.110045 -67.401115) (xy 447.126113 -67.454522) (xy 447.134233 -67.509698)
			(xy 447.134742 -67.537584) (xy 447.134233 -67.56547) (xy 447.130188 -67.592956) (xy 447.64528 -67.592956)
			(xy 447.649351 -67.537334) (xy 447.661477 -67.482897) (xy 447.6814 -67.430806) (xy 447.708696 -67.382171)
			(xy 447.742782 -67.338028) (xy 447.782931 -67.299319) (xy 447.828289 -67.266868) (xy 447.877889 -67.241367)
			(xy 447.930673 -67.22336) (xy 447.985516 -67.21323) (xy 448.04125 -67.211193) (xy 448.096687 -67.217293)
			(xy 448.150644 -67.231399) (xy 448.201973 -67.253211) (xy 448.249579 -67.282265) (xy 448.292447 -67.31794)
			(xy 448.329664 -67.359477) (xy 448.360437 -67.40599) (xy 448.384109 -67.456487) (xy 448.400177 -67.509894)
			(xy 448.408297 -67.56507) (xy 448.408806 -67.592956) (xy 448.408297 -67.620842) (xy 448.400177 -67.676018)
			(xy 448.384109 -67.729425) (xy 448.360437 -67.779922) (xy 448.329664 -67.826435) (xy 448.292447 -67.867972)
			(xy 448.249579 -67.903647) (xy 448.201973 -67.932701) (xy 448.150644 -67.954513) (xy 448.096687 -67.968619)
			(xy 448.04125 -67.974719) (xy 447.985516 -67.972682) (xy 447.930673 -67.962552) (xy 447.877889 -67.944545)
			(xy 447.828289 -67.919044) (xy 447.782931 -67.886593) (xy 447.742782 -67.847884) (xy 447.708696 -67.803741)
			(xy 447.6814 -67.755106) (xy 447.661477 -67.703015) (xy 447.649351 -67.648578) (xy 447.64528 -67.592956)
			(xy 447.130188 -67.592956) (xy 447.126113 -67.620646) (xy 447.110045 -67.674053) (xy 447.086373 -67.72455)
			(xy 447.0556 -67.771063) (xy 447.018383 -67.8126) (xy 446.975515 -67.848275) (xy 446.927909 -67.877329)
			(xy 446.87658 -67.899141) (xy 446.822623 -67.913247) (xy 446.767186 -67.919347) (xy 446.711452 -67.91731)
			(xy 446.656609 -67.90718) (xy 446.603825 -67.889173) (xy 446.554225 -67.863672) (xy 446.508867 -67.831221)
			(xy 446.468718 -67.792512) (xy 446.434632 -67.748369) (xy 446.407336 -67.699734) (xy 446.387413 -67.647643)
			(xy 446.375287 -67.593206) (xy 446.371216 -67.537584) (xy 445.83895 -67.537584) (xy 445.834015 -67.571116)
			(xy 445.817947 -67.624523) (xy 445.794275 -67.67502) (xy 445.763502 -67.721533) (xy 445.726285 -67.76307)
			(xy 445.683417 -67.798745) (xy 445.635811 -67.827799) (xy 445.584482 -67.849611) (xy 445.530525 -67.863717)
			(xy 445.475088 -67.869817) (xy 445.419354 -67.86778) (xy 445.364511 -67.85765) (xy 445.311727 -67.839643)
			(xy 445.262127 -67.814142) (xy 445.216769 -67.781691) (xy 445.17662 -67.742982) (xy 445.142534 -67.698839)
			(xy 445.115238 -67.650204) (xy 445.095315 -67.598113) (xy 445.083189 -67.543676) (xy 445.079118 -67.488054)
			(xy 437.288241 -67.488054) (xy 436.447265 -68.586604) (xy 442.9252 -68.586604) (xy 442.925668 -68.559234)
			(xy 442.933486 -68.505055) (xy 442.948974 -68.452552) (xy 442.971815 -68.402805) (xy 443.001539 -68.356838)
			(xy 443.01918 -68.335906) (xy 443.019434 -68.335652) (xy 443.025009 -68.328557) (xy 443.031261 -68.311647)
			(xy 443.031626 -68.302632) (xy 443.031626 -68.235576) (xy 443.031275 -68.226559) (xy 443.025023 -68.209642)
			(xy 443.019434 -68.202556) (xy 443.01918 -68.202556) (xy 443.01918 -68.202302) (xy 443.001525 -68.181383)
			(xy 442.971816 -68.135406) (xy 442.948984 -68.085655) (xy 442.933496 -68.033152) (xy 442.925672 -67.978974)
			(xy 442.9252 -67.951604) (xy 442.925659 -67.924351) (xy 442.933416 -67.870399) (xy 442.948772 -67.818101)
			(xy 442.971414 -67.76852) (xy 443.000883 -67.722667) (xy 443.036577 -67.681474) (xy 443.07777 -67.64578)
			(xy 443.123624 -67.616312) (xy 443.173205 -67.59367) (xy 443.225503 -67.578315) (xy 443.279455 -67.570559)
			(xy 443.306708 -67.570096) (xy 443.333022 -67.570559) (xy 443.385151 -67.577795) (xy 443.435793 -67.592115)
			(xy 443.483992 -67.613248) (xy 443.528836 -67.640795) (xy 443.569475 -67.674234) (xy 443.587632 -67.693286)
			(xy 443.595142 -67.700702) (xy 443.614431 -67.709218) (xy 443.62497 -67.709796) (xy 443.699646 -67.709796)
			(xy 443.710194 -67.709253) (xy 443.72949 -67.700728) (xy 443.736984 -67.693286) (xy 443.755152 -67.674243)
			(xy 443.795779 -67.640785) (xy 443.840617 -67.613225) (xy 443.888815 -67.592084) (xy 443.93946 -67.577764)
			(xy 443.991593 -67.570536) (xy 444.017908 -67.570096) (xy 444.045278 -67.570558) (xy 444.099458 -67.578377)
			(xy 444.151961 -67.593867) (xy 444.201707 -67.61671) (xy 444.247674 -67.646435) (xy 444.268606 -67.664076)
			(xy 444.26886 -67.66433) (xy 444.275951 -67.669909) (xy 444.292865 -67.676159) (xy 444.30188 -67.676522)
			(xy 444.368936 -67.676522) (xy 444.377954 -67.676178) (xy 444.394871 -67.669921) (xy 444.401956 -67.66433)
			(xy 444.401956 -67.664076) (xy 444.40221 -67.664076) (xy 444.423124 -67.646415) (xy 444.469102 -67.616707)
			(xy 444.518854 -67.593876) (xy 444.571359 -67.57839) (xy 444.625538 -67.570567) (xy 444.652908 -67.570096)
			(xy 444.68016 -67.57057) (xy 444.734108 -67.578328) (xy 444.786403 -67.593684) (xy 444.835981 -67.616327)
			(xy 444.881831 -67.645794) (xy 444.923022 -67.681487) (xy 444.958713 -67.722678) (xy 444.988179 -67.76853)
			(xy 445.01082 -67.818108) (xy 445.026174 -67.870404) (xy 445.03393 -67.924352) (xy 445.034416 -67.951604)
			(xy 445.033973 -67.978975) (xy 445.026153 -68.033156) (xy 445.010659 -68.08566) (xy 444.987812 -68.135407)
			(xy 444.958081 -68.181372) (xy 444.940436 -68.202302) (xy 444.940182 -68.202556) (xy 444.934606 -68.20965)
			(xy 444.928353 -68.226561) (xy 444.92799 -68.235576) (xy 444.92799 -68.302632) (xy 444.928334 -68.31165)
			(xy 444.934591 -68.328567) (xy 444.940182 -68.335652) (xy 444.940436 -68.335652) (xy 444.940436 -68.335906)
			(xy 444.958097 -68.35682) (xy 444.987804 -68.402799) (xy 445.010635 -68.452551) (xy 445.026121 -68.505055)
			(xy 445.033945 -68.559234) (xy 445.034416 -68.586604) (xy 445.033926 -68.613855) (xy 445.026169 -68.667802)
			(xy 445.010814 -68.720096) (xy 444.988173 -68.769673) (xy 444.958707 -68.815523) (xy 444.923016 -68.856713)
			(xy 444.881826 -68.892404) (xy 444.835977 -68.921871) (xy 444.7864 -68.944512) (xy 444.734106 -68.959868)
			(xy 444.680159 -68.967626) (xy 444.652908 -68.968112) (xy 444.625538 -68.967638) (xy 444.571359 -68.959822)
			(xy 444.518857 -68.944334) (xy 444.46911 -68.921494) (xy 444.423142 -68.891772) (xy 444.40221 -68.874132)
			(xy 444.401956 -68.873878) (xy 444.394859 -68.868306) (xy 444.37795 -68.862051) (xy 444.368936 -68.861686)
			(xy 444.30188 -68.861686) (xy 444.292863 -68.862037) (xy 444.275946 -68.868289) (xy 444.26886 -68.873878)
			(xy 444.26886 -68.874132) (xy 444.268606 -68.874132) (xy 444.247687 -68.891787) (xy 444.20171 -68.921495)
			(xy 444.151959 -68.944328) (xy 444.099456 -68.959815) (xy 444.045278 -68.96764) (xy 444.017908 -68.968112)
			(xy 443.991594 -68.967635) (xy 443.939466 -68.960402) (xy 443.888824 -68.946084) (xy 443.840625 -68.924954)
			(xy 443.795781 -68.897409) (xy 443.755141 -68.863973) (xy 443.736984 -68.844922) (xy 443.729467 -68.837515)
			(xy 443.710184 -68.828993) (xy 443.699646 -68.828412) (xy 443.62497 -68.828412) (xy 443.614423 -68.828962)
			(xy 443.595127 -68.837482) (xy 443.587632 -68.844922) (xy 443.569507 -68.864008) (xy 443.52887 -68.897461)
			(xy 443.484023 -68.925016) (xy 443.435817 -68.946149) (xy 443.385164 -68.96046) (xy 443.333026 -68.967677)
			(xy 443.306708 -68.968112) (xy 443.279456 -68.967637) (xy 443.225505 -68.959881) (xy 443.173208 -68.944527)
			(xy 443.123628 -68.921885) (xy 443.077775 -68.892419) (xy 443.036582 -68.856726) (xy 443.000889 -68.815535)
			(xy 442.97142 -68.769683) (xy 442.948778 -68.720103) (xy 442.933421 -68.667807) (xy 442.925664 -68.613856)
			(xy 442.9252 -68.586604) (xy 436.447265 -68.586604) (xy 434.1742 -71.555864) (xy 445.494408 -71.555864)
			(xy 445.498479 -71.500242) (xy 445.510605 -71.445805) (xy 445.530528 -71.393714) (xy 445.557824 -71.345079)
			(xy 445.59191 -71.300936) (xy 445.632059 -71.262227) (xy 445.677417 -71.229776) (xy 445.727017 -71.204275)
			(xy 445.779801 -71.186268) (xy 445.834644 -71.176138) (xy 445.890378 -71.174101) (xy 445.945815 -71.180201)
			(xy 445.999772 -71.194307) (xy 446.051101 -71.216119) (xy 446.098707 -71.245173) (xy 446.141575 -71.280848)
			(xy 446.178792 -71.322385) (xy 446.209565 -71.368898) (xy 446.233237 -71.419395) (xy 446.249305 -71.472802)
			(xy 446.257425 -71.527978) (xy 446.257934 -71.555864) (xy 446.257425 -71.58375) (xy 446.251586 -71.623428)
			(xy 447.003422 -71.623428) (xy 447.007493 -71.567806) (xy 447.019619 -71.513369) (xy 447.039542 -71.461278)
			(xy 447.066838 -71.412643) (xy 447.100924 -71.3685) (xy 447.141073 -71.329791) (xy 447.186431 -71.29734)
			(xy 447.236031 -71.271839) (xy 447.288815 -71.253832) (xy 447.343658 -71.243702) (xy 447.399392 -71.241665)
			(xy 447.454829 -71.247765) (xy 447.508786 -71.261871) (xy 447.560115 -71.283683) (xy 447.607721 -71.312737)
			(xy 447.650589 -71.348412) (xy 447.687806 -71.389949) (xy 447.718579 -71.436462) (xy 447.742251 -71.486959)
			(xy 447.758319 -71.540366) (xy 447.766439 -71.595542) (xy 447.766948 -71.623428) (xy 447.766439 -71.651314)
			(xy 447.758319 -71.70649) (xy 447.742251 -71.759897) (xy 447.718579 -71.810394) (xy 447.687806 -71.856907)
			(xy 447.650589 -71.898444) (xy 447.607721 -71.934119) (xy 447.560115 -71.963173) (xy 447.508786 -71.984985)
			(xy 447.454829 -71.999091) (xy 447.399392 -72.005191) (xy 447.343658 -72.003154) (xy 447.288815 -71.993024)
			(xy 447.236031 -71.975017) (xy 447.186431 -71.949516) (xy 447.141073 -71.917065) (xy 447.100924 -71.878356)
			(xy 447.066838 -71.834213) (xy 447.039542 -71.785578) (xy 447.019619 -71.733487) (xy 447.007493 -71.67905)
			(xy 447.003422 -71.623428) (xy 446.251586 -71.623428) (xy 446.249305 -71.638926) (xy 446.233237 -71.692333)
			(xy 446.209565 -71.74283) (xy 446.178792 -71.789343) (xy 446.141575 -71.83088) (xy 446.098707 -71.866555)
			(xy 446.051101 -71.895609) (xy 445.999772 -71.917421) (xy 445.945815 -71.931527) (xy 445.890378 -71.937627)
			(xy 445.834644 -71.93559) (xy 445.779801 -71.92546) (xy 445.727017 -71.907453) (xy 445.677417 -71.881952)
			(xy 445.632059 -71.849501) (xy 445.59191 -71.810792) (xy 445.557824 -71.766649) (xy 445.530528 -71.718014)
			(xy 445.510605 -71.665923) (xy 445.498479 -71.611486) (xy 445.494408 -71.555864) (xy 434.1742 -71.555864)
			(xy 433.107084 -72.949816) (xy 433.102981 -72.95627) (xy 433.098465 -72.970874) (xy 433.098194 -72.978518)
			(xy 433.098194 -72.978772) (xy 433.097726 -73.006543) (xy 433.08974 -73.061507) (xy 433.073874 -73.114734)
			(xy 433.050463 -73.165101) (xy 433.020001 -73.211543) (xy 432.983131 -73.253082) (xy 432.940632 -73.28884)
			(xy 432.8934 -73.318063) (xy 432.842432 -73.340133) (xy 432.815746 -73.347834) (xy 432.812952 -73.348596)
			(xy 432.806732 -73.350918) (xy 432.795672 -73.358253) (xy 432.791108 -73.363074) (xy 432.552856 -73.67397)
			(xy 432.550316 -73.684384) (xy 432.543622 -73.709668) (xy 432.524248 -73.758252) (xy 432.498415 -73.80373)
			(xy 432.466608 -73.845251) (xy 432.429423 -73.882034) (xy 432.387559 -73.913388) (xy 432.364896 -73.926446)
			(xy 432.355498 -73.931526) (xy 432.280314 -74.030078) (xy 432.256184 -74.061574) (xy 432.23942 -74.083418)
			(xy 432.234581 -74.090372) (xy 432.229268 -74.106446) (xy 432.229006 -74.114914) (xy 432.230022 -74.12482)
			(xy 432.23053 -74.127106) (xy 432.234143 -74.146075) (xy 432.237956 -74.184504) (xy 432.23815 -74.203814)
			(xy 432.237608 -74.232723) (xy 432.228869 -74.289879) (xy 432.211609 -74.345061) (xy 432.186223 -74.397009)
			(xy 432.153291 -74.444534) (xy 432.113567 -74.486547) (xy 432.06796 -74.522087) (xy 432.017515 -74.550341)
			(xy 431.963384 -74.570662) (xy 431.906808 -74.582586) (xy 431.877978 -74.584814) (xy 431.867432 -74.58593)
			(xy 431.84854 -74.595513) (xy 431.841402 -74.603356) (xy 429.848759 -77.206348) (xy 430.98415 -77.206348)
			(xy 430.988221 -77.150726) (xy 431.000347 -77.096289) (xy 431.02027 -77.044198) (xy 431.047566 -76.995563)
			(xy 431.081652 -76.95142) (xy 431.121801 -76.912711) (xy 431.167159 -76.88026) (xy 431.216759 -76.854759)
			(xy 431.269543 -76.836752) (xy 431.324386 -76.826622) (xy 431.38012 -76.824585) (xy 431.435557 -76.830685)
			(xy 431.489514 -76.844791) (xy 431.540843 -76.866603) (xy 431.588449 -76.895657) (xy 431.631317 -76.931332)
			(xy 431.668534 -76.972869) (xy 431.699307 -77.019382) (xy 431.722979 -77.069879) (xy 431.739047 -77.123286)
			(xy 431.747167 -77.178462) (xy 431.747676 -77.206348) (xy 431.747167 -77.234234) (xy 431.739047 -77.28941)
			(xy 431.722979 -77.342817) (xy 431.699307 -77.393314) (xy 431.668534 -77.439827) (xy 431.631317 -77.481364)
			(xy 431.588449 -77.517039) (xy 431.540843 -77.546093) (xy 431.489514 -77.567905) (xy 431.435557 -77.582011)
			(xy 431.38012 -77.588111) (xy 431.324386 -77.586074) (xy 431.269543 -77.575944) (xy 431.216759 -77.557937)
			(xy 431.167159 -77.532436) (xy 431.121801 -77.499985) (xy 431.081652 -77.461276) (xy 431.047566 -77.417133)
			(xy 431.02027 -77.368498) (xy 431.000347 -77.316407) (xy 430.988221 -77.26197) (xy 430.98415 -77.206348)
			(xy 429.848759 -77.206348) (xy 428.568358 -78.878938) (xy 428.563519 -78.885892) (xy 428.558208 -78.901966)
			(xy 428.557944 -78.910434) (xy 428.557944 -78.918816) (xy 428.563786 -78.934564) (xy 428.569374 -78.941422)
			(xy 428.585437 -78.961916) (xy 428.612451 -79.006429) (xy 428.633167 -79.0542) (xy 428.647202 -79.104342)
			(xy 428.654294 -79.155926) (xy 428.654718 -79.18196) (xy 428.654198 -79.210634) (xy 428.645608 -79.267335)
			(xy 428.62863 -79.322112) (xy 428.603647 -79.373732) (xy 428.571222 -79.421033) (xy 428.532084 -79.462949)
			(xy 428.509938 -79.481172) (xy 428.507398 -79.483204) (xy 428.499016 -79.491586) (xy 428.493959 -79.498656)
			(xy 428.488515 -79.515152) (xy 428.488348 -79.523844) (xy 428.494444 -79.610712) (xy 428.495036 -79.616966)
			(xy 428.49888 -79.62892) (xy 428.502064 -79.634334) (xy 428.505366 -79.639414) (xy 428.514256 -79.647796)
			(xy 428.519844 -79.651098) (xy 428.544432 -79.665784) (xy 428.589302 -79.701372) (xy 428.628349 -79.743266)
			(xy 428.660696 -79.790526) (xy 428.685615 -79.84209) (xy 428.702548 -79.8968) (xy 428.711114 -79.953425)
			(xy 428.711614 -79.98206) (xy 428.711153 -80.009315) (xy 428.703401 -80.06327) (xy 428.688049 -80.115573)
			(xy 428.665408 -80.165159) (xy 428.635942 -80.211018) (xy 428.600248 -80.252215) (xy 428.559054 -80.287914)
			(xy 428.513199 -80.317386) (xy 428.463617 -80.340032) (xy 428.411315 -80.355391) (xy 428.357361 -80.36315)
			(xy 428.330106 -80.363568) (xy 428.303084 -80.363099) (xy 428.249579 -80.355474) (xy 428.197686 -80.340376)
			(xy 428.148443 -80.318106) (xy 428.102835 -80.289111) (xy 428.061774 -80.25397) (xy 428.026083 -80.213387)
			(xy 427.996475 -80.168174) (xy 427.973543 -80.119235) (xy 427.957746 -80.067551) (xy 427.9494 -80.014154)
			(xy 427.948598 -79.98714) (xy 427.948598 -79.986886) (xy 427.947915 -79.976391) (xy 427.939214 -79.957269)
			(xy 427.923597 -79.943216) (xy 427.9138 -79.939388) (xy 427.822614 -79.909416) (xy 427.812461 -79.9066)
			(xy 427.791503 -79.908526) (xy 427.773063 -79.918671) (xy 427.766226 -79.926688) (xy 427.755812 -79.940404)
			(xy 427.498764 -80.276192) (xy 427.431708 -80.363568) (xy 427.428788 -80.367672) (xy 427.424435 -80.376753)
			(xy 427.423072 -80.381602) (xy 427.420532 -80.391) (xy 427.421802 -80.400906) (xy 427.423255 -80.413045)
			(xy 427.424781 -80.437448) (xy 427.42485 -80.449674) (xy 427.424355 -80.477308) (xy 427.416372 -80.531997)
			(xy 427.400585 -80.584962) (xy 427.377322 -80.635097) (xy 427.347072 -80.681351) (xy 427.310466 -80.722759)
			(xy 427.26827 -80.758453) (xy 427.221366 -80.787688) (xy 427.170737 -80.809851) (xy 427.117439 -80.82448)
			(xy 427.090078 -80.828388) (xy 427.089824 -80.828388) (xy 427.084744 -80.82915) (xy 427.07687 -80.833722)
			(xy 427.072572 -80.836341) (xy 427.065019 -80.842992) (xy 427.061884 -80.84693) (xy 426.214032 -81.95437)
			(xy 426.208629 -81.9645) (xy 426.2064 -81.987318) (xy 426.209714 -81.998312) (xy 426.212 -82.004408)
			(xy 426.215048 -82.013044) (xy 426.216318 -82.016092) (xy 426.221742 -82.0257) (xy 426.239005 -82.039398)
			(xy 426.249592 -82.042508) (xy 426.249846 -82.042508) (xy 426.250354 -82.042762) (xy 426.254926 -82.043778)
			(xy 426.255688 -82.044032) (xy 426.282888 -82.051304) (xy 426.334944 -82.072754) (xy 426.383281 -82.101624)
			(xy 426.426848 -82.137286) (xy 426.4647 -82.178966) (xy 426.496012 -82.225757) (xy 426.520106 -82.276643)
			(xy 426.536457 -82.330519) (xy 426.54471 -82.386213) (xy 426.545248 -82.414364) (xy 426.545009 -82.427572)
			(xy 427.232824 -82.427572) (xy 427.236895 -82.37195) (xy 427.249021 -82.317513) (xy 427.268944 -82.265422)
			(xy 427.29624 -82.216787) (xy 427.330326 -82.172644) (xy 427.370475 -82.133935) (xy 427.415833 -82.101484)
			(xy 427.465433 -82.075983) (xy 427.518217 -82.057976) (xy 427.57306 -82.047846) (xy 427.628794 -82.045809)
			(xy 427.684231 -82.051909) (xy 427.738188 -82.066015) (xy 427.789517 -82.087827) (xy 427.837123 -82.116881)
			(xy 427.879991 -82.152556) (xy 427.917208 -82.194093) (xy 427.947981 -82.240606) (xy 427.971653 -82.291103)
			(xy 427.987721 -82.34451) (xy 427.995841 -82.399686) (xy 427.99635 -82.427572) (xy 427.995841 -82.455458)
			(xy 427.987721 -82.510634) (xy 427.971653 -82.564041) (xy 427.947981 -82.614538) (xy 427.917208 -82.661051)
			(xy 427.879991 -82.702588) (xy 427.837123 -82.738263) (xy 427.789517 -82.767317) (xy 427.738188 -82.789129)
			(xy 427.684231 -82.803235) (xy 427.628794 -82.809335) (xy 427.57306 -82.807298) (xy 427.518217 -82.797168)
			(xy 427.465433 -82.779161) (xy 427.415833 -82.75366) (xy 427.370475 -82.721209) (xy 427.330326 -82.6825)
			(xy 427.29624 -82.638357) (xy 427.268944 -82.589722) (xy 427.249021 -82.537631) (xy 427.236895 -82.483194)
			(xy 427.232824 -82.427572) (xy 426.545009 -82.427572) (xy 426.544746 -82.442101) (xy 426.536706 -82.496989)
			(xy 426.520803 -82.550134) (xy 426.497375 -82.600417) (xy 426.466913 -82.646779) (xy 426.43006 -82.688242)
			(xy 426.387592 -82.723933) (xy 426.340405 -82.753099) (xy 426.289492 -82.775127) (xy 426.235927 -82.789552)
			(xy 426.208444 -82.793332) (xy 426.194728 -82.794856) (xy 426.16374 -82.796126) (xy 426.134369 -82.795589)
			(xy 426.076321 -82.786594) (xy 426.020336 -82.76881) (xy 425.967738 -82.742658) (xy 425.919768 -82.708755)
			(xy 425.877559 -82.667902) (xy 425.842109 -82.621064) (xy 425.827698 -82.595466) (xy 425.824904 -82.590132)
			(xy 425.818696 -82.581965) (xy 425.801403 -82.570964) (xy 425.791376 -82.568796) (xy 425.758864 -82.566256)
			(xy 425.752514 -82.565748) (xy 425.746418 -82.56524) (xy 425.528861 -82.849466) (xy 435.673752 -82.849466)
			(xy 435.677823 -82.793844) (xy 435.689949 -82.739407) (xy 435.709872 -82.687316) (xy 435.737168 -82.638681)
			(xy 435.771254 -82.594538) (xy 435.811403 -82.555829) (xy 435.856761 -82.523378) (xy 435.906361 -82.497877)
			(xy 435.959145 -82.47987) (xy 436.013988 -82.46974) (xy 436.069722 -82.467703) (xy 436.125159 -82.473803)
			(xy 436.179116 -82.487909) (xy 436.230445 -82.509721) (xy 436.278051 -82.538775) (xy 436.320919 -82.57445)
			(xy 436.358136 -82.615987) (xy 436.388909 -82.6625) (xy 436.412581 -82.712997) (xy 436.428649 -82.766404)
			(xy 436.436769 -82.82158) (xy 436.437278 -82.849466) (xy 436.436769 -82.877352) (xy 436.428649 -82.932528)
			(xy 436.412581 -82.985935) (xy 436.388909 -83.036432) (xy 436.358136 -83.082945) (xy 436.320919 -83.124482)
			(xy 436.278051 -83.160157) (xy 436.230445 -83.189211) (xy 436.179116 -83.211023) (xy 436.125159 -83.225129)
			(xy 436.069722 -83.231229) (xy 436.013988 -83.229192) (xy 435.959145 -83.219062) (xy 435.906361 -83.201055)
			(xy 435.856761 -83.175554) (xy 435.811403 -83.143103) (xy 435.771254 -83.104394) (xy 435.737168 -83.060251)
			(xy 435.709872 -83.011616) (xy 435.689949 -82.959525) (xy 435.677823 -82.905088) (xy 435.673752 -82.849466)
			(xy 425.528861 -82.849466) (xy 425.261532 -83.198716) (xy 425.256384 -83.206151) (xy 425.251177 -83.223457)
			(xy 425.251372 -83.232498) (xy 425.252388 -83.251294) (xy 425.258738 -83.257644) (xy 425.26585 -83.26501)
			(xy 425.286198 -83.286543) (xy 425.320661 -83.334728) (xy 425.347264 -83.387661) (xy 425.365366 -83.444069)
			(xy 425.374534 -83.502597) (xy 425.37507 -83.532218) (xy 425.374605 -83.559469) (xy 425.366846 -83.613416)
			(xy 425.351488 -83.665709) (xy 425.328844 -83.715285) (xy 425.299375 -83.761133) (xy 425.263681 -83.80232)
			(xy 425.222488 -83.838009) (xy 425.176636 -83.867471) (xy 425.127057 -83.890108) (xy 425.074761 -83.905458)
			(xy 425.020813 -83.913209) (xy 424.993562 -83.913726) (xy 424.993308 -83.913726) (xy 424.968915 -83.913345)
			(xy 424.920525 -83.907138) (xy 424.873322 -83.894811) (xy 424.828075 -83.876566) (xy 424.806618 -83.864958)
			(xy 424.806364 -83.864958) (xy 424.798258 -83.86082) (xy 424.780299 -83.857942) (xy 424.771312 -83.85937)
			(xy 424.762422 -83.861148) (xy 424.747182 -83.8708) (xy 424.283654 -84.476336) (xy 427.965614 -84.476336)
			(xy 427.969685 -84.420714) (xy 427.981811 -84.366277) (xy 428.001734 -84.314186) (xy 428.02903 -84.265551)
			(xy 428.063116 -84.221408) (xy 428.103265 -84.182699) (xy 428.148623 -84.150248) (xy 428.198223 -84.124747)
			(xy 428.251007 -84.10674) (xy 428.30585 -84.09661) (xy 428.361584 -84.094573) (xy 428.417021 -84.100673)
			(xy 428.470978 -84.114779) (xy 428.522307 -84.136591) (xy 428.569913 -84.165645) (xy 428.612781 -84.20132)
			(xy 428.649998 -84.242857) (xy 428.659108 -84.256626) (xy 435.377842 -84.256626) (xy 435.381913 -84.201004)
			(xy 435.394039 -84.146567) (xy 435.413962 -84.094476) (xy 435.441258 -84.045841) (xy 435.475344 -84.001698)
			(xy 435.515493 -83.962989) (xy 435.560851 -83.930538) (xy 435.610451 -83.905037) (xy 435.663235 -83.88703)
			(xy 435.718078 -83.8769) (xy 435.773812 -83.874863) (xy 435.829249 -83.880963) (xy 435.883206 -83.895069)
			(xy 435.934535 -83.916881) (xy 435.982141 -83.945935) (xy 436.025009 -83.98161) (xy 436.062226 -84.023147)
			(xy 436.092999 -84.06966) (xy 436.116671 -84.120157) (xy 436.132739 -84.173564) (xy 436.140859 -84.22874)
			(xy 436.141368 -84.256626) (xy 436.140859 -84.284512) (xy 436.132739 -84.339688) (xy 436.116671 -84.393095)
			(xy 436.092999 -84.443592) (xy 436.062226 -84.490105) (xy 436.025009 -84.531642) (xy 435.982141 -84.567317)
			(xy 435.934535 -84.596371) (xy 435.883206 -84.618183) (xy 435.829249 -84.632289) (xy 435.773812 -84.638389)
			(xy 435.718078 -84.636352) (xy 435.663235 -84.626222) (xy 435.610451 -84.608215) (xy 435.560851 -84.582714)
			(xy 435.515493 -84.550263) (xy 435.475344 -84.511554) (xy 435.441258 -84.467411) (xy 435.413962 -84.418776)
			(xy 435.394039 -84.366685) (xy 435.381913 -84.312248) (xy 435.377842 -84.256626) (xy 428.659108 -84.256626)
			(xy 428.680771 -84.28937) (xy 428.704443 -84.339867) (xy 428.720511 -84.393274) (xy 428.728631 -84.44845)
			(xy 428.72914 -84.476336) (xy 428.728631 -84.504222) (xy 428.720511 -84.559398) (xy 428.704443 -84.612805)
			(xy 428.680771 -84.663302) (xy 428.649998 -84.709815) (xy 428.612781 -84.751352) (xy 428.569913 -84.787027)
			(xy 428.522307 -84.816081) (xy 428.470978 -84.837893) (xy 428.417021 -84.851999) (xy 428.361584 -84.858099)
			(xy 428.30585 -84.856062) (xy 428.251007 -84.845932) (xy 428.198223 -84.827925) (xy 428.148623 -84.802424)
			(xy 428.103265 -84.769973) (xy 428.063116 -84.731264) (xy 428.02903 -84.687121) (xy 428.001734 -84.638486)
			(xy 427.981811 -84.586395) (xy 427.969685 -84.531958) (xy 427.965614 -84.476336) (xy 424.283654 -84.476336)
			(xy 422.927483 -86.247986) (xy 423.538648 -86.247986) (xy 423.542719 -86.192364) (xy 423.554845 -86.137927)
			(xy 423.574768 -86.085836) (xy 423.602064 -86.037201) (xy 423.63615 -85.993058) (xy 423.676299 -85.954349)
			(xy 423.721657 -85.921898) (xy 423.771257 -85.896397) (xy 423.824041 -85.87839) (xy 423.878884 -85.86826)
			(xy 423.934618 -85.866223) (xy 423.990055 -85.872323) (xy 424.044012 -85.886429) (xy 424.095341 -85.908241)
			(xy 424.142947 -85.937295) (xy 424.185815 -85.97297) (xy 424.223032 -86.014507) (xy 424.253805 -86.06102)
			(xy 424.277477 -86.111517) (xy 424.293545 -86.164924) (xy 424.301665 -86.2201) (xy 424.302174 -86.247986)
			(xy 424.301665 -86.275872) (xy 424.293545 -86.331048) (xy 424.277477 -86.384455) (xy 424.253805 -86.434952)
			(xy 424.223032 -86.481465) (xy 424.185815 -86.523002) (xy 424.142947 -86.558677) (xy 424.095341 -86.587731)
			(xy 424.044012 -86.609543) (xy 423.990055 -86.623649) (xy 423.934618 -86.629749) (xy 423.878884 -86.627712)
			(xy 423.824041 -86.617582) (xy 423.771257 -86.599575) (xy 423.721657 -86.574074) (xy 423.676299 -86.541623)
			(xy 423.63615 -86.502914) (xy 423.602064 -86.458771) (xy 423.574768 -86.410136) (xy 423.554845 -86.358045)
			(xy 423.542719 -86.303608) (xy 423.538648 -86.247986) (xy 422.927483 -86.247986) (xy 422.058562 -87.383112)
			(xy 434.523386 -87.383112) (xy 434.527457 -87.32749) (xy 434.539583 -87.273053) (xy 434.559506 -87.220962)
			(xy 434.586802 -87.172327) (xy 434.620888 -87.128184) (xy 434.661037 -87.089475) (xy 434.706395 -87.057024)
			(xy 434.755995 -87.031523) (xy 434.808779 -87.013516) (xy 434.863622 -87.003386) (xy 434.919356 -87.001349)
			(xy 434.974793 -87.007449) (xy 435.02875 -87.021555) (xy 435.080079 -87.043367) (xy 435.127685 -87.072421)
			(xy 435.170553 -87.108096) (xy 435.20777 -87.149633) (xy 435.238543 -87.196146) (xy 435.262215 -87.246643)
			(xy 435.278283 -87.30005) (xy 435.286403 -87.355226) (xy 435.286912 -87.383112) (xy 435.286403 -87.410998)
			(xy 435.278283 -87.466174) (xy 435.262215 -87.519581) (xy 435.238543 -87.570078) (xy 435.20777 -87.616591)
			(xy 435.170553 -87.658128) (xy 435.127685 -87.693803) (xy 435.080079 -87.722857) (xy 435.02875 -87.744669)
			(xy 434.974793 -87.758775) (xy 434.919356 -87.764875) (xy 434.863622 -87.762838) (xy 434.808779 -87.752708)
			(xy 434.755995 -87.734701) (xy 434.706395 -87.7092) (xy 434.661037 -87.676749) (xy 434.620888 -87.63804)
			(xy 434.586802 -87.593897) (xy 434.559506 -87.545262) (xy 434.539583 -87.493171) (xy 434.527457 -87.438734)
			(xy 434.523386 -87.383112) (xy 422.058562 -87.383112) (xy 420.663116 -89.20607) (xy 420.658946 -89.211804)
			(xy 420.653662 -89.224953) (xy 420.652702 -89.231978) (xy 420.652194 -89.23909) (xy 420.65448 -89.252552)
			(xy 420.657528 -89.258902) (xy 420.670165 -89.285699) (xy 420.688045 -89.342181) (xy 420.697094 -89.40073)
			(xy 420.69766 -89.430352) (xy 420.697195 -89.457916) (xy 420.689356 -89.512485) (xy 420.673831 -89.565383)
			(xy 420.650935 -89.615532) (xy 420.621135 -89.661913) (xy 420.585038 -89.70358) (xy 420.543378 -89.739686)
			(xy 420.509983 -89.761153) (xy 422.18606 -89.761153) (xy 422.18606 -89.706647) (xy 422.193817 -89.652697)
			(xy 422.209173 -89.6004) (xy 422.231815 -89.55082) (xy 422.261282 -89.504968) (xy 422.296976 -89.463776)
			(xy 422.338168 -89.428082) (xy 422.38402 -89.398615) (xy 422.4336 -89.375973) (xy 422.485897 -89.360617)
			(xy 422.539847 -89.35286) (xy 422.5671 -89.352374) (xy 422.594118 -89.352881) (xy 422.64761 -89.360518)
			(xy 422.699491 -89.375624) (xy 422.748722 -89.397899) (xy 422.794318 -89.426895) (xy 422.835368 -89.462034)
			(xy 422.87105 -89.502612) (xy 422.900651 -89.547818) (xy 422.91254 -89.572084) (xy 422.919278 -89.585231)
			(xy 422.938949 -89.607253) (xy 422.964097 -89.622728) (xy 422.992621 -89.630364) (xy 423.022138 -89.629523)
			(xy 423.050181 -89.620275) (xy 423.074407 -89.603392) (xy 423.08399 -89.59215) (xy 423.102187 -89.570117)
			(xy 423.144068 -89.531242) (xy 423.191278 -89.499046) (xy 423.24276 -89.474249) (xy 423.297364 -89.457405)
			(xy 423.353869 -89.448891) (xy 423.38244 -89.448386) (xy 423.409689 -89.448886) (xy 423.463632 -89.456648)
			(xy 423.515921 -89.472006) (xy 423.565492 -89.494649) (xy 423.611337 -89.524116) (xy 423.652522 -89.559807)
			(xy 423.688208 -89.600995) (xy 423.71767 -89.646843) (xy 423.740308 -89.696417) (xy 423.755661 -89.748708)
			(xy 423.762695 -89.797636) (xy 423.880024 -89.797636) (xy 423.884095 -89.742014) (xy 423.896221 -89.687577)
			(xy 423.916144 -89.635486) (xy 423.94344 -89.586851) (xy 423.977526 -89.542708) (xy 424.017675 -89.503999)
			(xy 424.063033 -89.471548) (xy 424.112633 -89.446047) (xy 424.165417 -89.42804) (xy 424.22026 -89.41791)
			(xy 424.275994 -89.415873) (xy 424.331431 -89.421973) (xy 424.385388 -89.436079) (xy 424.436717 -89.457891)
			(xy 424.484323 -89.486945) (xy 424.527191 -89.52262) (xy 424.564408 -89.564157) (xy 424.595181 -89.61067)
			(xy 424.618853 -89.661167) (xy 424.634921 -89.714574) (xy 424.643041 -89.76975) (xy 424.64355 -89.797636)
			(xy 424.643041 -89.825522) (xy 424.634921 -89.880698) (xy 424.618853 -89.934105) (xy 424.595181 -89.984602)
			(xy 424.564408 -90.031115) (xy 424.527191 -90.072652) (xy 424.484323 -90.108327) (xy 424.436717 -90.137381)
			(xy 424.385388 -90.159193) (xy 424.331431 -90.173299) (xy 424.275994 -90.179399) (xy 424.22026 -90.177362)
			(xy 424.165417 -90.167232) (xy 424.112633 -90.149225) (xy 424.063033 -90.123724) (xy 424.017675 -90.091273)
			(xy 423.977526 -90.052564) (xy 423.94344 -90.008421) (xy 423.916144 -89.959786) (xy 423.896221 -89.907695)
			(xy 423.884095 -89.853258) (xy 423.880024 -89.797636) (xy 423.762695 -89.797636) (xy 423.763416 -89.802651)
			(xy 423.763416 -89.857149) (xy 423.755661 -89.911092) (xy 423.740308 -89.963383) (xy 423.71767 -90.012957)
			(xy 423.688208 -90.058805) (xy 423.652522 -90.099993) (xy 423.611337 -90.135684) (xy 423.565492 -90.165151)
			(xy 423.515921 -90.187794) (xy 423.463632 -90.203152) (xy 423.409689 -90.210914) (xy 423.38244 -90.211402)
			(xy 423.35542 -90.210959) (xy 423.301924 -90.203313) (xy 423.250041 -90.188198) (xy 423.200809 -90.165914)
			(xy 423.155213 -90.136909) (xy 423.114165 -90.101762) (xy 423.078485 -90.061175) (xy 423.048887 -90.015961)
			(xy 423.037 -89.991692) (xy 423.030208 -89.978577) (xy 423.010545 -89.956563) (xy 422.985408 -89.941092)
			(xy 422.956896 -89.933454) (xy 422.927391 -89.934289) (xy 422.899357 -89.943525) (xy 422.875134 -89.960392)
			(xy 422.86555 -89.971626) (xy 422.847325 -89.993634) (xy 422.80545 -90.032512) (xy 422.758247 -90.064712)
			(xy 422.70677 -90.089513) (xy 422.652171 -90.106362) (xy 422.59567 -90.114882) (xy 422.5671 -90.11539)
			(xy 422.539847 -90.11494) (xy 422.485897 -90.107183) (xy 422.4336 -90.091827) (xy 422.38402 -90.069185)
			(xy 422.338168 -90.039718) (xy 422.296976 -90.004024) (xy 422.261282 -89.962832) (xy 422.231815 -89.91698)
			(xy 422.209173 -89.8674) (xy 422.193817 -89.815103) (xy 422.18606 -89.761153) (xy 420.509983 -89.761153)
			(xy 420.497004 -89.769496) (xy 420.446859 -89.792402) (xy 420.393965 -89.807938) (xy 420.339398 -89.815789)
			(xy 420.311834 -89.816178) (xy 420.31158 -89.816178) (xy 420.292914 -89.815925) (xy 420.255763 -89.812239)
			(xy 420.237412 -89.808812) (xy 420.231062 -89.807542) (xy 420.230554 -89.807542) (xy 420.22268 -89.806018)
			(xy 420.209726 -89.810844) (xy 420.203124 -89.813576) (xy 420.191652 -89.822084) (xy 420.18712 -89.827608)
			(xy 416.677602 -94.412308) (xy 416.672522 -94.420182) (xy 416.668458 -94.431612) (xy 416.611562 -94.671134)
			(xy 416.611562 -94.671388) (xy 416.611054 -94.672658) (xy 416.610038 -94.676976) (xy 416.608617 -94.686442)
			(xy 416.612153 -94.705237) (xy 416.616896 -94.713552) (xy 416.61715 -94.713806) (xy 416.656012 -94.775274)
			(xy 416.658876 -94.779569) (xy 416.666044 -94.786994) (xy 416.670236 -94.790006) (xy 416.678618 -94.795848)
			(xy 416.688524 -94.79788) (xy 416.716716 -94.804349) (xy 416.770875 -94.824648) (xy 416.82135 -94.852891)
			(xy 416.866982 -94.88843) (xy 416.906726 -94.930451) (xy 416.939671 -94.97799) (xy 416.965061 -95.029958)
			(xy 416.982316 -95.085163) (xy 416.991038 -95.142341) (xy 416.991546 -95.17126) (xy 416.991086 -95.198516)
			(xy 416.983334 -95.252473) (xy 416.967982 -95.304778) (xy 416.945342 -95.354366) (xy 416.915875 -95.400227)
			(xy 416.880182 -95.441427) (xy 416.838989 -95.477129) (xy 416.793134 -95.506604) (xy 416.743551 -95.529254)
			(xy 416.691249 -95.544617) (xy 416.637294 -95.55238) (xy 416.610038 -95.552768) (xy 416.609276 -95.552768)
			(xy 416.584672 -95.552366) (xy 416.535878 -95.545989) (xy 416.511994 -95.540068) (xy 416.502088 -95.537528)
			(xy 416.491928 -95.538798) (xy 416.486898 -95.539657) (xy 416.477296 -95.543104) (xy 416.472878 -95.545656)
			(xy 416.410394 -95.582994) (xy 416.402598 -95.588106) (xy 416.391013 -95.602694) (xy 416.387788 -95.611442)
			(xy 416.321748 -95.889064) (xy 416.308032 -95.946976) (xy 416.308032 -95.947484) (xy 416.29203 -96.018604)
			(xy 416.29187 -96.024609) (xy 416.294064 -96.036415) (xy 416.296348 -96.041972) (xy 416.299904 -96.049846)
			(xy 416.310826 -96.06153) (xy 416.319208 -96.066102) (xy 416.345439 -96.080857) (xy 416.393294 -96.117349)
			(xy 416.414458 -96.138746) (xy 416.428174 -96.153986) (xy 416.430206 -96.152716) (xy 416.447986 -96.179386)
			(xy 416.449002 -96.180402) (xy 416.454797 -96.188653) (xy 416.465599 -96.205679) (xy 416.470592 -96.214438)
			(xy 416.473894 -96.22028) (xy 416.483038 -96.229932) (xy 416.48888 -96.233234) (xy 416.494621 -96.236402)
			(xy 416.507224 -96.240004) (xy 416.513772 -96.240346) (xy 416.548316 -96.241108) (xy 416.603688 -96.242124)
			(xy 416.612109 -96.241613) (xy 416.627911 -96.235735) (xy 416.640929 -96.22502) (xy 416.645598 -96.217994)
			(xy 416.660595 -96.194644) (xy 416.696275 -96.152141) (xy 416.737735 -96.115254) (xy 416.784101 -96.084763)
			(xy 416.834396 -96.061309) (xy 416.887557 -96.045389) (xy 416.942463 -96.037337) (xy 416.97021 -96.036892)
			(xy 416.997461 -96.037378) (xy 417.051407 -96.045136) (xy 417.103701 -96.060492) (xy 417.153277 -96.083134)
			(xy 417.199126 -96.1126) (xy 417.240315 -96.148292) (xy 417.276006 -96.189482) (xy 417.305471 -96.235332)
			(xy 417.328111 -96.284908) (xy 417.343466 -96.337202) (xy 417.351222 -96.391149) (xy 417.351222 -96.445651)
			(xy 417.343466 -96.499598) (xy 417.328111 -96.551892) (xy 417.305471 -96.601468) (xy 417.276006 -96.647318)
			(xy 417.240315 -96.688508) (xy 417.199126 -96.7242) (xy 417.153277 -96.753666) (xy 417.103701 -96.776308)
			(xy 417.051407 -96.791664) (xy 416.997461 -96.799422) (xy 416.97021 -96.799908) (xy 416.97021 -96.800162)
			(xy 416.942465 -96.799664) (xy 416.887559 -96.791625) (xy 416.834398 -96.775716) (xy 416.784103 -96.752272)
			(xy 416.737735 -96.721788) (xy 416.696273 -96.684908) (xy 416.660593 -96.64241) (xy 416.645598 -96.61906)
			(xy 416.644074 -96.616774) (xy 416.642804 -96.614488) (xy 416.63747 -96.605598) (xy 416.633914 -96.60001)
			(xy 416.62985 -96.595184) (xy 416.625532 -96.590612) (xy 416.61969 -96.58731) (xy 416.614532 -96.584384)
			(xy 416.603238 -96.580782) (xy 416.597338 -96.580198) (xy 416.560254 -96.579436) (xy 416.504882 -96.57842)
			(xy 416.496462 -96.578935) (xy 416.480662 -96.584815) (xy 416.467643 -96.595526) (xy 416.462972 -96.60255)
			(xy 416.448409 -96.625278) (xy 416.413886 -96.666774) (xy 416.373859 -96.702989) (xy 416.329127 -96.733202)
			(xy 416.280583 -96.756808) (xy 416.229197 -96.773337) (xy 416.175995 -96.782459) (xy 416.149028 -96.783652)
			(xy 416.144202 -96.783906) (xy 416.137005 -96.784901) (xy 416.123579 -96.790443) (xy 416.117786 -96.794828)
			(xy 416.093908 -96.901) (xy 417.621972 -96.901) (xy 417.626043 -96.845378) (xy 417.638169 -96.790941)
			(xy 417.658092 -96.73885) (xy 417.685388 -96.690215) (xy 417.719474 -96.646072) (xy 417.759623 -96.607363)
			(xy 417.804981 -96.574912) (xy 417.854581 -96.549411) (xy 417.907365 -96.531404) (xy 417.962208 -96.521274)
			(xy 418.017942 -96.519237) (xy 418.073379 -96.525337) (xy 418.127336 -96.539443) (xy 418.178665 -96.561255)
			(xy 418.226271 -96.590309) (xy 418.269139 -96.625984) (xy 418.306356 -96.667521) (xy 418.337129 -96.714034)
			(xy 418.360801 -96.764531) (xy 418.376869 -96.817938) (xy 418.384989 -96.873114) (xy 418.385498 -96.901)
			(xy 418.384989 -96.928886) (xy 418.376869 -96.984062) (xy 418.360801 -97.037469) (xy 418.337129 -97.087966)
			(xy 418.306356 -97.134479) (xy 418.269139 -97.176016) (xy 418.226271 -97.211691) (xy 418.178665 -97.240745)
			(xy 418.127336 -97.262557) (xy 418.073379 -97.276663) (xy 418.017942 -97.282763) (xy 417.962208 -97.280726)
			(xy 417.907365 -97.270596) (xy 417.854581 -97.252589) (xy 417.804981 -97.227088) (xy 417.759623 -97.194637)
			(xy 417.719474 -97.155928) (xy 417.685388 -97.111785) (xy 417.658092 -97.06315) (xy 417.638169 -97.011059)
			(xy 417.626043 -96.956622) (xy 417.621972 -96.901) (xy 416.093908 -96.901) (xy 415.579787 -99.187)
			(xy 418.422072 -99.187) (xy 418.426143 -99.131378) (xy 418.438269 -99.076941) (xy 418.458192 -99.02485)
			(xy 418.485488 -98.976215) (xy 418.519574 -98.932072) (xy 418.559723 -98.893363) (xy 418.605081 -98.860912)
			(xy 418.654681 -98.835411) (xy 418.707465 -98.817404) (xy 418.762308 -98.807274) (xy 418.818042 -98.805237)
			(xy 418.873479 -98.811337) (xy 418.927436 -98.825443) (xy 418.978765 -98.847255) (xy 419.026371 -98.876309)
			(xy 419.069239 -98.911984) (xy 419.106456 -98.953521) (xy 419.137229 -99.000034) (xy 419.160901 -99.050531)
			(xy 419.176969 -99.103938) (xy 419.185089 -99.159114) (xy 419.185598 -99.187) (xy 419.185089 -99.214886)
			(xy 419.176969 -99.270062) (xy 419.160901 -99.323469) (xy 419.137229 -99.373966) (xy 419.106456 -99.420479)
			(xy 419.069239 -99.462016) (xy 419.026371 -99.497691) (xy 418.978765 -99.526745) (xy 418.927436 -99.548557)
			(xy 418.873479 -99.562663) (xy 418.818042 -99.568763) (xy 418.762308 -99.566726) (xy 418.707465 -99.556596)
			(xy 418.654681 -99.538589) (xy 418.605081 -99.513088) (xy 418.559723 -99.480637) (xy 418.519574 -99.441928)
			(xy 418.485488 -99.397785) (xy 418.458192 -99.34915) (xy 418.438269 -99.297059) (xy 418.426143 -99.242622)
			(xy 418.422072 -99.187) (xy 415.579787 -99.187) (xy 414.806892 -102.62362) (xy 413.854392 -106.860086)
			(xy 413.855916 -106.86415) (xy 413.858964 -106.871008) (xy 413.863028 -106.875834) (xy 413.865432 -106.878593)
			(xy 413.870917 -106.883438) (xy 413.87395 -106.885486) (xy 413.88157 -106.890312) (xy 413.904023 -106.905515)
			(xy 413.944805 -106.941253) (xy 413.980125 -106.982396) (xy 414.009273 -107.02812) (xy 414.031664 -107.077506)
			(xy 414.046849 -107.129561) (xy 414.054522 -107.18324) (xy 414.055052 -107.210352) (xy 414.054599 -107.236883)
			(xy 414.047253 -107.289433) (xy 414.032697 -107.340459) (xy 414.01121 -107.388976) (xy 413.983209 -107.434047)
			(xy 413.949232 -107.474804) (xy 413.909936 -107.51046) (xy 413.866078 -107.540326) (xy 413.818505 -107.563828)
			(xy 413.768134 -107.580511) (xy 413.742124 -107.585764) (xy 413.737298 -107.586526) (xy 413.728953 -107.589293)
			(xy 413.714672 -107.599526) (xy 413.704657 -107.613961) (xy 413.701992 -107.62234) (xy 413.572452 -108.302044)
			(xy 413.365442 -109.389926) (xy 413.364934 -109.396276) (xy 413.36595 -109.406182) (xy 413.36722 -109.412786)
			(xy 413.37008 -109.429722) (xy 413.37313 -109.463937) (xy 413.373316 -109.481112) (xy 413.373316 -109.48162)
			(xy 413.372841 -109.509022) (xy 413.364996 -109.563262) (xy 413.349471 -109.615821) (xy 413.326586 -109.665618)
			(xy 413.312102 -109.688884) (xy 413.310832 -109.690662) (xy 413.310324 -109.691678) (xy 413.305498 -109.703108)
			(xy 413.176466 -110.381542) (xy 413.123126 -110.660688) (xy 413.072072 -110.929674) (xy 413.070507 -110.940277)
			(xy 413.075374 -110.96113) (xy 413.088329 -110.97818) (xy 413.097472 -110.983776) (xy 413.101282 -110.985554)
			(xy 413.126184 -110.997172) (xy 413.172651 -111.026503) (xy 413.21443 -111.062196) (xy 413.250657 -111.103513)
			(xy 413.280583 -111.149599) (xy 413.303589 -111.199501) (xy 413.319198 -111.252187) (xy 413.327089 -111.306567)
			(xy 413.327596 -111.334042) (xy 413.32752 -111.34678) (xy 413.32587 -111.372202) (xy 413.324294 -111.384842)
			(xy 413.320289 -111.411162) (xy 413.30593 -111.462428) (xy 413.284584 -111.5112) (xy 413.256666 -111.556532)
			(xy 413.222717 -111.597542) (xy 413.183397 -111.633435) (xy 413.13947 -111.663514) (xy 413.091788 -111.687195)
			(xy 413.041277 -111.704017) (xy 412.988918 -111.713655) (xy 412.962344 -111.715296) (xy 412.959042 -111.71555)
			(xy 412.95147 -111.716602) (xy 412.937394 -111.722544) (xy 412.931356 -111.727234) (xy 412.924752 -111.732822)
			(xy 412.920434 -111.739934) (xy 412.915608 -111.751872) (xy 412.846012 -112.114584) (xy 412.811976 -112.293908)
			(xy 412.811468 -112.300512) (xy 412.816548 -112.319562) (xy 412.820612 -112.329722) (xy 412.820866 -112.330484)
			(xy 412.835071 -112.358356) (xy 412.855204 -112.41758) (xy 412.865418 -112.479294) (xy 412.865547 -112.485424)
			(xy 414.951162 -112.485424) (xy 414.955233 -112.429802) (xy 414.967359 -112.375365) (xy 414.987282 -112.323274)
			(xy 415.014578 -112.274639) (xy 415.048664 -112.230496) (xy 415.088813 -112.191787) (xy 415.134171 -112.159336)
			(xy 415.183771 -112.133835) (xy 415.236555 -112.115828) (xy 415.291398 -112.105698) (xy 415.347132 -112.103661)
			(xy 415.402569 -112.109761) (xy 415.456526 -112.123867) (xy 415.507855 -112.145679) (xy 415.555461 -112.174733)
			(xy 415.598329 -112.210408) (xy 415.635546 -112.251945) (xy 415.666319 -112.298458) (xy 415.689991 -112.348955)
			(xy 415.706059 -112.402362) (xy 415.714179 -112.457538) (xy 415.714688 -112.485424) (xy 415.714179 -112.51331)
			(xy 415.706059 -112.568486) (xy 415.689991 -112.621893) (xy 415.666319 -112.67239) (xy 415.635546 -112.718903)
			(xy 415.598329 -112.76044) (xy 415.555461 -112.796115) (xy 415.507855 -112.825169) (xy 415.456526 -112.846981)
			(xy 415.402569 -112.861087) (xy 415.347132 -112.867187) (xy 415.291398 -112.86515) (xy 415.236555 -112.85502)
			(xy 415.183771 -112.837013) (xy 415.134171 -112.811512) (xy 415.088813 -112.779061) (xy 415.048664 -112.740352)
			(xy 415.014578 -112.696209) (xy 414.987282 -112.647574) (xy 414.967359 -112.595483) (xy 414.955233 -112.541046)
			(xy 414.951162 -112.485424) (xy 412.865547 -112.485424) (xy 412.866078 -112.51057) (xy 412.866078 -112.518952)
			(xy 412.86502 -112.546395) (xy 412.855996 -112.600568) (xy 412.839295 -112.652886) (xy 412.815262 -112.702268)
			(xy 412.784395 -112.747691) (xy 412.74733 -112.788217) (xy 412.726378 -112.805972) (xy 412.71952 -112.81283)
			(xy 412.716044 -112.817245) (xy 412.710914 -112.827242) (xy 412.70936 -112.832642) (xy 412.708852 -112.835944)
			(xy 412.699962 -112.88141) (xy 412.698712 -112.889558) (xy 412.700929 -112.905881) (xy 412.70428 -112.913414)
			(xy 412.706173 -112.917181) (xy 412.711027 -112.924075) (xy 412.713932 -112.92713) (xy 412.725108 -112.935512)
			(xy 412.736792 -112.940338) (xy 412.740602 -112.9411) (xy 412.743396 -112.941608) (xy 412.749712 -112.942199)
			(xy 412.762297 -112.940647) (xy 412.768288 -112.93856) (xy 412.775908 -112.934496) (xy 412.776924 -112.933988)
			(xy 412.778448 -112.933226) (xy 412.779972 -112.931956) (xy 412.803272 -112.91737) (xy 412.853174 -112.894316)
			(xy 412.905866 -112.878659) (xy 412.96026 -112.870722) (xy 412.987744 -112.870234) (xy 412.988252 -112.870234)
			(xy 413.015506 -112.870694) (xy 413.06946 -112.878446) (xy 413.121761 -112.893798) (xy 413.171345 -112.916438)
			(xy 413.217201 -112.945906) (xy 413.258396 -112.9816) (xy 413.294091 -113.022794) (xy 413.323559 -113.06865)
			(xy 413.3462 -113.118233) (xy 413.361553 -113.170534) (xy 413.369305 -113.224488) (xy 413.36976 -113.251742)
			(xy 413.369298 -113.278311) (xy 413.361919 -113.330933) (xy 413.34731 -113.382023) (xy 413.325753 -113.430591)
			(xy 413.322927 -113.43513) (xy 414.954972 -113.43513) (xy 414.959043 -113.379508) (xy 414.971169 -113.325071)
			(xy 414.991092 -113.27298) (xy 415.018388 -113.224345) (xy 415.052474 -113.180202) (xy 415.092623 -113.141493)
			(xy 415.137981 -113.109042) (xy 415.187581 -113.083541) (xy 415.240365 -113.065534) (xy 415.295208 -113.055404)
			(xy 415.350942 -113.053367) (xy 415.406379 -113.059467) (xy 415.460336 -113.073573) (xy 415.511665 -113.095385)
			(xy 415.559271 -113.124439) (xy 415.602139 -113.160114) (xy 415.639356 -113.201651) (xy 415.670129 -113.248164)
			(xy 415.693801 -113.298661) (xy 415.709869 -113.352068) (xy 415.717989 -113.407244) (xy 415.718498 -113.43513)
			(xy 415.717989 -113.463016) (xy 415.709869 -113.518192) (xy 415.693801 -113.571599) (xy 415.670129 -113.622096)
			(xy 415.639356 -113.668609) (xy 415.602139 -113.710146) (xy 415.559271 -113.745821) (xy 415.511665 -113.774875)
			(xy 415.460336 -113.796687) (xy 415.406379 -113.810793) (xy 415.350942 -113.816893) (xy 415.295208 -113.814856)
			(xy 415.240365 -113.804726) (xy 415.187581 -113.786719) (xy 415.137981 -113.761218) (xy 415.092623 -113.728767)
			(xy 415.052474 -113.690058) (xy 415.018388 -113.645915) (xy 414.991092 -113.59728) (xy 414.971169 -113.545189)
			(xy 414.959043 -113.490752) (xy 414.954972 -113.43513) (xy 413.322927 -113.43513) (xy 413.297665 -113.475698)
			(xy 413.26359 -113.516472) (xy 413.224187 -113.552123) (xy 413.180218 -113.581962) (xy 413.132535 -113.605411)
			(xy 413.082059 -113.622017) (xy 413.029767 -113.631458) (xy 413.003238 -113.632996) (xy 413.002222 -113.632996)
			(xy 412.988252 -113.63325) (xy 412.987998 -113.63325) (xy 412.98749 -113.63325) (xy 412.985712 -113.63325)
			(xy 412.959013 -113.632617) (xy 412.906181 -113.62481) (xy 412.85495 -113.609723) (xy 412.806319 -113.58765)
			(xy 412.761235 -113.559021) (xy 412.740602 -113.542064) (xy 412.73984 -113.541556) (xy 412.731966 -113.534952)
			(xy 412.659068 -113.534952) (xy 412.650432 -113.535714) (xy 412.644844 -113.536984) (xy 412.598362 -113.552732)
			(xy 412.598108 -113.552732) (xy 412.5864 -113.557399) (xy 412.569211 -113.575789) (xy 412.565342 -113.587784)
			(xy 412.492444 -113.970308) (xy 412.3148 -114.902552) (xy 414.258465 -114.902552) (xy 414.258465 -114.848048)
			(xy 414.266222 -114.794098) (xy 414.281578 -114.741801) (xy 414.304221 -114.692221) (xy 414.333688 -114.646369)
			(xy 414.369382 -114.605177) (xy 414.410574 -114.569485) (xy 414.456427 -114.540018) (xy 414.506006 -114.517376)
			(xy 414.558303 -114.502021) (xy 414.612254 -114.494265) (xy 414.639506 -114.493802) (xy 414.666851 -114.494272)
			(xy 414.720984 -114.502056) (xy 414.77345 -114.517493) (xy 414.823173 -114.540266) (xy 414.869134 -114.569908)
			(xy 414.910389 -114.60581) (xy 414.946093 -114.647238) (xy 414.975513 -114.69334) (xy 414.998046 -114.743172)
			(xy 415.01323 -114.795712) (xy 415.017458 -114.822732) (xy 415.01949 -114.83721) (xy 415.038032 -114.859308)
			(xy 415.13887 -114.892074) (xy 415.14802 -114.894706) (xy 415.167018 -114.893639) (xy 415.184311 -114.8857)
			(xy 415.191194 -114.87912) (xy 415.214888 -114.855243) (xy 415.266806 -114.81247) (xy 415.323282 -114.775925)
			(xy 415.383571 -114.746087) (xy 415.446881 -114.723351) (xy 415.512378 -114.708014) (xy 415.5792 -114.70028)
			(xy 415.612834 -114.699796) (xy 415.896298 -114.699796) (xy 415.906371 -114.699397) (xy 415.92497 -114.691661)
			(xy 415.932366 -114.68481) (xy 416.595814 -114.021616) (xy 416.602641 -114.014206) (xy 416.610368 -113.995614)
			(xy 416.6108 -113.985548) (xy 416.6108 -111.06531) (xy 416.611284 -111.032457) (xy 416.618646 -110.967165)
			(xy 416.633266 -110.903107) (xy 416.654962 -110.841086) (xy 416.683461 -110.781883) (xy 416.718404 -110.726239)
			(xy 416.759354 -110.674855) (xy 416.78225 -110.65129) (xy 419.5191 -107.91444) (xy 419.542665 -107.891509)
			(xy 419.594078 -107.850515) (xy 419.649754 -107.81553) (xy 419.708995 -107.786992) (xy 419.771055 -107.765259)
			(xy 419.835157 -107.750605) (xy 419.900496 -107.743214) (xy 419.933374 -107.742736) (xy 420.791132 -107.742736)
			(xy 420.801137 -107.742239) (xy 420.819623 -107.734576) (xy 420.833773 -107.720426) (xy 420.841438 -107.701941)
			(xy 420.841932 -107.691936) (xy 420.841932 -106.413808) (xy 420.84152 -106.403737) (xy 420.833792 -106.385138)
			(xy 420.826946 -106.37774) (xy 420.092378 -105.643172) (xy 420.069467 -105.619619) (xy 420.0285 -105.568241)
			(xy 419.993544 -105.5126) (xy 419.965037 -105.453395) (xy 419.943338 -105.39137) (xy 419.928721 -105.327306)
			(xy 419.921369 -105.262007) (xy 419.920928 -105.229152) (xy 419.920928 -97.780602) (xy 419.921399 -97.747749)
			(xy 419.928762 -97.682456) (xy 419.943384 -97.618397) (xy 419.965081 -97.556376) (xy 419.993582 -97.497173)
			(xy 420.028528 -97.44153) (xy 420.069481 -97.390146) (xy 420.092378 -97.366582) (xy 421.005508 -96.453452)
			(xy 421.012016 -96.446209) (xy 421.019601 -96.428299) (xy 421.019977 -96.408852) (xy 421.016938 -96.399604)
			(xy 420.979092 -96.298766) (xy 420.954962 -96.28124) (xy 420.939976 -96.280224) (xy 420.893973 -96.276766)
			(xy 420.802746 -96.263005) (xy 420.713047 -96.241421) (xy 420.625545 -96.212175) (xy 420.540895 -96.175487)
			(xy 420.459727 -96.131629) (xy 420.382647 -96.080929) (xy 420.310231 -96.023765) (xy 420.243019 -95.960565)
			(xy 420.181513 -95.891799) (xy 420.126171 -95.817981) (xy 420.077407 -95.739662) (xy 420.035585 -95.657426)
			(xy 420.001017 -95.571888) (xy 419.973961 -95.483685) (xy 419.954619 -95.393476) (xy 419.943135 -95.301934)
			(xy 419.939595 -95.209743) (xy 419.944025 -95.11759) (xy 419.956393 -95.026164) (xy 419.976605 -94.936146)
			(xy 420.004512 -94.848208) (xy 420.039905 -94.763008) (xy 420.082519 -94.68118) (xy 420.132037 -94.603335)
			(xy 420.188088 -94.530055) (xy 420.250256 -94.461887) (xy 420.318075 -94.399338) (xy 420.39104 -94.342877)
			(xy 420.468606 -94.292924) (xy 420.550194 -94.249852) (xy 420.635195 -94.213982) (xy 420.722974 -94.185583)
			(xy 420.812878 -94.164867) (xy 420.904233 -94.151987) (xy 420.99636 -94.147041) (xy 421.08857 -94.150064)
			(xy 421.180174 -94.161035) (xy 421.27049 -94.179872) (xy 421.358843 -94.206433) (xy 421.444574 -94.240521)
			(xy 421.527043 -94.281882) (xy 421.566594 -94.305628) (xy 421.578278 -94.312994) (xy 421.605964 -94.313502)
			(xy 421.695372 -94.263464) (xy 421.703014 -94.258731) (xy 421.7147 -94.245094) (xy 421.720925 -94.228248)
			(xy 421.72128 -94.219268) (xy 421.72128 -94.123764) (xy 421.721739 -94.090883) (xy 421.7291 -94.025535)
			(xy 421.743737 -93.961424) (xy 421.765465 -93.899356) (xy 421.794011 -93.840113) (xy 421.829016 -93.784442)
			(xy 421.870037 -93.733044) (xy 421.892984 -93.70949) (xy 425.16298 -90.439494) (xy 425.169579 -90.432369)
			(xy 425.177235 -90.414536) (xy 425.177675 -90.395135) (xy 425.174664 -90.3859) (xy 425.137072 -90.285062)
			(xy 425.11345 -90.267282) (xy 425.098464 -90.266266) (xy 425.069952 -90.263753) (xy 425.014108 -90.251197)
			(xy 424.960768 -90.230438) (xy 424.911127 -90.201943) (xy 424.866301 -90.166352) (xy 424.827296 -90.124462)
			(xy 424.794987 -90.077216) (xy 424.770099 -90.025672) (xy 424.753192 -89.970989) (xy 424.744644 -89.914393)
			(xy 424.744134 -89.885774) (xy 424.744531 -89.858519) (xy 424.752292 -89.804563) (xy 424.767654 -89.752261)
			(xy 424.790302 -89.702678) (xy 424.819777 -89.656823) (xy 424.855478 -89.61563) (xy 424.896678 -89.579936)
			(xy 424.942538 -89.55047) (xy 424.992125 -89.52783) (xy 425.04443 -89.512478) (xy 425.098386 -89.504726)
			(xy 425.125642 -89.504266) (xy 425.154257 -89.50481) (xy 425.210844 -89.513364) (xy 425.265519 -89.530276)
			(xy 425.317054 -89.555164) (xy 425.364294 -89.587471) (xy 425.406178 -89.626472) (xy 425.441766 -89.671291)
			(xy 425.47026 -89.720924) (xy 425.491021 -89.774256) (xy 425.503583 -89.83009) (xy 425.506134 -89.858596)
			(xy 425.50715 -89.873582) (xy 425.52493 -89.897204) (xy 425.625768 -89.934796) (xy 425.634995 -89.9378)
			(xy 425.65438 -89.937305) (xy 425.672201 -89.929663) (xy 425.679362 -89.923112) (xy 427.64075 -87.961724)
			(xy 427.664335 -87.938814) (xy 427.715745 -87.897819) (xy 427.771418 -87.862832) (xy 427.830654 -87.834291)
			(xy 427.892712 -87.812555) (xy 427.956811 -87.797897) (xy 428.022147 -87.790501) (xy 428.055024 -87.79002)
			(xy 428.605696 -87.79002) (xy 428.640529 -87.790567) (xy 428.709703 -87.798831) (xy 428.777409 -87.815241)
			(xy 428.84269 -87.839567) (xy 428.904625 -87.871465) (xy 428.962338 -87.910484) (xy 429.015016 -87.956073)
			(xy 429.061914 -88.00759) (xy 429.10237 -88.064305) (xy 429.135813 -88.12542) (xy 429.149256 -88.157558)
			(xy 429.154082 -88.169496) (xy 429.17364 -88.185752) (xy 429.269398 -88.20531) (xy 429.281859 -88.207192)
			(xy 429.305979 -88.199996) (xy 429.315372 -88.191594) (xy 429.52543 -87.981536) (xy 429.549026 -87.958638)
			(xy 429.600434 -87.917642) (xy 429.656104 -87.882653) (xy 429.715339 -87.85411) (xy 429.777395 -87.832373)
			(xy 429.841493 -87.817712) (xy 429.906828 -87.810314) (xy 429.939704 -87.809832) (xy 429.975111 -87.810386)
			(xy 430.045408 -87.818924) (xy 430.114163 -87.835875) (xy 430.180373 -87.860992) (xy 430.243072 -87.893908)
			(xy 430.301345 -87.934143) (xy 430.354341 -87.98111) (xy 430.401289 -88.034124) (xy 430.441503 -88.092412)
			(xy 430.474396 -88.155122) (xy 430.499489 -88.221341) (xy 430.516415 -88.290103) (xy 430.524927 -88.360403)
			(xy 430.525428 -88.39581) (xy 430.524997 -88.428682) (xy 430.517648 -88.494014) (xy 430.503032 -88.558113)
			(xy 430.481333 -88.620173) (xy 430.452824 -88.679414) (xy 430.417862 -88.735092) (xy 430.376888 -88.786506)
			(xy 430.353978 -88.810084) (xy 429.780192 -89.38387) (xy 429.756627 -89.406768) (xy 429.70525 -89.447732)
			(xy 429.649611 -89.482687) (xy 429.590407 -89.511192) (xy 429.528384 -89.53289) (xy 429.464322 -89.547508)
			(xy 429.399026 -89.554861) (xy 429.366172 -89.55532) (xy 429.297846 -89.55532) (xy 429.287825 -89.555758)
			(xy 429.269305 -89.563416) (xy 429.255131 -89.577584) (xy 429.247463 -89.596099) (xy 429.247046 -89.60612)
			(xy 429.247046 -89.617042) (xy 429.251364 -89.626948) (xy 429.26171 -89.651365) (xy 429.276285 -89.702352)
			(xy 429.283659 -89.754866) (xy 429.28413 -89.78138) (xy 429.283644 -89.808631) (xy 429.275888 -89.862579)
			(xy 429.260533 -89.914874) (xy 429.237891 -89.964451) (xy 429.208425 -90.010301) (xy 429.172734 -90.051492)
			(xy 429.131543 -90.087183) (xy 429.085693 -90.116649) (xy 429.036116 -90.139291) (xy 428.983821 -90.154646)
			(xy 428.929873 -90.162402) (xy 428.875371 -90.162402) (xy 428.821423 -90.154646) (xy 428.769128 -90.139291)
			(xy 428.719551 -90.116649) (xy 428.673701 -90.087183) (xy 428.63251 -90.051492) (xy 428.596819 -90.010301)
			(xy 428.567353 -89.964451) (xy 428.544711 -89.914874) (xy 428.529356 -89.862579) (xy 428.5216 -89.808631)
			(xy 428.521114 -89.78138) (xy 428.521596 -89.754867) (xy 428.528971 -89.702354) (xy 428.543547 -89.65137)
			(xy 428.55388 -89.626948) (xy 428.558198 -89.617042) (xy 428.558198 -89.60612) (xy 428.557764 -89.5961)
			(xy 428.5501 -89.577583) (xy 428.535932 -89.56341) (xy 428.517418 -89.55574) (xy 428.507398 -89.55532)
			(xy 428.471838 -89.55532) (xy 428.46177 -89.55576) (xy 428.443172 -89.56347) (xy 428.43577 -89.570306)
			(xy 427.32407 -90.682064) (xy 429.17821 -90.682064) (xy 429.182281 -90.626442) (xy 429.194407 -90.572005)
			(xy 429.21433 -90.519914) (xy 429.241626 -90.471279) (xy 429.275712 -90.427136) (xy 429.315861 -90.388427)
			(xy 429.361219 -90.355976) (xy 429.410819 -90.330475) (xy 429.463603 -90.312468) (xy 429.518446 -90.302338)
			(xy 429.57418 -90.300301) (xy 429.629617 -90.306401) (xy 429.683574 -90.320507) (xy 429.734903 -90.342319)
			(xy 429.782509 -90.371373) (xy 429.825377 -90.407048) (xy 429.862594 -90.448585) (xy 429.893367 -90.495098)
			(xy 429.917039 -90.545595) (xy 429.933107 -90.599002) (xy 429.941227 -90.654178) (xy 429.941736 -90.682064)
			(xy 429.941227 -90.70995) (xy 429.933107 -90.765126) (xy 429.917039 -90.818533) (xy 429.893367 -90.86903)
			(xy 429.862594 -90.915543) (xy 429.825377 -90.95708) (xy 429.782509 -90.992755) (xy 429.734903 -91.021809)
			(xy 429.683574 -91.043621) (xy 429.629617 -91.057727) (xy 429.57418 -91.063827) (xy 429.518446 -91.06179)
			(xy 429.463603 -91.05166) (xy 429.410819 -91.033653) (xy 429.361219 -91.008152) (xy 429.315861 -90.975701)
			(xy 429.275712 -90.936992) (xy 429.241626 -90.892849) (xy 429.21433 -90.844214) (xy 429.194407 -90.792123)
			(xy 429.182281 -90.737686) (xy 429.17821 -90.682064) (xy 427.32407 -90.682064) (xy 423.595546 -94.410784)
			(xy 423.588727 -94.418201) (xy 423.580993 -94.436787) (xy 423.58056 -94.446852) (xy 423.58056 -95.989648)
			(xy 423.864022 -95.989648) (xy 423.868093 -95.934026) (xy 423.880219 -95.879589) (xy 423.900142 -95.827498)
			(xy 423.927438 -95.778863) (xy 423.961524 -95.73472) (xy 424.001673 -95.696011) (xy 424.047031 -95.66356)
			(xy 424.096631 -95.638059) (xy 424.149415 -95.620052) (xy 424.204258 -95.609922) (xy 424.259992 -95.607885)
			(xy 424.315429 -95.613985) (xy 424.369386 -95.628091) (xy 424.420715 -95.649903) (xy 424.468321 -95.678957)
			(xy 424.511189 -95.714632) (xy 424.548406 -95.756169) (xy 424.579179 -95.802682) (xy 424.602851 -95.853179)
			(xy 424.618919 -95.906586) (xy 424.627039 -95.961762) (xy 424.627548 -95.989648) (xy 426.469554 -95.989648)
			(xy 426.473625 -95.934026) (xy 426.485751 -95.879589) (xy 426.505674 -95.827498) (xy 426.53297 -95.778863)
			(xy 426.567056 -95.73472) (xy 426.607205 -95.696011) (xy 426.652563 -95.66356) (xy 426.702163 -95.638059)
			(xy 426.754947 -95.620052) (xy 426.80979 -95.609922) (xy 426.865524 -95.607885) (xy 426.920961 -95.613985)
			(xy 426.974918 -95.628091) (xy 427.026247 -95.649903) (xy 427.073853 -95.678957) (xy 427.116721 -95.714632)
			(xy 427.153938 -95.756169) (xy 427.184711 -95.802682) (xy 427.208383 -95.853179) (xy 427.224451 -95.906586)
			(xy 427.232571 -95.961762) (xy 427.23308 -95.989648) (xy 427.232571 -96.017534) (xy 427.224451 -96.07271)
			(xy 427.208383 -96.126117) (xy 427.184711 -96.176614) (xy 427.153938 -96.223127) (xy 427.116721 -96.264664)
			(xy 427.073853 -96.300339) (xy 427.026247 -96.329393) (xy 426.974918 -96.351205) (xy 426.920961 -96.365311)
			(xy 426.865524 -96.371411) (xy 426.80979 -96.369374) (xy 426.754947 -96.359244) (xy 426.702163 -96.341237)
			(xy 426.652563 -96.315736) (xy 426.607205 -96.283285) (xy 426.567056 -96.244576) (xy 426.53297 -96.200433)
			(xy 426.505674 -96.151798) (xy 426.485751 -96.099707) (xy 426.473625 -96.04527) (xy 426.469554 -95.989648)
			(xy 424.627548 -95.989648) (xy 424.627039 -96.017534) (xy 424.618919 -96.07271) (xy 424.602851 -96.126117)
			(xy 424.579179 -96.176614) (xy 424.548406 -96.223127) (xy 424.511189 -96.264664) (xy 424.468321 -96.300339)
			(xy 424.420715 -96.329393) (xy 424.369386 -96.351205) (xy 424.315429 -96.365311) (xy 424.259992 -96.371411)
			(xy 424.204258 -96.369374) (xy 424.149415 -96.359244) (xy 424.096631 -96.341237) (xy 424.047031 -96.315736)
			(xy 424.001673 -96.283285) (xy 423.961524 -96.244576) (xy 423.927438 -96.200433) (xy 423.900142 -96.151798)
			(xy 423.880219 -96.099707) (xy 423.868093 -96.04527) (xy 423.864022 -95.989648) (xy 423.58056 -95.989648)
			(xy 423.58056 -96.264984) (xy 423.579942 -96.301734) (xy 423.570708 -96.374654) (xy 423.552419 -96.445843)
			(xy 423.525364 -96.514185) (xy 423.50817 -96.54667) (xy 423.507916 -96.546924) (xy 423.503377 -96.556441)
			(xy 423.501681 -96.577436) (xy 423.504614 -96.587564) (xy 423.529252 -96.658938) (xy 423.533189 -96.668898)
			(xy 423.547782 -96.684549) (xy 423.557446 -96.689164) (xy 423.582839 -96.700584) (xy 423.630327 -96.729648)
			(xy 423.673082 -96.76531) (xy 423.710196 -96.806811) (xy 423.740881 -96.853268) (xy 423.764482 -96.903693)
			(xy 423.780499 -96.957016) (xy 423.787643 -97.005648) (xy 426.469554 -97.005648) (xy 426.473625 -96.950026)
			(xy 426.485751 -96.895589) (xy 426.505674 -96.843498) (xy 426.53297 -96.794863) (xy 426.567056 -96.75072)
			(xy 426.607205 -96.712011) (xy 426.652563 -96.67956) (xy 426.702163 -96.654059) (xy 426.754947 -96.636052)
			(xy 426.80979 -96.625922) (xy 426.865524 -96.623885) (xy 426.920961 -96.629985) (xy 426.974918 -96.644091)
			(xy 427.026247 -96.665903) (xy 427.073853 -96.694957) (xy 427.116721 -96.730632) (xy 427.153938 -96.772169)
			(xy 427.184711 -96.818682) (xy 427.208383 -96.869179) (xy 427.224451 -96.922586) (xy 427.232571 -96.977762)
			(xy 427.23308 -97.005648) (xy 427.232571 -97.033534) (xy 427.224451 -97.08871) (xy 427.208383 -97.142117)
			(xy 427.184711 -97.192614) (xy 427.153938 -97.239127) (xy 427.116721 -97.280664) (xy 427.073853 -97.316339)
			(xy 427.026247 -97.345393) (xy 426.974918 -97.367205) (xy 426.920961 -97.381311) (xy 426.865524 -97.387411)
			(xy 426.80979 -97.385374) (xy 426.754947 -97.375244) (xy 426.702163 -97.357237) (xy 426.652563 -97.331736)
			(xy 426.607205 -97.299285) (xy 426.567056 -97.260576) (xy 426.53297 -97.216433) (xy 426.505674 -97.167798)
			(xy 426.485751 -97.115707) (xy 426.473625 -97.06127) (xy 426.469554 -97.005648) (xy 423.787643 -97.005648)
			(xy 423.788591 -97.0121) (xy 423.789094 -97.039938) (xy 423.788657 -97.067191) (xy 423.780895 -97.121141)
			(xy 423.765535 -97.173438) (xy 423.742888 -97.223016) (xy 423.713417 -97.268867) (xy 423.67772 -97.310057)
			(xy 423.636525 -97.345748) (xy 423.59067 -97.375213) (xy 423.541089 -97.397853) (xy 423.48879 -97.413207)
			(xy 423.434839 -97.420961) (xy 423.407586 -97.421446) (xy 423.381185 -97.421034) (xy 423.328891 -97.413727)
			(xy 423.278103 -97.399281) (xy 423.229791 -97.377973) (xy 423.184878 -97.350209) (xy 423.14422 -97.316519)
			(xy 423.108594 -97.277546) (xy 423.078679 -97.234035) (xy 423.066464 -97.210626) (xy 423.060455 -97.20022)
			(xy 423.041114 -97.186026) (xy 423.02938 -97.183448) (xy 422.947846 -97.169986) (xy 422.935844 -97.168799)
			(xy 422.912927 -97.176208) (xy 422.903904 -97.18421) (xy 422.86555 -97.222564) (xy 422.858744 -97.230046)
			(xy 422.851152 -97.248777) (xy 422.850818 -97.258886) (xy 422.851072 -97.331022) (xy 422.851563 -97.341054)
			(xy 422.85943 -97.359519) (xy 422.866312 -97.366836) (xy 422.866566 -97.36709) (xy 422.884453 -97.385085)
			(xy 422.915746 -97.425025) (xy 422.941469 -97.468761) (xy 422.961167 -97.51552) (xy 422.974494 -97.564478)
			(xy 422.981214 -97.61477) (xy 422.981628 -97.64014) (xy 422.981159 -97.667391) (xy 422.973398 -97.721339)
			(xy 422.958039 -97.773632) (xy 422.935394 -97.823209) (xy 422.905926 -97.869058) (xy 422.870233 -97.910247)
			(xy 422.829042 -97.945938) (xy 422.783191 -97.975404) (xy 422.733614 -97.998046) (xy 422.681319 -98.013402)
			(xy 422.627371 -98.021161) (xy 422.60012 -98.021648) (xy 422.574751 -98.021238) (xy 422.524461 -98.014515)
			(xy 422.475505 -98.001183) (xy 422.42875 -97.98148) (xy 422.385019 -97.955752) (xy 422.345084 -97.924453)
			(xy 422.32707 -97.906586) (xy 422.326816 -97.906332) (xy 422.319466 -97.899506) (xy 422.301018 -97.891675)
			(xy 422.291002 -97.891092) (xy 422.218866 -97.890838) (xy 422.208753 -97.891141) (xy 422.190021 -97.898751)
			(xy 422.182544 -97.90557) (xy 421.91694 -98.171) (xy 423.864022 -98.171) (xy 423.868093 -98.115378)
			(xy 423.880219 -98.060941) (xy 423.900142 -98.00885) (xy 423.927438 -97.960215) (xy 423.961524 -97.916072)
			(xy 424.001673 -97.877363) (xy 424.047031 -97.844912) (xy 424.096631 -97.819411) (xy 424.149415 -97.801404)
			(xy 424.204258 -97.791274) (xy 424.259992 -97.789237) (xy 424.315429 -97.795337) (xy 424.369386 -97.809443)
			(xy 424.420715 -97.831255) (xy 424.468321 -97.860309) (xy 424.511189 -97.895984) (xy 424.548406 -97.937521)
			(xy 424.579179 -97.984034) (xy 424.602851 -98.034531) (xy 424.618919 -98.087938) (xy 424.627039 -98.143114)
			(xy 424.627548 -98.171) (xy 424.627039 -98.198886) (xy 424.618919 -98.254062) (xy 424.602851 -98.307469)
			(xy 424.579179 -98.357966) (xy 424.548406 -98.404479) (xy 424.511189 -98.446016) (xy 424.468321 -98.481691)
			(xy 424.420715 -98.510745) (xy 424.369386 -98.532557) (xy 424.315429 -98.546663) (xy 424.259992 -98.552763)
			(xy 424.204258 -98.550726) (xy 424.149415 -98.540596) (xy 424.096631 -98.522589) (xy 424.047031 -98.497088)
			(xy 424.001673 -98.464637) (xy 423.961524 -98.425928) (xy 423.927438 -98.381785) (xy 423.900142 -98.33315)
			(xy 423.880219 -98.281059) (xy 423.868093 -98.226622) (xy 423.864022 -98.171) (xy 421.91694 -98.171)
			(xy 421.794686 -98.293174) (xy 421.787863 -98.300587) (xy 421.780134 -98.319177) (xy 421.7797 -98.329242)
			(xy 421.7797 -99.439984) (xy 423.610022 -99.439984) (xy 423.614093 -99.384362) (xy 423.626219 -99.329925)
			(xy 423.646142 -99.277834) (xy 423.673438 -99.229199) (xy 423.707524 -99.185056) (xy 423.747673 -99.146347)
			(xy 423.793031 -99.113896) (xy 423.842631 -99.088395) (xy 423.895415 -99.070388) (xy 423.950258 -99.060258)
			(xy 424.005992 -99.058221) (xy 424.061429 -99.064321) (xy 424.115386 -99.078427) (xy 424.166715 -99.100239)
			(xy 424.214321 -99.129293) (xy 424.257189 -99.164968) (xy 424.294406 -99.206505) (xy 424.325179 -99.253018)
			(xy 424.348851 -99.303515) (xy 424.364919 -99.356922) (xy 424.373039 -99.412098) (xy 424.373548 -99.439984)
			(xy 424.373039 -99.46787) (xy 424.364919 -99.523046) (xy 424.348851 -99.576453) (xy 424.325179 -99.62695)
			(xy 424.294406 -99.673463) (xy 424.257189 -99.715) (xy 424.214321 -99.750675) (xy 424.166715 -99.779729)
			(xy 424.115386 -99.801541) (xy 424.061429 -99.815647) (xy 424.005992 -99.821747) (xy 423.950258 -99.81971)
			(xy 423.895415 -99.80958) (xy 423.842631 -99.791573) (xy 423.793031 -99.766072) (xy 423.747673 -99.733621)
			(xy 423.707524 -99.694912) (xy 423.673438 -99.650769) (xy 423.646142 -99.602134) (xy 423.626219 -99.550043)
			(xy 423.614093 -99.495606) (xy 423.610022 -99.439984) (xy 421.7797 -99.439984) (xy 421.7797 -100.039932)
			(xy 422.176954 -100.039932) (xy 422.181025 -99.98431) (xy 422.193151 -99.929873) (xy 422.213074 -99.877782)
			(xy 422.24037 -99.829147) (xy 422.274456 -99.785004) (xy 422.314605 -99.746295) (xy 422.359963 -99.713844)
			(xy 422.409563 -99.688343) (xy 422.462347 -99.670336) (xy 422.51719 -99.660206) (xy 422.572924 -99.658169)
			(xy 422.628361 -99.664269) (xy 422.682318 -99.678375) (xy 422.733647 -99.700187) (xy 422.781253 -99.729241)
			(xy 422.824121 -99.764916) (xy 422.861338 -99.806453) (xy 422.892111 -99.852966) (xy 422.915783 -99.903463)
			(xy 422.931851 -99.95687) (xy 422.939971 -100.012046) (xy 422.94048 -100.039932) (xy 422.939971 -100.067818)
			(xy 422.931851 -100.122994) (xy 422.915783 -100.176401) (xy 422.892111 -100.226898) (xy 422.861338 -100.273411)
			(xy 422.824121 -100.314948) (xy 422.781253 -100.350623) (xy 422.733647 -100.379677) (xy 422.682318 -100.401489)
			(xy 422.628361 -100.415595) (xy 422.572924 -100.421695) (xy 422.51719 -100.419658) (xy 422.462347 -100.409528)
			(xy 422.409563 -100.391521) (xy 422.359963 -100.36602) (xy 422.314605 -100.333569) (xy 422.274456 -100.29486)
			(xy 422.24037 -100.250717) (xy 422.213074 -100.202082) (xy 422.193151 -100.149991) (xy 422.181025 -100.095554)
			(xy 422.176954 -100.039932) (xy 421.7797 -100.039932) (xy 421.7797 -101.240082) (xy 422.594022 -101.240082)
			(xy 422.598093 -101.18446) (xy 422.610219 -101.130023) (xy 422.630142 -101.077932) (xy 422.657438 -101.029297)
			(xy 422.691524 -100.985154) (xy 422.731673 -100.946445) (xy 422.777031 -100.913994) (xy 422.826631 -100.888493)
			(xy 422.879415 -100.870486) (xy 422.934258 -100.860356) (xy 422.989992 -100.858319) (xy 423.045429 -100.864419)
			(xy 423.099386 -100.878525) (xy 423.150715 -100.900337) (xy 423.198321 -100.929391) (xy 423.241189 -100.965066)
			(xy 423.278406 -101.006603) (xy 423.309179 -101.053116) (xy 423.316929 -101.069648) (xy 423.886374 -101.069648)
			(xy 423.890445 -101.014026) (xy 423.902571 -100.959589) (xy 423.922494 -100.907498) (xy 423.94979 -100.858863)
			(xy 423.983876 -100.81472) (xy 424.024025 -100.776011) (xy 424.069383 -100.74356) (xy 424.118983 -100.718059)
			(xy 424.171767 -100.700052) (xy 424.22661 -100.689922) (xy 424.282344 -100.687885) (xy 424.337781 -100.693985)
			(xy 424.391738 -100.708091) (xy 424.443067 -100.729903) (xy 424.490673 -100.758957) (xy 424.533541 -100.794632)
			(xy 424.570758 -100.836169) (xy 424.601531 -100.882682) (xy 424.625203 -100.933179) (xy 424.641271 -100.986586)
			(xy 424.649391 -101.041762) (xy 424.6499 -101.069648) (xy 426.469554 -101.069648) (xy 426.473625 -101.014026)
			(xy 426.485751 -100.959589) (xy 426.505674 -100.907498) (xy 426.53297 -100.858863) (xy 426.567056 -100.81472)
			(xy 426.607205 -100.776011) (xy 426.652563 -100.74356) (xy 426.702163 -100.718059) (xy 426.754947 -100.700052)
			(xy 426.80979 -100.689922) (xy 426.865524 -100.687885) (xy 426.920961 -100.693985) (xy 426.974918 -100.708091)
			(xy 427.026247 -100.729903) (xy 427.073853 -100.758957) (xy 427.116721 -100.794632) (xy 427.153938 -100.836169)
			(xy 427.184711 -100.882682) (xy 427.208383 -100.933179) (xy 427.224451 -100.986586) (xy 427.232571 -101.041762)
			(xy 427.23308 -101.069648) (xy 427.232571 -101.097534) (xy 427.224451 -101.15271) (xy 427.208383 -101.206117)
			(xy 427.184711 -101.256614) (xy 427.153938 -101.303127) (xy 427.116721 -101.344664) (xy 427.073853 -101.380339)
			(xy 427.026247 -101.409393) (xy 426.974918 -101.431205) (xy 426.920961 -101.445311) (xy 426.865524 -101.451411)
			(xy 426.80979 -101.449374) (xy 426.754947 -101.439244) (xy 426.702163 -101.421237) (xy 426.652563 -101.395736)
			(xy 426.607205 -101.363285) (xy 426.567056 -101.324576) (xy 426.53297 -101.280433) (xy 426.505674 -101.231798)
			(xy 426.485751 -101.179707) (xy 426.473625 -101.12527) (xy 426.469554 -101.069648) (xy 424.6499 -101.069648)
			(xy 424.649391 -101.097534) (xy 424.641271 -101.15271) (xy 424.625203 -101.206117) (xy 424.601531 -101.256614)
			(xy 424.570758 -101.303127) (xy 424.533541 -101.344664) (xy 424.490673 -101.380339) (xy 424.443067 -101.409393)
			(xy 424.391738 -101.431205) (xy 424.337781 -101.445311) (xy 424.282344 -101.451411) (xy 424.22661 -101.449374)
			(xy 424.171767 -101.439244) (xy 424.118983 -101.421237) (xy 424.069383 -101.395736) (xy 424.024025 -101.363285)
			(xy 423.983876 -101.324576) (xy 423.94979 -101.280433) (xy 423.922494 -101.231798) (xy 423.902571 -101.179707)
			(xy 423.890445 -101.12527) (xy 423.886374 -101.069648) (xy 423.316929 -101.069648) (xy 423.332851 -101.103613)
			(xy 423.348919 -101.15702) (xy 423.357039 -101.212196) (xy 423.357548 -101.240082) (xy 423.357039 -101.267968)
			(xy 423.348919 -101.323144) (xy 423.332851 -101.376551) (xy 423.309179 -101.427048) (xy 423.278406 -101.473561)
			(xy 423.241189 -101.515098) (xy 423.198321 -101.550773) (xy 423.150715 -101.579827) (xy 423.099386 -101.601639)
			(xy 423.045429 -101.615745) (xy 422.989992 -101.621845) (xy 422.934258 -101.619808) (xy 422.879415 -101.609678)
			(xy 422.826631 -101.591671) (xy 422.777031 -101.56617) (xy 422.731673 -101.533719) (xy 422.691524 -101.49501)
			(xy 422.657438 -101.450867) (xy 422.630142 -101.402232) (xy 422.610219 -101.350141) (xy 422.598093 -101.295704)
			(xy 422.594022 -101.240082) (xy 421.7797 -101.240082) (xy 421.7797 -102.489) (xy 423.102022 -102.489)
			(xy 423.106093 -102.433378) (xy 423.118219 -102.378941) (xy 423.138142 -102.32685) (xy 423.165438 -102.278215)
			(xy 423.199524 -102.234072) (xy 423.239673 -102.195363) (xy 423.285031 -102.162912) (xy 423.334631 -102.137411)
			(xy 423.387415 -102.119404) (xy 423.442258 -102.109274) (xy 423.497992 -102.107237) (xy 423.553429 -102.113337)
			(xy 423.607386 -102.127443) (xy 423.658715 -102.149255) (xy 423.706321 -102.178309) (xy 423.749189 -102.213984)
			(xy 423.786406 -102.255521) (xy 423.817179 -102.302034) (xy 423.840851 -102.352531) (xy 423.856919 -102.405938)
			(xy 423.865039 -102.461114) (xy 423.865548 -102.489) (xy 423.865039 -102.516886) (xy 423.856919 -102.572062)
			(xy 423.840851 -102.625469) (xy 423.817179 -102.675966) (xy 423.786406 -102.722479) (xy 423.749189 -102.764016)
			(xy 423.706321 -102.799691) (xy 423.658715 -102.828745) (xy 423.607386 -102.850557) (xy 423.553429 -102.864663)
			(xy 423.497992 -102.870763) (xy 423.442258 -102.868726) (xy 423.387415 -102.858596) (xy 423.334631 -102.840589)
			(xy 423.285031 -102.815088) (xy 423.239673 -102.782637) (xy 423.199524 -102.743928) (xy 423.165438 -102.699785)
			(xy 423.138142 -102.65115) (xy 423.118219 -102.599059) (xy 423.106093 -102.544622) (xy 423.102022 -102.489)
			(xy 421.7797 -102.489) (xy 421.7797 -103.886) (xy 423.610022 -103.886) (xy 423.614093 -103.830378)
			(xy 423.626219 -103.775941) (xy 423.646142 -103.72385) (xy 423.673438 -103.675215) (xy 423.707524 -103.631072)
			(xy 423.747673 -103.592363) (xy 423.793031 -103.559912) (xy 423.842631 -103.534411) (xy 423.895415 -103.516404)
			(xy 423.950258 -103.506274) (xy 424.005992 -103.504237) (xy 424.061429 -103.510337) (xy 424.115386 -103.524443)
			(xy 424.166715 -103.546255) (xy 424.214321 -103.575309) (xy 424.257189 -103.610984) (xy 424.294406 -103.652521)
			(xy 424.325179 -103.699034) (xy 424.348851 -103.749531) (xy 424.364919 -103.802938) (xy 424.373039 -103.858114)
			(xy 424.373548 -103.886) (xy 424.373039 -103.913886) (xy 424.364919 -103.969062) (xy 424.348851 -104.022469)
			(xy 424.325179 -104.072966) (xy 424.294406 -104.119479) (xy 424.257189 -104.161016) (xy 424.214321 -104.196691)
			(xy 424.166715 -104.225745) (xy 424.115386 -104.247557) (xy 424.061429 -104.261663) (xy 424.005992 -104.267763)
			(xy 423.950258 -104.265726) (xy 423.895415 -104.255596) (xy 423.842631 -104.237589) (xy 423.793031 -104.212088)
			(xy 423.747673 -104.179637) (xy 423.707524 -104.140928) (xy 423.673438 -104.096785) (xy 423.646142 -104.04815)
			(xy 423.626219 -103.996059) (xy 423.614093 -103.941622) (xy 423.610022 -103.886) (xy 421.7797 -103.886)
			(xy 421.7797 -104.356154) (xy 421.780123 -104.366224) (xy 421.787843 -104.384823) (xy 421.794686 -104.392222)
			(xy 422.418256 -105.015538) (xy 422.441157 -105.039132) (xy 422.482153 -105.09054) (xy 422.517142 -105.146211)
			(xy 422.545684 -105.205446) (xy 422.567421 -105.267502) (xy 422.582081 -105.3316) (xy 422.589479 -105.396936)
			(xy 422.58996 -105.429812) (xy 422.58996 -108.929932) (xy 422.614852 -108.95838) (xy 422.633902 -108.96092)
			(xy 422.660093 -108.964899) (xy 422.71112 -108.979128) (xy 422.759687 -109.000283) (xy 422.804859 -109.027957)
			(xy 422.845765 -109.061617) (xy 422.864026 -109.080808) (xy 422.871535 -109.088224) (xy 422.890825 -109.09674)
			(xy 422.901364 -109.097318) (xy 422.97604 -109.097318) (xy 422.986587 -109.096765) (xy 423.005882 -109.088246)
			(xy 423.013378 -109.080808) (xy 423.031553 -109.061772) (xy 423.072178 -109.028312) (xy 423.117014 -109.000751)
			(xy 423.165211 -108.979609) (xy 423.215856 -108.965288) (xy 423.267987 -108.958059) (xy 423.294302 -108.957618)
			(xy 423.321556 -108.958054) (xy 423.375509 -108.965811) (xy 423.427809 -108.981169) (xy 423.477391 -109.003814)
			(xy 423.523246 -109.033284) (xy 423.564439 -109.068981) (xy 423.600132 -109.110177) (xy 423.6296 -109.156033)
			(xy 423.652241 -109.205617) (xy 423.667594 -109.257918) (xy 423.675348 -109.311872) (xy 423.67581 -109.339126)
			(xy 423.675299 -109.367865) (xy 423.666673 -109.424693) (xy 423.64962 -109.479584) (xy 423.624526 -109.531295)
			(xy 423.591958 -109.578657) (xy 423.572686 -109.599984) (xy 423.566082 -109.606842) (xy 423.55897 -109.624876)
			(xy 423.55897 -109.713776) (xy 423.566082 -109.73181) (xy 423.572686 -109.738668) (xy 423.591982 -109.759973)
			(xy 423.624546 -109.807339) (xy 423.649635 -109.859055) (xy 423.666683 -109.913949) (xy 423.675303 -109.970779)
			(xy 423.6753 -110.028259) (xy 423.666674 -110.085088) (xy 423.649621 -110.139981) (xy 423.624527 -110.191694)
			(xy 423.591958 -110.239057) (xy 423.572686 -110.260384) (xy 423.566082 -110.267242) (xy 423.55897 -110.285276)
			(xy 423.55897 -110.374176) (xy 423.566082 -110.39221) (xy 423.572686 -110.399068) (xy 423.591982 -110.420373)
			(xy 423.624546 -110.467739) (xy 423.649635 -110.519455) (xy 423.666683 -110.574349) (xy 423.675303 -110.631179)
			(xy 423.6753 -110.688659) (xy 423.666674 -110.745488) (xy 423.649621 -110.800381) (xy 423.624527 -110.852094)
			(xy 423.591958 -110.899457) (xy 423.572686 -110.920784) (xy 423.566082 -110.927642) (xy 423.55897 -110.945676)
			(xy 423.55897 -111.034576) (xy 423.566082 -111.05261) (xy 423.572686 -111.059468) (xy 423.591982 -111.080773)
			(xy 423.624546 -111.128139) (xy 423.649635 -111.179855) (xy 423.666683 -111.234749) (xy 423.675303 -111.291579)
			(xy 423.6753 -111.349059) (xy 423.666674 -111.405888) (xy 423.649621 -111.460781) (xy 423.624527 -111.512494)
			(xy 423.591958 -111.559857) (xy 423.572686 -111.581184) (xy 423.566082 -111.588042) (xy 423.55897 -111.606076)
			(xy 423.55897 -111.694976) (xy 423.566082 -111.71301) (xy 423.572686 -111.719868) (xy 423.591973 -111.741181)
			(xy 423.624536 -111.788547) (xy 423.649625 -111.840262) (xy 423.666672 -111.895156) (xy 423.675291 -111.951986)
			(xy 423.67581 -111.980726) (xy 423.675346 -112.007978) (xy 423.667586 -112.061926) (xy 423.652228 -112.114221)
			(xy 423.629584 -112.163798) (xy 423.600115 -112.209649) (xy 423.564421 -112.250838) (xy 423.523229 -112.28653)
			(xy 423.477377 -112.315996) (xy 423.427799 -112.338636) (xy 423.375503 -112.353991) (xy 423.321554 -112.361748)
			(xy 423.294302 -112.362234) (xy 423.267989 -112.361754) (xy 423.215861 -112.35452) (xy 423.165219 -112.340203)
			(xy 423.11702 -112.319073) (xy 423.072176 -112.291529) (xy 423.031536 -112.258094) (xy 423.013378 -112.239044)
			(xy 423.005861 -112.231637) (xy 422.986578 -112.223114) (xy 422.97604 -112.222534) (xy 422.901364 -112.222534)
			(xy 422.890815 -112.223074) (xy 422.871519 -112.2316) (xy 422.864026 -112.239044) (xy 422.845859 -112.258088)
			(xy 422.805231 -112.291545) (xy 422.760393 -112.319104) (xy 422.712194 -112.340244) (xy 422.661549 -112.354564)
			(xy 422.609417 -112.361793) (xy 422.583102 -112.362234) (xy 422.582086 -112.362234) (xy 422.572407 -112.362681)
			(xy 422.554417 -112.369827) (xy 422.540332 -112.383105) (xy 422.535858 -112.391698) (xy 422.520971 -112.422778)
			(xy 422.484947 -112.481527) (xy 422.442271 -112.535639) (xy 422.418256 -112.560354) (xy 421.003476 -113.975134)
			(xy 420.979923 -113.998045) (xy 420.928545 -114.039012) (xy 420.872904 -114.073968) (xy 420.813699 -114.102475)
			(xy 420.751674 -114.124173) (xy 420.687609 -114.13879) (xy 420.622311 -114.146143) (xy 420.589456 -114.146584)
			(xy 420.035228 -114.146584) (xy 420.025157 -114.147002) (xy 420.006558 -114.154725) (xy 419.99916 -114.16157)
			(xy 419.456616 -114.704368) (xy 419.433045 -114.727293) (xy 419.381633 -114.768287) (xy 419.325958 -114.803273)
			(xy 419.266718 -114.831811) (xy 419.204659 -114.853545) (xy 419.140558 -114.8682) (xy 419.075219 -114.875593)
			(xy 419.042342 -114.876072) (xy 419.006929 -114.875525) (xy 418.936618 -114.866992) (xy 418.867848 -114.850046)
			(xy 418.801623 -114.824934) (xy 418.738907 -114.792022) (xy 418.680616 -114.751791) (xy 418.6276 -114.704826)
			(xy 418.580632 -114.651812) (xy 418.540396 -114.593524) (xy 418.50748 -114.53081) (xy 418.482364 -114.464586)
			(xy 418.465414 -114.395818) (xy 418.456877 -114.325507) (xy 418.456364 -114.290094) (xy 418.456781 -114.257212)
			(xy 418.46415 -114.191863) (xy 418.478794 -114.12775) (xy 418.500529 -114.065682) (xy 418.529082 -114.00644)
			(xy 418.564092 -113.95077) (xy 418.605119 -113.899373) (xy 418.628068 -113.87582) (xy 418.999924 -113.503964)
			(xy 419.008366 -113.494733) (xy 419.015835 -113.470892) (xy 419.014148 -113.458498) (xy 418.996114 -113.363756)
			(xy 418.98062 -113.344198) (xy 418.968936 -113.339118) (xy 418.943835 -113.327577) (xy 418.896966 -113.298332)
			(xy 418.854805 -113.262633) (xy 418.818234 -113.221227) (xy 418.788017 -113.174978) (xy 418.764787 -113.124855)
			(xy 418.74903 -113.071905) (xy 418.741074 -113.017236) (xy 418.74059 -112.989614) (xy 418.741068 -112.962362)
			(xy 418.748823 -112.908411) (xy 418.764178 -112.856114) (xy 418.786818 -112.806534) (xy 418.816285 -112.760681)
			(xy 418.851977 -112.719488) (xy 418.893168 -112.683794) (xy 418.93902 -112.654326) (xy 418.988599 -112.631683)
			(xy 419.040896 -112.616327) (xy 419.094846 -112.608569) (xy 419.122098 -112.608106) (xy 419.148373 -112.608481)
			(xy 419.200428 -112.615681) (xy 419.251001 -112.629958) (xy 419.299136 -112.651042) (xy 419.343921 -112.678534)
			(xy 419.384508 -112.711913) (xy 419.42013 -112.750547) (xy 419.45011 -112.793706) (xy 419.473883 -112.840572)
			(xy 419.490997 -112.890257) (xy 419.496494 -112.915954) (xy 419.498526 -112.926368) (xy 419.51021 -112.94364)
			(xy 419.582092 -112.988344) (xy 419.591123 -112.993416) (xy 419.611577 -112.996559) (xy 419.621716 -112.99444)
			(xy 419.62197 -112.99444) (xy 419.658454 -112.985421) (xy 419.732983 -112.975743) (xy 419.77056 -112.975136)
			(xy 420.32555 -112.975136) (xy 420.335619 -112.974702) (xy 420.354218 -112.966989) (xy 420.361618 -112.96015)
			(xy 421.403018 -111.918496) (xy 421.409855 -111.911093) (xy 421.417576 -111.892496) (xy 421.418004 -111.882428)
			(xy 421.418004 -109.00156) (xy 421.417366 -108.990241) (xy 421.407605 -108.969808) (xy 421.399208 -108.96219)
			(xy 421.329358 -108.905294) (xy 421.307006 -108.89996) (xy 421.29583 -108.902246) (xy 421.266201 -108.908069)
			(xy 421.206136 -108.914304) (xy 421.175942 -108.914692) (xy 420.197026 -108.914692) (xy 420.186955 -108.915106)
			(xy 420.168356 -108.922832) (xy 420.160958 -108.929678) (xy 419.11016 -109.980476) (xy 419.103859 -109.987418)
			(xy 419.096309 -110.004559) (xy 419.095422 -110.023269) (xy 419.097968 -110.032292) (xy 419.130734 -110.132114)
			(xy 419.152578 -110.150656) (xy 419.167056 -110.152688) (xy 419.193855 -110.157198) (xy 419.245934 -110.172711)
			(xy 419.295286 -110.195455) (xy 419.340912 -110.224971) (xy 419.38189 -110.26066) (xy 419.417389 -110.301803)
			(xy 419.446694 -110.347565) (xy 419.469209 -110.397021) (xy 419.484481 -110.449172) (xy 419.492199 -110.502962)
			(xy 419.492684 -110.530132) (xy 419.492252 -110.557385) (xy 419.48449 -110.611336) (xy 419.46913 -110.663633)
			(xy 419.446483 -110.713212) (xy 419.417012 -110.759064) (xy 419.381314 -110.800254) (xy 419.340119 -110.835945)
			(xy 419.294263 -110.86541) (xy 419.244681 -110.88805) (xy 419.192381 -110.903402) (xy 419.138429 -110.911156)
			(xy 419.111176 -110.91164) (xy 419.084 -110.911197) (xy 419.030198 -110.903494) (xy 418.978033 -110.888232)
			(xy 418.928563 -110.86572) (xy 418.882789 -110.836415) (xy 418.841638 -110.800909) (xy 418.805943 -110.759922)
			(xy 418.776426 -110.714284) (xy 418.753687 -110.664918) (xy 418.738184 -110.612825) (xy 418.733732 -110.586012)
			(xy 418.7317 -110.571534) (xy 418.713158 -110.54969) (xy 418.613336 -110.516924) (xy 418.604322 -110.514342)
			(xy 418.585606 -110.515247) (xy 418.568461 -110.522809) (xy 418.56152 -110.529116) (xy 417.797234 -111.293148)
			(xy 417.790429 -111.300576) (xy 417.782688 -111.319154) (xy 417.782248 -111.329216) (xy 417.782248 -111.884206)
			(xy 418.664388 -111.884206) (xy 418.668459 -111.828584) (xy 418.680585 -111.774147) (xy 418.700508 -111.722056)
			(xy 418.727804 -111.673421) (xy 418.76189 -111.629278) (xy 418.802039 -111.590569) (xy 418.847397 -111.558118)
			(xy 418.896997 -111.532617) (xy 418.949781 -111.51461) (xy 419.004624 -111.50448) (xy 419.060358 -111.502443)
			(xy 419.115795 -111.508543) (xy 419.169752 -111.522649) (xy 419.221081 -111.544461) (xy 419.268687 -111.573515)
			(xy 419.311555 -111.60919) (xy 419.348772 -111.650727) (xy 419.379545 -111.69724) (xy 419.403217 -111.747737)
			(xy 419.419285 -111.801144) (xy 419.427405 -111.85632) (xy 419.427914 -111.884206) (xy 419.427405 -111.912092)
			(xy 419.419285 -111.967268) (xy 419.403217 -112.020675) (xy 419.379545 -112.071172) (xy 419.348772 -112.117685)
			(xy 419.311555 -112.159222) (xy 419.268687 -112.194897) (xy 419.221081 -112.223951) (xy 419.169752 -112.245763)
			(xy 419.115795 -112.259869) (xy 419.060358 -112.265969) (xy 419.004624 -112.263932) (xy 418.949781 -112.253802)
			(xy 418.896997 -112.235795) (xy 418.847397 -112.210294) (xy 418.802039 -112.177843) (xy 418.76189 -112.139134)
			(xy 418.727804 -112.094991) (xy 418.700508 -112.046356) (xy 418.680585 -111.994265) (xy 418.668459 -111.939828)
			(xy 418.664388 -111.884206) (xy 417.782248 -111.884206) (xy 417.782248 -112.010444) (xy 417.78263 -112.019419)
			(xy 417.788873 -112.036251) (xy 417.800514 -112.049918) (xy 417.808156 -112.05464) (xy 417.898072 -112.104932)
			(xy 417.92525 -112.104424) (xy 417.937188 -112.097058) (xy 417.959832 -112.083643) (xy 418.008006 -112.062449)
			(xy 418.058641 -112.048095) (xy 418.110771 -112.040855) (xy 418.137086 -112.040416) (xy 418.164341 -112.04083)
			(xy 418.218297 -112.048586) (xy 418.2706 -112.063942) (xy 418.320185 -112.086585) (xy 418.366043 -112.116054)
			(xy 418.40724 -112.15175) (xy 418.442937 -112.192946) (xy 418.472409 -112.238803) (xy 418.495054 -112.288387)
			(xy 418.510411 -112.340689) (xy 418.518169 -112.394645) (xy 418.518169 -112.449155) (xy 418.510411 -112.503111)
			(xy 418.495054 -112.555413) (xy 418.472409 -112.604997) (xy 418.442937 -112.650854) (xy 418.40724 -112.69205)
			(xy 418.366043 -112.727746) (xy 418.320185 -112.757215) (xy 418.2706 -112.779858) (xy 418.218297 -112.795214)
			(xy 418.164341 -112.80297) (xy 418.137086 -112.803432) (xy 418.110774 -112.802947) (xy 418.058653 -112.795686)
			(xy 418.00802 -112.781346) (xy 417.959833 -112.760196) (xy 417.937188 -112.74679) (xy 417.929345 -112.742354)
			(xy 417.911685 -112.738832) (xy 417.893902 -112.741669) (xy 417.88588 -112.745774) (xy 417.808156 -112.789208)
			(xy 417.800466 -112.793873) (xy 417.788793 -112.807543) (xy 417.78259 -112.824415) (xy 417.782248 -112.833404)
			(xy 417.782248 -112.980724) (xy 417.782953 -112.992884) (xy 417.794082 -113.014507) (xy 417.803584 -113.022126)
			(xy 417.8808 -113.077244) (xy 417.90493 -113.0808) (xy 417.916614 -113.076736) (xy 417.946335 -113.067282)
			(xy 418.00786 -113.057077) (xy 418.039042 -113.056416) (xy 418.039804 -113.056416) (xy 418.067057 -113.056854)
			(xy 418.121007 -113.064612) (xy 418.173305 -113.079968) (xy 418.222885 -113.102611) (xy 418.268738 -113.132079)
			(xy 418.30993 -113.167773) (xy 418.345623 -113.208966) (xy 418.375091 -113.254819) (xy 418.397733 -113.304399)
			(xy 418.413089 -113.356696) (xy 418.420846 -113.410647) (xy 418.420846 -113.465153) (xy 418.413089 -113.519104)
			(xy 418.397733 -113.571401) (xy 418.375091 -113.620981) (xy 418.345623 -113.666834) (xy 418.30993 -113.708027)
			(xy 418.268738 -113.743721) (xy 418.222885 -113.773189) (xy 418.173305 -113.795832) (xy 418.121007 -113.811188)
			(xy 418.067057 -113.818946) (xy 418.039804 -113.819432) (xy 418.039042 -113.819432) (xy 418.007859 -113.818785)
			(xy 417.946334 -113.808573) (xy 417.916614 -113.799112) (xy 417.90493 -113.795048) (xy 417.8808 -113.798604)
			(xy 417.803584 -113.853722) (xy 417.794069 -113.861329) (xy 417.782935 -113.88296) (xy 417.782248 -113.895124)
			(xy 417.782248 -114.249454) (xy 417.781821 -114.282309) (xy 417.774451 -114.347603) (xy 417.759822 -114.411663)
			(xy 417.738118 -114.473685) (xy 417.70961 -114.532888) (xy 417.674657 -114.58853) (xy 417.633698 -114.639911)
			(xy 417.610798 -114.663474) (xy 416.913314 -115.360958) (xy 422.41851 -115.360958) (xy 422.419008 -115.333589)
			(xy 422.426817 -115.279411) (xy 422.442299 -115.226908) (xy 422.465134 -115.177161) (xy 422.494852 -115.131193)
			(xy 422.51249 -115.11026) (xy 422.512744 -115.110006) (xy 422.51834 -115.102926) (xy 422.52458 -115.086004)
			(xy 422.524936 -115.076986) (xy 422.524936 -115.00993) (xy 422.524557 -115.000916) (xy 422.518324 -114.983999)
			(xy 422.512744 -114.97691) (xy 422.51249 -114.97691) (xy 422.51249 -114.976656) (xy 422.494862 -114.955715)
			(xy 422.465149 -114.909744) (xy 422.442311 -114.859999) (xy 422.426817 -114.807501) (xy 422.418986 -114.753327)
			(xy 422.41851 -114.725958) (xy 422.418939 -114.698705) (xy 422.426701 -114.644754) (xy 422.442063 -114.592457)
			(xy 422.46471 -114.542879) (xy 422.494183 -114.497028) (xy 422.52988 -114.455837) (xy 422.571076 -114.420147)
			(xy 422.616931 -114.390681) (xy 422.666514 -114.368042) (xy 422.718813 -114.352689) (xy 422.772765 -114.344935)
			(xy 422.800018 -114.34445) (xy 422.827389 -114.344893) (xy 422.88157 -114.352715) (xy 422.934074 -114.368208)
			(xy 422.98382 -114.391056) (xy 423.029786 -114.420786) (xy 423.050716 -114.43843) (xy 423.05097 -114.438684)
			(xy 423.058062 -114.444262) (xy 423.074975 -114.450514) (xy 423.08399 -114.450876) (xy 423.151046 -114.450876)
			(xy 423.160061 -114.450498) (xy 423.176978 -114.444266) (xy 423.184066 -114.438684) (xy 423.184066 -114.43843)
			(xy 423.18432 -114.43843) (xy 423.205275 -114.42082) (xy 423.251241 -114.391102) (xy 423.300983 -114.36826)
			(xy 423.353478 -114.352763) (xy 423.40765 -114.344928) (xy 423.435018 -114.34445) (xy 423.462268 -114.344961)
			(xy 423.516212 -114.352719) (xy 423.568504 -114.368074) (xy 423.618079 -114.390714) (xy 423.663927 -114.420179)
			(xy 423.705116 -114.455867) (xy 423.740807 -114.497054) (xy 423.770274 -114.5429) (xy 423.792918 -114.592473)
			(xy 423.808276 -114.644764) (xy 423.816037 -114.698708) (xy 423.816526 -114.725958) (xy 423.816053 -114.753328)
			(xy 423.80824 -114.807508) (xy 423.792753 -114.860011) (xy 423.769913 -114.909759) (xy 423.740188 -114.955725)
			(xy 423.722546 -114.976656) (xy 423.722292 -114.97691) (xy 423.716694 -114.983989) (xy 423.710455 -115.000912)
			(xy 423.7101 -115.00993) (xy 423.7101 -115.076986) (xy 423.710464 -115.086002) (xy 423.716707 -115.102919)
			(xy 423.722292 -115.110006) (xy 423.722546 -115.110006) (xy 423.722546 -115.11026) (xy 423.740171 -115.131203)
			(xy 423.769887 -115.177172) (xy 423.792727 -115.226917) (xy 423.808221 -115.279415) (xy 423.816051 -115.333589)
			(xy 423.816526 -115.360958) (xy 423.816006 -115.388209) (xy 423.808255 -115.442157) (xy 423.792905 -115.494453)
			(xy 423.770269 -115.544031) (xy 423.740807 -115.589884) (xy 423.705119 -115.631077) (xy 423.663932 -115.666771)
			(xy 423.618084 -115.69624) (xy 423.568509 -115.718884) (xy 423.516216 -115.734242) (xy 423.462269 -115.742001)
			(xy 423.435018 -115.742466) (xy 423.407648 -115.741998) (xy 423.353468 -115.734182) (xy 423.300965 -115.718694)
			(xy 423.251218 -115.695852) (xy 423.205251 -115.666127) (xy 423.18432 -115.648486) (xy 423.184066 -115.648232)
			(xy 423.176971 -115.642659) (xy 423.16006 -115.636406) (xy 423.151046 -115.63604) (xy 423.08399 -115.63604)
			(xy 423.074972 -115.636383) (xy 423.058054 -115.642639) (xy 423.05097 -115.648232) (xy 423.05097 -115.648486)
			(xy 423.050716 -115.648486) (xy 423.029787 -115.666129) (xy 422.983814 -115.695841) (xy 422.934065 -115.718676)
			(xy 422.881564 -115.734166) (xy 422.827387 -115.741993) (xy 422.800018 -115.742466) (xy 422.772764 -115.742028)
			(xy 422.71881 -115.734272) (xy 422.666509 -115.718916) (xy 422.616926 -115.696273) (xy 422.571071 -115.666803)
			(xy 422.529877 -115.631106) (xy 422.494183 -115.58991) (xy 422.464716 -115.544053) (xy 422.442075 -115.494469)
			(xy 422.426723 -115.442167) (xy 422.41897 -115.388212) (xy 422.41851 -115.360958) (xy 416.913314 -115.360958)
			(xy 416.574224 -115.700048) (xy 416.550646 -115.722966) (xy 416.499235 -115.763961) (xy 416.443562 -115.798948)
			(xy 416.384324 -115.827488) (xy 416.322265 -115.849222) (xy 416.258165 -115.863879) (xy 416.192827 -115.871273)
			(xy 416.15995 -115.871752) (xy 415.612834 -115.871752) (xy 415.577431 -115.871212) (xy 415.50714 -115.862683)
			(xy 415.438389 -115.845745) (xy 415.37218 -115.820646) (xy 415.309479 -115.787751) (xy 415.251198 -115.747539)
			(xy 415.198189 -115.700596) (xy 415.151223 -115.647608) (xy 415.110985 -115.589346) (xy 415.078062 -115.526659)
			(xy 415.052933 -115.460462) (xy 415.035964 -115.391718) (xy 415.027404 -115.321431) (xy 415.026856 -115.286028)
			(xy 415.026856 -115.28552) (xy 415.027364 -115.26774) (xy 415.027364 -115.267486) (xy 415.027218 -115.258027)
			(xy 415.020795 -115.240247) (xy 415.008376 -115.225992) (xy 415.000186 -115.221258) (xy 414.919414 -115.178586)
			(xy 414.910802 -115.174486) (xy 414.891864 -115.172347) (xy 414.87346 -115.177297) (xy 414.865566 -115.18265)
			(xy 414.840853 -115.200123) (xy 414.787041 -115.227825) (xy 414.729532 -115.246688) (xy 414.669768 -115.256239)
			(xy 414.639506 -115.256818) (xy 414.612254 -115.256335) (xy 414.558303 -115.248579) (xy 414.506006 -115.233224)
			(xy 414.456427 -115.210582) (xy 414.410574 -115.181115) (xy 414.369382 -115.145423) (xy 414.333688 -115.104231)
			(xy 414.304221 -115.058379) (xy 414.281578 -115.008799) (xy 414.266222 -114.956502) (xy 414.258465 -114.902552)
			(xy 412.3148 -114.902552) (xy 412.173674 -115.643152) (xy 412.173674 -115.64366) (xy 412.172912 -115.652804)
			(xy 412.183834 -115.684046) (xy 412.18866 -115.690396) (xy 412.203439 -115.710437) (xy 412.228236 -115.753619)
			(xy 412.247209 -115.799658) (xy 412.260037 -115.847773) (xy 412.266504 -115.897146) (xy 412.266892 -115.922044)
			(xy 412.266379 -115.950638) (xy 412.257838 -116.007185) (xy 412.240955 -116.061824) (xy 412.216107 -116.113332)
			(xy 412.183851 -116.160556) (xy 412.144909 -116.202436) (xy 412.100153 -116.238037) (xy 412.07563 -116.252752)
			(xy 412.06547 -116.258594) (xy 412.059628 -116.266976) (xy 412.056683 -116.271318) (xy 412.052459 -116.280921)
			(xy 412.051246 -116.286026) (xy 412.02042 -116.44757) (xy 414.457132 -116.44757) (xy 414.461203 -116.391948)
			(xy 414.473329 -116.337511) (xy 414.493252 -116.28542) (xy 414.520548 -116.236785) (xy 414.554634 -116.192642)
			(xy 414.594783 -116.153933) (xy 414.640141 -116.121482) (xy 414.689741 -116.095981) (xy 414.742525 -116.077974)
			(xy 414.797368 -116.067844) (xy 414.853102 -116.065807) (xy 414.908539 -116.071907) (xy 414.962496 -116.086013)
			(xy 415.013825 -116.107825) (xy 415.061431 -116.136879) (xy 415.104299 -116.172554) (xy 415.141516 -116.214091)
			(xy 415.172289 -116.260604) (xy 415.195961 -116.311101) (xy 415.212029 -116.364508) (xy 415.220149 -116.419684)
			(xy 415.220658 -116.44757) (xy 415.220149 -116.475456) (xy 415.219879 -116.477288) (xy 419.604442 -116.477288)
			(xy 419.608513 -116.421666) (xy 419.620639 -116.367229) (xy 419.640562 -116.315138) (xy 419.667858 -116.266503)
			(xy 419.701944 -116.22236) (xy 419.742093 -116.183651) (xy 419.787451 -116.1512) (xy 419.837051 -116.125699)
			(xy 419.889835 -116.107692) (xy 419.944678 -116.097562) (xy 420.000412 -116.095525) (xy 420.055849 -116.101625)
			(xy 420.109806 -116.115731) (xy 420.161135 -116.137543) (xy 420.208741 -116.166597) (xy 420.251609 -116.202272)
			(xy 420.288826 -116.243809) (xy 420.319599 -116.290322) (xy 420.343271 -116.340819) (xy 420.359339 -116.394226)
			(xy 420.367459 -116.449402) (xy 420.367968 -116.477288) (xy 420.367459 -116.505174) (xy 420.359339 -116.56035)
			(xy 420.343271 -116.613757) (xy 420.319599 -116.664254) (xy 420.288826 -116.710767) (xy 420.251609 -116.752304)
			(xy 420.208741 -116.787979) (xy 420.161135 -116.817033) (xy 420.109806 -116.838845) (xy 420.055849 -116.852951)
			(xy 420.000412 -116.859051) (xy 419.944678 -116.857014) (xy 419.889835 -116.846884) (xy 419.837051 -116.828877)
			(xy 419.787451 -116.803376) (xy 419.742093 -116.770925) (xy 419.701944 -116.732216) (xy 419.667858 -116.688073)
			(xy 419.640562 -116.639438) (xy 419.620639 -116.587347) (xy 419.608513 -116.53291) (xy 419.604442 -116.477288)
			(xy 415.219879 -116.477288) (xy 415.212029 -116.530632) (xy 415.195961 -116.584039) (xy 415.172289 -116.634536)
			(xy 415.141516 -116.681049) (xy 415.104299 -116.722586) (xy 415.061431 -116.758261) (xy 415.013825 -116.787315)
			(xy 414.962496 -116.809127) (xy 414.908539 -116.823233) (xy 414.853102 -116.829333) (xy 414.797368 -116.827296)
			(xy 414.742525 -116.817166) (xy 414.689741 -116.799159) (xy 414.640141 -116.773658) (xy 414.594783 -116.741207)
			(xy 414.554634 -116.702498) (xy 414.520548 -116.658355) (xy 414.493252 -116.60972) (xy 414.473329 -116.557629)
			(xy 414.461203 -116.503192) (xy 414.457132 -116.44757) (xy 412.02042 -116.44757) (xy 411.929834 -116.922296)
			(xy 411.844236 -117.371622) (xy 411.844236 -117.371876) (xy 411.843982 -117.373654) (xy 411.801742 -117.723666)
			(xy 417.989764 -117.723666) (xy 417.993835 -117.668044) (xy 418.005961 -117.613607) (xy 418.025884 -117.561516)
			(xy 418.05318 -117.512881) (xy 418.087266 -117.468738) (xy 418.127415 -117.430029) (xy 418.172773 -117.397578)
			(xy 418.222373 -117.372077) (xy 418.275157 -117.35407) (xy 418.33 -117.34394) (xy 418.385734 -117.341903)
			(xy 418.441171 -117.348003) (xy 418.495128 -117.362109) (xy 418.546457 -117.383921) (xy 418.594063 -117.412975)
			(xy 418.636931 -117.44865) (xy 418.674148 -117.490187) (xy 418.704921 -117.5367) (xy 418.728593 -117.587197)
			(xy 418.744661 -117.640604) (xy 418.752781 -117.69578) (xy 418.75329 -117.723666) (xy 418.752781 -117.751552)
			(xy 418.751652 -117.759226) (xy 422.774872 -117.759226) (xy 422.774872 -116.895626) (xy 422.775362 -116.865642)
			(xy 422.78319 -116.806186) (xy 422.798711 -116.748261) (xy 422.82166 -116.692857) (xy 422.851644 -116.640923)
			(xy 422.88815 -116.593347) (xy 422.930555 -116.550942) (xy 422.978131 -116.514436) (xy 423.030065 -116.484452)
			(xy 423.085469 -116.461503) (xy 423.143394 -116.445982) (xy 423.20285 -116.438154) (xy 423.262818 -116.438154)
			(xy 423.322274 -116.445982) (xy 423.380199 -116.461503) (xy 423.435603 -116.484452) (xy 423.487537 -116.514436)
			(xy 423.535113 -116.550942) (xy 423.577518 -116.593347) (xy 423.614024 -116.640923) (xy 423.644008 -116.692857)
			(xy 423.666957 -116.748261) (xy 423.682478 -116.806186) (xy 423.690306 -116.865642) (xy 423.690796 -116.895626)
			(xy 423.690796 -117.759226) (xy 423.690306 -117.78921) (xy 423.682478 -117.848666) (xy 423.666957 -117.906591)
			(xy 423.644008 -117.961995) (xy 423.614024 -118.013929) (xy 423.577518 -118.061505) (xy 423.535113 -118.10391)
			(xy 423.487537 -118.140416) (xy 423.435603 -118.1704) (xy 423.380199 -118.193349) (xy 423.322274 -118.20887)
			(xy 423.262818 -118.216698) (xy 423.20285 -118.216698) (xy 423.143394 -118.20887) (xy 423.085469 -118.193349)
			(xy 423.030065 -118.1704) (xy 422.978131 -118.140416) (xy 422.930555 -118.10391) (xy 422.88815 -118.061505)
			(xy 422.851644 -118.013929) (xy 422.82166 -117.961995) (xy 422.798711 -117.906591) (xy 422.78319 -117.848666)
			(xy 422.775362 -117.78921) (xy 422.774872 -117.759226) (xy 418.751652 -117.759226) (xy 418.744661 -117.806728)
			(xy 418.728593 -117.860135) (xy 418.704921 -117.910632) (xy 418.674148 -117.957145) (xy 418.636931 -117.998682)
			(xy 418.594063 -118.034357) (xy 418.546457 -118.063411) (xy 418.495128 -118.085223) (xy 418.441171 -118.099329)
			(xy 418.385734 -118.105429) (xy 418.33 -118.103392) (xy 418.275157 -118.093262) (xy 418.222373 -118.075255)
			(xy 418.172773 -118.049754) (xy 418.127415 -118.017303) (xy 418.087266 -117.978594) (xy 418.05318 -117.934451)
			(xy 418.025884 -117.885816) (xy 418.005961 -117.833725) (xy 417.993835 -117.779288) (xy 417.989764 -117.723666)
			(xy 411.801742 -117.723666) (xy 411.7721 -117.969284) (xy 411.771449 -117.976226) (xy 411.77352 -117.990009)
			(xy 411.776164 -117.996462) (xy 411.779212 -118.002812) (xy 411.787594 -118.012972) (xy 411.79369 -118.01729)
			(xy 411.815225 -118.032626) (xy 411.854255 -118.068286) (xy 411.88799 -118.108992) (xy 411.915785 -118.153964)
			(xy 411.937106 -118.202341) (xy 411.951547 -118.253198) (xy 411.95883 -118.305562) (xy 411.959298 -118.331996)
			(xy 411.958769 -118.360849) (xy 411.950078 -118.417898) (xy 411.932894 -118.472987) (xy 411.90761 -118.52486)
			(xy 411.874801 -118.572333) (xy 411.835216 -118.614323) (xy 411.789759 -118.649872) (xy 411.739467 -118.678169)
			(xy 411.712664 -118.688866) (xy 411.709616 -118.689882) (xy 411.698698 -118.695552) (xy 411.683419 -118.714786)
			(xy 411.680406 -118.726712) (xy 411.578948 -119.567198) (xy 414.899348 -119.567198) (xy 414.899348 -118.703598)
			(xy 414.899838 -118.673614) (xy 414.907666 -118.614158) (xy 414.923187 -118.556233) (xy 414.946136 -118.500829)
			(xy 414.97612 -118.448895) (xy 415.012626 -118.401319) (xy 415.055031 -118.358914) (xy 415.102607 -118.322408)
			(xy 415.154541 -118.292424) (xy 415.209945 -118.269475) (xy 415.26787 -118.253954) (xy 415.327326 -118.246126)
			(xy 415.387294 -118.246126) (xy 415.44675 -118.253954) (xy 415.504675 -118.269475) (xy 415.560079 -118.292424)
			(xy 415.612013 -118.322408) (xy 415.659589 -118.358914) (xy 415.701994 -118.401319) (xy 415.7385 -118.448895)
			(xy 415.768484 -118.500829) (xy 415.791433 -118.556233) (xy 415.806954 -118.614158) (xy 415.814782 -118.673614)
			(xy 415.815272 -118.703598) (xy 415.815272 -118.711218) (xy 418.109398 -118.711218) (xy 418.113469 -118.655596)
			(xy 418.125595 -118.601159) (xy 418.145518 -118.549068) (xy 418.172814 -118.500433) (xy 418.2069 -118.45629)
			(xy 418.247049 -118.417581) (xy 418.292407 -118.38513) (xy 418.342007 -118.359629) (xy 418.394791 -118.341622)
			(xy 418.449634 -118.331492) (xy 418.505368 -118.329455) (xy 418.560805 -118.335555) (xy 418.614762 -118.349661)
			(xy 418.666091 -118.371473) (xy 418.713697 -118.400527) (xy 418.756565 -118.436202) (xy 418.793782 -118.477739)
			(xy 418.824555 -118.524252) (xy 418.848227 -118.574749) (xy 418.864295 -118.628156) (xy 418.872415 -118.683332)
			(xy 418.872924 -118.711218) (xy 418.872415 -118.739104) (xy 418.864295 -118.79428) (xy 418.848227 -118.847687)
			(xy 418.824555 -118.898184) (xy 418.793782 -118.944697) (xy 418.756565 -118.986234) (xy 418.713697 -119.021909)
			(xy 418.666091 -119.050963) (xy 418.614762 -119.072775) (xy 418.560805 -119.086881) (xy 418.505368 -119.092981)
			(xy 418.449634 -119.090944) (xy 418.394791 -119.080814) (xy 418.342007 -119.062807) (xy 418.292407 -119.037306)
			(xy 418.247049 -119.004855) (xy 418.2069 -118.966146) (xy 418.172814 -118.922003) (xy 418.145518 -118.873368)
			(xy 418.125595 -118.821277) (xy 418.113469 -118.76684) (xy 418.109398 -118.711218) (xy 415.815272 -118.711218)
			(xy 415.815272 -119.567198) (xy 415.814782 -119.597182) (xy 415.806954 -119.656638) (xy 415.791433 -119.714563)
			(xy 415.768484 -119.769967) (xy 415.7385 -119.821901) (xy 415.701994 -119.869477) (xy 415.659589 -119.911882)
			(xy 415.612013 -119.948388) (xy 415.560079 -119.978372) (xy 415.504675 -120.001321) (xy 415.44675 -120.016842)
			(xy 415.387294 -120.02467) (xy 415.327326 -120.02467) (xy 415.26787 -120.016842) (xy 415.209945 -120.001321)
			(xy 415.154541 -119.978372) (xy 415.102607 -119.948388) (xy 415.055031 -119.911882) (xy 415.012626 -119.869477)
			(xy 414.97612 -119.821901) (xy 414.946136 -119.769967) (xy 414.923187 -119.714563) (xy 414.907666 -119.656638)
			(xy 414.899838 -119.597182) (xy 414.899348 -119.567198) (xy 411.578948 -119.567198) (xy 411.52572 -120.008142)
			(xy 411.43174 -120.786652) (xy 411.40126 -121.041414) (xy 411.401006 -121.04497) (xy 411.383939 -121.367296)
			(xy 413.045148 -121.367296) (xy 413.045148 -120.503696) (xy 413.045638 -120.473712) (xy 413.053466 -120.414256)
			(xy 413.068987 -120.356331) (xy 413.091936 -120.300927) (xy 413.12192 -120.248993) (xy 413.158426 -120.201417)
			(xy 413.200831 -120.159012) (xy 413.248407 -120.122506) (xy 413.300341 -120.092522) (xy 413.355745 -120.069573)
			(xy 413.41367 -120.054052) (xy 413.473126 -120.046224) (xy 413.533094 -120.046224) (xy 413.59255 -120.054052)
			(xy 413.650475 -120.069573) (xy 413.705879 -120.092522) (xy 413.757813 -120.122506) (xy 413.805389 -120.159012)
			(xy 413.847794 -120.201417) (xy 413.8843 -120.248993) (xy 413.914284 -120.300927) (xy 413.937233 -120.356331)
			(xy 413.952754 -120.414256) (xy 413.960582 -120.473712) (xy 413.961072 -120.503696) (xy 413.961072 -121.367296)
			(xy 413.960582 -121.39728) (xy 413.952754 -121.456736) (xy 413.937233 -121.514661) (xy 413.914284 -121.570065)
			(xy 413.8843 -121.621999) (xy 413.847794 -121.669575) (xy 413.805389 -121.71198) (xy 413.757813 -121.748486)
			(xy 413.705879 -121.77847) (xy 413.650475 -121.801419) (xy 413.59255 -121.81694) (xy 413.533094 -121.824768)
			(xy 413.473126 -121.824768) (xy 413.41367 -121.81694) (xy 413.355745 -121.801419) (xy 413.300341 -121.77847)
			(xy 413.248407 -121.748486) (xy 413.200831 -121.71198) (xy 413.158426 -121.669575) (xy 413.12192 -121.621999)
			(xy 413.091936 -121.570065) (xy 413.068987 -121.514661) (xy 413.053466 -121.456736) (xy 413.045638 -121.39728)
			(xy 413.045148 -121.367296) (xy 411.383939 -121.367296) (xy 411.288641 -123.16714) (xy 414.899348 -123.16714)
			(xy 414.899348 -122.30354) (xy 414.899838 -122.273556) (xy 414.907666 -122.2141) (xy 414.923187 -122.156175)
			(xy 414.946136 -122.100771) (xy 414.97612 -122.048837) (xy 415.012626 -122.001261) (xy 415.055031 -121.958856)
			(xy 415.102607 -121.92235) (xy 415.154541 -121.892366) (xy 415.209945 -121.869417) (xy 415.26787 -121.853896)
			(xy 415.327326 -121.846068) (xy 415.387294 -121.846068) (xy 415.44675 -121.853896) (xy 415.504675 -121.869417)
			(xy 415.560079 -121.892366) (xy 415.612013 -121.92235) (xy 415.659589 -121.958856) (xy 415.701994 -122.001261)
			(xy 415.7385 -122.048837) (xy 415.768484 -122.100771) (xy 415.791433 -122.156175) (xy 415.806954 -122.2141)
			(xy 415.814782 -122.273556) (xy 415.815272 -122.30354) (xy 415.815272 -123.16714) (xy 415.814782 -123.197124)
			(xy 415.806954 -123.25658) (xy 415.791433 -123.314505) (xy 415.768484 -123.369909) (xy 415.7385 -123.421843)
			(xy 415.701994 -123.469419) (xy 415.659589 -123.511824) (xy 415.612013 -123.54833) (xy 415.560079 -123.578314)
			(xy 415.504675 -123.601263) (xy 415.44675 -123.616784) (xy 415.387294 -123.624612) (xy 415.327326 -123.624612)
			(xy 415.26787 -123.616784) (xy 415.209945 -123.601263) (xy 415.154541 -123.578314) (xy 415.102607 -123.54833)
			(xy 415.055031 -123.511824) (xy 415.012626 -123.469419) (xy 414.97612 -123.421843) (xy 414.946136 -123.369909)
			(xy 414.923187 -123.314505) (xy 414.907666 -123.25658) (xy 414.899838 -123.197124) (xy 414.899348 -123.16714)
			(xy 411.288641 -123.16714) (xy 411.193329 -124.967238) (xy 413.045148 -124.967238) (xy 413.045148 -124.103638)
			(xy 413.045638 -124.073654) (xy 413.053466 -124.014198) (xy 413.068987 -123.956273) (xy 413.091936 -123.900869)
			(xy 413.12192 -123.848935) (xy 413.158426 -123.801359) (xy 413.200831 -123.758954) (xy 413.248407 -123.722448)
			(xy 413.300341 -123.692464) (xy 413.355745 -123.669515) (xy 413.41367 -123.653994) (xy 413.473126 -123.646166)
			(xy 413.533094 -123.646166) (xy 413.59255 -123.653994) (xy 413.650475 -123.669515) (xy 413.705879 -123.692464)
			(xy 413.757813 -123.722448) (xy 413.805389 -123.758954) (xy 413.847794 -123.801359) (xy 413.8843 -123.848935)
			(xy 413.914284 -123.900869) (xy 413.937233 -123.956273) (xy 413.952754 -124.014198) (xy 413.960582 -124.073654)
			(xy 413.961072 -124.103638) (xy 413.961072 -124.967238) (xy 413.960582 -124.997222) (xy 413.952754 -125.056678)
			(xy 413.937233 -125.114603) (xy 413.914284 -125.170007) (xy 413.8843 -125.221941) (xy 413.847794 -125.269517)
			(xy 413.805389 -125.311922) (xy 413.757813 -125.348428) (xy 413.705879 -125.378412) (xy 413.650475 -125.401361)
			(xy 413.59255 -125.416882) (xy 413.533094 -125.42471) (xy 413.473126 -125.42471) (xy 413.41367 -125.416882)
			(xy 413.355745 -125.401361) (xy 413.300341 -125.378412) (xy 413.248407 -125.348428) (xy 413.200831 -125.311922)
			(xy 413.158426 -125.269517) (xy 413.12192 -125.221941) (xy 413.091936 -125.170007) (xy 413.068987 -125.114603)
			(xy 413.053466 -125.056678) (xy 413.045638 -124.997222) (xy 413.045148 -124.967238) (xy 411.193329 -124.967238)
			(xy 410.964888 -129.281682) (xy 410.885727 -130.777234) (xy 414.899348 -130.777234) (xy 414.899348 -129.913634)
			(xy 414.899838 -129.88365) (xy 414.907666 -129.824194) (xy 414.923187 -129.766269) (xy 414.946136 -129.710865)
			(xy 414.97612 -129.658931) (xy 415.012626 -129.611355) (xy 415.055031 -129.56895) (xy 415.102607 -129.532444)
			(xy 415.154541 -129.50246) (xy 415.209945 -129.479511) (xy 415.26787 -129.46399) (xy 415.327326 -129.456162)
			(xy 415.387294 -129.456162) (xy 415.44675 -129.46399) (xy 415.504675 -129.479511) (xy 415.560079 -129.50246)
			(xy 415.612013 -129.532444) (xy 415.659589 -129.56895) (xy 415.701994 -129.611355) (xy 415.7385 -129.658931)
			(xy 415.768484 -129.710865) (xy 415.791433 -129.766269) (xy 415.806954 -129.824194) (xy 415.814782 -129.88365)
			(xy 415.815272 -129.913634) (xy 415.815272 -130.777234) (xy 415.814782 -130.807218) (xy 415.806954 -130.866674)
			(xy 415.791433 -130.924599) (xy 415.768484 -130.980003) (xy 415.7385 -131.031937) (xy 415.701994 -131.079513)
			(xy 415.659589 -131.121918) (xy 415.612013 -131.158424) (xy 415.560079 -131.188408) (xy 415.504675 -131.211357)
			(xy 415.44675 -131.226878) (xy 415.387294 -131.234706) (xy 415.327326 -131.234706) (xy 415.26787 -131.226878)
			(xy 415.209945 -131.211357) (xy 415.154541 -131.188408) (xy 415.102607 -131.158424) (xy 415.055031 -131.121918)
			(xy 415.012626 -131.079513) (xy 414.97612 -131.031937) (xy 414.946136 -130.980003) (xy 414.923187 -130.924599)
			(xy 414.907666 -130.866674) (xy 414.899838 -130.807218) (xy 414.899348 -130.777234) (xy 410.885727 -130.777234)
			(xy 410.790447 -132.577332) (xy 413.045148 -132.577332) (xy 413.045148 -131.713732) (xy 413.045638 -131.683748)
			(xy 413.053466 -131.624292) (xy 413.068987 -131.566367) (xy 413.091936 -131.510963) (xy 413.12192 -131.459029)
			(xy 413.158426 -131.411453) (xy 413.200831 -131.369048) (xy 413.248407 -131.332542) (xy 413.300341 -131.302558)
			(xy 413.355745 -131.279609) (xy 413.41367 -131.264088) (xy 413.473126 -131.25626) (xy 413.533094 -131.25626)
			(xy 413.59255 -131.264088) (xy 413.650475 -131.279609) (xy 413.705879 -131.302558) (xy 413.757813 -131.332542)
			(xy 413.805389 -131.369048) (xy 413.847794 -131.411453) (xy 413.8843 -131.459029) (xy 413.914284 -131.510963)
			(xy 413.937233 -131.566367) (xy 413.952754 -131.624292) (xy 413.960582 -131.683748) (xy 413.961072 -131.713732)
			(xy 413.961072 -132.577332) (xy 413.960582 -132.607316) (xy 413.952754 -132.666772) (xy 413.937233 -132.724697)
			(xy 413.914284 -132.780101) (xy 413.8843 -132.832035) (xy 413.847794 -132.879611) (xy 413.805389 -132.922016)
			(xy 413.757813 -132.958522) (xy 413.705879 -132.988506) (xy 413.650475 -133.011455) (xy 413.59255 -133.026976)
			(xy 413.533094 -133.034804) (xy 413.473126 -133.034804) (xy 413.41367 -133.026976) (xy 413.355745 -133.011455)
			(xy 413.300341 -132.988506) (xy 413.248407 -132.958522) (xy 413.200831 -132.922016) (xy 413.158426 -132.879611)
			(xy 413.12192 -132.832035) (xy 413.091936 -132.780101) (xy 413.068987 -132.724697) (xy 413.053466 -132.666772)
			(xy 413.045638 -132.607316) (xy 413.045148 -132.577332) (xy 410.790447 -132.577332) (xy 410.69518 -134.377176)
			(xy 414.899348 -134.377176) (xy 414.899348 -133.513576) (xy 414.899838 -133.483592) (xy 414.907666 -133.424136)
			(xy 414.923187 -133.366211) (xy 414.946136 -133.310807) (xy 414.97612 -133.258873) (xy 415.012626 -133.211297)
			(xy 415.055031 -133.168892) (xy 415.102607 -133.132386) (xy 415.154541 -133.102402) (xy 415.209945 -133.079453)
			(xy 415.26787 -133.063932) (xy 415.327326 -133.056104) (xy 415.387294 -133.056104) (xy 415.44675 -133.063932)
			(xy 415.504675 -133.079453) (xy 415.560079 -133.102402) (xy 415.612013 -133.132386) (xy 415.659589 -133.168892)
			(xy 415.701994 -133.211297) (xy 415.7385 -133.258873) (xy 415.768484 -133.310807) (xy 415.791433 -133.366211)
			(xy 415.806954 -133.424136) (xy 415.814782 -133.483592) (xy 415.815272 -133.513576) (xy 415.815272 -134.377176)
			(xy 415.814782 -134.40716) (xy 415.806954 -134.466616) (xy 415.791433 -134.524541) (xy 415.768484 -134.579945)
			(xy 415.7385 -134.631879) (xy 415.701994 -134.679455) (xy 415.659589 -134.72186) (xy 415.612013 -134.758366)
			(xy 415.560079 -134.78835) (xy 415.504675 -134.811299) (xy 415.44675 -134.82682) (xy 415.387294 -134.834648)
			(xy 415.327326 -134.834648) (xy 415.26787 -134.82682) (xy 415.209945 -134.811299) (xy 415.154541 -134.78835)
			(xy 415.102607 -134.758366) (xy 415.055031 -134.72186) (xy 415.012626 -134.679455) (xy 414.97612 -134.631879)
			(xy 414.946136 -134.579945) (xy 414.923187 -134.524541) (xy 414.907666 -134.466616) (xy 414.899838 -134.40716)
			(xy 414.899348 -134.377176) (xy 410.69518 -134.377176) (xy 410.599899 -136.177274) (xy 413.045148 -136.177274)
			(xy 413.045148 -135.313674) (xy 413.045638 -135.28369) (xy 413.053466 -135.224234) (xy 413.068987 -135.166309)
			(xy 413.091936 -135.110905) (xy 413.12192 -135.058971) (xy 413.158426 -135.011395) (xy 413.200831 -134.96899)
			(xy 413.248407 -134.932484) (xy 413.300341 -134.9025) (xy 413.355745 -134.879551) (xy 413.41367 -134.86403)
			(xy 413.473126 -134.856202) (xy 413.533094 -134.856202) (xy 413.59255 -134.86403) (xy 413.650475 -134.879551)
			(xy 413.705879 -134.9025) (xy 413.757813 -134.932484) (xy 413.805389 -134.96899) (xy 413.847794 -135.011395)
			(xy 413.8843 -135.058971) (xy 413.914284 -135.110905) (xy 413.937233 -135.166309) (xy 413.952754 -135.224234)
			(xy 413.960582 -135.28369) (xy 413.961072 -135.313674) (xy 413.961072 -136.177274) (xy 413.960582 -136.207258)
			(xy 413.952754 -136.266714) (xy 413.937233 -136.324639) (xy 413.914284 -136.380043) (xy 413.8843 -136.431977)
			(xy 413.847794 -136.479553) (xy 413.805389 -136.521958) (xy 413.757813 -136.558464) (xy 413.705879 -136.588448)
			(xy 413.650475 -136.611397) (xy 413.59255 -136.626918) (xy 413.533094 -136.634746) (xy 413.473126 -136.634746)
			(xy 413.41367 -136.626918) (xy 413.355745 -136.611397) (xy 413.300341 -136.588448) (xy 413.248407 -136.558464)
			(xy 413.200831 -136.521958) (xy 413.158426 -136.479553) (xy 413.12192 -136.431977) (xy 413.091936 -136.380043)
			(xy 413.068987 -136.324639) (xy 413.053466 -136.266714) (xy 413.045638 -136.207258) (xy 413.045148 -136.177274)
			(xy 410.599899 -136.177274) (xy 410.534358 -137.415524) (xy 410.534332 -137.424968) (xy 410.540283 -137.442872)
			(xy 410.552301 -137.457418) (xy 410.568761 -137.46664) (xy 410.578046 -137.468356) (xy 410.58592 -137.468864)
			(xy 410.589222 -137.46861) (xy 410.621988 -137.46734) (xy 410.625798 -137.46734) (xy 410.652871 -137.468084)
			(xy 410.706405 -137.476277) (xy 410.758243 -137.491959) (xy 410.807342 -137.514814) (xy 410.852714 -137.544384)
			(xy 410.893449 -137.580074) (xy 410.928726 -137.621166) (xy 410.957837 -137.666835) (xy 410.980197 -137.716162)
			(xy 410.995355 -137.768155) (xy 411.003008 -137.821769) (xy 411.003496 -137.848848) (xy 411.003006 -137.876097)
			(xy 410.995244 -137.930038) (xy 410.979885 -137.982327) (xy 410.957241 -138.031897) (xy 410.927773 -138.077741)
			(xy 410.892082 -138.118924) (xy 410.850892 -138.154609) (xy 410.805044 -138.18407) (xy 410.75547 -138.206706)
			(xy 410.70318 -138.222057) (xy 410.649237 -138.229811) (xy 410.621988 -138.230356) (xy 410.594556 -138.22934)
			(xy 410.584396 -138.228578) (xy 410.575252 -138.231626) (xy 410.570461 -138.233385) (xy 410.561634 -138.238504)
			(xy 410.557726 -138.241786) (xy 410.501338 -138.291316) (xy 410.495342 -138.297688) (xy 410.487672 -138.313401)
			(xy 410.486352 -138.32205) (xy 410.483304 -138.37793) (xy 410.483255 -138.388754) (xy 410.491153 -138.408884)
			(xy 410.498544 -138.416792) (xy 410.553154 -138.470132) (xy 410.557132 -138.473847) (xy 410.566361 -138.479612)
			(xy 410.571442 -138.481562) (xy 410.581602 -138.485118) (xy 410.592524 -138.484356) (xy 410.619194 -138.48334)
			(xy 410.619702 -138.48334) (xy 410.626814 -138.48334) (xy 410.653839 -138.484152) (xy 410.707264 -138.492461)
			(xy 410.758981 -138.508229) (xy 410.807953 -138.531141) (xy 410.8532 -138.560739) (xy 410.893815 -138.596428)
			(xy 410.928983 -138.637494) (xy 410.958001 -138.683114) (xy 410.980288 -138.732374) (xy 410.995396 -138.784288)
			(xy 411.003023 -138.837814) (xy 411.003496 -138.864848) (xy 411.003006 -138.892097) (xy 410.995244 -138.946038)
			(xy 410.979885 -138.998327) (xy 410.957241 -139.047897) (xy 410.927773 -139.093741) (xy 410.892082 -139.134924)
			(xy 410.850892 -139.170609) (xy 410.805044 -139.20007) (xy 410.75547 -139.222706) (xy 410.70318 -139.238057)
			(xy 410.649237 -139.245811) (xy 410.621988 -139.246356) (xy 410.604553 -139.246161) (xy 410.569827 -139.242981)
			(xy 410.552646 -139.240006) (xy 410.541724 -139.237974) (xy 410.531564 -139.240514) (xy 410.526276 -139.241923)
			(xy 410.516416 -139.246671) (xy 410.512006 -139.249912) (xy 410.451808 -139.29741) (xy 410.444062 -139.304115)
			(xy 410.434236 -139.32207) (xy 410.432758 -139.332208) (xy 410.21285 -143.48714) (xy 414.899348 -143.48714)
			(xy 414.899348 -142.62354) (xy 414.899838 -142.593556) (xy 414.907666 -142.5341) (xy 414.923187 -142.476175)
			(xy 414.946136 -142.420771) (xy 414.97612 -142.368837) (xy 415.012626 -142.321261) (xy 415.055031 -142.278856)
			(xy 415.102607 -142.24235) (xy 415.154541 -142.212366) (xy 415.209945 -142.189417) (xy 415.26787 -142.173896)
			(xy 415.327326 -142.166068) (xy 415.387294 -142.166068) (xy 415.44675 -142.173896) (xy 415.504675 -142.189417)
			(xy 415.560079 -142.212366) (xy 415.612013 -142.24235) (xy 415.659589 -142.278856) (xy 415.701994 -142.321261)
			(xy 415.7385 -142.368837) (xy 415.768484 -142.420771) (xy 415.791433 -142.476175) (xy 415.806954 -142.5341)
			(xy 415.814782 -142.593556) (xy 415.815272 -142.62354) (xy 415.815272 -143.48714) (xy 415.814782 -143.517124)
			(xy 415.806954 -143.57658) (xy 415.791433 -143.634505) (xy 415.768484 -143.689909) (xy 415.7385 -143.741843)
			(xy 415.701994 -143.789419) (xy 415.659589 -143.831824) (xy 415.612013 -143.86833) (xy 415.560079 -143.898314)
			(xy 415.504675 -143.921263) (xy 415.44675 -143.936784) (xy 415.387294 -143.944612) (xy 415.327326 -143.944612)
			(xy 415.26787 -143.936784) (xy 415.209945 -143.921263) (xy 415.154541 -143.898314) (xy 415.102607 -143.86833)
			(xy 415.055031 -143.831824) (xy 415.012626 -143.789419) (xy 414.97612 -143.741843) (xy 414.946136 -143.689909)
			(xy 414.923187 -143.634505) (xy 414.907666 -143.57658) (xy 414.899838 -143.517124) (xy 414.899348 -143.48714)
			(xy 410.21285 -143.48714) (xy 410.117576 -145.287238) (xy 413.045148 -145.287238) (xy 413.045148 -144.423638)
			(xy 413.045638 -144.393654) (xy 413.053466 -144.334198) (xy 413.068987 -144.276273) (xy 413.091936 -144.220869)
			(xy 413.12192 -144.168935) (xy 413.158426 -144.121359) (xy 413.200831 -144.078954) (xy 413.248407 -144.042448)
			(xy 413.300341 -144.012464) (xy 413.355745 -143.989515) (xy 413.41367 -143.973994) (xy 413.473126 -143.966166)
			(xy 413.533094 -143.966166) (xy 413.59255 -143.973994) (xy 413.650475 -143.989515) (xy 413.705879 -144.012464)
			(xy 413.757813 -144.042448) (xy 413.805389 -144.078954) (xy 413.847794 -144.121359) (xy 413.8843 -144.168935)
			(xy 413.914284 -144.220869) (xy 413.937233 -144.276273) (xy 413.952754 -144.334198) (xy 413.960582 -144.393654)
			(xy 413.961072 -144.423638) (xy 413.961072 -145.287238) (xy 413.960582 -145.317222) (xy 413.952754 -145.376678)
			(xy 413.937233 -145.434603) (xy 413.914284 -145.490007) (xy 413.8843 -145.541941) (xy 413.847794 -145.589517)
			(xy 413.805389 -145.631922) (xy 413.757813 -145.668428) (xy 413.705879 -145.698412) (xy 413.650475 -145.721361)
			(xy 413.59255 -145.736882) (xy 413.533094 -145.74471) (xy 413.473126 -145.74471) (xy 413.41367 -145.736882)
			(xy 413.355745 -145.721361) (xy 413.300341 -145.698412) (xy 413.248407 -145.668428) (xy 413.200831 -145.631922)
			(xy 413.158426 -145.589517) (xy 413.12192 -145.541941) (xy 413.091936 -145.490007) (xy 413.068987 -145.434603)
			(xy 413.053466 -145.376678) (xy 413.045638 -145.317222) (xy 413.045148 -145.287238) (xy 410.117576 -145.287238)
			(xy 410.022302 -147.087336) (xy 414.899348 -147.087336) (xy 414.899348 -146.223736) (xy 414.899838 -146.193752)
			(xy 414.907666 -146.134296) (xy 414.923187 -146.076371) (xy 414.946136 -146.020967) (xy 414.97612 -145.969033)
			(xy 415.012626 -145.921457) (xy 415.055031 -145.879052) (xy 415.102607 -145.842546) (xy 415.154541 -145.812562)
			(xy 415.209945 -145.789613) (xy 415.26787 -145.774092) (xy 415.327326 -145.766264) (xy 415.387294 -145.766264)
			(xy 415.44675 -145.774092) (xy 415.504675 -145.789613) (xy 415.560079 -145.812562) (xy 415.612013 -145.842546)
			(xy 415.659589 -145.879052) (xy 415.701994 -145.921457) (xy 415.7385 -145.969033) (xy 415.768484 -146.020967)
			(xy 415.791433 -146.076371) (xy 415.806954 -146.134296) (xy 415.814782 -146.193752) (xy 415.815272 -146.223736)
			(xy 415.815272 -147.087336) (xy 415.814782 -147.11732) (xy 415.806954 -147.176776) (xy 415.791433 -147.234701)
			(xy 415.768484 -147.290105) (xy 415.7385 -147.342039) (xy 415.701994 -147.389615) (xy 415.659589 -147.43202)
			(xy 415.612013 -147.468526) (xy 415.560079 -147.49851) (xy 415.504675 -147.521459) (xy 415.44675 -147.53698)
			(xy 415.387294 -147.544808) (xy 415.327326 -147.544808) (xy 415.26787 -147.53698) (xy 415.209945 -147.521459)
			(xy 415.154541 -147.49851) (xy 415.102607 -147.468526) (xy 415.055031 -147.43202) (xy 415.012626 -147.389615)
			(xy 414.97612 -147.342039) (xy 414.946136 -147.290105) (xy 414.923187 -147.234701) (xy 414.907666 -147.176776)
			(xy 414.899838 -147.11732) (xy 414.899348 -147.087336) (xy 410.022302 -147.087336) (xy 409.927028 -148.887434)
			(xy 413.045148 -148.887434) (xy 413.045148 -148.023834) (xy 413.045638 -147.99385) (xy 413.053466 -147.934394)
			(xy 413.068987 -147.876469) (xy 413.091936 -147.821065) (xy 413.12192 -147.769131) (xy 413.158426 -147.721555)
			(xy 413.200831 -147.67915) (xy 413.248407 -147.642644) (xy 413.300341 -147.61266) (xy 413.355745 -147.589711)
			(xy 413.41367 -147.57419) (xy 413.473126 -147.566362) (xy 413.533094 -147.566362) (xy 413.59255 -147.57419)
			(xy 413.650475 -147.589711) (xy 413.705879 -147.61266) (xy 413.757813 -147.642644) (xy 413.805389 -147.67915)
			(xy 413.847794 -147.721555) (xy 413.8843 -147.769131) (xy 413.914284 -147.821065) (xy 413.937233 -147.876469)
			(xy 413.952754 -147.934394) (xy 413.960582 -147.99385) (xy 413.961072 -148.023834) (xy 413.961072 -148.887434)
			(xy 413.960582 -148.917418) (xy 413.952754 -148.976874) (xy 413.937233 -149.034799) (xy 413.914284 -149.090203)
			(xy 413.8843 -149.142137) (xy 413.847794 -149.189713) (xy 413.805389 -149.232118) (xy 413.757813 -149.268624)
			(xy 413.705879 -149.298608) (xy 413.650475 -149.321557) (xy 413.59255 -149.337078) (xy 413.533094 -149.344906)
			(xy 413.473126 -149.344906) (xy 413.41367 -149.337078) (xy 413.355745 -149.321557) (xy 413.300341 -149.298608)
			(xy 413.248407 -149.268624) (xy 413.200831 -149.232118) (xy 413.158426 -149.189713) (xy 413.12192 -149.142137)
			(xy 413.091936 -149.090203) (xy 413.068987 -149.034799) (xy 413.053466 -148.976874) (xy 413.045638 -148.917418)
			(xy 413.045148 -148.887434) (xy 409.927028 -148.887434) (xy 409.831767 -150.687278) (xy 414.899348 -150.687278)
			(xy 414.899348 -149.823678) (xy 414.899838 -149.793694) (xy 414.907666 -149.734238) (xy 414.923187 -149.676313)
			(xy 414.946136 -149.620909) (xy 414.97612 -149.568975) (xy 415.012626 -149.521399) (xy 415.055031 -149.478994)
			(xy 415.102607 -149.442488) (xy 415.154541 -149.412504) (xy 415.209945 -149.389555) (xy 415.26787 -149.374034)
			(xy 415.327326 -149.366206) (xy 415.387294 -149.366206) (xy 415.44675 -149.374034) (xy 415.504675 -149.389555)
			(xy 415.560079 -149.412504) (xy 415.612013 -149.442488) (xy 415.659589 -149.478994) (xy 415.701994 -149.521399)
			(xy 415.7385 -149.568975) (xy 415.768484 -149.620909) (xy 415.791433 -149.676313) (xy 415.806954 -149.734238)
			(xy 415.814782 -149.793694) (xy 415.815272 -149.823678) (xy 415.815272 -150.687278) (xy 415.814782 -150.717262)
			(xy 415.806954 -150.776718) (xy 415.791433 -150.834643) (xy 415.768484 -150.890047) (xy 415.7385 -150.941981)
			(xy 415.701994 -150.989557) (xy 415.659589 -151.031962) (xy 415.612013 -151.068468) (xy 415.560079 -151.098452)
			(xy 415.504675 -151.121401) (xy 415.44675 -151.136922) (xy 415.387294 -151.14475) (xy 415.327326 -151.14475)
			(xy 415.26787 -151.136922) (xy 415.209945 -151.121401) (xy 415.154541 -151.098452) (xy 415.102607 -151.068468)
			(xy 415.055031 -151.031962) (xy 415.012626 -150.989557) (xy 414.97612 -150.941981) (xy 414.946136 -150.890047)
			(xy 414.923187 -150.834643) (xy 414.907666 -150.776718) (xy 414.899838 -150.717262) (xy 414.899348 -150.687278)
			(xy 409.831767 -150.687278) (xy 409.736493 -152.487376) (xy 413.045148 -152.487376) (xy 413.045148 -151.623776)
			(xy 413.045638 -151.593792) (xy 413.053466 -151.534336) (xy 413.068987 -151.476411) (xy 413.091936 -151.421007)
			(xy 413.12192 -151.369073) (xy 413.158426 -151.321497) (xy 413.200831 -151.279092) (xy 413.248407 -151.242586)
			(xy 413.300341 -151.212602) (xy 413.355745 -151.189653) (xy 413.41367 -151.174132) (xy 413.473126 -151.166304)
			(xy 413.533094 -151.166304) (xy 413.59255 -151.174132) (xy 413.650475 -151.189653) (xy 413.705879 -151.212602)
			(xy 413.757813 -151.242586) (xy 413.805389 -151.279092) (xy 413.847794 -151.321497) (xy 413.8843 -151.369073)
			(xy 413.914284 -151.421007) (xy 413.937233 -151.476411) (xy 413.952754 -151.534336) (xy 413.960582 -151.593792)
			(xy 413.961072 -151.623776) (xy 413.961072 -152.487376) (xy 413.960582 -152.51736) (xy 413.952754 -152.576816)
			(xy 413.937233 -152.634741) (xy 413.914284 -152.690145) (xy 413.8843 -152.742079) (xy 413.847794 -152.789655)
			(xy 413.805389 -152.83206) (xy 413.757813 -152.868566) (xy 413.705879 -152.89855) (xy 413.650475 -152.921499)
			(xy 413.59255 -152.93702) (xy 413.533094 -152.944848) (xy 413.473126 -152.944848) (xy 413.41367 -152.93702)
			(xy 413.355745 -152.921499) (xy 413.300341 -152.89855) (xy 413.248407 -152.868566) (xy 413.200831 -152.83206)
			(xy 413.158426 -152.789655) (xy 413.12192 -152.742079) (xy 413.091936 -152.690145) (xy 413.068987 -152.634741)
			(xy 413.053466 -152.576816) (xy 413.045638 -152.51736) (xy 413.045148 -152.487376) (xy 409.736493 -152.487376)
			(xy 409.641233 -154.28722) (xy 414.899348 -154.28722) (xy 414.899348 -153.42362) (xy 414.899838 -153.393636)
			(xy 414.907666 -153.33418) (xy 414.923187 -153.276255) (xy 414.946136 -153.220851) (xy 414.97612 -153.168917)
			(xy 415.012626 -153.121341) (xy 415.055031 -153.078936) (xy 415.102607 -153.04243) (xy 415.154541 -153.012446)
			(xy 415.209945 -152.989497) (xy 415.26787 -152.973976) (xy 415.327326 -152.966148) (xy 415.387294 -152.966148)
			(xy 415.44675 -152.973976) (xy 415.504675 -152.989497) (xy 415.560079 -153.012446) (xy 415.612013 -153.04243)
			(xy 415.659589 -153.078936) (xy 415.701994 -153.121341) (xy 415.7385 -153.168917) (xy 415.768484 -153.220851)
			(xy 415.791433 -153.276255) (xy 415.806954 -153.33418) (xy 415.814782 -153.393636) (xy 415.815272 -153.42362)
			(xy 415.815272 -154.28722) (xy 415.814782 -154.317204) (xy 415.806954 -154.37666) (xy 415.791433 -154.434585)
			(xy 415.768484 -154.489989) (xy 415.7385 -154.541923) (xy 415.701994 -154.589499) (xy 415.659589 -154.631904)
			(xy 415.612013 -154.66841) (xy 415.560079 -154.698394) (xy 415.504675 -154.721343) (xy 415.44675 -154.736864)
			(xy 415.387294 -154.744692) (xy 415.327326 -154.744692) (xy 415.26787 -154.736864) (xy 415.209945 -154.721343)
			(xy 415.154541 -154.698394) (xy 415.102607 -154.66841) (xy 415.055031 -154.631904) (xy 415.012626 -154.589499)
			(xy 414.97612 -154.541923) (xy 414.946136 -154.489989) (xy 414.923187 -154.434585) (xy 414.907666 -154.37666)
			(xy 414.899838 -154.317204) (xy 414.899348 -154.28722) (xy 409.641233 -154.28722) (xy 409.545959 -156.087318)
			(xy 413.045148 -156.087318) (xy 413.045148 -155.223718) (xy 413.045638 -155.193734) (xy 413.053466 -155.134278)
			(xy 413.068987 -155.076353) (xy 413.091936 -155.020949) (xy 413.12192 -154.969015) (xy 413.158426 -154.921439)
			(xy 413.200831 -154.879034) (xy 413.248407 -154.842528) (xy 413.300341 -154.812544) (xy 413.355745 -154.789595)
			(xy 413.41367 -154.774074) (xy 413.473126 -154.766246) (xy 413.533094 -154.766246) (xy 413.59255 -154.774074)
			(xy 413.650475 -154.789595) (xy 413.705879 -154.812544) (xy 413.757813 -154.842528) (xy 413.805389 -154.879034)
			(xy 413.847794 -154.921439) (xy 413.8843 -154.969015) (xy 413.914284 -155.020949) (xy 413.937233 -155.076353)
			(xy 413.952754 -155.134278) (xy 413.960582 -155.193734) (xy 413.961072 -155.223718) (xy 413.961072 -156.087318)
			(xy 413.960582 -156.117302) (xy 413.952754 -156.176758) (xy 413.937233 -156.234683) (xy 413.914284 -156.290087)
			(xy 413.8843 -156.342021) (xy 413.847794 -156.389597) (xy 413.805389 -156.432002) (xy 413.757813 -156.468508)
			(xy 413.705879 -156.498492) (xy 413.650475 -156.521441) (xy 413.59255 -156.536962) (xy 413.533094 -156.54479)
			(xy 413.473126 -156.54479) (xy 413.41367 -156.536962) (xy 413.355745 -156.521441) (xy 413.300341 -156.498492)
			(xy 413.248407 -156.468508) (xy 413.200831 -156.432002) (xy 413.158426 -156.389597) (xy 413.12192 -156.342021)
			(xy 413.091936 -156.290087) (xy 413.068987 -156.234683) (xy 413.053466 -156.176758) (xy 413.045638 -156.117302)
			(xy 413.045148 -156.087318) (xy 409.545959 -156.087318) (xy 409.495264 -157.045152) (xy 409.710634 -157.045152)
			(xy 409.714705 -156.98953) (xy 409.726831 -156.935093) (xy 409.746754 -156.883002) (xy 409.77405 -156.834367)
			(xy 409.808136 -156.790224) (xy 409.848285 -156.751515) (xy 409.893643 -156.719064) (xy 409.943243 -156.693563)
			(xy 409.996027 -156.675556) (xy 410.05087 -156.665426) (xy 410.106604 -156.663389) (xy 410.162041 -156.669489)
			(xy 410.215998 -156.683595) (xy 410.267327 -156.705407) (xy 410.314933 -156.734461) (xy 410.357801 -156.770136)
			(xy 410.395018 -156.811673) (xy 410.425791 -156.858186) (xy 410.449463 -156.908683) (xy 410.465531 -156.96209)
			(xy 410.473651 -157.017266) (xy 410.47416 -157.045152) (xy 410.726634 -157.045152) (xy 410.730705 -156.98953)
			(xy 410.742831 -156.935093) (xy 410.762754 -156.883002) (xy 410.79005 -156.834367) (xy 410.824136 -156.790224)
			(xy 410.864285 -156.751515) (xy 410.909643 -156.719064) (xy 410.959243 -156.693563) (xy 411.012027 -156.675556)
			(xy 411.06687 -156.665426) (xy 411.122604 -156.663389) (xy 411.178041 -156.669489) (xy 411.231998 -156.683595)
			(xy 411.283327 -156.705407) (xy 411.330933 -156.734461) (xy 411.373801 -156.770136) (xy 411.411018 -156.811673)
			(xy 411.441791 -156.858186) (xy 411.465463 -156.908683) (xy 411.481531 -156.96209) (xy 411.489651 -157.017266)
			(xy 411.49016 -157.045152) (xy 411.489651 -157.073038) (xy 411.481531 -157.128214) (xy 411.465463 -157.181621)
			(xy 411.441791 -157.232118) (xy 411.411018 -157.278631) (xy 411.373801 -157.320168) (xy 411.330933 -157.355843)
			(xy 411.283327 -157.384897) (xy 411.231998 -157.406709) (xy 411.178041 -157.420815) (xy 411.122604 -157.426915)
			(xy 411.06687 -157.424878) (xy 411.012027 -157.414748) (xy 410.959243 -157.396741) (xy 410.909643 -157.37124)
			(xy 410.864285 -157.338789) (xy 410.824136 -157.30008) (xy 410.79005 -157.255937) (xy 410.762754 -157.207302)
			(xy 410.742831 -157.155211) (xy 410.730705 -157.100774) (xy 410.726634 -157.045152) (xy 410.47416 -157.045152)
			(xy 410.473651 -157.073038) (xy 410.465531 -157.128214) (xy 410.449463 -157.181621) (xy 410.425791 -157.232118)
			(xy 410.395018 -157.278631) (xy 410.357801 -157.320168) (xy 410.314933 -157.355843) (xy 410.267327 -157.384897)
			(xy 410.215998 -157.406709) (xy 410.162041 -157.420815) (xy 410.106604 -157.426915) (xy 410.05087 -157.424878)
			(xy 409.996027 -157.414748) (xy 409.943243 -157.396741) (xy 409.893643 -157.37124) (xy 409.848285 -157.338789)
			(xy 409.808136 -157.30008) (xy 409.77405 -157.255937) (xy 409.746754 -157.207302) (xy 409.726831 -157.155211)
			(xy 409.714705 -157.100774) (xy 409.710634 -157.045152) (xy 409.495264 -157.045152) (xy 409.329076 -160.1851)
			(xy 418.188915 -160.1851) (xy 418.192871 -160.093241) (xy 418.204708 -160.002062) (xy 418.22434 -159.912238)
			(xy 418.251621 -159.824435) (xy 418.286349 -159.739302) (xy 418.328267 -159.657469) (xy 418.377065 -159.579542)
			(xy 418.43238 -159.506099) (xy 418.493805 -159.437683) (xy 418.560884 -159.374801) (xy 418.633119 -159.317918)
			(xy 418.709978 -159.267455) (xy 418.79089 -159.223786) (xy 418.875256 -159.187234) (xy 418.962452 -159.15807)
			(xy 419.051833 -159.13651) (xy 419.142736 -159.122714) (xy 419.234489 -159.116782) (xy 419.326411 -159.118761)
			(xy 419.417824 -159.128634) (xy 419.508049 -159.146329) (xy 419.59642 -159.171714) (xy 419.68228 -159.204602)
			(xy 419.764996 -159.24475) (xy 419.843954 -159.291859) (xy 419.918571 -159.345582) (xy 419.988292 -159.40552)
			(xy 420.052603 -159.47123) (xy 420.111028 -159.542226) (xy 420.163133 -159.61798) (xy 420.208532 -159.697934)
			(xy 420.246891 -159.781494) (xy 420.277924 -159.868043) (xy 420.301402 -159.956939) (xy 420.317152 -160.047524)
			(xy 420.325056 -160.139128) (xy 420.32555 -160.1851) (xy 420.325056 -160.231072) (xy 420.317152 -160.322676)
			(xy 420.301402 -160.413261) (xy 420.277924 -160.502157) (xy 420.246891 -160.588706) (xy 420.208532 -160.672266)
			(xy 420.163133 -160.75222) (xy 420.111028 -160.827974) (xy 420.052603 -160.89897) (xy 419.988292 -160.96468)
			(xy 419.918571 -161.024618) (xy 419.843954 -161.078341) (xy 419.764996 -161.12545) (xy 419.68228 -161.165598)
			(xy 419.59642 -161.198486) (xy 419.508049 -161.223871) (xy 419.417824 -161.241566) (xy 419.326411 -161.251439)
			(xy 419.234489 -161.253418) (xy 419.142736 -161.247486) (xy 419.051833 -161.23369) (xy 418.962452 -161.21213)
			(xy 418.875256 -161.182966) (xy 418.79089 -161.146414) (xy 418.709978 -161.102745) (xy 418.633119 -161.052282)
			(xy 418.560884 -160.995399) (xy 418.493805 -160.932517) (xy 418.43238 -160.864101) (xy 418.377065 -160.790658)
			(xy 418.328267 -160.712731) (xy 418.286349 -160.630898) (xy 418.251621 -160.545765) (xy 418.22434 -160.457962)
			(xy 418.204708 -160.368138) (xy 418.192871 -160.276959) (xy 418.188915 -160.1851) (xy 409.329076 -160.1851)
			(xy 409.159661 -163.386008) (xy 412.932878 -163.386008) (xy 412.936949 -163.330386) (xy 412.949075 -163.275949)
			(xy 412.968998 -163.223858) (xy 412.996294 -163.175223) (xy 413.03038 -163.13108) (xy 413.070529 -163.092371)
			(xy 413.115887 -163.05992) (xy 413.165487 -163.034419) (xy 413.218271 -163.016412) (xy 413.273114 -163.006282)
			(xy 413.328848 -163.004245) (xy 413.384285 -163.010345) (xy 413.438242 -163.024451) (xy 413.489571 -163.046263)
			(xy 413.537177 -163.075317) (xy 413.580045 -163.110992) (xy 413.617262 -163.152529) (xy 413.648035 -163.199042)
			(xy 413.671707 -163.249539) (xy 413.687775 -163.302946) (xy 413.695895 -163.358122) (xy 413.696404 -163.386008)
			(xy 413.695895 -163.413894) (xy 413.687775 -163.46907) (xy 413.671707 -163.522477) (xy 413.648035 -163.572974)
			(xy 413.617262 -163.619487) (xy 413.580045 -163.661024) (xy 413.537177 -163.696699) (xy 413.489571 -163.725753)
			(xy 413.438242 -163.747565) (xy 413.384285 -163.761671) (xy 413.328848 -163.767771) (xy 413.273114 -163.765734)
			(xy 413.218271 -163.755604) (xy 413.165487 -163.737597) (xy 413.115887 -163.712096) (xy 413.070529 -163.679645)
			(xy 413.03038 -163.640936) (xy 412.996294 -163.596793) (xy 412.968998 -163.548158) (xy 412.949075 -163.496067)
			(xy 412.936949 -163.44163) (xy 412.932878 -163.386008) (xy 409.159661 -163.386008) (xy 408.983968 -166.705534)
			(xy 409.41193 -166.705534) (xy 409.416001 -166.649912) (xy 409.428127 -166.595475) (xy 409.44805 -166.543384)
			(xy 409.475346 -166.494749) (xy 409.509432 -166.450606) (xy 409.549581 -166.411897) (xy 409.594939 -166.379446)
			(xy 409.644539 -166.353945) (xy 409.697323 -166.335938) (xy 409.752166 -166.325808) (xy 409.8079 -166.323771)
			(xy 409.863337 -166.329871) (xy 409.917294 -166.343977) (xy 409.968623 -166.365789) (xy 410.016229 -166.394843)
			(xy 410.059097 -166.430518) (xy 410.096314 -166.472055) (xy 410.127087 -166.518568) (xy 410.150759 -166.569065)
			(xy 410.166827 -166.622472) (xy 410.174947 -166.677648) (xy 410.175456 -166.705534) (xy 410.42793 -166.705534)
			(xy 410.432001 -166.649912) (xy 410.444127 -166.595475) (xy 410.46405 -166.543384) (xy 410.491346 -166.494749)
			(xy 410.525432 -166.450606) (xy 410.565581 -166.411897) (xy 410.610939 -166.379446) (xy 410.660539 -166.353945)
			(xy 410.713323 -166.335938) (xy 410.768166 -166.325808) (xy 410.8239 -166.323771) (xy 410.879337 -166.329871)
			(xy 410.933294 -166.343977) (xy 410.984623 -166.365789) (xy 411.032229 -166.394843) (xy 411.075097 -166.430518)
			(xy 411.112314 -166.472055) (xy 411.143087 -166.518568) (xy 411.166759 -166.569065) (xy 411.182827 -166.622472)
			(xy 411.190947 -166.677648) (xy 411.191456 -166.705534) (xy 411.44393 -166.705534) (xy 411.448001 -166.649912)
			(xy 411.460127 -166.595475) (xy 411.48005 -166.543384) (xy 411.507346 -166.494749) (xy 411.541432 -166.450606)
			(xy 411.581581 -166.411897) (xy 411.626939 -166.379446) (xy 411.676539 -166.353945) (xy 411.729323 -166.335938)
			(xy 411.784166 -166.325808) (xy 411.8399 -166.323771) (xy 411.895337 -166.329871) (xy 411.949294 -166.343977)
			(xy 412.000623 -166.365789) (xy 412.048229 -166.394843) (xy 412.091097 -166.430518) (xy 412.128314 -166.472055)
			(xy 412.159087 -166.518568) (xy 412.182759 -166.569065) (xy 412.198827 -166.622472) (xy 412.206947 -166.677648)
			(xy 412.207456 -166.705534) (xy 412.206947 -166.73342) (xy 412.198827 -166.788596) (xy 412.182759 -166.842003)
			(xy 412.159087 -166.8925) (xy 412.128314 -166.939013) (xy 412.091097 -166.98055) (xy 412.048229 -167.016225)
			(xy 412.000623 -167.045279) (xy 411.949294 -167.067091) (xy 411.895337 -167.081197) (xy 411.8399 -167.087297)
			(xy 411.784166 -167.08526) (xy 411.729323 -167.07513) (xy 411.676539 -167.057123) (xy 411.626939 -167.031622)
			(xy 411.581581 -166.999171) (xy 411.541432 -166.960462) (xy 411.507346 -166.916319) (xy 411.48005 -166.867684)
			(xy 411.460127 -166.815593) (xy 411.448001 -166.761156) (xy 411.44393 -166.705534) (xy 411.191456 -166.705534)
			(xy 411.190947 -166.73342) (xy 411.182827 -166.788596) (xy 411.166759 -166.842003) (xy 411.143087 -166.8925)
			(xy 411.112314 -166.939013) (xy 411.075097 -166.98055) (xy 411.032229 -167.016225) (xy 410.984623 -167.045279)
			(xy 410.933294 -167.067091) (xy 410.879337 -167.081197) (xy 410.8239 -167.087297) (xy 410.768166 -167.08526)
			(xy 410.713323 -167.07513) (xy 410.660539 -167.057123) (xy 410.610939 -167.031622) (xy 410.565581 -166.999171)
			(xy 410.525432 -166.960462) (xy 410.491346 -166.916319) (xy 410.46405 -166.867684) (xy 410.444127 -166.815593)
			(xy 410.432001 -166.761156) (xy 410.42793 -166.705534) (xy 410.175456 -166.705534) (xy 410.174947 -166.73342)
			(xy 410.166827 -166.788596) (xy 410.150759 -166.842003) (xy 410.127087 -166.8925) (xy 410.096314 -166.939013)
			(xy 410.059097 -166.98055) (xy 410.016229 -167.016225) (xy 409.968623 -167.045279) (xy 409.917294 -167.067091)
			(xy 409.863337 -167.081197) (xy 409.8079 -167.087297) (xy 409.752166 -167.08526) (xy 409.697323 -167.07513)
			(xy 409.644539 -167.057123) (xy 409.594939 -167.031622) (xy 409.549581 -166.999171) (xy 409.509432 -166.960462)
			(xy 409.475346 -166.916319) (xy 409.44805 -166.867684) (xy 409.428127 -166.815593) (xy 409.416001 -166.761156)
			(xy 409.41193 -166.705534) (xy 408.983968 -166.705534) (xy 408.686316 -172.329348) (xy 410.148022 -172.329348)
			(xy 410.152093 -172.273726) (xy 410.164219 -172.219289) (xy 410.184142 -172.167198) (xy 410.211438 -172.118563)
			(xy 410.245524 -172.07442) (xy 410.285673 -172.035711) (xy 410.331031 -172.00326) (xy 410.380631 -171.977759)
			(xy 410.433415 -171.959752) (xy 410.488258 -171.949622) (xy 410.543992 -171.947585) (xy 410.599429 -171.953685)
			(xy 410.653386 -171.967791) (xy 410.704715 -171.989603) (xy 410.752321 -172.018657) (xy 410.795189 -172.054332)
			(xy 410.832406 -172.095869) (xy 410.863179 -172.142382) (xy 410.886851 -172.192879) (xy 410.902919 -172.246286)
			(xy 410.911039 -172.301462) (xy 410.911548 -172.329348) (xy 410.911284 -172.343826) (xy 411.085282 -172.343826)
			(xy 411.089353 -172.288204) (xy 411.101479 -172.233767) (xy 411.121402 -172.181676) (xy 411.148698 -172.133041)
			(xy 411.182784 -172.088898) (xy 411.222933 -172.050189) (xy 411.268291 -172.017738) (xy 411.317891 -171.992237)
			(xy 411.370675 -171.97423) (xy 411.425518 -171.9641) (xy 411.481252 -171.962063) (xy 411.536689 -171.968163)
			(xy 411.590646 -171.982269) (xy 411.641975 -172.004081) (xy 411.689581 -172.033135) (xy 411.732449 -172.06881)
			(xy 411.769666 -172.110347) (xy 411.800439 -172.15686) (xy 411.824111 -172.207357) (xy 411.840179 -172.260764)
			(xy 411.848299 -172.31594) (xy 411.848808 -172.343826) (xy 411.848299 -172.371712) (xy 411.840179 -172.426888)
			(xy 411.824111 -172.480295) (xy 411.800439 -172.530792) (xy 411.769666 -172.577305) (xy 411.732449 -172.618842)
			(xy 411.689581 -172.654517) (xy 411.641975 -172.683571) (xy 411.590646 -172.705383) (xy 411.536689 -172.719489)
			(xy 411.481252 -172.725589) (xy 411.425518 -172.723552) (xy 411.370675 -172.713422) (xy 411.317891 -172.695415)
			(xy 411.268291 -172.669914) (xy 411.222933 -172.637463) (xy 411.182784 -172.598754) (xy 411.148698 -172.554611)
			(xy 411.121402 -172.505976) (xy 411.101479 -172.453885) (xy 411.089353 -172.399448) (xy 411.085282 -172.343826)
			(xy 410.911284 -172.343826) (xy 410.911039 -172.357234) (xy 410.902919 -172.41241) (xy 410.886851 -172.465817)
			(xy 410.863179 -172.516314) (xy 410.832406 -172.562827) (xy 410.795189 -172.604364) (xy 410.752321 -172.640039)
			(xy 410.704715 -172.669093) (xy 410.653386 -172.690905) (xy 410.599429 -172.705011) (xy 410.543992 -172.711111)
			(xy 410.488258 -172.709074) (xy 410.433415 -172.698944) (xy 410.380631 -172.680937) (xy 410.331031 -172.655436)
			(xy 410.285673 -172.622985) (xy 410.245524 -172.584276) (xy 410.211438 -172.540133) (xy 410.184142 -172.491498)
			(xy 410.164219 -172.439407) (xy 410.152093 -172.38497) (xy 410.148022 -172.329348) (xy 408.686316 -172.329348)
			(xy 408.587668 -174.1932) (xy 408.892246 -174.1932) (xy 408.896317 -174.137578) (xy 408.908443 -174.083141)
			(xy 408.928366 -174.03105) (xy 408.955662 -173.982415) (xy 408.989748 -173.938272) (xy 409.029897 -173.899563)
			(xy 409.075255 -173.867112) (xy 409.124855 -173.841611) (xy 409.177639 -173.823604) (xy 409.232482 -173.813474)
			(xy 409.288216 -173.811437) (xy 409.343653 -173.817537) (xy 409.39761 -173.831643) (xy 409.448939 -173.853455)
			(xy 409.496545 -173.882509) (xy 409.539413 -173.918184) (xy 409.57663 -173.959721) (xy 409.607403 -174.006234)
			(xy 409.631075 -174.056731) (xy 409.647143 -174.110138) (xy 409.655263 -174.165314) (xy 409.655772 -174.1932)
			(xy 409.655263 -174.221086) (xy 409.647143 -174.276262) (xy 409.631075 -174.329669) (xy 409.607403 -174.380166)
			(xy 409.57663 -174.426679) (xy 409.539413 -174.468216) (xy 409.496545 -174.503891) (xy 409.448939 -174.532945)
			(xy 409.39761 -174.554757) (xy 409.343653 -174.568863) (xy 409.288216 -174.574963) (xy 409.232482 -174.572926)
			(xy 409.177639 -174.562796) (xy 409.124855 -174.544789) (xy 409.075255 -174.519288) (xy 409.029897 -174.486837)
			(xy 408.989748 -174.448128) (xy 408.955662 -174.403985) (xy 408.928366 -174.35535) (xy 408.908443 -174.303259)
			(xy 408.896317 -174.248822) (xy 408.892246 -174.1932) (xy 408.587668 -174.1932) (xy 408.501025 -175.83023)
			(xy 410.059884 -175.83023) (xy 410.063955 -175.774608) (xy 410.076081 -175.720171) (xy 410.096004 -175.66808)
			(xy 410.1233 -175.619445) (xy 410.157386 -175.575302) (xy 410.197535 -175.536593) (xy 410.242893 -175.504142)
			(xy 410.292493 -175.478641) (xy 410.345277 -175.460634) (xy 410.40012 -175.450504) (xy 410.455854 -175.448467)
			(xy 410.511291 -175.454567) (xy 410.565248 -175.468673) (xy 410.616577 -175.490485) (xy 410.664183 -175.519539)
			(xy 410.707051 -175.555214) (xy 410.744268 -175.596751) (xy 410.775041 -175.643264) (xy 410.798713 -175.693761)
			(xy 410.814781 -175.747168) (xy 410.822901 -175.802344) (xy 410.82341 -175.83023) (xy 410.822901 -175.858116)
			(xy 410.814781 -175.913292) (xy 410.798713 -175.966699) (xy 410.775041 -176.017196) (xy 410.744268 -176.063709)
			(xy 410.707051 -176.105246) (xy 410.664183 -176.140921) (xy 410.616577 -176.169975) (xy 410.565248 -176.191787)
			(xy 410.511291 -176.205893) (xy 410.455854 -176.211993) (xy 410.40012 -176.209956) (xy 410.345277 -176.199826)
			(xy 410.292493 -176.181819) (xy 410.242893 -176.156318) (xy 410.197535 -176.123867) (xy 410.157386 -176.085158)
			(xy 410.1233 -176.041015) (xy 410.096004 -175.99238) (xy 410.076081 -175.940289) (xy 410.063955 -175.885852)
			(xy 410.059884 -175.83023) (xy 408.501025 -175.83023) (xy 408.317454 -179.2986) (xy 409.269182 -179.2986)
			(xy 409.273253 -179.242978) (xy 409.285379 -179.188541) (xy 409.305302 -179.13645) (xy 409.332598 -179.087815)
			(xy 409.366684 -179.043672) (xy 409.406833 -179.004963) (xy 409.452191 -178.972512) (xy 409.501791 -178.947011)
			(xy 409.554575 -178.929004) (xy 409.609418 -178.918874) (xy 409.665152 -178.916837) (xy 409.720589 -178.922937)
			(xy 409.774546 -178.937043) (xy 409.825875 -178.958855) (xy 409.873481 -178.987909) (xy 409.916349 -179.023584)
			(xy 409.953566 -179.065121) (xy 409.984339 -179.111634) (xy 410.008011 -179.162131) (xy 410.024079 -179.215538)
			(xy 410.032199 -179.270714) (xy 410.032708 -179.2986) (xy 411.250382 -179.2986) (xy 411.254453 -179.242978)
			(xy 411.266579 -179.188541) (xy 411.286502 -179.13645) (xy 411.313798 -179.087815) (xy 411.347884 -179.043672)
			(xy 411.388033 -179.004963) (xy 411.433391 -178.972512) (xy 411.482991 -178.947011) (xy 411.535775 -178.929004)
			(xy 411.590618 -178.918874) (xy 411.646352 -178.916837) (xy 411.701789 -178.922937) (xy 411.755746 -178.937043)
			(xy 411.807075 -178.958855) (xy 411.854681 -178.987909) (xy 411.897549 -179.023584) (xy 411.934766 -179.065121)
			(xy 411.965539 -179.111634) (xy 411.989211 -179.162131) (xy 412.005279 -179.215538) (xy 412.013399 -179.270714)
			(xy 412.013908 -179.2986) (xy 412.013399 -179.326486) (xy 412.005279 -179.381662) (xy 411.989211 -179.435069)
			(xy 411.965539 -179.485566) (xy 411.934766 -179.532079) (xy 411.897549 -179.573616) (xy 411.854681 -179.609291)
			(xy 411.807075 -179.638345) (xy 411.755746 -179.660157) (xy 411.701789 -179.674263) (xy 411.646352 -179.680363)
			(xy 411.590618 -179.678326) (xy 411.535775 -179.668196) (xy 411.482991 -179.650189) (xy 411.433391 -179.624688)
			(xy 411.388033 -179.592237) (xy 411.347884 -179.553528) (xy 411.313798 -179.509385) (xy 411.286502 -179.46075)
			(xy 411.266579 -179.408659) (xy 411.254453 -179.354222) (xy 411.250382 -179.2986) (xy 410.032708 -179.2986)
			(xy 410.032199 -179.326486) (xy 410.024079 -179.381662) (xy 410.008011 -179.435069) (xy 409.984339 -179.485566)
			(xy 409.953566 -179.532079) (xy 409.916349 -179.573616) (xy 409.873481 -179.609291) (xy 409.825875 -179.638345)
			(xy 409.774546 -179.660157) (xy 409.720589 -179.674263) (xy 409.665152 -179.680363) (xy 409.609418 -179.678326)
			(xy 409.554575 -179.668196) (xy 409.501791 -179.650189) (xy 409.452191 -179.624688) (xy 409.406833 -179.592237)
			(xy 409.366684 -179.553528) (xy 409.332598 -179.509385) (xy 409.305302 -179.46075) (xy 409.285379 -179.408659)
			(xy 409.273253 -179.354222) (xy 409.269182 -179.2986) (xy 408.317454 -179.2986) (xy 408.243286 -180.699918)
			(xy 413.180782 -180.699918) (xy 413.184853 -180.644296) (xy 413.196979 -180.589859) (xy 413.216902 -180.537768)
			(xy 413.244198 -180.489133) (xy 413.278284 -180.44499) (xy 413.318433 -180.406281) (xy 413.363791 -180.37383)
			(xy 413.413391 -180.348329) (xy 413.466175 -180.330322) (xy 413.521018 -180.320192) (xy 413.576752 -180.318155)
			(xy 413.632189 -180.324255) (xy 413.686146 -180.338361) (xy 413.737475 -180.360173) (xy 413.785081 -180.389227)
			(xy 413.827949 -180.424902) (xy 413.865166 -180.466439) (xy 413.895939 -180.512952) (xy 413.919611 -180.563449)
			(xy 413.935679 -180.616856) (xy 413.943799 -180.672032) (xy 413.944308 -180.699918) (xy 413.943799 -180.727804)
			(xy 413.935679 -180.78298) (xy 413.919611 -180.836387) (xy 413.895939 -180.886884) (xy 413.865166 -180.933397)
			(xy 413.827949 -180.974934) (xy 413.785081 -181.010609) (xy 413.737475 -181.039663) (xy 413.686146 -181.061475)
			(xy 413.632189 -181.075581) (xy 413.576752 -181.081681) (xy 413.521018 -181.079644) (xy 413.466175 -181.069514)
			(xy 413.413391 -181.051507) (xy 413.363791 -181.026006) (xy 413.318433 -180.993555) (xy 413.278284 -180.954846)
			(xy 413.244198 -180.910703) (xy 413.216902 -180.862068) (xy 413.196979 -180.809977) (xy 413.184853 -180.75554)
			(xy 413.180782 -180.699918) (xy 408.243286 -180.699918) (xy 408.095274 -183.496458) (xy 408.81884 -183.496458)
			(xy 408.822911 -183.440836) (xy 408.835037 -183.386399) (xy 408.85496 -183.334308) (xy 408.882256 -183.285673)
			(xy 408.916342 -183.24153) (xy 408.956491 -183.202821) (xy 409.001849 -183.17037) (xy 409.051449 -183.144869)
			(xy 409.104233 -183.126862) (xy 409.159076 -183.116732) (xy 409.21481 -183.114695) (xy 409.270247 -183.120795)
			(xy 409.324204 -183.134901) (xy 409.375533 -183.156713) (xy 409.423139 -183.185767) (xy 409.466007 -183.221442)
			(xy 409.503224 -183.262979) (xy 409.533997 -183.309492) (xy 409.557669 -183.359989) (xy 409.573737 -183.413396)
			(xy 409.581857 -183.468572) (xy 409.582366 -183.496458) (xy 409.581857 -183.524344) (xy 409.573737 -183.57952)
			(xy 409.557669 -183.632927) (xy 409.533997 -183.683424) (xy 409.527794 -183.6928) (xy 411.224982 -183.6928)
			(xy 411.229053 -183.637178) (xy 411.241179 -183.582741) (xy 411.261102 -183.53065) (xy 411.288398 -183.482015)
			(xy 411.322484 -183.437872) (xy 411.362633 -183.399163) (xy 411.407991 -183.366712) (xy 411.457591 -183.341211)
			(xy 411.510375 -183.323204) (xy 411.565218 -183.313074) (xy 411.620952 -183.311037) (xy 411.676389 -183.317137)
			(xy 411.730346 -183.331243) (xy 411.781675 -183.353055) (xy 411.829281 -183.382109) (xy 411.872149 -183.417784)
			(xy 411.909366 -183.459321) (xy 411.940139 -183.505834) (xy 411.963811 -183.556331) (xy 411.979879 -183.609738)
			(xy 411.987999 -183.664914) (xy 411.988508 -183.6928) (xy 411.987999 -183.720686) (xy 411.979879 -183.775862)
			(xy 411.963811 -183.829269) (xy 411.940139 -183.879766) (xy 411.909366 -183.926279) (xy 411.872149 -183.967816)
			(xy 411.829281 -184.003491) (xy 411.781675 -184.032545) (xy 411.730346 -184.054357) (xy 411.676389 -184.068463)
			(xy 411.620952 -184.074563) (xy 411.565218 -184.072526) (xy 411.510375 -184.062396) (xy 411.457591 -184.044389)
			(xy 411.407991 -184.018888) (xy 411.362633 -183.986437) (xy 411.322484 -183.947728) (xy 411.288398 -183.903585)
			(xy 411.261102 -183.85495) (xy 411.241179 -183.802859) (xy 411.229053 -183.748422) (xy 411.224982 -183.6928)
			(xy 409.527794 -183.6928) (xy 409.503224 -183.729937) (xy 409.466007 -183.771474) (xy 409.423139 -183.807149)
			(xy 409.375533 -183.836203) (xy 409.324204 -183.858015) (xy 409.270247 -183.872121) (xy 409.21481 -183.878221)
			(xy 409.159076 -183.876184) (xy 409.104233 -183.866054) (xy 409.051449 -183.848047) (xy 409.001849 -183.822546)
			(xy 408.956491 -183.790095) (xy 408.916342 -183.751386) (xy 408.882256 -183.707243) (xy 408.85496 -183.658608)
			(xy 408.835037 -183.606517) (xy 408.822911 -183.55208) (xy 408.81884 -183.496458) (xy 408.095274 -183.496458)
			(xy 408.018781 -184.941718) (xy 414.979864 -184.941718) (xy 414.983935 -184.886096) (xy 414.996061 -184.831659)
			(xy 415.015984 -184.779568) (xy 415.04328 -184.730933) (xy 415.077366 -184.68679) (xy 415.117515 -184.648081)
			(xy 415.162873 -184.61563) (xy 415.212473 -184.590129) (xy 415.265257 -184.572122) (xy 415.3201 -184.561992)
			(xy 415.375834 -184.559955) (xy 415.431271 -184.566055) (xy 415.485228 -184.580161) (xy 415.536557 -184.601973)
			(xy 415.584163 -184.631027) (xy 415.627031 -184.666702) (xy 415.664248 -184.708239) (xy 415.695021 -184.754752)
			(xy 415.718693 -184.805249) (xy 415.734761 -184.858656) (xy 415.742881 -184.913832) (xy 415.74339 -184.941718)
			(xy 415.742881 -184.969604) (xy 415.734761 -185.02478) (xy 415.718693 -185.078187) (xy 415.695021 -185.128684)
			(xy 415.664248 -185.175197) (xy 415.627031 -185.216734) (xy 415.584163 -185.252409) (xy 415.536557 -185.281463)
			(xy 415.485228 -185.303275) (xy 415.431271 -185.317381) (xy 415.375834 -185.323481) (xy 415.3201 -185.321444)
			(xy 415.265257 -185.311314) (xy 415.212473 -185.293307) (xy 415.162873 -185.267806) (xy 415.117515 -185.235355)
			(xy 415.077366 -185.196646) (xy 415.04328 -185.152503) (xy 415.015984 -185.103868) (xy 414.996061 -185.051777)
			(xy 414.983935 -184.99734) (xy 414.979864 -184.941718) (xy 408.018781 -184.941718) (xy 407.913169 -186.937142)
			(xy 408.89504 -186.937142) (xy 408.899111 -186.88152) (xy 408.911237 -186.827083) (xy 408.93116 -186.774992)
			(xy 408.958456 -186.726357) (xy 408.992542 -186.682214) (xy 409.032691 -186.643505) (xy 409.078049 -186.611054)
			(xy 409.127649 -186.585553) (xy 409.180433 -186.567546) (xy 409.235276 -186.557416) (xy 409.29101 -186.555379)
			(xy 409.346447 -186.561479) (xy 409.400404 -186.575585) (xy 409.451733 -186.597397) (xy 409.499339 -186.626451)
			(xy 409.542207 -186.662126) (xy 409.579424 -186.703663) (xy 409.610197 -186.750176) (xy 409.633869 -186.800673)
			(xy 409.649937 -186.85408) (xy 409.658057 -186.909256) (xy 409.658566 -186.937142) (xy 409.658057 -186.965028)
			(xy 409.649937 -187.020204) (xy 409.633869 -187.073611) (xy 409.610197 -187.124108) (xy 409.579424 -187.170621)
			(xy 409.542207 -187.212158) (xy 409.499339 -187.247833) (xy 409.451733 -187.276887) (xy 409.400404 -187.298699)
			(xy 409.346447 -187.312805) (xy 409.29101 -187.318905) (xy 409.235276 -187.316868) (xy 409.180433 -187.306738)
			(xy 409.127649 -187.288731) (xy 409.078049 -187.26323) (xy 409.032691 -187.230779) (xy 408.992542 -187.19207)
			(xy 408.958456 -187.147927) (xy 408.93116 -187.099292) (xy 408.911237 -187.047201) (xy 408.899111 -186.992764)
			(xy 408.89504 -186.937142) (xy 407.913169 -186.937142) (xy 407.881886 -187.5282) (xy 411.123382 -187.5282)
			(xy 411.127453 -187.472578) (xy 411.139579 -187.418141) (xy 411.159502 -187.36605) (xy 411.186798 -187.317415)
			(xy 411.220884 -187.273272) (xy 411.261033 -187.234563) (xy 411.306391 -187.202112) (xy 411.355991 -187.176611)
			(xy 411.408775 -187.158604) (xy 411.463618 -187.148474) (xy 411.519352 -187.146437) (xy 411.574789 -187.152537)
			(xy 411.628746 -187.166643) (xy 411.680075 -187.188455) (xy 411.727681 -187.217509) (xy 411.770549 -187.253184)
			(xy 411.807766 -187.294721) (xy 411.838539 -187.341234) (xy 411.862211 -187.391731) (xy 411.878279 -187.445138)
			(xy 411.886399 -187.500314) (xy 411.886908 -187.5282) (xy 411.886399 -187.556086) (xy 411.878279 -187.611262)
			(xy 411.862211 -187.664669) (xy 411.838539 -187.715166) (xy 411.807766 -187.761679) (xy 411.770549 -187.803216)
			(xy 411.727681 -187.838891) (xy 411.680075 -187.867945) (xy 411.628746 -187.889757) (xy 411.574789 -187.903863)
			(xy 411.519352 -187.909963) (xy 411.463618 -187.907926) (xy 411.408775 -187.897796) (xy 411.355991 -187.879789)
			(xy 411.306391 -187.854288) (xy 411.261033 -187.821837) (xy 411.220884 -187.783128) (xy 411.186798 -187.738985)
			(xy 411.159502 -187.69035) (xy 411.139579 -187.638259) (xy 411.127453 -187.583822) (xy 411.123382 -187.5282)
			(xy 407.881886 -187.5282) (xy 407.798308 -189.107318) (xy 410.255464 -189.107318) (xy 410.259535 -189.051696)
			(xy 410.271661 -188.997259) (xy 410.291584 -188.945168) (xy 410.31888 -188.896533) (xy 410.352966 -188.85239)
			(xy 410.393115 -188.813681) (xy 410.438473 -188.78123) (xy 410.488073 -188.755729) (xy 410.540857 -188.737722)
			(xy 410.5957 -188.727592) (xy 410.651434 -188.725555) (xy 410.706871 -188.731655) (xy 410.760828 -188.745761)
			(xy 410.812157 -188.767573) (xy 410.859763 -188.796627) (xy 410.902631 -188.832302) (xy 410.939848 -188.873839)
			(xy 410.970621 -188.920352) (xy 410.994293 -188.970849) (xy 411.010361 -189.024256) (xy 411.018481 -189.079432)
			(xy 411.01899 -189.107318) (xy 411.018481 -189.135204) (xy 411.010361 -189.19038) (xy 410.994293 -189.243787)
			(xy 410.970621 -189.294284) (xy 410.939848 -189.340797) (xy 410.902631 -189.382334) (xy 410.859763 -189.418009)
			(xy 410.812157 -189.447063) (xy 410.760828 -189.468875) (xy 410.706871 -189.482981) (xy 410.651434 -189.489081)
			(xy 410.5957 -189.487044) (xy 410.540857 -189.476914) (xy 410.488073 -189.458907) (xy 410.438473 -189.433406)
			(xy 410.393115 -189.400955) (xy 410.352966 -189.362246) (xy 410.31888 -189.318103) (xy 410.291584 -189.269468)
			(xy 410.271661 -189.217377) (xy 410.259535 -189.16294) (xy 410.255464 -189.107318) (xy 407.798308 -189.107318)
			(xy 407.761056 -189.811152) (xy 413.217104 -189.811152) (xy 413.221175 -189.75553) (xy 413.233301 -189.701093)
			(xy 413.253224 -189.649002) (xy 413.28052 -189.600367) (xy 413.314606 -189.556224) (xy 413.354755 -189.517515)
			(xy 413.400113 -189.485064) (xy 413.449713 -189.459563) (xy 413.502497 -189.441556) (xy 413.55734 -189.431426)
			(xy 413.613074 -189.429389) (xy 413.668511 -189.435489) (xy 413.722468 -189.449595) (xy 413.773797 -189.471407)
			(xy 413.821403 -189.500461) (xy 413.864271 -189.536136) (xy 413.901488 -189.577673) (xy 413.932261 -189.624186)
			(xy 413.955933 -189.674683) (xy 413.972001 -189.72809) (xy 413.980121 -189.783266) (xy 413.98063 -189.811152)
			(xy 413.980121 -189.839038) (xy 413.972001 -189.894214) (xy 413.955933 -189.947621) (xy 413.932261 -189.998118)
			(xy 413.901488 -190.044631) (xy 413.864271 -190.086168) (xy 413.821403 -190.121843) (xy 413.773797 -190.150897)
			(xy 413.722468 -190.172709) (xy 413.668511 -190.186815) (xy 413.613074 -190.192915) (xy 413.55734 -190.190878)
			(xy 413.502497 -190.180748) (xy 413.449713 -190.162741) (xy 413.400113 -190.13724) (xy 413.354755 -190.104789)
			(xy 413.314606 -190.06608) (xy 413.28052 -190.021937) (xy 413.253224 -189.973302) (xy 413.233301 -189.921211)
			(xy 413.221175 -189.866774) (xy 413.217104 -189.811152) (xy 407.761056 -189.811152) (xy 407.570978 -193.402458)
			(xy 409.211524 -193.402458) (xy 409.215595 -193.346836) (xy 409.227721 -193.292399) (xy 409.247644 -193.240308)
			(xy 409.27494 -193.191673) (xy 409.309026 -193.14753) (xy 409.349175 -193.108821) (xy 409.394533 -193.07637)
			(xy 409.444133 -193.050869) (xy 409.496917 -193.032862) (xy 409.55176 -193.022732) (xy 409.607494 -193.020695)
			(xy 409.662931 -193.026795) (xy 409.716888 -193.040901) (xy 409.768217 -193.062713) (xy 409.815823 -193.091767)
			(xy 409.858691 -193.127442) (xy 409.895908 -193.168979) (xy 409.926681 -193.215492) (xy 409.950353 -193.265989)
			(xy 409.951139 -193.2686) (xy 412.113982 -193.2686) (xy 412.118053 -193.212978) (xy 412.130179 -193.158541)
			(xy 412.150102 -193.10645) (xy 412.177398 -193.057815) (xy 412.211484 -193.013672) (xy 412.251633 -192.974963)
			(xy 412.296991 -192.942512) (xy 412.346591 -192.917011) (xy 412.399375 -192.899004) (xy 412.454218 -192.888874)
			(xy 412.509952 -192.886837) (xy 412.565389 -192.892937) (xy 412.619346 -192.907043) (xy 412.670675 -192.928855)
			(xy 412.718281 -192.957909) (xy 412.761149 -192.993584) (xy 412.798366 -193.035121) (xy 412.829139 -193.081634)
			(xy 412.852811 -193.132131) (xy 412.868879 -193.185538) (xy 412.876999 -193.240714) (xy 412.877508 -193.2686)
			(xy 412.876999 -193.296486) (xy 412.868879 -193.351662) (xy 412.852811 -193.405069) (xy 412.829139 -193.455566)
			(xy 412.798366 -193.502079) (xy 412.761149 -193.543616) (xy 412.718281 -193.579291) (xy 412.670675 -193.608345)
			(xy 412.619346 -193.630157) (xy 412.565389 -193.644263) (xy 412.509952 -193.650363) (xy 412.454218 -193.648326)
			(xy 412.399375 -193.638196) (xy 412.346591 -193.620189) (xy 412.296991 -193.594688) (xy 412.251633 -193.562237)
			(xy 412.211484 -193.523528) (xy 412.177398 -193.479385) (xy 412.150102 -193.43075) (xy 412.130179 -193.378659)
			(xy 412.118053 -193.324222) (xy 412.113982 -193.2686) (xy 409.951139 -193.2686) (xy 409.966421 -193.319396)
			(xy 409.974541 -193.374572) (xy 409.97505 -193.402458) (xy 409.974541 -193.430344) (xy 409.966421 -193.48552)
			(xy 409.950353 -193.538927) (xy 409.926681 -193.589424) (xy 409.895908 -193.635937) (xy 409.858691 -193.677474)
			(xy 409.815823 -193.713149) (xy 409.768217 -193.742203) (xy 409.716888 -193.764015) (xy 409.662931 -193.778121)
			(xy 409.607494 -193.784221) (xy 409.55176 -193.782184) (xy 409.496917 -193.772054) (xy 409.444133 -193.754047)
			(xy 409.394533 -193.728546) (xy 409.349175 -193.696095) (xy 409.309026 -193.657386) (xy 409.27494 -193.613243)
			(xy 409.247644 -193.564608) (xy 409.227721 -193.512517) (xy 409.215595 -193.45808) (xy 409.211524 -193.402458)
			(xy 407.570978 -193.402458) (xy 407.373722 -197.1294) (xy 408.430982 -197.1294) (xy 408.435053 -197.073778)
			(xy 408.447179 -197.019341) (xy 408.467102 -196.96725) (xy 408.494398 -196.918615) (xy 408.528484 -196.874472)
			(xy 408.568633 -196.835763) (xy 408.613991 -196.803312) (xy 408.663591 -196.777811) (xy 408.716375 -196.759804)
			(xy 408.771218 -196.749674) (xy 408.826952 -196.747637) (xy 408.882389 -196.753737) (xy 408.888207 -196.755258)
			(xy 413.72104 -196.755258) (xy 413.725111 -196.699636) (xy 413.737237 -196.645199) (xy 413.75716 -196.593108)
			(xy 413.784456 -196.544473) (xy 413.818542 -196.50033) (xy 413.858691 -196.461621) (xy 413.904049 -196.42917)
			(xy 413.953649 -196.403669) (xy 414.006433 -196.385662) (xy 414.061276 -196.375532) (xy 414.11701 -196.373495)
			(xy 414.172447 -196.379595) (xy 414.226404 -196.393701) (xy 414.277733 -196.415513) (xy 414.325339 -196.444567)
			(xy 414.368207 -196.480242) (xy 414.405424 -196.521779) (xy 414.436197 -196.568292) (xy 414.459869 -196.618789)
			(xy 414.475937 -196.672196) (xy 414.484057 -196.727372) (xy 414.484566 -196.755258) (xy 414.484057 -196.783144)
			(xy 414.475937 -196.83832) (xy 414.459869 -196.891727) (xy 414.436197 -196.942224) (xy 414.405424 -196.988737)
			(xy 414.368207 -197.030274) (xy 414.325339 -197.065949) (xy 414.277733 -197.095003) (xy 414.226404 -197.116815)
			(xy 414.172447 -197.130921) (xy 414.11701 -197.137021) (xy 414.061276 -197.134984) (xy 414.006433 -197.124854)
			(xy 413.953649 -197.106847) (xy 413.904049 -197.081346) (xy 413.858691 -197.048895) (xy 413.818542 -197.010186)
			(xy 413.784456 -196.966043) (xy 413.75716 -196.917408) (xy 413.737237 -196.865317) (xy 413.725111 -196.81088)
			(xy 413.72104 -196.755258) (xy 408.888207 -196.755258) (xy 408.936346 -196.767843) (xy 408.987675 -196.789655)
			(xy 409.035281 -196.818709) (xy 409.078149 -196.854384) (xy 409.115366 -196.895921) (xy 409.146139 -196.942434)
			(xy 409.169811 -196.992931) (xy 409.185879 -197.046338) (xy 409.193999 -197.101514) (xy 409.194508 -197.1294)
			(xy 409.193999 -197.157286) (xy 409.185879 -197.212462) (xy 409.169811 -197.265869) (xy 409.146139 -197.316366)
			(xy 409.115366 -197.362879) (xy 409.078149 -197.404416) (xy 409.035281 -197.440091) (xy 408.987675 -197.469145)
			(xy 408.936346 -197.490957) (xy 408.882389 -197.505063) (xy 408.826952 -197.511163) (xy 408.771218 -197.509126)
			(xy 408.716375 -197.498996) (xy 408.663591 -197.480989) (xy 408.613991 -197.455488) (xy 408.568633 -197.423037)
			(xy 408.528484 -197.384328) (xy 408.494398 -197.340185) (xy 408.467102 -197.29155) (xy 408.447179 -197.239459)
			(xy 408.435053 -197.185022) (xy 408.430982 -197.1294) (xy 407.373722 -197.1294) (xy 407.316896 -198.203058)
			(xy 408.97124 -198.203058) (xy 408.975311 -198.147436) (xy 408.987437 -198.092999) (xy 409.00736 -198.040908)
			(xy 409.034656 -197.992273) (xy 409.068742 -197.94813) (xy 409.108891 -197.909421) (xy 409.154249 -197.87697)
			(xy 409.203849 -197.851469) (xy 409.256633 -197.833462) (xy 409.311476 -197.823332) (xy 409.36721 -197.821295)
			(xy 409.422647 -197.827395) (xy 409.476604 -197.841501) (xy 409.527933 -197.863313) (xy 409.575539 -197.892367)
			(xy 409.618407 -197.928042) (xy 409.655624 -197.969579) (xy 409.686397 -198.016092) (xy 409.710069 -198.066589)
			(xy 409.726137 -198.119996) (xy 409.734257 -198.175172) (xy 409.734766 -198.203058) (xy 409.734257 -198.230944)
			(xy 409.726137 -198.28612) (xy 409.710069 -198.339527) (xy 409.686397 -198.390024) (xy 409.655624 -198.436537)
			(xy 409.618407 -198.478074) (xy 409.575539 -198.513749) (xy 409.527933 -198.542803) (xy 409.476604 -198.564615)
			(xy 409.422647 -198.578721) (xy 409.36721 -198.584821) (xy 409.311476 -198.582784) (xy 409.256633 -198.572654)
			(xy 409.203849 -198.554647) (xy 409.154249 -198.529146) (xy 409.108891 -198.496695) (xy 409.068742 -198.457986)
			(xy 409.034656 -198.413843) (xy 409.00736 -198.365208) (xy 408.987437 -198.313117) (xy 408.975311 -198.25868)
			(xy 408.97124 -198.203058) (xy 407.316896 -198.203058) (xy 407.222792 -199.981058) (xy 413.61944 -199.981058)
			(xy 413.623511 -199.925436) (xy 413.635637 -199.870999) (xy 413.65556 -199.818908) (xy 413.682856 -199.770273)
			(xy 413.716942 -199.72613) (xy 413.757091 -199.687421) (xy 413.802449 -199.65497) (xy 413.852049 -199.629469)
			(xy 413.904833 -199.611462) (xy 413.959676 -199.601332) (xy 414.01541 -199.599295) (xy 414.070847 -199.605395)
			(xy 414.124804 -199.619501) (xy 414.176133 -199.641313) (xy 414.223739 -199.670367) (xy 414.266607 -199.706042)
			(xy 414.303824 -199.747579) (xy 414.334597 -199.794092) (xy 414.358269 -199.844589) (xy 414.374337 -199.897996)
			(xy 414.382457 -199.953172) (xy 414.382966 -199.981058) (xy 414.382457 -200.008944) (xy 414.374337 -200.06412)
			(xy 414.358269 -200.117527) (xy 414.334597 -200.168024) (xy 414.303824 -200.214537) (xy 414.266607 -200.256074)
			(xy 414.223739 -200.291749) (xy 414.176133 -200.320803) (xy 414.124804 -200.342615) (xy 414.070847 -200.356721)
			(xy 414.01541 -200.362821) (xy 413.959676 -200.360784) (xy 413.904833 -200.350654) (xy 413.852049 -200.332647)
			(xy 413.802449 -200.307146) (xy 413.757091 -200.274695) (xy 413.716942 -200.235986) (xy 413.682856 -200.191843)
			(xy 413.65556 -200.143208) (xy 413.635637 -200.091117) (xy 413.623511 -200.03668) (xy 413.61944 -199.981058)
			(xy 407.222792 -199.981058) (xy 407.117933 -201.962258) (xy 409.033724 -201.962258) (xy 409.037795 -201.906636)
			(xy 409.049921 -201.852199) (xy 409.069844 -201.800108) (xy 409.09714 -201.751473) (xy 409.131226 -201.70733)
			(xy 409.171375 -201.668621) (xy 409.216733 -201.63617) (xy 409.266333 -201.610669) (xy 409.319117 -201.592662)
			(xy 409.37396 -201.582532) (xy 409.429694 -201.580495) (xy 409.485131 -201.586595) (xy 409.539088 -201.600701)
			(xy 409.590417 -201.622513) (xy 409.638023 -201.651567) (xy 409.680891 -201.687242) (xy 409.718108 -201.728779)
			(xy 409.748881 -201.775292) (xy 409.772553 -201.825789) (xy 409.788621 -201.879196) (xy 409.796741 -201.934372)
			(xy 409.79725 -201.962258) (xy 409.796741 -201.990144) (xy 409.788621 -202.04532) (xy 409.772553 -202.098727)
			(xy 409.748881 -202.149224) (xy 409.718108 -202.195737) (xy 409.680891 -202.237274) (xy 409.638023 -202.272949)
			(xy 409.590417 -202.302003) (xy 409.539088 -202.323815) (xy 409.485131 -202.337921) (xy 409.429694 -202.344021)
			(xy 409.37396 -202.341984) (xy 409.319117 -202.331854) (xy 409.266333 -202.313847) (xy 409.216733 -202.288346)
			(xy 409.171375 -202.255895) (xy 409.131226 -202.217186) (xy 409.09714 -202.173043) (xy 409.069844 -202.124408)
			(xy 409.049921 -202.072317) (xy 409.037795 -202.01788) (xy 409.033724 -201.962258) (xy 407.117933 -201.962258)
			(xy 407.090118 -202.487784) (xy 407.001684 -204.158596) (xy 407.590242 -204.158596) (xy 407.594313 -204.102974)
			(xy 407.606439 -204.048537) (xy 407.626362 -203.996446) (xy 407.653658 -203.947811) (xy 407.687744 -203.903668)
			(xy 407.727893 -203.864959) (xy 407.773251 -203.832508) (xy 407.822851 -203.807007) (xy 407.875635 -203.789)
			(xy 407.930478 -203.77887) (xy 407.986212 -203.776833) (xy 408.041649 -203.782933) (xy 408.095606 -203.797039)
			(xy 408.146935 -203.818851) (xy 408.194541 -203.847905) (xy 408.237409 -203.88358) (xy 408.274626 -203.925117)
			(xy 408.305399 -203.97163) (xy 408.329071 -204.022127) (xy 408.345139 -204.075534) (xy 408.353259 -204.13071)
			(xy 408.353768 -204.158596) (xy 408.353259 -204.186482) (xy 408.345139 -204.241658) (xy 408.329071 -204.295065)
			(xy 408.305399 -204.345562) (xy 408.274626 -204.392075) (xy 408.237409 -204.433612) (xy 408.194541 -204.469287)
			(xy 408.146935 -204.498341) (xy 408.095606 -204.520153) (xy 408.041649 -204.534259) (xy 407.986212 -204.540359)
			(xy 407.930478 -204.538322) (xy 407.875635 -204.528192) (xy 407.822851 -204.510185) (xy 407.773251 -204.484684)
			(xy 407.727893 -204.452233) (xy 407.687744 -204.413524) (xy 407.653658 -204.369381) (xy 407.626362 -204.320746)
			(xy 407.606439 -204.268655) (xy 407.594313 -204.214218) (xy 407.590242 -204.158596) (xy 407.001684 -204.158596)
			(xy 406.79477 -208.06791) (xy 407.722068 -208.06791) (xy 407.726139 -208.012288) (xy 407.738265 -207.957851)
			(xy 407.758188 -207.90576) (xy 407.785484 -207.857125) (xy 407.81957 -207.812982) (xy 407.859719 -207.774273)
			(xy 407.905077 -207.741822) (xy 407.954677 -207.716321) (xy 408.007461 -207.698314) (xy 408.062304 -207.688184)
			(xy 408.118038 -207.686147) (xy 408.173475 -207.692247) (xy 408.227432 -207.706353) (xy 408.278761 -207.728165)
			(xy 408.326367 -207.757219) (xy 408.369235 -207.792894) (xy 408.406452 -207.834431) (xy 408.437225 -207.880944)
			(xy 408.460897 -207.931441) (xy 408.476965 -207.984848) (xy 408.485085 -208.040024) (xy 408.485594 -208.06791)
			(xy 408.485085 -208.095796) (xy 408.476965 -208.150972) (xy 408.460897 -208.204379) (xy 408.437225 -208.254876)
			(xy 408.406452 -208.301389) (xy 408.369235 -208.342926) (xy 408.326367 -208.378601) (xy 408.278761 -208.407655)
			(xy 408.227432 -208.429467) (xy 408.173475 -208.443573) (xy 408.118038 -208.449673) (xy 408.062304 -208.447636)
			(xy 408.007461 -208.437506) (xy 407.954677 -208.419499) (xy 407.905077 -208.393998) (xy 407.859719 -208.361547)
			(xy 407.81957 -208.322838) (xy 407.785484 -208.278695) (xy 407.758188 -208.23006) (xy 407.738265 -208.177969)
			(xy 407.726139 -208.123532) (xy 407.722068 -208.06791) (xy 406.79477 -208.06791) (xy 406.674421 -210.341718)
			(xy 409.3497 -210.341718) (xy 409.353771 -210.286096) (xy 409.365897 -210.231659) (xy 409.38582 -210.179568)
			(xy 409.413116 -210.130933) (xy 409.447202 -210.08679) (xy 409.487351 -210.048081) (xy 409.532709 -210.01563)
			(xy 409.582309 -209.990129) (xy 409.635093 -209.972122) (xy 409.689936 -209.961992) (xy 409.74567 -209.959955)
			(xy 409.801107 -209.966055) (xy 409.855064 -209.980161) (xy 409.906393 -210.001973) (xy 409.953999 -210.031027)
			(xy 409.996867 -210.066702) (xy 410.034084 -210.108239) (xy 410.064857 -210.154752) (xy 410.088529 -210.205249)
			(xy 410.104597 -210.258656) (xy 410.112717 -210.313832) (xy 410.113226 -210.341718) (xy 410.112717 -210.369604)
			(xy 410.104597 -210.42478) (xy 410.088529 -210.478187) (xy 410.064857 -210.528684) (xy 410.034084 -210.575197)
			(xy 409.996867 -210.616734) (xy 409.953999 -210.652409) (xy 409.906393 -210.681463) (xy 409.855064 -210.703275)
			(xy 409.801107 -210.717381) (xy 409.74567 -210.723481) (xy 409.689936 -210.721444) (xy 409.635093 -210.711314)
			(xy 409.582309 -210.693307) (xy 409.532709 -210.667806) (xy 409.487351 -210.635355) (xy 409.447202 -210.596646)
			(xy 409.413116 -210.552503) (xy 409.38582 -210.503868) (xy 409.365897 -210.451777) (xy 409.353771 -210.39734)
			(xy 409.3497 -210.341718) (xy 406.674421 -210.341718) (xy 405.46528 -233.186478) (xy 405.465205 -233.196812)
			(xy 405.472293 -233.216203) (xy 405.478996 -233.22407) (xy 405.486362 -233.23169) (xy 405.495252 -233.2355)
			(xy 405.500092 -233.237502) (xy 405.510336 -233.239678) (xy 405.515572 -233.239818) (xy 408.399234 -233.239818)
			(xy 408.411024 -233.239139) (xy 408.432087 -233.228517) (xy 408.446236 -233.209642) (xy 408.449018 -233.198162)
			(xy 413.812228 -204.023468) (xy 413.813087 -204.018219) (xy 413.812833 -204.007587) (xy 413.81172 -204.002386)
			(xy 413.809406 -203.994204) (xy 413.800184 -203.979931) (xy 413.793686 -203.974446) (xy 413.723582 -203.918566)
			(xy 413.717994 -203.91452) (xy 413.705247 -203.909256) (xy 413.698436 -203.908152) (xy 413.691578 -203.907136)
			(xy 413.67837 -203.909168) (xy 413.671766 -203.911962) (xy 413.647559 -203.922083) (xy 413.597064 -203.936334)
			(xy 413.545092 -203.943525) (xy 413.518858 -203.943966) (xy 413.491612 -203.943477) (xy 413.437675 -203.935716)
			(xy 413.385391 -203.920359) (xy 413.335824 -203.897718) (xy 413.289984 -203.868254) (xy 413.248804 -203.832567)
			(xy 413.213121 -203.791382) (xy 413.183661 -203.745539) (xy 413.161026 -203.69597) (xy 413.145675 -203.643684)
			(xy 413.13792 -203.589746) (xy 413.13792 -203.535254) (xy 413.145675 -203.481316) (xy 413.161026 -203.42903)
			(xy 413.183661 -203.379461) (xy 413.213121 -203.333618) (xy 413.248804 -203.292433) (xy 413.289984 -203.256746)
			(xy 413.335824 -203.227282) (xy 413.385391 -203.204641) (xy 413.437675 -203.189284) (xy 413.491612 -203.181523)
			(xy 413.518858 -203.18095) (xy 413.548479 -203.181507) (xy 413.60701 -203.190659) (xy 413.663423 -203.208751)
			(xy 413.71636 -203.235346) (xy 413.764549 -203.269806) (xy 413.786066 -203.29017) (xy 413.78632 -203.290424)
			(xy 413.7928 -203.296191) (xy 413.808573 -203.303383) (xy 413.825839 -203.304921) (xy 413.834326 -203.303124)
			(xy 413.925258 -203.274168) (xy 413.936365 -203.269153) (xy 413.952551 -203.250983) (xy 413.956246 -203.23937)
			(xy 421.658796 -161.340038) (xy 421.659304 -161.33699) (xy 422.206928 -156.7434) (xy 422.207267 -156.739715)
			(xy 422.20701 -156.732321) (xy 422.20642 -156.728668) (xy 422.205404 -156.722826) (xy 422.202356 -156.715968)
			(xy 422.19076 -156.689832) (xy 422.174648 -156.634972) (xy 422.1669 -156.578323) (xy 422.16769 -156.521152)
			(xy 422.176999 -156.464738) (xy 422.194619 -156.410344) (xy 422.220157 -156.359187) (xy 422.236138 -156.335476)
			(xy 422.249854 -156.317188) (xy 422.250108 -156.316934) (xy 422.254009 -156.311759) (xy 422.259282 -156.299927)
			(xy 422.260522 -156.293566) (xy 422.297606 -155.981908) (xy 422.393872 -155.172918) (xy 422.397428 -155.143708)
			(xy 422.398203 -155.13354) (xy 422.392586 -155.113956) (xy 422.379784 -155.098107) (xy 422.371012 -155.092908)
			(xy 422.370758 -155.092654) (xy 422.348016 -155.080217) (xy 422.305816 -155.050118) (xy 422.268085 -155.014578)
			(xy 422.235517 -154.974253) (xy 422.208715 -154.929887) (xy 422.188172 -154.882297) (xy 422.174268 -154.832363)
			(xy 422.167259 -154.781005) (xy 422.166796 -154.755088) (xy 422.166875 -154.74235) (xy 422.168529 -154.716929)
			(xy 422.170098 -154.704288) (xy 422.174312 -154.67662) (xy 422.189785 -154.622834) (xy 422.212939 -154.571882)
			(xy 422.24328 -154.524853) (xy 422.280158 -154.482755) (xy 422.301162 -154.464258) (xy 422.322335 -154.446923)
			(xy 422.368692 -154.417849) (xy 422.418718 -154.395675) (xy 422.444926 -154.387804) (xy 422.45534 -154.384502)
			(xy 422.482264 -154.354022) (xy 422.487209 -154.348077) (xy 422.493539 -154.33398) (xy 422.49471 -154.326336)
			(xy 423.057066 -149.60981) (xy 423.069766 -149.503384) (xy 423.111168 -149.156166) (xy 423.111422 -149.152102)
			(xy 423.286936 -144.881092) (xy 423.31132 -144.287494) (xy 423.416984 -141.71676) (xy 423.419379 -141.670421)
			(xy 423.431716 -141.578449) (xy 423.441622 -141.533118) (xy 423.565066 -140.998702) (xy 423.566336 -140.989812)
			(xy 423.773854 -136.095232) (xy 423.853356 -134.218934) (xy 423.853356 -131.097782) (xy 423.853864 -131.068826)
			(xy 423.853864 -131.068318) (xy 423.854372 -131.056888) (xy 424.383962 -118.147084) (xy 424.384976 -118.125431)
			(xy 424.388661 -118.082236) (xy 424.391328 -118.060724) (xy 424.963844 -113.611406) (xy 424.964184 -113.601684)
			(xy 424.958431 -113.583116) (xy 424.946217 -113.567995) (xy 424.937936 -113.562892) (xy 424.927694 -113.557082)
			(xy 424.907869 -113.544371) (xy 424.898312 -113.537492) (xy 424.895264 -113.535206) (xy 424.874914 -113.519421)
			(xy 424.838233 -113.483269) (xy 424.806742 -113.442516) (xy 424.781014 -113.397901) (xy 424.761513 -113.350234)
			(xy 424.748594 -113.300379) (xy 424.74515 -113.274856) (xy 424.74388 -113.263172) (xy 424.742356 -113.229898)
			(xy 424.74288 -113.201387) (xy 424.751356 -113.144998) (xy 424.768135 -113.0905) (xy 424.792841 -113.039108)
			(xy 424.824924 -112.991968) (xy 424.863669 -112.95013) (xy 424.908212 -112.914529) (xy 424.957559 -112.885956)
			(xy 424.98391 -112.87506) (xy 424.994758 -112.870852) (xy 425.01687 -112.863605) (xy 425.028106 -112.860582)
			(xy 425.03217 -112.859566) (xy 425.043346 -112.856518) (xy 425.053252 -112.845342) (xy 425.05813 -112.839501)
			(xy 425.064467 -112.825673) (xy 425.065698 -112.818164) (xy 425.617894 -108.528358) (xy 425.866306 -106.598974)
			(xy 425.866758 -106.594849) (xy 425.866503 -106.586554) (xy 425.865798 -106.582464) (xy 425.864274 -106.575352)
			(xy 425.86021 -106.567986) (xy 425.845507 -106.539724) (xy 425.82468 -106.479524) (xy 425.814124 -106.416703)
			(xy 425.813474 -106.384852) (xy 425.813474 -106.383328) (xy 425.813474 -106.369358) (xy 425.813728 -106.364786)
			(xy 425.814998 -106.349292) (xy 425.816776 -106.334052) (xy 425.821303 -106.304628) (xy 425.838287 -106.247572)
			(xy 425.863918 -106.193842) (xy 425.897575 -106.14474) (xy 425.917614 -106.122724) (xy 425.923202 -106.116882)
			(xy 425.926504 -106.10977) (xy 425.928177 -106.106139) (xy 425.930473 -106.098482) (xy 425.931076 -106.09453)
			(xy 426.098208 -104.796336) (xy 426.104965 -104.74836) (xy 426.126596 -104.653912) (xy 426.157279 -104.562006)
			(xy 426.196724 -104.473506) (xy 426.220128 -104.431084) (xy 436.046626 -87.126318) (xy 436.051114 -87.117514)
			(xy 436.05368 -87.09794) (xy 436.048646 -87.07885) (xy 436.04307 -87.070692) (xy 436.019448 -87.03945)
			(xy 435.98719 -86.99627) (xy 435.982561 -86.990512) (xy 435.970685 -86.981733) (xy 435.963822 -86.978998)
			(xy 435.949598 -86.973664) (xy 435.943248 -86.975188) (xy 435.934866 -86.97722) (xy 435.913094 -86.982095)
			(xy 435.868783 -86.987312) (xy 435.846474 -86.987634) (xy 435.843934 -86.987634) (xy 435.816788 -86.986994)
			(xy 435.763084 -86.978977) (xy 435.711059 -86.963427) (xy 435.661764 -86.940658) (xy 435.616196 -86.91113)
			(xy 435.575273 -86.875441) (xy 435.539824 -86.83431) (xy 435.510565 -86.788568) (xy 435.488086 -86.739141)
			(xy 435.472841 -86.687026) (xy 435.46514 -86.633276) (xy 435.464712 -86.606126) (xy 435.465174 -86.578872)
			(xy 435.472928 -86.52492) (xy 435.488282 -86.47262) (xy 435.510923 -86.423038) (xy 435.540391 -86.377183)
			(xy 435.576084 -86.335989) (xy 435.617278 -86.300294) (xy 435.663133 -86.270826) (xy 435.712714 -86.248184)
			(xy 435.765014 -86.232829) (xy 435.818966 -86.225074) (xy 435.84622 -86.224618) (xy 435.873089 -86.225072)
			(xy 435.926295 -86.232606) (xy 435.977916 -86.247536) (xy 436.02693 -86.269566) (xy 436.072365 -86.29826)
			(xy 436.113321 -86.333049) (xy 436.148986 -86.373244) (xy 436.178654 -86.418049) (xy 436.201738 -86.466575)
			(xy 436.210202 -86.49208) (xy 436.210202 -86.492334) (xy 436.212662 -86.499253) (xy 436.220921 -86.511387)
			(xy 436.226458 -86.51621) (xy 436.232363 -86.520688) (xy 436.24604 -86.526379) (xy 436.253382 -86.527386)
			(xy 436.346092 -86.537292) (xy 436.35553 -86.537901) (xy 436.373764 -86.532933) (xy 436.38896 -86.521695)
			(xy 436.394352 -86.513924) (xy 440.39536 -79.468218) (xy 440.417742 -79.429765) (xy 440.468375 -79.356596)
			(xy 440.525326 -79.288229) (xy 440.556396 -79.256382) (xy 442.7474 -77.060298) (xy 442.747654 -77.060044)
			(xy 442.7601 -77.047344) (xy 442.761624 -77.046074) (xy 442.773562 -77.034136) (xy 442.794274 -77.013669)
			(xy 442.837735 -76.974909) (xy 442.86043 -76.956666) (xy 447.040508 -73.655428) (xy 447.041016 -73.65492)
			(xy 447.276474 -73.461626) (xy 447.276728 -73.461372) (xy 447.281808 -73.457308) (xy 450.15023 -69.279262)
			(xy 450.156504 -69.268897) (xy 450.159549 -69.244895) (xy 450.156072 -69.233288) (xy 450.132196 -69.166486)
			(xy 450.129963 -69.160897) (xy 450.123285 -69.150889) (xy 450.118988 -69.146674) (xy 450.118734 -69.14642)
			(xy 450.107304 -69.135752) (xy 450.097652 -69.12864) (xy 450.08419 -69.12102) (xy 450.083682 -69.120766)
			(xy 450.056758 -69.11086) (xy 450.05625 -69.11086) (xy 450.04228 -69.104764) (xy 450.041772 -69.104764)
			(xy 450.016372 -69.09181) (xy 450.015864 -69.09181) (xy 449.999775 -69.08284) (xy 449.969239 -69.062231)
			(xy 449.954904 -69.050662) (xy 449.946746 -69.043874) (xy 449.931114 -69.029517) (xy 449.923662 -69.02196)
			(xy 449.916804 -69.014848) (xy 449.889626 -69.002656) (xy 449.882006 -69.000116) (xy 449.869052 -68.998338)
			(xy 449.815712 -68.998338) (xy 449.815458 -68.998338) (xy 449.81091 -68.99846) (xy 449.801965 -69.000116)
			(xy 449.797678 -69.00164) (xy 449.777612 -69.01053) (xy 449.773163 -69.012622) (xy 449.765102 -69.018246)
			(xy 449.76161 -69.021706) (xy 449.743516 -69.03976) (xy 449.703371 -69.071398) (xy 449.659372 -69.097411)
			(xy 449.612301 -69.117336) (xy 449.562998 -69.130819) (xy 449.512339 -69.13762) (xy 449.486782 -69.138038)
			(xy 449.461271 -69.137612) (xy 449.410705 -69.130815) (xy 449.361493 -69.117344) (xy 449.314515 -69.09744)
			(xy 449.270605 -69.071456) (xy 449.250308 -69.055996) (xy 449.24726 -69.053456) (xy 449.245736 -69.05244)
			(xy 449.239132 -69.049138) (xy 449.23391 -69.046793) (xy 449.222756 -69.044227) (xy 449.217034 -69.044058)
			(xy 449.18503 -69.044058) (xy 449.18503 -69.032882) (xy 449.13423 -69.032882) (xy 449.125626 -69.033217)
			(xy 449.109395 -69.038929) (xy 449.10248 -69.044058) (xy 449.100956 -69.045328) (xy 449.080079 -69.062722)
			(xy 449.03433 -69.09204) (xy 448.984882 -69.114567) (xy 448.932737 -69.129848) (xy 448.878951 -69.137572)
			(xy 448.851782 -69.138038) (xy 448.824531 -69.137551) (xy 448.770583 -69.129793) (xy 448.718289 -69.114436)
			(xy 448.668712 -69.091794) (xy 448.622862 -69.062328) (xy 448.581671 -69.026637) (xy 448.545979 -68.985448)
			(xy 448.516511 -68.939598) (xy 448.493868 -68.890022) (xy 448.47851 -68.837728) (xy 448.47075 -68.783781)
			(xy 448.470274 -68.75653) (xy 448.470697 -68.731018) (xy 448.477487 -68.680447) (xy 448.49095 -68.631231)
			(xy 448.510846 -68.584245) (xy 448.536821 -68.540328) (xy 448.552316 -68.520056) (xy 448.554856 -68.517008)
			(xy 448.555872 -68.515484) (xy 448.559174 -68.50888) (xy 448.561513 -68.503656) (xy 448.564068 -68.492503)
			(xy 448.564254 -68.486782) (xy 448.564254 -68.454778) (xy 448.57543 -68.454778) (xy 448.57543 -68.403978)
			(xy 448.575101 -68.395373) (xy 448.569393 -68.379137) (xy 448.564254 -68.372228) (xy 448.562984 -68.370704)
			(xy 448.545593 -68.349827) (xy 448.51628 -68.304076) (xy 448.493758 -68.254627) (xy 448.478484 -68.202483)
			(xy 448.470767 -68.148698) (xy 448.470274 -68.12153) (xy 448.470735 -68.094275) (xy 448.478488 -68.04032)
			(xy 448.493841 -67.988018) (xy 448.516482 -67.938432) (xy 448.545949 -67.892574) (xy 448.581642 -67.851376)
			(xy 448.622836 -67.815678) (xy 448.66869 -67.786205) (xy 448.718272 -67.763558) (xy 448.770573 -67.748198)
			(xy 448.824527 -67.740438) (xy 448.851782 -67.740022) (xy 448.877294 -67.740445) (xy 448.927863 -67.747238)
			(xy 448.977078 -67.760703) (xy 449.024061 -67.780603) (xy 449.067975 -67.806582) (xy 449.088256 -67.822064)
			(xy 449.091304 -67.824604) (xy 449.092828 -67.82562) (xy 449.099432 -67.828922) (xy 449.104654 -67.831268)
			(xy 449.115808 -67.833839) (xy 449.12153 -67.834002) (xy 449.153534 -67.834002) (xy 449.153534 -67.845178)
			(xy 449.204334 -67.845178) (xy 449.212939 -67.844848) (xy 449.229175 -67.839141) (xy 449.236084 -67.834002)
			(xy 449.237608 -67.832732) (xy 449.258487 -67.815344) (xy 449.304239 -67.786036) (xy 449.353687 -67.763519)
			(xy 449.405832 -67.748249) (xy 449.459615 -67.740535) (xy 449.486782 -67.740022) (xy 449.512339 -67.740445)
			(xy 449.562998 -67.747246) (xy 449.612301 -67.760727) (xy 449.659372 -67.780651) (xy 449.703373 -67.806661)
			(xy 449.74352 -67.838297) (xy 449.76161 -67.856354) (xy 449.765107 -67.859808) (xy 449.773168 -67.86543)
			(xy 449.777612 -67.86753) (xy 449.797678 -67.87642) (xy 449.801964 -67.87795) (xy 449.810909 -67.879618)
			(xy 449.815458 -67.879722) (xy 449.869052 -67.879722) (xy 449.869306 -67.879722) (xy 449.873853 -67.879595)
			(xy 449.882794 -67.877926) (xy 449.887086 -67.87642) (xy 449.907152 -67.86753) (xy 449.911597 -67.865432)
			(xy 449.919648 -67.859798) (xy 449.923154 -67.856354) (xy 449.941248 -67.8383) (xy 449.981394 -67.806661)
			(xy 450.025393 -67.780647) (xy 450.072463 -67.760719) (xy 450.121766 -67.747233) (xy 450.172425 -67.740429)
			(xy 450.197982 -67.740022) (xy 450.225235 -67.740484) (xy 450.279186 -67.748239) (xy 450.331484 -67.763594)
			(xy 450.381065 -67.786236) (xy 450.426918 -67.815704) (xy 450.468111 -67.851398) (xy 450.503803 -67.892591)
			(xy 450.53327 -67.938446) (xy 450.55591 -67.988027) (xy 450.571263 -68.040326) (xy 450.579017 -68.094277)
			(xy 450.57949 -68.12153) (xy 450.579063 -68.147041) (xy 450.572266 -68.197607) (xy 450.558795 -68.246819)
			(xy 450.538892 -68.293798) (xy 450.51291 -68.337709) (xy 450.497448 -68.358004) (xy 450.494908 -68.361052)
			(xy 450.493892 -68.362576) (xy 450.49059 -68.36918) (xy 450.488248 -68.374403) (xy 450.485687 -68.385557)
			(xy 450.48551 -68.391278) (xy 450.48551 -68.423282) (xy 450.474334 -68.423282) (xy 450.474334 -68.474082)
			(xy 450.474672 -68.482684) (xy 450.480392 -68.498909) (xy 450.48551 -68.505832) (xy 450.48678 -68.507356)
			(xy 450.491352 -68.51269) (xy 450.491606 -68.512944) (xy 450.492876 -68.514468) (xy 450.503544 -68.527676)
			(xy 450.503544 -68.528184) (xy 450.504052 -68.528438) (xy 450.50771 -68.532981) (xy 450.516685 -68.540426)
			(xy 450.521832 -68.54317) (xy 450.527166 -68.54571) (xy 450.53885 -68.54825) (xy 450.568314 -68.547742)
			(xy 450.627496 -68.546218) (xy 450.639529 -68.545321) (xy 450.660754 -68.533918) (xy 450.668136 -68.524374)
			(xy 450.987922 -68.058792) (xy 450.987922 -68.058284) (xy 451.005702 -68.032122) (xy 451.011477 -68.022722)
			(xy 451.015152 -68.000994) (xy 451.012814 -67.990212) (xy 450.992748 -67.91579) (xy 450.9897 -67.907662)
			(xy 450.965316 -67.883278) (xy 450.957696 -67.879468) (xy 450.934204 -67.86728) (xy 450.890529 -67.837389)
			(xy 450.851408 -67.801746) (xy 450.81759 -67.761036) (xy 450.789727 -67.716041) (xy 450.768353 -67.667625)
			(xy 450.753879 -67.616719) (xy 450.746584 -67.5643) (xy 450.746114 -67.537838) (xy 450.746575 -67.510584)
			(xy 450.754327 -67.45663) (xy 450.76968 -67.404329) (xy 450.792321 -67.354745) (xy 450.821788 -67.308889)
			(xy 450.857482 -67.267694) (xy 450.898676 -67.231998) (xy 450.944531 -67.202529) (xy 450.994114 -67.179886)
			(xy 451.046414 -67.164531) (xy 451.100368 -67.156776) (xy 451.127622 -67.15633) (xy 451.153906 -67.156782)
			(xy 451.205972 -67.164033) (xy 451.256544 -67.178382) (xy 451.30466 -67.199555) (xy 451.327266 -67.212972)
			(xy 451.327774 -67.212972) (xy 451.328028 -67.213226) (xy 451.333246 -67.216168) (xy 451.344672 -67.21975)
			(xy 451.350634 -67.220338) (xy 451.362826 -67.221354) (xy 451.450964 -67.182492) (xy 451.461555 -67.17713)
			(xy 451.47666 -67.158854) (xy 451.47992 -67.14744) (xy 453.483472 -56.755284) (xy 453.483924 -56.751025)
			(xy 453.483536 -56.742469) (xy 453.48271 -56.738266) (xy 453.481635 -56.73375) (xy 453.478061 -56.725183)
			(xy 453.475598 -56.721248) (xy 453.472804 -56.71693) (xy 453.464422 -56.707024) (xy 453.449944 -56.693816)
			(xy 453.445118 -56.691276) (xy 453.419204 -56.676932) (xy 453.371755 -56.641486) (xy 453.330338 -56.599149)
			(xy 453.295944 -56.550932) (xy 453.269396 -56.497988) (xy 453.251328 -56.441584) (xy 453.242172 -56.383069)
			(xy 453.241664 -56.353456) (xy 453.242135 -56.326362) (xy 453.249796 -56.272719) (xy 453.264972 -56.2207)
			(xy 453.287356 -56.171353) (xy 453.316499 -56.12567) (xy 453.351814 -56.084571) (xy 453.39259 -56.048884)
			(xy 453.438006 -56.019326) (xy 453.46239 -56.007508) (xy 453.462644 -56.007508) (xy 453.471032 -56.003143)
			(xy 453.484063 -55.989459) (xy 453.49126 -55.971988) (xy 453.491854 -55.96255) (xy 453.48398 -55.48503)
			(xy 453.483614 -55.478108) (xy 453.479632 -55.464836) (xy 453.476106 -55.458868) (xy 453.459342 -55.432452)
			(xy 453.44969 -55.423562) (xy 453.443848 -55.420514) (xy 453.418044 -55.406165) (xy 453.370809 -55.370745)
			(xy 453.329591 -55.328475) (xy 453.295372 -55.280363) (xy 453.268969 -55.227556) (xy 453.251012 -55.171313)
			(xy 453.241929 -55.112976) (xy 453.24141 -55.083456) (xy 453.24268 -55.052976) (xy 453.244204 -55.038498)
			(xy 453.247704 -55.012728) (xy 453.260789 -54.962394) (xy 453.280593 -54.914306) (xy 453.306749 -54.869355)
			(xy 453.33877 -54.828376) (xy 453.376064 -54.792129) (xy 453.417938 -54.761286) (xy 453.440546 -54.74843)
			(xy 453.448166 -54.744366) (xy 453.45827 -54.736945) (xy 453.470267 -54.714968) (xy 453.471026 -54.702456)
			(xy 453.469248 -54.597046) (xy 453.466962 -54.443884) (xy 453.46614 -54.435367) (xy 453.459571 -54.419579)
			(xy 453.448157 -54.406847) (xy 453.4408 -54.402482) (xy 453.440546 -54.402482) (xy 453.415151 -54.38801)
			(xy 453.368694 -54.352542) (xy 453.328193 -54.310401) (xy 453.294597 -54.262574) (xy 453.268692 -54.21018)
			(xy 453.251084 -54.154447) (xy 453.242188 -54.09668) (xy 453.241664 -54.067456) (xy 453.242183 -54.039142)
			(xy 453.250561 -53.983138) (xy 453.267128 -53.928988) (xy 453.291517 -53.877883) (xy 453.323195 -53.830944)
			(xy 453.361463 -53.789205) (xy 453.405482 -53.753582) (xy 453.429624 -53.73878) (xy 453.43548 -53.735087)
			(xy 453.445132 -53.725171) (xy 453.448674 -53.719222) (xy 453.451468 -53.714142) (xy 453.454516 -53.701188)
			(xy 453.454262 -53.683154) (xy 453.449944 -53.4162) (xy 453.449204 -53.410634) (xy 453.445611 -53.399998)
			(xy 453.442832 -53.395118) (xy 453.425814 -53.3781) (xy 453.423274 -53.376576) (xy 453.399088 -53.361105)
			(xy 453.355231 -53.324053) (xy 453.317424 -53.280845) (xy 453.286523 -53.232458) (xy 453.263225 -53.179984)
			(xy 453.248057 -53.124611) (xy 453.244204 -53.09616) (xy 453.243188 -53.08727) (xy 453.241664 -53.051456)
			(xy 453.242133 -53.024351) (xy 453.249784 -52.970683) (xy 453.264942 -52.918635) (xy 453.287301 -52.86925)
			(xy 453.316413 -52.82352) (xy 453.351694 -52.782362) (xy 453.392436 -52.746602) (xy 453.414892 -52.731416)
			(xy 453.419464 -52.728114) (xy 453.427338 -52.72151) (xy 453.43191 -52.712874) (xy 453.43482 -52.707073)
			(xy 453.437908 -52.694471) (xy 453.438006 -52.687982) (xy 453.432926 -52.386484) (xy 453.432926 -52.38115)
			(xy 453.420988 -52.359306) (xy 453.416924 -52.356512) (xy 453.394263 -52.341357) (xy 453.353078 -52.305643)
			(xy 453.317391 -52.264433) (xy 453.287928 -52.218568) (xy 453.265288 -52.168977) (xy 453.249931 -52.116671)
			(xy 453.242169 -52.062713) (xy 453.241664 -52.035456) (xy 453.242095 -52.009623) (xy 453.249068 -51.95843)
			(xy 453.26288 -51.908644) (xy 453.283279 -51.861175) (xy 453.309892 -51.816891) (xy 453.342234 -51.7766)
			(xy 453.379714 -51.741038) (xy 453.400414 -51.725576) (xy 453.400668 -51.725322) (xy 453.405438 -51.721667)
			(xy 453.413268 -51.712554) (xy 453.416162 -51.707288) (xy 453.418956 -51.7017) (xy 453.42175 -51.689762)
			(xy 453.418194 -51.469036) (xy 453.416162 -51.363118) (xy 453.414833 -51.352328) (xy 453.404444 -51.333252)
			(xy 453.396096 -51.326288) (xy 453.395842 -51.326034) (xy 453.372365 -51.30788) (xy 453.330786 -51.265537)
			(xy 453.296251 -51.217276) (xy 453.26959 -51.164257) (xy 453.251443 -51.107756) (xy 453.242248 -51.049128)
			(xy 453.241664 -51.019456) (xy 453.242173 -50.990792) (xy 453.250733 -50.934106) (xy 453.267669 -50.879336)
			(xy 453.2926 -50.827713) (xy 453.324967 -50.780396) (xy 453.364042 -50.738447) (xy 453.38619 -50.720244)
			(xy 453.390508 -50.716688) (xy 453.39762 -50.707798) (xy 453.40016 -50.702464) (xy 453.402487 -50.697111)
			(xy 453.404912 -50.685695) (xy 453.404986 -50.679858) (xy 453.40143 -50.451766) (xy 453.398636 -50.288698)
			(xy 453.39724 -50.278374) (xy 453.387398 -50.260033) (xy 453.379586 -50.253138) (xy 453.379332 -50.252884)
			(xy 453.357028 -50.234689) (xy 453.31763 -50.192728) (xy 453.284981 -50.145325) (xy 453.259823 -50.093555)
			(xy 453.242726 -50.038595) (xy 453.234079 -49.981689) (xy 453.233536 -49.95291) (xy 453.234034 -49.925171)
			(xy 453.242071 -49.870279) (xy 453.257977 -49.81713) (xy 453.281416 -49.766846) (xy 453.311893 -49.72049)
			(xy 453.348765 -49.679039) (xy 453.36968 -49.66081) (xy 453.373998 -49.657254) (xy 453.380856 -49.64811)
			(xy 453.383396 -49.64303) (xy 453.385529 -49.637831) (xy 453.387697 -49.626806) (xy 453.387714 -49.621186)
			(xy 453.38619 -49.51984) (xy 453.382126 -49.28108) (xy 453.380796 -49.270244) (xy 453.370269 -49.251145)
			(xy 453.361806 -49.24425) (xy 453.361552 -49.243996) (xy 453.337935 -49.225878) (xy 453.296087 -49.18355)
			(xy 453.261319 -49.135239) (xy 453.234472 -49.082115) (xy 453.216198 -49.025468) (xy 453.20694 -48.966671)
			(xy 453.206358 -48.93691) (xy 453.206436 -48.924172) (xy 453.208089 -48.898751) (xy 453.20966 -48.88611)
			(xy 453.214091 -48.857062) (xy 453.230715 -48.800706) (xy 453.255781 -48.747563) (xy 453.288697 -48.698891)
			(xy 453.328684 -48.655839) (xy 453.351392 -48.63719) (xy 453.353932 -48.635158) (xy 453.361662 -48.627455)
			(xy 453.370353 -48.607457) (xy 453.370696 -48.59655) (xy 453.364092 -48.185324) (xy 453.356472 -47.709836)
			(xy 453.356278 -47.705545) (xy 453.354614 -47.697118) (xy 453.35317 -47.693072) (xy 453.35063 -47.686214)
			(xy 453.345296 -47.679356) (xy 453.329633 -47.659008) (xy 453.303328 -47.614907) (xy 453.283172 -47.567678)
			(xy 453.269528 -47.518174) (xy 453.262643 -47.467287) (xy 453.262238 -47.441612) (xy 453.262837 -47.411077)
			(xy 453.272558 -47.350786) (xy 453.291752 -47.292811) (xy 453.319932 -47.238631) (xy 453.337676 -47.213774)
			(xy 453.342756 -47.206916) (xy 453.345296 -47.199296) (xy 453.346479 -47.195276) (xy 453.347634 -47.186976)
			(xy 453.347582 -47.182786) (xy 453.330818 -46.161198) (xy 453.330459 -46.153366) (xy 453.32555 -46.138487)
			(xy 453.321166 -46.131988) (xy 453.319388 -46.129956) (xy 453.303216 -46.109459) (xy 453.27604 -46.064879)
			(xy 453.255203 -46.017007) (xy 453.241095 -45.966739) (xy 453.233981 -45.915015) (xy 453.233536 -45.88891)
			(xy 453.233938 -45.864036) (xy 453.240405 -45.814711) (xy 453.253231 -45.766646) (xy 453.272198 -45.720656)
			(xy 453.296984 -45.677523) (xy 453.311768 -45.657516) (xy 453.317102 -45.650404) (xy 453.319642 -45.642784)
			(xy 453.320825 -45.638764) (xy 453.321979 -45.630464) (xy 453.321928 -45.626274) (xy 453.3138 -45.1231)
			(xy 453.313368 -45.115488) (xy 453.308598 -45.101016) (xy 453.304402 -45.094652) (xy 453.287693 -45.070267)
			(xy 453.261205 -45.017422) (xy 453.243189 -44.961124) (xy 453.234074 -44.90272) (xy 453.233536 -44.873164)
			(xy 453.233536 -44.872656) (xy 453.234024 -44.844681) (xy 453.242197 -44.789331) (xy 453.258377 -44.735771)
			(xy 453.282214 -44.685152) (xy 453.29729 -44.661582) (xy 453.301608 -44.655232) (xy 453.303894 -44.647612)
			(xy 453.304892 -44.643948) (xy 453.305918 -44.636423) (xy 453.305926 -44.632626) (xy 453.296528 -44.080938)
			(xy 453.29475 -44.067984) (xy 453.292972 -44.061634) (xy 453.291956 -44.06011) (xy 453.289162 -44.055538)
			(xy 453.275984 -44.032986) (xy 453.255192 -43.98507) (xy 453.241107 -43.934772) (xy 453.233991 -43.883026)
			(xy 453.233536 -43.85691) (xy 453.233536 -43.842178) (xy 453.235298 -43.811807) (xy 453.247263 -43.752164)
			(xy 453.268555 -43.69518) (xy 453.283066 -43.668442) (xy 453.286368 -43.6626) (xy 453.287892 -43.657012)
			(xy 453.288856 -43.653471) (xy 453.289874 -43.646204) (xy 453.289924 -43.642534) (xy 453.286114 -43.422316)
			(xy 453.27951 -43.02887) (xy 453.276716 -43.017694) (xy 453.274176 -43.012614) (xy 453.261956 -42.987181)
			(xy 453.244296 -42.933593) (xy 453.234698 -42.877992) (xy 453.233536 -42.8498) (xy 453.233282 -42.837608)
			(xy 450.472302 -37.702744) (xy 450.472302 -37.70249) (xy 450.462142 -37.683694) (xy 449.95592 -36.755324)
			(xy 449.89369 -36.641024) (xy 449.879466 -36.614862) (xy 449.872862 -36.605464) (xy 449.861686 -36.592764)
			(xy 449.857114 -36.589462) (xy 449.829033 -36.568771) (xy 449.775517 -36.524026) (xy 449.75018 -36.500054)
			(xy 449.713325 -36.463695) (xy 449.646544 -36.384576) (xy 449.588329 -36.298958) (xy 449.563236 -36.253674)
			(xy 449.543678 -36.217098) (xy 449.540122 -36.21278) (xy 449.539868 -36.212526) (xy 449.506986 -36.173042)
			(xy 449.448699 -36.088416) (xy 449.423536 -36.043616) (xy 449.267834 -35.757866) (xy 449.211954 -35.655504)
			(xy 449.188752 -35.61169) (xy 449.150238 -35.520327) (xy 449.121076 -35.425564) (xy 449.101557 -35.328356)
			(xy 449.09613 -35.279076) (xy 449.095876 -35.277044) (xy 449.094372 -35.268349) (xy 449.086184 -35.252731)
			(xy 449.079874 -35.246564) (xy 449.078604 -35.245548) (xy 449.074286 -35.24123) (xy 449.071228 -35.238676)
			(xy 449.064463 -35.234469) (xy 449.060824 -35.232848) (xy 449.052696 -35.229546) (xy 449.044822 -35.22726)
			(xy 448.971924 -35.22726) (xy 448.967047 -35.227358) (xy 448.957459 -35.229151) (xy 448.952874 -35.230816)
			(xy 448.944238 -35.234372) (xy 448.936872 -35.241484) (xy 448.906001 -35.270423) (xy 448.840137 -35.323556)
			(xy 448.770008 -35.370916) (xy 448.696116 -35.412162) (xy 448.618995 -35.446997) (xy 448.539198 -35.475169)
			(xy 448.457301 -35.496477) (xy 448.373893 -35.510767) (xy 448.289574 -35.517936) (xy 448.247262 -35.518344)
			(xy 448.200748 -35.517807) (xy 448.108124 -35.509141) (xy 448.016709 -35.491888) (xy 447.927299 -35.466198)
			(xy 447.840668 -35.432295) (xy 447.757571 -35.390472) (xy 447.678729 -35.341094) (xy 447.604828 -35.284588)
			(xy 447.536509 -35.221447) (xy 447.474366 -35.152219) (xy 447.41894 -35.077505) (xy 447.39433 -35.03803)
			(xy 447.39179 -35.033712) (xy 447.3829 -35.023806) (xy 447.37655 -35.017964) (xy 447.354378 -34.999742)
			(xy 447.315233 -34.957777) (xy 447.282807 -34.910428) (xy 447.25783 -34.85876) (xy 447.240865 -34.803937)
			(xy 447.232293 -34.747192) (xy 447.23177 -34.718498) (xy 447.23177 -34.718244) (xy 447.232274 -34.689809)
			(xy 447.240691 -34.633567) (xy 447.248534 -34.60623) (xy 447.250058 -34.599118) (xy 447.251836 -34.588196)
			(xy 447.251836 -34.584386) (xy 447.251582 -34.581592) (xy 447.249804 -34.52114) (xy 447.249804 -34.502852)
			(xy 447.249804 -34.50082) (xy 447.250566 -34.481008) (xy 447.251577 -34.458462) (xy 447.25539 -34.413487)
			(xy 447.258186 -34.391092) (xy 447.265039 -34.343493) (xy 447.286722 -34.249796) (xy 447.317322 -34.158622)
			(xy 447.336418 -34.114486) (xy 447.339466 -34.104834) (xy 447.343022 -34.089594) (xy 447.343022 -34.088578)
			(xy 447.339466 -34.073338) (xy 447.336418 -34.063686) (xy 447.319739 -34.025283) (xy 447.29213 -33.946233)
			(xy 447.271252 -33.865144) (xy 447.257251 -33.78259) (xy 447.250227 -33.699152) (xy 447.249804 -33.657286)
			(xy 447.251836 -33.595564) (xy 447.252598 -33.585404) (xy 447.252598 -33.58388) (xy 447.251836 -33.581594)
			(xy 447.251328 -33.58007) (xy 447.250566 -33.578038) (xy 447.24193 -33.563814) (xy 447.235326 -33.554924)
			(xy 447.19367 -33.510982) (xy 447.1864 -33.504642) (xy 447.168509 -33.497471) (xy 447.158872 -33.497012)
			(xy 446.99428 -33.497012) (xy 446.946718 -33.496427) (xy 446.852035 -33.487256) (xy 446.758671 -33.469039)
			(xy 446.667486 -33.441945) (xy 446.623186 -33.424622) (xy 446.619884 -33.423352) (xy 446.613534 -33.420812)
			(xy 446.329562 -33.420812) (xy 446.328038 -33.420812) (xy 446.319508 -33.421398) (xy 446.303547 -33.427503)
			(xy 446.296796 -33.43275) (xy 446.265889 -33.461872) (xy 446.199903 -33.515335) (xy 446.129609 -33.562993)
			(xy 446.055518 -33.604502) (xy 445.978166 -33.63956) (xy 445.898112 -33.667914) (xy 445.815937 -33.689357)
			(xy 445.732237 -33.703736) (xy 445.647617 -33.710945) (xy 445.605154 -33.711388) (xy 445.591946 -33.711388)
			(xy 445.546083 -33.710256) (xy 445.454844 -33.700615) (xy 445.364875 -33.682635) (xy 445.276939 -33.656467)
			(xy 445.191778 -33.622332) (xy 445.110112 -33.58052) (xy 445.032632 -33.531383) (xy 444.959993 -33.475337)
			(xy 444.892808 -33.412856) (xy 444.831647 -33.344468) (xy 444.777026 -33.270752) (xy 444.75273 -33.231836)
			(xy 444.75019 -33.227772) (xy 444.737744 -33.214056) (xy 444.734442 -33.211516) (xy 444.712624 -33.193615)
			(xy 444.673992 -33.152476) (xy 444.64183 -33.106103) (xy 444.616838 -33.055504) (xy 444.599559 -33.001779)
			(xy 444.59037 -32.946098) (xy 444.589408 -32.917892) (xy 444.589662 -32.903922) (xy 444.590588 -32.877213)
			(xy 444.598999 -32.824438) (xy 444.606426 -32.798766) (xy 444.60795 -32.791654) (xy 444.609728 -32.780732)
			(xy 444.609728 -32.776922) (xy 444.609474 -32.774128) (xy 444.607696 -32.714692) (xy 444.607696 -32.707326)
			(xy 444.608295 -32.670113) (xy 444.614353 -32.595927) (xy 444.625928 -32.522399) (xy 444.634112 -32.486092)
			(xy 444.645477 -32.440144) (xy 444.675753 -32.350456) (xy 444.694564 -32.307022) (xy 444.696342 -32.302958)
			(xy 444.700914 -32.282892) (xy 444.700914 -32.281876) (xy 444.696342 -32.26181) (xy 444.695072 -32.259016)
			(xy 444.678949 -32.222083) (xy 444.652013 -32.146124) (xy 444.631285 -32.068242) (xy 444.616901 -31.988942)
			(xy 444.612522 -31.948882) (xy 444.610258 -31.924434) (xy 444.607845 -31.87539) (xy 444.607696 -31.850838)
			(xy 444.607696 -31.850584) (xy 444.609474 -31.789878) (xy 444.609728 -31.78683) (xy 444.609728 -31.78302)
			(xy 444.60795 -31.772098) (xy 444.606426 -31.76524) (xy 444.598598 -31.7379) (xy 444.590177 -31.68166)
			(xy 444.589662 -31.653226) (xy 444.589662 -31.652972) (xy 444.590207 -31.623901) (xy 444.599016 -31.566432)
			(xy 444.616428 -31.510959) (xy 444.642039 -31.458762) (xy 444.67526 -31.411047) (xy 444.715325 -31.368913)
			(xy 444.737998 -31.350712) (xy 444.743078 -31.34614) (xy 444.74892 -31.339028) (xy 444.771704 -31.30176)
			(xy 444.822861 -31.230949) (xy 444.880021 -31.164888) (xy 444.942745 -31.104085) (xy 445.010551 -31.049006)
			(xy 445.082918 -31.000075) (xy 445.159291 -30.957667) (xy 445.199008 -30.939486) (xy 445.237372 -30.92286)
			(xy 445.316333 -30.895342) (xy 445.39732 -30.87453) (xy 445.479766 -30.860571) (xy 445.563091 -30.853563)
			(xy 445.6049 -30.853126) (xy 445.605154 -30.853126) (xy 445.647735 -30.853574) (xy 445.732587 -30.860839)
			(xy 445.816511 -30.875309) (xy 445.898896 -30.896882) (xy 445.979143 -30.925398) (xy 446.056666 -30.960651)
			(xy 446.130902 -31.002384) (xy 446.20131 -31.050294) (xy 446.267378 -31.104031) (xy 446.29832 -31.133288)
			(xy 446.304585 -31.137829) (xy 446.319062 -31.143272) (xy 446.326768 -31.143956) (xy 447.176906 -31.143956)
			(xy 447.184272 -31.143448) (xy 447.192622 -31.14185) (xy 447.207663 -31.133947) (xy 447.219318 -31.121582)
			(xy 447.223134 -31.113984) (xy 447.232532 -31.09087) (xy 447.233294 -31.08325) (xy 447.233294 -31.082996)
			(xy 447.234056 -31.07563) (xy 447.236214 -31.057771) (xy 447.243467 -31.022533) (xy 447.248534 -31.005272)
			(xy 447.250058 -30.99816) (xy 447.251836 -30.987238) (xy 447.251836 -30.983428) (xy 447.251582 -30.980634)
			(xy 447.249804 -30.921452) (xy 447.249804 -30.92069) (xy 447.250245 -30.878825) (xy 447.257284 -30.79539)
			(xy 447.271286 -30.712838) (xy 447.292153 -30.631748) (xy 447.319738 -30.552691) (xy 447.336418 -30.51429)
			(xy 447.339466 -30.504638) (xy 447.343022 -30.489398) (xy 447.343022 -30.488382) (xy 447.339466 -30.473142)
			(xy 447.336418 -30.46349) (xy 447.32028 -30.426347) (xy 447.293365 -30.349961) (xy 447.27273 -30.271644)
			(xy 447.258509 -30.191913) (xy 447.250797 -30.111291) (xy 447.249804 -30.070806) (xy 447.249804 -30.056836)
			(xy 447.250058 -30.034738) (xy 447.250312 -30.03042) (xy 447.250312 -30.029912) (xy 447.250566 -30.021784)
			(xy 447.250566 -30.019752) (xy 447.246756 -30.0101) (xy 447.244784 -30.005619) (xy 447.239415 -29.997435)
			(xy 447.236088 -29.993844) (xy 447.191892 -29.948632) (xy 447.18565 -29.943204) (xy 447.170618 -29.936324)
			(xy 447.162428 -29.93517) (xy 447.157094 -29.934916) (xy 447.080386 -29.934916) (xy 447.033639 -29.93435)
			(xy 446.940567 -29.925477) (xy 446.84875 -29.90785) (xy 446.75901 -29.881626) (xy 446.672148 -29.84704)
			(xy 446.630298 -29.826204) (xy 446.624872 -29.823616) (xy 446.613193 -29.820783) (xy 446.607184 -29.820616)
			(xy 446.339214 -29.820616) (xy 446.334324 -29.820756) (xy 446.324734 -29.822681) (xy 446.320164 -29.824426)
			(xy 446.295018 -29.834586) (xy 446.287906 -29.84119) (xy 446.253412 -29.872857) (xy 446.179447 -29.930291)
			(xy 446.100426 -29.980542) (xy 446.017045 -30.023168) (xy 445.930036 -30.057793) (xy 445.840166 -30.084114)
			(xy 445.748225 -30.101899) (xy 445.655022 -30.110991) (xy 445.608202 -30.1117) (xy 445.598296 -30.1117)
			(xy 445.551467 -30.110837) (xy 445.458275 -30.101402) (xy 445.366378 -30.083272) (xy 445.276585 -30.056607)
			(xy 445.189688 -30.021642) (xy 445.106451 -29.978684) (xy 445.027607 -29.928113) (xy 444.953852 -29.870374)
			(xy 444.885834 -29.805974) (xy 444.854584 -29.771086) (xy 444.826513 -29.738272) (xy 444.775518 -29.668574)
			(xy 444.75273 -29.631894) (xy 444.75019 -29.62783) (xy 444.737744 -29.614114) (xy 444.734442 -29.611574)
			(xy 444.712301 -29.593379) (xy 444.673202 -29.551484) (xy 444.640799 -29.50422) (xy 444.615817 -29.452646)
			(xy 444.598818 -29.39792) (xy 444.590183 -29.341268) (xy 444.589662 -29.312616) (xy 444.589662 -29.312108)
			(xy 444.589662 -29.30525) (xy 444.590678 -29.283152) (xy 444.594742 -29.249116) (xy 444.596826 -29.237353)
			(xy 444.60229 -29.214094) (xy 444.605664 -29.202634) (xy 444.605664 -29.202126) (xy 444.607442 -29.196284)
			(xy 444.609728 -29.181552) (xy 444.609728 -29.177742) (xy 444.609474 -29.174948) (xy 444.607696 -29.115258)
			(xy 444.607696 -29.114242) (xy 444.60813 -29.072295) (xy 444.615179 -28.988698) (xy 444.629223 -28.905988)
			(xy 444.650162 -28.824749) (xy 444.677848 -28.745555) (xy 444.694564 -28.70708) (xy 444.696342 -28.703016)
			(xy 444.700914 -28.68295) (xy 444.700914 -28.681934) (xy 444.696342 -28.661868) (xy 444.694564 -28.657804)
			(xy 444.677889 -28.619476) (xy 444.650269 -28.54058) (xy 444.629351 -28.459648) (xy 444.615282 -28.377249)
			(xy 444.608161 -28.293961) (xy 444.607696 -28.252166) (xy 444.607696 -28.250642) (xy 444.609474 -28.189936)
			(xy 444.609728 -28.187142) (xy 444.609728 -28.183332) (xy 444.60795 -28.17241) (xy 444.606426 -28.165298)
			(xy 444.598587 -28.137896) (xy 444.590173 -28.081527) (xy 444.589662 -28.05303) (xy 444.589662 -28.04668)
			(xy 444.589916 -28.038298) (xy 444.591186 -28.01874) (xy 444.591186 -28.018486) (xy 444.591694 -28.012898)
			(xy 444.595365 -27.983489) (xy 444.610628 -27.926225) (xy 444.634561 -27.872009) (xy 444.650114 -27.846782)
			(xy 444.653416 -27.841702) (xy 444.670622 -27.816868) (xy 444.711582 -27.77246) (xy 444.73495 -27.75331)
			(xy 444.740792 -27.747722) (xy 444.745618 -27.742388) (xy 444.751714 -27.73426) (xy 444.774715 -27.697232)
			(xy 444.826226 -27.626903) (xy 444.854584 -27.593798) (xy 444.882895 -27.562106) (xy 444.94409 -27.503134)
			(xy 445.010083 -27.449584) (xy 445.080395 -27.401845) (xy 445.154514 -27.360265) (xy 445.231904 -27.325143)
			(xy 445.312002 -27.296736) (xy 445.394227 -27.27525) (xy 445.477983 -27.26084) (xy 445.562661 -27.253611)
			(xy 445.605154 -27.253184) (xy 445.605408 -27.253184) (xy 445.652927 -27.25374) (xy 445.747532 -27.262799)
			(xy 445.840845 -27.280825) (xy 445.932017 -27.307654) (xy 446.020221 -27.343043) (xy 446.104655 -27.386668)
			(xy 446.144904 -27.411934) (xy 446.182839 -27.436963) (xy 446.254452 -27.492932) (xy 446.287906 -27.523694)
			(xy 446.29324 -27.528774) (xy 446.29451 -27.530044) (xy 446.294764 -27.530298) (xy 446.320164 -27.540458)
			(xy 446.32473 -27.542217) (xy 446.334323 -27.544142) (xy 446.339214 -27.544268) (xy 447.713862 -27.544268)
			(xy 447.752888 -27.544646) (xy 447.830702 -27.550748) (xy 447.86931 -27.55646) (xy 447.873374 -27.556968)
			(xy 448.171824 -27.556968) (xy 448.216217 -27.557493) (xy 448.30464 -27.565503) (xy 448.391991 -27.581403)
			(xy 448.477565 -27.605064) (xy 448.519296 -27.620214) (xy 448.549522 -27.632152) (xy 450.066156 -28.260802)
			(xy 450.075507 -28.264186) (xy 450.095374 -28.264326) (xy 450.104764 -28.261056) (xy 450.111203 -28.258228)
			(xy 450.122295 -28.249592) (xy 450.126608 -28.244038) (xy 450.126608 -28.243784) (xy 450.144718 -28.220028)
			(xy 450.187082 -28.177919) (xy 450.23549 -28.142925) (xy 450.288759 -28.115901) (xy 450.345589 -28.097508)
			(xy 450.40459 -28.088194) (xy 450.434456 -28.087574) (xy 450.471794 -28.089352) (xy 450.47916 -28.090114)
			(xy 450.506341 -28.093797) (xy 450.559333 -28.107953) (xy 450.609752 -28.129551) (xy 450.656558 -28.158148)
			(xy 450.698786 -28.193153) (xy 450.735565 -28.233844) (xy 450.766139 -28.279384) (xy 450.789875 -28.328832)
			(xy 450.806285 -28.38117) (xy 450.815031 -28.435318) (xy 450.815964 -28.462732) (xy 450.815964 -28.469082)
			(xy 450.815964 -28.46959) (xy 450.815964 -28.473908) (xy 450.81524 -28.499605) (xy 450.807733 -28.55046)
			(xy 450.793463 -28.599847) (xy 450.772688 -28.646869) (xy 450.759576 -28.66898) (xy 450.758306 -28.670758)
			(xy 450.757544 -28.672282) (xy 450.756782 -28.673552) (xy 450.756274 -28.674314) (xy 450.751336 -28.682283)
			(xy 450.747174 -28.700549) (xy 450.748146 -28.709874) (xy 450.749416 -28.71851) (xy 450.758052 -28.734512)
			(xy 450.765164 -28.740862) (xy 450.778763 -28.752755) (xy 450.805186 -28.777399) (xy 450.817996 -28.790138)
			(xy 451.210426 -29.183838) (xy 451.451218 -29.425138) (xy 451.458709 -29.431389) (xy 451.476967 -29.43822)
			(xy 451.496456 -29.437752) (xy 451.505574 -29.434282) (xy 451.505828 -29.434282) (xy 451.529777 -29.424362)
			(xy 451.579689 -29.410362) (xy 451.63104 -29.403267) (xy 451.656958 -29.402786) (xy 451.659752 -29.402786)
			(xy 451.687373 -29.403445) (xy 451.741995 -29.411747) (xy 451.79485 -29.427837) (xy 451.844832 -29.451378)
			(xy 451.890899 -29.481879) (xy 451.932087 -29.518703) (xy 451.967537 -29.56108) (xy 451.996506 -29.608125)
			(xy 452.018391 -29.658855) (xy 452.032734 -29.712211) (xy 452.036434 -29.73959) (xy 452.03745 -29.749242)
			(xy 452.039228 -29.78404) (xy 452.039228 -29.784548) (xy 452.038765 -29.810697) (xy 452.031547 -29.862495)
			(xy 452.01731 -29.912818) (xy 452.007224 -29.936948) (xy 452.007224 -29.937202) (xy 452.004402 -29.944274)
			(xy 452.00259 -29.959383) (xy 452.003668 -29.96692) (xy 452.004938 -29.973778) (xy 452.01205 -29.986986)
			(xy 452.768892 -30.745738) (xy 457.614517 -30.745738) (xy 457.614517 -30.616598) (xy 457.622467 -30.487703)
			(xy 457.638337 -30.359543) (xy 457.662066 -30.232602) (xy 457.693565 -30.107363) (xy 457.732714 -29.9843)
			(xy 457.779365 -29.863881) (xy 457.83334 -29.746562) (xy 457.894435 -29.632788) (xy 457.962418 -29.522991)
			(xy 458.037032 -29.417588) (xy 458.117993 -29.316978) (xy 458.204993 -29.221543) (xy 458.297704 -29.131644)
			(xy 458.395774 -29.047623) (xy 458.498829 -28.969799) (xy 458.60648 -28.898467) (xy 458.718319 -28.833897)
			(xy 458.83392 -28.776335) (xy 458.952845 -28.725998) (xy 459.074644 -28.683078) (xy 459.198854 -28.647737)
			(xy 459.325003 -28.62011) (xy 459.452615 -28.600301) (xy 459.581204 -28.588385) (xy 459.710282 -28.584409)
			(xy 459.83936 -28.588385) (xy 459.967949 -28.600301) (xy 460.095561 -28.62011) (xy 460.22171 -28.647737)
			(xy 460.34592 -28.683078) (xy 460.467719 -28.725998) (xy 460.586644 -28.776335) (xy 460.702245 -28.833897)
			(xy 460.814084 -28.898467) (xy 460.921735 -28.969799) (xy 461.02479 -29.047623) (xy 461.12286 -29.131644)
			(xy 461.215571 -29.221543) (xy 461.302571 -29.316978) (xy 461.383532 -29.417588) (xy 461.458146 -29.522991)
			(xy 461.526129 -29.632788) (xy 461.587224 -29.746562) (xy 461.641199 -29.863881) (xy 461.68785 -29.9843)
			(xy 461.726999 -30.107363) (xy 461.758498 -30.232602) (xy 461.782227 -30.359543) (xy 461.798097 -30.487703)
			(xy 461.806047 -30.616598) (xy 461.806544 -30.681168) (xy 461.806047 -30.745738) (xy 461.798097 -30.874633)
			(xy 461.782227 -31.002793) (xy 461.758498 -31.129734) (xy 461.726999 -31.254973) (xy 461.68785 -31.378036)
			(xy 461.641199 -31.498455) (xy 461.587224 -31.615774) (xy 461.526129 -31.729548) (xy 461.458146 -31.839345)
			(xy 461.383532 -31.944748) (xy 461.302571 -32.045358) (xy 461.215571 -32.140793) (xy 461.12286 -32.230692)
			(xy 461.02479 -32.314713) (xy 460.921735 -32.392537) (xy 460.814084 -32.463869) (xy 460.702245 -32.528439)
			(xy 460.586644 -32.586001) (xy 460.467719 -32.636338) (xy 460.34592 -32.679258) (xy 460.22171 -32.714599)
			(xy 460.095561 -32.742226) (xy 459.967949 -32.762035) (xy 459.83936 -32.773951) (xy 459.710282 -32.777928)
			(xy 459.581204 -32.773951) (xy 459.452615 -32.762035) (xy 459.325003 -32.742226) (xy 459.198854 -32.714599)
			(xy 459.074644 -32.679258) (xy 458.952845 -32.636338) (xy 458.83392 -32.586001) (xy 458.718319 -32.528439)
			(xy 458.60648 -32.463869) (xy 458.498829 -32.392537) (xy 458.395774 -32.314713) (xy 458.297704 -32.230692)
			(xy 458.204993 -32.140793) (xy 458.117993 -32.045358) (xy 458.037032 -31.944748) (xy 457.962418 -31.839345)
			(xy 457.894435 -31.729548) (xy 457.83334 -31.615774) (xy 457.779365 -31.498455) (xy 457.732714 -31.378036)
			(xy 457.693565 -31.254973) (xy 457.662066 -31.129734) (xy 457.638337 -31.002793) (xy 457.622467 -30.874633)
			(xy 457.614517 -30.745738) (xy 452.768892 -30.745738) (xy 452.81723 -30.794198) (xy 452.994014 -30.97149)
			(xy 453.026935 -31.005317) (xy 453.086946 -31.078185) (xy 453.13981 -31.156394) (xy 453.162924 -31.19755)
			(xy 457.606908 -39.328344) (xy 457.623268 -39.35881) (xy 457.652249 -39.421605) (xy 457.66482 -39.45382)
			(xy 457.673641 -39.477592) (xy 457.689144 -39.525875) (xy 457.695808 -39.55034) (xy 457.910946 -40.35933)
			(xy 458.011022 -40.736012) (xy 458.015086 -40.745664) (xy 458.255116 -41.1861) (xy 458.277327 -41.228003)
			(xy 458.314545 -41.315241) (xy 458.343232 -41.405644) (xy 458.363123 -41.49838) (xy 458.374036 -41.592595)
			(xy 458.375512 -41.639998) (xy 458.385672 -42.142918) (xy 458.38618 -42.146728) (xy 458.392784 -42.171874)
			(xy 458.39761 -42.189908) (xy 458.407482 -42.228571) (xy 458.421754 -42.307088) (xy 458.429696 -42.386496)
			(xy 458.430884 -42.426382) (xy 458.72019 -56.951372) (xy 458.720444 -56.971184) (xy 458.720162 -57.004433)
			(xy 458.715715 -57.070783) (xy 458.711554 -57.103772) (xy 458.701648 -57.162954) (xy 456.392026 -68.957698)
			(xy 456.384453 -68.994512) (xy 456.364491 -69.066978) (xy 456.352148 -69.102478) (xy 454.314469 -74.784966)
			(xy 458.026514 -74.784966) (xy 458.030585 -74.729344) (xy 458.042711 -74.674907) (xy 458.062634 -74.622816)
			(xy 458.08993 -74.574181) (xy 458.124016 -74.530038) (xy 458.164165 -74.491329) (xy 458.209523 -74.458878)
			(xy 458.259123 -74.433377) (xy 458.311907 -74.41537) (xy 458.36675 -74.40524) (xy 458.422484 -74.403203)
			(xy 458.477921 -74.409303) (xy 458.531878 -74.423409) (xy 458.583207 -74.445221) (xy 458.630813 -74.474275)
			(xy 458.673681 -74.50995) (xy 458.710898 -74.551487) (xy 458.741671 -74.598) (xy 458.765343 -74.648497)
			(xy 458.781411 -74.701904) (xy 458.789531 -74.75708) (xy 458.79004 -74.784966) (xy 458.789531 -74.812852)
			(xy 458.781411 -74.868028) (xy 458.765343 -74.921435) (xy 458.741671 -74.971932) (xy 458.710898 -75.018445)
			(xy 458.673681 -75.059982) (xy 458.630813 -75.095657) (xy 458.583207 -75.124711) (xy 458.531878 -75.146523)
			(xy 458.477921 -75.160629) (xy 458.422484 -75.166729) (xy 458.36675 -75.164692) (xy 458.311907 -75.154562)
			(xy 458.259123 -75.136555) (xy 458.209523 -75.111054) (xy 458.164165 -75.078603) (xy 458.124016 -75.039894)
			(xy 458.08993 -74.995751) (xy 458.062634 -74.947116) (xy 458.042711 -74.895025) (xy 458.030585 -74.840588)
			(xy 458.026514 -74.784966) (xy 454.314469 -74.784966) (xy 453.93229 -75.85075) (xy 453.918664 -75.88763)
			(xy 453.886387 -75.959329) (xy 453.848574 -76.028269) (xy 453.80546 -76.094023) (xy 453.781668 -76.125324)
			(xy 453.536219 -76.441808) (xy 458.137766 -76.441808) (xy 458.141837 -76.386186) (xy 458.153963 -76.331749)
			(xy 458.173886 -76.279658) (xy 458.201182 -76.231023) (xy 458.235268 -76.18688) (xy 458.275417 -76.148171)
			(xy 458.320775 -76.11572) (xy 458.370375 -76.090219) (xy 458.423159 -76.072212) (xy 458.478002 -76.062082)
			(xy 458.533736 -76.060045) (xy 458.589173 -76.066145) (xy 458.64313 -76.080251) (xy 458.694459 -76.102063)
			(xy 458.742065 -76.131117) (xy 458.784933 -76.166792) (xy 458.82215 -76.208329) (xy 458.852923 -76.254842)
			(xy 458.876595 -76.305339) (xy 458.892663 -76.358746) (xy 458.900783 -76.413922) (xy 458.901292 -76.441808)
			(xy 458.900783 -76.469694) (xy 458.892663 -76.52487) (xy 458.876595 -76.578277) (xy 458.852923 -76.628774)
			(xy 458.82215 -76.675287) (xy 458.784933 -76.716824) (xy 458.742065 -76.752499) (xy 458.694459 -76.781553)
			(xy 458.64313 -76.803365) (xy 458.589173 -76.817471) (xy 458.533736 -76.823571) (xy 458.478002 -76.821534)
			(xy 458.423159 -76.811404) (xy 458.370375 -76.793397) (xy 458.320775 -76.767896) (xy 458.275417 -76.735445)
			(xy 458.235268 -76.696736) (xy 458.201182 -76.652593) (xy 458.173886 -76.603958) (xy 458.153963 -76.551867)
			(xy 458.141837 -76.49743) (xy 458.137766 -76.441808) (xy 453.536219 -76.441808) (xy 453.107177 -76.99502)
			(xy 453.687178 -76.99502) (xy 453.691249 -76.939398) (xy 453.703375 -76.884961) (xy 453.723298 -76.83287)
			(xy 453.750594 -76.784235) (xy 453.78468 -76.740092) (xy 453.824829 -76.701383) (xy 453.870187 -76.668932)
			(xy 453.919787 -76.643431) (xy 453.972571 -76.625424) (xy 454.027414 -76.615294) (xy 454.083148 -76.613257)
			(xy 454.138585 -76.619357) (xy 454.192542 -76.633463) (xy 454.243871 -76.655275) (xy 454.291477 -76.684329)
			(xy 454.334345 -76.720004) (xy 454.371562 -76.761541) (xy 454.402335 -76.808054) (xy 454.426007 -76.858551)
			(xy 454.442075 -76.911958) (xy 454.450195 -76.967134) (xy 454.450704 -76.99502) (xy 454.450195 -77.022906)
			(xy 454.446337 -77.049122) (xy 455.173078 -77.049122) (xy 455.177149 -76.9935) (xy 455.189275 -76.939063)
			(xy 455.209198 -76.886972) (xy 455.236494 -76.838337) (xy 455.27058 -76.794194) (xy 455.310729 -76.755485)
			(xy 455.356087 -76.723034) (xy 455.405687 -76.697533) (xy 455.458471 -76.679526) (xy 455.513314 -76.669396)
			(xy 455.569048 -76.667359) (xy 455.624485 -76.673459) (xy 455.678442 -76.687565) (xy 455.729771 -76.709377)
			(xy 455.777377 -76.738431) (xy 455.820245 -76.774106) (xy 455.857462 -76.815643) (xy 455.888235 -76.862156)
			(xy 455.911907 -76.912653) (xy 455.927975 -76.96606) (xy 455.936095 -77.021236) (xy 455.936604 -77.049122)
			(xy 455.936095 -77.077008) (xy 455.927975 -77.132184) (xy 455.911907 -77.185591) (xy 455.888235 -77.236088)
			(xy 455.857462 -77.282601) (xy 455.820245 -77.324138) (xy 455.777377 -77.359813) (xy 455.729771 -77.388867)
			(xy 455.678442 -77.410679) (xy 455.624485 -77.424785) (xy 455.569048 -77.430885) (xy 455.513314 -77.428848)
			(xy 455.458471 -77.418718) (xy 455.405687 -77.400711) (xy 455.356087 -77.37521) (xy 455.310729 -77.342759)
			(xy 455.27058 -77.30405) (xy 455.236494 -77.259907) (xy 455.209198 -77.211272) (xy 455.189275 -77.159181)
			(xy 455.177149 -77.104744) (xy 455.173078 -77.049122) (xy 454.446337 -77.049122) (xy 454.442075 -77.078082)
			(xy 454.426007 -77.131489) (xy 454.402335 -77.181986) (xy 454.371562 -77.228499) (xy 454.334345 -77.270036)
			(xy 454.291477 -77.305711) (xy 454.243871 -77.334765) (xy 454.192542 -77.356577) (xy 454.138585 -77.370683)
			(xy 454.083148 -77.376783) (xy 454.027414 -77.374746) (xy 453.972571 -77.364616) (xy 453.919787 -77.346609)
			(xy 453.870187 -77.321108) (xy 453.824829 -77.288657) (xy 453.78468 -77.249948) (xy 453.750594 -77.205805)
			(xy 453.723298 -77.15717) (xy 453.703375 -77.105079) (xy 453.691249 -77.050642) (xy 453.687178 -76.99502)
			(xy 453.107177 -76.99502) (xy 452.81977 -77.365606) (xy 452.809864 -77.378306) (xy 452.80961 -77.37856)
			(xy 452.69785 -77.522578) (xy 452.694505 -77.526706) (xy 452.686436 -77.533615) (xy 452.681848 -77.536294)
			(xy 452.518018 -77.625194) (xy 452.517002 -77.625702) (xy 452.516748 -77.625956) (xy 452.510144 -77.629512)
			(xy 452.09968 -77.85227) (xy 449.438776 -79.296006) (xy 449.437252 -79.296768) (xy 449.425368 -79.304235)
			(xy 449.405922 -79.324459) (xy 449.392719 -79.349214) (xy 449.386757 -79.376629) (xy 449.388487 -79.404632)
			(xy 449.397777 -79.431105) (xy 449.413926 -79.454047) (xy 449.435713 -79.471724) (xy 449.46149 -79.482799)
			(xy 449.475352 -79.484982) (xy 449.577099 -79.498652) (xy 449.779535 -79.53294) (xy 449.980478 -79.575103)
			(xy 450.179622 -79.625079) (xy 450.376664 -79.68279) (xy 450.571302 -79.748149) (xy 450.763241 -79.821055)
			(xy 450.952188 -79.901399) (xy 451.137854 -79.989058) (xy 451.319957 -80.083897) (xy 451.498219 -80.185772)
			(xy 451.672368 -80.294529) (xy 451.84214 -80.41) (xy 452.007274 -80.532011) (xy 452.167519 -80.660375)
			(xy 452.322632 -80.794897) (xy 452.472375 -80.935371) (xy 452.616521 -81.081583) (xy 452.754849 -81.233311)
			(xy 452.887149 -81.390323) (xy 453.013219 -81.552379) (xy 453.132866 -81.719234) (xy 453.24591 -81.890631)
			(xy 453.352176 -82.066311) (xy 453.451504 -82.246005) (xy 453.543741 -82.42944) (xy 453.628747 -82.616335)
			(xy 453.706393 -82.806407) (xy 453.77656 -82.999364) (xy 453.839142 -83.194913) (xy 453.894042 -83.392756)
			(xy 453.941178 -83.592592) (xy 453.980476 -83.794115) (xy 454.011878 -83.997019) (xy 454.035336 -84.200993)
			(xy 454.050813 -84.405728) (xy 454.058287 -84.610911) (xy 454.058528 -84.713572) (xy 454.058528 -84.718144)
			(xy 454.057646 -84.822798) (xy 454.048581 -85.031914) (xy 454.031199 -85.240504) (xy 454.00553 -85.448236)
			(xy 453.971612 -85.654783) (xy 453.929499 -85.859815) (xy 453.87926 -86.063009) (xy 453.820972 -86.264042)
			(xy 453.754729 -86.462596) (xy 453.718168 -86.56066) (xy 453.681257 -86.6568) (xy 453.600886 -86.846432)
			(xy 453.513151 -87.032773) (xy 453.418187 -87.215535) (xy 453.316139 -87.394438) (xy 453.207165 -87.569208)
			(xy 453.091431 -87.739578) (xy 452.969115 -87.905285) (xy 452.840405 -88.066076) (xy 452.705497 -88.221704)
			(xy 452.564599 -88.371929) (xy 452.417927 -88.516523) (xy 452.265705 -88.655263) (xy 452.108168 -88.787936)
			(xy 451.945557 -88.914339) (xy 451.778121 -89.034277) (xy 451.606117 -89.147568) (xy 451.429809 -89.254037)
			(xy 451.249467 -89.35352) (xy 451.065369 -89.445866) (xy 450.877795 -89.530933) (xy 450.687035 -89.608589)
			(xy 450.49338 -89.678717) (xy 450.297128 -89.741209) (xy 450.098579 -89.795968) (xy 449.898039 -89.84291)
			(xy 449.695814 -89.881965) (xy 449.492215 -89.913071) (xy 449.287555 -89.936181) (xy 449.082146 -89.95126)
			(xy 448.876304 -89.958284) (xy 448.670346 -89.957243) (xy 448.464586 -89.948138) (xy 448.25934 -89.930984)
			(xy 448.054923 -89.905806) (xy 447.851649 -89.872644) (xy 447.64983 -89.831547) (xy 447.449774 -89.78258)
			(xy 447.251789 -89.725817) (xy 447.056179 -89.661345) (xy 446.863243 -89.589263) (xy 446.673277 -89.509682)
			(xy 446.486573 -89.422724) (xy 446.303417 -89.328522) (xy 446.12409 -89.22722) (xy 445.948868 -89.118975)
			(xy 445.778018 -89.003951) (xy 445.611803 -88.882326) (xy 445.450477 -88.754286) (xy 445.294289 -88.620028)
			(xy 445.143478 -88.479756) (xy 444.998275 -88.333688) (xy 444.858903 -88.182045) (xy 444.725575 -88.025062)
			(xy 444.598496 -87.862978) (xy 444.477861 -87.696043) (xy 444.363855 -87.524512) (xy 444.256653 -87.348649)
			(xy 444.15642 -87.168724) (xy 444.063308 -86.985011) (xy 443.977461 -86.797793) (xy 443.899011 -86.607358)
			(xy 443.828077 -86.413997) (xy 443.764769 -86.218007) (xy 443.709184 -86.019688) (xy 443.661407 -85.819345)
			(xy 443.621511 -85.617284) (xy 443.589557 -85.413817) (xy 443.565595 -85.209254) (xy 443.549661 -85.00391)
			(xy 443.545214 -84.901024) (xy 443.545214 -84.89315) (xy 443.539626 -84.877148) (xy 443.535308 -84.87156)
			(xy 443.534038 -84.870036) (xy 443.528863 -84.864025) (xy 443.515666 -84.855242) (xy 443.50813 -84.852764)
			(xy 443.4078 -84.82965) (xy 443.397977 -84.828375) (xy 443.378634 -84.832545) (xy 443.362314 -84.843735)
			(xy 443.356492 -84.851748) (xy 439.674254 -91.628468) (xy 439.669174 -91.637866) (xy 439.668158 -91.63939)
			(xy 439.667904 -91.639898) (xy 439.66765 -91.640406) (xy 439.664348 -91.646502) (xy 439.663332 -91.64828)
			(xy 439.589672 -91.770708) (xy 438.25668 -93.987366) (xy 438.251967 -93.997337) (xy 438.250631 -94.01933)
			(xy 438.25414 -94.029784) (xy 438.260744 -94.043754) (xy 438.272897 -94.07109) (xy 438.290071 -94.128395)
			(xy 438.298787 -94.187579) (xy 438.299352 -94.21749) (xy 438.298867 -94.2465) (xy 438.29848 -94.24924)
			(xy 443.73622 -94.24924) (xy 443.740291 -94.193618) (xy 443.752417 -94.139181) (xy 443.77234 -94.08709)
			(xy 443.799636 -94.038455) (xy 443.833722 -93.994312) (xy 443.873871 -93.955603) (xy 443.919229 -93.923152)
			(xy 443.968829 -93.897651) (xy 444.021613 -93.879644) (xy 444.076456 -93.869514) (xy 444.13219 -93.867477)
			(xy 444.187627 -93.873577) (xy 444.241584 -93.887683) (xy 444.292913 -93.909495) (xy 444.340519 -93.938549)
			(xy 444.383387 -93.974224) (xy 444.420604 -94.015761) (xy 444.451377 -94.062274) (xy 444.475049 -94.112771)
			(xy 444.491117 -94.166178) (xy 444.499237 -94.221354) (xy 444.499746 -94.24924) (xy 444.499672 -94.253304)
			(xy 444.75222 -94.253304) (xy 444.756291 -94.197682) (xy 444.768417 -94.143245) (xy 444.78834 -94.091154)
			(xy 444.815636 -94.042519) (xy 444.849722 -93.998376) (xy 444.889871 -93.959667) (xy 444.935229 -93.927216)
			(xy 444.984829 -93.901715) (xy 445.037613 -93.883708) (xy 445.092456 -93.873578) (xy 445.14819 -93.871541)
			(xy 445.203627 -93.877641) (xy 445.257584 -93.891747) (xy 445.308913 -93.913559) (xy 445.356519 -93.942613)
			(xy 445.399387 -93.978288) (xy 445.436604 -94.019825) (xy 445.467377 -94.066338) (xy 445.491049 -94.116835)
			(xy 445.507117 -94.170242) (xy 445.515237 -94.225418) (xy 445.515746 -94.253304) (xy 445.515237 -94.28119)
			(xy 445.507117 -94.336366) (xy 445.491049 -94.389773) (xy 445.467377 -94.44027) (xy 445.436604 -94.486783)
			(xy 445.399387 -94.52832) (xy 445.356519 -94.563995) (xy 445.308913 -94.593049) (xy 445.257584 -94.614861)
			(xy 445.203627 -94.628967) (xy 445.14819 -94.635067) (xy 445.092456 -94.63303) (xy 445.037613 -94.6229)
			(xy 444.984829 -94.604893) (xy 444.935229 -94.579392) (xy 444.889871 -94.546941) (xy 444.849722 -94.508232)
			(xy 444.815636 -94.464089) (xy 444.78834 -94.415454) (xy 444.768417 -94.363363) (xy 444.756291 -94.308926)
			(xy 444.75222 -94.253304) (xy 444.499672 -94.253304) (xy 444.499237 -94.277126) (xy 444.491117 -94.332302)
			(xy 444.475049 -94.385709) (xy 444.451377 -94.436206) (xy 444.420604 -94.482719) (xy 444.383387 -94.524256)
			(xy 444.340519 -94.559931) (xy 444.292913 -94.588985) (xy 444.241584 -94.610797) (xy 444.187627 -94.624903)
			(xy 444.13219 -94.631003) (xy 444.076456 -94.628966) (xy 444.021613 -94.618836) (xy 443.968829 -94.600829)
			(xy 443.919229 -94.575328) (xy 443.873871 -94.542877) (xy 443.833722 -94.504168) (xy 443.799636 -94.460025)
			(xy 443.77234 -94.41139) (xy 443.752417 -94.359299) (xy 443.740291 -94.304862) (xy 443.73622 -94.24924)
			(xy 438.29848 -94.24924) (xy 438.290753 -94.303949) (xy 438.27467 -94.359695) (xy 438.250935 -94.412638)
			(xy 438.220016 -94.461733) (xy 438.182524 -94.506012) (xy 438.139198 -94.544601) (xy 438.090892 -94.576739)
			(xy 438.03856 -94.601792) (xy 437.983234 -94.619265) (xy 437.926006 -94.628814) (xy 437.897016 -94.629986)
			(xy 437.8833 -94.63024) (xy 437.872886 -94.63659) (xy 437.865266 -94.642178) (xy 437.857138 -94.651068)
			(xy 437.74106 -94.8436) (xy 437.454548 -95.320612) (xy 437.449846 -95.32964) (xy 437.447362 -95.349825)
			(xy 437.449722 -95.359728) (xy 437.469788 -95.429324) (xy 437.473852 -95.435674) (xy 437.477408 -95.441262)
			(xy 437.484266 -95.449898) (xy 437.49595 -95.461582) (xy 437.502554 -95.465138) (xy 437.52834 -95.479478)
			(xy 437.575544 -95.514874) (xy 437.616739 -95.557111) (xy 437.650944 -95.605185) (xy 437.677343 -95.65795)
			(xy 437.695309 -95.714148) (xy 437.704412 -95.772442) (xy 437.704992 -95.801942) (xy 438.974736 -95.801942)
			(xy 438.978807 -95.74632) (xy 438.990933 -95.691883) (xy 439.010856 -95.639792) (xy 439.038152 -95.591157)
			(xy 439.072238 -95.547014) (xy 439.112387 -95.508305) (xy 439.157745 -95.475854) (xy 439.207345 -95.450353)
			(xy 439.260129 -95.432346) (xy 439.314972 -95.422216) (xy 439.370706 -95.420179) (xy 439.426143 -95.426279)
			(xy 439.4801 -95.440385) (xy 439.531429 -95.462197) (xy 439.579035 -95.491251) (xy 439.621903 -95.526926)
			(xy 439.65912 -95.568463) (xy 439.689893 -95.614976) (xy 439.713565 -95.665473) (xy 439.729633 -95.71888)
			(xy 439.737753 -95.774056) (xy 439.738262 -95.801942) (xy 441.015626 -95.801942) (xy 441.019697 -95.74632)
			(xy 441.031823 -95.691883) (xy 441.051746 -95.639792) (xy 441.079042 -95.591157) (xy 441.113128 -95.547014)
			(xy 441.153277 -95.508305) (xy 441.198635 -95.475854) (xy 441.248235 -95.450353) (xy 441.301019 -95.432346)
			(xy 441.355862 -95.422216) (xy 441.411596 -95.420179) (xy 441.467033 -95.426279) (xy 441.52099 -95.440385)
			(xy 441.572319 -95.462197) (xy 441.619925 -95.491251) (xy 441.662793 -95.526926) (xy 441.70001 -95.568463)
			(xy 441.730783 -95.614976) (xy 441.754455 -95.665473) (xy 441.770523 -95.71888) (xy 441.778643 -95.774056)
			(xy 441.779152 -95.801942) (xy 442.021466 -95.801942) (xy 442.025537 -95.74632) (xy 442.037663 -95.691883)
			(xy 442.057586 -95.639792) (xy 442.084882 -95.591157) (xy 442.118968 -95.547014) (xy 442.159117 -95.508305)
			(xy 442.204475 -95.475854) (xy 442.254075 -95.450353) (xy 442.306859 -95.432346) (xy 442.361702 -95.422216)
			(xy 442.417436 -95.420179) (xy 442.472873 -95.426279) (xy 442.52683 -95.440385) (xy 442.578159 -95.462197)
			(xy 442.625765 -95.491251) (xy 442.668633 -95.526926) (xy 442.70585 -95.568463) (xy 442.736623 -95.614976)
			(xy 442.760295 -95.665473) (xy 442.776363 -95.71888) (xy 442.784483 -95.774056) (xy 442.784992 -95.801942)
			(xy 442.784483 -95.829828) (xy 442.777338 -95.878378) (xy 447.420115 -95.878378) (xy 447.427868 -95.824421)
			(xy 447.443221 -95.772116) (xy 447.465861 -95.722529) (xy 447.495329 -95.676668) (xy 447.531023 -95.635468)
			(xy 447.572217 -95.599767) (xy 447.618072 -95.570292) (xy 447.667656 -95.547643) (xy 447.719958 -95.532281)
			(xy 447.773914 -95.524519) (xy 447.828426 -95.524515) (xy 447.882383 -95.532268) (xy 447.934688 -95.547622)
			(xy 447.984275 -95.570263) (xy 448.030135 -95.599731) (xy 448.071335 -95.635425) (xy 448.107035 -95.67662)
			(xy 448.13651 -95.722476) (xy 448.159158 -95.77206) (xy 448.17452 -95.824362) (xy 448.182281 -95.878318)
			(xy 448.182746 -95.905574) (xy 448.182746 -95.906082) (xy 448.182663 -95.916454) (xy 448.181521 -95.937166)
			(xy 448.18046 -95.947484) (xy 448.179401 -95.96203) (xy 448.184605 -95.990714) (xy 448.197692 -96.016765)
			(xy 448.217597 -96.038064) (xy 448.242703 -96.052882) (xy 448.27097 -96.060014) (xy 448.3001 -96.05888)
			(xy 448.314064 -96.054672) (xy 448.343673 -96.045318) (xy 448.404939 -96.035236) (xy 448.435984 -96.034606)
			(xy 448.436238 -96.034606) (xy 448.463486 -96.035119) (xy 448.517426 -96.04288) (xy 448.569712 -96.058237)
			(xy 448.619281 -96.08088) (xy 448.665123 -96.110346) (xy 448.706305 -96.146036) (xy 448.741989 -96.187224)
			(xy 448.771448 -96.233071) (xy 448.794083 -96.282643) (xy 448.809433 -96.334932) (xy 448.817185 -96.388873)
			(xy 448.817182 -96.443368) (xy 448.809424 -96.497309) (xy 448.794069 -96.549596) (xy 448.771428 -96.599166)
			(xy 448.741964 -96.645009) (xy 448.706276 -96.686193) (xy 448.66509 -96.721879) (xy 448.619245 -96.75134)
			(xy 448.569673 -96.773977) (xy 448.517385 -96.789329) (xy 448.463444 -96.797084) (xy 448.408949 -96.797084)
			(xy 448.355008 -96.789328) (xy 448.30272 -96.773975) (xy 448.253149 -96.751337) (xy 448.207305 -96.721875)
			(xy 448.166119 -96.686188) (xy 448.130432 -96.645004) (xy 448.100968 -96.59916) (xy 448.078329 -96.54959)
			(xy 448.062974 -96.497302) (xy 448.055217 -96.443362) (xy 448.05473 -96.416114) (xy 448.05473 -96.415606)
			(xy 448.054812 -96.405234) (xy 448.055955 -96.384522) (xy 448.057016 -96.374204) (xy 448.058118 -96.359659)
			(xy 448.052909 -96.330969) (xy 448.039816 -96.304914) (xy 448.019904 -96.283612) (xy 447.99479 -96.268795)
			(xy 447.966515 -96.261666) (xy 447.937378 -96.262804) (xy 447.923412 -96.267016) (xy 447.893805 -96.276375)
			(xy 447.832537 -96.286454) (xy 447.801492 -96.287082) (xy 447.801238 -96.287082) (xy 447.773982 -96.286686)
			(xy 447.720025 -96.278933) (xy 447.66772 -96.263581) (xy 447.618132 -96.240941) (xy 447.572271 -96.211474)
			(xy 447.531071 -96.17578) (xy 447.495369 -96.134586) (xy 447.465894 -96.088731) (xy 447.443244 -96.039148)
			(xy 447.427882 -95.986846) (xy 447.420119 -95.93289) (xy 447.420115 -95.878378) (xy 442.777338 -95.878378)
			(xy 442.776363 -95.885004) (xy 442.760295 -95.938411) (xy 442.736623 -95.988908) (xy 442.70585 -96.035421)
			(xy 442.668633 -96.076958) (xy 442.625765 -96.112633) (xy 442.578159 -96.141687) (xy 442.52683 -96.163499)
			(xy 442.472873 -96.177605) (xy 442.417436 -96.183705) (xy 442.361702 -96.181668) (xy 442.306859 -96.171538)
			(xy 442.254075 -96.153531) (xy 442.204475 -96.12803) (xy 442.159117 -96.095579) (xy 442.118968 -96.05687)
			(xy 442.084882 -96.012727) (xy 442.057586 -95.964092) (xy 442.037663 -95.912001) (xy 442.025537 -95.857564)
			(xy 442.021466 -95.801942) (xy 441.779152 -95.801942) (xy 441.778643 -95.829828) (xy 441.770523 -95.885004)
			(xy 441.754455 -95.938411) (xy 441.730783 -95.988908) (xy 441.70001 -96.035421) (xy 441.662793 -96.076958)
			(xy 441.619925 -96.112633) (xy 441.572319 -96.141687) (xy 441.52099 -96.163499) (xy 441.467033 -96.177605)
			(xy 441.411596 -96.183705) (xy 441.355862 -96.181668) (xy 441.301019 -96.171538) (xy 441.248235 -96.153531)
			(xy 441.198635 -96.12803) (xy 441.153277 -96.095579) (xy 441.113128 -96.05687) (xy 441.079042 -96.012727)
			(xy 441.051746 -95.964092) (xy 441.031823 -95.912001) (xy 441.019697 -95.857564) (xy 441.015626 -95.801942)
			(xy 439.738262 -95.801942) (xy 439.737753 -95.829828) (xy 439.729633 -95.885004) (xy 439.713565 -95.938411)
			(xy 439.689893 -95.988908) (xy 439.65912 -96.035421) (xy 439.621903 -96.076958) (xy 439.579035 -96.112633)
			(xy 439.531429 -96.141687) (xy 439.4801 -96.163499) (xy 439.426143 -96.177605) (xy 439.370706 -96.183705)
			(xy 439.314972 -96.181668) (xy 439.260129 -96.171538) (xy 439.207345 -96.153531) (xy 439.157745 -96.12803)
			(xy 439.112387 -96.095579) (xy 439.072238 -96.05687) (xy 439.038152 -96.012727) (xy 439.010856 -95.964092)
			(xy 438.990933 -95.912001) (xy 438.978807 -95.857564) (xy 438.974736 -95.801942) (xy 437.704992 -95.801942)
			(xy 437.704503 -95.829191) (xy 437.696741 -95.883133) (xy 437.681382 -95.935422) (xy 437.658739 -95.984993)
			(xy 437.629271 -96.030837) (xy 437.593579 -96.07202) (xy 437.55239 -96.107706) (xy 437.506542 -96.137167)
			(xy 437.456967 -96.159803) (xy 437.404676 -96.175154) (xy 437.350733 -96.182907) (xy 437.323484 -96.18345)
			(xy 437.322722 -96.18345) (xy 437.293551 -96.182848) (xy 437.2359 -96.173882) (xy 437.18028 -96.156261)
			(xy 437.127983 -96.130394) (xy 437.103774 -96.114108) (xy 437.10352 -96.113854) (xy 437.094884 -96.107758)
			(xy 437.084724 -96.105726) (xy 437.079944 -96.104832) (xy 437.070221 -96.104698) (xy 437.06542 -96.105472)
			(xy 436.988204 -96.121982) (xy 436.983124 -96.123506) (xy 436.976343 -96.126473) (xy 436.964723 -96.135632)
			(xy 436.960264 -96.14154) (xy 436.819751 -96.374966) (xy 442.727078 -96.374966) (xy 442.731149 -96.319344)
			(xy 442.743275 -96.264907) (xy 442.763198 -96.212816) (xy 442.790494 -96.164181) (xy 442.82458 -96.120038)
			(xy 442.864729 -96.081329) (xy 442.910087 -96.048878) (xy 442.959687 -96.023377) (xy 443.012471 -96.00537)
			(xy 443.067314 -95.99524) (xy 443.123048 -95.993203) (xy 443.178485 -95.999303) (xy 443.232442 -96.013409)
			(xy 443.283771 -96.035221) (xy 443.331377 -96.064275) (xy 443.374245 -96.09995) (xy 443.411462 -96.141487)
			(xy 443.442235 -96.188) (xy 443.465907 -96.238497) (xy 443.480906 -96.288352) (xy 444.152272 -96.288352)
			(xy 444.156343 -96.23273) (xy 444.168469 -96.178293) (xy 444.188392 -96.126202) (xy 444.215688 -96.077567)
			(xy 444.249774 -96.033424) (xy 444.289923 -95.994715) (xy 444.335281 -95.962264) (xy 444.384881 -95.936763)
			(xy 444.437665 -95.918756) (xy 444.492508 -95.908626) (xy 444.548242 -95.906589) (xy 444.603679 -95.912689)
			(xy 444.657636 -95.926795) (xy 444.708965 -95.948607) (xy 444.756571 -95.977661) (xy 444.799439 -96.013336)
			(xy 444.836656 -96.054873) (xy 444.867429 -96.101386) (xy 444.891101 -96.151883) (xy 444.907169 -96.20529)
			(xy 444.915289 -96.260466) (xy 444.91552 -96.273112) (xy 445.497964 -96.273112) (xy 445.502035 -96.21749)
			(xy 445.514161 -96.163053) (xy 445.534084 -96.110962) (xy 445.56138 -96.062327) (xy 445.595466 -96.018184)
			(xy 445.635615 -95.979475) (xy 445.680973 -95.947024) (xy 445.730573 -95.921523) (xy 445.783357 -95.903516)
			(xy 445.8382 -95.893386) (xy 445.893934 -95.891349) (xy 445.949371 -95.897449) (xy 446.003328 -95.911555)
			(xy 446.054657 -95.933367) (xy 446.102263 -95.962421) (xy 446.145131 -95.998096) (xy 446.182348 -96.039633)
			(xy 446.213121 -96.086146) (xy 446.236793 -96.136643) (xy 446.252861 -96.19005) (xy 446.260981 -96.245226)
			(xy 446.26149 -96.273112) (xy 446.260981 -96.300998) (xy 446.252861 -96.356174) (xy 446.236793 -96.409581)
			(xy 446.213121 -96.460078) (xy 446.182348 -96.506591) (xy 446.145131 -96.548128) (xy 446.102263 -96.583803)
			(xy 446.054657 -96.612857) (xy 446.003328 -96.634669) (xy 445.949371 -96.648775) (xy 445.893934 -96.654875)
			(xy 445.8382 -96.652838) (xy 445.783357 -96.642708) (xy 445.730573 -96.624701) (xy 445.680973 -96.5992)
			(xy 445.635615 -96.566749) (xy 445.595466 -96.52804) (xy 445.56138 -96.483897) (xy 445.534084 -96.435262)
			(xy 445.514161 -96.383171) (xy 445.502035 -96.328734) (xy 445.497964 -96.273112) (xy 444.91552 -96.273112)
			(xy 444.915798 -96.288352) (xy 444.915289 -96.316238) (xy 444.907169 -96.371414) (xy 444.891101 -96.424821)
			(xy 444.867429 -96.475318) (xy 444.836656 -96.521831) (xy 444.799439 -96.563368) (xy 444.756571 -96.599043)
			(xy 444.708965 -96.628097) (xy 444.657636 -96.649909) (xy 444.603679 -96.664015) (xy 444.548242 -96.670115)
			(xy 444.492508 -96.668078) (xy 444.437665 -96.657948) (xy 444.384881 -96.639941) (xy 444.335281 -96.61444)
			(xy 444.289923 -96.581989) (xy 444.249774 -96.54328) (xy 444.215688 -96.499137) (xy 444.188392 -96.450502)
			(xy 444.168469 -96.398411) (xy 444.156343 -96.343974) (xy 444.152272 -96.288352) (xy 443.480906 -96.288352)
			(xy 443.481975 -96.291904) (xy 443.490095 -96.34708) (xy 443.490604 -96.374966) (xy 443.490095 -96.402852)
			(xy 443.481975 -96.458028) (xy 443.465907 -96.511435) (xy 443.442235 -96.561932) (xy 443.411462 -96.608445)
			(xy 443.374245 -96.649982) (xy 443.331377 -96.685657) (xy 443.283771 -96.714711) (xy 443.232442 -96.736523)
			(xy 443.178485 -96.750629) (xy 443.123048 -96.756729) (xy 443.067314 -96.754692) (xy 443.012471 -96.744562)
			(xy 442.959687 -96.726555) (xy 442.910087 -96.701054) (xy 442.864729 -96.668603) (xy 442.82458 -96.629894)
			(xy 442.790494 -96.585751) (xy 442.763198 -96.537116) (xy 442.743275 -96.485025) (xy 442.731149 -96.430588)
			(xy 442.727078 -96.374966) (xy 436.819751 -96.374966) (xy 436.804308 -96.40062) (xy 436.736236 -96.513904)
			(xy 436.735728 -96.51492) (xy 436.109364 -97.62871) (xy 436.005732 -97.812606) (xy 435.926569 -97.953576)
			(xy 436.643016 -97.953576) (xy 436.647087 -97.897954) (xy 436.659213 -97.843517) (xy 436.679136 -97.791426)
			(xy 436.706432 -97.742791) (xy 436.740518 -97.698648) (xy 436.780667 -97.659939) (xy 436.826025 -97.627488)
			(xy 436.875625 -97.601987) (xy 436.928409 -97.58398) (xy 436.983252 -97.57385) (xy 437.038986 -97.571813)
			(xy 437.094423 -97.577913) (xy 437.14838 -97.592019) (xy 437.199709 -97.613831) (xy 437.247315 -97.642885)
			(xy 437.290183 -97.67856) (xy 437.3274 -97.720097) (xy 437.358173 -97.76661) (xy 437.381845 -97.817107)
			(xy 437.383089 -97.821242) (xy 437.957466 -97.821242) (xy 437.961537 -97.76562) (xy 437.973663 -97.711183)
			(xy 437.993586 -97.659092) (xy 438.020882 -97.610457) (xy 438.054968 -97.566314) (xy 438.095117 -97.527605)
			(xy 438.140475 -97.495154) (xy 438.190075 -97.469653) (xy 438.242859 -97.451646) (xy 438.297702 -97.441516)
			(xy 438.353436 -97.439479) (xy 438.408873 -97.445579) (xy 438.46283 -97.459685) (xy 438.514159 -97.481497)
			(xy 438.561765 -97.510551) (xy 438.604633 -97.546226) (xy 438.64185 -97.587763) (xy 438.672623 -97.634276)
			(xy 438.696295 -97.684773) (xy 438.712363 -97.73818) (xy 438.720483 -97.793356) (xy 438.720992 -97.821242)
			(xy 438.720495 -97.848447) (xy 439.22852 -97.848447) (xy 439.22852 -97.793953) (xy 439.236275 -97.740012)
			(xy 439.251628 -97.687725) (xy 439.274265 -97.638154) (xy 439.303727 -97.592309) (xy 439.339413 -97.551124)
			(xy 439.380597 -97.515437) (xy 439.42644 -97.485973) (xy 439.47601 -97.463334) (xy 439.528297 -97.447979)
			(xy 439.582237 -97.440221) (xy 439.609484 -97.439734) (xy 439.638401 -97.440251) (xy 439.695573 -97.448978)
			(xy 439.750772 -97.466236) (xy 439.802734 -97.491628) (xy 439.850268 -97.524572) (xy 439.892284 -97.564314)
			(xy 439.910474 -97.5868) (xy 439.918102 -97.595585) (xy 439.938987 -97.605781) (xy 439.950606 -97.606358)
			(xy 440.030362 -97.606358) (xy 440.041999 -97.605855) (xy 440.062909 -97.595642) (xy 440.070494 -97.5868)
			(xy 440.088688 -97.564319) (xy 440.130707 -97.524584) (xy 440.178242 -97.491645) (xy 440.230202 -97.466256)
			(xy 440.285399 -97.448999) (xy 440.342568 -97.440269) (xy 440.371484 -97.439734) (xy 440.398741 -97.440112)
			(xy 440.452699 -97.447868) (xy 440.505005 -97.463224) (xy 440.554593 -97.485868) (xy 440.600453 -97.515339)
			(xy 440.641652 -97.551037) (xy 440.677351 -97.592234) (xy 440.706824 -97.638093) (xy 440.72947 -97.68768)
			(xy 440.744829 -97.739985) (xy 440.752587 -97.793943) (xy 440.752587 -97.821242) (xy 441.005466 -97.821242)
			(xy 441.009537 -97.76562) (xy 441.021663 -97.711183) (xy 441.041586 -97.659092) (xy 441.068882 -97.610457)
			(xy 441.102968 -97.566314) (xy 441.143117 -97.527605) (xy 441.188475 -97.495154) (xy 441.238075 -97.469653)
			(xy 441.290859 -97.451646) (xy 441.345702 -97.441516) (xy 441.401436 -97.439479) (xy 441.456873 -97.445579)
			(xy 441.51083 -97.459685) (xy 441.562159 -97.481497) (xy 441.609765 -97.510551) (xy 441.629968 -97.527364)
			(xy 442.639702 -97.527364) (xy 442.643773 -97.471742) (xy 442.655899 -97.417305) (xy 442.675822 -97.365214)
			(xy 442.703118 -97.316579) (xy 442.737204 -97.272436) (xy 442.777353 -97.233727) (xy 442.822711 -97.201276)
			(xy 442.872311 -97.175775) (xy 442.925095 -97.157768) (xy 442.979938 -97.147638) (xy 443.035672 -97.145601)
			(xy 443.091109 -97.151701) (xy 443.145066 -97.165807) (xy 443.196395 -97.187619) (xy 443.244001 -97.216673)
			(xy 443.286869 -97.252348) (xy 443.324086 -97.293885) (xy 443.354859 -97.340398) (xy 443.378531 -97.390895)
			(xy 443.394599 -97.444302) (xy 443.402719 -97.499478) (xy 443.403228 -97.527364) (xy 443.402719 -97.55525)
			(xy 443.394599 -97.610426) (xy 443.378531 -97.663833) (xy 443.354859 -97.71433) (xy 443.324086 -97.760843)
			(xy 443.286869 -97.80238) (xy 443.244001 -97.838055) (xy 443.196395 -97.867109) (xy 443.145066 -97.888921)
			(xy 443.091109 -97.903027) (xy 443.035672 -97.909127) (xy 442.979938 -97.90709) (xy 442.925095 -97.89696)
			(xy 442.872311 -97.878953) (xy 442.822711 -97.853452) (xy 442.777353 -97.821001) (xy 442.737204 -97.782292)
			(xy 442.703118 -97.738149) (xy 442.675822 -97.689514) (xy 442.655899 -97.637423) (xy 442.643773 -97.582986)
			(xy 442.639702 -97.527364) (xy 441.629968 -97.527364) (xy 441.652633 -97.546226) (xy 441.68985 -97.587763)
			(xy 441.720623 -97.634276) (xy 441.744295 -97.684773) (xy 441.760363 -97.73818) (xy 441.768483 -97.793356)
			(xy 441.768992 -97.821242) (xy 441.768483 -97.849128) (xy 441.760363 -97.904304) (xy 441.744295 -97.957711)
			(xy 441.720623 -98.008208) (xy 441.68985 -98.054721) (xy 441.652633 -98.096258) (xy 441.609765 -98.131933)
			(xy 441.562159 -98.160987) (xy 441.51083 -98.182799) (xy 441.456873 -98.196905) (xy 441.401436 -98.203005)
			(xy 441.345702 -98.200968) (xy 441.290859 -98.190838) (xy 441.238075 -98.172831) (xy 441.188475 -98.14733)
			(xy 441.143117 -98.114879) (xy 441.102968 -98.07617) (xy 441.068882 -98.032027) (xy 441.041586 -97.983392)
			(xy 441.021663 -97.931301) (xy 441.009537 -97.876864) (xy 441.005466 -97.821242) (xy 440.752587 -97.821242)
			(xy 440.752587 -97.848457) (xy 440.744829 -97.902415) (xy 440.72947 -97.95472) (xy 440.706824 -98.004307)
			(xy 440.677351 -98.050166) (xy 440.641652 -98.091363) (xy 440.600453 -98.127061) (xy 440.554593 -98.156532)
			(xy 440.505005 -98.179176) (xy 440.452699 -98.194532) (xy 440.398741 -98.202288) (xy 440.371484 -98.20275)
			(xy 440.342568 -98.20219) (xy 440.285398 -98.193472) (xy 440.2302 -98.176224) (xy 440.178237 -98.15084)
			(xy 440.130702 -98.117903) (xy 440.088685 -98.078167) (xy 440.070494 -98.055684) (xy 440.062883 -98.046881)
			(xy 440.041985 -98.036696) (xy 440.030362 -98.036126) (xy 439.950606 -98.036126) (xy 439.938975 -98.036674)
			(xy 439.918065 -98.046856) (xy 439.910474 -98.055684) (xy 439.892294 -98.078177) (xy 439.850272 -98.117912)
			(xy 439.802735 -98.15085) (xy 439.750772 -98.176237) (xy 439.695572 -98.193491) (xy 439.638401 -98.202217)
			(xy 439.609484 -98.20275) (xy 439.582237 -98.202179) (xy 439.528297 -98.194421) (xy 439.47601 -98.179066)
			(xy 439.42644 -98.156427) (xy 439.380597 -98.126963) (xy 439.339413 -98.091276) (xy 439.303727 -98.050091)
			(xy 439.274265 -98.004246) (xy 439.251628 -97.954675) (xy 439.236275 -97.902388) (xy 439.22852 -97.848447)
			(xy 438.720495 -97.848447) (xy 438.720483 -97.849128) (xy 438.712363 -97.904304) (xy 438.696295 -97.957711)
			(xy 438.672623 -98.008208) (xy 438.64185 -98.054721) (xy 438.604633 -98.096258) (xy 438.561765 -98.131933)
			(xy 438.514159 -98.160987) (xy 438.46283 -98.182799) (xy 438.408873 -98.196905) (xy 438.353436 -98.203005)
			(xy 438.297702 -98.200968) (xy 438.242859 -98.190838) (xy 438.190075 -98.172831) (xy 438.140475 -98.14733)
			(xy 438.095117 -98.114879) (xy 438.054968 -98.07617) (xy 438.020882 -98.032027) (xy 437.993586 -97.983392)
			(xy 437.973663 -97.931301) (xy 437.961537 -97.876864) (xy 437.957466 -97.821242) (xy 437.383089 -97.821242)
			(xy 437.397913 -97.870514) (xy 437.406033 -97.92569) (xy 437.406542 -97.953576) (xy 437.406033 -97.981462)
			(xy 437.397913 -98.036638) (xy 437.381845 -98.090045) (xy 437.358173 -98.140542) (xy 437.3274 -98.187055)
			(xy 437.290183 -98.228592) (xy 437.247315 -98.264267) (xy 437.199709 -98.293321) (xy 437.14838 -98.315133)
			(xy 437.094423 -98.329239) (xy 437.038986 -98.335339) (xy 436.983252 -98.333302) (xy 436.928409 -98.323172)
			(xy 436.875625 -98.305165) (xy 436.826025 -98.279664) (xy 436.780667 -98.247213) (xy 436.740518 -98.208504)
			(xy 436.706432 -98.164361) (xy 436.679136 -98.115726) (xy 436.659213 -98.063635) (xy 436.647087 -98.009198)
			(xy 436.643016 -97.953576) (xy 435.926569 -97.953576) (xy 435.844696 -98.099372) (xy 435.844442 -98.09988)
			(xy 435.841648 -98.104706) (xy 435.838496 -98.11162) (xy 435.836054 -98.12661) (xy 435.836822 -98.13417)
			(xy 435.837584 -98.138234) (xy 435.852824 -98.199956) (xy 435.859174 -98.208338) (xy 435.864508 -98.215704)
			(xy 435.872636 -98.221038) (xy 435.87289 -98.221292) (xy 435.895746 -98.236397) (xy 435.937287 -98.272115)
			(xy 435.973295 -98.313404) (xy 436.003033 -98.359415) (xy 436.025889 -98.409205) (xy 436.041394 -98.46175)
			(xy 436.04923 -98.515972) (xy 436.049674 -98.543364) (xy 436.049213 -98.570637) (xy 436.041455 -98.624628)
			(xy 436.026092 -98.676966) (xy 436.003437 -98.726585) (xy 435.982275 -98.759518) (xy 447.471292 -98.759518)
			(xy 447.471771 -98.732148) (xy 447.479586 -98.67797) (xy 447.495072 -98.625467) (xy 447.517911 -98.57572)
			(xy 447.547632 -98.529752) (xy 447.565272 -98.50882) (xy 447.565526 -98.508566) (xy 447.571094 -98.501467)
			(xy 447.577351 -98.48456) (xy 447.577718 -98.475546) (xy 447.577718 -98.40849) (xy 447.577362 -98.399473)
			(xy 447.571113 -98.382556) (xy 447.565526 -98.37547) (xy 447.565272 -98.37547) (xy 447.565272 -98.375216)
			(xy 447.547647 -98.35427) (xy 447.517918 -98.308306) (xy 447.495069 -98.258562) (xy 447.479569 -98.206061)
			(xy 447.471738 -98.151884) (xy 447.471736 -98.097143) (xy 447.479564 -98.042965) (xy 447.495059 -97.990464)
			(xy 447.517905 -97.940718) (xy 447.547631 -97.894752) (xy 447.565272 -97.87382) (xy 447.565526 -97.873566)
			(xy 447.571094 -97.866467) (xy 447.577351 -97.84956) (xy 447.577718 -97.840546) (xy 447.577718 -97.77349)
			(xy 447.577362 -97.764473) (xy 447.571113 -97.747556) (xy 447.565526 -97.74047) (xy 447.565272 -97.74047)
			(xy 447.565272 -97.740216) (xy 447.547623 -97.719292) (xy 447.517913 -97.673317) (xy 447.49508 -97.623567)
			(xy 447.479591 -97.571065) (xy 447.471765 -97.516888) (xy 447.471292 -97.489518) (xy 447.471778 -97.462267)
			(xy 447.479534 -97.408319) (xy 447.494889 -97.356024) (xy 447.517531 -97.306447) (xy 447.546997 -97.260597)
			(xy 447.582688 -97.219406) (xy 447.623879 -97.183715) (xy 447.669729 -97.154249) (xy 447.719306 -97.131607)
			(xy 447.771601 -97.116252) (xy 447.825549 -97.108496) (xy 447.880051 -97.108496) (xy 447.933999 -97.116252)
			(xy 447.986294 -97.131607) (xy 448.035871 -97.154249) (xy 448.081721 -97.183715) (xy 448.122912 -97.219406)
			(xy 448.158603 -97.260597) (xy 448.188069 -97.306447) (xy 448.210711 -97.356024) (xy 448.226066 -97.408319)
			(xy 448.233822 -97.462267) (xy 448.234308 -97.489518) (xy 448.233851 -97.516889) (xy 448.22603 -97.571068)
			(xy 448.210539 -97.623571) (xy 448.187696 -97.673318) (xy 448.15797 -97.719284) (xy 448.140328 -97.740216)
			(xy 448.140074 -97.74047) (xy 448.134491 -97.747559) (xy 448.128243 -97.764474) (xy 448.127882 -97.77349)
			(xy 448.127882 -97.840546) (xy 448.128269 -97.84956) (xy 448.134496 -97.866477) (xy 448.140074 -97.873566)
			(xy 448.140328 -97.873566) (xy 448.140328 -97.87382) (xy 448.157988 -97.894738) (xy 448.187716 -97.940707)
			(xy 448.210563 -97.990455) (xy 448.22606 -98.04296) (xy 448.233887 -98.097142) (xy 448.233886 -98.151886)
			(xy 448.226054 -98.206066) (xy 448.210553 -98.25857) (xy 448.187703 -98.308317) (xy 448.157972 -98.354284)
			(xy 448.140328 -98.375216) (xy 448.140074 -98.37547) (xy 448.134491 -98.382559) (xy 448.128243 -98.399474)
			(xy 448.127882 -98.40849) (xy 448.127882 -98.475546) (xy 448.128269 -98.48456) (xy 448.134496 -98.501477)
			(xy 448.136129 -98.503552) (xy 449.126063 -98.503552) (xy 449.126063 -98.449048) (xy 449.13382 -98.395098)
			(xy 449.149176 -98.342801) (xy 449.171818 -98.293222) (xy 449.201286 -98.247369) (xy 449.236979 -98.206177)
			(xy 449.278171 -98.170485) (xy 449.324023 -98.141017) (xy 449.373603 -98.118375) (xy 449.4259 -98.10302)
			(xy 449.47985 -98.095263) (xy 449.507102 -98.0948) (xy 449.533416 -98.095266) (xy 449.585545 -98.102501)
			(xy 449.636187 -98.116821) (xy 449.684386 -98.137953) (xy 449.72923 -98.1655) (xy 449.769869 -98.198938)
			(xy 449.788026 -98.21799) (xy 449.795537 -98.225404) (xy 449.814825 -98.233921) (xy 449.825364 -98.2345)
			(xy 449.90004 -98.2345) (xy 449.910588 -98.233952) (xy 449.929883 -98.22543) (xy 449.937378 -98.21799)
			(xy 449.955549 -98.19895) (xy 449.996176 -98.165492) (xy 450.041013 -98.137931) (xy 450.089211 -98.11679)
			(xy 450.139855 -98.102469) (xy 450.191987 -98.095241) (xy 450.218302 -98.0948) (xy 450.245554 -98.09527)
			(xy 450.299502 -98.103027) (xy 450.351798 -98.118382) (xy 450.401376 -98.141024) (xy 450.447227 -98.170491)
			(xy 450.488418 -98.206183) (xy 450.52411 -98.247374) (xy 450.553577 -98.293226) (xy 450.573272 -98.336354)
			(xy 451.149466 -98.336354) (xy 451.149948 -98.308984) (xy 451.157759 -98.254805) (xy 451.173244 -98.202302)
			(xy 451.196082 -98.152554) (xy 451.225805 -98.106587) (xy 451.243446 -98.085656) (xy 451.2437 -98.085402)
			(xy 451.249292 -98.078319) (xy 451.255535 -98.0614) (xy 451.255892 -98.052382) (xy 451.255892 -97.985326)
			(xy 451.255524 -97.97631) (xy 451.249284 -97.959393) (xy 451.2437 -97.952306) (xy 451.243446 -97.952306)
			(xy 451.243446 -97.952052) (xy 451.225759 -97.931156) (xy 451.196035 -97.885182) (xy 451.173191 -97.83543)
			(xy 451.157698 -97.782922) (xy 451.149873 -97.728738) (xy 451.149878 -97.673992) (xy 451.157713 -97.61981)
			(xy 451.173216 -97.567305) (xy 451.196068 -97.517557) (xy 451.225801 -97.471588) (xy 451.243446 -97.450656)
			(xy 451.2437 -97.450402) (xy 451.249292 -97.443319) (xy 451.255535 -97.4264) (xy 451.255892 -97.417382)
			(xy 451.255892 -97.350326) (xy 451.255524 -97.34131) (xy 451.249284 -97.324393) (xy 451.2437 -97.317306)
			(xy 451.243446 -97.317306) (xy 451.243446 -97.317052) (xy 451.225825 -97.296105) (xy 451.196109 -97.250137)
			(xy 451.173269 -97.200394) (xy 451.157774 -97.147896) (xy 451.149942 -97.093722) (xy 451.149466 -97.066354)
			(xy 451.149952 -97.039103) (xy 451.157708 -96.985155) (xy 451.173063 -96.93286) (xy 451.195705 -96.883283)
			(xy 451.225171 -96.837433) (xy 451.260862 -96.796242) (xy 451.302053 -96.760551) (xy 451.347903 -96.731085)
			(xy 451.39748 -96.708443) (xy 451.449775 -96.693088) (xy 451.503723 -96.685332) (xy 451.558225 -96.685332)
			(xy 451.612173 -96.693088) (xy 451.664468 -96.708443) (xy 451.714045 -96.731085) (xy 451.759895 -96.760551)
			(xy 451.801086 -96.796242) (xy 451.836777 -96.837433) (xy 451.866243 -96.883283) (xy 451.888885 -96.93286)
			(xy 451.90424 -96.985155) (xy 451.911996 -97.039103) (xy 451.912482 -97.066354) (xy 451.911993 -97.093723)
			(xy 451.904182 -97.147902) (xy 451.888698 -97.200405) (xy 451.865861 -97.250152) (xy 451.836141 -97.29612)
			(xy 451.818502 -97.317052) (xy 451.818248 -97.317306) (xy 451.812647 -97.324382) (xy 451.80641 -97.341307)
			(xy 451.806056 -97.350326) (xy 451.806056 -97.417382) (xy 451.80641 -97.426399) (xy 451.812658 -97.443317)
			(xy 451.818248 -97.450402) (xy 451.818502 -97.450402) (xy 451.818502 -97.450656) (xy 451.836096 -97.471626)
			(xy 451.865821 -97.517588) (xy 451.888667 -97.567328) (xy 451.904166 -97.619824) (xy 451.911998 -97.673997)
			(xy 451.912003 -97.728733) (xy 451.904181 -97.782908) (xy 451.888692 -97.835407) (xy 451.865854 -97.885151)
			(xy 451.836138 -97.931119) (xy 451.818502 -97.952052) (xy 451.818248 -97.952306) (xy 451.812647 -97.959382)
			(xy 451.80641 -97.976307) (xy 451.806056 -97.985326) (xy 451.806056 -98.052382) (xy 451.80641 -98.061399)
			(xy 451.812658 -98.078317) (xy 451.818248 -98.085402) (xy 451.818502 -98.085402) (xy 451.818502 -98.085656)
			(xy 451.836134 -98.106594) (xy 451.865847 -98.152565) (xy 451.888684 -98.202311) (xy 451.904177 -98.25481)
			(xy 451.912007 -98.308985) (xy 451.912482 -98.336354) (xy 451.911996 -98.363605) (xy 451.90424 -98.417553)
			(xy 451.888885 -98.469848) (xy 451.866243 -98.519425) (xy 451.836777 -98.565275) (xy 451.801086 -98.606466)
			(xy 451.759895 -98.642157) (xy 451.714045 -98.671623) (xy 451.664468 -98.694265) (xy 451.612173 -98.70962)
			(xy 451.558225 -98.717376) (xy 451.503723 -98.717376) (xy 451.449775 -98.70962) (xy 451.39748 -98.694265)
			(xy 451.347903 -98.671623) (xy 451.302053 -98.642157) (xy 451.260862 -98.606466) (xy 451.225171 -98.565275)
			(xy 451.195705 -98.519425) (xy 451.173063 -98.469848) (xy 451.157708 -98.417553) (xy 451.149952 -98.363605)
			(xy 451.149466 -98.336354) (xy 450.573272 -98.336354) (xy 450.576218 -98.342804) (xy 450.591574 -98.3951)
			(xy 450.59933 -98.449048) (xy 450.59933 -98.503552) (xy 450.591574 -98.5575) (xy 450.576218 -98.609796)
			(xy 450.553577 -98.659374) (xy 450.52411 -98.705226) (xy 450.488418 -98.746417) (xy 450.447227 -98.782109)
			(xy 450.401376 -98.811576) (xy 450.351798 -98.834218) (xy 450.299502 -98.849573) (xy 450.245554 -98.85733)
			(xy 450.218302 -98.857816) (xy 450.191988 -98.857342) (xy 450.13986 -98.850108) (xy 450.089218 -98.83579)
			(xy 450.041019 -98.814658) (xy 449.996175 -98.787114) (xy 449.955535 -98.753677) (xy 449.937378 -98.734626)
			(xy 449.929863 -98.727216) (xy 449.910578 -98.718696) (xy 449.90004 -98.718116) (xy 449.825364 -98.718116)
			(xy 449.814816 -98.718662) (xy 449.79552 -98.727185) (xy 449.788026 -98.734626) (xy 449.769856 -98.753667)
			(xy 449.729229 -98.787124) (xy 449.684391 -98.814685) (xy 449.636194 -98.835826) (xy 449.585549 -98.850146)
			(xy 449.533417 -98.857375) (xy 449.507102 -98.857816) (xy 449.47985 -98.857337) (xy 449.4259 -98.84958)
			(xy 449.373603 -98.834225) (xy 449.324023 -98.811583) (xy 449.278171 -98.782115) (xy 449.236979 -98.746423)
			(xy 449.201286 -98.705231) (xy 449.171818 -98.659378) (xy 449.149176 -98.609799) (xy 449.13382 -98.557502)
			(xy 449.126063 -98.503552) (xy 448.136129 -98.503552) (xy 448.140074 -98.508566) (xy 448.140328 -98.509074)
			(xy 448.151273 -98.521808) (xy 448.171114 -98.548899) (xy 448.179952 -98.563176) (xy 448.185286 -98.572066)
			(xy 448.202304 -98.584258) (xy 448.295522 -98.604578) (xy 448.316096 -98.60026) (xy 448.324732 -98.594418)
			(xy 448.348787 -98.578404) (xy 448.400722 -98.553064) (xy 448.455882 -98.535842) (xy 448.513009 -98.527132)
			(xy 448.541902 -98.5266) (xy 448.569154 -98.52707) (xy 448.623102 -98.534827) (xy 448.675398 -98.550182)
			(xy 448.724976 -98.572824) (xy 448.770827 -98.602291) (xy 448.812018 -98.637983) (xy 448.84771 -98.679174)
			(xy 448.877177 -98.725026) (xy 448.899818 -98.774604) (xy 448.915174 -98.8269) (xy 448.92293 -98.880848)
			(xy 448.92293 -98.935352) (xy 448.915174 -98.9893) (xy 448.899818 -99.041596) (xy 448.877177 -99.091174)
			(xy 448.84771 -99.137026) (xy 448.812018 -99.178217) (xy 448.770827 -99.213909) (xy 448.724976 -99.243376)
			(xy 448.675398 -99.266018) (xy 448.623102 -99.281373) (xy 448.569154 -99.28913) (xy 448.541902 -99.289616)
			(xy 448.51381 -99.28912) (xy 448.458233 -99.280893) (xy 448.404464 -99.264602) (xy 448.353667 -99.2406)
			(xy 448.30694 -99.209405) (xy 448.265295 -99.171693) (xy 448.229633 -99.12828) (xy 448.21475 -99.10445)
			(xy 448.209416 -99.09556) (xy 448.192398 -99.083368) (xy 448.09918 -99.063048) (xy 448.078606 -99.067366)
			(xy 448.06997 -99.073208) (xy 448.045916 -99.089224) (xy 447.993981 -99.114563) (xy 447.93882 -99.131784)
			(xy 447.881693 -99.140494) (xy 447.8528 -99.141026) (xy 447.82555 -99.140522) (xy 447.771603 -99.132766)
			(xy 447.71931 -99.117412) (xy 447.669734 -99.094772) (xy 447.623885 -99.065308) (xy 447.582695 -99.029618)
			(xy 447.547003 -98.98843) (xy 447.517536 -98.942582) (xy 447.494894 -98.893007) (xy 447.479538 -98.840714)
			(xy 447.471779 -98.786768) (xy 447.471292 -98.759518) (xy 435.982275 -98.759518) (xy 435.97395 -98.772474)
			(xy 435.938233 -98.813699) (xy 435.897012 -98.849421) (xy 435.851127 -98.878914) (xy 435.801511 -98.901575)
			(xy 435.749175 -98.916945) (xy 435.695185 -98.92471) (xy 435.667912 -98.925126) (xy 435.640562 -98.924637)
			(xy 435.586426 -98.916792) (xy 435.533964 -98.901304) (xy 435.508908 -98.890328) (xy 435.500526 -98.886518)
			(xy 435.499002 -98.885756) (xy 435.490465 -98.881874) (xy 435.471812 -98.880063) (xy 435.46268 -98.8822)
			(xy 435.441598 -98.889058) (xy 435.44109 -98.889058) (xy 435.411118 -98.898456) (xy 435.403006 -98.901396)
			(xy 435.389239 -98.911778) (xy 435.384194 -98.918776) (xy 435.08598 -99.449382) (xy 436.206136 -99.449382)
			(xy 436.210207 -99.39376) (xy 436.222333 -99.339323) (xy 436.242256 -99.287232) (xy 436.269552 -99.238597)
			(xy 436.303638 -99.194454) (xy 436.343787 -99.155745) (xy 436.389145 -99.123294) (xy 436.438745 -99.097793)
			(xy 436.491529 -99.079786) (xy 436.546372 -99.069656) (xy 436.602106 -99.067619) (xy 436.657543 -99.073719)
			(xy 436.7115 -99.087825) (xy 436.762829 -99.109637) (xy 436.810435 -99.138691) (xy 436.853303 -99.174366)
			(xy 436.89052 -99.215903) (xy 436.921293 -99.262416) (xy 436.944965 -99.312913) (xy 436.961033 -99.36632)
			(xy 436.969153 -99.421496) (xy 436.969662 -99.449382) (xy 436.969495 -99.458526) (xy 441.938662 -99.458526)
			(xy 441.942733 -99.402904) (xy 441.954859 -99.348467) (xy 441.974782 -99.296376) (xy 442.002078 -99.247741)
			(xy 442.036164 -99.203598) (xy 442.076313 -99.164889) (xy 442.121671 -99.132438) (xy 442.171271 -99.106937)
			(xy 442.224055 -99.08893) (xy 442.278898 -99.0788) (xy 442.334632 -99.076763) (xy 442.390069 -99.082863)
			(xy 442.444026 -99.096969) (xy 442.495355 -99.118781) (xy 442.542961 -99.147835) (xy 442.585829 -99.18351)
			(xy 442.623046 -99.225047) (xy 442.653819 -99.27156) (xy 442.677491 -99.322057) (xy 442.693559 -99.375464)
			(xy 442.701679 -99.43064) (xy 442.702188 -99.458526) (xy 442.701679 -99.486412) (xy 442.693559 -99.541588)
			(xy 442.677491 -99.594995) (xy 442.653819 -99.645492) (xy 442.623046 -99.692005) (xy 442.585829 -99.733542)
			(xy 442.542961 -99.769217) (xy 442.495355 -99.798271) (xy 442.444026 -99.820083) (xy 442.390069 -99.834189)
			(xy 442.334632 -99.840289) (xy 442.278898 -99.838252) (xy 442.224055 -99.828122) (xy 442.171271 -99.810115)
			(xy 442.121671 -99.784614) (xy 442.076313 -99.752163) (xy 442.036164 -99.713454) (xy 442.002078 -99.669311)
			(xy 441.974782 -99.620676) (xy 441.954859 -99.568585) (xy 441.942733 -99.514148) (xy 441.938662 -99.458526)
			(xy 436.969495 -99.458526) (xy 436.969153 -99.477268) (xy 436.961033 -99.532444) (xy 436.944965 -99.585851)
			(xy 436.921293 -99.636348) (xy 436.89052 -99.682861) (xy 436.853303 -99.724398) (xy 436.810435 -99.760073)
			(xy 436.762829 -99.789127) (xy 436.7115 -99.810939) (xy 436.657543 -99.825045) (xy 436.602106 -99.831145)
			(xy 436.546372 -99.829108) (xy 436.491529 -99.818978) (xy 436.438745 -99.800971) (xy 436.389145 -99.77547)
			(xy 436.343787 -99.743019) (xy 436.303638 -99.70431) (xy 436.269552 -99.660167) (xy 436.242256 -99.611532)
			(xy 436.222333 -99.559441) (xy 436.210207 -99.505004) (xy 436.206136 -99.449382) (xy 435.08598 -99.449382)
			(xy 434.96992 -99.655884) (xy 434.107603 -101.18985) (xy 445.29349 -101.18985) (xy 445.29349 -101.13535)
			(xy 445.301246 -101.081404) (xy 445.316601 -101.029111) (xy 445.339241 -100.979536) (xy 445.368706 -100.933687)
			(xy 445.404396 -100.892499) (xy 445.445584 -100.856808) (xy 445.491433 -100.827343) (xy 445.541008 -100.804702)
			(xy 445.5933 -100.789347) (xy 445.647246 -100.781591) (xy 445.674496 -100.781104) (xy 445.701866 -100.781571)
			(xy 445.756045 -100.789389) (xy 445.808548 -100.804877) (xy 445.858295 -100.827719) (xy 445.904262 -100.857443)
			(xy 445.925194 -100.875084) (xy 445.925448 -100.875338) (xy 445.932542 -100.880913) (xy 445.949453 -100.887166)
			(xy 445.958468 -100.88753) (xy 446.025524 -100.88753) (xy 446.034541 -100.887178) (xy 446.051458 -100.880926)
			(xy 446.058544 -100.875338) (xy 446.058544 -100.875084) (xy 446.058798 -100.875084) (xy 446.079718 -100.85743)
			(xy 446.125694 -100.827721) (xy 446.175445 -100.804888) (xy 446.227948 -100.7894) (xy 446.282126 -100.781576)
			(xy 446.309496 -100.781104) (xy 446.33675 -100.781543) (xy 446.390703 -100.789299) (xy 446.443003 -100.804656)
			(xy 446.492585 -100.827299) (xy 446.53844 -100.856767) (xy 446.579635 -100.892462) (xy 446.61533 -100.933656)
			(xy 446.6448 -100.979511) (xy 446.667443 -101.029093) (xy 446.6828 -101.081393) (xy 446.690557 -101.135346)
			(xy 446.690557 -101.189854) (xy 446.6828 -101.243807) (xy 446.667443 -101.296107) (xy 446.6448 -101.345689)
			(xy 446.61533 -101.391544) (xy 446.579635 -101.432738) (xy 446.53844 -101.468433) (xy 446.492585 -101.497901)
			(xy 446.443003 -101.520544) (xy 446.390703 -101.535901) (xy 446.33675 -101.543657) (xy 446.309496 -101.54412)
			(xy 446.282125 -101.543676) (xy 446.227944 -101.535856) (xy 446.17544 -101.520363) (xy 446.125693 -101.497515)
			(xy 446.079728 -101.467785) (xy 446.058798 -101.45014) (xy 446.058544 -101.449886) (xy 446.05145 -101.44431)
			(xy 446.034539 -101.438057) (xy 446.025524 -101.437694) (xy 445.958468 -101.437694) (xy 445.94945 -101.438037)
			(xy 445.932533 -101.444295) (xy 445.925448 -101.449886) (xy 445.925448 -101.45014) (xy 445.925194 -101.45014)
			(xy 445.90428 -101.467802) (xy 445.858302 -101.497509) (xy 445.80855 -101.52034) (xy 445.756045 -101.535826)
			(xy 445.701866 -101.543649) (xy 445.674496 -101.54412) (xy 445.647246 -101.543609) (xy 445.5933 -101.535853)
			(xy 445.541008 -101.520498) (xy 445.491433 -101.497857) (xy 445.445584 -101.468392) (xy 445.404396 -101.432701)
			(xy 445.368706 -101.391513) (xy 445.339241 -101.345664) (xy 445.316601 -101.296089) (xy 445.301246 -101.243796)
			(xy 445.29349 -101.18985) (xy 434.107603 -101.18985) (xy 433.888746 -101.579172) (xy 436.070754 -101.579172)
			(xy 436.074825 -101.52355) (xy 436.086951 -101.469113) (xy 436.106874 -101.417022) (xy 436.13417 -101.368387)
			(xy 436.168256 -101.324244) (xy 436.208405 -101.285535) (xy 436.253763 -101.253084) (xy 436.303363 -101.227583)
			(xy 436.356147 -101.209576) (xy 436.41099 -101.199446) (xy 436.466724 -101.197409) (xy 436.522161 -101.203509)
			(xy 436.576118 -101.217615) (xy 436.627447 -101.239427) (xy 436.675053 -101.268481) (xy 436.717921 -101.304156)
			(xy 436.755138 -101.345693) (xy 436.785911 -101.392206) (xy 436.809583 -101.442703) (xy 436.825651 -101.49611)
			(xy 436.833771 -101.551286) (xy 436.83428 -101.579172) (xy 436.833771 -101.607058) (xy 436.825651 -101.662234)
			(xy 436.809583 -101.715641) (xy 436.785911 -101.766138) (xy 436.755138 -101.812651) (xy 436.717921 -101.854188)
			(xy 436.698003 -101.870764) (xy 441.53912 -101.870764) (xy 441.543191 -101.815142) (xy 441.555317 -101.760705)
			(xy 441.57524 -101.708614) (xy 441.602536 -101.659979) (xy 441.636622 -101.615836) (xy 441.676771 -101.577127)
			(xy 441.722129 -101.544676) (xy 441.771729 -101.519175) (xy 441.824513 -101.501168) (xy 441.879356 -101.491038)
			(xy 441.93509 -101.489001) (xy 441.990527 -101.495101) (xy 442.044484 -101.509207) (xy 442.095813 -101.531019)
			(xy 442.143419 -101.560073) (xy 442.186287 -101.595748) (xy 442.223504 -101.637285) (xy 442.254277 -101.683798)
			(xy 442.277949 -101.734295) (xy 442.294017 -101.787702) (xy 442.302137 -101.842878) (xy 442.302646 -101.870764)
			(xy 442.302137 -101.89865) (xy 442.294017 -101.953826) (xy 442.277949 -102.007233) (xy 442.254277 -102.05773)
			(xy 442.223504 -102.104243) (xy 442.200022 -102.130451) (xy 444.843152 -102.130451) (xy 444.843152 -102.075949)
			(xy 444.850908 -102.022002) (xy 444.866261 -101.969707) (xy 444.888901 -101.920129) (xy 444.918365 -101.874278)
			(xy 444.954054 -101.833086) (xy 444.995241 -101.797392) (xy 445.041089 -101.767923) (xy 445.090664 -101.745277)
			(xy 445.142957 -101.729917) (xy 445.196903 -101.722155) (xy 445.224154 -101.721666) (xy 445.251524 -101.722143)
			(xy 445.305703 -101.729956) (xy 445.358207 -101.745441) (xy 445.407954 -101.768281) (xy 445.453921 -101.798005)
			(xy 445.474852 -101.815646) (xy 445.475106 -101.8159) (xy 445.482187 -101.821495) (xy 445.499108 -101.827737)
			(xy 445.508126 -101.828092) (xy 445.575182 -101.828092) (xy 445.584198 -101.827728) (xy 445.601115 -101.821486)
			(xy 445.608202 -101.8159) (xy 445.608202 -101.815646) (xy 445.608456 -101.815646) (xy 445.6294 -101.798021)
			(xy 445.675369 -101.768306) (xy 445.725113 -101.745466) (xy 445.777611 -101.729972) (xy 445.831786 -101.722141)
			(xy 445.859154 -101.721666) (xy 445.886407 -101.722178) (xy 445.940359 -101.729929) (xy 445.992659 -101.74528)
			(xy 446.042242 -101.767919) (xy 446.088097 -101.797383) (xy 446.129293 -101.833075) (xy 446.164989 -101.874266)
			(xy 446.194459 -101.920118) (xy 446.217104 -101.969698) (xy 446.232461 -102.021996) (xy 446.240219 -102.075947)
			(xy 446.240219 -102.130453) (xy 446.232461 -102.184404) (xy 446.217104 -102.236702) (xy 446.194459 -102.286282)
			(xy 446.164989 -102.332134) (xy 446.129293 -102.373325) (xy 446.088097 -102.409017) (xy 446.042242 -102.438481)
			(xy 445.992659 -102.46112) (xy 445.940359 -102.476471) (xy 445.886407 -102.484222) (xy 445.859154 -102.484682)
			(xy 445.831785 -102.484189) (xy 445.777607 -102.476378) (xy 445.725104 -102.460896) (xy 445.675356 -102.43806)
			(xy 445.629388 -102.408341) (xy 445.608456 -102.390702) (xy 445.608202 -102.390448) (xy 445.601124 -102.38485)
			(xy 445.5842 -102.378611) (xy 445.575182 -102.378256) (xy 445.508126 -102.378256) (xy 445.499109 -102.378613)
			(xy 445.482191 -102.384859) (xy 445.475106 -102.390448) (xy 445.475106 -102.390702) (xy 445.474852 -102.390702)
			(xy 445.453911 -102.40833) (xy 445.407941 -102.438044) (xy 445.358196 -102.460882) (xy 445.305697 -102.476375)
			(xy 445.251523 -102.484206) (xy 445.224154 -102.484682) (xy 445.196903 -102.484245) (xy 445.142957 -102.476483)
			(xy 445.090664 -102.461123) (xy 445.041089 -102.438477) (xy 444.995241 -102.409008) (xy 444.954054 -102.373314)
			(xy 444.918365 -102.332122) (xy 444.888901 -102.286271) (xy 444.866261 -102.236693) (xy 444.850908 -102.184398)
			(xy 444.843152 -102.130451) (xy 442.200022 -102.130451) (xy 442.186287 -102.14578) (xy 442.143419 -102.181455)
			(xy 442.095813 -102.210509) (xy 442.044484 -102.232321) (xy 441.990527 -102.246427) (xy 441.93509 -102.252527)
			(xy 441.879356 -102.25049) (xy 441.824513 -102.24036) (xy 441.771729 -102.222353) (xy 441.722129 -102.196852)
			(xy 441.676771 -102.164401) (xy 441.636622 -102.125692) (xy 441.602536 -102.081549) (xy 441.57524 -102.032914)
			(xy 441.555317 -101.980823) (xy 441.543191 -101.926386) (xy 441.53912 -101.870764) (xy 436.698003 -101.870764)
			(xy 436.675053 -101.889863) (xy 436.627447 -101.918917) (xy 436.576118 -101.940729) (xy 436.522161 -101.954835)
			(xy 436.466724 -101.960935) (xy 436.41099 -101.958898) (xy 436.356147 -101.948768) (xy 436.303363 -101.930761)
			(xy 436.253763 -101.90526) (xy 436.208405 -101.872809) (xy 436.168256 -101.8341) (xy 436.13417 -101.789957)
			(xy 436.106874 -101.741322) (xy 436.086951 -101.689231) (xy 436.074825 -101.634794) (xy 436.070754 -101.579172)
			(xy 433.888746 -101.579172) (xy 433.011756 -103.13924) (xy 437.807098 -103.13924) (xy 437.811169 -103.083618)
			(xy 437.823295 -103.029181) (xy 437.843218 -102.97709) (xy 437.870514 -102.928455) (xy 437.9046 -102.884312)
			(xy 437.944749 -102.845603) (xy 437.990107 -102.813152) (xy 438.039707 -102.787651) (xy 438.092491 -102.769644)
			(xy 438.147334 -102.759514) (xy 438.203068 -102.757477) (xy 438.258505 -102.763577) (xy 438.312462 -102.777683)
			(xy 438.363791 -102.799495) (xy 438.411397 -102.828549) (xy 438.454265 -102.864224) (xy 438.491482 -102.905761)
			(xy 438.522255 -102.952274) (xy 438.545927 -103.002771) (xy 438.561995 -103.056178) (xy 438.570115 -103.111354)
			(xy 438.570624 -103.13924) (xy 438.570115 -103.167126) (xy 438.561995 -103.222302) (xy 438.545927 -103.275709)
			(xy 438.522255 -103.326206) (xy 438.491482 -103.372719) (xy 438.454265 -103.414256) (xy 438.411397 -103.449931)
			(xy 438.363791 -103.478985) (xy 438.312462 -103.500797) (xy 438.258505 -103.514903) (xy 438.203068 -103.521003)
			(xy 438.147334 -103.518966) (xy 438.092491 -103.508836) (xy 438.039707 -103.490829) (xy 437.990107 -103.465328)
			(xy 437.944749 -103.432877) (xy 437.9046 -103.394168) (xy 437.870514 -103.350025) (xy 437.843218 -103.30139)
			(xy 437.823295 -103.249299) (xy 437.811169 -103.194862) (xy 437.807098 -103.13924) (xy 433.011756 -103.13924)
			(xy 432.148473 -104.674924) (xy 436.859424 -104.674924) (xy 436.863495 -104.619302) (xy 436.875621 -104.564865)
			(xy 436.895544 -104.512774) (xy 436.92284 -104.464139) (xy 436.956926 -104.419996) (xy 436.997075 -104.381287)
			(xy 437.042433 -104.348836) (xy 437.092033 -104.323335) (xy 437.144817 -104.305328) (xy 437.19966 -104.295198)
			(xy 437.255394 -104.293161) (xy 437.310831 -104.299261) (xy 437.364788 -104.313367) (xy 437.416117 -104.335179)
			(xy 437.463723 -104.364233) (xy 437.506591 -104.399908) (xy 437.543808 -104.441445) (xy 437.574581 -104.487958)
			(xy 437.598253 -104.538455) (xy 437.614321 -104.591862) (xy 437.622441 -104.647038) (xy 437.62295 -104.674924)
			(xy 437.622441 -104.70281) (xy 437.614321 -104.757986) (xy 437.598253 -104.811393) (xy 437.574581 -104.86189)
			(xy 437.543808 -104.908403) (xy 437.506591 -104.94994) (xy 437.463723 -104.985615) (xy 437.416117 -105.014669)
			(xy 437.364788 -105.036481) (xy 437.310831 -105.050587) (xy 437.255394 -105.056687) (xy 437.19966 -105.05465)
			(xy 437.144817 -105.04452) (xy 437.092033 -105.026513) (xy 437.042433 -105.001012) (xy 436.997075 -104.968561)
			(xy 436.956926 -104.929852) (xy 436.92284 -104.885709) (xy 436.895544 -104.837074) (xy 436.875621 -104.784983)
			(xy 436.863495 -104.730546) (xy 436.859424 -104.674924) (xy 432.148473 -104.674924) (xy 431.208942 -106.346244)
			(xy 431.20564 -106.35742) (xy 431.118567 -107.058206) (xy 437.873902 -107.058206) (xy 437.874429 -107.029467)
			(xy 437.883051 -106.97264) (xy 437.9001 -106.917749) (xy 437.925191 -106.866037) (xy 437.957755 -106.818675)
			(xy 437.977026 -106.797348) (xy 437.98363 -106.79049) (xy 437.990742 -106.772456) (xy 437.990742 -106.683556)
			(xy 437.98363 -106.665522) (xy 437.977026 -106.658664) (xy 437.957761 -106.637332) (xy 437.925195 -106.589971)
			(xy 437.900103 -106.53826) (xy 437.883053 -106.48337) (xy 437.87443 -106.426543) (xy 437.874429 -106.369066)
			(xy 437.883051 -106.312239) (xy 437.9001 -106.257349) (xy 437.925191 -106.205637) (xy 437.957756 -106.158275)
			(xy 437.977026 -106.136948) (xy 437.98363 -106.13009) (xy 437.990742 -106.112056) (xy 437.990742 -106.023156)
			(xy 437.98363 -106.005122) (xy 437.977026 -105.998264) (xy 437.957756 -105.976936) (xy 437.92519 -105.929574)
			(xy 437.900098 -105.877863) (xy 437.883047 -105.822972) (xy 437.874423 -105.766145) (xy 437.873902 -105.737406)
			(xy 437.874388 -105.710155) (xy 437.882144 -105.656207) (xy 437.897499 -105.603912) (xy 437.920141 -105.554335)
			(xy 437.949607 -105.508485) (xy 437.985298 -105.467294) (xy 438.026489 -105.431603) (xy 438.072339 -105.402137)
			(xy 438.121916 -105.379495) (xy 438.174211 -105.36414) (xy 438.228159 -105.356384) (xy 438.282661 -105.356384)
			(xy 438.336609 -105.36414) (xy 438.388904 -105.379495) (xy 438.438481 -105.402137) (xy 438.484331 -105.431603)
			(xy 438.525522 -105.467294) (xy 438.561213 -105.508485) (xy 438.590679 -105.554335) (xy 438.613321 -105.603912)
			(xy 438.628676 -105.656207) (xy 438.636432 -105.710155) (xy 438.636918 -105.737406) (xy 438.636393 -105.766145)
			(xy 438.62777 -105.822972) (xy 438.61072 -105.877862) (xy 438.585629 -105.929574) (xy 438.553064 -105.976937)
			(xy 438.533794 -105.998264) (xy 438.52719 -106.005122) (xy 438.520078 -106.023156) (xy 438.520078 -106.112056)
			(xy 438.52719 -106.13009) (xy 438.533794 -106.136948) (xy 438.55307 -106.15827) (xy 438.585633 -106.205634)
			(xy 438.610724 -106.257346) (xy 438.627772 -106.312238) (xy 438.636394 -106.369065) (xy 438.636393 -106.426543)
			(xy 438.62777 -106.483371) (xy 438.61072 -106.538262) (xy 438.585629 -106.589974) (xy 438.553064 -106.637337)
			(xy 438.533794 -106.658664) (xy 438.52719 -106.665522) (xy 438.520078 -106.683556) (xy 438.520078 -106.772456)
			(xy 438.52719 -106.79049) (xy 438.533794 -106.797348) (xy 438.553056 -106.818683) (xy 438.585626 -106.866042)
			(xy 438.610721 -106.917751) (xy 438.627773 -106.972641) (xy 438.636397 -107.029467) (xy 438.636918 -107.058206)
			(xy 438.636432 -107.085457) (xy 438.628676 -107.139405) (xy 438.613321 -107.1917) (xy 438.590679 -107.241277)
			(xy 438.561213 -107.287127) (xy 438.525522 -107.328318) (xy 438.484331 -107.364009) (xy 438.438481 -107.393475)
			(xy 438.388904 -107.416117) (xy 438.336609 -107.431472) (xy 438.282661 -107.439228) (xy 438.228159 -107.439228)
			(xy 438.174211 -107.431472) (xy 438.121916 -107.416117) (xy 438.072339 -107.393475) (xy 438.026489 -107.364009)
			(xy 437.985298 -107.328318) (xy 437.949607 -107.287127) (xy 437.920141 -107.241277) (xy 437.897499 -107.1917)
			(xy 437.882144 -107.139405) (xy 437.874388 -107.085457) (xy 437.873902 -107.058206) (xy 431.118567 -107.058206)
			(xy 430.954458 -108.379006) (xy 438.762902 -108.379006) (xy 438.763429 -108.350267) (xy 438.772051 -108.29344)
			(xy 438.7891 -108.238549) (xy 438.814191 -108.186837) (xy 438.846755 -108.139475) (xy 438.866026 -108.118148)
			(xy 438.87263 -108.11129) (xy 438.879742 -108.093256) (xy 438.879742 -108.004356) (xy 438.87263 -107.986322)
			(xy 438.866026 -107.979464) (xy 438.846761 -107.958132) (xy 438.814195 -107.910771) (xy 438.789103 -107.85906)
			(xy 438.772053 -107.80417) (xy 438.76343 -107.747343) (xy 438.763429 -107.689866) (xy 438.772051 -107.633039)
			(xy 438.7891 -107.578149) (xy 438.814191 -107.526437) (xy 438.846756 -107.479075) (xy 438.866026 -107.457748)
			(xy 438.87263 -107.45089) (xy 438.879742 -107.432856) (xy 438.879742 -107.343956) (xy 438.87263 -107.325922)
			(xy 438.866026 -107.319064) (xy 438.846761 -107.297732) (xy 438.814195 -107.250371) (xy 438.789103 -107.19866)
			(xy 438.772053 -107.14377) (xy 438.76343 -107.086943) (xy 438.763429 -107.029466) (xy 438.772051 -106.972639)
			(xy 438.7891 -106.917749) (xy 438.814191 -106.866037) (xy 438.846756 -106.818675) (xy 438.866026 -106.797348)
			(xy 438.87263 -106.79049) (xy 438.879742 -106.772456) (xy 438.879742 -106.683556) (xy 438.87263 -106.665522)
			(xy 438.866026 -106.658664) (xy 438.846761 -106.637332) (xy 438.814195 -106.589971) (xy 438.789103 -106.53826)
			(xy 438.772053 -106.48337) (xy 438.76343 -106.426543) (xy 438.763429 -106.369066) (xy 438.772051 -106.312239)
			(xy 438.7891 -106.257349) (xy 438.814191 -106.205637) (xy 438.846756 -106.158275) (xy 438.866026 -106.136948)
			(xy 438.87263 -106.13009) (xy 438.879742 -106.112056) (xy 438.879742 -106.023156) (xy 438.87263 -106.005122)
			(xy 438.866026 -105.998264) (xy 438.846761 -105.976932) (xy 438.814195 -105.929571) (xy 438.789103 -105.87786)
			(xy 438.772053 -105.82297) (xy 438.76343 -105.766143) (xy 438.763429 -105.708666) (xy 438.772051 -105.651839)
			(xy 438.7891 -105.596949) (xy 438.814191 -105.545237) (xy 438.846756 -105.497875) (xy 438.866026 -105.476548)
			(xy 438.87263 -105.46969) (xy 438.879742 -105.451656) (xy 438.879742 -105.362756) (xy 438.87263 -105.344722)
			(xy 438.866026 -105.337864) (xy 438.846761 -105.316532) (xy 438.814195 -105.269171) (xy 438.789103 -105.21746)
			(xy 438.772053 -105.16257) (xy 438.76343 -105.105743) (xy 438.763429 -105.048266) (xy 438.772051 -104.991439)
			(xy 438.7891 -104.936549) (xy 438.814191 -104.884837) (xy 438.846756 -104.837475) (xy 438.866026 -104.816148)
			(xy 438.87263 -104.80929) (xy 438.879742 -104.791256) (xy 438.879742 -104.702356) (xy 438.87263 -104.684322)
			(xy 438.866026 -104.677464) (xy 438.846761 -104.656132) (xy 438.814195 -104.608771) (xy 438.789103 -104.55706)
			(xy 438.772053 -104.50217) (xy 438.76343 -104.445343) (xy 438.763429 -104.387866) (xy 438.772051 -104.331039)
			(xy 438.7891 -104.276149) (xy 438.814191 -104.224437) (xy 438.846756 -104.177075) (xy 438.866026 -104.155748)
			(xy 438.87263 -104.14889) (xy 438.879742 -104.130856) (xy 438.879742 -104.041956) (xy 438.87263 -104.023922)
			(xy 438.866026 -104.017064) (xy 438.846761 -103.995732) (xy 438.814195 -103.948371) (xy 438.789103 -103.89666)
			(xy 438.772053 -103.84177) (xy 438.76343 -103.784943) (xy 438.763429 -103.727466) (xy 438.772051 -103.670639)
			(xy 438.7891 -103.615749) (xy 438.814191 -103.564037) (xy 438.846756 -103.516675) (xy 438.866026 -103.495348)
			(xy 438.87263 -103.48849) (xy 438.879742 -103.470456) (xy 438.879742 -103.381556) (xy 438.87263 -103.363522)
			(xy 438.866026 -103.356664) (xy 438.846756 -103.335336) (xy 438.81419 -103.287974) (xy 438.789098 -103.236263)
			(xy 438.772047 -103.181372) (xy 438.763423 -103.124545) (xy 438.762902 -103.095806) (xy 438.763344 -103.068599)
			(xy 438.771069 -103.014735) (xy 438.786375 -102.962517) (xy 438.808953 -102.913008) (xy 438.838342 -102.867212)
			(xy 438.873946 -102.826063) (xy 438.915041 -102.790395) (xy 438.937654 -102.775258) (xy 438.946036 -102.769924)
			(xy 438.957212 -102.753668) (xy 438.9755 -102.674674) (xy 438.977308 -102.665045) (xy 438.974311 -102.645703)
			(xy 438.969658 -102.637082) (xy 438.969404 -102.637082) (xy 438.969404 -102.636574) (xy 438.956199 -102.614063)
			(xy 438.935343 -102.566221) (xy 438.921193 -102.515987) (xy 438.914009 -102.464294) (xy 438.913524 -102.4382)
			(xy 438.91401 -102.410949) (xy 438.921766 -102.357001) (xy 438.937121 -102.304706) (xy 438.959763 -102.255129)
			(xy 438.989229 -102.209279) (xy 439.02492 -102.168088) (xy 439.066111 -102.132397) (xy 439.111961 -102.102931)
			(xy 439.161538 -102.080289) (xy 439.213833 -102.064934) (xy 439.267781 -102.057178) (xy 439.322283 -102.057178)
			(xy 439.376231 -102.064934) (xy 439.428526 -102.080289) (xy 439.478103 -102.102931) (xy 439.523953 -102.132397)
			(xy 439.565144 -102.168088) (xy 439.600835 -102.209279) (xy 439.630301 -102.255129) (xy 439.652943 -102.304706)
			(xy 439.668298 -102.357001) (xy 439.676054 -102.410949) (xy 439.67654 -102.4382) (xy 439.676083 -102.465407)
			(xy 439.668359 -102.519269) (xy 439.653054 -102.571485) (xy 439.630478 -102.620994) (xy 439.601091 -102.666789)
			(xy 439.56549 -102.70794) (xy 439.524399 -102.743609) (xy 439.501788 -102.758748) (xy 439.493406 -102.764082)
			(xy 439.48223 -102.780338) (xy 439.463942 -102.859332) (xy 439.462138 -102.868962) (xy 439.465134 -102.888302)
			(xy 439.469784 -102.896924) (xy 439.470038 -102.896924) (xy 439.470038 -102.897432) (xy 439.48325 -102.919939)
			(xy 439.504103 -102.967783) (xy 439.518251 -103.018018) (xy 439.525433 -103.069712) (xy 439.525918 -103.095806)
			(xy 439.525393 -103.124545) (xy 439.51677 -103.181372) (xy 439.49972 -103.236262) (xy 439.474629 -103.287974)
			(xy 439.442064 -103.335337) (xy 439.422794 -103.356664) (xy 439.41619 -103.363522) (xy 439.409078 -103.381556)
			(xy 439.409078 -103.470456) (xy 439.41619 -103.48849) (xy 439.422794 -103.495348) (xy 439.44207 -103.51667)
			(xy 439.474633 -103.564034) (xy 439.499724 -103.615746) (xy 439.516772 -103.670638) (xy 439.525394 -103.727465)
			(xy 439.525393 -103.784943) (xy 439.51677 -103.841771) (xy 439.49972 -103.896662) (xy 439.474629 -103.948374)
			(xy 439.442064 -103.995737) (xy 439.422794 -104.017064) (xy 439.417168 -104.022906) (xy 444.16599 -104.022906)
			(xy 444.166465 -103.996592) (xy 444.173698 -103.944464) (xy 444.188016 -103.893822) (xy 444.209147 -103.845623)
			(xy 444.236692 -103.800779) (xy 444.270129 -103.760139) (xy 444.28918 -103.741982) (xy 444.296589 -103.734466)
			(xy 444.30511 -103.715182) (xy 444.30569 -103.704644) (xy 444.30569 -103.629968) (xy 444.30514 -103.619421)
			(xy 444.29662 -103.600125) (xy 444.28918 -103.59263) (xy 444.270142 -103.574457) (xy 444.236684 -103.53383)
			(xy 444.209123 -103.488994) (xy 444.187982 -103.440796) (xy 444.173661 -103.390152) (xy 444.166431 -103.338021)
			(xy 444.16599 -103.311706) (xy 444.166461 -103.284453) (xy 444.174217 -103.230503) (xy 444.189572 -103.178205)
			(xy 444.212214 -103.128625) (xy 444.241681 -103.082772) (xy 444.277374 -103.04158) (xy 444.318566 -103.005886)
			(xy 444.364418 -102.976418) (xy 444.413998 -102.953775) (xy 444.466295 -102.938419) (xy 444.520245 -102.930661)
			(xy 444.547498 -102.930198) (xy 444.575163 -102.930713) (xy 444.629912 -102.938712) (xy 444.682933 -102.954528)
			(xy 444.733117 -102.977831) (xy 444.779413 -103.008132) (xy 444.820851 -103.044796) (xy 444.856564 -103.087057)
			(xy 444.871602 -103.110284) (xy 444.878229 -103.119969) (xy 444.898098 -103.132408) (xy 444.909702 -103.13416)
			(xy 444.989712 -103.142034) (xy 445.001351 -103.14267) (xy 445.023189 -103.134588) (xy 445.031622 -103.12654)
			(xy 445.031876 -103.126286) (xy 445.049936 -103.107683) (xy 445.090272 -103.075107) (xy 445.134651 -103.048297)
			(xy 445.182254 -103.027749) (xy 445.232202 -103.01384) (xy 445.283574 -103.006827) (xy 445.309498 -103.006398)
			(xy 445.336751 -103.006857) (xy 445.390702 -103.014614) (xy 445.443001 -103.02997) (xy 445.492581 -103.052613)
			(xy 445.538435 -103.082081) (xy 445.579628 -103.117775) (xy 445.615321 -103.158969) (xy 445.644789 -103.204822)
			(xy 445.667431 -103.254403) (xy 445.682787 -103.306701) (xy 445.690543 -103.360653) (xy 445.691006 -103.387906)
			(xy 445.690542 -103.415276) (xy 445.682723 -103.469455) (xy 445.667234 -103.521958) (xy 445.644392 -103.571705)
			(xy 445.614667 -103.617672) (xy 445.597026 -103.638604) (xy 445.596772 -103.638858) (xy 445.591194 -103.64595)
			(xy 445.584943 -103.662863) (xy 445.58458 -103.671878) (xy 445.58458 -103.685653) (xy 456.792771 -103.685653)
			(xy 456.792771 -103.631147) (xy 456.800529 -103.577195) (xy 456.815886 -103.524896) (xy 456.838531 -103.475315)
			(xy 456.868001 -103.429462) (xy 456.903697 -103.38827) (xy 456.944893 -103.352578) (xy 456.990749 -103.323112)
			(xy 457.040332 -103.300473) (xy 457.092632 -103.285121) (xy 457.146585 -103.277369) (xy 457.173838 -103.276908)
			(xy 457.200153 -103.277348) (xy 457.252283 -103.284588) (xy 457.302926 -103.298912) (xy 457.351125 -103.32005)
			(xy 457.395968 -103.347601) (xy 457.436606 -103.381044) (xy 457.454762 -103.400098) (xy 457.462296 -103.407484)
			(xy 457.481567 -103.416017) (xy 457.4921 -103.416608) (xy 457.566776 -103.416608) (xy 457.577325 -103.416077)
			(xy 457.596621 -103.407543) (xy 457.604114 -103.400098) (xy 457.623934 -103.37931) (xy 457.668706 -103.343335)
			(xy 457.718364 -103.314475) (xy 457.771786 -103.293382) (xy 457.827765 -103.280533) (xy 457.885038 -103.276218)
			(xy 457.942311 -103.280533) (xy 457.99829 -103.293382) (xy 458.051712 -103.314475) (xy 458.10137 -103.343335)
			(xy 458.146142 -103.37931) (xy 458.165962 -103.400098) (xy 458.173496 -103.407484) (xy 458.192767 -103.416017)
			(xy 458.2033 -103.416608) (xy 458.277976 -103.416608) (xy 458.288525 -103.416077) (xy 458.307821 -103.407543)
			(xy 458.315314 -103.400098) (xy 458.333469 -103.381042) (xy 458.374099 -103.347585) (xy 458.418939 -103.320026)
			(xy 458.46714 -103.298888) (xy 458.517788 -103.284571) (xy 458.569922 -103.277346) (xy 458.596238 -103.276908)
			(xy 458.623489 -103.277364) (xy 458.677434 -103.285126) (xy 458.729727 -103.300485) (xy 458.779301 -103.323129)
			(xy 458.825149 -103.352598) (xy 458.866336 -103.388291) (xy 458.902025 -103.429482) (xy 458.931489 -103.475332)
			(xy 458.954129 -103.524909) (xy 458.969482 -103.577203) (xy 458.977238 -103.631149) (xy 458.977238 -103.685651)
			(xy 458.969482 -103.739597) (xy 458.954129 -103.791891) (xy 458.931489 -103.841468) (xy 458.902025 -103.887319)
			(xy 458.866336 -103.928509) (xy 458.825149 -103.964202) (xy 458.779301 -103.993671) (xy 458.729727 -104.016315)
			(xy 458.677434 -104.031674) (xy 458.623489 -104.039436) (xy 458.596238 -104.039924) (xy 458.569923 -104.03949)
			(xy 458.517793 -104.032247) (xy 458.46715 -104.017921) (xy 458.418952 -103.996782) (xy 458.374109 -103.969231)
			(xy 458.33347 -103.935788) (xy 458.315314 -103.916734) (xy 458.307785 -103.909341) (xy 458.288511 -103.900811)
			(xy 458.277976 -103.900224) (xy 458.2033 -103.900224) (xy 458.192748 -103.900733) (xy 458.173452 -103.909281)
			(xy 458.165962 -103.916734) (xy 458.146142 -103.937522) (xy 458.10137 -103.973497) (xy 458.051712 -104.002357)
			(xy 457.99829 -104.02345) (xy 457.942311 -104.036299) (xy 457.885038 -104.040614) (xy 457.827765 -104.036299)
			(xy 457.771786 -104.02345) (xy 457.718364 -104.002357) (xy 457.668706 -103.973497) (xy 457.623934 -103.937522)
			(xy 457.604114 -103.916734) (xy 457.596585 -103.909341) (xy 457.577311 -103.900811) (xy 457.566776 -103.900224)
			(xy 457.4921 -103.900224) (xy 457.481548 -103.900733) (xy 457.462252 -103.909281) (xy 457.454762 -103.916734)
			(xy 457.436625 -103.935807) (xy 457.39599 -103.969262) (xy 457.351146 -103.996817) (xy 457.302942 -104.017953)
			(xy 457.252291 -104.032266) (xy 457.200155 -104.039487) (xy 457.173838 -104.039924) (xy 457.146585 -104.039431)
			(xy 457.092632 -104.031679) (xy 457.040332 -104.016327) (xy 456.990749 -103.993688) (xy 456.944893 -103.964222)
			(xy 456.903697 -103.92853) (xy 456.868001 -103.887338) (xy 456.838531 -103.841485) (xy 456.815886 -103.791904)
			(xy 456.800529 -103.739605) (xy 456.792771 -103.685653) (xy 445.58458 -103.685653) (xy 445.58458 -103.738934)
			(xy 445.584925 -103.747952) (xy 445.591181 -103.764869) (xy 445.596772 -103.771954) (xy 445.597026 -103.771954)
			(xy 445.597026 -103.772208) (xy 445.614686 -103.793123) (xy 445.644394 -103.839101) (xy 445.667226 -103.888853)
			(xy 445.682712 -103.941357) (xy 445.690535 -103.995536) (xy 445.691006 -104.022906) (xy 445.690528 -104.050157)
			(xy 445.68277 -104.104106) (xy 445.667414 -104.156401) (xy 445.644772 -104.205978) (xy 445.615305 -104.251828)
			(xy 445.579613 -104.293019) (xy 445.538422 -104.32871) (xy 445.492571 -104.358176) (xy 445.442993 -104.380817)
			(xy 445.390698 -104.396172) (xy 445.336749 -104.403928) (xy 445.309498 -104.404414) (xy 445.280579 -104.40393)
			(xy 445.223405 -104.395198) (xy 445.168204 -104.377936) (xy 445.116242 -104.352538) (xy 445.068709 -104.319587)
			(xy 445.026696 -104.279838) (xy 445.008508 -104.257348) (xy 445.000897 -104.248546) (xy 444.979999 -104.238361)
			(xy 444.968376 -104.23779) (xy 444.88862 -104.23779) (xy 444.876992 -104.238359) (xy 444.856082 -104.248527)
			(xy 444.848488 -104.257348) (xy 444.830316 -104.279847) (xy 444.788291 -104.319579) (xy 444.740751 -104.352515)
			(xy 444.688787 -104.3779) (xy 444.633587 -104.395154) (xy 444.576415 -104.40388) (xy 444.547498 -104.404414)
			(xy 444.520247 -104.403924) (xy 444.4663 -104.396167) (xy 444.414005 -104.380812) (xy 444.364429 -104.358171)
			(xy 444.318578 -104.328706) (xy 444.277388 -104.293014) (xy 444.241697 -104.251825) (xy 444.21223 -104.205975)
			(xy 444.189589 -104.156398) (xy 444.174233 -104.104104) (xy 444.166476 -104.050157) (xy 444.16599 -104.022906)
			(xy 439.417168 -104.022906) (xy 439.41619 -104.023922) (xy 439.409078 -104.041956) (xy 439.409078 -104.130856)
			(xy 439.41619 -104.14889) (xy 439.422794 -104.155748) (xy 439.44207 -104.17707) (xy 439.474633 -104.224434)
			(xy 439.499724 -104.276146) (xy 439.516772 -104.331038) (xy 439.525394 -104.387865) (xy 439.525393 -104.445343)
			(xy 439.51677 -104.502171) (xy 439.49972 -104.557062) (xy 439.474629 -104.608774) (xy 439.442064 -104.656137)
			(xy 439.422794 -104.677464) (xy 439.41619 -104.684322) (xy 439.409078 -104.702356) (xy 439.409078 -104.791256)
			(xy 439.41619 -104.80929) (xy 439.422794 -104.816148) (xy 439.44207 -104.83747) (xy 439.474633 -104.884834)
			(xy 439.499724 -104.936546) (xy 439.516772 -104.991438) (xy 439.525394 -105.048265) (xy 439.525393 -105.08445)
			(xy 444.044072 -105.08445) (xy 444.044072 -105.02995) (xy 444.051828 -104.976004) (xy 444.067181 -104.923711)
			(xy 444.089821 -104.874135) (xy 444.119285 -104.828285) (xy 444.154974 -104.787095) (xy 444.196161 -104.751403)
			(xy 444.242008 -104.721935) (xy 444.291582 -104.699292) (xy 444.343874 -104.683934) (xy 444.39782 -104.676174)
			(xy 444.42507 -104.675686) (xy 444.452439 -104.676173) (xy 444.506617 -104.683986) (xy 444.55912 -104.699471)
			(xy 444.608867 -104.722308) (xy 444.654835 -104.752027) (xy 444.675768 -104.769666) (xy 444.676022 -104.76992)
			(xy 444.683096 -104.775524) (xy 444.700023 -104.78176) (xy 444.709042 -104.782112) (xy 444.776098 -104.782112)
			(xy 444.785114 -104.781751) (xy 444.802031 -104.775506) (xy 444.809118 -104.76992) (xy 444.809118 -104.769666)
			(xy 444.809372 -104.769666) (xy 444.830305 -104.752025) (xy 444.876273 -104.722301) (xy 444.926019 -104.699455)
			(xy 444.978521 -104.683959) (xy 445.032699 -104.67613) (xy 445.087441 -104.67613) (xy 445.141619 -104.683959)
			(xy 445.194121 -104.699455) (xy 445.243867 -104.722301) (xy 445.289835 -104.752025) (xy 445.310768 -104.769666)
			(xy 445.311022 -104.76992) (xy 445.318096 -104.775524) (xy 445.335023 -104.78176) (xy 445.344042 -104.782112)
			(xy 445.411098 -104.782112) (xy 445.420114 -104.781751) (xy 445.437031 -104.775506) (xy 445.444118 -104.76992)
			(xy 445.444118 -104.769666) (xy 445.444372 -104.769666) (xy 445.465305 -104.752025) (xy 445.511273 -104.722301)
			(xy 445.561019 -104.699455) (xy 445.613521 -104.683959) (xy 445.667699 -104.67613) (xy 445.722441 -104.67613)
			(xy 445.776619 -104.683959) (xy 445.829121 -104.699455) (xy 445.878867 -104.722301) (xy 445.924835 -104.752025)
			(xy 445.945768 -104.769666) (xy 445.946022 -104.76992) (xy 445.953096 -104.775524) (xy 445.970023 -104.78176)
			(xy 445.979042 -104.782112) (xy 446.046098 -104.782112) (xy 446.055114 -104.781751) (xy 446.072031 -104.775506)
			(xy 446.079118 -104.76992) (xy 446.079118 -104.769666) (xy 446.079372 -104.769666) (xy 446.100299 -104.752021)
			(xy 446.146274 -104.722311) (xy 446.196023 -104.699477) (xy 446.248524 -104.683987) (xy 446.302701 -104.67616)
			(xy 446.33007 -104.675686) (xy 446.357324 -104.676159) (xy 446.411277 -104.683913) (xy 446.463578 -104.699266)
			(xy 446.513161 -104.721906) (xy 446.559017 -104.751373) (xy 446.600213 -104.787066) (xy 446.635909 -104.828259)
			(xy 446.665379 -104.874113) (xy 446.688024 -104.923694) (xy 446.703381 -104.975994) (xy 446.711139 -105.029946)
			(xy 446.711139 -105.084454) (xy 446.703381 -105.138406) (xy 446.688024 -105.190706) (xy 446.665379 -105.240287)
			(xy 446.635909 -105.286141) (xy 446.600213 -105.327334) (xy 446.559017 -105.363027) (xy 446.513161 -105.392494)
			(xy 446.463578 -105.415134) (xy 446.411277 -105.430487) (xy 446.357324 -105.438241) (xy 446.33007 -105.438702)
			(xy 446.302699 -105.438253) (xy 446.248519 -105.430431) (xy 446.196016 -105.414938) (xy 446.14627 -105.392092)
			(xy 446.100303 -105.362365) (xy 446.079372 -105.344722) (xy 446.079118 -105.344468) (xy 446.072033 -105.338879)
			(xy 446.055115 -105.332635) (xy 446.046098 -105.332276) (xy 445.979042 -105.332276) (xy 445.970028 -105.332658)
			(xy 445.953111 -105.338889) (xy 445.946022 -105.344468) (xy 445.945768 -105.344722) (xy 445.924835 -105.362363)
			(xy 445.878867 -105.392087) (xy 445.829121 -105.414933) (xy 445.776619 -105.430429) (xy 445.722441 -105.438258)
			(xy 445.667699 -105.438258) (xy 445.613521 -105.430429) (xy 445.561019 -105.414933) (xy 445.511273 -105.392087)
			(xy 445.465305 -105.362363) (xy 445.444372 -105.344722) (xy 445.444118 -105.344468) (xy 445.437033 -105.338879)
			(xy 445.420115 -105.332635) (xy 445.411098 -105.332276) (xy 445.344042 -105.332276) (xy 445.335028 -105.332658)
			(xy 445.318111 -105.338889) (xy 445.311022 -105.344468) (xy 445.311022 -105.344722) (xy 445.310768 -105.344722)
			(xy 445.289835 -105.362363) (xy 445.243867 -105.392087) (xy 445.194121 -105.414933) (xy 445.141619 -105.430429)
			(xy 445.087441 -105.438258) (xy 445.032699 -105.438258) (xy 444.978521 -105.430429) (xy 444.926019 -105.414933)
			(xy 444.876273 -105.392087) (xy 444.830305 -105.362363) (xy 444.809372 -105.344722) (xy 444.809118 -105.344468)
			(xy 444.802033 -105.338879) (xy 444.785115 -105.332635) (xy 444.776098 -105.332276) (xy 444.709042 -105.332276)
			(xy 444.700028 -105.332658) (xy 444.683111 -105.338889) (xy 444.676022 -105.344468) (xy 444.676022 -105.344722)
			(xy 444.675768 -105.344722) (xy 444.654824 -105.362346) (xy 444.608854 -105.392059) (xy 444.55911 -105.414898)
			(xy 444.506612 -105.430393) (xy 444.452438 -105.438225) (xy 444.42507 -105.438702) (xy 444.39782 -105.438226)
			(xy 444.343874 -105.430466) (xy 444.291582 -105.415108) (xy 444.242008 -105.392465) (xy 444.196161 -105.362997)
			(xy 444.154974 -105.327305) (xy 444.119285 -105.286115) (xy 444.089821 -105.240265) (xy 444.067181 -105.190689)
			(xy 444.051828 -105.138396) (xy 444.044072 -105.08445) (xy 439.525393 -105.08445) (xy 439.525393 -105.105743)
			(xy 439.51677 -105.162571) (xy 439.49972 -105.217462) (xy 439.474629 -105.269174) (xy 439.442064 -105.316537)
			(xy 439.422794 -105.337864) (xy 439.41619 -105.344722) (xy 439.409078 -105.362756) (xy 439.409078 -105.451656)
			(xy 439.41619 -105.46969) (xy 439.422794 -105.476548) (xy 439.44207 -105.49787) (xy 439.474633 -105.545234)
			(xy 439.499724 -105.596946) (xy 439.516772 -105.651838) (xy 439.525394 -105.708665) (xy 439.525393 -105.766143)
			(xy 439.51677 -105.822971) (xy 439.49972 -105.877862) (xy 439.474629 -105.929574) (xy 439.442064 -105.976937)
			(xy 439.422794 -105.998264) (xy 439.41619 -106.005122) (xy 439.409078 -106.023156) (xy 439.409078 -106.112056)
			(xy 439.41619 -106.13009) (xy 439.422794 -106.136948) (xy 439.44207 -106.15827) (xy 439.474633 -106.205634)
			(xy 439.499724 -106.257346) (xy 439.516772 -106.312238) (xy 439.525394 -106.369065) (xy 439.525393 -106.426543)
			(xy 439.51677 -106.483371) (xy 439.49972 -106.538262) (xy 439.474629 -106.589974) (xy 439.442064 -106.637337)
			(xy 439.422794 -106.658664) (xy 439.41619 -106.665522) (xy 439.409078 -106.683556) (xy 439.409078 -106.772456)
			(xy 439.41619 -106.79049) (xy 439.422794 -106.797348) (xy 439.427403 -106.802446) (xy 456.721028 -106.802446)
			(xy 456.721028 -106.747954) (xy 456.728782 -106.694018) (xy 456.744133 -106.641733) (xy 456.766768 -106.592166)
			(xy 456.796226 -106.546323) (xy 456.831909 -106.50514) (xy 456.873088 -106.469453) (xy 456.918927 -106.439989)
			(xy 456.968492 -106.417349) (xy 457.020775 -106.401992) (xy 457.07471 -106.394231) (xy 457.101956 -106.393742)
			(xy 457.128272 -106.394159) (xy 457.180403 -106.401402) (xy 457.231047 -106.41573) (xy 457.279246 -106.436872)
			(xy 457.324089 -106.464428) (xy 457.364725 -106.497876) (xy 457.38288 -106.516932) (xy 457.390416 -106.524317)
			(xy 457.409685 -106.532853) (xy 457.420218 -106.533442) (xy 457.494894 -106.533442) (xy 457.505443 -106.532911)
			(xy 457.524738 -106.524376) (xy 457.532232 -106.516932) (xy 457.552052 -106.496144) (xy 457.596824 -106.460169)
			(xy 457.646482 -106.431309) (xy 457.699904 -106.410216) (xy 457.755883 -106.397367) (xy 457.813156 -106.393052)
			(xy 457.870429 -106.397367) (xy 457.926408 -106.410216) (xy 457.97983 -106.431309) (xy 458.029488 -106.460169)
			(xy 458.07426 -106.496144) (xy 458.09408 -106.516932) (xy 458.101616 -106.524317) (xy 458.120885 -106.532853)
			(xy 458.131418 -106.533442) (xy 458.206094 -106.533442) (xy 458.216643 -106.532911) (xy 458.235938 -106.524376)
			(xy 458.243432 -106.516932) (xy 458.261585 -106.497874) (xy 458.302215 -106.464416) (xy 458.347055 -106.436856)
			(xy 458.395257 -106.415718) (xy 458.445905 -106.401402) (xy 458.49804 -106.394179) (xy 458.524356 -106.393742)
			(xy 458.551614 -106.394102) (xy 458.605577 -106.401855) (xy 458.657887 -106.417209) (xy 458.70748 -106.439852)
			(xy 458.753344 -106.469323) (xy 458.794548 -106.505021) (xy 458.830251 -106.54622) (xy 458.859727 -106.592082)
			(xy 458.882375 -106.641671) (xy 458.897736 -106.69398) (xy 458.905495 -106.747942) (xy 458.905495 -106.802458)
			(xy 458.897736 -106.85642) (xy 458.882375 -106.908729) (xy 458.859727 -106.958318) (xy 458.830251 -107.00418)
			(xy 458.794548 -107.045379) (xy 458.753344 -107.081077) (xy 458.70748 -107.110548) (xy 458.657887 -107.133191)
			(xy 458.605577 -107.148545) (xy 458.551615 -107.156298) (xy 458.524356 -107.156758) (xy 458.49804 -107.156333)
			(xy 458.44591 -107.149092) (xy 458.395265 -107.134765) (xy 458.347066 -107.113625) (xy 458.302224 -107.08607)
			(xy 458.261587 -107.052624) (xy 458.243432 -107.033568) (xy 458.235891 -107.026188) (xy 458.216626 -107.017649)
			(xy 458.206094 -107.017058) (xy 458.131418 -107.017058) (xy 458.12087 -107.017596) (xy 458.101575 -107.026126)
			(xy 458.09408 -107.033568) (xy 458.07426 -107.054356) (xy 458.029488 -107.090331) (xy 457.97983 -107.119191)
			(xy 457.926408 -107.140284) (xy 457.870429 -107.153133) (xy 457.813156 -107.157448) (xy 457.755883 -107.153133)
			(xy 457.699904 -107.140284) (xy 457.646482 -107.119191) (xy 457.596824 -107.090331) (xy 457.552052 -107.054356)
			(xy 457.532232 -107.033568) (xy 457.524691 -107.026188) (xy 457.505426 -107.017649) (xy 457.494894 -107.017058)
			(xy 457.420218 -107.017058) (xy 457.40967 -107.017596) (xy 457.390375 -107.026126) (xy 457.38288 -107.033568)
			(xy 457.364721 -107.05262) (xy 457.324093 -107.086079) (xy 457.279253 -107.113639) (xy 457.231053 -107.134778)
			(xy 457.180406 -107.149096) (xy 457.128272 -107.15632) (xy 457.101956 -107.156758) (xy 457.07471 -107.156169)
			(xy 457.020775 -107.148408) (xy 456.968492 -107.133051) (xy 456.918927 -107.110411) (xy 456.873088 -107.080947)
			(xy 456.831909 -107.04526) (xy 456.796226 -107.004077) (xy 456.766768 -106.958234) (xy 456.744133 -106.908667)
			(xy 456.728782 -106.856382) (xy 456.721028 -106.802446) (xy 439.427403 -106.802446) (xy 439.44207 -106.81867)
			(xy 439.474633 -106.866034) (xy 439.499724 -106.917746) (xy 439.516772 -106.972638) (xy 439.525394 -107.029465)
			(xy 439.525393 -107.086943) (xy 439.51677 -107.143771) (xy 439.49972 -107.198662) (xy 439.474629 -107.250374)
			(xy 439.442064 -107.297737) (xy 439.422794 -107.319064) (xy 439.41619 -107.325922) (xy 439.409078 -107.343956)
			(xy 439.409078 -107.432856) (xy 439.41619 -107.45089) (xy 439.422794 -107.457748) (xy 439.44207 -107.47907)
			(xy 439.474633 -107.526434) (xy 439.499724 -107.578146) (xy 439.516772 -107.633038) (xy 439.525394 -107.689865)
			(xy 439.525393 -107.740249) (xy 443.984396 -107.740249) (xy 443.984396 -107.685751) (xy 443.992152 -107.631808)
			(xy 444.007505 -107.579517) (xy 444.030144 -107.529944) (xy 444.059607 -107.484096) (xy 444.095294 -107.442909)
			(xy 444.13648 -107.407219) (xy 444.182326 -107.377753) (xy 444.231898 -107.355112) (xy 444.284188 -107.339756)
			(xy 444.338131 -107.331998) (xy 444.36538 -107.33151) (xy 444.39275 -107.331985) (xy 444.446929 -107.339801)
			(xy 444.499432 -107.355287) (xy 444.549179 -107.378127) (xy 444.595146 -107.40785) (xy 444.616078 -107.42549)
			(xy 444.616332 -107.425744) (xy 444.62343 -107.431314) (xy 444.640338 -107.437569) (xy 444.649352 -107.437936)
			(xy 444.716408 -107.437936) (xy 444.725424 -107.437575) (xy 444.742341 -107.43133) (xy 444.749428 -107.425744)
			(xy 444.749428 -107.42549) (xy 444.749682 -107.42549) (xy 444.770615 -107.407849) (xy 444.816583 -107.378125)
			(xy 444.866329 -107.355279) (xy 444.918831 -107.339783) (xy 444.973009 -107.331954) (xy 445.027751 -107.331954)
			(xy 445.081929 -107.339783) (xy 445.134431 -107.355279) (xy 445.184177 -107.378125) (xy 445.230145 -107.407849)
			(xy 445.251078 -107.42549) (xy 445.251332 -107.425744) (xy 445.25843 -107.431314) (xy 445.275338 -107.437569)
			(xy 445.284352 -107.437936) (xy 445.351408 -107.437936) (xy 445.360424 -107.437575) (xy 445.377341 -107.43133)
			(xy 445.384428 -107.425744) (xy 445.384428 -107.42549) (xy 445.384682 -107.42549) (xy 445.405615 -107.407849)
			(xy 445.451583 -107.378125) (xy 445.501329 -107.355279) (xy 445.553831 -107.339783) (xy 445.608009 -107.331954)
			(xy 445.662751 -107.331954) (xy 445.716929 -107.339783) (xy 445.769431 -107.355279) (xy 445.819177 -107.378125)
			(xy 445.865145 -107.407849) (xy 445.886078 -107.42549) (xy 445.886332 -107.425744) (xy 445.89343 -107.431314)
			(xy 445.910338 -107.437569) (xy 445.919352 -107.437936) (xy 445.986408 -107.437936) (xy 445.995424 -107.437575)
			(xy 446.012341 -107.43133) (xy 446.019428 -107.425744) (xy 446.019428 -107.42549) (xy 446.019682 -107.42549)
			(xy 446.040609 -107.407844) (xy 446.086583 -107.378134) (xy 446.136332 -107.355299) (xy 446.188834 -107.33981)
			(xy 446.24301 -107.331983) (xy 446.27038 -107.33151) (xy 446.297635 -107.331936) (xy 446.351591 -107.339691)
			(xy 446.403894 -107.355046) (xy 446.453479 -107.377688) (xy 446.499336 -107.407157) (xy 446.540534 -107.442852)
			(xy 446.576231 -107.484047) (xy 446.605702 -107.529904) (xy 446.628347 -107.579488) (xy 446.643705 -107.63179)
			(xy 446.651463 -107.685745) (xy 446.651463 -107.740255) (xy 446.643705 -107.79421) (xy 446.628347 -107.846512)
			(xy 446.605702 -107.896096) (xy 446.576231 -107.941953) (xy 446.540534 -107.983148) (xy 446.499336 -108.018843)
			(xy 446.453479 -108.048312) (xy 446.403894 -108.070954) (xy 446.351591 -108.086309) (xy 446.297635 -108.094064)
			(xy 446.27038 -108.094526) (xy 446.243008 -108.09409) (xy 446.188827 -108.086267) (xy 446.136323 -108.070772)
			(xy 446.086577 -108.047924) (xy 446.040612 -108.018191) (xy 446.019682 -108.000546) (xy 446.019428 -108.000292)
			(xy 446.012338 -107.99471) (xy 445.995424 -107.988461) (xy 445.986408 -107.9881) (xy 445.919352 -107.9881)
			(xy 445.910338 -107.988482) (xy 445.893421 -107.994712) (xy 445.886332 -108.000292) (xy 445.886078 -108.000546)
			(xy 445.865145 -108.018187) (xy 445.819177 -108.047911) (xy 445.769431 -108.070757) (xy 445.716929 -108.086253)
			(xy 445.662751 -108.094082) (xy 445.608009 -108.094082) (xy 445.553831 -108.086253) (xy 445.501329 -108.070757)
			(xy 445.451583 -108.047911) (xy 445.405615 -108.018187) (xy 445.384682 -108.000546) (xy 445.384428 -108.000292)
			(xy 445.377338 -107.99471) (xy 445.360424 -107.988461) (xy 445.351408 -107.9881) (xy 445.284352 -107.9881)
			(xy 445.275338 -107.988482) (xy 445.258421 -107.994712) (xy 445.251332 -108.000292) (xy 445.251332 -108.000546)
			(xy 445.251078 -108.000546) (xy 445.230145 -108.018187) (xy 445.184177 -108.047911) (xy 445.134431 -108.070757)
			(xy 445.081929 -108.086253) (xy 445.027751 -108.094082) (xy 444.973009 -108.094082) (xy 444.918831 -108.086253)
			(xy 444.866329 -108.070757) (xy 444.816583 -108.047911) (xy 444.770615 -108.018187) (xy 444.749682 -108.000546)
			(xy 444.749428 -108.000292) (xy 444.742338 -107.99471) (xy 444.725424 -107.988461) (xy 444.716408 -107.9881)
			(xy 444.649352 -107.9881) (xy 444.640338 -107.988482) (xy 444.623421 -107.994712) (xy 444.616332 -108.000292)
			(xy 444.616332 -108.000546) (xy 444.616078 -108.000546) (xy 444.59512 -108.018154) (xy 444.549155 -108.047872)
			(xy 444.499415 -108.070715) (xy 444.446919 -108.086213) (xy 444.392748 -108.094048) (xy 444.36538 -108.094526)
			(xy 444.338131 -108.094002) (xy 444.284188 -108.086244) (xy 444.231898 -108.070888) (xy 444.182326 -108.048247)
			(xy 444.13648 -108.018781) (xy 444.095294 -107.983091) (xy 444.059607 -107.941904) (xy 444.030144 -107.896056)
			(xy 444.007505 -107.846483) (xy 443.992152 -107.794192) (xy 443.984396 -107.740249) (xy 439.525393 -107.740249)
			(xy 439.525393 -107.747343) (xy 439.51677 -107.804171) (xy 439.49972 -107.859062) (xy 439.474629 -107.910774)
			(xy 439.442064 -107.958137) (xy 439.422794 -107.979464) (xy 439.41619 -107.986322) (xy 439.409078 -108.004356)
			(xy 439.409078 -108.093256) (xy 439.41619 -108.11129) (xy 439.422794 -108.118148) (xy 439.442056 -108.139483)
			(xy 439.474626 -108.186842) (xy 439.499721 -108.238551) (xy 439.516773 -108.293441) (xy 439.525397 -108.350267)
			(xy 439.525918 -108.379006) (xy 439.525432 -108.406257) (xy 439.517676 -108.460205) (xy 439.502321 -108.5125)
			(xy 439.479679 -108.562077) (xy 439.474905 -108.569506) (xy 455.161142 -108.569506) (xy 455.161601 -108.542135)
			(xy 455.169419 -108.487956) (xy 455.184909 -108.435452) (xy 455.207753 -108.385705) (xy 455.23748 -108.339739)
			(xy 455.255122 -108.318808) (xy 455.255376 -108.318554) (xy 455.260955 -108.311463) (xy 455.267204 -108.294549)
			(xy 455.267568 -108.285534) (xy 455.267568 -108.218478) (xy 455.267229 -108.209459) (xy 455.26097 -108.192542)
			(xy 455.255376 -108.185458) (xy 455.255122 -108.185458) (xy 455.255122 -108.185204) (xy 455.237475 -108.164278)
			(xy 455.207763 -108.118304) (xy 455.184929 -108.068555) (xy 455.16944 -108.016053) (xy 455.161614 -107.961876)
			(xy 455.161142 -107.934506) (xy 455.161628 -107.907255) (xy 455.169384 -107.853307) (xy 455.184739 -107.801012)
			(xy 455.207381 -107.751435) (xy 455.236847 -107.705585) (xy 455.272538 -107.664394) (xy 455.313729 -107.628703)
			(xy 455.359579 -107.599237) (xy 455.409156 -107.576595) (xy 455.461451 -107.56124) (xy 455.515399 -107.553484)
			(xy 455.569901 -107.553484) (xy 455.623849 -107.56124) (xy 455.676144 -107.576595) (xy 455.725721 -107.599237)
			(xy 455.771571 -107.628703) (xy 455.812762 -107.664394) (xy 455.848453 -107.705585) (xy 455.877919 -107.751435)
			(xy 455.900561 -107.801012) (xy 455.915916 -107.853307) (xy 455.923672 -107.907255) (xy 455.924158 -107.934506)
			(xy 455.923706 -107.961877) (xy 455.915886 -108.016057) (xy 455.900394 -108.068561) (xy 455.877549 -108.118307)
			(xy 455.847821 -108.164273) (xy 455.830178 -108.185204) (xy 455.829924 -108.185458) (xy 455.82434 -108.192546)
			(xy 455.818094 -108.209462) (xy 455.817732 -108.218478) (xy 455.817732 -108.285534) (xy 455.818066 -108.294553)
			(xy 455.824329 -108.311471) (xy 455.829924 -108.318554) (xy 455.830178 -108.318554) (xy 455.830178 -108.318808)
			(xy 455.847831 -108.339729) (xy 455.877541 -108.385705) (xy 455.900375 -108.435455) (xy 455.915863 -108.487958)
			(xy 455.923687 -108.542136) (xy 455.924158 -108.569506) (xy 455.923672 -108.596757) (xy 455.915916 -108.650705)
			(xy 455.900561 -108.703) (xy 455.877919 -108.752577) (xy 455.848453 -108.798427) (xy 455.812762 -108.839618)
			(xy 455.771571 -108.875309) (xy 455.725721 -108.904775) (xy 455.676144 -108.927417) (xy 455.623849 -108.942772)
			(xy 455.569901 -108.950528) (xy 455.515399 -108.950528) (xy 455.461451 -108.942772) (xy 455.409156 -108.927417)
			(xy 455.359579 -108.904775) (xy 455.313729 -108.875309) (xy 455.272538 -108.839618) (xy 455.236847 -108.798427)
			(xy 455.207381 -108.752577) (xy 455.184739 -108.703) (xy 455.169384 -108.650705) (xy 455.161628 -108.596757)
			(xy 455.161142 -108.569506) (xy 439.474905 -108.569506) (xy 439.450213 -108.607927) (xy 439.414522 -108.649118)
			(xy 439.373331 -108.684809) (xy 439.327481 -108.714275) (xy 439.277904 -108.736917) (xy 439.225609 -108.752272)
			(xy 439.171661 -108.760028) (xy 439.117159 -108.760028) (xy 439.063211 -108.752272) (xy 439.010916 -108.736917)
			(xy 438.961339 -108.714275) (xy 438.915489 -108.684809) (xy 438.874298 -108.649118) (xy 438.838607 -108.607927)
			(xy 438.809141 -108.562077) (xy 438.786499 -108.5125) (xy 438.771144 -108.460205) (xy 438.763388 -108.406257)
			(xy 438.762902 -108.379006) (xy 430.954458 -108.379006) (xy 430.81487 -109.502448) (xy 457.714602 -109.502448)
			(xy 457.718673 -109.446826) (xy 457.730799 -109.392389) (xy 457.750722 -109.340298) (xy 457.778018 -109.291663)
			(xy 457.812104 -109.24752) (xy 457.852253 -109.208811) (xy 457.897611 -109.17636) (xy 457.947211 -109.150859)
			(xy 457.999995 -109.132852) (xy 458.054838 -109.122722) (xy 458.110572 -109.120685) (xy 458.166009 -109.126785)
			(xy 458.219966 -109.140891) (xy 458.271295 -109.162703) (xy 458.318901 -109.191757) (xy 458.361769 -109.227432)
			(xy 458.398986 -109.268969) (xy 458.429759 -109.315482) (xy 458.453431 -109.365979) (xy 458.469499 -109.419386)
			(xy 458.477619 -109.474562) (xy 458.478128 -109.502448) (xy 458.477619 -109.530334) (xy 458.469499 -109.58551)
			(xy 458.453431 -109.638917) (xy 458.429759 -109.689414) (xy 458.398986 -109.735927) (xy 458.361769 -109.777464)
			(xy 458.318901 -109.813139) (xy 458.271295 -109.842193) (xy 458.219966 -109.864005) (xy 458.166009 -109.878111)
			(xy 458.110572 -109.884211) (xy 458.054838 -109.882174) (xy 457.999995 -109.872044) (xy 457.947211 -109.854037)
			(xy 457.897611 -109.828536) (xy 457.852253 -109.796085) (xy 457.812104 -109.757376) (xy 457.778018 -109.713233)
			(xy 457.750722 -109.664598) (xy 457.730799 -109.612507) (xy 457.718673 -109.55807) (xy 457.714602 -109.502448)
			(xy 430.81487 -109.502448) (xy 430.675819 -110.621572) (xy 438.8612 -110.621572) (xy 438.861649 -110.595257)
			(xy 438.868887 -110.543128) (xy 438.88321 -110.492485) (xy 438.904346 -110.444286) (xy 438.931895 -110.399443)
			(xy 438.965337 -110.358804) (xy 438.98439 -110.340648) (xy 438.991815 -110.333146) (xy 439.000326 -110.313851)
			(xy 439.0009 -110.30331) (xy 439.0009 -110.228634) (xy 439.000366 -110.218085) (xy 438.991834 -110.198789)
			(xy 438.98439 -110.191296) (xy 438.965338 -110.173137) (xy 438.931881 -110.132508) (xy 438.904321 -110.087668)
			(xy 438.883182 -110.039468) (xy 438.868864 -109.988821) (xy 438.861639 -109.936688) (xy 438.8612 -109.910372)
			(xy 438.861686 -109.883121) (xy 438.869442 -109.829173) (xy 438.884797 -109.776878) (xy 438.907439 -109.727301)
			(xy 438.936905 -109.681451) (xy 438.972596 -109.64026) (xy 439.013787 -109.604569) (xy 439.059637 -109.575103)
			(xy 439.109214 -109.552461) (xy 439.161509 -109.537106) (xy 439.215457 -109.52935) (xy 439.269959 -109.52935)
			(xy 439.323907 -109.537106) (xy 439.376202 -109.552461) (xy 439.425779 -109.575103) (xy 439.471629 -109.604569)
			(xy 439.51282 -109.64026) (xy 439.548511 -109.681451) (xy 439.577977 -109.727301) (xy 439.600619 -109.776878)
			(xy 439.615974 -109.829173) (xy 439.62373 -109.883121) (xy 439.624216 -109.910372) (xy 439.623791 -109.936687)
			(xy 439.616547 -109.988818) (xy 439.602219 -110.039461) (xy 439.581079 -110.08766) (xy 439.553525 -110.132502)
			(xy 439.52008 -110.17314) (xy 439.501026 -110.191296) (xy 439.493628 -110.198821) (xy 439.485101 -110.218098)
			(xy 439.484516 -110.228634) (xy 439.484516 -110.30331) (xy 439.485022 -110.313863) (xy 439.493573 -110.333158)
			(xy 439.501026 -110.340648) (xy 439.520103 -110.358782) (xy 439.553557 -110.399417) (xy 439.581113 -110.444262)
			(xy 439.602247 -110.492467) (xy 439.61656 -110.543118) (xy 439.62378 -110.595255) (xy 439.624216 -110.621572)
			(xy 439.62373 -110.648823) (xy 439.615974 -110.702771) (xy 439.600619 -110.755066) (xy 439.577977 -110.804643)
			(xy 439.548511 -110.850493) (xy 439.51282 -110.891684) (xy 439.471629 -110.927375) (xy 439.425779 -110.956841)
			(xy 439.376202 -110.979483) (xy 439.323907 -110.994838) (xy 439.269959 -111.002594) (xy 439.215457 -111.002594)
			(xy 439.161509 -110.994838) (xy 439.109214 -110.979483) (xy 439.059637 -110.956841) (xy 439.013787 -110.927375)
			(xy 438.972596 -110.891684) (xy 438.936905 -110.850493) (xy 438.907439 -110.804643) (xy 438.884797 -110.755066)
			(xy 438.869442 -110.702771) (xy 438.861686 -110.648823) (xy 438.8612 -110.621572) (xy 430.675819 -110.621572)
			(xy 430.467527 -112.297972) (xy 441.369958 -112.297972) (xy 441.370388 -112.271657) (xy 441.377628 -112.219526)
			(xy 441.391953 -112.168882) (xy 441.413093 -112.120682) (xy 441.440646 -112.07584) (xy 441.474093 -112.035203)
			(xy 441.493148 -112.017048) (xy 441.500567 -112.009541) (xy 441.509083 -111.99025) (xy 441.509658 -111.97971)
			(xy 441.509658 -111.905034) (xy 441.509136 -111.894483) (xy 441.500597 -111.875187) (xy 441.493148 -111.867696)
			(xy 441.474088 -111.849546) (xy 441.440633 -111.808914) (xy 441.413076 -111.764072) (xy 441.391939 -111.71587)
			(xy 441.377622 -111.665222) (xy 441.370397 -111.613088) (xy 441.369958 -111.586772) (xy 441.370444 -111.559521)
			(xy 441.3782 -111.505573) (xy 441.393555 -111.453278) (xy 441.416197 -111.403701) (xy 441.445663 -111.357851)
			(xy 441.481354 -111.31666) (xy 441.522545 -111.280969) (xy 441.568395 -111.251503) (xy 441.617972 -111.228861)
			(xy 441.670267 -111.213506) (xy 441.724215 -111.20575) (xy 441.778717 -111.20575) (xy 441.832665 -111.213506)
			(xy 441.88496 -111.228861) (xy 441.934537 -111.251503) (xy 441.980387 -111.280969) (xy 442.021578 -111.31666)
			(xy 442.057269 -111.357851) (xy 442.086735 -111.403701) (xy 442.109377 -111.453278) (xy 442.124732 -111.505573)
			(xy 442.132488 -111.559521) (xy 442.132974 -111.586772) (xy 442.132563 -111.613088) (xy 442.125318 -111.665219)
			(xy 442.110988 -111.715863) (xy 442.089845 -111.764062) (xy 442.062289 -111.808904) (xy 442.02884 -111.849541)
			(xy 442.009784 -111.867696) (xy 442.00238 -111.875215) (xy 441.993857 -111.894497) (xy 441.993274 -111.905034)
			(xy 441.993274 -111.97971) (xy 441.993792 -111.990261) (xy 442.002336 -112.009556) (xy 442.009784 -112.017048)
			(xy 442.028853 -112.03519) (xy 442.062309 -112.075823) (xy 442.089867 -112.120665) (xy 442.111003 -112.168869)
			(xy 442.125317 -112.219519) (xy 442.132538 -112.271655) (xy 442.132974 -112.297972) (xy 443.401958 -112.297972)
			(xy 443.402388 -112.271657) (xy 443.409628 -112.219526) (xy 443.423953 -112.168882) (xy 443.445093 -112.120682)
			(xy 443.472646 -112.07584) (xy 443.506093 -112.035203) (xy 443.525148 -112.017048) (xy 443.532567 -112.009541)
			(xy 443.541083 -111.99025) (xy 443.541658 -111.97971) (xy 443.541658 -111.905034) (xy 443.541136 -111.894483)
			(xy 443.532597 -111.875187) (xy 443.525148 -111.867696) (xy 443.506088 -111.849546) (xy 443.472633 -111.808914)
			(xy 443.445076 -111.764072) (xy 443.423939 -111.71587) (xy 443.409622 -111.665222) (xy 443.402397 -111.613088)
			(xy 443.401958 -111.586772) (xy 443.402444 -111.559521) (xy 443.4102 -111.505573) (xy 443.425555 -111.453278)
			(xy 443.448197 -111.403701) (xy 443.477663 -111.357851) (xy 443.513354 -111.31666) (xy 443.554545 -111.280969)
			(xy 443.600395 -111.251503) (xy 443.649972 -111.228861) (xy 443.702267 -111.213506) (xy 443.756215 -111.20575)
			(xy 443.810717 -111.20575) (xy 443.864665 -111.213506) (xy 443.91696 -111.228861) (xy 443.966537 -111.251503)
			(xy 444.012387 -111.280969) (xy 444.053578 -111.31666) (xy 444.089269 -111.357851) (xy 444.118735 -111.403701)
			(xy 444.141377 -111.453278) (xy 444.156732 -111.505573) (xy 444.164488 -111.559521) (xy 444.164974 -111.586772)
			(xy 444.164563 -111.613088) (xy 444.157318 -111.665219) (xy 444.142988 -111.715863) (xy 444.121845 -111.764062)
			(xy 444.094289 -111.808904) (xy 444.06084 -111.849541) (xy 444.041784 -111.867696) (xy 444.03438 -111.875215)
			(xy 444.025857 -111.894497) (xy 444.025274 -111.905034) (xy 444.025274 -111.97971) (xy 444.025792 -111.990261)
			(xy 444.034336 -112.009556) (xy 444.041784 -112.017048) (xy 444.060853 -112.03519) (xy 444.06285 -112.037615)
			(xy 445.856202 -112.037615) (xy 445.860515 -111.980345) (xy 445.87336 -111.924368) (xy 445.894448 -111.870948)
			(xy 445.923303 -111.821291) (xy 445.959273 -111.776519) (xy 445.980058 -111.756698) (xy 445.987456 -111.749173)
			(xy 445.995984 -111.729896) (xy 445.996568 -111.71936) (xy 445.996568 -111.644684) (xy 445.99607 -111.63413)
			(xy 445.987514 -111.614835) (xy 445.980058 -111.607346) (xy 445.960975 -111.589218) (xy 445.927522 -111.548581)
			(xy 445.899968 -111.503735) (xy 445.878834 -111.455529) (xy 445.864523 -111.404877) (xy 445.857304 -111.35274)
			(xy 445.856868 -111.326422) (xy 445.857354 -111.299171) (xy 445.86511 -111.245223) (xy 445.880465 -111.192928)
			(xy 445.903107 -111.143351) (xy 445.932573 -111.097501) (xy 445.968264 -111.05631) (xy 446.009455 -111.020619)
			(xy 446.055305 -110.991153) (xy 446.104882 -110.968511) (xy 446.157177 -110.953156) (xy 446.211125 -110.9454)
			(xy 446.265627 -110.9454) (xy 446.319575 -110.953156) (xy 446.37187 -110.968511) (xy 446.421447 -110.991153)
			(xy 446.467297 -111.020619) (xy 446.508488 -111.05631) (xy 446.544179 -111.097501) (xy 446.573645 -111.143351)
			(xy 446.596287 -111.192928) (xy 446.611642 -111.245223) (xy 446.619398 -111.299171) (xy 446.619884 -111.326422)
			(xy 446.619436 -111.352737) (xy 446.612198 -111.404866) (xy 446.597876 -111.45551) (xy 446.576739 -111.503709)
			(xy 446.54919 -111.548552) (xy 446.515747 -111.58919) (xy 446.496694 -111.607346) (xy 446.489269 -111.614848)
			(xy 446.480759 -111.634143) (xy 446.480184 -111.644684) (xy 446.480184 -111.71936) (xy 446.480726 -111.729908)
			(xy 446.489253 -111.749203) (xy 446.496694 -111.756698) (xy 446.517505 -111.776495) (xy 446.553482 -111.82127)
			(xy 446.582343 -111.870931) (xy 446.603436 -111.924356) (xy 446.616284 -111.980339) (xy 446.620598 -112.037615)
			(xy 448.394417 -112.037615) (xy 448.39873 -111.980345) (xy 448.411576 -111.924367) (xy 448.432666 -111.870947)
			(xy 448.461522 -111.82129) (xy 448.497494 -111.776518) (xy 448.51828 -111.756698) (xy 448.525682 -111.749176)
			(xy 448.534207 -111.729896) (xy 448.53479 -111.71936) (xy 448.53479 -111.644684) (xy 448.534286 -111.634131)
			(xy 448.525734 -111.614836) (xy 448.51828 -111.607346) (xy 448.499201 -111.589214) (xy 448.465747 -111.548578)
			(xy 448.438192 -111.503733) (xy 448.417057 -111.455528) (xy 448.402745 -111.404877) (xy 448.395526 -111.352739)
			(xy 448.39509 -111.326422) (xy 448.395576 -111.299171) (xy 448.403332 -111.245223) (xy 448.418687 -111.192928)
			(xy 448.441329 -111.143351) (xy 448.470795 -111.097501) (xy 448.506486 -111.05631) (xy 448.547677 -111.020619)
			(xy 448.593527 -110.991153) (xy 448.643104 -110.968511) (xy 448.695399 -110.953156) (xy 448.749347 -110.9454)
			(xy 448.803849 -110.9454) (xy 448.857797 -110.953156) (xy 448.910092 -110.968511) (xy 448.959669 -110.991153)
			(xy 449.005519 -111.020619) (xy 449.04671 -111.05631) (xy 449.082401 -111.097501) (xy 449.111867 -111.143351)
			(xy 449.134509 -111.192928) (xy 449.149864 -111.245223) (xy 449.15762 -111.299171) (xy 449.158106 -111.326422)
			(xy 449.157651 -111.352736) (xy 449.150414 -111.404865) (xy 449.136092 -111.455508) (xy 449.114957 -111.503707)
			(xy 449.087409 -111.54855) (xy 449.053968 -111.58919) (xy 449.034916 -111.607346) (xy 449.027494 -111.614851)
			(xy 449.018981 -111.634143) (xy 449.018406 -111.644684) (xy 449.018406 -111.71936) (xy 449.018941 -111.729909)
			(xy 449.027472 -111.749205) (xy 449.034916 -111.756698) (xy 449.055726 -111.776496) (xy 449.091701 -111.821271)
			(xy 449.12056 -111.870932) (xy 449.141652 -111.924357) (xy 449.154499 -111.98034) (xy 449.155522 -111.993923)
			(xy 452.597351 -111.993923) (xy 452.601664 -111.936653) (xy 452.61451 -111.880675) (xy 452.6356 -111.827255)
			(xy 452.664458 -111.777599) (xy 452.700431 -111.732829) (xy 452.721218 -111.71301) (xy 452.72862 -111.705489)
			(xy 452.737144 -111.686208) (xy 452.737728 -111.675672) (xy 452.737728 -111.600996) (xy 452.737206 -111.590446)
			(xy 452.728665 -111.571151) (xy 452.721218 -111.563658) (xy 452.700462 -111.543805) (xy 452.664484 -111.499039)
			(xy 452.63562 -111.449386) (xy 452.614523 -111.395969) (xy 452.60167 -111.339993) (xy 452.597351 -111.282723)
			(xy 452.601664 -111.225453) (xy 452.61451 -111.169475) (xy 452.6356 -111.116055) (xy 452.664458 -111.066399)
			(xy 452.700431 -111.021629) (xy 452.721218 -111.00181) (xy 452.72862 -110.994289) (xy 452.737144 -110.975008)
			(xy 452.737728 -110.964472) (xy 452.737728 -110.889796) (xy 452.737206 -110.879246) (xy 452.728665 -110.859951)
			(xy 452.721218 -110.852458) (xy 452.702153 -110.834312) (xy 452.668696 -110.793681) (xy 452.641137 -110.748839)
			(xy 452.620001 -110.700636) (xy 452.605686 -110.649986) (xy 452.598464 -110.597851) (xy 452.598028 -110.571534)
			(xy 452.598487 -110.54428) (xy 452.60624 -110.490327) (xy 452.621594 -110.438027) (xy 452.644235 -110.388445)
			(xy 452.673703 -110.34259) (xy 452.709397 -110.301396) (xy 452.750591 -110.265702) (xy 452.796447 -110.236234)
			(xy 452.846029 -110.213593) (xy 452.898329 -110.19824) (xy 452.952282 -110.190487) (xy 452.979536 -110.190026)
			(xy 453.005851 -110.190461) (xy 453.057981 -110.197701) (xy 453.108625 -110.212026) (xy 453.156824 -110.233165)
			(xy 453.201667 -110.260717) (xy 453.242305 -110.294162) (xy 453.26046 -110.313216) (xy 453.267992 -110.320604)
			(xy 453.287264 -110.329136) (xy 453.297798 -110.329726) (xy 453.372474 -110.329726) (xy 453.383022 -110.329188)
			(xy 453.402317 -110.320658) (xy 453.409812 -110.313216) (xy 453.427972 -110.294165) (xy 453.4686 -110.260707)
			(xy 453.51344 -110.233147) (xy 453.56164 -110.212007) (xy 453.612286 -110.197689) (xy 453.66442 -110.190464)
			(xy 453.690736 -110.190026) (xy 453.71799 -110.190444) (xy 453.771942 -110.198207) (xy 453.82424 -110.213568)
			(xy 453.873819 -110.236216) (xy 453.913439 -110.261683) (xy 455.214548 -110.261683) (xy 455.214548 -110.209717)
			(xy 455.222677 -110.158392) (xy 455.238734 -110.10897) (xy 455.262325 -110.062668) (xy 455.292869 -110.020627)
			(xy 455.329613 -109.983881) (xy 455.371653 -109.953335) (xy 455.417953 -109.929741) (xy 455.467374 -109.913681)
			(xy 455.518699 -109.905549) (xy 455.544682 -109.905038) (xy 455.571328 -109.905497) (xy 455.623931 -109.914033)
			(xy 455.674482 -109.930904) (xy 455.721668 -109.955672) (xy 455.764266 -109.987694) (xy 455.80117 -110.026139)
			(xy 455.816716 -110.047786) (xy 455.82508 -110.059072) (xy 455.846753 -110.076927) (xy 455.872467 -110.08821)
			(xy 455.900282 -110.092068) (xy 455.928097 -110.08821) (xy 455.953811 -110.076927) (xy 455.975484 -110.059072)
			(xy 455.983848 -110.047786) (xy 455.999412 -110.026159) (xy 456.036331 -109.987743) (xy 456.078931 -109.955744)
			(xy 456.126112 -109.930989) (xy 456.176652 -109.914121) (xy 456.229242 -109.905575) (xy 456.255882 -109.905038)
			(xy 456.281876 -109.905428) (xy 456.333224 -109.913558) (xy 456.382667 -109.929621) (xy 456.42899 -109.953221)
			(xy 456.471049 -109.983777) (xy 456.507811 -110.020537) (xy 456.53837 -110.062595) (xy 456.561972 -110.108916)
			(xy 456.578038 -110.158359) (xy 456.586171 -110.209706) (xy 456.586171 -110.261694) (xy 456.578038 -110.313041)
			(xy 456.561972 -110.362484) (xy 456.53837 -110.408805) (xy 456.507811 -110.450863) (xy 456.471049 -110.487623)
			(xy 456.432466 -110.515654) (xy 459.128112 -110.515654) (xy 459.132183 -110.460032) (xy 459.144309 -110.405595)
			(xy 459.164232 -110.353504) (xy 459.191528 -110.304869) (xy 459.225614 -110.260726) (xy 459.265763 -110.222017)
			(xy 459.311121 -110.189566) (xy 459.360721 -110.164065) (xy 459.413505 -110.146058) (xy 459.468348 -110.135928)
			(xy 459.524082 -110.133891) (xy 459.579519 -110.139991) (xy 459.633476 -110.154097) (xy 459.684805 -110.175909)
			(xy 459.732411 -110.204963) (xy 459.775279 -110.240638) (xy 459.812496 -110.282175) (xy 459.843269 -110.328688)
			(xy 459.866941 -110.379185) (xy 459.883009 -110.432592) (xy 459.891129 -110.487768) (xy 459.891638 -110.515654)
			(xy 459.891129 -110.54354) (xy 459.883009 -110.598716) (xy 459.866941 -110.652123) (xy 459.843269 -110.70262)
			(xy 459.812496 -110.749133) (xy 459.775279 -110.79067) (xy 459.732411 -110.826345) (xy 459.684805 -110.855399)
			(xy 459.633476 -110.877211) (xy 459.579519 -110.891317) (xy 459.524082 -110.897417) (xy 459.468348 -110.89538)
			(xy 459.413505 -110.88525) (xy 459.360721 -110.867243) (xy 459.311121 -110.841742) (xy 459.265763 -110.809291)
			(xy 459.225614 -110.770582) (xy 459.191528 -110.726439) (xy 459.164232 -110.677804) (xy 459.144309 -110.625713)
			(xy 459.132183 -110.571276) (xy 459.128112 -110.515654) (xy 456.432466 -110.515654) (xy 456.42899 -110.518179)
			(xy 456.382667 -110.541779) (xy 456.333224 -110.557842) (xy 456.281876 -110.565972) (xy 456.255882 -110.566454)
			(xy 456.229238 -110.565951) (xy 456.176636 -110.557424) (xy 456.126087 -110.540563) (xy 456.0789 -110.515803)
			(xy 456.036301 -110.483789) (xy 455.999395 -110.44535) (xy 455.983848 -110.423706) (xy 455.975484 -110.41242)
			(xy 455.953811 -110.394565) (xy 455.928097 -110.383282) (xy 455.900282 -110.379424) (xy 455.872467 -110.383282)
			(xy 455.846753 -110.394565) (xy 455.82508 -110.41242) (xy 455.816716 -110.423706) (xy 455.80111 -110.445301)
			(xy 455.7642 -110.483719) (xy 455.721608 -110.515722) (xy 455.674436 -110.540482) (xy 455.623904 -110.557357)
			(xy 455.57132 -110.565912) (xy 455.544682 -110.566454) (xy 455.518699 -110.565851) (xy 455.467374 -110.557719)
			(xy 455.417953 -110.541659) (xy 455.371653 -110.518065) (xy 455.329613 -110.487519) (xy 455.292869 -110.450773)
			(xy 455.262325 -110.408732) (xy 455.238734 -110.36243) (xy 455.222677 -110.313008) (xy 455.214548 -110.261683)
			(xy 453.913439 -110.261683) (xy 453.919671 -110.265689) (xy 453.960862 -110.301388) (xy 453.996553 -110.342585)
			(xy 454.026018 -110.388442) (xy 454.048656 -110.438026) (xy 454.064008 -110.490327) (xy 454.071761 -110.54428)
			(xy 454.072244 -110.571534) (xy 454.071817 -110.59785) (xy 454.064577 -110.649981) (xy 454.050251 -110.700625)
			(xy 454.029111 -110.748824) (xy 454.001557 -110.793666) (xy 453.96811 -110.834303) (xy 453.949054 -110.852458)
			(xy 453.941677 -110.860001) (xy 453.933137 -110.879264) (xy 453.932544 -110.889796) (xy 453.932544 -110.964472)
			(xy 453.933062 -110.975023) (xy 453.941604 -110.994319) (xy 453.949054 -111.00181) (xy 453.969874 -111.021597)
			(xy 454.005846 -111.066375) (xy 454.034702 -111.116038) (xy 454.052798 -111.161885) (xy 455.214523 -111.161885)
			(xy 455.214523 -111.109915) (xy 455.222653 -111.058586) (xy 455.238712 -111.00916) (xy 455.262304 -110.962855)
			(xy 455.29285 -110.920811) (xy 455.329597 -110.884062) (xy 455.37164 -110.853514) (xy 455.417944 -110.829919)
			(xy 455.467369 -110.813857) (xy 455.518697 -110.805725) (xy 455.544682 -110.805214) (xy 455.571327 -110.805683)
			(xy 455.62393 -110.814219) (xy 455.674479 -110.831089) (xy 455.721665 -110.855854) (xy 455.764264 -110.887874)
			(xy 455.801169 -110.926316) (xy 455.816716 -110.947962) (xy 455.82508 -110.959248) (xy 455.846753 -110.977103)
			(xy 455.872467 -110.988386) (xy 455.900282 -110.992244) (xy 455.928097 -110.988386) (xy 455.953811 -110.977103)
			(xy 455.975484 -110.959248) (xy 455.983848 -110.947962) (xy 455.999405 -110.92633) (xy 456.036326 -110.887915)
			(xy 456.078928 -110.855917) (xy 456.12611 -110.831164) (xy 456.176651 -110.814296) (xy 456.229242 -110.805751)
			(xy 456.255882 -110.805214) (xy 456.281874 -110.805652) (xy 456.333218 -110.813781) (xy 456.382658 -110.829843)
			(xy 456.428977 -110.853441) (xy 456.471034 -110.883995) (xy 456.507793 -110.920752) (xy 456.538349 -110.962808)
			(xy 456.56195 -111.009125) (xy 456.578014 -111.058564) (xy 456.586147 -111.109908) (xy 456.586147 -111.161892)
			(xy 456.578014 -111.213236) (xy 456.56195 -111.262675) (xy 456.538349 -111.308992) (xy 456.507793 -111.351048)
			(xy 456.471034 -111.387805) (xy 456.428977 -111.418359) (xy 456.382658 -111.441957) (xy 456.333218 -111.458019)
			(xy 456.281874 -111.466148) (xy 456.255882 -111.46663) (xy 456.229237 -111.466138) (xy 456.176635 -111.45761)
			(xy 456.126084 -111.440747) (xy 456.078897 -111.415985) (xy 456.036299 -111.383969) (xy 455.999394 -111.345527)
			(xy 455.983848 -111.323882) (xy 455.975484 -111.312596) (xy 455.953811 -111.294741) (xy 455.928097 -111.283458)
			(xy 455.900282 -111.2796) (xy 455.872467 -111.283458) (xy 455.846753 -111.294741) (xy 455.82508 -111.312596)
			(xy 455.816716 -111.323882) (xy 455.801133 -111.345494) (xy 455.764215 -111.383907) (xy 455.721618 -111.415906)
			(xy 455.674441 -111.440662) (xy 455.623907 -111.457535) (xy 455.571321 -111.466089) (xy 455.544682 -111.46663)
			(xy 455.518697 -111.466075) (xy 455.467369 -111.457943) (xy 455.417944 -111.441881) (xy 455.37164 -111.418286)
			(xy 455.329597 -111.387738) (xy 455.29285 -111.350989) (xy 455.262304 -111.308945) (xy 455.238712 -111.26264)
			(xy 455.222653 -111.213214) (xy 455.214523 -111.161885) (xy 454.052798 -111.161885) (xy 454.05579 -111.169465)
			(xy 454.068636 -111.225447) (xy 454.072947 -111.282723) (xy 454.068629 -111.339998) (xy 454.055777 -111.395979)
			(xy 454.034681 -111.449403) (xy 454.00582 -111.499063) (xy 453.969843 -111.543837) (xy 453.949054 -111.563658)
			(xy 453.941677 -111.571201) (xy 453.933137 -111.590464) (xy 453.932544 -111.600996) (xy 453.932544 -111.675672)
			(xy 453.933062 -111.686223) (xy 453.941604 -111.705519) (xy 453.949054 -111.71301) (xy 453.969874 -111.732797)
			(xy 454.005846 -111.777575) (xy 454.034702 -111.827238) (xy 454.05579 -111.880665) (xy 454.068636 -111.936647)
			(xy 454.072947 -111.993923) (xy 454.068629 -112.051198) (xy 454.066199 -112.061783) (xy 455.214546 -112.061783)
			(xy 455.214546 -112.009817) (xy 455.222675 -111.958491) (xy 455.238732 -111.909069) (xy 455.262324 -111.862767)
			(xy 455.292867 -111.820725) (xy 455.329612 -111.783979) (xy 455.371652 -111.753433) (xy 455.417952 -111.729839)
			(xy 455.467374 -111.713779) (xy 455.518699 -111.705647) (xy 455.544682 -111.705136) (xy 455.571328 -111.705595)
			(xy 455.623931 -111.714132) (xy 455.674481 -111.731003) (xy 455.721668 -111.755771) (xy 455.764266 -111.787792)
			(xy 455.80117 -111.826237) (xy 455.816716 -111.847884) (xy 455.82508 -111.85917) (xy 455.846753 -111.877025)
			(xy 455.872467 -111.888308) (xy 455.900282 -111.892166) (xy 455.928097 -111.888308) (xy 455.953811 -111.877025)
			(xy 455.975484 -111.85917) (xy 455.983848 -111.847884) (xy 455.999411 -111.826257) (xy 456.03633 -111.787841)
			(xy 456.078931 -111.755841) (xy 456.126112 -111.731087) (xy 456.176651 -111.714219) (xy 456.229242 -111.705673)
			(xy 456.255882 -111.705136) (xy 456.281876 -111.70553) (xy 456.333223 -111.71366) (xy 456.382667 -111.729723)
			(xy 456.428989 -111.753323) (xy 456.471048 -111.783879) (xy 456.472823 -111.785654) (xy 457.757782 -111.785654)
			(xy 457.761853 -111.730032) (xy 457.773979 -111.675595) (xy 457.793902 -111.623504) (xy 457.821198 -111.574869)
			(xy 457.855284 -111.530726) (xy 457.895433 -111.492017) (xy 457.940791 -111.459566) (xy 457.990391 -111.434065)
			(xy 458.043175 -111.416058) (xy 458.098018 -111.405928) (xy 458.153752 -111.403891) (xy 458.209189 -111.409991)
			(xy 458.263146 -111.424097) (xy 458.314475 -111.445909) (xy 458.362081 -111.474963) (xy 458.404949 -111.510638)
			(xy 458.442166 -111.552175) (xy 458.472939 -111.598688) (xy 458.496611 -111.649185) (xy 458.512679 -111.702592)
			(xy 458.520799 -111.757768) (xy 458.521308 -111.785654) (xy 458.520799 -111.81354) (xy 458.512679 -111.868716)
			(xy 458.496611 -111.922123) (xy 458.472939 -111.97262) (xy 458.442166 -112.019133) (xy 458.404949 -112.06067)
			(xy 458.362081 -112.096345) (xy 458.314475 -112.125399) (xy 458.263146 -112.147211) (xy 458.209189 -112.161317)
			(xy 458.153752 -112.167417) (xy 458.098018 -112.16538) (xy 458.043175 -112.15525) (xy 457.990391 -112.137243)
			(xy 457.940791 -112.111742) (xy 457.895433 -112.079291) (xy 457.855284 -112.040582) (xy 457.821198 -111.996439)
			(xy 457.793902 -111.947804) (xy 457.773979 -111.895713) (xy 457.761853 -111.841276) (xy 457.757782 -111.785654)
			(xy 456.472823 -111.785654) (xy 456.50781 -111.820638) (xy 456.538368 -111.862696) (xy 456.56197 -111.909017)
			(xy 456.578036 -111.958459) (xy 456.586169 -112.009806) (xy 456.586169 -112.061794) (xy 456.578036 -112.113141)
			(xy 456.56197 -112.162583) (xy 456.538368 -112.208904) (xy 456.50781 -112.250962) (xy 456.471048 -112.287721)
			(xy 456.458336 -112.296956) (xy 459.194914 -112.296956) (xy 459.198985 -112.241334) (xy 459.211111 -112.186897)
			(xy 459.231034 -112.134806) (xy 459.25833 -112.086171) (xy 459.292416 -112.042028) (xy 459.332565 -112.003319)
			(xy 459.377923 -111.970868) (xy 459.427523 -111.945367) (xy 459.480307 -111.92736) (xy 459.53515 -111.91723)
			(xy 459.590884 -111.915193) (xy 459.646321 -111.921293) (xy 459.700278 -111.935399) (xy 459.751607 -111.957211)
			(xy 459.799213 -111.986265) (xy 459.842081 -112.02194) (xy 459.879298 -112.063477) (xy 459.910071 -112.10999)
			(xy 459.933743 -112.160487) (xy 459.949811 -112.213894) (xy 459.957931 -112.26907) (xy 459.95844 -112.296956)
			(xy 459.957931 -112.324842) (xy 459.949811 -112.380018) (xy 459.933743 -112.433425) (xy 459.910071 -112.483922)
			(xy 459.879298 -112.530435) (xy 459.842081 -112.571972) (xy 459.799213 -112.607647) (xy 459.751607 -112.636701)
			(xy 459.700278 -112.658513) (xy 459.646321 -112.672619) (xy 459.590884 -112.678719) (xy 459.53515 -112.676682)
			(xy 459.480307 -112.666552) (xy 459.427523 -112.648545) (xy 459.377923 -112.623044) (xy 459.332565 -112.590593)
			(xy 459.292416 -112.551884) (xy 459.25833 -112.507741) (xy 459.231034 -112.459106) (xy 459.211111 -112.407015)
			(xy 459.198985 -112.352578) (xy 459.194914 -112.296956) (xy 456.458336 -112.296956) (xy 456.428989 -112.318277)
			(xy 456.382667 -112.341877) (xy 456.333223 -112.35794) (xy 456.281876 -112.36607) (xy 456.255882 -112.366552)
			(xy 456.229238 -112.36605) (xy 456.176636 -112.357523) (xy 456.126086 -112.340661) (xy 456.0789 -112.315902)
			(xy 456.036301 -112.283887) (xy 455.999395 -112.245448) (xy 455.983848 -112.223804) (xy 455.975484 -112.212518)
			(xy 455.953811 -112.194663) (xy 455.928097 -112.18338) (xy 455.900282 -112.179522) (xy 455.872467 -112.18338)
			(xy 455.846753 -112.194663) (xy 455.82508 -112.212518) (xy 455.816716 -112.223804) (xy 455.801109 -112.245399)
			(xy 455.7642 -112.283817) (xy 455.721608 -112.31582) (xy 455.674436 -112.340579) (xy 455.623904 -112.357455)
			(xy 455.57132 -112.36601) (xy 455.544682 -112.366552) (xy 455.518699 -112.365953) (xy 455.467374 -112.357821)
			(xy 455.417952 -112.341761) (xy 455.371652 -112.318167) (xy 455.329612 -112.287621) (xy 455.292867 -112.250875)
			(xy 455.262324 -112.208833) (xy 455.238732 -112.162531) (xy 455.222675 -112.113109) (xy 455.214546 -112.061783)
			(xy 454.066199 -112.061783) (xy 454.055777 -112.107179) (xy 454.034681 -112.160603) (xy 454.00582 -112.210263)
			(xy 453.969843 -112.255037) (xy 453.949054 -112.274858) (xy 453.941677 -112.282401) (xy 453.933137 -112.301664)
			(xy 453.932544 -112.312196) (xy 453.932544 -112.386872) (xy 453.933062 -112.397423) (xy 453.941604 -112.416719)
			(xy 453.949054 -112.42421) (xy 453.968118 -112.442357) (xy 454.001572 -112.48299) (xy 454.029129 -112.527832)
			(xy 454.050265 -112.576034) (xy 454.064581 -112.626683) (xy 454.071806 -112.678818) (xy 454.072244 -112.705134)
			(xy 454.071754 -112.732384) (xy 454.063994 -112.78633) (xy 454.048636 -112.838623) (xy 454.025994 -112.888198)
			(xy 453.996527 -112.934046) (xy 453.972487 -112.961789) (xy 455.214468 -112.961789) (xy 455.214468 -112.909811)
			(xy 455.222598 -112.858473) (xy 455.23866 -112.809039) (xy 455.262257 -112.762726) (xy 455.292808 -112.720674)
			(xy 455.329561 -112.683919) (xy 455.371611 -112.653366) (xy 455.417922 -112.629767) (xy 455.467356 -112.613703)
			(xy 455.518693 -112.605569) (xy 455.544682 -112.605058) (xy 455.571328 -112.605508) (xy 455.623932 -112.614045)
			(xy 455.674484 -112.630917) (xy 455.72167 -112.655687) (xy 455.764268 -112.687711) (xy 455.801171 -112.726158)
			(xy 455.816716 -112.747806) (xy 455.82508 -112.759092) (xy 455.846753 -112.776947) (xy 455.872467 -112.78823)
			(xy 455.900282 -112.792088) (xy 455.928097 -112.78823) (xy 455.953811 -112.776947) (xy 455.975484 -112.759092)
			(xy 455.983848 -112.747806) (xy 455.999388 -112.726162) (xy 456.036315 -112.68775) (xy 456.078921 -112.655755)
			(xy 456.126106 -112.631005) (xy 456.176648 -112.614139) (xy 456.229241 -112.605594) (xy 456.255882 -112.605058)
			(xy 456.28187 -112.605608) (xy 456.333205 -112.613736) (xy 456.382637 -112.629795) (xy 456.428948 -112.653389)
			(xy 456.470997 -112.683938) (xy 456.50775 -112.720689) (xy 456.538301 -112.762737) (xy 456.561898 -112.809046)
			(xy 456.57796 -112.858477) (xy 456.586091 -112.909813) (xy 456.586091 -112.961787) (xy 456.57796 -113.013123)
			(xy 456.561898 -113.062554) (xy 456.538301 -113.108863) (xy 456.50775 -113.150911) (xy 456.470997 -113.187662)
			(xy 456.428948 -113.218211) (xy 456.382637 -113.241805) (xy 456.333205 -113.257864) (xy 456.28187 -113.265992)
			(xy 456.255882 -113.266474) (xy 456.229238 -113.265963) (xy 456.176638 -113.257436) (xy 456.126088 -113.240576)
			(xy 456.078902 -113.215818) (xy 456.036303 -113.183805) (xy 455.999395 -113.145369) (xy 455.983848 -113.123726)
			(xy 455.975484 -113.11244) (xy 455.953811 -113.094585) (xy 455.928097 -113.083302) (xy 455.900282 -113.079444)
			(xy 455.872467 -113.083302) (xy 455.846753 -113.094585) (xy 455.82508 -113.11244) (xy 455.816716 -113.123726)
			(xy 455.801116 -113.145325) (xy 455.764204 -113.183742) (xy 455.721611 -113.215744) (xy 455.674437 -113.240503)
			(xy 455.623904 -113.257378) (xy 455.57132 -113.265932) (xy 455.544682 -113.266474) (xy 455.518693 -113.266031)
			(xy 455.467356 -113.257897) (xy 455.417922 -113.241833) (xy 455.371611 -113.218234) (xy 455.329561 -113.187681)
			(xy 455.292808 -113.150926) (xy 455.262257 -113.108874) (xy 455.23866 -113.062561) (xy 455.222598 -113.013127)
			(xy 455.214468 -112.961789) (xy 453.972487 -112.961789) (xy 453.960836 -112.975235) (xy 453.919648 -113.010926)
			(xy 453.873799 -113.040393) (xy 453.824224 -113.063035) (xy 453.771932 -113.078393) (xy 453.717986 -113.086154)
			(xy 453.690736 -113.086642) (xy 453.66442 -113.086236) (xy 453.612288 -113.078991) (xy 453.561643 -113.064661)
			(xy 453.513444 -113.043517) (xy 453.468602 -113.01596) (xy 453.427966 -112.982509) (xy 453.409812 -112.963452)
			(xy 453.402281 -112.956061) (xy 453.383008 -112.947529) (xy 453.372474 -112.946942) (xy 453.297798 -112.946942)
			(xy 453.287245 -112.947444) (xy 453.267949 -112.955997) (xy 453.26046 -112.963452) (xy 453.242327 -112.98253)
			(xy 453.201691 -113.015983) (xy 453.156846 -113.043538) (xy 453.108641 -113.064672) (xy 453.05799 -113.078985)
			(xy 453.005853 -113.086206) (xy 452.979536 -113.086642) (xy 452.952286 -113.086111) (xy 452.898339 -113.07836)
			(xy 452.846044 -113.06301) (xy 452.796467 -113.040375) (xy 452.750615 -113.010913) (xy 452.709423 -112.975227)
			(xy 452.673729 -112.934041) (xy 452.644259 -112.888195) (xy 452.621614 -112.838621) (xy 452.606255 -112.78633)
			(xy 452.598494 -112.732384) (xy 452.598028 -112.705134) (xy 452.598442 -112.678818) (xy 452.605687 -112.626687)
			(xy 452.620016 -112.576043) (xy 452.641158 -112.527844) (xy 452.668714 -112.483002) (xy 452.702162 -112.442365)
			(xy 452.721218 -112.42421) (xy 452.72862 -112.416689) (xy 452.737144 -112.397408) (xy 452.737728 -112.386872)
			(xy 452.737728 -112.312196) (xy 452.737206 -112.301646) (xy 452.728665 -112.282351) (xy 452.721218 -112.274858)
			(xy 452.700462 -112.255005) (xy 452.664484 -112.210239) (xy 452.63562 -112.160586) (xy 452.614523 -112.107169)
			(xy 452.60167 -112.051193) (xy 452.597351 -111.993923) (xy 449.155522 -111.993923) (xy 449.158813 -112.037615)
			(xy 449.154495 -112.09489) (xy 449.141643 -112.150871) (xy 449.120547 -112.204294) (xy 449.091684 -112.253953)
			(xy 449.055706 -112.298726) (xy 449.034916 -112.318546) (xy 449.027494 -112.326051) (xy 449.018981 -112.345343)
			(xy 449.018406 -112.355884) (xy 449.018406 -112.43056) (xy 449.018941 -112.441109) (xy 449.027472 -112.460405)
			(xy 449.034916 -112.467898) (xy 449.053967 -112.486058) (xy 449.087424 -112.526687) (xy 449.114983 -112.571527)
			(xy 449.136122 -112.619727) (xy 449.15044 -112.670373) (xy 449.157667 -112.722506) (xy 449.158106 -112.748822)
			(xy 449.15762 -112.776073) (xy 449.149864 -112.830021) (xy 449.134509 -112.882316) (xy 449.111867 -112.931893)
			(xy 449.082401 -112.977743) (xy 449.04671 -113.018934) (xy 449.005519 -113.054625) (xy 448.959669 -113.084091)
			(xy 448.910092 -113.106733) (xy 448.857797 -113.122088) (xy 448.803849 -113.129844) (xy 448.749347 -113.129844)
			(xy 448.695399 -113.122088) (xy 448.643104 -113.106733) (xy 448.593527 -113.084091) (xy 448.547677 -113.054625)
			(xy 448.506486 -113.018934) (xy 448.470795 -112.977743) (xy 448.441329 -112.931893) (xy 448.418687 -112.882316)
			(xy 448.403332 -112.830021) (xy 448.395576 -112.776073) (xy 448.39509 -112.748822) (xy 448.395575 -112.722509)
			(xy 448.402807 -112.670381) (xy 448.417123 -112.619739) (xy 448.438252 -112.57154) (xy 448.465795 -112.526696)
			(xy 448.49923 -112.486055) (xy 448.51828 -112.467898) (xy 448.525682 -112.460376) (xy 448.534207 -112.441096)
			(xy 448.53479 -112.43056) (xy 448.53479 -112.355884) (xy 448.534286 -112.345331) (xy 448.525734 -112.326036)
			(xy 448.51828 -112.318546) (xy 448.497514 -112.298704) (xy 448.461539 -112.253935) (xy 448.432679 -112.20428)
			(xy 448.411585 -112.150861) (xy 448.398734 -112.094885) (xy 448.394417 -112.037615) (xy 446.620598 -112.037615)
			(xy 446.61628 -112.094891) (xy 446.603427 -112.150872) (xy 446.58233 -112.204296) (xy 446.553465 -112.253954)
			(xy 446.517485 -112.298727) (xy 446.496694 -112.318546) (xy 446.489269 -112.326048) (xy 446.480759 -112.345343)
			(xy 446.480184 -112.355884) (xy 446.480184 -112.43056) (xy 446.480726 -112.441108) (xy 446.489253 -112.460403)
			(xy 446.496694 -112.467898) (xy 446.51574 -112.486063) (xy 446.549199 -112.52669) (xy 446.576759 -112.571529)
			(xy 446.597899 -112.619728) (xy 446.612218 -112.670374) (xy 446.619445 -112.722506) (xy 446.619884 -112.748822)
			(xy 446.619398 -112.776073) (xy 446.611642 -112.830021) (xy 446.596287 -112.882316) (xy 446.573645 -112.931893)
			(xy 446.544179 -112.977743) (xy 446.508488 -113.018934) (xy 446.467297 -113.054625) (xy 446.421447 -113.084091)
			(xy 446.37187 -113.106733) (xy 446.319575 -113.122088) (xy 446.265627 -113.129844) (xy 446.211125 -113.129844)
			(xy 446.157177 -113.122088) (xy 446.104882 -113.106733) (xy 446.055305 -113.084091) (xy 446.009455 -113.054625)
			(xy 445.968264 -113.018934) (xy 445.932573 -112.977743) (xy 445.903107 -112.931893) (xy 445.880465 -112.882316)
			(xy 445.86511 -112.830021) (xy 445.857354 -112.776073) (xy 445.856868 -112.748822) (xy 445.85736 -112.722509)
			(xy 445.864592 -112.670382) (xy 445.878906 -112.61974) (xy 445.900034 -112.571541) (xy 445.927575 -112.526697)
			(xy 445.961009 -112.486056) (xy 445.980058 -112.467898) (xy 445.987456 -112.460373) (xy 445.995984 -112.441096)
			(xy 445.996568 -112.43056) (xy 445.996568 -112.355884) (xy 445.99607 -112.34533) (xy 445.987514 -112.326035)
			(xy 445.980058 -112.318546) (xy 445.959293 -112.298703) (xy 445.92332 -112.253933) (xy 445.894462 -112.204279)
			(xy 445.873369 -112.15086) (xy 445.860519 -112.094884) (xy 445.856202 -112.037615) (xy 444.06285 -112.037615)
			(xy 444.094309 -112.075823) (xy 444.121867 -112.120665) (xy 444.143003 -112.168869) (xy 444.157317 -112.219519)
			(xy 444.164538 -112.271655) (xy 444.164974 -112.297972) (xy 444.164488 -112.325223) (xy 444.156732 -112.379171)
			(xy 444.141377 -112.431466) (xy 444.118735 -112.481043) (xy 444.089269 -112.526893) (xy 444.053578 -112.568084)
			(xy 444.012387 -112.603775) (xy 443.966537 -112.633241) (xy 443.91696 -112.655883) (xy 443.864665 -112.671238)
			(xy 443.810717 -112.678994) (xy 443.756215 -112.678994) (xy 443.702267 -112.671238) (xy 443.649972 -112.655883)
			(xy 443.600395 -112.633241) (xy 443.554545 -112.603775) (xy 443.513354 -112.568084) (xy 443.477663 -112.526893)
			(xy 443.448197 -112.481043) (xy 443.425555 -112.431466) (xy 443.4102 -112.379171) (xy 443.402444 -112.325223)
			(xy 443.401958 -112.297972) (xy 442.132974 -112.297972) (xy 442.132488 -112.325223) (xy 442.124732 -112.379171)
			(xy 442.109377 -112.431466) (xy 442.086735 -112.481043) (xy 442.057269 -112.526893) (xy 442.021578 -112.568084)
			(xy 441.980387 -112.603775) (xy 441.934537 -112.633241) (xy 441.88496 -112.655883) (xy 441.832665 -112.671238)
			(xy 441.778717 -112.678994) (xy 441.724215 -112.678994) (xy 441.670267 -112.671238) (xy 441.617972 -112.655883)
			(xy 441.568395 -112.633241) (xy 441.522545 -112.603775) (xy 441.481354 -112.568084) (xy 441.445663 -112.526893)
			(xy 441.416197 -112.481043) (xy 441.393555 -112.431466) (xy 441.3782 -112.379171) (xy 441.370444 -112.325223)
			(xy 441.369958 -112.297972) (xy 430.467527 -112.297972) (xy 430.245537 -114.084613) (xy 437.749383 -114.084613)
			(xy 437.749388 -114.030111) (xy 437.75715 -113.976165) (xy 437.77251 -113.923872) (xy 437.795156 -113.874298)
			(xy 437.824627 -113.828451) (xy 437.860322 -113.787265) (xy 437.901515 -113.751579) (xy 437.947368 -113.722118)
			(xy 437.996947 -113.699482) (xy 438.049243 -113.684133) (xy 438.103191 -113.676382) (xy 438.130442 -113.675922)
			(xy 438.130696 -113.675922) (xy 438.160133 -113.676472) (xy 438.218307 -113.685537) (xy 438.24652 -113.693956)
			(xy 438.258458 -113.697766) (xy 438.282334 -113.693956) (xy 438.358534 -113.637568) (xy 438.367806 -113.629826)
			(xy 438.37855 -113.608231) (xy 438.379108 -113.596166) (xy 438.379108 -113.591086) (xy 438.379542 -113.563832)
			(xy 438.387301 -113.509879) (xy 438.40266 -113.45758) (xy 438.425305 -113.407998) (xy 438.454776 -113.362145)
			(xy 438.490473 -113.320952) (xy 438.531669 -113.285258) (xy 438.577525 -113.255791) (xy 438.627108 -113.233149)
			(xy 438.679409 -113.217795) (xy 438.733362 -113.21004) (xy 438.760616 -113.209578) (xy 438.789532 -113.210127)
			(xy 438.846703 -113.218846) (xy 438.901903 -113.236096) (xy 438.953865 -113.261481) (xy 439.0014 -113.294421)
			(xy 439.043416 -113.33416) (xy 439.061606 -113.356644) (xy 439.069213 -113.365451) (xy 439.090114 -113.375633)
			(xy 439.101738 -113.376202) (xy 439.181494 -113.376202) (xy 439.193124 -113.375645) (xy 439.214033 -113.365469)
			(xy 439.221626 -113.356644) (xy 439.239813 -113.334157) (xy 439.281833 -113.29442) (xy 439.329368 -113.26148)
			(xy 439.38133 -113.236092) (xy 439.436529 -113.218837) (xy 439.4937 -113.210111) (xy 439.522616 -113.209578)
			(xy 439.549867 -113.210063) (xy 439.603814 -113.217821) (xy 439.656108 -113.233178) (xy 439.705684 -113.25582)
			(xy 439.751534 -113.285286) (xy 439.792724 -113.320978) (xy 439.828415 -113.362168) (xy 439.857881 -113.408017)
			(xy 439.880523 -113.457594) (xy 439.895879 -113.509888) (xy 439.903637 -113.563835) (xy 439.903725 -113.568734)
			(xy 459.189834 -113.568734) (xy 459.193905 -113.513112) (xy 459.206031 -113.458675) (xy 459.225954 -113.406584)
			(xy 459.25325 -113.357949) (xy 459.287336 -113.313806) (xy 459.327485 -113.275097) (xy 459.372843 -113.242646)
			(xy 459.422443 -113.217145) (xy 459.475227 -113.199138) (xy 459.53007 -113.189008) (xy 459.585804 -113.186971)
			(xy 459.641241 -113.193071) (xy 459.695198 -113.207177) (xy 459.746527 -113.228989) (xy 459.794133 -113.258043)
			(xy 459.837001 -113.293718) (xy 459.874218 -113.335255) (xy 459.904991 -113.381768) (xy 459.928663 -113.432265)
			(xy 459.944731 -113.485672) (xy 459.952851 -113.540848) (xy 459.95336 -113.568734) (xy 459.952851 -113.59662)
			(xy 459.944731 -113.651796) (xy 459.928663 -113.705203) (xy 459.904991 -113.7557) (xy 459.874218 -113.802213)
			(xy 459.837001 -113.84375) (xy 459.794133 -113.879425) (xy 459.746527 -113.908479) (xy 459.695198 -113.930291)
			(xy 459.641241 -113.944397) (xy 459.585804 -113.950497) (xy 459.53007 -113.94846) (xy 459.475227 -113.93833)
			(xy 459.422443 -113.920323) (xy 459.372843 -113.894822) (xy 459.327485 -113.862371) (xy 459.287336 -113.823662)
			(xy 459.25325 -113.779519) (xy 459.225954 -113.730884) (xy 459.206031 -113.678793) (xy 459.193905 -113.624356)
			(xy 459.189834 -113.568734) (xy 439.903725 -113.568734) (xy 439.904124 -113.591086) (xy 439.903696 -113.618491)
			(xy 439.895842 -113.672735) (xy 439.880307 -113.725297) (xy 439.857412 -113.775095) (xy 439.827627 -113.821106)
			(xy 439.791566 -113.862381) (xy 439.74997 -113.898072) (xy 439.727086 -113.913158) (xy 439.718067 -113.919608)
			(xy 439.706213 -113.938317) (xy 439.704226 -113.949226) (xy 439.692034 -114.037364) (xy 439.698638 -114.0587)
			(xy 439.706258 -114.067082) (xy 439.724546 -114.088672) (xy 439.73208 -114.097462) (xy 439.75286 -114.107627)
			(xy 439.764424 -114.10823) (xy 439.844434 -114.10823) (xy 439.85607 -114.107721) (xy 439.876981 -114.097513)
			(xy 439.884566 -114.088672) (xy 439.902769 -114.066199) (xy 439.944787 -114.026464) (xy 439.99232 -113.993525)
			(xy 440.044279 -113.968135) (xy 440.099474 -113.950876) (xy 440.156641 -113.942143) (xy 440.185556 -113.941606)
			(xy 440.212812 -113.942038) (xy 440.26677 -113.94979) (xy 440.319075 -113.965143) (xy 440.368662 -113.987784)
			(xy 440.414523 -114.017252) (xy 440.427475 -114.028474) (xy 453.305162 -114.028474) (xy 453.309233 -113.972852)
			(xy 453.321359 -113.918415) (xy 453.341282 -113.866324) (xy 453.368578 -113.817689) (xy 453.402664 -113.773546)
			(xy 453.442813 -113.734837) (xy 453.488171 -113.702386) (xy 453.537771 -113.676885) (xy 453.590555 -113.658878)
			(xy 453.645398 -113.648748) (xy 453.701132 -113.646711) (xy 453.756569 -113.652811) (xy 453.810526 -113.666917)
			(xy 453.861855 -113.688729) (xy 453.909461 -113.717783) (xy 453.952329 -113.753458) (xy 453.989546 -113.794995)
			(xy 454.020319 -113.841508) (xy 454.043991 -113.892005) (xy 454.060059 -113.945412) (xy 454.068179 -114.000588)
			(xy 454.068688 -114.028474) (xy 454.068179 -114.05636) (xy 454.060059 -114.111536) (xy 454.043991 -114.164943)
			(xy 454.020319 -114.21544) (xy 453.989546 -114.261953) (xy 453.952329 -114.30349) (xy 453.909461 -114.339165)
			(xy 453.861855 -114.368219) (xy 453.810526 -114.390031) (xy 453.756569 -114.404137) (xy 453.701132 -114.410237)
			(xy 453.645398 -114.4082) (xy 453.590555 -114.39807) (xy 453.537771 -114.380063) (xy 453.488171 -114.354562)
			(xy 453.442813 -114.322111) (xy 453.402664 -114.283402) (xy 453.368578 -114.239259) (xy 453.341282 -114.190624)
			(xy 453.321359 -114.138533) (xy 453.309233 -114.084096) (xy 453.305162 -114.028474) (xy 440.427475 -114.028474)
			(xy 440.455722 -114.052947) (xy 440.491422 -114.094142) (xy 440.520895 -114.139999) (xy 440.543542 -114.189584)
			(xy 440.558901 -114.241887) (xy 440.566659 -114.295844) (xy 440.566659 -114.350356) (xy 440.558901 -114.404313)
			(xy 440.543542 -114.456616) (xy 440.520895 -114.506201) (xy 440.491422 -114.552058) (xy 440.455722 -114.593253)
			(xy 440.414523 -114.628948) (xy 440.368662 -114.658416) (xy 440.319075 -114.681057) (xy 440.26677 -114.69641)
			(xy 440.212812 -114.704162) (xy 440.185556 -114.704622) (xy 440.156639 -114.704093) (xy 440.099467 -114.69537)
			(xy 440.044267 -114.678116) (xy 439.992305 -114.652727) (xy 439.944771 -114.619784) (xy 439.902755 -114.580042)
			(xy 439.884566 -114.557556) (xy 439.876971 -114.548736) (xy 439.856061 -114.538561) (xy 439.844434 -114.537998)
			(xy 439.764678 -114.537998) (xy 439.753046 -114.53854) (xy 439.732137 -114.548727) (xy 439.724546 -114.557556)
			(xy 439.706318 -114.580008) (xy 439.664307 -114.619747) (xy 439.61678 -114.652691) (xy 439.564826 -114.678086)
			(xy 439.509635 -114.695348) (xy 439.45247 -114.704084) (xy 439.423556 -114.704622) (xy 439.396304 -114.704163)
			(xy 439.342356 -114.696401) (xy 439.290062 -114.681041) (xy 439.240486 -114.658396) (xy 439.194636 -114.628926)
			(xy 439.153447 -114.593232) (xy 439.117756 -114.55204) (xy 439.08829 -114.506188) (xy 439.065648 -114.45661)
			(xy 439.050293 -114.404314) (xy 439.042535 -114.350366) (xy 439.042048 -114.323114) (xy 439.042489 -114.29571)
			(xy 439.050342 -114.241467) (xy 439.065876 -114.188906) (xy 439.088769 -114.139108) (xy 439.118552 -114.093098)
			(xy 439.154611 -114.051822) (xy 439.196204 -114.016129) (xy 439.219086 -114.001042) (xy 439.228118 -113.994609)
			(xy 439.239962 -113.975886) (xy 439.241946 -113.964974) (xy 439.254138 -113.876836) (xy 439.247534 -113.8555)
			(xy 439.239914 -113.847118) (xy 439.221626 -113.825528) (xy 439.214061 -113.81677) (xy 439.193304 -113.806588)
			(xy 439.181748 -113.80597) (xy 439.101738 -113.80597) (xy 439.0901 -113.806463) (xy 439.069189 -113.816682)
			(xy 439.061606 -113.825528) (xy 439.043419 -113.848014) (xy 439.001397 -113.887748) (xy 438.953861 -113.920686)
			(xy 438.9019 -113.946074) (xy 438.846702 -113.96333) (xy 438.789532 -113.972059) (xy 438.760616 -113.972594)
			(xy 438.760362 -113.972594) (xy 438.730925 -113.97203) (xy 438.672752 -113.962975) (xy 438.644538 -113.95456)
			(xy 438.6326 -113.95075) (xy 438.608724 -113.95456) (xy 438.532524 -114.010948) (xy 438.523238 -114.018675)
			(xy 438.512503 -114.040282) (xy 438.51195 -114.05235) (xy 438.51195 -114.05743) (xy 438.511413 -114.084681)
			(xy 438.503652 -114.138627) (xy 438.488293 -114.19092) (xy 438.465648 -114.240495) (xy 438.436178 -114.286342)
			(xy 438.400484 -114.327529) (xy 438.359291 -114.363217) (xy 438.313439 -114.392679) (xy 438.26386 -114.415315)
			(xy 438.211565 -114.430665) (xy 438.157617 -114.438417) (xy 438.103115 -114.438412) (xy 438.049169 -114.430651)
			(xy 437.996876 -114.415291) (xy 437.947302 -114.392646) (xy 437.901455 -114.363176) (xy 437.860268 -114.327481)
			(xy 437.824581 -114.286288) (xy 437.79512 -114.240435) (xy 437.772483 -114.190856) (xy 437.757134 -114.138561)
			(xy 437.749383 -114.084613) (xy 430.245537 -114.084613) (xy 430.081996 -115.400836) (xy 435.560722 -115.400836)
			(xy 435.564793 -115.345214) (xy 435.576919 -115.290777) (xy 435.596842 -115.238686) (xy 435.624138 -115.190051)
			(xy 435.658224 -115.145908) (xy 435.698373 -115.107199) (xy 435.743731 -115.074748) (xy 435.793331 -115.049247)
			(xy 435.846115 -115.03124) (xy 435.900958 -115.02111) (xy 435.956692 -115.019073) (xy 436.012129 -115.025173)
			(xy 436.066086 -115.039279) (xy 436.117415 -115.061091) (xy 436.165021 -115.090145) (xy 436.207889 -115.12582)
			(xy 436.245106 -115.167357) (xy 436.275879 -115.21387) (xy 436.299551 -115.264367) (xy 436.315619 -115.317774)
			(xy 436.323357 -115.370356) (xy 437.661302 -115.370356) (xy 437.665373 -115.314734) (xy 437.677499 -115.260297)
			(xy 437.697422 -115.208206) (xy 437.724718 -115.159571) (xy 437.758804 -115.115428) (xy 437.798953 -115.076719)
			(xy 437.844311 -115.044268) (xy 437.893911 -115.018767) (xy 437.946695 -115.00076) (xy 438.001538 -114.99063)
			(xy 438.057272 -114.988593) (xy 438.112709 -114.994693) (xy 438.166666 -115.008799) (xy 438.171718 -115.010946)
			(xy 454.91984 -115.010946) (xy 454.923911 -114.955324) (xy 454.936037 -114.900887) (xy 454.95596 -114.848796)
			(xy 454.983256 -114.800161) (xy 455.017342 -114.756018) (xy 455.057491 -114.717309) (xy 455.102849 -114.684858)
			(xy 455.152449 -114.659357) (xy 455.205233 -114.64135) (xy 455.260076 -114.63122) (xy 455.31581 -114.629183)
			(xy 455.371247 -114.635283) (xy 455.425204 -114.649389) (xy 455.476533 -114.671201) (xy 455.524139 -114.700255)
			(xy 455.567007 -114.73593) (xy 455.604224 -114.777467) (xy 455.634997 -114.82398) (xy 455.658669 -114.874477)
			(xy 455.674737 -114.927884) (xy 455.682857 -114.98306) (xy 455.683366 -115.010946) (xy 455.682857 -115.038832)
			(xy 455.679933 -115.058698) (xy 456.28636 -115.058698) (xy 456.290431 -115.003076) (xy 456.302557 -114.948639)
			(xy 456.32248 -114.896548) (xy 456.349776 -114.847913) (xy 456.383862 -114.80377) (xy 456.424011 -114.765061)
			(xy 456.469369 -114.73261) (xy 456.518969 -114.707109) (xy 456.571753 -114.689102) (xy 456.626596 -114.678972)
			(xy 456.68233 -114.676935) (xy 456.737767 -114.683035) (xy 456.791724 -114.697141) (xy 456.843053 -114.718953)
			(xy 456.890659 -114.748007) (xy 456.933527 -114.783682) (xy 456.970744 -114.825219) (xy 457.001517 -114.871732)
			(xy 457.025189 -114.922229) (xy 457.041257 -114.975636) (xy 457.043426 -114.990372) (xy 457.665072 -114.990372)
			(xy 457.669143 -114.93475) (xy 457.681269 -114.880313) (xy 457.701192 -114.828222) (xy 457.728488 -114.779587)
			(xy 457.762574 -114.735444) (xy 457.802723 -114.696735) (xy 457.848081 -114.664284) (xy 457.897681 -114.638783)
			(xy 457.950465 -114.620776) (xy 458.005308 -114.610646) (xy 458.061042 -114.608609) (xy 458.116479 -114.614709)
			(xy 458.170436 -114.628815) (xy 458.221765 -114.650627) (xy 458.269371 -114.679681) (xy 458.312239 -114.715356)
			(xy 458.349456 -114.756893) (xy 458.380229 -114.803406) (xy 458.403901 -114.853903) (xy 458.419969 -114.90731)
			(xy 458.427819 -114.960654) (xy 459.191866 -114.960654) (xy 459.195937 -114.905032) (xy 459.208063 -114.850595)
			(xy 459.227986 -114.798504) (xy 459.255282 -114.749869) (xy 459.289368 -114.705726) (xy 459.329517 -114.667017)
			(xy 459.374875 -114.634566) (xy 459.424475 -114.609065) (xy 459.477259 -114.591058) (xy 459.532102 -114.580928)
			(xy 459.587836 -114.578891) (xy 459.643273 -114.584991) (xy 459.69723 -114.599097) (xy 459.748559 -114.620909)
			(xy 459.796165 -114.649963) (xy 459.839033 -114.685638) (xy 459.87625 -114.727175) (xy 459.907023 -114.773688)
			(xy 459.930695 -114.824185) (xy 459.946763 -114.877592) (xy 459.954883 -114.932768) (xy 459.955392 -114.960654)
			(xy 459.954883 -114.98854) (xy 459.946763 -115.043716) (xy 459.930695 -115.097123) (xy 459.907023 -115.14762)
			(xy 459.87625 -115.194133) (xy 459.839033 -115.23567) (xy 459.796165 -115.271345) (xy 459.748559 -115.300399)
			(xy 459.69723 -115.322211) (xy 459.643273 -115.336317) (xy 459.587836 -115.342417) (xy 459.532102 -115.34038)
			(xy 459.477259 -115.33025) (xy 459.424475 -115.312243) (xy 459.374875 -115.286742) (xy 459.329517 -115.254291)
			(xy 459.289368 -115.215582) (xy 459.255282 -115.171439) (xy 459.227986 -115.122804) (xy 459.208063 -115.070713)
			(xy 459.195937 -115.016276) (xy 459.191866 -114.960654) (xy 458.427819 -114.960654) (xy 458.428089 -114.962486)
			(xy 458.428598 -114.990372) (xy 458.428089 -115.018258) (xy 458.419969 -115.073434) (xy 458.403901 -115.126841)
			(xy 458.380229 -115.177338) (xy 458.349456 -115.223851) (xy 458.312239 -115.265388) (xy 458.269371 -115.301063)
			(xy 458.221765 -115.330117) (xy 458.170436 -115.351929) (xy 458.116479 -115.366035) (xy 458.061042 -115.372135)
			(xy 458.005308 -115.370098) (xy 457.950465 -115.359968) (xy 457.897681 -115.341961) (xy 457.848081 -115.31646)
			(xy 457.802723 -115.284009) (xy 457.762574 -115.2453) (xy 457.728488 -115.201157) (xy 457.701192 -115.152522)
			(xy 457.681269 -115.100431) (xy 457.669143 -115.045994) (xy 457.665072 -114.990372) (xy 457.043426 -114.990372)
			(xy 457.049377 -115.030812) (xy 457.049886 -115.058698) (xy 457.049377 -115.086584) (xy 457.041257 -115.14176)
			(xy 457.025189 -115.195167) (xy 457.001517 -115.245664) (xy 456.970744 -115.292177) (xy 456.933527 -115.333714)
			(xy 456.890659 -115.369389) (xy 456.843053 -115.398443) (xy 456.791724 -115.420255) (xy 456.737767 -115.434361)
			(xy 456.68233 -115.440461) (xy 456.626596 -115.438424) (xy 456.571753 -115.428294) (xy 456.518969 -115.410287)
			(xy 456.469369 -115.384786) (xy 456.424011 -115.352335) (xy 456.383862 -115.313626) (xy 456.349776 -115.269483)
			(xy 456.32248 -115.220848) (xy 456.302557 -115.168757) (xy 456.290431 -115.11432) (xy 456.28636 -115.058698)
			(xy 455.679933 -115.058698) (xy 455.674737 -115.094008) (xy 455.658669 -115.147415) (xy 455.634997 -115.197912)
			(xy 455.604224 -115.244425) (xy 455.567007 -115.285962) (xy 455.524139 -115.321637) (xy 455.476533 -115.350691)
			(xy 455.425204 -115.372503) (xy 455.371247 -115.386609) (xy 455.31581 -115.392709) (xy 455.260076 -115.390672)
			(xy 455.205233 -115.380542) (xy 455.152449 -115.362535) (xy 455.102849 -115.337034) (xy 455.057491 -115.304583)
			(xy 455.017342 -115.265874) (xy 454.983256 -115.221731) (xy 454.95596 -115.173096) (xy 454.936037 -115.121005)
			(xy 454.923911 -115.066568) (xy 454.91984 -115.010946) (xy 438.171718 -115.010946) (xy 438.217995 -115.030611)
			(xy 438.265601 -115.059665) (xy 438.308469 -115.09534) (xy 438.345686 -115.136877) (xy 438.376459 -115.18339)
			(xy 438.400131 -115.233887) (xy 438.416199 -115.287294) (xy 438.424319 -115.34247) (xy 438.424828 -115.370356)
			(xy 438.424319 -115.398242) (xy 438.416199 -115.453418) (xy 438.400131 -115.506825) (xy 438.376459 -115.557322)
			(xy 438.345686 -115.603835) (xy 438.308469 -115.645372) (xy 438.265601 -115.681047) (xy 438.217995 -115.710101)
			(xy 438.166666 -115.731913) (xy 438.112709 -115.746019) (xy 438.057272 -115.752119) (xy 438.001538 -115.750082)
			(xy 437.946695 -115.739952) (xy 437.893911 -115.721945) (xy 437.844311 -115.696444) (xy 437.798953 -115.663993)
			(xy 437.758804 -115.625284) (xy 437.724718 -115.581141) (xy 437.697422 -115.532506) (xy 437.677499 -115.480415)
			(xy 437.665373 -115.425978) (xy 437.661302 -115.370356) (xy 436.323357 -115.370356) (xy 436.323739 -115.37295)
			(xy 436.324248 -115.400836) (xy 436.323739 -115.428722) (xy 436.315619 -115.483898) (xy 436.299551 -115.537305)
			(xy 436.275879 -115.587802) (xy 436.245106 -115.634315) (xy 436.207889 -115.675852) (xy 436.165021 -115.711527)
			(xy 436.117415 -115.740581) (xy 436.066086 -115.762393) (xy 436.012129 -115.776499) (xy 435.956692 -115.782599)
			(xy 435.900958 -115.780562) (xy 435.846115 -115.770432) (xy 435.793331 -115.752425) (xy 435.743731 -115.726924)
			(xy 435.698373 -115.694473) (xy 435.658224 -115.655764) (xy 435.624138 -115.611621) (xy 435.596842 -115.562986)
			(xy 435.576919 -115.510895) (xy 435.564793 -115.456458) (xy 435.560722 -115.400836) (xy 430.081996 -115.400836)
			(xy 430.028345 -115.832636) (xy 441.279278 -115.832636) (xy 441.283349 -115.777014) (xy 441.295475 -115.722577)
			(xy 441.315398 -115.670486) (xy 441.342694 -115.621851) (xy 441.37678 -115.577708) (xy 441.416929 -115.538999)
			(xy 441.462287 -115.506548) (xy 441.511887 -115.481047) (xy 441.564671 -115.46304) (xy 441.619514 -115.45291)
			(xy 441.675248 -115.450873) (xy 441.730685 -115.456973) (xy 441.784642 -115.471079) (xy 441.835971 -115.492891)
			(xy 441.883577 -115.521945) (xy 441.926445 -115.55762) (xy 441.963662 -115.599157) (xy 441.994435 -115.64567)
			(xy 442.018107 -115.696167) (xy 442.034175 -115.749574) (xy 442.042295 -115.80475) (xy 442.042804 -115.832636)
			(xy 442.042295 -115.860522) (xy 442.034175 -115.915698) (xy 442.018107 -115.969105) (xy 441.994435 -116.019602)
			(xy 441.963662 -116.066115) (xy 441.926445 -116.107652) (xy 441.883577 -116.143327) (xy 441.835971 -116.172381)
			(xy 441.784642 -116.194193) (xy 441.730685 -116.208299) (xy 441.675248 -116.214399) (xy 441.619514 -116.212362)
			(xy 441.564671 -116.202232) (xy 441.511887 -116.184225) (xy 441.462287 -116.158724) (xy 441.416929 -116.126273)
			(xy 441.37678 -116.087564) (xy 441.342694 -116.043421) (xy 441.315398 -115.994786) (xy 441.295475 -115.942695)
			(xy 441.283349 -115.888258) (xy 441.279278 -115.832636) (xy 430.028345 -115.832636) (xy 430.001172 -116.05133)
			(xy 429.92431 -116.66982) (xy 437.67324 -116.66982) (xy 437.677311 -116.614198) (xy 437.689437 -116.559761)
			(xy 437.70936 -116.50767) (xy 437.736656 -116.459035) (xy 437.770742 -116.414892) (xy 437.810891 -116.376183)
			(xy 437.856249 -116.343732) (xy 437.905849 -116.318231) (xy 437.958633 -116.300224) (xy 438.013476 -116.290094)
			(xy 438.06921 -116.288057) (xy 438.124647 -116.294157) (xy 438.178604 -116.308263) (xy 438.229933 -116.330075)
			(xy 438.277539 -116.359129) (xy 438.320407 -116.394804) (xy 438.357624 -116.436341) (xy 438.388397 -116.482854)
			(xy 438.412069 -116.533351) (xy 438.428137 -116.586758) (xy 438.43438 -116.62918) (xy 453.438004 -116.62918)
			(xy 453.442075 -116.573558) (xy 453.454201 -116.519121) (xy 453.474124 -116.46703) (xy 453.50142 -116.418395)
			(xy 453.535506 -116.374252) (xy 453.575655 -116.335543) (xy 453.621013 -116.303092) (xy 453.670613 -116.277591)
			(xy 453.723397 -116.259584) (xy 453.77824 -116.249454) (xy 453.833974 -116.247417) (xy 453.889411 -116.253517)
			(xy 453.943368 -116.267623) (xy 453.994697 -116.289435) (xy 454.042303 -116.318489) (xy 454.085171 -116.354164)
			(xy 454.122388 -116.395701) (xy 454.153161 -116.442214) (xy 454.176833 -116.492711) (xy 454.192901 -116.546118)
			(xy 454.201021 -116.601294) (xy 454.20153 -116.62918) (xy 454.201021 -116.657066) (xy 454.192901 -116.712242)
			(xy 454.176833 -116.765649) (xy 454.153161 -116.816146) (xy 454.122388 -116.862659) (xy 454.085171 -116.904196)
			(xy 454.042303 -116.939871) (xy 453.994697 -116.968925) (xy 453.943368 -116.990737) (xy 453.889411 -117.004843)
			(xy 453.833974 -117.010943) (xy 453.77824 -117.008906) (xy 453.723397 -116.998776) (xy 453.670613 -116.980769)
			(xy 453.621013 -116.955268) (xy 453.575655 -116.922817) (xy 453.535506 -116.884108) (xy 453.50142 -116.839965)
			(xy 453.474124 -116.79133) (xy 453.454201 -116.739239) (xy 453.442075 -116.684802) (xy 453.438004 -116.62918)
			(xy 438.43438 -116.62918) (xy 438.436257 -116.641934) (xy 438.436766 -116.66982) (xy 438.436257 -116.697706)
			(xy 438.428137 -116.752882) (xy 438.412069 -116.806289) (xy 438.388397 -116.856786) (xy 438.357624 -116.903299)
			(xy 438.320407 -116.944836) (xy 438.277539 -116.980511) (xy 438.229933 -117.009565) (xy 438.178604 -117.031377)
			(xy 438.124647 -117.045483) (xy 438.06921 -117.051583) (xy 438.013476 -117.049546) (xy 437.958633 -117.039416)
			(xy 437.905849 -117.021409) (xy 437.856249 -116.995908) (xy 437.810891 -116.963457) (xy 437.770742 -116.924748)
			(xy 437.736656 -116.880605) (xy 437.70936 -116.83197) (xy 437.689437 -116.779879) (xy 437.677311 -116.725442)
			(xy 437.67324 -116.66982) (xy 429.92431 -116.66982) (xy 429.834755 -117.390446) (xy 439.042618 -117.390446)
			(xy 439.042618 -117.335954) (xy 439.050373 -117.282015) (xy 439.065724 -117.22973) (xy 439.088359 -117.180161)
			(xy 439.117818 -117.134317) (xy 439.153501 -117.093133) (xy 439.194682 -117.057445) (xy 439.240522 -117.027981)
			(xy 439.290089 -117.005339) (xy 439.342372 -116.989982) (xy 439.39631 -116.982221) (xy 439.423556 -116.981732)
			(xy 439.452472 -116.98227) (xy 439.509643 -116.990993) (xy 439.564842 -117.008246) (xy 439.616804 -117.033634)
			(xy 439.664339 -117.066575) (xy 439.706356 -117.106314) (xy 439.724546 -117.128798) (xy 439.732143 -117.137616)
			(xy 439.753051 -117.147794) (xy 439.764678 -117.148356) (xy 439.844434 -117.148356) (xy 439.856069 -117.147838)
			(xy 439.876979 -117.137636) (xy 439.884566 -117.128798) (xy 439.902776 -117.10633) (xy 439.944792 -117.066594)
			(xy 439.992323 -117.033653) (xy 440.04428 -117.008262) (xy 440.099474 -116.991003) (xy 440.156641 -116.982269)
			(xy 440.185556 -116.981732) (xy 440.212814 -116.982112) (xy 440.266775 -116.989865) (xy 440.319084 -117.005218)
			(xy 440.368675 -117.027861) (xy 440.414538 -117.057331) (xy 440.455741 -117.093028) (xy 440.464067 -117.102636)
			(xy 441.279278 -117.102636) (xy 441.283349 -117.047014) (xy 441.295475 -116.992577) (xy 441.315398 -116.940486)
			(xy 441.342694 -116.891851) (xy 441.37678 -116.847708) (xy 441.416929 -116.808999) (xy 441.462287 -116.776548)
			(xy 441.511887 -116.751047) (xy 441.564671 -116.73304) (xy 441.619514 -116.72291) (xy 441.675248 -116.720873)
			(xy 441.730685 -116.726973) (xy 441.784642 -116.741079) (xy 441.835971 -116.762891) (xy 441.883577 -116.791945)
			(xy 441.926445 -116.82762) (xy 441.963662 -116.869157) (xy 441.994435 -116.91567) (xy 442.018107 -116.966167)
			(xy 442.034175 -117.019574) (xy 442.042295 -117.07475) (xy 442.042804 -117.102636) (xy 442.042295 -117.130522)
			(xy 442.034175 -117.185698) (xy 442.018107 -117.239105) (xy 442.013854 -117.248178) (xy 456.038964 -117.248178)
			(xy 456.043035 -117.192556) (xy 456.055161 -117.138119) (xy 456.075084 -117.086028) (xy 456.10238 -117.037393)
			(xy 456.136466 -116.99325) (xy 456.176615 -116.954541) (xy 456.221973 -116.92209) (xy 456.271573 -116.896589)
			(xy 456.324357 -116.878582) (xy 456.3792 -116.868452) (xy 456.434934 -116.866415) (xy 456.490371 -116.872515)
			(xy 456.544328 -116.886621) (xy 456.595657 -116.908433) (xy 456.643263 -116.937487) (xy 456.686131 -116.973162)
			(xy 456.723348 -117.014699) (xy 456.754121 -117.061212) (xy 456.777793 -117.111709) (xy 456.793861 -117.165116)
			(xy 456.801981 -117.220292) (xy 456.80249 -117.248178) (xy 457.054964 -117.248178) (xy 457.059035 -117.192556)
			(xy 457.071161 -117.138119) (xy 457.091084 -117.086028) (xy 457.11838 -117.037393) (xy 457.152466 -116.99325)
			(xy 457.192615 -116.954541) (xy 457.237973 -116.92209) (xy 457.287573 -116.896589) (xy 457.340357 -116.878582)
			(xy 457.3952 -116.868452) (xy 457.450934 -116.866415) (xy 457.506371 -116.872515) (xy 457.560328 -116.886621)
			(xy 457.611657 -116.908433) (xy 457.659263 -116.937487) (xy 457.702131 -116.973162) (xy 457.739348 -117.014699)
			(xy 457.770121 -117.061212) (xy 457.793793 -117.111709) (xy 457.809861 -117.165116) (xy 457.817981 -117.220292)
			(xy 457.81849 -117.248178) (xy 458.070964 -117.248178) (xy 458.075035 -117.192556) (xy 458.087161 -117.138119)
			(xy 458.107084 -117.086028) (xy 458.13438 -117.037393) (xy 458.168466 -116.99325) (xy 458.208615 -116.954541)
			(xy 458.253973 -116.92209) (xy 458.303573 -116.896589) (xy 458.356357 -116.878582) (xy 458.4112 -116.868452)
			(xy 458.466934 -116.866415) (xy 458.522371 -116.872515) (xy 458.576328 -116.886621) (xy 458.627657 -116.908433)
			(xy 458.675263 -116.937487) (xy 458.718131 -116.973162) (xy 458.755348 -117.014699) (xy 458.786121 -117.061212)
			(xy 458.809793 -117.111709) (xy 458.825861 -117.165116) (xy 458.833981 -117.220292) (xy 458.83449 -117.248178)
			(xy 458.833981 -117.276064) (xy 458.825861 -117.33124) (xy 458.809793 -117.384647) (xy 458.786121 -117.435144)
			(xy 458.755348 -117.481657) (xy 458.718131 -117.523194) (xy 458.675263 -117.558869) (xy 458.627657 -117.587923)
			(xy 458.576328 -117.609735) (xy 458.522371 -117.623841) (xy 458.466934 -117.629941) (xy 458.4112 -117.627904)
			(xy 458.356357 -117.617774) (xy 458.303573 -117.599767) (xy 458.253973 -117.574266) (xy 458.208615 -117.541815)
			(xy 458.168466 -117.503106) (xy 458.13438 -117.458963) (xy 458.107084 -117.410328) (xy 458.087161 -117.358237)
			(xy 458.075035 -117.3038) (xy 458.070964 -117.248178) (xy 457.81849 -117.248178) (xy 457.817981 -117.276064)
			(xy 457.809861 -117.33124) (xy 457.793793 -117.384647) (xy 457.770121 -117.435144) (xy 457.739348 -117.481657)
			(xy 457.702131 -117.523194) (xy 457.659263 -117.558869) (xy 457.611657 -117.587923) (xy 457.560328 -117.609735)
			(xy 457.506371 -117.623841) (xy 457.450934 -117.629941) (xy 457.3952 -117.627904) (xy 457.340357 -117.617774)
			(xy 457.287573 -117.599767) (xy 457.237973 -117.574266) (xy 457.192615 -117.541815) (xy 457.152466 -117.503106)
			(xy 457.11838 -117.458963) (xy 457.091084 -117.410328) (xy 457.071161 -117.358237) (xy 457.059035 -117.3038)
			(xy 457.054964 -117.248178) (xy 456.80249 -117.248178) (xy 456.801981 -117.276064) (xy 456.793861 -117.33124)
			(xy 456.777793 -117.384647) (xy 456.754121 -117.435144) (xy 456.723348 -117.481657) (xy 456.686131 -117.523194)
			(xy 456.643263 -117.558869) (xy 456.595657 -117.587923) (xy 456.544328 -117.609735) (xy 456.490371 -117.623841)
			(xy 456.434934 -117.629941) (xy 456.3792 -117.627904) (xy 456.324357 -117.617774) (xy 456.271573 -117.599767)
			(xy 456.221973 -117.574266) (xy 456.176615 -117.541815) (xy 456.136466 -117.503106) (xy 456.10238 -117.458963)
			(xy 456.075084 -117.410328) (xy 456.055161 -117.358237) (xy 456.043035 -117.3038) (xy 456.038964 -117.248178)
			(xy 442.013854 -117.248178) (xy 441.994435 -117.289602) (xy 441.963662 -117.336115) (xy 441.926445 -117.377652)
			(xy 441.883577 -117.413327) (xy 441.835971 -117.442381) (xy 441.784642 -117.464193) (xy 441.730685 -117.478299)
			(xy 441.675248 -117.484399) (xy 441.619514 -117.482362) (xy 441.564671 -117.472232) (xy 441.511887 -117.454225)
			(xy 441.462287 -117.428724) (xy 441.416929 -117.396273) (xy 441.37678 -117.357564) (xy 441.342694 -117.313421)
			(xy 441.315398 -117.264786) (xy 441.295475 -117.212695) (xy 441.283349 -117.158258) (xy 441.279278 -117.102636)
			(xy 440.464067 -117.102636) (xy 440.491443 -117.134226) (xy 440.520918 -117.180087) (xy 440.543566 -117.229675)
			(xy 440.558926 -117.281982) (xy 440.566685 -117.335942) (xy 440.566685 -117.390458) (xy 440.558926 -117.444418)
			(xy 440.543566 -117.496725) (xy 440.520918 -117.546313) (xy 440.491443 -117.592174) (xy 440.455741 -117.633372)
			(xy 440.414538 -117.669069) (xy 440.368675 -117.698539) (xy 440.319084 -117.721182) (xy 440.266775 -117.736535)
			(xy 440.212814 -117.744288) (xy 440.185556 -117.744748) (xy 440.15664 -117.744209) (xy 440.099468 -117.735487)
			(xy 440.044269 -117.718235) (xy 439.992307 -117.692847) (xy 439.944773 -117.659906) (xy 439.902756 -117.620167)
			(xy 439.884566 -117.597682) (xy 439.876967 -117.588866) (xy 439.85606 -117.578688) (xy 439.844434 -117.578124)
			(xy 439.764678 -117.578124) (xy 439.753045 -117.578656) (xy 439.732135 -117.588849) (xy 439.724546 -117.597682)
			(xy 439.706324 -117.62014) (xy 439.664312 -117.659877) (xy 439.616783 -117.69282) (xy 439.564828 -117.718213)
			(xy 439.509635 -117.735475) (xy 439.45247 -117.74421) (xy 439.423556 -117.744748) (xy 439.39631 -117.744179)
			(xy 439.342372 -117.736418) (xy 439.290089 -117.721061) (xy 439.240522 -117.698419) (xy 439.194682 -117.668955)
			(xy 439.153501 -117.633267) (xy 439.117818 -117.592083) (xy 439.088359 -117.546239) (xy 439.065724 -117.49667)
			(xy 439.050373 -117.444385) (xy 439.042618 -117.390446) (xy 429.834755 -117.390446) (xy 429.751236 -118.062502)
			(xy 429.750982 -118.064534) (xy 429.749204 -118.108222) (xy 429.748188 -118.13413) (xy 429.748188 -118.134638)
			(xy 429.747426 -118.149878) (xy 429.747873 -118.158373) (xy 429.753724 -118.174335) (xy 429.758856 -118.18112)
			(xy 429.768254 -118.192042) (xy 429.768762 -118.19255) (xy 429.793654 -118.220744) (xy 429.80119 -118.228541)
			(xy 429.820923 -118.23748) (xy 429.831754 -118.238016) (xy 429.850804 -118.238016) (xy 429.87997 -118.23965)
			(xy 429.937567 -118.249403) (xy 429.993456 -118.266404) (xy 430.046728 -118.290375) (xy 430.096518 -118.320928)
			(xy 430.142017 -118.357566) (xy 430.182487 -118.399694) (xy 430.217269 -118.446627) (xy 430.229167 -118.467886)
			(xy 445.782444 -118.467886) (xy 445.786515 -118.412264) (xy 445.798641 -118.357827) (xy 445.818564 -118.305736)
			(xy 445.84586 -118.257101) (xy 445.879946 -118.212958) (xy 445.920095 -118.174249) (xy 445.965453 -118.141798)
			(xy 446.015053 -118.116297) (xy 446.067837 -118.09829) (xy 446.12268 -118.08816) (xy 446.178414 -118.086123)
			(xy 446.233851 -118.092223) (xy 446.287808 -118.106329) (xy 446.339137 -118.128141) (xy 446.386743 -118.157195)
			(xy 446.429611 -118.19287) (xy 446.466828 -118.234407) (xy 446.497601 -118.28092) (xy 446.521273 -118.331417)
			(xy 446.537341 -118.384824) (xy 446.545461 -118.44) (xy 446.54597 -118.467886) (xy 446.545461 -118.495772)
			(xy 446.537341 -118.550948) (xy 446.521273 -118.604355) (xy 446.497601 -118.654852) (xy 446.466828 -118.701365)
			(xy 446.429611 -118.742902) (xy 446.408777 -118.76024) (xy 448.838826 -118.76024) (xy 448.842897 -118.704618)
			(xy 448.855023 -118.650181) (xy 448.874946 -118.59809) (xy 448.902242 -118.549455) (xy 448.936328 -118.505312)
			(xy 448.976477 -118.466603) (xy 449.021835 -118.434152) (xy 449.071435 -118.408651) (xy 449.124219 -118.390644)
			(xy 449.179062 -118.380514) (xy 449.234796 -118.378477) (xy 449.290233 -118.384577) (xy 449.34419 -118.398683)
			(xy 449.395519 -118.420495) (xy 449.443125 -118.449549) (xy 449.485993 -118.485224) (xy 449.52321 -118.526761)
			(xy 449.553983 -118.573274) (xy 449.577655 -118.623771) (xy 449.593723 -118.677178) (xy 449.601843 -118.732354)
			(xy 449.602352 -118.76024) (xy 450.864476 -118.76024) (xy 450.868547 -118.704618) (xy 450.880673 -118.650181)
			(xy 450.900596 -118.59809) (xy 450.927892 -118.549455) (xy 450.961978 -118.505312) (xy 451.002127 -118.466603)
			(xy 451.047485 -118.434152) (xy 451.097085 -118.408651) (xy 451.149869 -118.390644) (xy 451.204712 -118.380514)
			(xy 451.260446 -118.378477) (xy 451.315883 -118.384577) (xy 451.36984 -118.398683) (xy 451.421169 -118.420495)
			(xy 451.468775 -118.449549) (xy 451.511643 -118.485224) (xy 451.54886 -118.526761) (xy 451.579633 -118.573274)
			(xy 451.603305 -118.623771) (xy 451.619373 -118.677178) (xy 451.627493 -118.732354) (xy 451.628002 -118.76024)
			(xy 451.627493 -118.788126) (xy 451.619373 -118.843302) (xy 451.603305 -118.896709) (xy 451.579633 -118.947206)
			(xy 451.54886 -118.993719) (xy 451.511643 -119.035256) (xy 451.468775 -119.070931) (xy 451.421169 -119.099985)
			(xy 451.36984 -119.121797) (xy 451.315883 -119.135903) (xy 451.260446 -119.142003) (xy 451.204712 -119.139966)
			(xy 451.149869 -119.129836) (xy 451.097085 -119.111829) (xy 451.047485 -119.086328) (xy 451.002127 -119.053877)
			(xy 450.961978 -119.015168) (xy 450.927892 -118.971025) (xy 450.900596 -118.92239) (xy 450.880673 -118.870299)
			(xy 450.868547 -118.815862) (xy 450.864476 -118.76024) (xy 449.602352 -118.76024) (xy 449.601843 -118.788126)
			(xy 449.593723 -118.843302) (xy 449.577655 -118.896709) (xy 449.553983 -118.947206) (xy 449.52321 -118.993719)
			(xy 449.485993 -119.035256) (xy 449.443125 -119.070931) (xy 449.395519 -119.099985) (xy 449.34419 -119.121797)
			(xy 449.290233 -119.135903) (xy 449.234796 -119.142003) (xy 449.179062 -119.139966) (xy 449.124219 -119.129836)
			(xy 449.071435 -119.111829) (xy 449.021835 -119.086328) (xy 448.976477 -119.053877) (xy 448.936328 -119.015168)
			(xy 448.902242 -118.971025) (xy 448.874946 -118.92239) (xy 448.855023 -118.870299) (xy 448.842897 -118.815862)
			(xy 448.838826 -118.76024) (xy 446.408777 -118.76024) (xy 446.386743 -118.778577) (xy 446.339137 -118.807631)
			(xy 446.287808 -118.829443) (xy 446.233851 -118.843549) (xy 446.178414 -118.849649) (xy 446.12268 -118.847612)
			(xy 446.067837 -118.837482) (xy 446.015053 -118.819475) (xy 445.965453 -118.793974) (xy 445.920095 -118.761523)
			(xy 445.879946 -118.722814) (xy 445.84586 -118.678671) (xy 445.818564 -118.630036) (xy 445.798641 -118.577945)
			(xy 445.786515 -118.523508) (xy 445.782444 -118.467886) (xy 430.229167 -118.467886) (xy 430.245799 -118.497603)
			(xy 430.267614 -118.551794) (xy 430.282358 -118.60832) (xy 430.289792 -118.666262) (xy 430.290224 -118.69547)
			(xy 430.290224 -119.407557) (xy 442.799609 -119.407557) (xy 442.799609 -119.353043) (xy 442.807368 -119.299083)
			(xy 442.822727 -119.246777) (xy 442.845374 -119.197189) (xy 442.874848 -119.151329) (xy 442.910548 -119.110131)
			(xy 442.951749 -119.074433) (xy 442.99761 -119.044962) (xy 443.0472 -119.022318) (xy 443.099507 -119.006962)
			(xy 443.153467 -118.999207) (xy 443.180724 -118.998746) (xy 443.208095 -118.999187) (xy 443.262276 -119.007009)
			(xy 443.31478 -119.022503) (xy 443.364526 -119.045351) (xy 443.410492 -119.075082) (xy 443.431422 -119.092726)
			(xy 443.431676 -119.09298) (xy 443.438758 -119.098572) (xy 443.455679 -119.104813) (xy 443.464696 -119.105172)
			(xy 443.531752 -119.105172) (xy 443.540767 -119.104798) (xy 443.557685 -119.098563) (xy 443.564772 -119.09298)
			(xy 443.564772 -119.092726) (xy 443.565026 -119.092726) (xy 443.585979 -119.075112) (xy 443.631945 -119.045396)
			(xy 443.681688 -119.022554) (xy 443.734184 -119.007058) (xy 443.788356 -118.999223) (xy 443.815724 -118.998746)
			(xy 443.842971 -118.999326) (xy 443.896909 -119.007084) (xy 443.949195 -119.022439) (xy 443.998763 -119.045079)
			(xy 444.044605 -119.074543) (xy 444.085787 -119.11023) (xy 444.121472 -119.151414) (xy 444.150932 -119.197258)
			(xy 444.173569 -119.246828) (xy 444.188921 -119.299114) (xy 444.196676 -119.353053) (xy 444.196676 -119.407547)
			(xy 444.188921 -119.461486) (xy 444.184358 -119.477028) (xy 447.903344 -119.477028) (xy 447.907415 -119.421406)
			(xy 447.919541 -119.366969) (xy 447.939464 -119.314878) (xy 447.96676 -119.266243) (xy 448.000846 -119.2221)
			(xy 448.040995 -119.183391) (xy 448.086353 -119.15094) (xy 448.135953 -119.125439) (xy 448.188737 -119.107432)
			(xy 448.24358 -119.097302) (xy 448.299314 -119.095265) (xy 448.354751 -119.101365) (xy 448.408708 -119.115471)
			(xy 448.460037 -119.137283) (xy 448.507643 -119.166337) (xy 448.550511 -119.202012) (xy 448.587728 -119.243549)
			(xy 448.618501 -119.290062) (xy 448.642173 -119.340559) (xy 448.658241 -119.393966) (xy 448.666361 -119.449142)
			(xy 448.66687 -119.477028) (xy 448.666361 -119.504914) (xy 448.658241 -119.56009) (xy 448.642173 -119.613497)
			(xy 448.618501 -119.663994) (xy 448.587728 -119.710507) (xy 448.580265 -119.718836) (xy 455.836526 -119.718836)
			(xy 455.840597 -119.663214) (xy 455.852723 -119.608777) (xy 455.872646 -119.556686) (xy 455.899942 -119.508051)
			(xy 455.934028 -119.463908) (xy 455.974177 -119.425199) (xy 456.019535 -119.392748) (xy 456.069135 -119.367247)
			(xy 456.121919 -119.34924) (xy 456.176762 -119.33911) (xy 456.232496 -119.337073) (xy 456.287933 -119.343173)
			(xy 456.34189 -119.357279) (xy 456.393219 -119.379091) (xy 456.440825 -119.408145) (xy 456.483693 -119.44382)
			(xy 456.52091 -119.485357) (xy 456.551683 -119.53187) (xy 456.575355 -119.582367) (xy 456.591423 -119.635774)
			(xy 456.599543 -119.69095) (xy 456.600052 -119.718836) (xy 456.599543 -119.746722) (xy 456.591423 -119.801898)
			(xy 456.575355 -119.855305) (xy 456.551683 -119.905802) (xy 456.52091 -119.952315) (xy 456.483693 -119.993852)
			(xy 456.440825 -120.029527) (xy 456.393219 -120.058581) (xy 456.34189 -120.080393) (xy 456.287933 -120.094499)
			(xy 456.232496 -120.100599) (xy 456.176762 -120.098562) (xy 456.121919 -120.088432) (xy 456.069135 -120.070425)
			(xy 456.019535 -120.044924) (xy 455.974177 -120.012473) (xy 455.934028 -119.973764) (xy 455.899942 -119.929621)
			(xy 455.872646 -119.880986) (xy 455.852723 -119.828895) (xy 455.840597 -119.774458) (xy 455.836526 -119.718836)
			(xy 448.580265 -119.718836) (xy 448.550511 -119.752044) (xy 448.507643 -119.787719) (xy 448.460037 -119.816773)
			(xy 448.408708 -119.838585) (xy 448.354751 -119.852691) (xy 448.299314 -119.858791) (xy 448.24358 -119.856754)
			(xy 448.188737 -119.846624) (xy 448.135953 -119.828617) (xy 448.086353 -119.803116) (xy 448.040995 -119.770665)
			(xy 448.000846 -119.731956) (xy 447.96676 -119.687813) (xy 447.939464 -119.639178) (xy 447.919541 -119.587087)
			(xy 447.907415 -119.53265) (xy 447.903344 -119.477028) (xy 444.184358 -119.477028) (xy 444.173569 -119.513772)
			(xy 444.150932 -119.563342) (xy 444.121472 -119.609186) (xy 444.085787 -119.65037) (xy 444.044605 -119.686057)
			(xy 443.998763 -119.715521) (xy 443.949195 -119.738161) (xy 443.896909 -119.753516) (xy 443.842971 -119.761274)
			(xy 443.815724 -119.761762) (xy 443.788354 -119.761291) (xy 443.734175 -119.753476) (xy 443.681671 -119.737988)
			(xy 443.631924 -119.715148) (xy 443.585957 -119.685423) (xy 443.565026 -119.667782) (xy 443.564772 -119.667528)
			(xy 443.557675 -119.661957) (xy 443.540766 -119.655703) (xy 443.531752 -119.655336) (xy 443.464696 -119.655336)
			(xy 443.455678 -119.655683) (xy 443.438761 -119.661937) (xy 443.431676 -119.667528) (xy 443.431676 -119.667782)
			(xy 443.431422 -119.667782) (xy 443.41049 -119.685421) (xy 443.364518 -119.715134) (xy 443.31477 -119.73797)
			(xy 443.262269 -119.753461) (xy 443.208093 -119.761288) (xy 443.180724 -119.761762) (xy 443.153467 -119.761393)
			(xy 443.099507 -119.753638) (xy 443.0472 -119.738282) (xy 442.99761 -119.715638) (xy 442.951749 -119.686167)
			(xy 442.910548 -119.650469) (xy 442.874848 -119.609271) (xy 442.845374 -119.563411) (xy 442.822727 -119.513823)
			(xy 442.807368 -119.461517) (xy 442.799609 -119.407557) (xy 430.290224 -119.407557) (xy 430.290224 -119.559578)
			(xy 430.289723 -119.589537) (xy 430.281883 -119.648939) (xy 430.266361 -119.706811) (xy 430.243422 -119.762164)
			(xy 430.213458 -119.814051) (xy 430.176981 -119.861586) (xy 430.14549 -119.89308) (xy 445.869058 -119.89308)
			(xy 445.873129 -119.837458) (xy 445.885255 -119.783021) (xy 445.905178 -119.73093) (xy 445.932474 -119.682295)
			(xy 445.96656 -119.638152) (xy 446.006709 -119.599443) (xy 446.052067 -119.566992) (xy 446.101667 -119.541491)
			(xy 446.154451 -119.523484) (xy 446.209294 -119.513354) (xy 446.265028 -119.511317) (xy 446.320465 -119.517417)
			(xy 446.374422 -119.531523) (xy 446.425751 -119.553335) (xy 446.473357 -119.582389) (xy 446.516225 -119.618064)
			(xy 446.553442 -119.659601) (xy 446.584215 -119.706114) (xy 446.607887 -119.756611) (xy 446.623955 -119.810018)
			(xy 446.632075 -119.865194) (xy 446.632584 -119.89308) (xy 446.632075 -119.920966) (xy 446.623955 -119.976142)
			(xy 446.607887 -120.029549) (xy 446.584215 -120.080046) (xy 446.553442 -120.126559) (xy 446.516225 -120.168096)
			(xy 446.473357 -120.203771) (xy 446.425751 -120.232825) (xy 446.374422 -120.254637) (xy 446.320465 -120.268743)
			(xy 446.265028 -120.274843) (xy 446.209294 -120.272806) (xy 446.154451 -120.262676) (xy 446.101667 -120.244669)
			(xy 446.052067 -120.219168) (xy 446.006709 -120.186717) (xy 445.96656 -120.148008) (xy 445.932474 -120.103865)
			(xy 445.905178 -120.05523) (xy 445.885255 -120.003139) (xy 445.873129 -119.948702) (xy 445.869058 -119.89308)
			(xy 430.14549 -119.89308) (xy 430.134615 -119.903956) (xy 430.087083 -119.940437) (xy 430.06137 -119.955818)
			(xy 430.049989 -119.962306) (xy 430.026606 -119.974123) (xy 430.014634 -119.97944) (xy 430.003284 -119.984237)
			(xy 429.980157 -119.992749) (xy 429.968406 -119.996458) (xy 429.9352 -120.006101) (xy 429.866834 -120.016436)
			(xy 429.832262 -120.017032) (xy 429.817812 -120.01701) (xy 429.788962 -120.015357) (xy 429.774604 -120.01373)
			(xy 429.771556 -120.013222) (xy 429.758308 -120.012817) (xy 429.732329 -120.01802) (xy 429.708563 -120.029731)
			(xy 429.68861 -120.047161) (xy 429.680878 -120.057926) (xy 429.674906 -120.067335) (xy 429.666838 -120.088103)
			(xy 429.664876 -120.099074) (xy 429.664368 -120.104662) (xy 429.610526 -121.365772) (xy 432.016408 -121.365772)
			(xy 432.016408 -120.502172) (xy 432.016898 -120.472188) (xy 432.024726 -120.412732) (xy 432.040247 -120.354807)
			(xy 432.063196 -120.299403) (xy 432.09318 -120.247469) (xy 432.129686 -120.199893) (xy 432.172091 -120.157488)
			(xy 432.219667 -120.120982) (xy 432.271601 -120.090998) (xy 432.327005 -120.068049) (xy 432.38493 -120.052528)
			(xy 432.444386 -120.0447) (xy 432.504354 -120.0447) (xy 432.56381 -120.052528) (xy 432.621735 -120.068049)
			(xy 432.677139 -120.090998) (xy 432.729073 -120.120982) (xy 432.776649 -120.157488) (xy 432.819054 -120.199893)
			(xy 432.85556 -120.247469) (xy 432.885544 -120.299403) (xy 432.908493 -120.354807) (xy 432.924014 -120.412732)
			(xy 432.931842 -120.472188) (xy 432.932332 -120.502172) (xy 432.932332 -121.365772) (xy 432.931842 -121.395756)
			(xy 432.924014 -121.455212) (xy 432.908493 -121.513137) (xy 432.885544 -121.568541) (xy 432.85556 -121.620475)
			(xy 432.819054 -121.668051) (xy 432.776649 -121.710456) (xy 432.729073 -121.746962) (xy 432.677139 -121.776946)
			(xy 432.621735 -121.799895) (xy 432.56381 -121.815416) (xy 432.504354 -121.823244) (xy 432.444386 -121.823244)
			(xy 432.38493 -121.815416) (xy 432.327005 -121.799895) (xy 432.271601 -121.776946) (xy 432.219667 -121.746962)
			(xy 432.172091 -121.710456) (xy 432.129686 -121.668051) (xy 432.09318 -121.620475) (xy 432.063196 -121.568541)
			(xy 432.040247 -121.513137) (xy 432.024726 -121.455212) (xy 432.016898 -121.395756) (xy 432.016408 -121.365772)
			(xy 429.610526 -121.365772) (xy 429.592232 -121.79427) (xy 429.592159 -121.802754) (xy 429.596965 -121.819015)
			(xy 429.606825 -121.832809) (xy 429.613568 -121.837958) (xy 429.660558 -121.871232) (xy 429.67783 -121.864628)
			(xy 429.688752 -121.860818) (xy 429.694086 -121.85904) (xy 429.69434 -121.85904) (xy 429.701706 -121.856754)
			(xy 429.73244 -121.848626) (xy 429.732948 -121.848626) (xy 429.739806 -121.847102) (xy 429.740314 -121.847102)
			(xy 429.76305 -121.842727) (xy 429.809111 -121.838019) (xy 429.832262 -121.837704) (xy 429.86225 -121.838171)
			(xy 429.921714 -121.845994) (xy 429.979647 -121.861513) (xy 430.03506 -121.88446) (xy 430.087003 -121.914444)
			(xy 430.134588 -121.950951) (xy 430.177001 -121.993357) (xy 430.213516 -122.040937) (xy 430.243508 -122.092875)
			(xy 430.266464 -122.148284) (xy 430.278191 -122.192034) (xy 437.750712 -122.192034) (xy 437.751195 -122.164664)
			(xy 437.759008 -122.110486) (xy 437.774493 -122.057983) (xy 437.797331 -122.008236) (xy 437.827052 -121.962268)
			(xy 437.844692 -121.941336) (xy 437.844946 -121.941082) (xy 437.850552 -121.934009) (xy 437.856786 -121.917082)
			(xy 437.857138 -121.908062) (xy 437.857138 -121.841006) (xy 437.85677 -121.83199) (xy 437.850529 -121.815074)
			(xy 437.844946 -121.807986) (xy 437.844692 -121.807986) (xy 437.844692 -121.807732) (xy 437.827086 -121.786772)
			(xy 437.797363 -121.740808) (xy 437.774517 -121.691066) (xy 437.75902 -121.638568) (xy 437.751189 -121.584394)
			(xy 437.751185 -121.529657) (xy 437.759009 -121.475482) (xy 437.774499 -121.422982) (xy 437.797338 -121.373237)
			(xy 437.827055 -121.327269) (xy 437.844692 -121.306336) (xy 437.844946 -121.306082) (xy 437.850552 -121.299009)
			(xy 437.856786 -121.282082) (xy 437.857138 -121.273062) (xy 437.857138 -121.206006) (xy 437.85677 -121.19699)
			(xy 437.850529 -121.180074) (xy 437.844946 -121.172986) (xy 437.844692 -121.172986) (xy 437.844692 -121.172732)
			(xy 437.827086 -121.151772) (xy 437.797363 -121.105808) (xy 437.774517 -121.056066) (xy 437.75902 -121.003568)
			(xy 437.751189 -120.949394) (xy 437.751185 -120.894657) (xy 437.759009 -120.840482) (xy 437.774499 -120.787982)
			(xy 437.797338 -120.738237) (xy 437.827055 -120.692269) (xy 437.844692 -120.671336) (xy 437.844946 -120.671082)
			(xy 437.850552 -120.664009) (xy 437.856786 -120.647082) (xy 437.857138 -120.638062) (xy 437.857138 -120.571006)
			(xy 437.85677 -120.56199) (xy 437.850529 -120.545074) (xy 437.844946 -120.537986) (xy 437.844692 -120.537986)
			(xy 437.844692 -120.537732) (xy 437.827053 -120.5168) (xy 437.797342 -120.470827) (xy 437.774506 -120.421079)
			(xy 437.759015 -120.368579) (xy 437.751186 -120.314403) (xy 437.750712 -120.287034) (xy 437.751198 -120.259783)
			(xy 437.758954 -120.205835) (xy 437.774309 -120.15354) (xy 437.796951 -120.103963) (xy 437.826417 -120.058113)
			(xy 437.862108 -120.016922) (xy 437.903299 -119.981231) (xy 437.949149 -119.951765) (xy 437.998726 -119.929123)
			(xy 438.051021 -119.913768) (xy 438.104969 -119.906012) (xy 438.159471 -119.906012) (xy 438.213419 -119.913768)
			(xy 438.265714 -119.929123) (xy 438.315291 -119.951765) (xy 438.361141 -119.981231) (xy 438.402332 -120.016922)
			(xy 438.438023 -120.058113) (xy 438.467489 -120.103963) (xy 438.490131 -120.15354) (xy 438.505486 -120.205835)
			(xy 438.513242 -120.259783) (xy 438.513728 -120.287034) (xy 438.513299 -120.314406) (xy 438.505475 -120.368587)
			(xy 438.489978 -120.421091) (xy 438.467128 -120.470838) (xy 438.452773 -120.493028) (xy 447.904106 -120.493028)
			(xy 447.908177 -120.437406) (xy 447.920303 -120.382969) (xy 447.940226 -120.330878) (xy 447.967522 -120.282243)
			(xy 448.001608 -120.2381) (xy 448.041757 -120.199391) (xy 448.087115 -120.16694) (xy 448.136715 -120.141439)
			(xy 448.189499 -120.123432) (xy 448.244342 -120.113302) (xy 448.300076 -120.111265) (xy 448.355513 -120.117365)
			(xy 448.40947 -120.131471) (xy 448.460799 -120.153283) (xy 448.508405 -120.182337) (xy 448.551273 -120.218012)
			(xy 448.58849 -120.259549) (xy 448.619263 -120.306062) (xy 448.642935 -120.356559) (xy 448.659003 -120.409966)
			(xy 448.667123 -120.465142) (xy 448.667632 -120.493028) (xy 448.667123 -120.520914) (xy 448.659003 -120.57609)
			(xy 448.642935 -120.629497) (xy 448.619263 -120.679994) (xy 448.58849 -120.726507) (xy 448.551273 -120.768044)
			(xy 448.522198 -120.79224) (xy 448.836032 -120.79224) (xy 448.840103 -120.736618) (xy 448.852229 -120.682181)
			(xy 448.872152 -120.63009) (xy 448.899448 -120.581455) (xy 448.933534 -120.537312) (xy 448.973683 -120.498603)
			(xy 449.019041 -120.466152) (xy 449.068641 -120.440651) (xy 449.121425 -120.422644) (xy 449.176268 -120.412514)
			(xy 449.232002 -120.410477) (xy 449.287439 -120.416577) (xy 449.341396 -120.430683) (xy 449.392725 -120.452495)
			(xy 449.440331 -120.481549) (xy 449.483199 -120.517224) (xy 449.520416 -120.558761) (xy 449.551189 -120.605274)
			(xy 449.574861 -120.655771) (xy 449.590929 -120.709178) (xy 449.599049 -120.764354) (xy 449.599558 -120.79224)
			(xy 450.991476 -120.79224) (xy 450.995547 -120.736618) (xy 451.007673 -120.682181) (xy 451.027596 -120.63009)
			(xy 451.054892 -120.581455) (xy 451.088978 -120.537312) (xy 451.129127 -120.498603) (xy 451.174485 -120.466152)
			(xy 451.224085 -120.440651) (xy 451.276869 -120.422644) (xy 451.331712 -120.412514) (xy 451.387446 -120.410477)
			(xy 451.442883 -120.416577) (xy 451.49684 -120.430683) (xy 451.548169 -120.452495) (xy 451.595775 -120.481549)
			(xy 451.638643 -120.517224) (xy 451.646777 -120.526302) (xy 454.293476 -120.526302) (xy 454.297547 -120.47068)
			(xy 454.309673 -120.416243) (xy 454.329596 -120.364152) (xy 454.356892 -120.315517) (xy 454.390978 -120.271374)
			(xy 454.431127 -120.232665) (xy 454.476485 -120.200214) (xy 454.526085 -120.174713) (xy 454.578869 -120.156706)
			(xy 454.633712 -120.146576) (xy 454.689446 -120.144539) (xy 454.744883 -120.150639) (xy 454.79884 -120.164745)
			(xy 454.850169 -120.186557) (xy 454.897775 -120.215611) (xy 454.940643 -120.251286) (xy 454.97786 -120.292823)
			(xy 455.008633 -120.339336) (xy 455.032305 -120.389833) (xy 455.048373 -120.44324) (xy 455.056493 -120.498416)
			(xy 455.057002 -120.526302) (xy 455.056493 -120.554188) (xy 455.048373 -120.609364) (xy 455.032305 -120.662771)
			(xy 455.008633 -120.713268) (xy 454.97786 -120.759781) (xy 454.940643 -120.801318) (xy 454.897775 -120.836993)
			(xy 454.850169 -120.866047) (xy 454.79884 -120.887859) (xy 454.744883 -120.901965) (xy 454.689446 -120.908065)
			(xy 454.633712 -120.906028) (xy 454.578869 -120.895898) (xy 454.526085 -120.877891) (xy 454.476485 -120.85239)
			(xy 454.431127 -120.819939) (xy 454.390978 -120.78123) (xy 454.356892 -120.737087) (xy 454.329596 -120.688452)
			(xy 454.309673 -120.636361) (xy 454.297547 -120.581924) (xy 454.293476 -120.526302) (xy 451.646777 -120.526302)
			(xy 451.67586 -120.558761) (xy 451.706633 -120.605274) (xy 451.730305 -120.655771) (xy 451.746373 -120.709178)
			(xy 451.754493 -120.764354) (xy 451.755002 -120.79224) (xy 451.754493 -120.820126) (xy 451.746373 -120.875302)
			(xy 451.730305 -120.928709) (xy 451.706633 -120.979206) (xy 451.67586 -121.025719) (xy 451.638643 -121.067256)
			(xy 451.595775 -121.102931) (xy 451.548169 -121.131985) (xy 451.49684 -121.153797) (xy 451.442883 -121.167903)
			(xy 451.387446 -121.174003) (xy 451.331712 -121.171966) (xy 451.276869 -121.161836) (xy 451.224085 -121.143829)
			(xy 451.174485 -121.118328) (xy 451.129127 -121.085877) (xy 451.088978 -121.047168) (xy 451.054892 -121.003025)
			(xy 451.027596 -120.95439) (xy 451.007673 -120.902299) (xy 450.995547 -120.847862) (xy 450.991476 -120.79224)
			(xy 449.599558 -120.79224) (xy 449.599049 -120.820126) (xy 449.590929 -120.875302) (xy 449.574861 -120.928709)
			(xy 449.551189 -120.979206) (xy 449.520416 -121.025719) (xy 449.483199 -121.067256) (xy 449.440331 -121.102931)
			(xy 449.392725 -121.131985) (xy 449.341396 -121.153797) (xy 449.287439 -121.167903) (xy 449.232002 -121.174003)
			(xy 449.176268 -121.171966) (xy 449.121425 -121.161836) (xy 449.068641 -121.143829) (xy 449.019041 -121.118328)
			(xy 448.973683 -121.085877) (xy 448.933534 -121.047168) (xy 448.899448 -121.003025) (xy 448.872152 -120.95439)
			(xy 448.852229 -120.902299) (xy 448.840103 -120.847862) (xy 448.836032 -120.79224) (xy 448.522198 -120.79224)
			(xy 448.508405 -120.803719) (xy 448.460799 -120.832773) (xy 448.40947 -120.854585) (xy 448.355513 -120.868691)
			(xy 448.300076 -120.874791) (xy 448.244342 -120.872754) (xy 448.189499 -120.862624) (xy 448.136715 -120.844617)
			(xy 448.087115 -120.819116) (xy 448.041757 -120.786665) (xy 448.001608 -120.747956) (xy 447.967522 -120.703813)
			(xy 447.940226 -120.655178) (xy 447.920303 -120.603087) (xy 447.908177 -120.54865) (xy 447.904106 -120.493028)
			(xy 438.452773 -120.493028) (xy 438.437394 -120.516802) (xy 438.419748 -120.537732) (xy 438.419494 -120.537986)
			(xy 438.413906 -120.545072) (xy 438.407661 -120.561989) (xy 438.407302 -120.571006) (xy 438.407302 -120.638062)
			(xy 438.407677 -120.647077) (xy 438.413912 -120.663994) (xy 438.419494 -120.671082) (xy 438.419748 -120.671082)
			(xy 438.419748 -120.671336) (xy 438.437423 -120.692241) (xy 438.467148 -120.738213) (xy 438.489993 -120.787964)
			(xy 438.505488 -120.84047) (xy 438.513314 -120.894653) (xy 438.51331 -120.949398) (xy 438.505477 -121.00358)
			(xy 438.489975 -121.056084) (xy 438.467124 -121.105832) (xy 438.437392 -121.1518) (xy 438.419748 -121.172732)
			(xy 438.419494 -121.172986) (xy 438.413906 -121.180072) (xy 438.407661 -121.196989) (xy 438.407591 -121.198756)
			(xy 438.785417 -121.198756) (xy 438.785417 -121.144244) (xy 438.793175 -121.090287) (xy 438.808533 -121.037983)
			(xy 438.831178 -120.988398) (xy 438.86065 -120.942539) (xy 438.896348 -120.901342) (xy 438.937546 -120.865645)
			(xy 438.983405 -120.836174) (xy 439.032991 -120.81353) (xy 439.085295 -120.798173) (xy 439.139252 -120.790416)
			(xy 439.166508 -120.789954) (xy 439.193879 -120.790402) (xy 439.248059 -120.798222) (xy 439.300563 -120.813715)
			(xy 439.35031 -120.836561) (xy 439.396275 -120.86629) (xy 439.417206 -120.883934) (xy 439.41746 -120.884188)
			(xy 439.424555 -120.889763) (xy 439.441465 -120.896017) (xy 439.45048 -120.89638) (xy 439.517536 -120.89638)
			(xy 439.526555 -120.896044) (xy 439.543472 -120.889782) (xy 439.550556 -120.884188) (xy 439.550556 -120.883934)
			(xy 439.55081 -120.883934) (xy 439.571732 -120.866282) (xy 439.617707 -120.836571) (xy 439.667457 -120.813737)
			(xy 439.71996 -120.798249) (xy 439.774138 -120.790425) (xy 439.801508 -120.789954) (xy 439.828756 -120.790517)
			(xy 439.882698 -120.798273) (xy 439.934986 -120.813628) (xy 439.984557 -120.836267) (xy 440.030402 -120.865731)
			(xy 440.071587 -120.901418) (xy 440.107274 -120.942604) (xy 440.136737 -120.98845) (xy 440.159375 -121.038021)
			(xy 440.174728 -121.09031) (xy 440.182484 -121.144252) (xy 440.182484 -121.198748) (xy 440.174728 -121.25269)
			(xy 440.159375 -121.304979) (xy 440.136737 -121.35455) (xy 440.107274 -121.400396) (xy 440.071587 -121.441582)
			(xy 440.030402 -121.477269) (xy 439.984557 -121.506733) (xy 439.934986 -121.529372) (xy 439.882698 -121.544727)
			(xy 439.828756 -121.552483) (xy 439.801508 -121.55297) (xy 439.774138 -121.552507) (xy 439.719958 -121.544689)
			(xy 439.667455 -121.5292) (xy 439.617708 -121.506357) (xy 439.571741 -121.476632) (xy 439.55081 -121.45899)
			(xy 439.550556 -121.458736) (xy 439.543463 -121.453159) (xy 439.526551 -121.446908) (xy 439.517536 -121.446544)
			(xy 439.45048 -121.446544) (xy 439.441461 -121.446882) (xy 439.424544 -121.453142) (xy 439.41746 -121.458736)
			(xy 439.41746 -121.45899) (xy 439.417206 -121.45899) (xy 439.396281 -121.476638) (xy 439.350307 -121.506349)
			(xy 439.300557 -121.529183) (xy 439.248055 -121.544672) (xy 439.193878 -121.552498) (xy 439.166508 -121.55297)
			(xy 439.139252 -121.552584) (xy 439.085295 -121.544827) (xy 439.032991 -121.52947) (xy 438.983405 -121.506826)
			(xy 438.937546 -121.477355) (xy 438.896348 -121.441658) (xy 438.86065 -121.400461) (xy 438.831178 -121.354602)
			(xy 438.808533 -121.305017) (xy 438.793175 -121.252713) (xy 438.785417 -121.198756) (xy 438.407591 -121.198756)
			(xy 438.407302 -121.206006) (xy 438.407302 -121.273062) (xy 438.407677 -121.282077) (xy 438.413912 -121.298994)
			(xy 438.419494 -121.306082) (xy 438.419748 -121.306082) (xy 438.419748 -121.306336) (xy 438.437423 -121.327241)
			(xy 438.467148 -121.373213) (xy 438.489993 -121.422964) (xy 438.505488 -121.47547) (xy 438.513314 -121.529653)
			(xy 438.51331 -121.584398) (xy 438.505477 -121.63858) (xy 438.489975 -121.691084) (xy 438.476179 -121.721118)
			(xy 440.2963 -121.721118) (xy 440.296777 -121.693748) (xy 440.304592 -121.63957) (xy 440.320079 -121.587067)
			(xy 440.342918 -121.537319) (xy 440.37264 -121.491352) (xy 440.39028 -121.47042) (xy 440.390534 -121.470166)
			(xy 440.396103 -121.463067) (xy 440.402359 -121.44616) (xy 440.402726 -121.437146) (xy 440.402726 -121.37009)
			(xy 440.402368 -121.361073) (xy 440.39612 -121.344157) (xy 440.390534 -121.33707) (xy 440.39028 -121.33707)
			(xy 440.39028 -121.336816) (xy 440.372632 -121.315891) (xy 440.342922 -121.269916) (xy 440.320088 -121.220167)
			(xy 440.304599 -121.167665) (xy 440.296773 -121.113488) (xy 440.2963 -121.086118) (xy 440.296772 -121.058865)
			(xy 440.304527 -121.004914) (xy 440.319881 -120.952616) (xy 440.342522 -120.903035) (xy 440.371989 -120.857182)
			(xy 440.407682 -120.815989) (xy 440.448874 -120.780295) (xy 440.494727 -120.750827) (xy 440.544307 -120.728184)
			(xy 440.596604 -120.712829) (xy 440.650555 -120.705073) (xy 440.677808 -120.70461) (xy 440.704687 -120.705028)
			(xy 440.757911 -120.712581) (xy 440.809546 -120.727536) (xy 440.858568 -120.749596) (xy 440.904005 -120.778325)
			(xy 440.944956 -120.813151) (xy 440.980608 -120.853384) (xy 440.995816 -120.875552) (xy 441.001846 -120.883889)
			(xy 441.019046 -120.895152) (xy 441.02909 -120.897396) (xy 441.111386 -120.912636) (xy 441.131452 -120.908064)
			(xy 441.139834 -120.901968) (xy 441.164289 -120.885159) (xy 441.217296 -120.858489) (xy 441.273792 -120.840343)
			(xy 441.332415 -120.831158) (xy 441.362084 -120.830594) (xy 441.389337 -120.83107) (xy 441.443287 -120.838825)
			(xy 441.495585 -120.854179) (xy 441.545165 -120.87682) (xy 441.591018 -120.906286) (xy 441.632211 -120.941979)
			(xy 441.667905 -120.98317) (xy 441.697373 -121.029023) (xy 441.720016 -121.078602) (xy 441.735372 -121.130899)
			(xy 441.743129 -121.184849) (xy 441.743592 -121.212102) (xy 441.743141 -121.238772) (xy 445.884298 -121.238772)
			(xy 445.888369 -121.18315) (xy 445.900495 -121.128713) (xy 445.920418 -121.076622) (xy 445.947714 -121.027987)
			(xy 445.9818 -120.983844) (xy 446.021949 -120.945135) (xy 446.067307 -120.912684) (xy 446.116907 -120.887183)
			(xy 446.169691 -120.869176) (xy 446.224534 -120.859046) (xy 446.280268 -120.857009) (xy 446.335705 -120.863109)
			(xy 446.389662 -120.877215) (xy 446.440991 -120.899027) (xy 446.488597 -120.928081) (xy 446.531465 -120.963756)
			(xy 446.568682 -121.005293) (xy 446.599455 -121.051806) (xy 446.623127 -121.102303) (xy 446.639195 -121.15571)
			(xy 446.647315 -121.210886) (xy 446.647824 -121.238772) (xy 446.647315 -121.266658) (xy 446.639195 -121.321834)
			(xy 446.623127 -121.375241) (xy 446.599455 -121.425738) (xy 446.568682 -121.472251) (xy 446.531465 -121.513788)
			(xy 446.488597 -121.549463) (xy 446.440991 -121.578517) (xy 446.389662 -121.600329) (xy 446.335705 -121.614435)
			(xy 446.280268 -121.620535) (xy 446.224534 -121.618498) (xy 446.169691 -121.608368) (xy 446.116907 -121.590361)
			(xy 446.067307 -121.56486) (xy 446.021949 -121.532409) (xy 445.9818 -121.4937) (xy 445.947714 -121.449557)
			(xy 445.920418 -121.400922) (xy 445.900495 -121.348831) (xy 445.888369 -121.294394) (xy 445.884298 -121.238772)
			(xy 441.743141 -121.238772) (xy 441.743129 -121.239472) (xy 441.735311 -121.293652) (xy 441.719821 -121.346155)
			(xy 441.696979 -121.395902) (xy 441.667253 -121.441868) (xy 441.649612 -121.4628) (xy 441.649358 -121.463054)
			(xy 441.643779 -121.470146) (xy 441.637529 -121.487059) (xy 441.637166 -121.496074) (xy 441.637166 -121.56313)
			(xy 441.637516 -121.572147) (xy 441.643769 -121.589064) (xy 441.649358 -121.59615) (xy 441.649612 -121.59615)
			(xy 441.649612 -121.596404) (xy 441.667268 -121.617322) (xy 441.696977 -121.663299) (xy 441.71981 -121.71305)
			(xy 441.735297 -121.765554) (xy 441.74312 -121.819732) (xy 441.743592 -121.847102) (xy 441.743146 -121.874356)
			(xy 441.735389 -121.928308) (xy 441.720032 -121.980607) (xy 441.697388 -122.030188) (xy 441.667918 -122.076042)
			(xy 441.632223 -122.117235) (xy 441.591028 -122.152929) (xy 441.545173 -122.182396) (xy 441.49559 -122.205038)
			(xy 441.44329 -122.220393) (xy 441.389338 -122.228148) (xy 441.362084 -122.22861) (xy 441.335206 -122.228189)
			(xy 441.281982 -122.220635) (xy 441.230347 -122.20568) (xy 441.181325 -122.18362) (xy 441.135888 -122.154893)
			(xy 441.094937 -122.120067) (xy 441.059284 -122.079835) (xy 441.044076 -122.057668) (xy 441.038004 -122.049367)
			(xy 441.020834 -122.038085) (xy 441.010802 -122.035824) (xy 440.928506 -122.020584) (xy 440.90844 -122.025156)
			(xy 440.900058 -122.031252) (xy 440.875599 -122.048055) (xy 440.822594 -122.074728) (xy 440.7661 -122.092877)
			(xy 440.707477 -122.102062) (xy 440.677808 -122.102626) (xy 440.650558 -122.102115) (xy 440.596612 -122.09436)
			(xy 440.544319 -122.079007) (xy 440.494743 -122.056368) (xy 440.448893 -122.026904) (xy 440.407703 -121.991215)
			(xy 440.372012 -121.950028) (xy 440.342545 -121.90418) (xy 440.319902 -121.854606) (xy 440.304546 -121.802314)
			(xy 440.296787 -121.748368) (xy 440.2963 -121.721118) (xy 438.476179 -121.721118) (xy 438.467124 -121.740832)
			(xy 438.437392 -121.7868) (xy 438.419748 -121.807732) (xy 438.419494 -121.807986) (xy 438.413906 -121.815072)
			(xy 438.407661 -121.831989) (xy 438.407302 -121.841006) (xy 438.407302 -121.908062) (xy 438.407677 -121.917077)
			(xy 438.413912 -121.933994) (xy 438.419494 -121.941082) (xy 438.419748 -121.941082) (xy 438.419748 -121.941336)
			(xy 438.437362 -121.962288) (xy 438.46708 -122.008255) (xy 438.489921 -122.057997) (xy 438.505418 -122.110493)
			(xy 438.513251 -122.164666) (xy 438.513728 -122.192034) (xy 438.513242 -122.219285) (xy 438.505486 -122.273233)
			(xy 438.490131 -122.325528) (xy 438.467489 -122.375105) (xy 438.438023 -122.420955) (xy 438.402332 -122.462146)
			(xy 438.361141 -122.497837) (xy 438.315291 -122.527303) (xy 438.265714 -122.549945) (xy 438.213419 -122.5653)
			(xy 438.159471 -122.573056) (xy 438.104969 -122.573056) (xy 438.051021 -122.5653) (xy 437.998726 -122.549945)
			(xy 437.949149 -122.527303) (xy 437.903299 -122.497837) (xy 437.862108 -122.462146) (xy 437.826417 -122.420955)
			(xy 437.796951 -122.375105) (xy 437.774309 -122.325528) (xy 437.758954 -122.273233) (xy 437.751198 -122.219285)
			(xy 437.750712 -122.192034) (xy 430.278191 -122.192034) (xy 430.281992 -122.206216) (xy 430.289825 -122.265678)
			(xy 430.290224 -122.295666) (xy 430.290224 -123.159266) (xy 430.289757 -123.189252) (xy 430.281933 -123.248712)
			(xy 430.266413 -123.306642) (xy 430.243465 -123.36205) (xy 430.242023 -123.364548) (xy 442.364398 -123.364548)
			(xy 442.364398 -123.310052) (xy 442.372153 -123.25611) (xy 442.387506 -123.20382) (xy 442.410144 -123.154248)
			(xy 442.439605 -123.108401) (xy 442.475292 -123.067214) (xy 442.516476 -123.031525) (xy 442.56232 -123.002059)
			(xy 442.61189 -122.979417) (xy 442.664178 -122.96406) (xy 442.71812 -122.9563) (xy 442.745368 -122.955812)
			(xy 442.772738 -122.956294) (xy 442.826916 -122.964107) (xy 442.879419 -122.979593) (xy 442.929166 -123.002431)
			(xy 442.975134 -123.032152) (xy 442.996066 -123.049792) (xy 442.99632 -123.050046) (xy 443.003393 -123.055653)
			(xy 443.02032 -123.061886) (xy 443.02934 -123.062238) (xy 443.096396 -123.062238) (xy 443.105412 -123.061871)
			(xy 443.122328 -123.055629) (xy 443.129416 -123.050046) (xy 443.129416 -123.049792) (xy 443.12967 -123.049792)
			(xy 443.150603 -123.032151) (xy 443.196571 -123.002427) (xy 443.246317 -122.979581) (xy 443.298819 -122.964085)
			(xy 443.352997 -122.956256) (xy 443.407739 -122.956256) (xy 443.461917 -122.964085) (xy 443.514419 -122.979581)
			(xy 443.564165 -123.002427) (xy 443.610133 -123.032151) (xy 443.631066 -123.049792) (xy 443.63132 -123.050046)
			(xy 443.638393 -123.055653) (xy 443.65532 -123.061886) (xy 443.66434 -123.062238) (xy 443.731396 -123.062238)
			(xy 443.740412 -123.061871) (xy 443.757328 -123.055629) (xy 443.764416 -123.050046) (xy 443.764416 -123.049792)
			(xy 443.76467 -123.049792) (xy 443.785602 -123.032152) (xy 443.831575 -123.002441) (xy 443.881322 -122.979605)
			(xy 443.933823 -122.964114) (xy 443.987999 -122.956286) (xy 444.015368 -122.955812) (xy 444.042624 -122.956233)
			(xy 444.096581 -122.963986) (xy 444.148886 -122.97934) (xy 444.198472 -123.001982) (xy 444.244332 -123.031451)
			(xy 444.285531 -123.067147) (xy 444.32123 -123.108342) (xy 444.350702 -123.154199) (xy 444.373348 -123.203784)
			(xy 444.388707 -123.256088) (xy 444.396465 -123.310044) (xy 444.396465 -123.364556) (xy 444.388707 -123.418512)
			(xy 444.373348 -123.470816) (xy 444.350702 -123.520401) (xy 444.32123 -123.566258) (xy 444.285531 -123.607453)
			(xy 444.244332 -123.643149) (xy 444.198472 -123.672618) (xy 444.148886 -123.69526) (xy 444.096581 -123.710614)
			(xy 444.042624 -123.718367) (xy 444.015368 -123.718828) (xy 443.987996 -123.718398) (xy 443.933815 -123.710574)
			(xy 443.881311 -123.695078) (xy 443.831564 -123.672227) (xy 443.7856 -123.642494) (xy 443.76467 -123.624848)
			(xy 443.764416 -123.624594) (xy 443.75733 -123.619007) (xy 443.740413 -123.612761) (xy 443.731396 -123.612402)
			(xy 443.66434 -123.612402) (xy 443.655325 -123.612778) (xy 443.638408 -123.619012) (xy 443.63132 -123.624594)
			(xy 443.631066 -123.624848) (xy 443.610133 -123.642489) (xy 443.564165 -123.672213) (xy 443.514419 -123.695059)
			(xy 443.461917 -123.710555) (xy 443.407739 -123.718384) (xy 443.352997 -123.718384) (xy 443.298819 -123.710555)
			(xy 443.246317 -123.695059) (xy 443.196571 -123.672213) (xy 443.150603 -123.642489) (xy 443.12967 -123.624848)
			(xy 443.129416 -123.624594) (xy 443.12233 -123.619007) (xy 443.105413 -123.612761) (xy 443.096396 -123.612402)
			(xy 443.02934 -123.612402) (xy 443.020325 -123.612778) (xy 443.003408 -123.619012) (xy 442.99632 -123.624594)
			(xy 442.99632 -123.624848) (xy 442.996066 -123.624848) (xy 442.975113 -123.642462) (xy 442.929147 -123.672179)
			(xy 442.879405 -123.695021) (xy 442.826908 -123.710518) (xy 442.772736 -123.718351) (xy 442.745368 -123.718828)
			(xy 442.71812 -123.7183) (xy 442.664178 -123.71054) (xy 442.61189 -123.695183) (xy 442.56232 -123.672541)
			(xy 442.516476 -123.643075) (xy 442.475292 -123.607386) (xy 442.439605 -123.566199) (xy 442.410144 -123.520352)
			(xy 442.387506 -123.47078) (xy 442.372153 -123.41849) (xy 442.364398 -123.364548) (xy 430.242023 -123.364548)
			(xy 430.21348 -123.413988) (xy 430.176971 -123.461567) (xy 430.134564 -123.503974) (xy 430.086985 -123.540482)
			(xy 430.035046 -123.570467) (xy 429.979638 -123.593415) (xy 429.921708 -123.608933) (xy 429.862248 -123.616757)
			(xy 429.832262 -123.617228) (xy 429.832008 -123.617228) (xy 429.818961 -123.617111) (xy 429.79291 -123.615584)
			(xy 429.779938 -123.61418) (xy 429.75039 -123.61029) (xy 429.692567 -123.595851) (xy 429.637099 -123.57405)
			(xy 429.610774 -123.560078) (xy 429.605694 -123.557284) (xy 429.589946 -123.552966) (xy 429.589692 -123.552966)
			(xy 429.583342 -123.551188) (xy 429.571404 -123.551188) (xy 429.55083 -123.556014) (xy 429.54152 -123.559298)
			(xy 429.526174 -123.571687) (xy 429.51663 -123.588947) (xy 429.515016 -123.598686) (xy 429.456751 -124.965714)
			(xy 432.016408 -124.965714) (xy 432.016408 -124.102114) (xy 432.016898 -124.07213) (xy 432.024726 -124.012674)
			(xy 432.040247 -123.954749) (xy 432.063196 -123.899345) (xy 432.09318 -123.847411) (xy 432.129686 -123.799835)
			(xy 432.172091 -123.75743) (xy 432.219667 -123.720924) (xy 432.271601 -123.69094) (xy 432.327005 -123.667991)
			(xy 432.38493 -123.65247) (xy 432.444386 -123.644642) (xy 432.504354 -123.644642) (xy 432.56381 -123.65247)
			(xy 432.621735 -123.667991) (xy 432.677139 -123.69094) (xy 432.729073 -123.720924) (xy 432.776649 -123.75743)
			(xy 432.819054 -123.799835) (xy 432.836238 -123.82223) (xy 445.742305 -123.82223) (xy 445.742308 -123.767732)
			(xy 445.750066 -123.713789) (xy 445.765422 -123.6615) (xy 445.788064 -123.611928) (xy 445.81753 -123.566082)
			(xy 445.85322 -123.524897) (xy 445.894408 -123.48921) (xy 445.940256 -123.459748) (xy 445.98983 -123.437111)
			(xy 446.042121 -123.421759) (xy 446.096065 -123.414005) (xy 446.123314 -123.41352) (xy 446.123822 -123.41352)
			(xy 446.134194 -123.4136) (xy 446.154906 -123.414744) (xy 446.165224 -123.415806) (xy 446.179773 -123.416855)
			(xy 446.208463 -123.411663) (xy 446.23452 -123.398583) (xy 446.255824 -123.378678) (xy 446.270643 -123.353569)
			(xy 446.27777 -123.325298) (xy 446.276627 -123.296165) (xy 446.272412 -123.282202) (xy 446.263052 -123.252595)
			(xy 446.252974 -123.191327) (xy 446.252346 -123.160282) (xy 446.252346 -123.160028) (xy 446.252825 -123.132772)
			(xy 446.260579 -123.078814) (xy 446.275934 -123.026509) (xy 446.298576 -122.976922) (xy 446.328045 -122.931062)
			(xy 446.363741 -122.889863) (xy 446.404937 -122.854164) (xy 446.450795 -122.824691) (xy 446.50038 -122.802045)
			(xy 446.552684 -122.786686) (xy 446.606641 -122.778927) (xy 446.661153 -122.778927) (xy 446.71511 -122.786684)
			(xy 446.767414 -122.802042) (xy 446.816999 -122.824688) (xy 446.862857 -122.85416) (xy 446.904054 -122.889859)
			(xy 446.939751 -122.931057) (xy 446.969221 -122.976916) (xy 446.991864 -123.026503) (xy 447.007219 -123.078808)
			(xy 447.014975 -123.132765) (xy 447.014971 -123.187277) (xy 447.00721 -123.241234) (xy 446.991849 -123.293537)
			(xy 446.9692 -123.343121) (xy 446.939725 -123.388977) (xy 446.904024 -123.430172) (xy 446.862823 -123.465866)
			(xy 446.816962 -123.495332) (xy 446.767374 -123.517972) (xy 446.715068 -123.533325) (xy 446.66111 -123.541076)
			(xy 446.633854 -123.541536) (xy 446.633346 -123.541536) (xy 446.622974 -123.541459) (xy 446.602262 -123.540313)
			(xy 446.591944 -123.53925) (xy 446.577396 -123.53823) (xy 446.548715 -123.543427) (xy 446.522667 -123.556507)
			(xy 446.501368 -123.576405) (xy 446.48655 -123.601505) (xy 446.479417 -123.629767) (xy 446.480549 -123.658893)
			(xy 446.484756 -123.672854) (xy 446.494108 -123.702463) (xy 446.504191 -123.763729) (xy 446.504822 -123.794774)
			(xy 446.504822 -123.795028) (xy 446.504292 -123.822277) (xy 446.496532 -123.87622) (xy 446.481174 -123.928509)
			(xy 446.458532 -123.978081) (xy 446.429065 -124.023925) (xy 446.393373 -124.06511) (xy 446.352184 -124.100795)
			(xy 446.306335 -124.130256) (xy 446.256761 -124.152892) (xy 446.204469 -124.168243) (xy 446.150526 -124.175995)
			(xy 446.096028 -124.175992) (xy 446.042085 -124.168233) (xy 445.989795 -124.152876) (xy 445.940224 -124.130234)
			(xy 445.894379 -124.100767) (xy 445.853194 -124.065077) (xy 445.817507 -124.023888) (xy 445.788046 -123.97804)
			(xy 445.765409 -123.928465) (xy 445.750058 -123.876174) (xy 445.742305 -123.82223) (xy 432.836238 -123.82223)
			(xy 432.85556 -123.847411) (xy 432.885544 -123.899345) (xy 432.908493 -123.954749) (xy 432.924014 -124.012674)
			(xy 432.931842 -124.07213) (xy 432.932332 -124.102114) (xy 432.932332 -124.215144) (xy 442.906656 -124.215144)
			(xy 442.910727 -124.159522) (xy 442.922853 -124.105085) (xy 442.942776 -124.052994) (xy 442.970072 -124.004359)
			(xy 443.004158 -123.960216) (xy 443.044307 -123.921507) (xy 443.089665 -123.889056) (xy 443.139265 -123.863555)
			(xy 443.192049 -123.845548) (xy 443.246892 -123.835418) (xy 443.302626 -123.833381) (xy 443.358063 -123.839481)
			(xy 443.41202 -123.853587) (xy 443.463349 -123.875399) (xy 443.510955 -123.904453) (xy 443.553823 -123.940128)
			(xy 443.59104 -123.981665) (xy 443.621813 -124.028178) (xy 443.645485 -124.078675) (xy 443.661553 -124.132082)
			(xy 443.669673 -124.187258) (xy 443.670182 -124.215144) (xy 443.669673 -124.24303) (xy 443.661553 -124.298206)
			(xy 443.645485 -124.351613) (xy 443.621813 -124.40211) (xy 443.59104 -124.448623) (xy 443.553823 -124.49016)
			(xy 443.510955 -124.525835) (xy 443.463349 -124.554889) (xy 443.41202 -124.576701) (xy 443.358063 -124.590807)
			(xy 443.302626 -124.596907) (xy 443.246892 -124.59487) (xy 443.192049 -124.58474) (xy 443.139265 -124.566733)
			(xy 443.089665 -124.541232) (xy 443.044307 -124.508781) (xy 443.004158 -124.470072) (xy 442.970072 -124.425929)
			(xy 442.942776 -124.377294) (xy 442.922853 -124.325203) (xy 442.910727 -124.270766) (xy 442.906656 -124.215144)
			(xy 432.932332 -124.215144) (xy 432.932332 -124.640594) (xy 449.232272 -124.640594) (xy 449.236343 -124.584972)
			(xy 449.248469 -124.530535) (xy 449.268392 -124.478444) (xy 449.295688 -124.429809) (xy 449.329774 -124.385666)
			(xy 449.369923 -124.346957) (xy 449.415281 -124.314506) (xy 449.464881 -124.289005) (xy 449.517665 -124.270998)
			(xy 449.572508 -124.260868) (xy 449.628242 -124.258831) (xy 449.683679 -124.264931) (xy 449.737636 -124.279037)
			(xy 449.788965 -124.300849) (xy 449.836571 -124.329903) (xy 449.879439 -124.365578) (xy 449.916656 -124.407115)
			(xy 449.947429 -124.453628) (xy 449.971101 -124.504125) (xy 449.987169 -124.557532) (xy 449.995289 -124.612708)
			(xy 449.995798 -124.640594) (xy 449.995289 -124.66848) (xy 449.987169 -124.723656) (xy 449.971101 -124.777063)
			(xy 449.947429 -124.82756) (xy 449.916656 -124.874073) (xy 449.879439 -124.91561) (xy 449.836571 -124.951285)
			(xy 449.788965 -124.980339) (xy 449.737636 -125.002151) (xy 449.683679 -125.016257) (xy 449.628242 -125.022357)
			(xy 449.572508 -125.02032) (xy 449.517665 -125.01019) (xy 449.464881 -124.992183) (xy 449.415281 -124.966682)
			(xy 449.369923 -124.934231) (xy 449.329774 -124.895522) (xy 449.295688 -124.851379) (xy 449.268392 -124.802744)
			(xy 449.248469 -124.750653) (xy 449.236343 -124.696216) (xy 449.232272 -124.640594) (xy 432.932332 -124.640594)
			(xy 432.932332 -124.965714) (xy 432.931842 -124.995698) (xy 432.924014 -125.055154) (xy 432.908493 -125.113079)
			(xy 432.885544 -125.168483) (xy 432.85556 -125.220417) (xy 432.819054 -125.267993) (xy 432.776649 -125.310398)
			(xy 432.729073 -125.346904) (xy 432.677139 -125.376888) (xy 432.621735 -125.399837) (xy 432.56381 -125.415358)
			(xy 432.504354 -125.423186) (xy 432.444386 -125.423186) (xy 432.38493 -125.415358) (xy 432.327005 -125.399837)
			(xy 432.271601 -125.376888) (xy 432.219667 -125.346904) (xy 432.172091 -125.310398) (xy 432.129686 -125.267993)
			(xy 432.09318 -125.220417) (xy 432.063196 -125.168483) (xy 432.040247 -125.113079) (xy 432.024726 -125.055154)
			(xy 432.016898 -124.995698) (xy 432.016408 -124.965714) (xy 429.456751 -124.965714) (xy 429.41729 -125.891544)
			(xy 443.47511 -125.891544) (xy 443.475537 -125.865229) (xy 443.48278 -125.813098) (xy 443.497106 -125.762455)
			(xy 443.518246 -125.714256) (xy 443.5458 -125.669413) (xy 443.579245 -125.628775) (xy 443.5983 -125.61062)
			(xy 443.605695 -125.603093) (xy 443.614223 -125.583817) (xy 443.61481 -125.573282) (xy 443.61481 -125.498606)
			(xy 443.614288 -125.488056) (xy 443.605748 -125.46876) (xy 443.5983 -125.461268) (xy 443.579236 -125.443121)
			(xy 443.54578 -125.402489) (xy 443.518222 -125.357647) (xy 443.497085 -125.309445) (xy 443.482769 -125.258796)
			(xy 443.475547 -125.206661) (xy 443.47511 -125.180344) (xy 443.475596 -125.153093) (xy 443.483352 -125.099145)
			(xy 443.498707 -125.04685) (xy 443.521349 -124.997273) (xy 443.550815 -124.951423) (xy 443.586506 -124.910232)
			(xy 443.627697 -124.874541) (xy 443.673547 -124.845075) (xy 443.723124 -124.822433) (xy 443.775419 -124.807078)
			(xy 443.829367 -124.799322) (xy 443.883869 -124.799322) (xy 443.937817 -124.807078) (xy 443.990112 -124.822433)
			(xy 444.039689 -124.845075) (xy 444.085539 -124.874541) (xy 444.12673 -124.910232) (xy 444.162421 -124.951423)
			(xy 444.191887 -124.997273) (xy 444.214529 -125.04685) (xy 444.229884 -125.099145) (xy 444.23764 -125.153093)
			(xy 444.238126 -125.180344) (xy 444.23768 -125.206659) (xy 444.230439 -125.258788) (xy 444.216115 -125.30943)
			(xy 444.194979 -125.357629) (xy 444.16743 -125.402472) (xy 444.133989 -125.443111) (xy 444.114936 -125.461268)
			(xy 444.107552 -125.468804) (xy 444.099016 -125.488073) (xy 444.098426 -125.498606) (xy 444.098426 -125.573282)
			(xy 444.098944 -125.583833) (xy 444.107486 -125.603129) (xy 444.114936 -125.61062) (xy 444.134001 -125.628766)
			(xy 444.167456 -125.669398) (xy 444.195013 -125.714241) (xy 444.216149 -125.762444) (xy 444.230465 -125.813092)
			(xy 444.237688 -125.865227) (xy 444.238126 -125.891544) (xy 444.23764 -125.918795) (xy 444.229884 -125.972743)
			(xy 444.214529 -126.025038) (xy 444.191887 -126.074615) (xy 444.162421 -126.120465) (xy 444.12673 -126.161656)
			(xy 444.085539 -126.197347) (xy 444.039689 -126.226813) (xy 443.990112 -126.249455) (xy 443.937817 -126.26481)
			(xy 443.883869 -126.272566) (xy 443.829367 -126.272566) (xy 443.775419 -126.26481) (xy 443.723124 -126.249455)
			(xy 443.673547 -126.226813) (xy 443.627697 -126.197347) (xy 443.586506 -126.161656) (xy 443.550815 -126.120465)
			(xy 443.521349 -126.074615) (xy 443.498707 -126.025038) (xy 443.483352 -125.972743) (xy 443.475596 -125.918795)
			(xy 443.47511 -125.891544) (xy 429.41729 -125.891544) (xy 429.367188 -127.067056) (xy 429.273208 -129.27584)
			(xy 429.273171 -129.284534) (xy 429.278244 -129.30115) (xy 429.283114 -129.308352) (xy 429.30826 -129.342134)
			(xy 429.317404 -129.345436) (xy 429.343502 -129.354511) (xy 429.392975 -129.379116) (xy 429.415956 -129.394458)
			(xy 429.440812 -129.412465) (xy 429.48497 -129.455087) (xy 429.50384 -129.479294) (xy 429.50892 -129.486406)
			(xy 429.531018 -129.501138) (xy 429.534969 -129.503571) (xy 429.543528 -129.507152) (xy 429.548036 -129.50825)
			(xy 429.569372 -129.513076) (xy 429.580802 -129.514346) (xy 429.605186 -129.507742) (xy 429.610774 -129.504694)
			(xy 429.620653 -129.49931) (xy 429.640855 -129.489399) (xy 429.65116 -129.484882) (xy 429.679878 -129.473082)
			(xy 429.7397 -129.456461) (xy 429.801218 -129.448071) (xy 429.832262 -129.447544) (xy 429.862249 -129.448011)
			(xy 429.921711 -129.455834) (xy 429.979643 -129.471353) (xy 430.035053 -129.494301) (xy 430.086994 -129.524285)
			(xy 430.134576 -129.560793) (xy 430.176986 -129.6032) (xy 430.213497 -129.65078) (xy 430.243485 -129.702718)
			(xy 430.266437 -129.758127) (xy 430.281959 -129.816058) (xy 430.289787 -129.875519) (xy 430.290224 -129.905506)
			(xy 430.290224 -130.769106) (xy 430.289754 -130.799091) (xy 430.281926 -130.858546) (xy 430.266403 -130.916472)
			(xy 430.243452 -130.971875) (xy 430.213466 -131.023809) (xy 430.176957 -131.071384) (xy 430.134551 -131.113786)
			(xy 430.086972 -131.15029) (xy 430.035036 -131.180272) (xy 429.97963 -131.203217) (xy 429.921703 -131.218734)
			(xy 429.862247 -131.226557) (xy 429.832262 -131.227068) (xy 429.801217 -131.226555) (xy 429.739696 -131.21817)
			(xy 429.679872 -131.201547) (xy 429.65116 -131.18973) (xy 429.640854 -131.185217) (xy 429.620651 -131.175307)
			(xy 429.610774 -131.169918) (xy 429.605186 -131.16687) (xy 429.580802 -131.160266) (xy 429.569372 -131.161536)
			(xy 429.548036 -131.166362) (xy 429.543517 -131.167427) (xy 429.534953 -131.171009) (xy 429.531018 -131.173474)
			(xy 429.50892 -131.188206) (xy 429.50384 -131.195318) (xy 429.487329 -131.216625) (xy 429.449291 -131.254817)
			(xy 429.406249 -131.287266) (xy 429.359064 -131.313325) (xy 429.308676 -131.332473) (xy 429.256093 -131.344328)
			(xy 429.229266 -131.346956) (xy 429.220122 -131.347718) (xy 429.203358 -131.355592) (xy 429.197008 -131.362196)
			(xy 429.190858 -131.369154) (xy 429.18357 -131.386217) (xy 429.182784 -131.39547) (xy 429.132423 -132.575808)
			(xy 432.016408 -132.575808) (xy 432.016408 -131.712208) (xy 432.016898 -131.682224) (xy 432.024726 -131.622768)
			(xy 432.040247 -131.564843) (xy 432.063196 -131.509439) (xy 432.09318 -131.457505) (xy 432.129686 -131.409929)
			(xy 432.172091 -131.367524) (xy 432.219667 -131.331018) (xy 432.271601 -131.301034) (xy 432.327005 -131.278085)
			(xy 432.38493 -131.262564) (xy 432.444386 -131.254736) (xy 432.504354 -131.254736) (xy 432.56381 -131.262564)
			(xy 432.621735 -131.278085) (xy 432.677139 -131.301034) (xy 432.729073 -131.331018) (xy 432.776649 -131.367524)
			(xy 432.819054 -131.409929) (xy 432.85556 -131.457505) (xy 432.885544 -131.509439) (xy 432.908493 -131.564843)
			(xy 432.924014 -131.622768) (xy 432.931842 -131.682224) (xy 432.932332 -131.712208) (xy 432.932332 -132.575808)
			(xy 432.931842 -132.605792) (xy 432.924014 -132.665248) (xy 432.908493 -132.723173) (xy 432.885544 -132.778577)
			(xy 432.85556 -132.830511) (xy 432.819054 -132.878087) (xy 432.776649 -132.920492) (xy 432.729073 -132.956998)
			(xy 432.677139 -132.986982) (xy 432.621735 -133.009931) (xy 432.56381 -133.025452) (xy 432.504354 -133.03328)
			(xy 432.444386 -133.03328) (xy 432.38493 -133.025452) (xy 432.327005 -133.009931) (xy 432.271601 -132.986982)
			(xy 432.219667 -132.956998) (xy 432.172091 -132.920492) (xy 432.129686 -132.878087) (xy 432.09318 -132.830511)
			(xy 432.063196 -132.778577) (xy 432.040247 -132.723173) (xy 432.024726 -132.665248) (xy 432.016898 -132.605792)
			(xy 432.016408 -132.575808) (xy 429.132423 -132.575808) (xy 429.055901 -134.369302) (xy 429.3743 -134.369302)
			(xy 429.3743 -133.505702) (xy 429.37479 -133.475718) (xy 429.382618 -133.416262) (xy 429.398139 -133.358337)
			(xy 429.421088 -133.302933) (xy 429.451072 -133.250999) (xy 429.487578 -133.203423) (xy 429.529983 -133.161018)
			(xy 429.577559 -133.124512) (xy 429.629493 -133.094528) (xy 429.684897 -133.071579) (xy 429.742822 -133.056058)
			(xy 429.802278 -133.04823) (xy 429.862246 -133.04823) (xy 429.921702 -133.056058) (xy 429.979627 -133.071579)
			(xy 430.035031 -133.094528) (xy 430.086965 -133.124512) (xy 430.134541 -133.161018) (xy 430.176946 -133.203423)
			(xy 430.213452 -133.250999) (xy 430.243436 -133.302933) (xy 430.266385 -133.358337) (xy 430.281906 -133.416262)
			(xy 430.289734 -133.475718) (xy 430.290224 -133.505702) (xy 430.290224 -134.369302) (xy 430.289734 -134.399286)
			(xy 430.281906 -134.458742) (xy 430.266385 -134.516667) (xy 430.243436 -134.572071) (xy 430.213452 -134.624005)
			(xy 430.176946 -134.671581) (xy 430.134541 -134.713986) (xy 430.086965 -134.750492) (xy 430.035031 -134.780476)
			(xy 429.979627 -134.803425) (xy 429.921702 -134.818946) (xy 429.862246 -134.826774) (xy 429.802278 -134.826774)
			(xy 429.742822 -134.818946) (xy 429.684897 -134.803425) (xy 429.629493 -134.780476) (xy 429.577559 -134.750492)
			(xy 429.529983 -134.713986) (xy 429.487578 -134.671581) (xy 429.451072 -134.624005) (xy 429.421088 -134.572071)
			(xy 429.398139 -134.516667) (xy 429.382618 -134.458742) (xy 429.37479 -134.399286) (xy 429.3743 -134.369302)
			(xy 429.055901 -134.369302) (xy 428.995332 -135.788908) (xy 428.995332 -136.17575) (xy 432.016408 -136.17575)
			(xy 432.016408 -135.31215) (xy 432.016898 -135.282166) (xy 432.024726 -135.22271) (xy 432.040247 -135.164785)
			(xy 432.063196 -135.109381) (xy 432.09318 -135.057447) (xy 432.129686 -135.009871) (xy 432.172091 -134.967466)
			(xy 432.219667 -134.93096) (xy 432.271601 -134.900976) (xy 432.327005 -134.878027) (xy 432.38493 -134.862506)
			(xy 432.444386 -134.854678) (xy 432.504354 -134.854678) (xy 432.56381 -134.862506) (xy 432.621735 -134.878027)
			(xy 432.677139 -134.900976) (xy 432.729073 -134.93096) (xy 432.776649 -134.967466) (xy 432.819054 -135.009871)
			(xy 432.85556 -135.057447) (xy 432.885544 -135.109381) (xy 432.908493 -135.164785) (xy 432.924014 -135.22271)
			(xy 432.931842 -135.282166) (xy 432.932332 -135.31215) (xy 432.932332 -136.17575) (xy 432.931842 -136.205734)
			(xy 432.924014 -136.26519) (xy 432.908493 -136.323115) (xy 432.885544 -136.378519) (xy 432.85556 -136.430453)
			(xy 432.819054 -136.478029) (xy 432.776649 -136.520434) (xy 432.729073 -136.55694) (xy 432.677139 -136.586924)
			(xy 432.621735 -136.609873) (xy 432.56381 -136.625394) (xy 432.504354 -136.633222) (xy 432.444386 -136.633222)
			(xy 432.38493 -136.625394) (xy 432.327005 -136.609873) (xy 432.271601 -136.586924) (xy 432.219667 -136.55694)
			(xy 432.172091 -136.520434) (xy 432.129686 -136.478029) (xy 432.09318 -136.430453) (xy 432.063196 -136.378519)
			(xy 432.040247 -136.323115) (xy 432.024726 -136.26519) (xy 432.016898 -136.205734) (xy 432.016408 -136.17575)
			(xy 428.995332 -136.17575) (xy 428.995332 -136.528048) (xy 428.995586 -136.531096) (xy 428.995586 -136.532112)
			(xy 428.996875 -136.543975) (xy 429.004196 -136.566679) (xy 429.010064 -136.57707) (xy 429.017388 -136.588371)
			(xy 429.036871 -136.60695) (xy 429.060541 -136.619775) (xy 429.086745 -136.625951) (xy 429.113651 -136.625045)
			(xy 429.12665 -136.62152) (xy 429.154096 -136.61356) (xy 429.210599 -136.605018) (xy 429.239172 -136.604502)
			(xy 429.23968 -136.604502) (xy 429.266933 -136.604964) (xy 429.320885 -136.612718) (xy 429.373184 -136.628072)
			(xy 429.422765 -136.650713) (xy 429.468619 -136.68018) (xy 429.509813 -136.715872) (xy 429.545508 -136.757065)
			(xy 429.574977 -136.802917) (xy 429.597621 -136.852498) (xy 429.612977 -136.904796) (xy 429.620735 -136.958747)
			(xy 429.620735 -137.013253) (xy 429.612977 -137.067204) (xy 429.597621 -137.119502) (xy 429.574977 -137.169083)
			(xy 429.545508 -137.214935) (xy 429.509813 -137.256128) (xy 429.468619 -137.29182) (xy 429.422765 -137.321287)
			(xy 429.373184 -137.343928) (xy 429.320885 -137.359282) (xy 429.266933 -137.367036) (xy 429.23968 -137.367518)
			(xy 429.238918 -137.367518) (xy 429.210412 -137.36695) (xy 429.154043 -137.358408) (xy 429.12665 -137.3505)
			(xy 429.112148 -137.346586) (xy 429.082127 -137.346456) (xy 429.053363 -137.355056) (xy 429.02834 -137.371644)
			(xy 429.009217 -137.394787) (xy 428.997645 -137.422489) (xy 428.995586 -137.437368) (xy 428.995332 -137.442448)
			(xy 428.995332 -137.65276) (xy 444.341248 -137.65276) (xy 444.345319 -137.597138) (xy 444.357445 -137.542701)
			(xy 444.377368 -137.49061) (xy 444.404664 -137.441975) (xy 444.43875 -137.397832) (xy 444.478899 -137.359123)
			(xy 444.524257 -137.326672) (xy 444.573857 -137.301171) (xy 444.626641 -137.283164) (xy 444.681484 -137.273034)
			(xy 444.737218 -137.270997) (xy 444.792655 -137.277097) (xy 444.846612 -137.291203) (xy 444.897941 -137.313015)
			(xy 444.945547 -137.342069) (xy 444.988415 -137.377744) (xy 445.025632 -137.419281) (xy 445.056405 -137.465794)
			(xy 445.080077 -137.516291) (xy 445.096145 -137.569698) (xy 445.104265 -137.624874) (xy 445.104774 -137.65276)
			(xy 445.104265 -137.680646) (xy 445.096145 -137.735822) (xy 445.080077 -137.789229) (xy 445.056405 -137.839726)
			(xy 445.025632 -137.886239) (xy 444.988415 -137.927776) (xy 444.977268 -137.937053) (xy 445.665563 -137.937053)
			(xy 445.665563 -137.882547) (xy 445.67332 -137.828597) (xy 445.688676 -137.7763) (xy 445.711319 -137.72672)
			(xy 445.740787 -137.680868) (xy 445.77648 -137.639676) (xy 445.817673 -137.603983) (xy 445.863526 -137.574516)
			(xy 445.913106 -137.551874) (xy 445.965403 -137.536519) (xy 446.019353 -137.528763) (xy 446.046606 -137.5283)
			(xy 446.074709 -137.528782) (xy 446.130306 -137.537029) (xy 446.184092 -137.553344) (xy 446.234901 -137.577374)
			(xy 446.281636 -137.608598) (xy 446.323284 -137.646341) (xy 446.3415 -137.667746) (xy 446.348803 -137.675928)
			(xy 446.368414 -137.685684) (xy 446.379346 -137.686542) (xy 446.466976 -137.689082) (xy 446.487296 -137.680446)
			(xy 446.494662 -137.672318) (xy 446.512803 -137.653333) (xy 446.553392 -137.620017) (xy 446.598162 -137.592577)
			(xy 446.64627 -137.571529) (xy 446.696808 -137.557272) (xy 446.748823 -137.550074) (xy 446.775078 -137.549636)
			(xy 446.802335 -137.550009) (xy 446.856295 -137.557765) (xy 446.908601 -137.573121) (xy 446.95819 -137.595765)
			(xy 447.004051 -137.625235) (xy 447.045251 -137.660933) (xy 447.080951 -137.702131) (xy 447.110425 -137.747991)
			(xy 447.133072 -137.797578) (xy 447.148431 -137.849884) (xy 447.156189 -137.903843) (xy 447.156189 -137.958357)
			(xy 447.148431 -138.012316) (xy 447.133072 -138.064622) (xy 447.110425 -138.114209) (xy 447.080951 -138.160069)
			(xy 447.045251 -138.201267) (xy 447.004051 -138.236965) (xy 446.95819 -138.266435) (xy 446.908601 -138.289079)
			(xy 446.856295 -138.304435) (xy 446.802335 -138.312191) (xy 446.775078 -138.312652) (xy 446.746976 -138.312128)
			(xy 446.69138 -138.303892) (xy 446.637595 -138.287587) (xy 446.586784 -138.263565) (xy 446.540049 -138.232347)
			(xy 446.4984 -138.194609) (xy 446.480184 -138.173206) (xy 446.472879 -138.165026) (xy 446.45327 -138.155267)
			(xy 446.442338 -138.15441) (xy 446.354708 -138.15187) (xy 446.334388 -138.160506) (xy 446.327022 -138.168634)
			(xy 446.308879 -138.187617) (xy 446.268292 -138.220935) (xy 446.223523 -138.248377) (xy 446.175415 -138.269425)
			(xy 446.124877 -138.283682) (xy 446.072861 -138.290879) (xy 446.046606 -138.291316) (xy 446.019353 -138.290837)
			(xy 445.965403 -138.283081) (xy 445.913106 -138.267726) (xy 445.863526 -138.245084) (xy 445.817673 -138.215617)
			(xy 445.77648 -138.179924) (xy 445.740787 -138.138732) (xy 445.711319 -138.09288) (xy 445.688676 -138.0433)
			(xy 445.67332 -137.991003) (xy 445.665563 -137.937053) (xy 444.977268 -137.937053) (xy 444.945547 -137.963451)
			(xy 444.897941 -137.992505) (xy 444.846612 -138.014317) (xy 444.792655 -138.028423) (xy 444.737218 -138.034523)
			(xy 444.681484 -138.032486) (xy 444.626641 -138.022356) (xy 444.573857 -138.004349) (xy 444.524257 -137.978848)
			(xy 444.478899 -137.946397) (xy 444.43875 -137.907688) (xy 444.404664 -137.863545) (xy 444.377368 -137.81491)
			(xy 444.357445 -137.762819) (xy 444.345319 -137.708382) (xy 444.341248 -137.65276) (xy 428.995332 -137.65276)
			(xy 428.995332 -139.281408) (xy 428.995855 -139.291677) (xy 429.003979 -139.310547) (xy 429.01108 -139.317984)
			(xy 429.039782 -139.34567) (xy 429.04029 -139.346178) (xy 429.04791 -139.35329) (xy 429.065944 -139.35329)
			(xy 429.067468 -139.35329) (xy 429.06823 -139.35329) (xy 429.080396 -139.353431) (xy 429.104672 -139.355082)
			(xy 429.116744 -139.356592) (xy 429.141946 -139.360386) (xy 429.191113 -139.373802) (xy 429.238053 -139.393651)
			(xy 429.28193 -139.419578) (xy 429.32196 -139.451121) (xy 429.34001 -139.469114) (xy 429.347122 -139.47648)
			(xy 429.373792 -139.48791) (xy 429.378473 -139.489754) (xy 429.388322 -139.491799) (xy 429.39335 -139.491974)
			(xy 429.447706 -139.491974) (xy 429.452803 -139.491861) (xy 429.462788 -139.489813) (xy 429.467518 -139.48791)
			(xy 429.494188 -139.47648) (xy 429.5013 -139.469114) (xy 429.51933 -139.451133) (xy 429.559332 -139.419625)
			(xy 429.60317 -139.393718) (xy 429.650065 -139.373875) (xy 429.699184 -139.360447) (xy 429.749652 -139.353674)
			(xy 429.775112 -139.35329) (xy 429.802363 -139.353777) (xy 429.85631 -139.361535) (xy 429.908603 -139.376891)
			(xy 429.958179 -139.399533) (xy 430.004028 -139.429) (xy 430.045217 -139.464691) (xy 430.080908 -139.505881)
			(xy 430.110373 -139.551731) (xy 430.133013 -139.601308) (xy 430.148368 -139.653602) (xy 430.156124 -139.707549)
			(xy 430.156124 -139.71651) (xy 431.091846 -139.71651) (xy 431.095917 -139.660888) (xy 431.108043 -139.606451)
			(xy 431.127966 -139.55436) (xy 431.155262 -139.505725) (xy 431.189348 -139.461582) (xy 431.229497 -139.422873)
			(xy 431.274855 -139.390422) (xy 431.324455 -139.364921) (xy 431.377239 -139.346914) (xy 431.432082 -139.336784)
			(xy 431.487816 -139.334747) (xy 431.543253 -139.340847) (xy 431.59721 -139.354953) (xy 431.648539 -139.376765)
			(xy 431.696145 -139.405819) (xy 431.739013 -139.441494) (xy 431.77623 -139.483031) (xy 431.807003 -139.529544)
			(xy 431.830675 -139.580041) (xy 431.846743 -139.633448) (xy 431.854863 -139.688624) (xy 431.855372 -139.71651)
			(xy 431.854863 -139.744396) (xy 431.846743 -139.799572) (xy 431.830675 -139.852979) (xy 431.807003 -139.903476)
			(xy 431.77623 -139.949989) (xy 431.739013 -139.991526) (xy 431.696145 -140.027201) (xy 431.648539 -140.056255)
			(xy 431.59721 -140.078067) (xy 431.543253 -140.092173) (xy 431.487816 -140.098273) (xy 431.432082 -140.096236)
			(xy 431.377239 -140.086106) (xy 431.324455 -140.068099) (xy 431.274855 -140.042598) (xy 431.229497 -140.010147)
			(xy 431.189348 -139.971438) (xy 431.155262 -139.927295) (xy 431.127966 -139.87866) (xy 431.108043 -139.826569)
			(xy 431.095917 -139.772132) (xy 431.091846 -139.71651) (xy 430.156124 -139.71651) (xy 430.156124 -139.762051)
			(xy 430.148368 -139.815998) (xy 430.133013 -139.868292) (xy 430.110373 -139.917869) (xy 430.080908 -139.963719)
			(xy 430.045217 -140.004909) (xy 430.004028 -140.0406) (xy 429.958179 -140.070067) (xy 429.908603 -140.092709)
			(xy 429.85631 -140.108065) (xy 429.802363 -140.115823) (xy 429.775112 -140.116306) (xy 429.749653 -140.115885)
			(xy 429.699187 -140.109115) (xy 429.650069 -140.095694) (xy 429.603172 -140.07586) (xy 429.55933 -140.049966)
			(xy 429.51932 -140.018471) (xy 429.5013 -140.000482) (xy 429.494188 -139.993116) (xy 429.467518 -139.981686)
			(xy 429.462779 -139.979815) (xy 429.452799 -139.977766) (xy 429.447706 -139.977622) (xy 429.39335 -139.977622)
			(xy 429.388254 -139.97774) (xy 429.378272 -139.979796) (xy 429.373538 -139.981686) (xy 429.346868 -139.993116)
			(xy 429.339756 -140.000482) (xy 429.318215 -140.021838) (xy 429.269618 -140.058131) (xy 429.21589 -140.086277)
			(xy 429.158385 -140.105567) (xy 429.098553 -140.115514) (xy 429.06823 -140.116306) (xy 429.067722 -140.116306)
			(xy 429.058129 -140.116856) (xy 429.040372 -140.124161) (xy 429.033178 -140.13053) (xy 429.01108 -140.151612)
			(xy 429.003955 -140.159034) (xy 428.99582 -140.177911) (xy 428.995332 -140.188188) (xy 428.995332 -140.487654)
			(xy 434.002178 -140.487654) (xy 434.006249 -140.432032) (xy 434.018375 -140.377595) (xy 434.038298 -140.325504)
			(xy 434.065594 -140.276869) (xy 434.09968 -140.232726) (xy 434.139829 -140.194017) (xy 434.185187 -140.161566)
			(xy 434.234787 -140.136065) (xy 434.287571 -140.118058) (xy 434.342414 -140.107928) (xy 434.398148 -140.105891)
			(xy 434.453585 -140.111991) (xy 434.507542 -140.126097) (xy 434.558871 -140.147909) (xy 434.606477 -140.176963)
			(xy 434.649345 -140.212638) (xy 434.686562 -140.254175) (xy 434.717335 -140.300688) (xy 434.741007 -140.351185)
			(xy 434.757075 -140.404592) (xy 434.765195 -140.459768) (xy 434.765704 -140.487654) (xy 434.765195 -140.51554)
			(xy 434.757075 -140.570716) (xy 434.741007 -140.624123) (xy 434.717335 -140.67462) (xy 434.686562 -140.721133)
			(xy 434.649345 -140.76267) (xy 434.606477 -140.798345) (xy 434.558871 -140.827399) (xy 434.507542 -140.849211)
			(xy 434.453585 -140.863317) (xy 434.398148 -140.869417) (xy 434.342414 -140.86738) (xy 434.287571 -140.85725)
			(xy 434.234787 -140.839243) (xy 434.185187 -140.813742) (xy 434.139829 -140.781291) (xy 434.09968 -140.742582)
			(xy 434.065594 -140.698439) (xy 434.038298 -140.649804) (xy 434.018375 -140.597713) (xy 434.006249 -140.543276)
			(xy 434.002178 -140.487654) (xy 428.995332 -140.487654) (xy 428.995332 -140.798042) (xy 428.995078 -140.81252)
			(xy 428.995078 -140.9065) (xy 428.993808 -140.91793) (xy 428.969424 -141.023594) (xy 428.809912 -141.709648)
			(xy 428.728124 -142.061692) (xy 428.72787 -142.065756) (xy 428.66754 -143.479266) (xy 429.3743 -143.479266)
			(xy 429.3743 -142.615666) (xy 429.37479 -142.585682) (xy 429.382618 -142.526226) (xy 429.398139 -142.468301)
			(xy 429.421088 -142.412897) (xy 429.451072 -142.360963) (xy 429.487578 -142.313387) (xy 429.529983 -142.270982)
			(xy 429.577559 -142.234476) (xy 429.629493 -142.204492) (xy 429.684897 -142.181543) (xy 429.742822 -142.166022)
			(xy 429.802278 -142.158194) (xy 429.862246 -142.158194) (xy 429.921702 -142.166022) (xy 429.979627 -142.181543)
			(xy 430.035031 -142.204492) (xy 430.086965 -142.234476) (xy 430.134541 -142.270982) (xy 430.176946 -142.313387)
			(xy 430.213452 -142.360963) (xy 430.243436 -142.412897) (xy 430.266385 -142.468301) (xy 430.281906 -142.526226)
			(xy 430.289734 -142.585682) (xy 430.290224 -142.615666) (xy 430.290224 -143.479266) (xy 430.289734 -143.50925)
			(xy 430.281906 -143.568706) (xy 430.266385 -143.626631) (xy 430.243436 -143.682035) (xy 430.213452 -143.733969)
			(xy 430.176946 -143.781545) (xy 430.134541 -143.82395) (xy 430.086965 -143.860456) (xy 430.035031 -143.89044)
			(xy 429.979627 -143.913389) (xy 429.921702 -143.92891) (xy 429.862246 -143.936738) (xy 429.802278 -143.936738)
			(xy 429.742822 -143.92891) (xy 429.684897 -143.913389) (xy 429.629493 -143.89044) (xy 429.577559 -143.860456)
			(xy 429.529983 -143.82395) (xy 429.487578 -143.781545) (xy 429.451072 -143.733969) (xy 429.421088 -143.682035)
			(xy 429.398139 -143.626631) (xy 429.382618 -143.568706) (xy 429.37479 -143.50925) (xy 429.3743 -143.479266)
			(xy 428.66754 -143.479266) (xy 428.59044 -145.285714) (xy 432.016408 -145.285714) (xy 432.016408 -144.422114)
			(xy 432.016898 -144.39213) (xy 432.024726 -144.332674) (xy 432.040247 -144.274749) (xy 432.063196 -144.219345)
			(xy 432.09318 -144.167411) (xy 432.129686 -144.119835) (xy 432.172091 -144.07743) (xy 432.219667 -144.040924)
			(xy 432.271601 -144.01094) (xy 432.327005 -143.987991) (xy 432.38493 -143.97247) (xy 432.444386 -143.964642)
			(xy 432.504354 -143.964642) (xy 432.56381 -143.97247) (xy 432.621735 -143.987991) (xy 432.677139 -144.01094)
			(xy 432.729073 -144.040924) (xy 432.776649 -144.07743) (xy 432.819054 -144.119835) (xy 432.85556 -144.167411)
			(xy 432.885544 -144.219345) (xy 432.908493 -144.274749) (xy 432.924014 -144.332674) (xy 432.931842 -144.39213)
			(xy 432.932332 -144.422114) (xy 432.932332 -145.285714) (xy 432.931842 -145.315698) (xy 432.924014 -145.375154)
			(xy 432.908493 -145.433079) (xy 432.885544 -145.488483) (xy 432.85556 -145.540417) (xy 432.819054 -145.587993)
			(xy 432.776649 -145.630398) (xy 432.729073 -145.666904) (xy 432.677139 -145.696888) (xy 432.621735 -145.719837)
			(xy 432.56381 -145.735358) (xy 432.504354 -145.743186) (xy 432.444386 -145.743186) (xy 432.38493 -145.735358)
			(xy 432.327005 -145.719837) (xy 432.271601 -145.696888) (xy 432.219667 -145.666904) (xy 432.172091 -145.630398)
			(xy 432.129686 -145.587993) (xy 432.09318 -145.540417) (xy 432.063196 -145.488483) (xy 432.040247 -145.433079)
			(xy 432.024726 -145.375154) (xy 432.016898 -145.315698) (xy 432.016408 -145.285714) (xy 428.59044 -145.285714)
			(xy 428.547022 -146.302984) (xy 428.547022 -146.305016) (xy 428.546006 -146.320764) (xy 428.546006 -146.323812)
			(xy 428.545498 -146.330416) (xy 428.545498 -146.33067) (xy 428.544482 -146.342354) (xy 428.483857 -147.079208)
			(xy 429.3743 -147.079208) (xy 429.3743 -146.215608) (xy 429.37479 -146.185624) (xy 429.382618 -146.126168)
			(xy 429.398139 -146.068243) (xy 429.421088 -146.012839) (xy 429.451072 -145.960905) (xy 429.487578 -145.913329)
			(xy 429.529983 -145.870924) (xy 429.577559 -145.834418) (xy 429.629493 -145.804434) (xy 429.684897 -145.781485)
			(xy 429.742822 -145.765964) (xy 429.802278 -145.758136) (xy 429.862246 -145.758136) (xy 429.921702 -145.765964)
			(xy 429.979627 -145.781485) (xy 430.035031 -145.804434) (xy 430.086965 -145.834418) (xy 430.134541 -145.870924)
			(xy 430.176946 -145.913329) (xy 430.213452 -145.960905) (xy 430.243436 -146.012839) (xy 430.266385 -146.068243)
			(xy 430.281906 -146.126168) (xy 430.289734 -146.185624) (xy 430.290224 -146.215608) (xy 430.290224 -147.079208)
			(xy 430.289734 -147.109192) (xy 430.281906 -147.168648) (xy 430.266385 -147.226573) (xy 430.243436 -147.281977)
			(xy 430.213452 -147.333911) (xy 430.176946 -147.381487) (xy 430.134541 -147.423892) (xy 430.086965 -147.460398)
			(xy 430.035031 -147.490382) (xy 429.979627 -147.513331) (xy 429.921702 -147.528852) (xy 429.862246 -147.53668)
			(xy 429.802278 -147.53668) (xy 429.742822 -147.528852) (xy 429.684897 -147.513331) (xy 429.629493 -147.490382)
			(xy 429.577559 -147.460398) (xy 429.529983 -147.423892) (xy 429.487578 -147.381487) (xy 429.451072 -147.333911)
			(xy 429.421088 -147.281977) (xy 429.398139 -147.226573) (xy 429.382618 -147.168648) (xy 429.37479 -147.109192)
			(xy 429.3743 -147.079208) (xy 428.483857 -147.079208) (xy 428.335209 -148.88591) (xy 432.016408 -148.88591)
			(xy 432.016408 -148.02231) (xy 432.016898 -147.992326) (xy 432.024726 -147.93287) (xy 432.040247 -147.874945)
			(xy 432.063196 -147.819541) (xy 432.09318 -147.767607) (xy 432.129686 -147.720031) (xy 432.172091 -147.677626)
			(xy 432.219667 -147.64112) (xy 432.271601 -147.611136) (xy 432.327005 -147.588187) (xy 432.38493 -147.572666)
			(xy 432.444386 -147.564838) (xy 432.504354 -147.564838) (xy 432.56381 -147.572666) (xy 432.621735 -147.588187)
			(xy 432.677139 -147.611136) (xy 432.729073 -147.64112) (xy 432.776649 -147.677626) (xy 432.819054 -147.720031)
			(xy 432.85556 -147.767607) (xy 432.885544 -147.819541) (xy 432.908493 -147.874945) (xy 432.924014 -147.93287)
			(xy 432.931842 -147.992326) (xy 432.932332 -148.02231) (xy 432.932332 -148.88591) (xy 432.931842 -148.915894)
			(xy 432.924014 -148.97535) (xy 432.908493 -149.033275) (xy 432.885544 -149.088679) (xy 432.85556 -149.140613)
			(xy 432.819054 -149.188189) (xy 432.776649 -149.230594) (xy 432.729073 -149.2671) (xy 432.677139 -149.297084)
			(xy 432.621735 -149.320033) (xy 432.56381 -149.335554) (xy 432.504354 -149.343382) (xy 432.444386 -149.343382)
			(xy 432.38493 -149.335554) (xy 432.327005 -149.320033) (xy 432.271601 -149.297084) (xy 432.219667 -149.2671)
			(xy 432.172091 -149.230594) (xy 432.129686 -149.188189) (xy 432.09318 -149.140613) (xy 432.063196 -149.088679)
			(xy 432.040247 -149.033275) (xy 432.024726 -148.97535) (xy 432.016898 -148.915894) (xy 432.016408 -148.88591)
			(xy 428.335209 -148.88591) (xy 428.187668 -150.67915) (xy 429.3743 -150.67915) (xy 429.3743 -149.81555)
			(xy 429.37479 -149.785566) (xy 429.382618 -149.72611) (xy 429.398139 -149.668185) (xy 429.421088 -149.612781)
			(xy 429.451072 -149.560847) (xy 429.487578 -149.513271) (xy 429.529983 -149.470866) (xy 429.577559 -149.43436)
			(xy 429.629493 -149.404376) (xy 429.684897 -149.381427) (xy 429.742822 -149.365906) (xy 429.802278 -149.358078)
			(xy 429.862246 -149.358078) (xy 429.921702 -149.365906) (xy 429.979627 -149.381427) (xy 430.035031 -149.404376)
			(xy 430.086965 -149.43436) (xy 430.134541 -149.470866) (xy 430.176946 -149.513271) (xy 430.213452 -149.560847)
			(xy 430.243436 -149.612781) (xy 430.266385 -149.668185) (xy 430.281906 -149.72611) (xy 430.289734 -149.785566)
			(xy 430.290224 -149.81555) (xy 430.290224 -150.67915) (xy 430.289734 -150.709134) (xy 430.281906 -150.76859)
			(xy 430.266385 -150.826515) (xy 430.243436 -150.881919) (xy 430.213452 -150.933853) (xy 430.176946 -150.981429)
			(xy 430.134541 -151.023834) (xy 430.086965 -151.06034) (xy 430.035031 -151.090324) (xy 429.979627 -151.113273)
			(xy 429.921702 -151.128794) (xy 429.862246 -151.136622) (xy 429.802278 -151.136622) (xy 429.742822 -151.128794)
			(xy 429.684897 -151.113273) (xy 429.629493 -151.090324) (xy 429.577559 -151.06034) (xy 429.529983 -151.023834)
			(xy 429.487578 -150.981429) (xy 429.451072 -150.933853) (xy 429.421088 -150.881919) (xy 429.398139 -150.826515)
			(xy 429.382618 -150.76859) (xy 429.37479 -150.709134) (xy 429.3743 -150.67915) (xy 428.187668 -150.67915)
			(xy 428.03902 -152.485852) (xy 432.016408 -152.485852) (xy 432.016408 -151.622252) (xy 432.016898 -151.592268)
			(xy 432.024726 -151.532812) (xy 432.040247 -151.474887) (xy 432.063196 -151.419483) (xy 432.09318 -151.367549)
			(xy 432.129686 -151.319973) (xy 432.172091 -151.277568) (xy 432.219667 -151.241062) (xy 432.271601 -151.211078)
			(xy 432.327005 -151.188129) (xy 432.38493 -151.172608) (xy 432.444386 -151.16478) (xy 432.504354 -151.16478)
			(xy 432.56381 -151.172608) (xy 432.621735 -151.188129) (xy 432.677139 -151.211078) (xy 432.729073 -151.241062)
			(xy 432.776649 -151.277568) (xy 432.819054 -151.319973) (xy 432.85556 -151.367549) (xy 432.885544 -151.419483)
			(xy 432.908493 -151.474887) (xy 432.924014 -151.532812) (xy 432.931842 -151.592268) (xy 432.932332 -151.622252)
			(xy 432.932332 -152.485852) (xy 432.931842 -152.515836) (xy 432.924014 -152.575292) (xy 432.908493 -152.633217)
			(xy 432.885544 -152.688621) (xy 432.85556 -152.740555) (xy 432.819054 -152.788131) (xy 432.776649 -152.830536)
			(xy 432.729073 -152.867042) (xy 432.677139 -152.897026) (xy 432.621735 -152.919975) (xy 432.56381 -152.935496)
			(xy 432.504354 -152.943324) (xy 432.444386 -152.943324) (xy 432.38493 -152.935496) (xy 432.327005 -152.919975)
			(xy 432.271601 -152.897026) (xy 432.219667 -152.867042) (xy 432.172091 -152.830536) (xy 432.129686 -152.788131)
			(xy 432.09318 -152.740555) (xy 432.063196 -152.688621) (xy 432.040247 -152.633217) (xy 432.024726 -152.575292)
			(xy 432.016898 -152.515836) (xy 432.016408 -152.485852) (xy 428.03902 -152.485852) (xy 427.918626 -153.949146)
			(xy 427.918626 -153.949654) (xy 427.916848 -153.969212) (xy 427.916848 -153.97099) (xy 427.91634 -153.975308)
			(xy 427.915578 -153.98115) (xy 427.915578 -153.981658) (xy 427.913292 -153.998676) (xy 427.913292 -153.999184)
			(xy 427.876167 -154.279346) (xy 429.3743 -154.279346) (xy 429.3743 -153.415746) (xy 429.37479 -153.385762)
			(xy 429.382618 -153.326306) (xy 429.398139 -153.268381) (xy 429.421088 -153.212977) (xy 429.451072 -153.161043)
			(xy 429.487578 -153.113467) (xy 429.529983 -153.071062) (xy 429.577559 -153.034556) (xy 429.629493 -153.004572)
			(xy 429.684897 -152.981623) (xy 429.742822 -152.966102) (xy 429.802278 -152.958274) (xy 429.862246 -152.958274)
			(xy 429.921702 -152.966102) (xy 429.979627 -152.981623) (xy 430.035031 -153.004572) (xy 430.086965 -153.034556)
			(xy 430.134541 -153.071062) (xy 430.176946 -153.113467) (xy 430.213452 -153.161043) (xy 430.243436 -153.212977)
			(xy 430.266385 -153.268381) (xy 430.281906 -153.326306) (xy 430.289734 -153.385762) (xy 430.290224 -153.415746)
			(xy 430.290224 -154.279346) (xy 430.289734 -154.30933) (xy 430.281906 -154.368786) (xy 430.266385 -154.426711)
			(xy 430.243436 -154.482115) (xy 430.213452 -154.534049) (xy 430.176946 -154.581625) (xy 430.134541 -154.62403)
			(xy 430.086965 -154.660536) (xy 430.035031 -154.69052) (xy 429.979627 -154.713469) (xy 429.921702 -154.72899)
			(xy 429.862246 -154.736818) (xy 429.802278 -154.736818) (xy 429.742822 -154.72899) (xy 429.684897 -154.713469)
			(xy 429.629493 -154.69052) (xy 429.577559 -154.660536) (xy 429.529983 -154.62403) (xy 429.487578 -154.581625)
			(xy 429.451072 -154.534049) (xy 429.421088 -154.482115) (xy 429.398139 -154.426711) (xy 429.382618 -154.368786)
			(xy 429.37479 -154.30933) (xy 429.3743 -154.279346) (xy 427.876167 -154.279346) (xy 427.825916 -154.658568)
			(xy 427.792134 -154.914854) (xy 427.79188 -154.917394) (xy 427.694157 -156.085794) (xy 432.016408 -156.085794)
			(xy 432.016408 -155.222194) (xy 432.016898 -155.19221) (xy 432.024726 -155.132754) (xy 432.040247 -155.074829)
			(xy 432.063196 -155.019425) (xy 432.09318 -154.967491) (xy 432.129686 -154.919915) (xy 432.172091 -154.87751)
			(xy 432.219667 -154.841004) (xy 432.271601 -154.81102) (xy 432.327005 -154.788071) (xy 432.38493 -154.77255)
			(xy 432.444386 -154.764722) (xy 432.504354 -154.764722) (xy 432.56381 -154.77255) (xy 432.621735 -154.788071)
			(xy 432.677139 -154.81102) (xy 432.729073 -154.841004) (xy 432.776649 -154.87751) (xy 432.819054 -154.919915)
			(xy 432.85556 -154.967491) (xy 432.885544 -155.019425) (xy 432.908493 -155.074829) (xy 432.924014 -155.132754)
			(xy 432.931842 -155.19221) (xy 432.932332 -155.222194) (xy 432.932332 -156.085794) (xy 432.931842 -156.115778)
			(xy 432.924014 -156.175234) (xy 432.908493 -156.233159) (xy 432.885544 -156.288563) (xy 432.85556 -156.340497)
			(xy 432.819054 -156.388073) (xy 432.776649 -156.430478) (xy 432.729073 -156.466984) (xy 432.677139 -156.496968)
			(xy 432.621735 -156.519917) (xy 432.56381 -156.535438) (xy 432.504354 -156.543266) (xy 432.444386 -156.543266)
			(xy 432.38493 -156.535438) (xy 432.327005 -156.519917) (xy 432.271601 -156.496968) (xy 432.219667 -156.466984)
			(xy 432.172091 -156.430478) (xy 432.129686 -156.388073) (xy 432.09318 -156.340497) (xy 432.063196 -156.288563)
			(xy 432.040247 -156.233159) (xy 432.024726 -156.175234) (xy 432.016898 -156.115778) (xy 432.016408 -156.085794)
			(xy 427.694157 -156.085794) (xy 427.565312 -157.626304) (xy 427.565312 -157.626558) (xy 427.564296 -157.638496)
			(xy 427.564042 -157.639766) (xy 427.561248 -157.671262) (xy 427.561248 -157.672278) (xy 427.56074 -157.677358)
			(xy 427.553374 -157.717236) (xy 427.553374 -157.71749) (xy 427.55312 -157.71876) (xy 427.552866 -157.719776)
			(xy 427.461003 -158.219648) (xy 429.482248 -158.219648) (xy 429.486319 -158.164026) (xy 429.498445 -158.109589)
			(xy 429.518368 -158.057498) (xy 429.545664 -158.008863) (xy 429.57975 -157.96472) (xy 429.619899 -157.926011)
			(xy 429.665257 -157.89356) (xy 429.714857 -157.868059) (xy 429.767641 -157.850052) (xy 429.822484 -157.839922)
			(xy 429.878218 -157.837885) (xy 429.933655 -157.843985) (xy 429.987612 -157.858091) (xy 430.038941 -157.879903)
			(xy 430.086547 -157.908957) (xy 430.129415 -157.944632) (xy 430.166632 -157.986169) (xy 430.197405 -158.032682)
			(xy 430.221077 -158.083179) (xy 430.237145 -158.136586) (xy 430.245265 -158.191762) (xy 430.245774 -158.219648)
			(xy 430.245265 -158.247534) (xy 430.237145 -158.30271) (xy 430.221077 -158.356117) (xy 430.197405 -158.406614)
			(xy 430.166632 -158.453127) (xy 430.129415 -158.494664) (xy 430.086547 -158.530339) (xy 430.038941 -158.559393)
			(xy 429.987612 -158.581205) (xy 429.933655 -158.595311) (xy 429.878218 -158.601411) (xy 429.822484 -158.599374)
			(xy 429.767641 -158.589244) (xy 429.714857 -158.571237) (xy 429.665257 -158.545736) (xy 429.619899 -158.513285)
			(xy 429.57975 -158.474576) (xy 429.545664 -158.430433) (xy 429.518368 -158.381798) (xy 429.498445 -158.329707)
			(xy 429.486319 -158.27527) (xy 429.482248 -158.219648) (xy 427.461003 -158.219648) (xy 427.27429 -159.235648)
			(xy 429.639982 -159.235648) (xy 429.644053 -159.180026) (xy 429.656179 -159.125589) (xy 429.676102 -159.073498)
			(xy 429.703398 -159.024863) (xy 429.737484 -158.98072) (xy 429.777633 -158.942011) (xy 429.822991 -158.90956)
			(xy 429.872591 -158.884059) (xy 429.925375 -158.866052) (xy 429.980218 -158.855922) (xy 430.035952 -158.853885)
			(xy 430.091389 -158.859985) (xy 430.145346 -158.874091) (xy 430.196675 -158.895903) (xy 430.244281 -158.924957)
			(xy 430.287149 -158.960632) (xy 430.324366 -159.002169) (xy 430.355139 -159.048682) (xy 430.378811 -159.099179)
			(xy 430.394879 -159.152586) (xy 430.402999 -159.207762) (xy 430.403508 -159.235648) (xy 430.402999 -159.263534)
			(xy 430.394879 -159.31871) (xy 430.378811 -159.372117) (xy 430.355139 -159.422614) (xy 430.324366 -159.469127)
			(xy 430.287149 -159.510664) (xy 430.244281 -159.546339) (xy 430.196675 -159.575393) (xy 430.145346 -159.597205)
			(xy 430.091389 -159.611311) (xy 430.035952 -159.617411) (xy 429.980218 -159.615374) (xy 429.925375 -159.605244)
			(xy 429.872591 -159.587237) (xy 429.822991 -159.561736) (xy 429.777633 -159.529285) (xy 429.737484 -159.490576)
			(xy 429.703398 -159.446433) (xy 429.676102 -159.397798) (xy 429.656179 -159.345707) (xy 429.644053 -159.29127)
			(xy 429.639982 -159.235648) (xy 427.27429 -159.235648) (xy 427.07306 -160.330642) (xy 427.072806 -160.332166)
			(xy 427.072552 -160.333182) (xy 427.00194 -160.866074) (xy 426.961808 -161.167572) (xy 426.961808 -161.168588)
			(xy 426.956474 -161.208974) (xy 426.955712 -161.213546) (xy 426.955458 -161.21507) (xy 426.955204 -161.216086)
			(xy 426.95495 -161.217864) (xy 426.954696 -161.218626) (xy 426.95114 -161.2392) (xy 423.975784 -177.428652)
			(xy 420.775638 -194.840352) (xy 420.774939 -194.848009) (xy 420.777655 -194.863134) (xy 420.780972 -194.87007)
			(xy 420.784782 -194.877182) (xy 420.797228 -194.888612) (xy 420.805864 -194.892422) (xy 420.830944 -194.903979)
			(xy 420.877766 -194.933252) (xy 420.919881 -194.968968) (xy 420.956409 -195.010381) (xy 420.986586 -195.056626)
			(xy 421.009784 -195.106738) (xy 421.025518 -195.159669) (xy 421.033458 -195.214316) (xy 421.033956 -195.241926)
			(xy 421.033514 -195.268312) (xy 421.02625 -195.320583) (xy 421.011849 -195.371353) (xy 420.990588 -195.419653)
			(xy 420.962871 -195.464561) (xy 420.929229 -195.505221) (xy 420.890303 -195.540854) (xy 420.846837 -195.570781)
			(xy 420.79966 -195.594431) (xy 420.749674 -195.611353) (xy 420.697832 -195.621222) (xy 420.671498 -195.622926)
			(xy 420.669466 -195.622926) (xy 420.66134 -195.623932) (xy 420.646313 -195.63041) (xy 420.640002 -195.635626)
			(xy 420.633652 -195.641214) (xy 420.629842 -195.647818) (xy 420.627879 -195.651532) (xy 420.625065 -195.659445)
			(xy 420.624254 -195.663566) (xy 420.596568 -195.813934) (xy 420.597076 -195.825364) (xy 420.598092 -195.83273)
			(xy 420.601902 -195.84035) (xy 420.614781 -195.867166) (xy 420.632996 -195.923796) (xy 420.642214 -195.982565)
			(xy 420.642796 -196.012308) (xy 420.642796 -196.016372) (xy 420.642288 -196.029834) (xy 420.642288 -196.031612)
			(xy 420.642352 -196.037246) (xy 420.644655 -196.048272) (xy 420.64686 -196.053456) (xy 420.6494 -196.05879)
			(xy 420.652956 -196.063108) (xy 420.661846 -196.071998) (xy 420.667942 -196.076824) (xy 420.730172 -196.12483)
			(xy 420.734744 -196.127864) (xy 420.744865 -196.1321) (xy 420.750238 -196.133212) (xy 420.762176 -196.135244)
			(xy 420.774368 -196.131434) (xy 420.801923 -196.123327) (xy 420.858682 -196.114527) (xy 420.887398 -196.113908)
			(xy 420.888668 -196.113908) (xy 420.915921 -196.114369) (xy 420.969873 -196.122122) (xy 421.022173 -196.137475)
			(xy 421.071755 -196.160114) (xy 421.11761 -196.18958) (xy 421.158805 -196.225272) (xy 421.1945 -196.266464)
			(xy 421.22397 -196.312317) (xy 421.246614 -196.361897) (xy 421.261971 -196.414195) (xy 421.269729 -196.468147)
			(xy 421.269729 -196.522653) (xy 421.261971 -196.576605) (xy 421.246614 -196.628903) (xy 421.22397 -196.678483)
			(xy 421.194501 -196.724336) (xy 421.158805 -196.765528) (xy 421.11761 -196.80122) (xy 421.071755 -196.830686)
			(xy 421.022173 -196.853325) (xy 420.969873 -196.868678) (xy 420.915921 -196.876431) (xy 420.888668 -196.876924)
			(xy 420.861774 -196.876465) (xy 420.808516 -196.868925) (xy 420.75684 -196.853999) (xy 420.707764 -196.831981)
			(xy 420.662257 -196.803305) (xy 420.621216 -196.768536) (xy 420.58545 -196.728361) (xy 420.570152 -196.706236)
			(xy 420.567104 -196.701664) (xy 420.558722 -196.693282) (xy 420.554912 -196.68998) (xy 420.551454 -196.687251)
			(xy 420.54379 -196.68291) (xy 420.539672 -196.681344) (xy 420.533322 -196.67982) (xy 420.528931 -196.678954)
			(xy 420.51999 -196.678564) (xy 420.515542 -196.679058) (xy 420.505382 -196.68109) (xy 420.465504 -196.688964)
			(xy 420.461028 -196.690168) (xy 420.45259 -196.694002) (xy 420.44874 -196.696584) (xy 420.442455 -196.701277)
			(xy 420.432896 -196.7137) (xy 420.429944 -196.720968) (xy 418.361571 -207.97393) (xy 454.542396 -207.97393)
			(xy 454.546467 -207.918308) (xy 454.558593 -207.863871) (xy 454.578516 -207.81178) (xy 454.605812 -207.763145)
			(xy 454.639898 -207.719002) (xy 454.680047 -207.680293) (xy 454.725405 -207.647842) (xy 454.775005 -207.622341)
			(xy 454.827789 -207.604334) (xy 454.882632 -207.594204) (xy 454.938366 -207.592167) (xy 454.993803 -207.598267)
			(xy 455.04776 -207.612373) (xy 455.099089 -207.634185) (xy 455.146695 -207.663239) (xy 455.189563 -207.698914)
			(xy 455.22678 -207.740451) (xy 455.257553 -207.786964) (xy 455.281225 -207.837461) (xy 455.297293 -207.890868)
			(xy 455.305413 -207.946044) (xy 455.305922 -207.97393) (xy 455.305413 -208.001816) (xy 455.297293 -208.056992)
			(xy 455.281225 -208.110399) (xy 455.257553 -208.160896) (xy 455.22678 -208.207409) (xy 455.189563 -208.248946)
			(xy 455.146695 -208.284621) (xy 455.099089 -208.313675) (xy 455.04776 -208.335487) (xy 454.993803 -208.349593)
			(xy 454.938366 -208.355693) (xy 454.882632 -208.353656) (xy 454.827789 -208.343526) (xy 454.775005 -208.325519)
			(xy 454.725405 -208.300018) (xy 454.680047 -208.267567) (xy 454.639898 -208.228858) (xy 454.605812 -208.184715)
			(xy 454.578516 -208.13608) (xy 454.558593 -208.083989) (xy 454.546467 -208.029552) (xy 454.542396 -207.97393)
			(xy 418.361571 -207.97393) (xy 418.102972 -209.380836) (xy 445.288416 -209.380836) (xy 445.288416 -208.517236)
			(xy 445.288906 -208.487268) (xy 445.296729 -208.427846) (xy 445.312242 -208.369953) (xy 445.335178 -208.31458)
			(xy 445.365145 -208.262674) (xy 445.401632 -208.215124) (xy 445.444012 -208.172744) (xy 445.491562 -208.136257)
			(xy 445.543468 -208.10629) (xy 445.598841 -208.083354) (xy 445.656734 -208.067841) (xy 445.716156 -208.060018)
			(xy 445.776092 -208.060018) (xy 445.835514 -208.067841) (xy 445.893407 -208.083354) (xy 445.94878 -208.10629)
			(xy 446.000686 -208.136257) (xy 446.048236 -208.172744) (xy 446.090616 -208.215124) (xy 446.127103 -208.262674)
			(xy 446.15707 -208.31458) (xy 446.180006 -208.369953) (xy 446.195519 -208.427846) (xy 446.203342 -208.487268)
			(xy 446.203832 -208.517236) (xy 446.203832 -209.380836) (xy 446.203342 -209.410804) (xy 446.195519 -209.470226)
			(xy 446.180006 -209.528119) (xy 446.15707 -209.583492) (xy 446.127103 -209.635398) (xy 446.090616 -209.682948)
			(xy 446.048236 -209.725328) (xy 446.000686 -209.761815) (xy 445.94878 -209.791782) (xy 445.893407 -209.814718)
			(xy 445.835514 -209.830231) (xy 445.776092 -209.838054) (xy 445.716156 -209.838054) (xy 445.656734 -209.830231)
			(xy 445.598841 -209.814718) (xy 445.543468 -209.791782) (xy 445.491562 -209.761815) (xy 445.444012 -209.725328)
			(xy 445.401632 -209.682948) (xy 445.365145 -209.635398) (xy 445.335178 -209.583492) (xy 445.312242 -209.528119)
			(xy 445.296729 -209.470226) (xy 445.288906 -209.410804) (xy 445.288416 -209.380836) (xy 418.102972 -209.380836)
			(xy 417.99858 -209.94878) (xy 451.586598 -209.94878) (xy 451.590669 -209.893158) (xy 451.602795 -209.838721)
			(xy 451.622718 -209.78663) (xy 451.650014 -209.737995) (xy 451.6841 -209.693852) (xy 451.724249 -209.655143)
			(xy 451.769607 -209.622692) (xy 451.819207 -209.597191) (xy 451.871991 -209.579184) (xy 451.926834 -209.569054)
			(xy 451.982568 -209.567017) (xy 452.038005 -209.573117) (xy 452.091962 -209.587223) (xy 452.143291 -209.609035)
			(xy 452.190897 -209.638089) (xy 452.233765 -209.673764) (xy 452.270982 -209.715301) (xy 452.301755 -209.761814)
			(xy 452.325427 -209.812311) (xy 452.341495 -209.865718) (xy 452.349615 -209.920894) (xy 452.350124 -209.94878)
			(xy 452.349615 -209.976666) (xy 452.341495 -210.031842) (xy 452.325427 -210.085249) (xy 452.301755 -210.135746)
			(xy 452.270982 -210.182259) (xy 452.233765 -210.223796) (xy 452.190897 -210.259471) (xy 452.143291 -210.288525)
			(xy 452.091962 -210.310337) (xy 452.038005 -210.324443) (xy 451.982568 -210.330543) (xy 451.926834 -210.328506)
			(xy 451.871991 -210.318376) (xy 451.819207 -210.300369) (xy 451.769607 -210.274868) (xy 451.724249 -210.242417)
			(xy 451.6841 -210.203708) (xy 451.650014 -210.159565) (xy 451.622718 -210.11093) (xy 451.602795 -210.058839)
			(xy 451.590669 -210.004402) (xy 451.586598 -209.94878) (xy 417.99858 -209.94878) (xy 415.907798 -221.323662)
			(xy 417.33419 -221.323662) (xy 417.338261 -221.26804) (xy 417.350387 -221.213603) (xy 417.37031 -221.161512)
			(xy 417.397606 -221.112877) (xy 417.431692 -221.068734) (xy 417.471841 -221.030025) (xy 417.517199 -220.997574)
			(xy 417.566799 -220.972073) (xy 417.619583 -220.954066) (xy 417.674426 -220.943936) (xy 417.73016 -220.941899)
			(xy 417.785597 -220.947999) (xy 417.839554 -220.962105) (xy 417.890883 -220.983917) (xy 417.938489 -221.012971)
			(xy 417.981357 -221.048646) (xy 418.018574 -221.090183) (xy 418.049347 -221.136696) (xy 418.073019 -221.187193)
			(xy 418.089087 -221.2406) (xy 418.097207 -221.295776) (xy 418.097716 -221.323662) (xy 418.097207 -221.351548)
			(xy 418.089087 -221.406724) (xy 418.073019 -221.460131) (xy 418.049347 -221.510628) (xy 418.018574 -221.557141)
			(xy 417.981357 -221.598678) (xy 417.938489 -221.634353) (xy 417.890883 -221.663407) (xy 417.839554 -221.685219)
			(xy 417.785597 -221.699325) (xy 417.73016 -221.705425) (xy 417.674426 -221.703388) (xy 417.619583 -221.693258)
			(xy 417.566799 -221.675251) (xy 417.517199 -221.64975) (xy 417.471841 -221.617299) (xy 417.431692 -221.57859)
			(xy 417.397606 -221.534447) (xy 417.37031 -221.485812) (xy 417.350387 -221.433721) (xy 417.338261 -221.379284)
			(xy 417.33419 -221.323662) (xy 415.907798 -221.323662) (xy 415.765543 -222.0976) (xy 451.742046 -222.0976)
			(xy 451.746117 -222.041978) (xy 451.758243 -221.987541) (xy 451.778166 -221.93545) (xy 451.805462 -221.886815)
			(xy 451.839548 -221.842672) (xy 451.879697 -221.803963) (xy 451.925055 -221.771512) (xy 451.974655 -221.746011)
			(xy 452.027439 -221.728004) (xy 452.082282 -221.717874) (xy 452.138016 -221.715837) (xy 452.193453 -221.721937)
			(xy 452.24741 -221.736043) (xy 452.298739 -221.757855) (xy 452.346345 -221.786909) (xy 452.389213 -221.822584)
			(xy 452.42643 -221.864121) (xy 452.457203 -221.910634) (xy 452.480875 -221.961131) (xy 452.496943 -222.014538)
			(xy 452.505063 -222.069714) (xy 452.505572 -222.0976) (xy 452.505063 -222.125486) (xy 452.496943 -222.180662)
			(xy 452.480875 -222.234069) (xy 452.457203 -222.284566) (xy 452.42643 -222.331079) (xy 452.389213 -222.372616)
			(xy 452.346345 -222.408291) (xy 452.298739 -222.437345) (xy 452.24741 -222.459157) (xy 452.193453 -222.473263)
			(xy 452.138016 -222.479363) (xy 452.082282 -222.477326) (xy 452.027439 -222.467196) (xy 451.974655 -222.449189)
			(xy 451.925055 -222.423688) (xy 451.879697 -222.391237) (xy 451.839548 -222.352528) (xy 451.805462 -222.308385)
			(xy 451.778166 -222.25975) (xy 451.758243 -222.207659) (xy 451.746117 -222.153222) (xy 451.742046 -222.0976)
			(xy 415.765543 -222.0976) (xy 415.541492 -223.316546) (xy 443.32982 -223.316546) (xy 443.333891 -223.260924)
			(xy 443.346017 -223.206487) (xy 443.36594 -223.154396) (xy 443.393236 -223.105761) (xy 443.427322 -223.061618)
			(xy 443.467471 -223.022909) (xy 443.512829 -222.990458) (xy 443.562429 -222.964957) (xy 443.615213 -222.94695)
			(xy 443.670056 -222.93682) (xy 443.72579 -222.934783) (xy 443.781227 -222.940883) (xy 443.835184 -222.954989)
			(xy 443.886513 -222.976801) (xy 443.934119 -223.005855) (xy 443.976987 -223.04153) (xy 444.014204 -223.083067)
			(xy 444.044977 -223.12958) (xy 444.068649 -223.180077) (xy 444.084717 -223.233484) (xy 444.092837 -223.28866)
			(xy 444.093346 -223.316546) (xy 444.092837 -223.344432) (xy 444.084717 -223.399608) (xy 444.068649 -223.453015)
			(xy 444.044977 -223.503512) (xy 444.014204 -223.550025) (xy 443.976987 -223.591562) (xy 443.934119 -223.627237)
			(xy 443.886513 -223.656291) (xy 443.835184 -223.678103) (xy 443.781227 -223.692209) (xy 443.72579 -223.698309)
			(xy 443.670056 -223.696272) (xy 443.615213 -223.686142) (xy 443.562429 -223.668135) (xy 443.512829 -223.642634)
			(xy 443.467471 -223.610183) (xy 443.427322 -223.571474) (xy 443.393236 -223.527331) (xy 443.36594 -223.478696)
			(xy 443.346017 -223.426605) (xy 443.333891 -223.372168) (xy 443.32982 -223.316546) (xy 415.541492 -223.316546)
			(xy 415.435933 -223.89084) (xy 418.05809 -223.89084) (xy 418.062161 -223.835218) (xy 418.074287 -223.780781)
			(xy 418.09421 -223.72869) (xy 418.121506 -223.680055) (xy 418.155592 -223.635912) (xy 418.195741 -223.597203)
			(xy 418.241099 -223.564752) (xy 418.290699 -223.539251) (xy 418.343483 -223.521244) (xy 418.398326 -223.511114)
			(xy 418.45406 -223.509077) (xy 418.509497 -223.515177) (xy 418.563454 -223.529283) (xy 418.614783 -223.551095)
			(xy 418.662389 -223.580149) (xy 418.705257 -223.615824) (xy 418.742474 -223.657361) (xy 418.773247 -223.703874)
			(xy 418.796919 -223.754371) (xy 418.812987 -223.807778) (xy 418.821107 -223.862954) (xy 418.821616 -223.89084)
			(xy 418.821107 -223.918726) (xy 418.812987 -223.973902) (xy 418.796919 -224.027309) (xy 418.773247 -224.077806)
			(xy 418.742474 -224.124319) (xy 418.705257 -224.165856) (xy 418.662389 -224.201531) (xy 418.614783 -224.230585)
			(xy 418.563454 -224.252397) (xy 418.509497 -224.266503) (xy 418.45406 -224.272603) (xy 418.398326 -224.270566)
			(xy 418.343483 -224.260436) (xy 418.290699 -224.242429) (xy 418.241099 -224.216928) (xy 418.195741 -224.184477)
			(xy 418.155592 -224.145768) (xy 418.121506 -224.101625) (xy 418.09421 -224.05299) (xy 418.074287 -224.000899)
			(xy 418.062161 -223.946462) (xy 418.05809 -223.89084) (xy 415.435933 -223.89084) (xy 415.297366 -224.644712)
			(xy 415.287091 -224.700846) (xy 443.326518 -224.700846) (xy 443.330589 -224.645224) (xy 443.342715 -224.590787)
			(xy 443.362638 -224.538696) (xy 443.389934 -224.490061) (xy 443.42402 -224.445918) (xy 443.464169 -224.407209)
			(xy 443.509527 -224.374758) (xy 443.559127 -224.349257) (xy 443.611911 -224.33125) (xy 443.666754 -224.32112)
			(xy 443.722488 -224.319083) (xy 443.777925 -224.325183) (xy 443.831882 -224.339289) (xy 443.883211 -224.361101)
			(xy 443.930817 -224.390155) (xy 443.973685 -224.42583) (xy 444.010902 -224.467367) (xy 444.041675 -224.51388)
			(xy 444.065347 -224.564377) (xy 444.081415 -224.617784) (xy 444.089535 -224.67296) (xy 444.090044 -224.700846)
			(xy 444.089535 -224.728732) (xy 444.081415 -224.783908) (xy 444.065347 -224.837315) (xy 444.041675 -224.887812)
			(xy 444.010902 -224.934325) (xy 443.973685 -224.975862) (xy 443.930817 -225.011537) (xy 443.883211 -225.040591)
			(xy 443.831882 -225.062403) (xy 443.777925 -225.076509) (xy 443.722488 -225.082609) (xy 443.666754 -225.080572)
			(xy 443.611911 -225.070442) (xy 443.559127 -225.052435) (xy 443.509527 -225.026934) (xy 443.464169 -224.994483)
			(xy 443.42402 -224.955774) (xy 443.389934 -224.911631) (xy 443.362638 -224.862996) (xy 443.342715 -224.810905)
			(xy 443.330589 -224.756468) (xy 443.326518 -224.700846) (xy 415.287091 -224.700846) (xy 415.269934 -224.794572)
			(xy 415.268804 -224.806235) (xy 415.276011 -224.828504) (xy 415.292364 -224.845249) (xy 415.303208 -224.84969)
			(xy 415.311266 -224.852373) (xy 415.327992 -224.855307) (xy 415.336482 -224.855532) (xy 415.363668 -224.85614)
			(xy 415.417459 -224.864107) (xy 415.469576 -224.879626) (xy 415.518963 -224.902383) (xy 415.564621 -224.931917)
			(xy 415.605626 -224.967631) (xy 415.641149 -225.008802) (xy 415.670471 -225.054597) (xy 415.692998 -225.10409)
			(xy 415.708274 -225.156278) (xy 415.715991 -225.210105) (xy 415.716466 -225.237294) (xy 415.716444 -225.238564)
			(xy 418.305232 -225.238564) (xy 418.309303 -225.182942) (xy 418.321429 -225.128505) (xy 418.341352 -225.076414)
			(xy 418.368648 -225.027779) (xy 418.402734 -224.983636) (xy 418.442883 -224.944927) (xy 418.488241 -224.912476)
			(xy 418.537841 -224.886975) (xy 418.590625 -224.868968) (xy 418.645468 -224.858838) (xy 418.701202 -224.856801)
			(xy 418.756639 -224.862901) (xy 418.810596 -224.877007) (xy 418.861925 -224.898819) (xy 418.909531 -224.927873)
			(xy 418.952399 -224.963548) (xy 418.989616 -225.005085) (xy 419.020389 -225.051598) (xy 419.044061 -225.102095)
			(xy 419.060129 -225.155502) (xy 419.068249 -225.210678) (xy 419.068758 -225.238564) (xy 419.068249 -225.26645)
			(xy 419.060129 -225.321626) (xy 419.044061 -225.375033) (xy 419.020389 -225.42553) (xy 418.989616 -225.472043)
			(xy 418.952399 -225.51358) (xy 418.909531 -225.549255) (xy 418.861925 -225.578309) (xy 418.810596 -225.600121)
			(xy 418.756639 -225.614227) (xy 418.701202 -225.620327) (xy 418.645468 -225.61829) (xy 418.590625 -225.60816)
			(xy 418.537841 -225.590153) (xy 418.488241 -225.564652) (xy 418.442883 -225.532201) (xy 418.402734 -225.493492)
			(xy 418.368648 -225.449349) (xy 418.341352 -225.400714) (xy 418.321429 -225.348623) (xy 418.309303 -225.294186)
			(xy 418.305232 -225.238564) (xy 415.716444 -225.238564) (xy 415.716003 -225.264565) (xy 415.708242 -225.318553)
			(xy 415.692876 -225.370887) (xy 415.670219 -225.420501) (xy 415.640731 -225.466386) (xy 415.605014 -225.507607)
			(xy 415.563794 -225.543325) (xy 415.51791 -225.572814) (xy 415.468296 -225.595472) (xy 415.415963 -225.610839)
			(xy 415.361975 -225.618602) (xy 415.334704 -225.619056) (xy 415.300422 -225.61826) (xy 415.232962 -225.605991)
			(xy 415.200592 -225.594672) (xy 415.192547 -225.591884) (xy 415.175824 -225.588689) (xy 415.167318 -225.588322)
			(xy 415.155969 -225.588642) (xy 415.13526 -225.597871) (xy 415.120544 -225.61512) (xy 415.117026 -225.625914)
			(xy 414.923051 -226.681538) (xy 457.325982 -226.681538) (xy 457.330053 -226.625916) (xy 457.342179 -226.571479)
			(xy 457.362102 -226.519388) (xy 457.389398 -226.470753) (xy 457.423484 -226.42661) (xy 457.463633 -226.387901)
			(xy 457.508991 -226.35545) (xy 457.558591 -226.329949) (xy 457.611375 -226.311942) (xy 457.666218 -226.301812)
			(xy 457.721952 -226.299775) (xy 457.777389 -226.305875) (xy 457.831346 -226.319981) (xy 457.882675 -226.341793)
			(xy 457.930281 -226.370847) (xy 457.973149 -226.406522) (xy 458.010366 -226.448059) (xy 458.041139 -226.494572)
			(xy 458.064811 -226.545069) (xy 458.080879 -226.598476) (xy 458.088999 -226.653652) (xy 458.089508 -226.681538)
			(xy 458.088999 -226.709424) (xy 458.080879 -226.7646) (xy 458.064811 -226.818007) (xy 458.041139 -226.868504)
			(xy 458.010366 -226.915017) (xy 457.973149 -226.956554) (xy 457.930281 -226.992229) (xy 457.882675 -227.021283)
			(xy 457.831346 -227.043095) (xy 457.777389 -227.057201) (xy 457.721952 -227.063301) (xy 457.666218 -227.061264)
			(xy 457.611375 -227.051134) (xy 457.558591 -227.033127) (xy 457.508991 -227.007626) (xy 457.463633 -226.975175)
			(xy 457.423484 -226.936466) (xy 457.389398 -226.892323) (xy 457.362102 -226.843688) (xy 457.342179 -226.791597)
			(xy 457.330053 -226.73716) (xy 457.325982 -226.681538) (xy 414.923051 -226.681538) (xy 414.558058 -228.667848)
			(xy 442.823618 -228.667848) (xy 442.823618 -228.613352) (xy 442.831374 -228.55941) (xy 442.846727 -228.50712)
			(xy 442.869366 -228.457548) (xy 442.898829 -228.411703) (xy 442.934517 -228.370517) (xy 442.975703 -228.334829)
			(xy 443.021548 -228.305366) (xy 443.07112 -228.282727) (xy 443.12341 -228.267374) (xy 443.177352 -228.259618)
			(xy 443.2046 -228.259132) (xy 443.233517 -228.259638) (xy 443.29069 -228.268368) (xy 443.345889 -228.285628)
			(xy 443.397851 -228.311022) (xy 443.445385 -228.343968) (xy 443.487401 -228.383711) (xy 443.50559 -228.406198)
			(xy 443.513212 -228.41499) (xy 443.534101 -228.425182) (xy 443.545722 -228.425756) (xy 443.625478 -228.425756)
			(xy 443.637109 -228.425205) (xy 443.658019 -228.415026) (xy 443.66561 -228.406198) (xy 443.683795 -228.383709)
			(xy 443.725816 -228.343975) (xy 443.773352 -228.311036) (xy 443.825315 -228.285649) (xy 443.880513 -228.268394)
			(xy 443.937684 -228.259666) (xy 443.9666 -228.259132) (xy 443.993854 -228.259538) (xy 444.047807 -228.267295)
			(xy 444.100108 -228.282652) (xy 444.14969 -228.305295) (xy 444.195545 -228.334765) (xy 444.23674 -228.37046)
			(xy 444.272435 -228.411655) (xy 444.301905 -228.45751) (xy 444.324548 -228.507092) (xy 444.339905 -228.559393)
			(xy 444.347662 -228.613346) (xy 444.347662 -228.667854) (xy 444.339905 -228.721807) (xy 444.324548 -228.774108)
			(xy 444.301905 -228.82369) (xy 444.272435 -228.869545) (xy 444.23674 -228.91074) (xy 444.195545 -228.946435)
			(xy 444.14969 -228.975905) (xy 444.100108 -228.998548) (xy 444.047807 -229.013905) (xy 443.993854 -229.021662)
			(xy 443.9666 -229.022148) (xy 443.937682 -229.021649) (xy 443.880509 -229.012919) (xy 443.825309 -228.995658)
			(xy 443.773347 -228.970263) (xy 443.725814 -228.937315) (xy 443.683799 -228.89757) (xy 443.66561 -228.875082)
			(xy 443.657992 -228.866286) (xy 443.637099 -228.856097) (xy 443.625478 -228.855524) (xy 443.545722 -228.855524)
			(xy 443.534092 -228.856082) (xy 443.513182 -228.866256) (xy 443.50559 -228.875082) (xy 443.4874 -228.897567)
			(xy 443.445381 -228.937302) (xy 443.397846 -228.970242) (xy 443.345884 -228.99563) (xy 443.290686 -229.012886)
			(xy 443.233516 -229.021614) (xy 443.2046 -229.022148) (xy 443.177352 -229.021582) (xy 443.12341 -229.013826)
			(xy 443.07112 -228.998473) (xy 443.021548 -228.975834) (xy 442.975703 -228.946371) (xy 442.934517 -228.910683)
			(xy 442.898829 -228.869497) (xy 442.869366 -228.823652) (xy 442.846727 -228.77408) (xy 442.831374 -228.72179)
			(xy 442.823618 -228.667848) (xy 414.558058 -228.667848) (xy 414.474611 -229.12197) (xy 444.350392 -229.12197)
			(xy 444.354463 -229.066348) (xy 444.366589 -229.011911) (xy 444.386512 -228.95982) (xy 444.413808 -228.911185)
			(xy 444.447894 -228.867042) (xy 444.488043 -228.828333) (xy 444.533401 -228.795882) (xy 444.583001 -228.770381)
			(xy 444.635785 -228.752374) (xy 444.690628 -228.742244) (xy 444.746362 -228.740207) (xy 444.801799 -228.746307)
			(xy 444.855756 -228.760413) (xy 444.907085 -228.782225) (xy 444.954691 -228.811279) (xy 444.997559 -228.846954)
			(xy 445.034776 -228.888491) (xy 445.065549 -228.935004) (xy 445.089221 -228.985501) (xy 445.105289 -229.038908)
			(xy 445.113409 -229.094084) (xy 445.113918 -229.12197) (xy 445.113409 -229.149856) (xy 445.105289 -229.205032)
			(xy 445.089221 -229.258439) (xy 445.065549 -229.308936) (xy 445.034776 -229.355449) (xy 444.997559 -229.396986)
			(xy 444.954691 -229.432661) (xy 444.907085 -229.461715) (xy 444.855756 -229.483527) (xy 444.801799 -229.497633)
			(xy 444.746362 -229.503733) (xy 444.690628 -229.501696) (xy 444.635785 -229.491566) (xy 444.583001 -229.473559)
			(xy 444.533401 -229.448058) (xy 444.488043 -229.415607) (xy 444.447894 -229.376898) (xy 444.413808 -229.332755)
			(xy 444.386512 -229.28412) (xy 444.366589 -229.232029) (xy 444.354463 -229.177592) (xy 444.350392 -229.12197)
			(xy 414.474611 -229.12197) (xy 414.138188 -230.952802) (xy 417.376354 -230.952802) (xy 417.380425 -230.89718)
			(xy 417.392551 -230.842743) (xy 417.412474 -230.790652) (xy 417.43977 -230.742017) (xy 417.473856 -230.697874)
			(xy 417.514005 -230.659165) (xy 417.559363 -230.626714) (xy 417.608963 -230.601213) (xy 417.661747 -230.583206)
			(xy 417.71659 -230.573076) (xy 417.772324 -230.571039) (xy 417.827761 -230.577139) (xy 417.881718 -230.591245)
			(xy 417.933047 -230.613057) (xy 417.980653 -230.642111) (xy 418.023521 -230.677786) (xy 418.060738 -230.719323)
			(xy 418.091511 -230.765836) (xy 418.115183 -230.816333) (xy 418.131251 -230.86974) (xy 418.139371 -230.924916)
			(xy 418.13988 -230.952802) (xy 418.139371 -230.980688) (xy 418.131251 -231.035864) (xy 418.115183 -231.089271)
			(xy 418.091511 -231.139768) (xy 418.060738 -231.186281) (xy 418.023521 -231.227818) (xy 417.980653 -231.263493)
			(xy 417.933047 -231.292547) (xy 417.881718 -231.314359) (xy 417.827761 -231.328465) (xy 417.772324 -231.334565)
			(xy 417.71659 -231.332528) (xy 417.661747 -231.322398) (xy 417.608963 -231.304391) (xy 417.559363 -231.27889)
			(xy 417.514005 -231.246439) (xy 417.473856 -231.20773) (xy 417.43977 -231.163587) (xy 417.412474 -231.114952)
			(xy 417.392551 -231.062861) (xy 417.380425 -231.008424) (xy 417.376354 -230.952802) (xy 414.138188 -230.952802)
			(xy 413.818148 -232.69448) (xy 451.24192 -232.69448) (xy 451.245991 -232.638858) (xy 451.258117 -232.584421)
			(xy 451.27804 -232.53233) (xy 451.305336 -232.483695) (xy 451.339422 -232.439552) (xy 451.379571 -232.400843)
			(xy 451.424929 -232.368392) (xy 451.474529 -232.342891) (xy 451.527313 -232.324884) (xy 451.582156 -232.314754)
			(xy 451.63789 -232.312717) (xy 451.693327 -232.318817) (xy 451.747284 -232.332923) (xy 451.798613 -232.354735)
			(xy 451.846219 -232.383789) (xy 451.889087 -232.419464) (xy 451.926304 -232.461001) (xy 451.957077 -232.507514)
			(xy 451.980749 -232.558011) (xy 451.996817 -232.611418) (xy 452.004937 -232.666594) (xy 452.005446 -232.69448)
			(xy 452.004937 -232.722366) (xy 451.996817 -232.777542) (xy 451.980749 -232.830949) (xy 451.957077 -232.881446)
			(xy 451.926304 -232.927959) (xy 451.889087 -232.969496) (xy 451.846219 -233.005171) (xy 451.798613 -233.034225)
			(xy 451.747284 -233.056037) (xy 451.693327 -233.070143) (xy 451.63789 -233.076243) (xy 451.582156 -233.074206)
			(xy 451.527313 -233.064076) (xy 451.474529 -233.046069) (xy 451.424929 -233.020568) (xy 451.379571 -232.988117)
			(xy 451.339422 -232.949408) (xy 451.305336 -232.905265) (xy 451.27804 -232.85663) (xy 451.258117 -232.804539)
			(xy 451.245991 -232.750102) (xy 451.24192 -232.69448) (xy 413.818148 -232.69448) (xy 413.671453 -233.492802)
			(xy 414.907982 -233.492802) (xy 414.912053 -233.43718) (xy 414.924179 -233.382743) (xy 414.944102 -233.330652)
			(xy 414.971398 -233.282017) (xy 415.005484 -233.237874) (xy 415.045633 -233.199165) (xy 415.090991 -233.166714)
			(xy 415.140591 -233.141213) (xy 415.193375 -233.123206) (xy 415.248218 -233.113076) (xy 415.303952 -233.111039)
			(xy 415.359389 -233.117139) (xy 415.413346 -233.131245) (xy 415.464675 -233.153057) (xy 415.512281 -233.182111)
			(xy 415.555149 -233.217786) (xy 415.592366 -233.259323) (xy 415.623139 -233.305836) (xy 415.646811 -233.356333)
			(xy 415.662879 -233.40974) (xy 415.670999 -233.464916) (xy 415.671508 -233.492802) (xy 415.671485 -233.494072)
			(xy 418.149784 -233.494072) (xy 418.153855 -233.43845) (xy 418.165981 -233.384013) (xy 418.185904 -233.331922)
			(xy 418.2132 -233.283287) (xy 418.247286 -233.239144) (xy 418.287435 -233.200435) (xy 418.332793 -233.167984)
			(xy 418.382393 -233.142483) (xy 418.435177 -233.124476) (xy 418.49002 -233.114346) (xy 418.545754 -233.112309)
			(xy 418.601191 -233.118409) (xy 418.655148 -233.132515) (xy 418.688293 -233.1466) (xy 442.035182 -233.1466)
			(xy 442.039253 -233.090978) (xy 442.051379 -233.036541) (xy 442.071302 -232.98445) (xy 442.098598 -232.935815)
			(xy 442.132684 -232.891672) (xy 442.172833 -232.852963) (xy 442.218191 -232.820512) (xy 442.267791 -232.795011)
			(xy 442.320575 -232.777004) (xy 442.375418 -232.766874) (xy 442.431152 -232.764837) (xy 442.486589 -232.770937)
			(xy 442.540546 -232.785043) (xy 442.591875 -232.806855) (xy 442.639481 -232.835909) (xy 442.682349 -232.871584)
			(xy 442.719566 -232.913121) (xy 442.750339 -232.959634) (xy 442.774011 -233.010131) (xy 442.790079 -233.063538)
			(xy 442.798199 -233.118714) (xy 442.798708 -233.1466) (xy 442.798199 -233.174486) (xy 442.790079 -233.229662)
			(xy 442.775866 -233.276902) (xy 443.9318 -233.276902) (xy 443.935871 -233.22128) (xy 443.947997 -233.166843)
			(xy 443.96792 -233.114752) (xy 443.995216 -233.066117) (xy 444.029302 -233.021974) (xy 444.069451 -232.983265)
			(xy 444.114809 -232.950814) (xy 444.164409 -232.925313) (xy 444.217193 -232.907306) (xy 444.272036 -232.897176)
			(xy 444.32777 -232.895139) (xy 444.383207 -232.901239) (xy 444.437164 -232.915345) (xy 444.488493 -232.937157)
			(xy 444.536099 -232.966211) (xy 444.578967 -233.001886) (xy 444.616184 -233.043423) (xy 444.646957 -233.089936)
			(xy 444.670629 -233.140433) (xy 444.686697 -233.19384) (xy 444.694817 -233.249016) (xy 444.695326 -233.276902)
			(xy 444.694817 -233.304788) (xy 444.686697 -233.359964) (xy 444.670629 -233.413371) (xy 444.646957 -233.463868)
			(xy 444.616184 -233.510381) (xy 444.578967 -233.551918) (xy 444.536099 -233.587593) (xy 444.488493 -233.616647)
			(xy 444.437164 -233.638459) (xy 444.383207 -233.652565) (xy 444.32777 -233.658665) (xy 444.272036 -233.656628)
			(xy 444.217193 -233.646498) (xy 444.164409 -233.628491) (xy 444.114809 -233.60299) (xy 444.069451 -233.570539)
			(xy 444.029302 -233.53183) (xy 443.995216 -233.487687) (xy 443.96792 -233.439052) (xy 443.947997 -233.386961)
			(xy 443.935871 -233.332524) (xy 443.9318 -233.276902) (xy 442.775866 -233.276902) (xy 442.774011 -233.283069)
			(xy 442.750339 -233.333566) (xy 442.719566 -233.380079) (xy 442.682349 -233.421616) (xy 442.639481 -233.457291)
			(xy 442.591875 -233.486345) (xy 442.540546 -233.508157) (xy 442.486589 -233.522263) (xy 442.431152 -233.528363)
			(xy 442.375418 -233.526326) (xy 442.320575 -233.516196) (xy 442.267791 -233.498189) (xy 442.218191 -233.472688)
			(xy 442.172833 -233.440237) (xy 442.132684 -233.401528) (xy 442.098598 -233.357385) (xy 442.071302 -233.30875)
			(xy 442.051379 -233.256659) (xy 442.039253 -233.202222) (xy 442.035182 -233.1466) (xy 418.688293 -233.1466)
			(xy 418.706477 -233.154327) (xy 418.754083 -233.183381) (xy 418.796951 -233.219056) (xy 418.834168 -233.260593)
			(xy 418.864941 -233.307106) (xy 418.888613 -233.357603) (xy 418.904681 -233.41101) (xy 418.912801 -233.466186)
			(xy 418.91331 -233.494072) (xy 418.912801 -233.521958) (xy 418.904681 -233.577134) (xy 418.888613 -233.630541)
			(xy 418.864941 -233.681038) (xy 418.834168 -233.727551) (xy 418.796951 -233.769088) (xy 418.754083 -233.804763)
			(xy 418.706477 -233.833817) (xy 418.655148 -233.855629) (xy 418.601191 -233.869735) (xy 418.545754 -233.875835)
			(xy 418.49002 -233.873798) (xy 418.435177 -233.863668) (xy 418.382393 -233.845661) (xy 418.332793 -233.82016)
			(xy 418.287435 -233.787709) (xy 418.247286 -233.749) (xy 418.2132 -233.704857) (xy 418.185904 -233.656222)
			(xy 418.165981 -233.604131) (xy 418.153855 -233.549694) (xy 418.149784 -233.494072) (xy 415.671485 -233.494072)
			(xy 415.670999 -233.520688) (xy 415.662879 -233.575864) (xy 415.646811 -233.629271) (xy 415.623139 -233.679768)
			(xy 415.592366 -233.726281) (xy 415.555149 -233.767818) (xy 415.512281 -233.803493) (xy 415.464675 -233.832547)
			(xy 415.413346 -233.854359) (xy 415.359389 -233.868465) (xy 415.303952 -233.874565) (xy 415.248218 -233.872528)
			(xy 415.193375 -233.862398) (xy 415.140591 -233.844391) (xy 415.090991 -233.81889) (xy 415.045633 -233.786439)
			(xy 415.005484 -233.74773) (xy 414.971398 -233.703587) (xy 414.944102 -233.654952) (xy 414.924179 -233.602861)
			(xy 414.912053 -233.548424) (xy 414.907982 -233.492802) (xy 413.671453 -233.492802) (xy 413.593788 -233.915458)
			(xy 413.593534 -233.918252) (xy 413.593534 -234.655869) (xy 448.021157 -234.655869) (xy 448.021157 -234.595931)
			(xy 448.028981 -234.536505) (xy 448.044494 -234.478608) (xy 448.067432 -234.423232) (xy 448.097401 -234.371324)
			(xy 448.13389 -234.323771) (xy 448.176273 -234.281388) (xy 448.223825 -234.2449) (xy 448.275734 -234.214931)
			(xy 448.33111 -234.191993) (xy 448.389007 -234.17648) (xy 448.448433 -234.168657) (xy 448.478402 -234.168188)
			(xy 449.342002 -234.168188) (xy 449.371969 -234.168686) (xy 449.431391 -234.176509) (xy 449.489283 -234.192022)
			(xy 449.544656 -234.214958) (xy 449.596561 -234.244925) (xy 449.64411 -234.281411) (xy 449.68649 -234.323792)
			(xy 449.722976 -234.371341) (xy 449.752943 -234.423246) (xy 449.775879 -234.478618) (xy 449.791391 -234.536511)
			(xy 449.799214 -234.595933) (xy 449.799214 -234.655867) (xy 449.791391 -234.715289) (xy 449.775879 -234.773182)
			(xy 449.752943 -234.828554) (xy 449.749404 -234.834684) (xy 450.697598 -234.834684) (xy 450.701669 -234.779062)
			(xy 450.713795 -234.724625) (xy 450.733718 -234.672534) (xy 450.761014 -234.623899) (xy 450.7951 -234.579756)
			(xy 450.835249 -234.541047) (xy 450.880607 -234.508596) (xy 450.930207 -234.483095) (xy 450.982991 -234.465088)
			(xy 451.037834 -234.454958) (xy 451.093568 -234.452921) (xy 451.149005 -234.459021) (xy 451.202962 -234.473127)
			(xy 451.254291 -234.494939) (xy 451.301897 -234.523993) (xy 451.344765 -234.559668) (xy 451.381982 -234.601205)
			(xy 451.412755 -234.647718) (xy 451.436427 -234.698215) (xy 451.452495 -234.751622) (xy 451.460615 -234.806798)
			(xy 451.461124 -234.834684) (xy 451.460615 -234.86257) (xy 451.452495 -234.917746) (xy 451.436427 -234.971153)
			(xy 451.412755 -235.02165) (xy 451.381982 -235.068163) (xy 451.344765 -235.1097) (xy 451.301897 -235.145375)
			(xy 451.254291 -235.174429) (xy 451.202962 -235.196241) (xy 451.149005 -235.210347) (xy 451.093568 -235.216447)
			(xy 451.037834 -235.21441) (xy 450.982991 -235.20428) (xy 450.930207 -235.186273) (xy 450.880607 -235.160772)
			(xy 450.835249 -235.128321) (xy 450.7951 -235.089612) (xy 450.761014 -235.045469) (xy 450.733718 -234.996834)
			(xy 450.713795 -234.944743) (xy 450.701669 -234.890306) (xy 450.697598 -234.834684) (xy 449.749404 -234.834684)
			(xy 449.722976 -234.880459) (xy 449.68649 -234.928008) (xy 449.64411 -234.970389) (xy 449.596561 -235.006875)
			(xy 449.544656 -235.036842) (xy 449.489283 -235.059778) (xy 449.431391 -235.075291) (xy 449.371969 -235.083114)
			(xy 449.342002 -235.083604) (xy 448.478402 -235.083604) (xy 448.448433 -235.083143) (xy 448.389007 -235.07532)
			(xy 448.33111 -235.059807) (xy 448.275734 -235.036869) (xy 448.223825 -235.0069) (xy 448.176273 -234.970412)
			(xy 448.13389 -234.928029) (xy 448.097401 -234.880476) (xy 448.067432 -234.828568) (xy 448.044494 -234.773192)
			(xy 448.028981 -234.715295) (xy 448.021157 -234.655869) (xy 413.593534 -234.655869) (xy 413.593534 -235.181394)
			(xy 418.770052 -235.181394) (xy 418.774123 -235.125772) (xy 418.786249 -235.071335) (xy 418.806172 -235.019244)
			(xy 418.833468 -234.970609) (xy 418.867554 -234.926466) (xy 418.907703 -234.887757) (xy 418.953061 -234.855306)
			(xy 419.002661 -234.829805) (xy 419.055445 -234.811798) (xy 419.110288 -234.801668) (xy 419.166022 -234.799631)
			(xy 419.221459 -234.805731) (xy 419.275416 -234.819837) (xy 419.326745 -234.841649) (xy 419.374351 -234.870703)
			(xy 419.417219 -234.906378) (xy 419.454436 -234.947915) (xy 419.485209 -234.994428) (xy 419.508881 -235.044925)
			(xy 419.524949 -235.098332) (xy 419.533069 -235.153508) (xy 419.533578 -235.181394) (xy 419.533069 -235.20928)
			(xy 419.524949 -235.264456) (xy 419.508881 -235.317863) (xy 419.485209 -235.36836) (xy 419.454436 -235.414873)
			(xy 419.417219 -235.45641) (xy 419.374351 -235.492085) (xy 419.326745 -235.521139) (xy 419.275416 -235.542951)
			(xy 419.221459 -235.557057) (xy 419.166022 -235.563157) (xy 419.110288 -235.56112) (xy 419.055445 -235.55099)
			(xy 419.002661 -235.532983) (xy 418.953061 -235.507482) (xy 418.907703 -235.475031) (xy 418.867554 -235.436322)
			(xy 418.833468 -235.392179) (xy 418.806172 -235.343544) (xy 418.786249 -235.291453) (xy 418.774123 -235.237016)
			(xy 418.770052 -235.181394) (xy 413.593534 -235.181394) (xy 413.593534 -236.4994) (xy 444.422782 -236.4994)
			(xy 444.426853 -236.443778) (xy 444.438979 -236.389341) (xy 444.458902 -236.33725) (xy 444.486198 -236.288615)
			(xy 444.520284 -236.244472) (xy 444.560433 -236.205763) (xy 444.605791 -236.173312) (xy 444.655391 -236.147811)
			(xy 444.708175 -236.129804) (xy 444.763018 -236.119674) (xy 444.818752 -236.117637) (xy 444.874189 -236.123737)
			(xy 444.928146 -236.137843) (xy 444.979475 -236.159655) (xy 445.027081 -236.188709) (xy 445.069949 -236.224384)
			(xy 445.107166 -236.265921) (xy 445.137939 -236.312434) (xy 445.161611 -236.362931) (xy 445.169274 -236.388402)
			(xy 450.160898 -236.388402) (xy 450.161419 -236.359485) (xy 450.170147 -236.302314) (xy 450.187405 -236.247115)
			(xy 450.212796 -236.195154) (xy 450.245739 -236.14762) (xy 450.285479 -236.105603) (xy 450.307964 -236.087412)
			(xy 450.316766 -236.079801) (xy 450.32695 -236.058903) (xy 450.327522 -236.04728) (xy 450.327522 -235.967524)
			(xy 450.326947 -235.955897) (xy 450.316783 -235.934987) (xy 450.307964 -235.927392) (xy 450.285469 -235.909215)
			(xy 450.245736 -235.867191) (xy 450.2128 -235.819653) (xy 450.187414 -235.767689) (xy 450.170159 -235.71249)
			(xy 450.161432 -235.655319) (xy 450.160898 -235.626402) (xy 450.161384 -235.599151) (xy 450.16914 -235.545203)
			(xy 450.184495 -235.492908) (xy 450.207137 -235.443331) (xy 450.236603 -235.397481) (xy 450.272294 -235.35629)
			(xy 450.313485 -235.320599) (xy 450.359335 -235.291133) (xy 450.408912 -235.268491) (xy 450.461207 -235.253136)
			(xy 450.515155 -235.24538) (xy 450.569657 -235.24538) (xy 450.623605 -235.253136) (xy 450.6759 -235.268491)
			(xy 450.725477 -235.291133) (xy 450.771327 -235.320599) (xy 450.812518 -235.35629) (xy 450.848209 -235.397481)
			(xy 450.877675 -235.443331) (xy 450.900317 -235.492908) (xy 450.915672 -235.545203) (xy 450.923428 -235.599151)
			(xy 450.923914 -235.626402) (xy 450.92343 -235.655321) (xy 450.914698 -235.712495) (xy 450.897436 -235.767696)
			(xy 450.872038 -235.819658) (xy 450.839087 -235.867191) (xy 450.799338 -235.909204) (xy 450.776848 -235.927392)
			(xy 450.768046 -235.935003) (xy 450.757861 -235.955901) (xy 450.75729 -235.967524) (xy 450.75729 -236.04728)
			(xy 450.757859 -236.058908) (xy 450.768027 -236.079818) (xy 450.776848 -236.087412) (xy 450.799347 -236.105584)
			(xy 450.839079 -236.147609) (xy 450.872015 -236.195149) (xy 450.8974 -236.247113) (xy 450.914654 -236.302313)
			(xy 450.921397 -236.346492) (xy 454.16038 -236.346492) (xy 454.164451 -236.29087) (xy 454.176577 -236.236433)
			(xy 454.1965 -236.184342) (xy 454.223796 -236.135707) (xy 454.257882 -236.091564) (xy 454.298031 -236.052855)
			(xy 454.343389 -236.020404) (xy 454.392989 -235.994903) (xy 454.445773 -235.976896) (xy 454.500616 -235.966766)
			(xy 454.55635 -235.964729) (xy 454.611787 -235.970829) (xy 454.665744 -235.984935) (xy 454.717073 -236.006747)
			(xy 454.764679 -236.035801) (xy 454.807547 -236.071476) (xy 454.844764 -236.113013) (xy 454.875537 -236.159526)
			(xy 454.899209 -236.210023) (xy 454.915277 -236.26343) (xy 454.922866 -236.314996) (xy 455.160378 -236.314996)
			(xy 455.164449 -236.259374) (xy 455.176575 -236.204937) (xy 455.196498 -236.152846) (xy 455.223794 -236.104211)
			(xy 455.25788 -236.060068) (xy 455.298029 -236.021359) (xy 455.343387 -235.988908) (xy 455.392987 -235.963407)
			(xy 455.445771 -235.9454) (xy 455.500614 -235.93527) (xy 455.556348 -235.933233) (xy 455.611785 -235.939333)
			(xy 455.665742 -235.953439) (xy 455.717071 -235.975251) (xy 455.764677 -236.004305) (xy 455.807545 -236.03998)
			(xy 455.844762 -236.081517) (xy 455.875535 -236.12803) (xy 455.899207 -236.178527) (xy 455.915275 -236.231934)
			(xy 455.923395 -236.28711) (xy 455.923904 -236.314996) (xy 455.923395 -236.342882) (xy 455.915275 -236.398058)
			(xy 455.910691 -236.413294) (xy 456.148692 -236.413294) (xy 456.152763 -236.357672) (xy 456.164889 -236.303235)
			(xy 456.184812 -236.251144) (xy 456.212108 -236.202509) (xy 456.246194 -236.158366) (xy 456.286343 -236.119657)
			(xy 456.331701 -236.087206) (xy 456.381301 -236.061705) (xy 456.434085 -236.043698) (xy 456.488928 -236.033568)
			(xy 456.544662 -236.031531) (xy 456.600099 -236.037631) (xy 456.654056 -236.051737) (xy 456.705385 -236.073549)
			(xy 456.752991 -236.102603) (xy 456.795859 -236.138278) (xy 456.833076 -236.179815) (xy 456.863849 -236.226328)
			(xy 456.887521 -236.276825) (xy 456.903589 -236.330232) (xy 456.911709 -236.385408) (xy 456.912218 -236.413294)
			(xy 456.911709 -236.44118) (xy 456.903589 -236.496356) (xy 456.887521 -236.549763) (xy 456.863849 -236.60026)
			(xy 456.833076 -236.646773) (xy 456.795859 -236.68831) (xy 456.752991 -236.723985) (xy 456.705385 -236.753039)
			(xy 456.654056 -236.774851) (xy 456.600099 -236.788957) (xy 456.544662 -236.795057) (xy 456.488928 -236.79302)
			(xy 456.434085 -236.78289) (xy 456.381301 -236.764883) (xy 456.331701 -236.739382) (xy 456.286343 -236.706931)
			(xy 456.246194 -236.668222) (xy 456.212108 -236.624079) (xy 456.184812 -236.575444) (xy 456.164889 -236.523353)
			(xy 456.152763 -236.468916) (xy 456.148692 -236.413294) (xy 455.910691 -236.413294) (xy 455.899207 -236.451465)
			(xy 455.875535 -236.501962) (xy 455.844762 -236.548475) (xy 455.807545 -236.590012) (xy 455.764677 -236.625687)
			(xy 455.717071 -236.654741) (xy 455.665742 -236.676553) (xy 455.611785 -236.690659) (xy 455.556348 -236.696759)
			(xy 455.500614 -236.694722) (xy 455.445771 -236.684592) (xy 455.392987 -236.666585) (xy 455.343387 -236.641084)
			(xy 455.298029 -236.608633) (xy 455.25788 -236.569924) (xy 455.223794 -236.525781) (xy 455.196498 -236.477146)
			(xy 455.176575 -236.425055) (xy 455.164449 -236.370618) (xy 455.160378 -236.314996) (xy 454.922866 -236.314996)
			(xy 454.923397 -236.318606) (xy 454.923906 -236.346492) (xy 454.923397 -236.374378) (xy 454.915277 -236.429554)
			(xy 454.899209 -236.482961) (xy 454.875537 -236.533458) (xy 454.844764 -236.579971) (xy 454.807547 -236.621508)
			(xy 454.764679 -236.657183) (xy 454.717073 -236.686237) (xy 454.665744 -236.708049) (xy 454.611787 -236.722155)
			(xy 454.55635 -236.728255) (xy 454.500616 -236.726218) (xy 454.445773 -236.716088) (xy 454.392989 -236.698081)
			(xy 454.343389 -236.67258) (xy 454.298031 -236.640129) (xy 454.257882 -236.60142) (xy 454.223796 -236.557277)
			(xy 454.1965 -236.508642) (xy 454.176577 -236.456551) (xy 454.164451 -236.402114) (xy 454.16038 -236.346492)
			(xy 450.921397 -236.346492) (xy 450.92338 -236.359485) (xy 450.923914 -236.388402) (xy 450.923428 -236.415653)
			(xy 450.915672 -236.469601) (xy 450.900317 -236.521896) (xy 450.877675 -236.571473) (xy 450.848209 -236.617323)
			(xy 450.812518 -236.658514) (xy 450.771327 -236.694205) (xy 450.725477 -236.723671) (xy 450.6759 -236.746313)
			(xy 450.623605 -236.761668) (xy 450.569657 -236.769424) (xy 450.515155 -236.769424) (xy 450.461207 -236.761668)
			(xy 450.408912 -236.746313) (xy 450.359335 -236.723671) (xy 450.313485 -236.694205) (xy 450.272294 -236.658514)
			(xy 450.236603 -236.617323) (xy 450.207137 -236.571473) (xy 450.184495 -236.521896) (xy 450.16914 -236.469601)
			(xy 450.161384 -236.415653) (xy 450.160898 -236.388402) (xy 445.169274 -236.388402) (xy 445.177679 -236.416338)
			(xy 445.185799 -236.471514) (xy 445.186308 -236.4994) (xy 445.185799 -236.527286) (xy 445.177679 -236.582462)
			(xy 445.161611 -236.635869) (xy 445.137939 -236.686366) (xy 445.107166 -236.732879) (xy 445.069949 -236.774416)
			(xy 445.027081 -236.810091) (xy 444.979475 -236.839145) (xy 444.928146 -236.860957) (xy 444.874189 -236.875063)
			(xy 444.818752 -236.881163) (xy 444.763018 -236.879126) (xy 444.708175 -236.868996) (xy 444.655391 -236.850989)
			(xy 444.605791 -236.825488) (xy 444.560433 -236.793037) (xy 444.520284 -236.754328) (xy 444.486198 -236.710185)
			(xy 444.458902 -236.66155) (xy 444.438979 -236.609459) (xy 444.426853 -236.555022) (xy 444.422782 -236.4994)
			(xy 413.593534 -236.4994) (xy 413.593534 -237.5154) (xy 443.254382 -237.5154) (xy 443.258453 -237.459778)
			(xy 443.270579 -237.405341) (xy 443.290502 -237.35325) (xy 443.317798 -237.304615) (xy 443.351884 -237.260472)
			(xy 443.392033 -237.221763) (xy 443.437391 -237.189312) (xy 443.486991 -237.163811) (xy 443.539775 -237.145804)
			(xy 443.594618 -237.135674) (xy 443.650352 -237.133637) (xy 443.705789 -237.139737) (xy 443.759746 -237.153843)
			(xy 443.811075 -237.175655) (xy 443.858681 -237.204709) (xy 443.901549 -237.240384) (xy 443.938766 -237.281921)
			(xy 443.969539 -237.328434) (xy 443.993211 -237.378931) (xy 444.009279 -237.432338) (xy 444.017399 -237.487514)
			(xy 444.017908 -237.5154) (xy 444.017399 -237.543286) (xy 444.009279 -237.598462) (xy 443.993211 -237.651869)
			(xy 443.969539 -237.702366) (xy 443.938766 -237.748879) (xy 443.901549 -237.790416) (xy 443.858681 -237.826091)
			(xy 443.811075 -237.855145) (xy 443.759746 -237.876957) (xy 443.705789 -237.891063) (xy 443.650352 -237.897163)
			(xy 443.594618 -237.895126) (xy 443.539775 -237.884996) (xy 443.486991 -237.866989) (xy 443.437391 -237.841488)
			(xy 443.392033 -237.809037) (xy 443.351884 -237.770328) (xy 443.317798 -237.726185) (xy 443.290502 -237.67755)
			(xy 443.270579 -237.625459) (xy 443.258453 -237.571022) (xy 443.254382 -237.5154) (xy 413.593534 -237.5154)
			(xy 413.593534 -239.29848) (xy 417.276532 -239.29848) (xy 417.280603 -239.242858) (xy 417.292729 -239.188421)
			(xy 417.312652 -239.13633) (xy 417.339948 -239.087695) (xy 417.374034 -239.043552) (xy 417.414183 -239.004843)
			(xy 417.459541 -238.972392) (xy 417.509141 -238.946891) (xy 417.561925 -238.928884) (xy 417.616768 -238.918754)
			(xy 417.672502 -238.916717) (xy 417.727939 -238.922817) (xy 417.781896 -238.936923) (xy 417.833225 -238.958735)
			(xy 417.880831 -238.987789) (xy 417.923699 -239.023464) (xy 417.960916 -239.065001) (xy 417.991689 -239.111514)
			(xy 418.015361 -239.162011) (xy 418.031429 -239.215418) (xy 418.039549 -239.270594) (xy 418.040058 -239.29848)
			(xy 418.039549 -239.326366) (xy 418.031429 -239.381542) (xy 418.015361 -239.434949) (xy 417.991689 -239.485446)
			(xy 417.960916 -239.531959) (xy 417.923699 -239.573496) (xy 417.880831 -239.609171) (xy 417.833225 -239.638225)
			(xy 417.781896 -239.660037) (xy 417.727939 -239.674143) (xy 417.672502 -239.680243) (xy 417.616768 -239.678206)
			(xy 417.561925 -239.668076) (xy 417.509141 -239.650069) (xy 417.459541 -239.624568) (xy 417.414183 -239.592117)
			(xy 417.374034 -239.553408) (xy 417.339948 -239.509265) (xy 417.312652 -239.46063) (xy 417.292729 -239.408539)
			(xy 417.280603 -239.354102) (xy 417.276532 -239.29848) (xy 413.593534 -239.29848) (xy 413.593534 -240.170716)
			(xy 418.30828 -240.170716) (xy 418.312351 -240.115094) (xy 418.324477 -240.060657) (xy 418.3444 -240.008566)
			(xy 418.371696 -239.959931) (xy 418.405782 -239.915788) (xy 418.445931 -239.877079) (xy 418.491289 -239.844628)
			(xy 418.540889 -239.819127) (xy 418.593673 -239.80112) (xy 418.648516 -239.79099) (xy 418.70425 -239.788953)
			(xy 418.759687 -239.795053) (xy 418.813644 -239.809159) (xy 418.864973 -239.830971) (xy 418.912579 -239.860025)
			(xy 418.955447 -239.8957) (xy 418.992664 -239.937237) (xy 419.023437 -239.98375) (xy 419.047109 -240.034247)
			(xy 419.063177 -240.087654) (xy 419.071297 -240.14283) (xy 419.071806 -240.170716) (xy 419.071297 -240.198602)
			(xy 419.063177 -240.253778) (xy 419.047109 -240.307185) (xy 419.023437 -240.357682) (xy 418.992664 -240.404195)
			(xy 418.955447 -240.445732) (xy 418.912579 -240.481407) (xy 418.864973 -240.510461) (xy 418.813644 -240.532273)
			(xy 418.759687 -240.546379) (xy 418.70425 -240.552479) (xy 418.648516 -240.550442) (xy 418.593673 -240.540312)
			(xy 418.540889 -240.522305) (xy 418.491289 -240.496804) (xy 418.445931 -240.464353) (xy 418.405782 -240.425644)
			(xy 418.371696 -240.381501) (xy 418.3444 -240.332866) (xy 418.324477 -240.280775) (xy 418.312351 -240.226338)
			(xy 418.30828 -240.170716) (xy 413.593534 -240.170716) (xy 413.593534 -241.83848) (xy 415.611816 -241.83848)
			(xy 415.615887 -241.782858) (xy 415.628013 -241.728421) (xy 415.647936 -241.67633) (xy 415.675232 -241.627695)
			(xy 415.709318 -241.583552) (xy 415.749467 -241.544843) (xy 415.794825 -241.512392) (xy 415.844425 -241.486891)
			(xy 415.897209 -241.468884) (xy 415.952052 -241.458754) (xy 416.007786 -241.456717) (xy 416.063223 -241.462817)
			(xy 416.11718 -241.476923) (xy 416.168509 -241.498735) (xy 416.216115 -241.527789) (xy 416.258983 -241.563464)
			(xy 416.2962 -241.605001) (xy 416.326973 -241.651514) (xy 416.350645 -241.702011) (xy 416.366713 -241.755418)
			(xy 416.374833 -241.810594) (xy 416.375342 -241.83848) (xy 416.375319 -241.83975) (xy 418.075362 -241.83975)
			(xy 418.079433 -241.784128) (xy 418.091559 -241.729691) (xy 418.111482 -241.6776) (xy 418.138778 -241.628965)
			(xy 418.172864 -241.584822) (xy 418.213013 -241.546113) (xy 418.258371 -241.513662) (xy 418.307971 -241.488161)
			(xy 418.360755 -241.470154) (xy 418.415598 -241.460024) (xy 418.471332 -241.457987) (xy 418.526769 -241.464087)
			(xy 418.580726 -241.478193) (xy 418.632055 -241.500005) (xy 418.679661 -241.529059) (xy 418.722529 -241.564734)
			(xy 418.759746 -241.606271) (xy 418.790519 -241.652784) (xy 418.814191 -241.703281) (xy 418.830259 -241.756688)
			(xy 418.838379 -241.811864) (xy 418.838888 -241.83975) (xy 418.838379 -241.867636) (xy 418.830259 -241.922812)
			(xy 418.814191 -241.976219) (xy 418.790519 -242.026716) (xy 418.759746 -242.073229) (xy 418.722529 -242.114766)
			(xy 418.679661 -242.150441) (xy 418.632055 -242.179495) (xy 418.580726 -242.201307) (xy 418.526769 -242.215413)
			(xy 418.471332 -242.221513) (xy 418.415598 -242.219476) (xy 418.360755 -242.209346) (xy 418.307971 -242.191339)
			(xy 418.258371 -242.165838) (xy 418.213013 -242.133387) (xy 418.172864 -242.094678) (xy 418.138778 -242.050535)
			(xy 418.111482 -242.0019) (xy 418.091559 -241.949809) (xy 418.079433 -241.895372) (xy 418.075362 -241.83975)
			(xy 416.375319 -241.83975) (xy 416.374833 -241.866366) (xy 416.366713 -241.921542) (xy 416.350645 -241.974949)
			(xy 416.326973 -242.025446) (xy 416.2962 -242.071959) (xy 416.258983 -242.113496) (xy 416.216115 -242.149171)
			(xy 416.168509 -242.178225) (xy 416.11718 -242.200037) (xy 416.063223 -242.214143) (xy 416.007786 -242.220243)
			(xy 415.952052 -242.218206) (xy 415.897209 -242.208076) (xy 415.844425 -242.190069) (xy 415.794825 -242.164568)
			(xy 415.749467 -242.132117) (xy 415.709318 -242.093408) (xy 415.675232 -242.049265) (xy 415.647936 -242.00063)
			(xy 415.628013 -241.948539) (xy 415.615887 -241.894102) (xy 415.611816 -241.83848) (xy 413.593534 -241.83848)
			(xy 413.593534 -242.84813) (xy 451.778624 -242.84813) (xy 451.779037 -242.821814) (xy 451.786282 -242.769683)
			(xy 451.800611 -242.719039) (xy 451.821754 -242.67084) (xy 451.84931 -242.625998) (xy 451.882758 -242.585361)
			(xy 451.901814 -242.567206) (xy 451.909217 -242.559686) (xy 451.91774 -242.540405) (xy 451.918324 -242.529868)
			(xy 451.918324 -242.455192) (xy 451.917806 -242.444641) (xy 451.909262 -242.425346) (xy 451.901814 -242.417854)
			(xy 451.882746 -242.399711) (xy 451.849289 -242.359079) (xy 451.821732 -242.314236) (xy 451.800595 -242.266033)
			(xy 451.786281 -242.215383) (xy 451.77906 -242.163247) (xy 451.778624 -242.13693) (xy 451.779083 -242.109676)
			(xy 451.786837 -242.055724) (xy 451.802191 -242.003424) (xy 451.824832 -241.953842) (xy 451.8543 -241.907987)
			(xy 451.889994 -241.866793) (xy 451.931188 -241.831099) (xy 451.977043 -241.801631) (xy 452.026626 -241.77899)
			(xy 452.078926 -241.763637) (xy 452.132878 -241.755883) (xy 452.160132 -241.755422) (xy 452.186447 -241.755861)
			(xy 452.238577 -241.763101) (xy 452.289221 -241.777425) (xy 452.33742 -241.798563) (xy 452.382262 -241.826114)
			(xy 452.4229 -241.859558) (xy 452.441056 -241.878612) (xy 452.44859 -241.885998) (xy 452.467861 -241.894531)
			(xy 452.478394 -241.895122) (xy 452.55307 -241.895122) (xy 452.563618 -241.894583) (xy 452.582913 -241.886054)
			(xy 452.590408 -241.878612) (xy 452.610228 -241.857824) (xy 452.655 -241.821849) (xy 452.704658 -241.792989)
			(xy 452.75808 -241.771896) (xy 452.814059 -241.759047) (xy 452.871332 -241.754732) (xy 452.928605 -241.759047)
			(xy 452.984584 -241.771896) (xy 453.038006 -241.792989) (xy 453.087664 -241.821849) (xy 453.132436 -241.857824)
			(xy 453.152256 -241.878612) (xy 453.15979 -241.885998) (xy 453.179061 -241.894531) (xy 453.189594 -241.895122)
			(xy 453.26427 -241.895122) (xy 453.274818 -241.894583) (xy 453.294113 -241.886054) (xy 453.301608 -241.878612)
			(xy 453.319769 -241.859562) (xy 453.360397 -241.826104) (xy 453.405236 -241.798544) (xy 453.453436 -241.777404)
			(xy 453.504083 -241.763086) (xy 453.556216 -241.755861) (xy 453.582532 -241.755422) (xy 453.609785 -241.755848)
			(xy 453.663737 -241.76361) (xy 453.716035 -241.77897) (xy 453.765614 -241.801618) (xy 453.811466 -241.83109)
			(xy 453.852656 -241.866788) (xy 453.888347 -241.907984) (xy 453.917812 -241.953841) (xy 453.940451 -242.003424)
			(xy 453.955803 -242.055724) (xy 453.963556 -242.109677) (xy 453.96404 -242.13693) (xy 453.963612 -242.163246)
			(xy 453.956372 -242.215376) (xy 453.942046 -242.266021) (xy 453.920906 -242.31422) (xy 453.893352 -242.359062)
			(xy 453.859906 -242.399699) (xy 453.84085 -242.417854) (xy 453.83343 -242.42536) (xy 453.824915 -242.444652)
			(xy 453.82434 -242.455192) (xy 453.82434 -242.529868) (xy 453.824861 -242.540419) (xy 453.833401 -242.559715)
			(xy 453.84085 -242.567206) (xy 453.859911 -242.585356) (xy 453.893366 -242.625988) (xy 453.920923 -242.67083)
			(xy 453.94206 -242.719031) (xy 453.956377 -242.769679) (xy 453.963601 -242.821814) (xy 453.96404 -242.84813)
			(xy 453.96355 -242.875381) (xy 453.95579 -242.929326) (xy 453.940433 -242.981619) (xy 453.917791 -243.031194)
			(xy 453.888324 -243.077043) (xy 453.852634 -243.118232) (xy 453.811445 -243.153923) (xy 453.765596 -243.18339)
			(xy 453.716021 -243.206032) (xy 453.663728 -243.22139) (xy 453.609783 -243.22915) (xy 453.582532 -243.229638)
			(xy 453.556216 -243.229236) (xy 453.504083 -243.22199) (xy 453.453439 -243.20766) (xy 453.40524 -243.186515)
			(xy 453.360398 -243.158957) (xy 453.319762 -243.125506) (xy 453.301608 -243.106448) (xy 453.294079 -243.099055)
			(xy 453.274805 -243.090524) (xy 453.26427 -243.089938) (xy 453.189594 -243.089938) (xy 453.179041 -243.090439)
			(xy 453.159745 -243.098993) (xy 453.152256 -243.106448) (xy 453.132436 -243.127236) (xy 453.087664 -243.163211)
			(xy 453.038006 -243.192071) (xy 452.984584 -243.213164) (xy 452.928605 -243.226013) (xy 452.871332 -243.230328)
			(xy 452.814059 -243.226013) (xy 452.75808 -243.213164) (xy 452.704658 -243.192071) (xy 452.655 -243.163211)
			(xy 452.610228 -243.127236) (xy 452.590408 -243.106448) (xy 452.582879 -243.099055) (xy 452.563605 -243.090524)
			(xy 452.55307 -243.089938) (xy 452.478394 -243.089938) (xy 452.467841 -243.090439) (xy 452.448545 -243.098993)
			(xy 452.441056 -243.106448) (xy 452.422924 -243.125527) (xy 452.382288 -243.15898) (xy 452.337443 -243.186535)
			(xy 452.289237 -243.207669) (xy 452.238586 -243.221982) (xy 452.186449 -243.229202) (xy 452.160132 -243.229638)
			(xy 452.132881 -243.229115) (xy 452.078934 -243.221363) (xy 452.026639 -243.206013) (xy 451.977061 -243.183376)
			(xy 451.931209 -243.153914) (xy 451.890017 -243.118227) (xy 451.854323 -243.07704) (xy 451.824854 -243.031193)
			(xy 451.802209 -242.981619) (xy 451.78685 -242.929327) (xy 451.779089 -242.875381) (xy 451.778624 -242.84813)
			(xy 413.593534 -242.84813) (xy 413.593534 -245.53164) (xy 458.764894 -245.53164) (xy 458.765323 -245.505325)
			(xy 458.772566 -245.453195) (xy 458.786893 -245.402551) (xy 458.808033 -245.354353) (xy 458.835585 -245.30951)
			(xy 458.86903 -245.268872) (xy 458.888084 -245.250716) (xy 458.895478 -245.243188) (xy 458.904007 -245.223913)
			(xy 458.904594 -245.213378) (xy 458.904594 -245.138702) (xy 458.904079 -245.128151) (xy 458.895534 -245.108855)
			(xy 458.888084 -245.101364) (xy 458.869015 -245.083222) (xy 458.83556 -245.042589) (xy 458.808003 -244.997746)
			(xy 458.786867 -244.949542) (xy 458.772552 -244.898893) (xy 458.765331 -244.846757) (xy 458.764894 -244.82044)
			(xy 458.76538 -244.793189) (xy 458.773136 -244.739241) (xy 458.788491 -244.686946) (xy 458.811133 -244.637369)
			(xy 458.840599 -244.591519) (xy 458.87629 -244.550328) (xy 458.917481 -244.514637) (xy 458.963331 -244.485171)
			(xy 459.012908 -244.462529) (xy 459.065203 -244.447174) (xy 459.119151 -244.439418) (xy 459.173653 -244.439418)
			(xy 459.227601 -244.447174) (xy 459.279896 -244.462529) (xy 459.329473 -244.485171) (xy 459.375323 -244.514637)
			(xy 459.416514 -244.550328) (xy 459.452205 -244.591519) (xy 459.481671 -244.637369) (xy 459.504313 -244.686946)
			(xy 459.519668 -244.739241) (xy 459.527424 -244.793189) (xy 459.52791 -244.82044) (xy 459.527466 -244.846755)
			(xy 459.520226 -244.898884) (xy 459.505902 -244.949527) (xy 459.484765 -244.997726) (xy 459.457215 -245.042569)
			(xy 459.423773 -245.083208) (xy 459.40472 -245.101364) (xy 459.397335 -245.1089) (xy 459.3888 -245.128169)
			(xy 459.38821 -245.138702) (xy 459.38821 -245.213378) (xy 459.388735 -245.223928) (xy 459.397273 -245.243224)
			(xy 459.40472 -245.250716) (xy 459.42378 -245.268867) (xy 459.457236 -245.309498) (xy 459.484794 -245.354339)
			(xy 459.505932 -245.402541) (xy 459.520248 -245.453189) (xy 459.527472 -245.505324) (xy 459.52791 -245.53164)
			(xy 459.527424 -245.558891) (xy 459.519668 -245.612839) (xy 459.504313 -245.665134) (xy 459.481671 -245.714711)
			(xy 459.452205 -245.760561) (xy 459.416514 -245.801752) (xy 459.375323 -245.837443) (xy 459.329473 -245.866909)
			(xy 459.279896 -245.889551) (xy 459.227601 -245.904906) (xy 459.173653 -245.912662) (xy 459.119151 -245.912662)
			(xy 459.065203 -245.904906) (xy 459.012908 -245.889551) (xy 458.963331 -245.866909) (xy 458.917481 -245.837443)
			(xy 458.87629 -245.801752) (xy 458.840599 -245.760561) (xy 458.811133 -245.714711) (xy 458.788491 -245.665134)
			(xy 458.773136 -245.612839) (xy 458.76538 -245.558891) (xy 458.764894 -245.53164) (xy 413.593534 -245.53164)
			(xy 413.593534 -246.16664) (xy 454.116184 -246.16664) (xy 454.120255 -246.111018) (xy 454.132381 -246.056581)
			(xy 454.152304 -246.00449) (xy 454.1796 -245.955855) (xy 454.213686 -245.911712) (xy 454.253835 -245.873003)
			(xy 454.299193 -245.840552) (xy 454.348793 -245.815051) (xy 454.401577 -245.797044) (xy 454.45642 -245.786914)
			(xy 454.512154 -245.784877) (xy 454.567591 -245.790977) (xy 454.621548 -245.805083) (xy 454.672877 -245.826895)
			(xy 454.720483 -245.855949) (xy 454.763351 -245.891624) (xy 454.800568 -245.933161) (xy 454.831341 -245.979674)
			(xy 454.855013 -246.030171) (xy 454.871081 -246.083578) (xy 454.879201 -246.138754) (xy 454.87971 -246.16664)
			(xy 457.316584 -246.16664) (xy 457.320655 -246.111018) (xy 457.332781 -246.056581) (xy 457.352704 -246.00449)
			(xy 457.38 -245.955855) (xy 457.414086 -245.911712) (xy 457.454235 -245.873003) (xy 457.499593 -245.840552)
			(xy 457.549193 -245.815051) (xy 457.601977 -245.797044) (xy 457.65682 -245.786914) (xy 457.712554 -245.784877)
			(xy 457.767991 -245.790977) (xy 457.821948 -245.805083) (xy 457.873277 -245.826895) (xy 457.920883 -245.855949)
			(xy 457.963751 -245.891624) (xy 458.000968 -245.933161) (xy 458.031741 -245.979674) (xy 458.055413 -246.030171)
			(xy 458.071481 -246.083578) (xy 458.079601 -246.138754) (xy 458.08011 -246.16664) (xy 458.079646 -246.19204)
			(xy 458.205584 -246.19204) (xy 458.209655 -246.136418) (xy 458.221781 -246.081981) (xy 458.241704 -246.02989)
			(xy 458.269 -245.981255) (xy 458.303086 -245.937112) (xy 458.343235 -245.898403) (xy 458.388593 -245.865952)
			(xy 458.438193 -245.840451) (xy 458.490977 -245.822444) (xy 458.54582 -245.812314) (xy 458.601554 -245.810277)
			(xy 458.656991 -245.816377) (xy 458.710948 -245.830483) (xy 458.762277 -245.852295) (xy 458.809883 -245.881349)
			(xy 458.852751 -245.917024) (xy 458.889968 -245.958561) (xy 458.920741 -246.005074) (xy 458.944413 -246.055571)
			(xy 458.960481 -246.108978) (xy 458.968601 -246.164154) (xy 458.96911 -246.19204) (xy 458.968601 -246.219926)
			(xy 458.960481 -246.275102) (xy 458.944413 -246.328509) (xy 458.920741 -246.379006) (xy 458.889968 -246.425519)
			(xy 458.852751 -246.467056) (xy 458.809883 -246.502731) (xy 458.762277 -246.531785) (xy 458.710948 -246.553597)
			(xy 458.656991 -246.567703) (xy 458.601554 -246.573803) (xy 458.54582 -246.571766) (xy 458.490977 -246.561636)
			(xy 458.438193 -246.543629) (xy 458.388593 -246.518128) (xy 458.343235 -246.485677) (xy 458.303086 -246.446968)
			(xy 458.269 -246.402825) (xy 458.241704 -246.35419) (xy 458.221781 -246.302099) (xy 458.209655 -246.247662)
			(xy 458.205584 -246.19204) (xy 458.079646 -246.19204) (xy 458.079601 -246.194526) (xy 458.071481 -246.249702)
			(xy 458.055413 -246.303109) (xy 458.031741 -246.353606) (xy 458.000968 -246.400119) (xy 457.963751 -246.441656)
			(xy 457.920883 -246.477331) (xy 457.873277 -246.506385) (xy 457.821948 -246.528197) (xy 457.767991 -246.542303)
			(xy 457.712554 -246.548403) (xy 457.65682 -246.546366) (xy 457.601977 -246.536236) (xy 457.549193 -246.518229)
			(xy 457.499593 -246.492728) (xy 457.454235 -246.460277) (xy 457.414086 -246.421568) (xy 457.38 -246.377425)
			(xy 457.352704 -246.32879) (xy 457.332781 -246.276699) (xy 457.320655 -246.222262) (xy 457.316584 -246.16664)
			(xy 454.87971 -246.16664) (xy 454.879201 -246.194526) (xy 454.871081 -246.249702) (xy 454.855013 -246.303109)
			(xy 454.831341 -246.353606) (xy 454.800568 -246.400119) (xy 454.763351 -246.441656) (xy 454.720483 -246.477331)
			(xy 454.672877 -246.506385) (xy 454.621548 -246.528197) (xy 454.567591 -246.542303) (xy 454.512154 -246.548403)
			(xy 454.45642 -246.546366) (xy 454.401577 -246.536236) (xy 454.348793 -246.518229) (xy 454.299193 -246.492728)
			(xy 454.253835 -246.460277) (xy 454.213686 -246.421568) (xy 454.1796 -246.377425) (xy 454.152304 -246.32879)
			(xy 454.132381 -246.276699) (xy 454.120255 -246.222262) (xy 454.116184 -246.16664) (xy 413.593534 -246.16664)
			(xy 413.593534 -248.86085) (xy 451.577195 -248.86085) (xy 451.577195 -248.80635) (xy 451.584951 -248.752404)
			(xy 451.600306 -248.700112) (xy 451.622946 -248.650537) (xy 451.652411 -248.604688) (xy 451.688101 -248.5635)
			(xy 451.72929 -248.52781) (xy 451.775139 -248.498345) (xy 451.824714 -248.475705) (xy 451.877006 -248.460351)
			(xy 451.930952 -248.452595) (xy 451.958202 -248.452132) (xy 451.985446 -248.45261) (xy 452.03938 -248.460367)
			(xy 452.091659 -248.475724) (xy 452.14122 -248.498367) (xy 452.187053 -248.527835) (xy 452.228223 -248.563527)
			(xy 452.263893 -248.604718) (xy 452.279004 -248.627392) (xy 452.283877 -248.634398) (xy 452.297271 -248.644952)
			(xy 452.313402 -248.650485) (xy 452.32193 -248.65076) (xy 452.407274 -248.65076) (xy 452.415794 -248.650449)
			(xy 452.431903 -248.644892) (xy 452.445314 -248.634379) (xy 452.4502 -248.627392) (xy 452.46533 -248.60473)
			(xy 452.500993 -248.563533) (xy 452.542158 -248.527834) (xy 452.587987 -248.498361) (xy 452.637546 -248.475714)
			(xy 452.689825 -248.460354) (xy 452.743758 -248.452595) (xy 452.771002 -248.452132) (xy 452.796977 -248.45258)
			(xy 452.848448 -248.459623) (xy 452.898485 -248.473591) (xy 452.946161 -248.494226) (xy 452.990592 -248.521146)
			(xy 453.030956 -248.55385) (xy 453.066503 -248.591734) (xy 453.081898 -248.61266) (xy 453.089508 -248.622172)
			(xy 453.111137 -248.633305) (xy 453.1233 -248.633996) (xy 453.206104 -248.633996) (xy 453.218266 -248.633301)
			(xy 453.23989 -248.622167) (xy 453.247506 -248.61266) (xy 453.262889 -248.591726) (xy 453.298445 -248.553849)
			(xy 453.338813 -248.521149) (xy 453.383246 -248.494232) (xy 453.430922 -248.473596) (xy 453.480957 -248.459623)
			(xy 453.532427 -248.452571) (xy 453.558402 -248.452132) (xy 453.585656 -248.452538) (xy 453.639609 -248.460296)
			(xy 453.691909 -248.475652) (xy 453.741491 -248.498296) (xy 453.787346 -248.527766) (xy 453.828541 -248.563461)
			(xy 453.864236 -248.604655) (xy 453.893705 -248.65051) (xy 453.916348 -248.700093) (xy 453.931705 -248.752393)
			(xy 453.939462 -248.806346) (xy 453.939462 -248.860854) (xy 453.931705 -248.914807) (xy 453.916348 -248.967107)
			(xy 453.893705 -249.01669) (xy 453.864236 -249.062545) (xy 453.828541 -249.103739) (xy 453.787346 -249.139434)
			(xy 453.741491 -249.168904) (xy 453.691909 -249.191548) (xy 453.639609 -249.206904) (xy 453.585656 -249.214662)
			(xy 453.558402 -249.215148) (xy 453.532427 -249.214705) (xy 453.480956 -249.207663) (xy 453.430918 -249.193694)
			(xy 453.383242 -249.173058) (xy 453.33881 -249.146138) (xy 453.298447 -249.113432) (xy 453.2629 -249.075547)
			(xy 453.247506 -249.05462) (xy 453.239898 -249.045106) (xy 453.218267 -249.033975) (xy 453.206104 -249.033284)
			(xy 453.1233 -249.033284) (xy 453.111139 -249.03399) (xy 453.089516 -249.045117) (xy 453.081898 -249.05462)
			(xy 453.066507 -249.075548) (xy 453.030953 -249.113426) (xy 452.990587 -249.146127) (xy 452.946155 -249.173045)
			(xy 452.89848 -249.193682) (xy 452.848446 -249.207656) (xy 452.796977 -249.214709) (xy 452.771002 -249.215148)
			(xy 452.743757 -249.214676) (xy 452.689823 -249.206919) (xy 452.637543 -249.191562) (xy 452.587982 -249.168918)
			(xy 452.54215 -249.139449) (xy 452.500979 -249.103755) (xy 452.46531 -249.062563) (xy 452.4502 -249.039888)
			(xy 452.445331 -249.03288) (xy 452.431934 -249.022327) (xy 452.415803 -249.016795) (xy 452.407274 -249.01652)
			(xy 452.32193 -249.01652) (xy 452.313406 -249.016798) (xy 452.297293 -249.022364) (xy 452.283885 -249.032893)
			(xy 452.279004 -249.039888) (xy 452.263898 -249.062566) (xy 452.228228 -249.103759) (xy 452.187058 -249.139454)
			(xy 452.141225 -249.168924) (xy 452.091663 -249.191569) (xy 452.039382 -249.206926) (xy 451.985447 -249.214684)
			(xy 451.958202 -249.215148) (xy 451.930952 -249.214605) (xy 451.877006 -249.206849) (xy 451.824714 -249.191495)
			(xy 451.775139 -249.168855) (xy 451.72929 -249.13939) (xy 451.688101 -249.1037) (xy 451.652411 -249.062512)
			(xy 451.622946 -249.016663) (xy 451.600306 -248.967088) (xy 451.584951 -248.914796) (xy 451.577195 -248.86085)
			(xy 413.593534 -248.86085) (xy 413.593534 -249.283728) (xy 418.099492 -249.283728) (xy 418.103563 -249.228106)
			(xy 418.115689 -249.173669) (xy 418.135612 -249.121578) (xy 418.162908 -249.072943) (xy 418.196994 -249.0288)
			(xy 418.237143 -248.990091) (xy 418.282501 -248.95764) (xy 418.332101 -248.932139) (xy 418.384885 -248.914132)
			(xy 418.439728 -248.904002) (xy 418.495462 -248.901965) (xy 418.550899 -248.908065) (xy 418.604856 -248.922171)
			(xy 418.656185 -248.943983) (xy 418.703791 -248.973037) (xy 418.746659 -249.008712) (xy 418.783876 -249.050249)
			(xy 418.814649 -249.096762) (xy 418.838321 -249.147259) (xy 418.854389 -249.200666) (xy 418.862509 -249.255842)
			(xy 418.863018 -249.283728) (xy 418.862633 -249.30481) (xy 419.084504 -249.30481) (xy 419.088575 -249.249188)
			(xy 419.100701 -249.194751) (xy 419.120624 -249.14266) (xy 419.14792 -249.094025) (xy 419.182006 -249.049882)
			(xy 419.222155 -249.011173) (xy 419.267513 -248.978722) (xy 419.317113 -248.953221) (xy 419.369897 -248.935214)
			(xy 419.42474 -248.925084) (xy 419.480474 -248.923047) (xy 419.535911 -248.929147) (xy 419.589868 -248.943253)
			(xy 419.641197 -248.965065) (xy 419.688803 -248.994119) (xy 419.731671 -249.029794) (xy 419.768888 -249.071331)
			(xy 419.799661 -249.117844) (xy 419.823333 -249.168341) (xy 419.839401 -249.221748) (xy 419.847521 -249.276924)
			(xy 419.84803 -249.30481) (xy 419.847521 -249.332696) (xy 419.839401 -249.387872) (xy 419.823333 -249.441279)
			(xy 419.799661 -249.491776) (xy 419.768888 -249.538289) (xy 419.731671 -249.579826) (xy 419.688803 -249.615501)
			(xy 419.641197 -249.644555) (xy 419.589868 -249.666367) (xy 419.535911 -249.680473) (xy 419.480474 -249.686573)
			(xy 419.42474 -249.684536) (xy 419.369897 -249.674406) (xy 419.317113 -249.656399) (xy 419.267513 -249.630898)
			(xy 419.222155 -249.598447) (xy 419.182006 -249.559738) (xy 419.14792 -249.515595) (xy 419.120624 -249.46696)
			(xy 419.100701 -249.414869) (xy 419.088575 -249.360432) (xy 419.084504 -249.30481) (xy 418.862633 -249.30481)
			(xy 418.862509 -249.311614) (xy 418.854389 -249.36679) (xy 418.838321 -249.420197) (xy 418.814649 -249.470694)
			(xy 418.783876 -249.517207) (xy 418.746659 -249.558744) (xy 418.703791 -249.594419) (xy 418.656185 -249.623473)
			(xy 418.604856 -249.645285) (xy 418.550899 -249.659391) (xy 418.495462 -249.665491) (xy 418.439728 -249.663454)
			(xy 418.384885 -249.653324) (xy 418.332101 -249.635317) (xy 418.282501 -249.609816) (xy 418.237143 -249.577365)
			(xy 418.196994 -249.538656) (xy 418.162908 -249.494513) (xy 418.135612 -249.445878) (xy 418.115689 -249.393787)
			(xy 418.103563 -249.33935) (xy 418.099492 -249.283728) (xy 413.593534 -249.283728) (xy 413.593534 -250.20524)
			(xy 453.481184 -250.20524) (xy 453.485255 -250.149618) (xy 453.497381 -250.095181) (xy 453.517304 -250.04309)
			(xy 453.5446 -249.994455) (xy 453.578686 -249.950312) (xy 453.618835 -249.911603) (xy 453.664193 -249.879152)
			(xy 453.713793 -249.853651) (xy 453.766577 -249.835644) (xy 453.82142 -249.825514) (xy 453.877154 -249.823477)
			(xy 453.932591 -249.829577) (xy 453.986548 -249.843683) (xy 454.037877 -249.865495) (xy 454.085483 -249.894549)
			(xy 454.128351 -249.930224) (xy 454.165568 -249.971761) (xy 454.196341 -250.018274) (xy 454.220013 -250.068771)
			(xy 454.236081 -250.122178) (xy 454.239782 -250.147328) (xy 458.853538 -250.147328) (xy 458.857609 -250.091706)
			(xy 458.869735 -250.037269) (xy 458.889658 -249.985178) (xy 458.916954 -249.936543) (xy 458.95104 -249.8924)
			(xy 458.991189 -249.853691) (xy 459.036547 -249.82124) (xy 459.086147 -249.795739) (xy 459.138931 -249.777732)
			(xy 459.193774 -249.767602) (xy 459.249508 -249.765565) (xy 459.304945 -249.771665) (xy 459.358902 -249.785771)
			(xy 459.410231 -249.807583) (xy 459.457837 -249.836637) (xy 459.500705 -249.872312) (xy 459.537922 -249.913849)
			(xy 459.568695 -249.960362) (xy 459.592367 -250.010859) (xy 459.608435 -250.064266) (xy 459.616555 -250.119442)
			(xy 459.617064 -250.147328) (xy 459.616555 -250.175214) (xy 459.608435 -250.23039) (xy 459.592367 -250.283797)
			(xy 459.568695 -250.334294) (xy 459.537922 -250.380807) (xy 459.500705 -250.422344) (xy 459.457837 -250.458019)
			(xy 459.410231 -250.487073) (xy 459.358902 -250.508885) (xy 459.304945 -250.522991) (xy 459.249508 -250.529091)
			(xy 459.193774 -250.527054) (xy 459.138931 -250.516924) (xy 459.086147 -250.498917) (xy 459.036547 -250.473416)
			(xy 458.991189 -250.440965) (xy 458.95104 -250.402256) (xy 458.916954 -250.358113) (xy 458.889658 -250.309478)
			(xy 458.869735 -250.257387) (xy 458.857609 -250.20295) (xy 458.853538 -250.147328) (xy 454.239782 -250.147328)
			(xy 454.244201 -250.177354) (xy 454.24471 -250.20524) (xy 454.244201 -250.233126) (xy 454.236081 -250.288302)
			(xy 454.220013 -250.341709) (xy 454.196341 -250.392206) (xy 454.165568 -250.438719) (xy 454.128351 -250.480256)
			(xy 454.085483 -250.515931) (xy 454.037877 -250.544985) (xy 453.986548 -250.566797) (xy 453.932591 -250.580903)
			(xy 453.877154 -250.587003) (xy 453.82142 -250.584966) (xy 453.766577 -250.574836) (xy 453.713793 -250.556829)
			(xy 453.664193 -250.531328) (xy 453.618835 -250.498877) (xy 453.578686 -250.460168) (xy 453.5446 -250.416025)
			(xy 453.517304 -250.36739) (xy 453.497381 -250.315299) (xy 453.485255 -250.260862) (xy 453.481184 -250.20524)
			(xy 413.593534 -250.20524) (xy 413.593534 -250.300236) (xy 413.594296 -250.308364) (xy 413.594296 -250.308872)
			(xy 413.595902 -250.316388) (xy 413.602885 -250.330069) (xy 413.608012 -250.335796) (xy 413.984948 -250.712732)
			(xy 443.057278 -250.712732) (xy 443.061349 -250.65711) (xy 443.073475 -250.602673) (xy 443.093398 -250.550582)
			(xy 443.120694 -250.501947) (xy 443.15478 -250.457804) (xy 443.194929 -250.419095) (xy 443.240287 -250.386644)
			(xy 443.289887 -250.361143) (xy 443.342671 -250.343136) (xy 443.397514 -250.333006) (xy 443.453248 -250.330969)
			(xy 443.508685 -250.337069) (xy 443.562642 -250.351175) (xy 443.613971 -250.372987) (xy 443.661577 -250.402041)
			(xy 443.704445 -250.437716) (xy 443.741662 -250.479253) (xy 443.772435 -250.525766) (xy 443.796107 -250.576263)
			(xy 443.812175 -250.62967) (xy 443.820295 -250.684846) (xy 443.820804 -250.712732) (xy 443.820295 -250.740618)
			(xy 443.812175 -250.795794) (xy 443.796107 -250.849201) (xy 443.772435 -250.899698) (xy 443.753964 -250.927616)
			(xy 443.943738 -250.927616) (xy 443.947809 -250.871994) (xy 443.959935 -250.817557) (xy 443.979858 -250.765466)
			(xy 444.007154 -250.716831) (xy 444.04124 -250.672688) (xy 444.081389 -250.633979) (xy 444.126747 -250.601528)
			(xy 444.176347 -250.576027) (xy 444.229131 -250.55802) (xy 444.283974 -250.54789) (xy 444.339708 -250.545853)
			(xy 444.395145 -250.551953) (xy 444.449102 -250.566059) (xy 444.500431 -250.587871) (xy 444.548037 -250.616925)
			(xy 444.590905 -250.6526) (xy 444.628122 -250.694137) (xy 444.658895 -250.74065) (xy 444.682567 -250.791147)
			(xy 444.698635 -250.844554) (xy 444.706755 -250.89973) (xy 444.707264 -250.927616) (xy 444.706755 -250.955502)
			(xy 444.698635 -251.010678) (xy 444.682567 -251.064085) (xy 444.658895 -251.114582) (xy 444.628122 -251.161095)
			(xy 444.590905 -251.202632) (xy 444.548037 -251.238307) (xy 444.500431 -251.267361) (xy 444.449102 -251.289173)
			(xy 444.395145 -251.303279) (xy 444.339708 -251.309379) (xy 444.283974 -251.307342) (xy 444.229131 -251.297212)
			(xy 444.176347 -251.279205) (xy 444.126747 -251.253704) (xy 444.081389 -251.221253) (xy 444.04124 -251.182544)
			(xy 444.007154 -251.138401) (xy 443.979858 -251.089766) (xy 443.959935 -251.037675) (xy 443.947809 -250.983238)
			(xy 443.943738 -250.927616) (xy 443.753964 -250.927616) (xy 443.741662 -250.946211) (xy 443.704445 -250.987748)
			(xy 443.661577 -251.023423) (xy 443.613971 -251.052477) (xy 443.562642 -251.074289) (xy 443.508685 -251.088395)
			(xy 443.453248 -251.094495) (xy 443.397514 -251.092458) (xy 443.342671 -251.082328) (xy 443.289887 -251.064321)
			(xy 443.240287 -251.03882) (xy 443.194929 -251.006369) (xy 443.15478 -250.96766) (xy 443.120694 -250.923517)
			(xy 443.093398 -250.874882) (xy 443.073475 -250.822791) (xy 443.061349 -250.768354) (xy 443.057278 -250.712732)
			(xy 413.984948 -250.712732) (xy 415.825686 -252.55347) (xy 415.831366 -252.558661) (xy 415.845072 -252.565639)
			(xy 415.85261 -252.567186) (xy 415.853118 -252.567186) (xy 415.861246 -252.567948) (xy 419.303962 -252.567948)
			(xy 419.317925 -252.567476) (xy 419.344791 -252.559844) (xy 419.368587 -252.545222) (xy 419.387533 -252.524702)
			(xy 419.400216 -252.499819) (xy 419.405687 -252.472431) (xy 419.405054 -252.458474) (xy 419.403784 -252.424946)
			(xy 419.403784 -252.424184) (xy 419.404294 -252.393543) (xy 419.412712 -252.332841) (xy 419.4294 -252.273874)
			(xy 419.45404 -252.217764) (xy 419.486164 -252.165576) (xy 419.525162 -252.118303) (xy 419.570291 -252.076843)
			(xy 419.620694 -252.041986) (xy 419.675413 -252.014393) (xy 419.704266 -252.004068) (xy 419.71087 -252.001782)
			(xy 419.716458 -251.997972) (xy 419.719347 -251.995959) (xy 419.724572 -251.99124) (xy 419.726872 -251.988574)
			(xy 419.736016 -251.977398) (xy 419.737794 -251.964952) (xy 419.74008 -251.949966) (xy 419.74055 -251.946234)
			(xy 419.740547 -251.938712) (xy 419.74008 -251.93498) (xy 419.737032 -251.923804) (xy 419.734746 -251.917962)
			(xy 419.727634 -251.908056) (xy 419.7223 -251.903484) (xy 419.701201 -251.885208) (xy 419.664005 -251.843588)
			(xy 419.63325 -251.797005) (xy 419.609588 -251.74645) (xy 419.59352 -251.692993) (xy 419.585389 -251.637769)
			(xy 419.584886 -251.60986) (xy 419.585373 -251.582554) (xy 419.593145 -251.528499) (xy 419.608531 -251.4761)
			(xy 419.631217 -251.426424) (xy 419.660742 -251.380482) (xy 419.696505 -251.339209) (xy 419.737778 -251.303446)
			(xy 419.78372 -251.273921) (xy 419.833396 -251.251235) (xy 419.885795 -251.235849) (xy 419.93985 -251.228077)
			(xy 419.994462 -251.228077) (xy 420.048517 -251.235849) (xy 420.100916 -251.251235) (xy 420.150592 -251.273921)
			(xy 420.196534 -251.303446) (xy 420.237807 -251.339209) (xy 420.27357 -251.380482) (xy 420.303095 -251.426424)
			(xy 420.325781 -251.4761) (xy 420.341167 -251.528499) (xy 420.348939 -251.582554) (xy 420.349426 -251.60986)
			(xy 420.348838 -251.639856) (xy 420.339473 -251.699114) (xy 420.320982 -251.756186) (xy 420.304094 -251.789438)
			(xy 444.588898 -251.789438) (xy 444.592969 -251.733816) (xy 444.605095 -251.679379) (xy 444.625018 -251.627288)
			(xy 444.652314 -251.578653) (xy 444.6864 -251.53451) (xy 444.726549 -251.495801) (xy 444.771907 -251.46335)
			(xy 444.821507 -251.437849) (xy 444.874291 -251.419842) (xy 444.929134 -251.409712) (xy 444.984868 -251.407675)
			(xy 445.040305 -251.413775) (xy 445.094262 -251.427881) (xy 445.145591 -251.449693) (xy 445.193197 -251.478747)
			(xy 445.236065 -251.514422) (xy 445.273282 -251.555959) (xy 445.304055 -251.602472) (xy 445.327727 -251.652969)
			(xy 445.343795 -251.706376) (xy 445.351915 -251.761552) (xy 445.352424 -251.789438) (xy 445.351915 -251.817324)
			(xy 445.343795 -251.8725) (xy 445.327727 -251.925907) (xy 445.304055 -251.976404) (xy 445.273282 -252.022917)
			(xy 445.236065 -252.064454) (xy 445.193197 -252.100129) (xy 445.145591 -252.129183) (xy 445.094262 -252.150995)
			(xy 445.040305 -252.165101) (xy 444.984868 -252.171201) (xy 444.929134 -252.169164) (xy 444.874291 -252.159034)
			(xy 444.821507 -252.141027) (xy 444.771907 -252.115526) (xy 444.726549 -252.083075) (xy 444.6864 -252.044366)
			(xy 444.652314 -252.000223) (xy 444.625018 -251.951588) (xy 444.605095 -251.899497) (xy 444.592969 -251.84506)
			(xy 444.588898 -251.789438) (xy 420.304094 -251.789438) (xy 420.293816 -251.809676) (xy 420.258641 -251.858275)
			(xy 420.216318 -251.900794) (xy 420.192454 -251.918978) (xy 420.191946 -251.918978) (xy 420.178992 -251.927614)
			(xy 420.163912 -251.937418) (xy 420.132234 -251.954461) (xy 420.115746 -251.96165) (xy 420.115492 -251.96165)
			(xy 420.113968 -251.962412) (xy 420.108634 -251.965206) (xy 420.101127 -251.970164) (xy 420.089921 -251.984222)
			(xy 420.084287 -252.001294) (xy 420.084923 -252.019261) (xy 420.08806 -252.02769) (xy 420.088568 -252.02896)
			(xy 420.102538 -252.056646) (xy 420.106856 -252.061472) (xy 420.110412 -252.06579) (xy 420.114984 -252.069346)
			(xy 420.115238 -252.0696) (xy 420.138354 -252.087664) (xy 420.180095 -252.12889) (xy 420.216052 -252.175248)
			(xy 420.2456 -252.225931) (xy 420.268227 -252.28006) (xy 420.283538 -252.336694) (xy 420.291268 -252.39485)
			(xy 420.291768 -252.424184) (xy 420.290498 -252.458474) (xy 420.289845 -252.472438) (xy 420.295297 -252.499845)
			(xy 420.307974 -252.524749) (xy 420.326927 -252.545285) (xy 420.350735 -252.559915) (xy 420.377618 -252.567545)
			(xy 420.39159 -252.567948) (xy 443.675262 -252.567948) (xy 443.680923 -252.567772) (xy 443.691954 -252.565219)
			(xy 443.697106 -252.562868) (xy 443.714886 -252.554486) (xy 443.720982 -252.54839) (xy 443.765686 -252.504702)
			(xy 443.767718 -252.50267) (xy 443.770766 -252.499114) (xy 443.773477 -252.495713) (xy 443.777819 -252.488179)
			(xy 443.779402 -252.484128) (xy 443.782196 -252.476254) (xy 443.78245 -252.467364) (xy 443.78245 -252.46711)
			(xy 443.783294 -252.440107) (xy 443.791657 -252.386734) (xy 443.807466 -252.335074) (xy 443.830405 -252.286162)
			(xy 443.860015 -252.240975) (xy 443.895704 -252.200417) (xy 443.936758 -252.1653) (xy 443.982355 -252.136326)
			(xy 444.031585 -252.114075) (xy 444.083461 -252.098992) (xy 444.136946 -252.091379) (xy 444.163958 -252.090936)
			(xy 444.190977 -252.091409) (xy 444.244475 -252.099042) (xy 444.29636 -252.114146) (xy 444.345595 -252.136419)
			(xy 444.391195 -252.165416) (xy 444.432248 -252.200557) (xy 444.467932 -252.241139) (xy 444.497533 -252.286349)
			(xy 444.52046 -252.335283) (xy 444.536253 -252.386963) (xy 444.544597 -252.440354) (xy 444.545466 -252.467364)
			(xy 444.545466 -252.467618) (xy 444.54572 -252.477778) (xy 444.550292 -252.488446) (xy 444.552041 -252.492044)
			(xy 444.556501 -252.498685) (xy 444.559182 -252.501654) (xy 444.588138 -252.530356) (xy 444.588392 -252.53061)
			(xy 444.611506 -252.553216) (xy 444.612268 -252.553978) (xy 444.615389 -252.556837) (xy 444.622416 -252.561556)
			(xy 444.626238 -252.563376) (xy 444.629032 -252.564392) (xy 444.633495 -252.566022) (xy 444.642825 -252.567818)
			(xy 444.647574 -252.567948) (xy 446.533524 -252.567948) (xy 446.545462 -252.566424) (xy 446.561718 -252.562106)
			(xy 446.567814 -252.558804) (xy 446.596113 -252.543548) (xy 446.656569 -252.521693) (xy 446.71983 -252.510265)
			(xy 446.751964 -252.509274) (xy 446.755774 -252.509274) (xy 446.756282 -252.509274) (xy 446.781573 -252.509611)
			(xy 446.831727 -252.516149) (xy 446.880578 -252.529258) (xy 446.927267 -252.548709) (xy 446.949322 -252.56109)
			(xy 446.95491 -252.564392) (xy 446.961006 -252.56617) (xy 446.974214 -252.567948) (xy 446.98539 -252.567948)
			(xy 446.994761 -252.567527) (xy 447.012252 -252.560798) (xy 447.026158 -252.548234) (xy 447.034622 -252.531513)
			(xy 447.035936 -252.522228) (xy 447.036698 -252.512068) (xy 447.037033 -252.50314) (xy 447.032187 -252.485955)
			(xy 447.021722 -252.471487) (xy 447.006917 -252.461505) (xy 446.998344 -252.458982) (xy 446.971194 -252.451656)
			(xy 446.919249 -252.430119) (xy 446.871026 -252.401192) (xy 446.827569 -252.365503) (xy 446.78982 -252.323823)
			(xy 446.758596 -252.277056) (xy 446.734572 -252.226213) (xy 446.718269 -252.172395) (xy 446.710039 -252.116767)
			(xy 446.709546 -252.08865) (xy 446.710005 -252.061394) (xy 446.717756 -252.007435) (xy 446.733108 -251.955128)
			(xy 446.755747 -251.905539) (xy 446.785213 -251.859676) (xy 446.820906 -251.818474) (xy 446.862099 -251.78277)
			(xy 446.907954 -251.753293) (xy 446.957538 -251.730641) (xy 447.009841 -251.715277) (xy 447.063798 -251.707512)
			(xy 447.091054 -251.707142) (xy 447.112183 -251.707384) (xy 447.15419 -251.711966) (xy 447.174874 -251.716286)
			(xy 447.175128 -251.716286) (xy 447.180282 -251.717289) (xy 447.190781 -251.717426) (xy 447.195956 -251.71654)
			(xy 447.206116 -251.714) (xy 447.210688 -251.71146) (xy 447.220848 -251.703586) (xy 447.246248 -251.678948)
			(xy 447.283078 -251.643134) (xy 447.29134 -251.633819) (xy 447.29841 -251.609976) (xy 447.29654 -251.597668)
			(xy 447.295524 -251.59208) (xy 447.292912 -251.575951) (xy 447.290118 -251.543394) (xy 447.289936 -251.527056)
			(xy 447.289936 -251.524008) (xy 447.290558 -251.496851) (xy 447.298544 -251.443121) (xy 447.314071 -251.391068)
			(xy 447.336826 -251.341743) (xy 447.366347 -251.296145) (xy 447.402038 -251.255196) (xy 447.443177 -251.219724)
			(xy 447.488932 -251.190447) (xy 447.538377 -251.167956) (xy 447.590512 -251.152707) (xy 447.644284 -251.145008)
			(xy 447.671444 -251.144532) (xy 447.69869 -251.145021) (xy 447.752628 -251.152782) (xy 447.804911 -251.168139)
			(xy 447.854478 -251.190781) (xy 447.900318 -251.220245) (xy 447.941499 -251.255933) (xy 447.977182 -251.297117)
			(xy 448.006641 -251.342961) (xy 448.029276 -251.39253) (xy 448.044627 -251.444815) (xy 448.052382 -251.498754)
			(xy 448.052382 -251.553246) (xy 448.044627 -251.607185) (xy 448.029276 -251.65947) (xy 448.025137 -251.668534)
			(xy 450.165722 -251.668534) (xy 450.169793 -251.612912) (xy 450.181919 -251.558475) (xy 450.201842 -251.506384)
			(xy 450.229138 -251.457749) (xy 450.263224 -251.413606) (xy 450.303373 -251.374897) (xy 450.348731 -251.342446)
			(xy 450.398331 -251.316945) (xy 450.451115 -251.298938) (xy 450.505958 -251.288808) (xy 450.561692 -251.286771)
			(xy 450.617129 -251.292871) (xy 450.671086 -251.306977) (xy 450.722415 -251.328789) (xy 450.770021 -251.357843)
			(xy 450.789003 -251.37364) (xy 457.418184 -251.37364) (xy 457.422255 -251.318018) (xy 457.434381 -251.263581)
			(xy 457.454304 -251.21149) (xy 457.4816 -251.162855) (xy 457.515686 -251.118712) (xy 457.555835 -251.080003)
			(xy 457.601193 -251.047552) (xy 457.650793 -251.022051) (xy 457.703577 -251.004044) (xy 457.75842 -250.993914)
			(xy 457.814154 -250.991877) (xy 457.869591 -250.997977) (xy 457.923548 -251.012083) (xy 457.974877 -251.033895)
			(xy 458.022483 -251.062949) (xy 458.065351 -251.098624) (xy 458.102568 -251.140161) (xy 458.133341 -251.186674)
			(xy 458.157013 -251.237171) (xy 458.173081 -251.290578) (xy 458.181201 -251.345754) (xy 458.18171 -251.37364)
			(xy 458.181201 -251.401526) (xy 458.173081 -251.456702) (xy 458.157013 -251.510109) (xy 458.133341 -251.560606)
			(xy 458.102568 -251.607119) (xy 458.065351 -251.648656) (xy 458.022483 -251.684331) (xy 457.974877 -251.713385)
			(xy 457.923548 -251.735197) (xy 457.869591 -251.749303) (xy 457.814154 -251.755403) (xy 457.75842 -251.753366)
			(xy 457.703577 -251.743236) (xy 457.650793 -251.725229) (xy 457.601193 -251.699728) (xy 457.555835 -251.667277)
			(xy 457.515686 -251.628568) (xy 457.4816 -251.584425) (xy 457.454304 -251.53579) (xy 457.434381 -251.483699)
			(xy 457.422255 -251.429262) (xy 457.418184 -251.37364) (xy 450.789003 -251.37364) (xy 450.812889 -251.393518)
			(xy 450.850106 -251.435055) (xy 450.880879 -251.481568) (xy 450.904551 -251.532065) (xy 450.920619 -251.585472)
			(xy 450.928739 -251.640648) (xy 450.929248 -251.668534) (xy 450.928739 -251.69642) (xy 450.920619 -251.751596)
			(xy 450.904551 -251.805003) (xy 450.880879 -251.8555) (xy 450.850106 -251.902013) (xy 450.812889 -251.94355)
			(xy 450.770021 -251.979225) (xy 450.722415 -252.008279) (xy 450.671086 -252.030091) (xy 450.617129 -252.044197)
			(xy 450.561692 -252.050297) (xy 450.505958 -252.04826) (xy 450.451115 -252.03813) (xy 450.398331 -252.020123)
			(xy 450.348731 -251.994622) (xy 450.303373 -251.962171) (xy 450.263224 -251.923462) (xy 450.229138 -251.879319)
			(xy 450.201842 -251.830684) (xy 450.181919 -251.778593) (xy 450.169793 -251.724156) (xy 450.165722 -251.668534)
			(xy 448.025137 -251.668534) (xy 448.006641 -251.709039) (xy 447.977182 -251.754883) (xy 447.941499 -251.796067)
			(xy 447.900318 -251.831755) (xy 447.854478 -251.861219) (xy 447.804911 -251.883861) (xy 447.752628 -251.899218)
			(xy 447.69869 -251.906979) (xy 447.671444 -251.907548) (xy 447.650315 -251.907306) (xy 447.608308 -251.902723)
			(xy 447.587624 -251.898404) (xy 447.58737 -251.898404) (xy 447.582216 -251.897401) (xy 447.571718 -251.897265)
			(xy 447.566542 -251.89815) (xy 447.556382 -251.90069) (xy 447.55181 -251.90323) (xy 447.54165 -251.911104)
			(xy 447.51625 -251.935742) (xy 447.47942 -251.971556) (xy 447.471157 -251.980871) (xy 447.464082 -252.004714)
			(xy 447.465958 -252.017022) (xy 447.466974 -252.02261) (xy 447.469578 -252.038676) (xy 447.472372 -252.071105)
			(xy 447.472562 -252.08738) (xy 447.472562 -252.091444) (xy 447.472308 -252.10135) (xy 447.470895 -252.129006)
			(xy 447.461075 -252.183503) (xy 447.443477 -252.236008) (xy 447.418471 -252.285416) (xy 447.386583 -252.330688)
			(xy 447.348484 -252.370874) (xy 447.32702 -252.38837) (xy 447.319754 -252.395363) (xy 447.310952 -252.413488)
			(xy 447.309808 -252.433605) (xy 447.312796 -252.443234) (xy 447.325496 -252.47981) (xy 447.345308 -252.536452)
			(xy 447.349523 -252.545576) (xy 447.363706 -252.559798) (xy 447.382256 -252.567497) (xy 447.392298 -252.567948)
			(xy 450.341238 -252.567948) (xy 450.346318 -252.567694) (xy 450.353176 -252.566424) (xy 450.358668 -252.565416)
			(xy 450.369047 -252.561306) (xy 450.37375 -252.558296) (xy 450.382386 -252.552454) (xy 450.388228 -252.542802)
			(xy 450.40331 -252.519037) (xy 450.439323 -252.475779) (xy 450.48125 -252.438226) (xy 450.528199 -252.407179)
			(xy 450.579169 -252.383299) (xy 450.633072 -252.367096) (xy 450.688761 -252.358915) (xy 450.716904 -252.358398)
			(xy 450.744183 -252.358878) (xy 450.79819 -252.366609) (xy 450.850557 -252.381913) (xy 450.900228 -252.404483)
			(xy 450.946199 -252.433863) (xy 450.987544 -252.469459) (xy 451.023429 -252.510555) (xy 451.038722 -252.53315)
			(xy 451.041516 -252.537468) (xy 451.05447 -252.550422) (xy 451.064376 -252.558296) (xy 451.074282 -252.563122)
			(xy 451.079279 -252.565314) (xy 451.089911 -252.567757) (xy 451.095364 -252.567948) (xy 451.482206 -252.567948)
			(xy 451.488721 -252.567707) (xy 451.501314 -252.564354) (xy 451.507098 -252.561344) (xy 451.526656 -252.550422)
			(xy 451.5358 -252.543056) (xy 451.543166 -252.53569) (xy 451.545706 -252.53188) (xy 451.563587 -252.507234)
			(xy 451.605128 -252.462718) (xy 451.652474 -252.424432) (xy 451.704698 -252.393126) (xy 451.760778 -252.369411)
			(xy 451.819619 -252.353751) (xy 451.880069 -252.346454) (xy 451.940945 -252.34766) (xy 452.001058 -252.357348)
			(xy 452.059232 -252.375327) (xy 452.08698 -252.387862) (xy 452.112778 -252.400462) (xy 452.161108 -252.431455)
			(xy 452.20494 -252.468537) (xy 452.243512 -252.511063) (xy 452.260208 -252.53442) (xy 452.260716 -252.534928)
			(xy 452.264272 -252.539754) (xy 452.268336 -252.543564) (xy 452.275194 -252.548644) (xy 452.300086 -252.562614)
			(xy 452.305413 -252.56507) (xy 452.316829 -252.567752) (xy 452.322692 -252.567948) (xy 458.35824 -252.567948)
			(xy 458.367638 -252.566932) (xy 458.368146 -252.566932) (xy 458.375302 -252.565221) (xy 458.38832 -252.55838)
			(xy 458.3938 -252.55347) (xy 461.907382 -249.039888) (xy 461.912368 -249.034461) (xy 461.919226 -249.021423)
			(xy 461.920844 -249.014234) (xy 461.920844 -249.013726) (xy 461.92186 -249.004328) (xy 461.92186 -230.547164)
			(xy 461.919574 -230.537004) (xy 461.916018 -230.530654) (xy 461.902411 -230.503239) (xy 461.883151 -230.445147)
			(xy 461.873418 -230.384725) (xy 461.872838 -230.354124) (xy 461.872838 -230.353616) (xy 461.872838 -230.351584)
			(xy 461.872838 -230.351076) (xy 461.873448 -230.320479) (xy 461.883201 -230.260065) (xy 461.902441 -230.201973)
			(xy 461.916018 -230.174546) (xy 461.919574 -230.168196) (xy 461.92186 -230.158036) (xy 461.92186 -108.318808)
			(xy 461.921606 -108.316776) (xy 461.920086 -108.307096) (xy 461.910807 -108.289857) (xy 461.903572 -108.283248)
			(xy 461.880966 -108.264452) (xy 461.880458 -108.263944) (xy 461.842104 -108.232956) (xy 461.83423 -108.226606)
			(xy 461.824832 -108.223812) (xy 461.813656 -108.220256) (xy 461.800194 -108.222288) (xy 461.797654 -108.222796)
			(xy 461.779179 -108.226253) (xy 461.741772 -108.229941) (xy 461.722978 -108.230162) (xy 461.722724 -108.230162)
			(xy 461.695473 -108.2297) (xy 461.641526 -108.221947) (xy 461.589232 -108.206595) (xy 461.539655 -108.183957)
			(xy 461.493804 -108.154493) (xy 461.452614 -108.118803) (xy 461.416922 -108.077615) (xy 461.387455 -108.031766)
			(xy 461.364813 -107.982191) (xy 461.349458 -107.929897) (xy 461.341701 -107.875951) (xy 461.341701 -107.821449)
			(xy 461.349458 -107.767503) (xy 461.364813 -107.715209) (xy 461.387455 -107.665634) (xy 461.416922 -107.619785)
			(xy 461.452614 -107.578597) (xy 461.493804 -107.542907) (xy 461.539655 -107.513443) (xy 461.589232 -107.490805)
			(xy 461.641526 -107.475453) (xy 461.695473 -107.4677) (xy 461.722724 -107.467146) (xy 461.740743 -107.46738)
			(xy 461.776617 -107.470813) (xy 461.794352 -107.474004) (xy 461.799178 -107.47502) (xy 461.810862 -107.47502)
			(xy 461.819555 -107.474679) (xy 461.83593 -107.468841) (xy 461.842866 -107.46359) (xy 461.872076 -107.439714)
			(xy 461.872584 -107.439714) (xy 461.904842 -107.413806) (xy 461.912185 -107.406595) (xy 461.920946 -107.387991)
			(xy 461.92186 -107.377738) (xy 461.92186 -85.185758) (xy 461.922292 -85.175693) (xy 461.930024 -85.157105)
			(xy 461.936846 -85.14969) (xy 465.686902 -81.399634) (xy 465.691881 -81.394203) (xy 465.698722 -81.381162)
			(xy 465.700364 -81.37398) (xy 465.700364 -81.373472) (xy 465.70138 -81.364074) (xy 465.70138 -17.074388)
			(xy 465.701805 -17.064318) (xy 465.70952 -17.045715) (xy 465.716366 -17.03832) (xy 466.130132 -16.624554)
			(xy 466.135115 -16.619053) (xy 466.141949 -16.605884) (xy 466.143594 -16.598646) (xy 466.143594 -16.598138)
			(xy 466.14461 -16.588994) (xy 466.14461 -2.884678) (xy 466.144446 -2.878668) (xy 466.141629 -2.866982)
			(xy 466.139022 -2.861564) (xy 466.137182 -2.85809) (xy 466.132588 -2.851711) (xy 466.129878 -2.848864)
			(xy 464.820508 -1.539494) (xy 464.817656 -1.536789) (xy 464.811276 -1.532199) (xy 464.807808 -1.53035)
			(xy 464.802381 -1.52777) (xy 464.790701 -1.524955) (xy 464.784694 -1.524762) (xy 446.601596 -1.524762)
			(xy 446.595588 -1.524935) (xy 446.583911 -1.527768) (xy 446.578482 -1.53035) (xy 446.575009 -1.532191)
			(xy 446.568633 -1.536788) (xy 446.565782 -1.539494) (xy 446.059306 -2.04597) (xy 446.0566 -2.048821)
			(xy 446.052006 -2.055199) (xy 446.050162 -2.05867) (xy 446.047579 -2.064097) (xy 446.044758 -2.075777)
			(xy 446.044574 -2.081784) (xy 446.044574 -13.713206) (xy 446.042034 -13.715746) (xy 446.051686 -13.807186)
			(xy 446.052486 -13.812766) (xy 446.056195 -13.823409) (xy 446.059052 -13.828268) (xy 446.06591 -13.839698)
			(xy 446.070228 -13.84681) (xy 446.076832 -13.854938) (xy 446.08115 -13.859256) (xy 446.085468 -13.86205)
			(xy 446.140684 -13.898648) (xy 446.246973 -13.977733) (xy 446.348151 -14.063259) (xy 446.386826 -14.100302)
			(xy 451.54291 -14.100302) (xy 451.546981 -14.04468) (xy 451.559107 -13.990243) (xy 451.57903 -13.938152)
			(xy 451.606326 -13.889517) (xy 451.640412 -13.845374) (xy 451.680561 -13.806665) (xy 451.725919 -13.774214)
			(xy 451.775519 -13.748713) (xy 451.828303 -13.730706) (xy 451.883146 -13.720576) (xy 451.93888 -13.718539)
			(xy 451.994317 -13.724639) (xy 452.048274 -13.738745) (xy 452.099603 -13.760557) (xy 452.147209 -13.789611)
			(xy 452.190077 -13.825286) (xy 452.227294 -13.866823) (xy 452.258067 -13.913336) (xy 452.281739 -13.963833)
			(xy 452.297807 -14.01724) (xy 452.305927 -14.072416) (xy 452.306436 -14.100302) (xy 452.305927 -14.128188)
			(xy 452.297807 -14.183364) (xy 452.281739 -14.236771) (xy 452.258067 -14.287268) (xy 452.227294 -14.333781)
			(xy 452.190077 -14.375318) (xy 452.147209 -14.410993) (xy 452.099603 -14.440047) (xy 452.048274 -14.461859)
			(xy 451.994317 -14.475965) (xy 451.93888 -14.482065) (xy 451.883146 -14.480028) (xy 451.828303 -14.469898)
			(xy 451.775519 -14.451891) (xy 451.725919 -14.42639) (xy 451.680561 -14.393939) (xy 451.640412 -14.35523)
			(xy 451.606326 -14.311087) (xy 451.57903 -14.262452) (xy 451.559107 -14.210361) (xy 451.546981 -14.155924)
			(xy 451.54291 -14.100302) (xy 446.386826 -14.100302) (xy 446.443828 -14.154898) (xy 446.533636 -14.252296)
			(xy 446.617228 -14.355078) (xy 446.694283 -14.462848) (xy 446.764503 -14.575191) (xy 446.827619 -14.691674)
			(xy 446.883386 -14.811848) (xy 446.93159 -14.93525) (xy 446.972046 -15.061405) (xy 447.004598 -15.189827)
			(xy 447.029119 -15.320021) (xy 447.03539 -15.370302) (xy 452.20331 -15.370302) (xy 452.207381 -15.31468)
			(xy 452.219507 -15.260243) (xy 452.23943 -15.208152) (xy 452.266726 -15.159517) (xy 452.300812 -15.115374)
			(xy 452.340961 -15.076665) (xy 452.386319 -15.044214) (xy 452.435919 -15.018713) (xy 452.488703 -15.000706)
			(xy 452.543546 -14.990576) (xy 452.59928 -14.988539) (xy 452.654717 -14.994639) (xy 452.708674 -15.008745)
			(xy 452.760003 -15.030557) (xy 452.807609 -15.059611) (xy 452.850477 -15.095286) (xy 452.887694 -15.136823)
			(xy 452.918467 -15.183336) (xy 452.942139 -15.233833) (xy 452.958207 -15.28724) (xy 452.966327 -15.342416)
			(xy 452.966836 -15.370302) (xy 452.966327 -15.398188) (xy 452.964936 -15.40764) (xy 453.070466 -15.40764)
			(xy 453.074537 -15.352018) (xy 453.086663 -15.297581) (xy 453.106586 -15.24549) (xy 453.133882 -15.196855)
			(xy 453.167968 -15.152712) (xy 453.208117 -15.114003) (xy 453.253475 -15.081552) (xy 453.303075 -15.056051)
			(xy 453.355859 -15.038044) (xy 453.410702 -15.027914) (xy 453.466436 -15.025877) (xy 453.521873 -15.031977)
			(xy 453.57583 -15.046083) (xy 453.627159 -15.067895) (xy 453.674765 -15.096949) (xy 453.717633 -15.132624)
			(xy 453.75485 -15.174161) (xy 453.772026 -15.200122) (xy 459.541372 -15.200122) (xy 459.541372 -13.599922)
			(xy 459.54188 -13.535242) (xy 459.550003 -13.406136) (xy 459.566216 -13.277796) (xy 459.590456 -13.150726)
			(xy 459.622626 -13.02543) (xy 459.662601 -12.9024) (xy 459.710222 -12.782124) (xy 459.765301 -12.665075)
			(xy 459.827621 -12.551715) (xy 459.896936 -12.442492) (xy 459.972972 -12.337837) (xy 460.05543 -12.238163)
			(xy 460.143983 -12.143863) (xy 460.238283 -12.05531) (xy 460.337957 -11.972852) (xy 460.442612 -11.896816)
			(xy 460.551835 -11.827501) (xy 460.665195 -11.765181) (xy 460.782244 -11.710102) (xy 460.90252 -11.662481)
			(xy 461.02555 -11.622506) (xy 461.150846 -11.590336) (xy 461.277916 -11.566096) (xy 461.406256 -11.549883)
			(xy 461.535362 -11.54176) (xy 461.664722 -11.54176) (xy 461.793828 -11.549883) (xy 461.922168 -11.566096)
			(xy 462.049238 -11.590336) (xy 462.174534 -11.622506) (xy 462.297564 -11.662481) (xy 462.41784 -11.710102)
			(xy 462.534889 -11.765181) (xy 462.648249 -11.827501) (xy 462.757472 -11.896816) (xy 462.862127 -11.972852)
			(xy 462.961801 -12.05531) (xy 463.056101 -12.143863) (xy 463.144654 -12.238163) (xy 463.227112 -12.337837)
			(xy 463.303148 -12.442492) (xy 463.372463 -12.551715) (xy 463.434783 -12.665075) (xy 463.489862 -12.782124)
			(xy 463.537483 -12.9024) (xy 463.577458 -13.02543) (xy 463.609628 -13.150726) (xy 463.633868 -13.277796)
			(xy 463.650081 -13.406136) (xy 463.658204 -13.535242) (xy 463.658712 -13.599922) (xy 463.658712 -15.200122)
			(xy 463.658204 -15.264802) (xy 463.650081 -15.393908) (xy 463.633868 -15.522248) (xy 463.609628 -15.649318)
			(xy 463.577458 -15.774614) (xy 463.537483 -15.897644) (xy 463.489862 -16.01792) (xy 463.434783 -16.134969)
			(xy 463.372463 -16.248329) (xy 463.303148 -16.357552) (xy 463.227112 -16.462207) (xy 463.144654 -16.561881)
			(xy 463.056101 -16.656181) (xy 462.961801 -16.744734) (xy 462.862127 -16.827192) (xy 462.757472 -16.903228)
			(xy 462.648249 -16.972543) (xy 462.534889 -17.034863) (xy 462.41784 -17.089942) (xy 462.297564 -17.137563)
			(xy 462.174534 -17.177538) (xy 462.049238 -17.209708) (xy 461.922168 -17.233948) (xy 461.793828 -17.250161)
			(xy 461.664722 -17.258284) (xy 461.535362 -17.258284) (xy 461.406256 -17.250161) (xy 461.277916 -17.233948)
			(xy 461.150846 -17.209708) (xy 461.02555 -17.177538) (xy 460.90252 -17.137563) (xy 460.782244 -17.089942)
			(xy 460.665195 -17.034863) (xy 460.551835 -16.972543) (xy 460.442612 -16.903228) (xy 460.337957 -16.827192)
			(xy 460.238283 -16.744734) (xy 460.143983 -16.656181) (xy 460.05543 -16.561881) (xy 459.972972 -16.462207)
			(xy 459.896936 -16.357552) (xy 459.827621 -16.248329) (xy 459.765301 -16.134969) (xy 459.710222 -16.01792)
			(xy 459.662601 -15.897644) (xy 459.622626 -15.774614) (xy 459.590456 -15.649318) (xy 459.566216 -15.522248)
			(xy 459.550003 -15.393908) (xy 459.54188 -15.264802) (xy 459.541372 -15.200122) (xy 453.772026 -15.200122)
			(xy 453.785623 -15.220674) (xy 453.809295 -15.271171) (xy 453.825363 -15.324578) (xy 453.833483 -15.379754)
			(xy 453.833992 -15.40764) (xy 453.833483 -15.435526) (xy 453.825363 -15.490702) (xy 453.809295 -15.544109)
			(xy 453.785623 -15.594606) (xy 453.75485 -15.641119) (xy 453.717633 -15.682656) (xy 453.674765 -15.718331)
			(xy 453.627159 -15.747385) (xy 453.57583 -15.769197) (xy 453.521873 -15.783303) (xy 453.466436 -15.789403)
			(xy 453.410702 -15.787366) (xy 453.355859 -15.777236) (xy 453.303075 -15.759229) (xy 453.253475 -15.733728)
			(xy 453.208117 -15.701277) (xy 453.167968 -15.662568) (xy 453.133882 -15.618425) (xy 453.106586 -15.56979)
			(xy 453.086663 -15.517699) (xy 453.074537 -15.463262) (xy 453.070466 -15.40764) (xy 452.964936 -15.40764)
			(xy 452.958207 -15.453364) (xy 452.942139 -15.506771) (xy 452.918467 -15.557268) (xy 452.887694 -15.603781)
			(xy 452.850477 -15.645318) (xy 452.807609 -15.680993) (xy 452.760003 -15.710047) (xy 452.708674 -15.731859)
			(xy 452.654717 -15.745965) (xy 452.59928 -15.752065) (xy 452.543546 -15.750028) (xy 452.488703 -15.739898)
			(xy 452.435919 -15.721891) (xy 452.386319 -15.69639) (xy 452.340961 -15.663939) (xy 452.300812 -15.62523)
			(xy 452.266726 -15.581087) (xy 452.23943 -15.532452) (xy 452.219507 -15.480361) (xy 452.207381 -15.425924)
			(xy 452.20331 -15.370302) (xy 447.03539 -15.370302) (xy 447.045516 -15.451486) (xy 447.053725 -15.583714)
			(xy 447.054224 -15.649956) (xy 447.053718 -15.715692) (xy 447.045625 -15.846913) (xy 447.029468 -15.977388)
			(xy 447.005311 -16.106621) (xy 446.973243 -16.234121) (xy 446.933387 -16.359405) (xy 446.885894 -16.481999)
			(xy 446.830945 -16.601436) (xy 446.768746 -16.717263) (xy 446.699536 -16.829042) (xy 446.623575 -16.936349)
			(xy 446.541153 -17.038775) (xy 446.452581 -17.135934) (xy 446.358196 -17.227455) (xy 446.258357 -17.312993)
			(xy 446.15344 -17.392222) (xy 446.112162 -17.419574) (xy 450.58406 -17.419574) (xy 450.588131 -17.363952)
			(xy 450.600257 -17.309515) (xy 450.62018 -17.257424) (xy 450.647476 -17.208789) (xy 450.681562 -17.164646)
			(xy 450.721711 -17.125937) (xy 450.767069 -17.093486) (xy 450.816669 -17.067985) (xy 450.869453 -17.049978)
			(xy 450.924296 -17.039848) (xy 450.98003 -17.037811) (xy 451.035467 -17.043911) (xy 451.089424 -17.058017)
			(xy 451.140753 -17.079829) (xy 451.188359 -17.108883) (xy 451.231227 -17.144558) (xy 451.268444 -17.186095)
			(xy 451.299217 -17.232608) (xy 451.322889 -17.283105) (xy 451.338957 -17.336512) (xy 451.347077 -17.391688)
			(xy 451.347586 -17.419574) (xy 451.347077 -17.44746) (xy 451.338957 -17.502636) (xy 451.322889 -17.556043)
			(xy 451.299217 -17.60654) (xy 451.268444 -17.653053) (xy 451.231227 -17.69459) (xy 451.188359 -17.730265)
			(xy 451.140753 -17.759319) (xy 451.089424 -17.781131) (xy 451.035467 -17.795237) (xy 450.98003 -17.801337)
			(xy 450.924296 -17.7993) (xy 450.869453 -17.78917) (xy 450.816669 -17.771163) (xy 450.767069 -17.745662)
			(xy 450.721711 -17.713211) (xy 450.681562 -17.674502) (xy 450.647476 -17.630359) (xy 450.62018 -17.581724)
			(xy 450.600257 -17.529633) (xy 450.588131 -17.475196) (xy 450.58406 -17.419574) (xy 446.112162 -17.419574)
			(xy 446.043846 -17.464842) (xy 445.929988 -17.530577) (xy 445.8123 -17.589179) (xy 445.691228 -17.640425)
			(xy 445.56723 -17.68412) (xy 445.440778 -17.720099) (xy 445.31235 -17.748225) (xy 445.182435 -17.768391)
			(xy 445.051525 -17.780522) (xy 444.920116 -17.784571) (xy 444.788707 -17.780522) (xy 444.657797 -17.768391)
			(xy 444.527882 -17.748225) (xy 444.399454 -17.720099) (xy 444.273002 -17.68412) (xy 444.149004 -17.640425)
			(xy 444.027932 -17.589179) (xy 443.910244 -17.530577) (xy 443.796386 -17.464842) (xy 443.686792 -17.392222)
			(xy 443.581875 -17.312993) (xy 443.482036 -17.227455) (xy 443.387651 -17.135934) (xy 443.299079 -17.038775)
			(xy 443.216657 -16.936349) (xy 443.140696 -16.829042) (xy 443.071486 -16.717263) (xy 443.009287 -16.601436)
			(xy 442.954338 -16.481999) (xy 442.906845 -16.359405) (xy 442.866989 -16.234121) (xy 442.834921 -16.106621)
			(xy 442.810764 -15.977388) (xy 442.794607 -15.846913) (xy 442.786514 -15.715692) (xy 442.786008 -15.649956)
			(xy 442.786492 -15.585639) (xy 442.794243 -15.457238) (xy 442.809716 -15.329537) (xy 442.832853 -15.203)
			(xy 442.863571 -15.078087) (xy 442.901758 -14.955252) (xy 442.947275 -14.834939) (xy 442.999957 -14.717588)
			(xy 443.02934 -14.660372) (xy 443.030864 -14.657324) (xy 443.033008 -14.652127) (xy 443.035198 -14.641102)
			(xy 443.035182 -14.63548) (xy 443.034674 -14.622018) (xy 443.018418 -14.595094) (xy 443.018418 -14.594586)
			(xy 442.98108 -14.533626) (xy 442.973555 -14.523731) (xy 442.951586 -14.512156) (xy 442.93917 -14.511528)
			(xy 433.377848 -14.511528) (xy 433.367781 -14.511096) (xy 433.349188 -14.503372) (xy 433.34178 -14.496542)
			(xy 432.627786 -13.782548) (xy 432.620939 -13.775151) (xy 432.61321 -13.756552) (xy 432.6128 -13.74648)
			(xy 432.6128 -1.941576) (xy 432.612636 -1.935566) (xy 432.609817 -1.92388) (xy 432.607212 -1.918462)
			(xy 432.605372 -1.914988) (xy 432.600777 -1.90861) (xy 432.598068 -1.905762) (xy 432.07305 -1.380744)
			(xy 432.070201 -1.378035) (xy 432.063826 -1.373436) (xy 432.06035 -1.3716) (xy 432.054923 -1.369018)
			(xy 432.043243 -1.366195) (xy 432.037236 -1.366012) (xy 420.29888 -1.366012) (xy 420.29287 -1.366176)
			(xy 420.281184 -1.368994) (xy 420.275766 -1.3716) (xy 420.272293 -1.37344) (xy 420.265915 -1.378035)
			(xy 420.263066 -1.380744) (xy 419.795452 -1.848358) (xy 419.792743 -1.851207) (xy 419.788144 -1.857582)
			(xy 419.786308 -1.861058) (xy 419.783726 -1.866485) (xy 419.780905 -1.878165) (xy 419.78072 -1.884172)
			(xy 419.78072 -13.649198) (xy 419.780951 -13.656468) (xy 419.785084 -13.670406) (xy 419.788848 -13.67663)
			(xy 419.806374 -13.704316) (xy 419.817042 -13.71346) (xy 419.823646 -13.716508) (xy 419.88069 -13.743684)
			(xy 419.991805 -13.803873) (xy 420.099164 -13.870533) (xy 420.20239 -13.943429) (xy 420.301121 -14.022306)
			(xy 420.387699 -14.100302) (xy 425.542962 -14.100302) (xy 425.547033 -14.04468) (xy 425.559159 -13.990243)
			(xy 425.579082 -13.938152) (xy 425.606378 -13.889517) (xy 425.640464 -13.845374) (xy 425.680613 -13.806665)
			(xy 425.725971 -13.774214) (xy 425.775571 -13.748713) (xy 425.828355 -13.730706) (xy 425.883198 -13.720576)
			(xy 425.938932 -13.718539) (xy 425.994369 -13.724639) (xy 426.048326 -13.738745) (xy 426.099655 -13.760557)
			(xy 426.147261 -13.789611) (xy 426.190129 -13.825286) (xy 426.227346 -13.866823) (xy 426.258119 -13.913336)
			(xy 426.281791 -13.963833) (xy 426.297859 -14.01724) (xy 426.305979 -14.072416) (xy 426.306488 -14.100302)
			(xy 426.305979 -14.128188) (xy 426.297859 -14.183364) (xy 426.281791 -14.236771) (xy 426.258119 -14.287268)
			(xy 426.227346 -14.333781) (xy 426.190129 -14.375318) (xy 426.147261 -14.410993) (xy 426.099655 -14.440047)
			(xy 426.048326 -14.461859) (xy 425.994369 -14.475965) (xy 425.938932 -14.482065) (xy 425.883198 -14.480028)
			(xy 425.828355 -14.469898) (xy 425.775571 -14.451891) (xy 425.725971 -14.42639) (xy 425.680613 -14.393939)
			(xy 425.640464 -14.35523) (xy 425.606378 -14.311087) (xy 425.579082 -14.262452) (xy 425.559159 -14.210361)
			(xy 425.547033 -14.155924) (xy 425.542962 -14.100302) (xy 420.387699 -14.100302) (xy 420.39501 -14.106888)
			(xy 420.48373 -14.196878) (xy 420.566968 -14.291961) (xy 420.644433 -14.391804) (xy 420.715854 -14.496056)
			(xy 420.78098 -14.604352) (xy 420.81069 -14.660118) (xy 420.81323 -14.665198) (xy 420.816532 -14.671548)
			(xy 420.84516 -14.72805) (xy 420.896455 -14.843878) (xy 420.94079 -14.962545) (xy 420.978006 -15.083633)
			(xy 421.007974 -15.206716) (xy 421.030587 -15.33136) (xy 421.038576 -15.39755) (xy 426.20438 -15.39755)
			(xy 426.20438 -15.34305) (xy 426.212136 -15.289104) (xy 426.22749 -15.236811) (xy 426.250129 -15.187236)
			(xy 426.279594 -15.141386) (xy 426.315283 -15.100197) (xy 426.35647 -15.064506) (xy 426.402318 -15.035039)
			(xy 426.451892 -15.012397) (xy 426.504185 -14.99704) (xy 426.55813 -14.989281) (xy 426.58538 -14.988794)
			(xy 426.611615 -14.989267) (xy 426.663591 -14.996459) (xy 426.714089 -15.010711) (xy 426.762155 -15.031753)
			(xy 426.806882 -15.059187) (xy 426.847425 -15.092496) (xy 426.865542 -15.111476) (xy 426.865796 -15.11173)
			(xy 426.873514 -15.119129) (xy 426.893208 -15.127394) (xy 426.903896 -15.127732) (xy 426.99178 -15.125446)
			(xy 427.011338 -15.116048) (xy 427.01845 -15.107412) (xy 427.036662 -15.086262) (xy 427.078202 -15.048987)
			(xy 427.124731 -15.018165) (xy 427.175256 -14.994454) (xy 427.228698 -14.978361) (xy 427.283914 -14.970229)
			(xy 427.31182 -14.969744) (xy 427.339067 -14.970328) (xy 427.393006 -14.978085) (xy 427.445291 -14.99344)
			(xy 427.49486 -15.01608) (xy 427.540702 -15.045543) (xy 427.581884 -15.08123) (xy 427.617569 -15.122414)
			(xy 427.64703 -15.168258) (xy 427.669667 -15.217827) (xy 427.685019 -15.270114) (xy 427.692774 -15.324053)
			(xy 427.692774 -15.378547) (xy 427.685019 -15.432486) (xy 427.669667 -15.484773) (xy 427.64703 -15.534342)
			(xy 427.617569 -15.580186) (xy 427.581884 -15.62137) (xy 427.540702 -15.657057) (xy 427.49486 -15.68652)
			(xy 427.445291 -15.70916) (xy 427.393006 -15.724515) (xy 427.339067 -15.732272) (xy 427.31182 -15.73276)
			(xy 427.285584 -15.732302) (xy 427.233608 -15.725108) (xy 427.183109 -15.710855) (xy 427.135042 -15.68981)
			(xy 427.090315 -15.662373) (xy 427.049774 -15.62906) (xy 427.031658 -15.610078) (xy 427.031404 -15.609824)
			(xy 427.023691 -15.602418) (xy 427.003993 -15.594159) (xy 426.993304 -15.593822) (xy 426.90542 -15.596108)
			(xy 426.885862 -15.605506) (xy 426.87875 -15.614142) (xy 426.860528 -15.635283) (xy 426.818991 -15.67256)
			(xy 426.772464 -15.703385) (xy 426.721941 -15.727097) (xy 426.668501 -15.743192) (xy 426.613286 -15.751325)
			(xy 426.58538 -15.75181) (xy 426.55813 -15.751319) (xy 426.504185 -15.74356) (xy 426.451892 -15.728203)
			(xy 426.402318 -15.705561) (xy 426.35647 -15.676094) (xy 426.315283 -15.640403) (xy 426.279594 -15.599214)
			(xy 426.250129 -15.553364) (xy 426.22749 -15.503789) (xy 426.212136 -15.451496) (xy 426.20438 -15.39755)
			(xy 421.038576 -15.39755) (xy 421.045767 -15.457125) (xy 421.053459 -15.58357) (xy 421.054022 -15.646908)
			(xy 421.054022 -15.665958) (xy 421.053035 -15.731376) (xy 421.044039 -15.861914) (xy 421.027063 -15.991656)
			(xy 421.002169 -16.120113) (xy 420.969452 -16.246804) (xy 420.929035 -16.371253) (xy 420.881068 -16.492992)
			(xy 420.825733 -16.611563) (xy 420.763238 -16.726521) (xy 420.693817 -16.837434) (xy 420.617731 -16.943886)
			(xy 420.596538 -16.969994) (xy 440.048149 -16.969994) (xy 440.052154 -16.882086) (xy 440.064137 -16.794906)
			(xy 440.083997 -16.709177) (xy 440.111572 -16.625609) (xy 440.146631 -16.544895) (xy 440.188884 -16.467703)
			(xy 440.237982 -16.394674) (xy 440.293518 -16.326412) (xy 440.35503 -16.263482) (xy 440.422011 -16.206408)
			(xy 440.493904 -16.15566) (xy 440.570113 -16.11166) (xy 440.650008 -16.074773) (xy 440.732927 -16.045304)
			(xy 440.818182 -16.023497) (xy 440.905066 -16.009533) (xy 440.99286 -16.003527) (xy 441.080837 -16.005531)
			(xy 441.168267 -16.015526) (xy 441.254426 -16.03343) (xy 441.3386 -16.059094) (xy 441.420091 -16.092307)
			(xy 441.498225 -16.132793) (xy 441.572353 -16.180215) (xy 441.641861 -16.234182) (xy 441.706175 -16.294247)
			(xy 441.764759 -16.359911) (xy 441.81713 -16.43063) (xy 441.862853 -16.505818) (xy 441.90155 -16.584853)
			(xy 441.932899 -16.667079) (xy 441.956641 -16.751815) (xy 441.972579 -16.838359) (xy 441.980581 -16.925994)
			(xy 441.981082 -16.969994) (xy 441.980581 -17.013994) (xy 441.972579 -17.101629) (xy 441.956641 -17.188173)
			(xy 441.932899 -17.272909) (xy 441.90155 -17.355135) (xy 441.862853 -17.43417) (xy 441.81713 -17.509358)
			(xy 441.764759 -17.580077) (xy 441.706175 -17.645741) (xy 441.641861 -17.705806) (xy 441.572353 -17.759773)
			(xy 441.498225 -17.807195) (xy 441.420091 -17.847681) (xy 441.3386 -17.880894) (xy 441.254426 -17.906558)
			(xy 441.168267 -17.924462) (xy 441.080837 -17.934457) (xy 440.99286 -17.936461) (xy 440.905066 -17.930455)
			(xy 440.818182 -17.916491) (xy 440.732927 -17.894684) (xy 440.650008 -17.865215) (xy 440.570113 -17.828328)
			(xy 440.493904 -17.784328) (xy 440.422011 -17.73358) (xy 440.35503 -17.676506) (xy 440.293518 -17.613576)
			(xy 440.237982 -17.545314) (xy 440.188884 -17.472285) (xy 440.146631 -17.395093) (xy 440.111572 -17.314379)
			(xy 440.083997 -17.230811) (xy 440.064137 -17.145082) (xy 440.052154 -17.057902) (xy 440.048149 -16.969994)
			(xy 420.596538 -16.969994) (xy 420.535265 -17.045476) (xy 420.446731 -17.141823) (xy 420.35246 -17.232564)
			(xy 420.252806 -17.317359) (xy 420.148145 -17.39589) (xy 420.112184 -17.419574) (xy 424.584112 -17.419574)
			(xy 424.588183 -17.363952) (xy 424.600309 -17.309515) (xy 424.620232 -17.257424) (xy 424.647528 -17.208789)
			(xy 424.681614 -17.164646) (xy 424.721763 -17.125937) (xy 424.767121 -17.093486) (xy 424.816721 -17.067985)
			(xy 424.869505 -17.049978) (xy 424.924348 -17.039848) (xy 424.980082 -17.037811) (xy 425.035519 -17.043911)
			(xy 425.089476 -17.058017) (xy 425.140805 -17.079829) (xy 425.188411 -17.108883) (xy 425.231279 -17.144558)
			(xy 425.268496 -17.186095) (xy 425.299269 -17.232608) (xy 425.322941 -17.283105) (xy 425.339009 -17.336512)
			(xy 425.347129 -17.391688) (xy 425.347638 -17.419574) (xy 425.347129 -17.44746) (xy 425.339009 -17.502636)
			(xy 425.322941 -17.556043) (xy 425.299269 -17.60654) (xy 425.268496 -17.653053) (xy 425.231279 -17.69459)
			(xy 425.188411 -17.730265) (xy 425.140805 -17.759319) (xy 425.089476 -17.781131) (xy 425.035519 -17.795237)
			(xy 424.980082 -17.801337) (xy 424.924348 -17.7993) (xy 424.869505 -17.78917) (xy 424.816721 -17.771163)
			(xy 424.767121 -17.745662) (xy 424.721763 -17.713211) (xy 424.681614 -17.674502) (xy 424.647528 -17.630359)
			(xy 424.620232 -17.581724) (xy 424.600309 -17.529633) (xy 424.588183 -17.475196) (xy 424.584112 -17.419574)
			(xy 420.112184 -17.419574) (xy 420.038868 -17.46786) (xy 419.925388 -17.533001) (xy 419.80813 -17.591066)
			(xy 419.687534 -17.641838) (xy 419.564055 -17.685126) (xy 419.438155 -17.720768) (xy 419.310308 -17.748629)
			(xy 419.180995 -17.768605) (xy 419.0507 -17.78062) (xy 418.919914 -17.78463) (xy 418.789128 -17.78062)
			(xy 418.658833 -17.768605) (xy 418.52952 -17.748629) (xy 418.401673 -17.720768) (xy 418.275773 -17.685126)
			(xy 418.152294 -17.641838) (xy 418.031698 -17.591066) (xy 417.91444 -17.533001) (xy 417.80096 -17.46786)
			(xy 417.691683 -17.39589) (xy 417.587022 -17.317359) (xy 417.487368 -17.232564) (xy 417.393097 -17.141823)
			(xy 417.304563 -17.045476) (xy 417.222097 -16.943886) (xy 417.146011 -16.837434) (xy 417.07659 -16.726521)
			(xy 417.014095 -16.611563) (xy 416.95876 -16.492992) (xy 416.910793 -16.371253) (xy 416.870376 -16.246804)
			(xy 416.837659 -16.120113) (xy 416.812765 -15.991656) (xy 416.795789 -15.861914) (xy 416.786793 -15.731376)
			(xy 416.785806 -15.665958) (xy 416.785806 -15.649702) (xy 416.786297 -15.585401) (xy 416.79406 -15.457032)
			(xy 416.80954 -15.329364) (xy 416.832681 -15.202861) (xy 416.863399 -15.07798) (xy 416.901581 -14.955176)
			(xy 416.947091 -14.834895) (xy 416.999762 -14.717573) (xy 417.029138 -14.660372) (xy 417.030662 -14.657324)
			(xy 417.032806 -14.652127) (xy 417.034996 -14.641102) (xy 417.03498 -14.63548) (xy 417.034472 -14.622018)
			(xy 417.018216 -14.595094) (xy 417.018216 -14.594586) (xy 416.980878 -14.533626) (xy 416.973353 -14.523732)
			(xy 416.951384 -14.512158) (xy 416.938968 -14.511528) (xy 407.378154 -14.511528) (xy 407.368087 -14.511097)
			(xy 407.349492 -14.503374) (xy 407.342086 -14.496542) (xy 406.627838 -13.782294) (xy 406.620988 -13.774897)
			(xy 406.61325 -13.756299) (xy 406.612852 -13.746226) (xy 406.612852 -1.941322) (xy 406.612514 -1.93272)
			(xy 406.606795 -1.916495) (xy 406.601676 -1.909572) (xy 406.601168 -1.909064) (xy 406.59812 -1.905508)
			(xy 406.073102 -1.38049) (xy 406.069372 -1.376967) (xy 406.060799 -1.371335) (xy 406.056084 -1.369314)
			(xy 406.047448 -1.365758) (xy 394.298932 -1.365758) (xy 394.290329 -1.366094) (xy 394.274103 -1.371812)
			(xy 394.267182 -1.376934) (xy 394.266674 -1.377442) (xy 394.263118 -1.38049) (xy 393.795504 -1.848104)
			(xy 393.791981 -1.851833) (xy 393.786348 -1.860406) (xy 393.784328 -1.865122) (xy 393.780772 -1.873758)
			(xy 393.780772 -13.649198) (xy 393.781009 -13.655945) (xy 393.784601 -13.668954) (xy 393.787884 -13.674852)
			(xy 393.802616 -13.697712) (xy 393.81176 -13.708634) (xy 393.817094 -13.713206) (xy 393.823698 -13.716254)
			(xy 393.884895 -13.745441) (xy 394.003843 -13.810541) (xy 394.118418 -13.883061) (xy 394.228157 -13.962711)
			(xy 394.332617 -14.049167) (xy 394.431377 -14.142081) (xy 394.524039 -14.241078) (xy 394.610228 -14.345759)
			(xy 394.689596 -14.455702) (xy 394.72616 -14.512798) (xy 394.734034 -14.512798) (xy 394.800074 -14.639544)
			(xy 394.804646 -14.64818) (xy 394.804646 -14.648434) (xy 394.810742 -14.660118) (xy 394.840143 -14.717325)
			(xy 394.848213 -14.735302) (xy 398.879312 -14.735302) (xy 398.883383 -14.67968) (xy 398.895509 -14.625243)
			(xy 398.915432 -14.573152) (xy 398.942728 -14.524517) (xy 398.976814 -14.480374) (xy 399.016963 -14.441665)
			(xy 399.062321 -14.409214) (xy 399.111921 -14.383713) (xy 399.164705 -14.365706) (xy 399.219548 -14.355576)
			(xy 399.275282 -14.353539) (xy 399.330719 -14.359639) (xy 399.384676 -14.373745) (xy 399.436005 -14.395557)
			(xy 399.483611 -14.424611) (xy 399.526479 -14.460286) (xy 399.563696 -14.501823) (xy 399.594469 -14.548336)
			(xy 399.618141 -14.598833) (xy 399.634209 -14.65224) (xy 399.642329 -14.707416) (xy 399.642838 -14.735302)
			(xy 399.642329 -14.763188) (xy 399.634209 -14.818364) (xy 399.618141 -14.871771) (xy 399.594469 -14.922268)
			(xy 399.563696 -14.968781) (xy 399.526479 -15.010318) (xy 399.483611 -15.045993) (xy 399.436005 -15.075047)
			(xy 399.384676 -15.096859) (xy 399.330719 -15.110965) (xy 399.275282 -15.117065) (xy 399.219548 -15.115028)
			(xy 399.164705 -15.104898) (xy 399.111921 -15.086891) (xy 399.062321 -15.06139) (xy 399.016963 -15.028939)
			(xy 398.976814 -14.99023) (xy 398.942728 -14.946087) (xy 398.915432 -14.897452) (xy 398.895509 -14.845361)
			(xy 398.883383 -14.790924) (xy 398.879312 -14.735302) (xy 394.848213 -14.735302) (xy 394.892826 -14.834677)
			(xy 394.938344 -14.954991) (xy 394.976531 -15.077828) (xy 395.007248 -15.202742) (xy 395.030384 -15.32928)
			(xy 395.038655 -15.397554) (xy 400.204357 -15.397554) (xy 400.204357 -15.343046) (xy 400.212115 -15.289092)
			(xy 400.227473 -15.236792) (xy 400.250117 -15.18721) (xy 400.279588 -15.141356) (xy 400.315285 -15.100163)
			(xy 400.356482 -15.064469) (xy 400.402338 -15.035002) (xy 400.451922 -15.012362) (xy 400.504224 -14.997008)
			(xy 400.558178 -14.989255) (xy 400.585432 -14.988794) (xy 400.611668 -14.989232) (xy 400.663645 -14.996432)
			(xy 400.714144 -15.01069) (xy 400.76221 -15.031739) (xy 400.806937 -15.059179) (xy 400.847478 -15.092493)
			(xy 400.865594 -15.111476) (xy 400.865848 -15.11173) (xy 400.873584 -15.119107) (xy 400.893265 -15.127384)
			(xy 400.903948 -15.127732) (xy 400.991832 -15.125446) (xy 401.01139 -15.116048) (xy 401.018502 -15.107412)
			(xy 401.036686 -15.086237) (xy 401.078232 -15.048964) (xy 401.124767 -15.018145) (xy 401.175297 -14.994439)
			(xy 401.228744 -14.978351) (xy 401.283964 -14.970225) (xy 401.311872 -14.969744) (xy 401.339123 -14.970301)
			(xy 401.39307 -14.978054) (xy 401.445365 -14.993406) (xy 401.494942 -15.016044) (xy 401.540793 -15.045507)
			(xy 401.581984 -15.081197) (xy 401.617676 -15.122385) (xy 401.647143 -15.168233) (xy 401.669784 -15.217809)
			(xy 401.68514 -15.270103) (xy 401.692897 -15.324049) (xy 401.692897 -15.378551) (xy 401.68514 -15.432497)
			(xy 401.669784 -15.484791) (xy 401.647143 -15.534367) (xy 401.617676 -15.580215) (xy 401.581984 -15.621403)
			(xy 401.540793 -15.657093) (xy 401.494942 -15.686556) (xy 401.445365 -15.709194) (xy 401.39307 -15.724546)
			(xy 401.339123 -15.732299) (xy 401.311872 -15.73276) (xy 401.285635 -15.732334) (xy 401.233657 -15.725134)
			(xy 401.183158 -15.710874) (xy 401.135091 -15.689823) (xy 401.090365 -15.66238) (xy 401.049825 -15.629063)
			(xy 401.03171 -15.610078) (xy 401.031456 -15.609824) (xy 401.023724 -15.602442) (xy 401.00404 -15.594169)
			(xy 400.993356 -15.593822) (xy 400.905472 -15.596108) (xy 400.885914 -15.605506) (xy 400.878802 -15.614142)
			(xy 400.860605 -15.635306) (xy 400.819064 -15.672582) (xy 400.772531 -15.703403) (xy 400.722003 -15.727112)
			(xy 400.668558 -15.743202) (xy 400.613339 -15.751328) (xy 400.585432 -15.75181) (xy 400.558178 -15.751345)
			(xy 400.504224 -15.743592) (xy 400.451922 -15.728238) (xy 400.402338 -15.705598) (xy 400.356481 -15.676131)
			(xy 400.315285 -15.640437) (xy 400.279588 -15.599244) (xy 400.250117 -15.55339) (xy 400.227473 -15.503808)
			(xy 400.212115 -15.451508) (xy 400.204357 -15.397554) (xy 395.038655 -15.397554) (xy 395.045854 -15.456982)
			(xy 395.053604 -15.585384) (xy 395.054074 -15.649702) (xy 395.054074 -15.649956) (xy 395.053568 -15.715692)
			(xy 395.045475 -15.846913) (xy 395.029318 -15.977388) (xy 395.005161 -16.106621) (xy 394.973093 -16.234121)
			(xy 394.933237 -16.359405) (xy 394.885744 -16.481999) (xy 394.830795 -16.601436) (xy 394.768596 -16.717263)
			(xy 394.699386 -16.829042) (xy 394.623425 -16.936349) (xy 394.596351 -16.969994) (xy 414.048201 -16.969994)
			(xy 414.052206 -16.882086) (xy 414.064189 -16.794906) (xy 414.084049 -16.709177) (xy 414.111624 -16.625609)
			(xy 414.146683 -16.544895) (xy 414.188936 -16.467703) (xy 414.238034 -16.394674) (xy 414.29357 -16.326412)
			(xy 414.355082 -16.263482) (xy 414.422063 -16.206408) (xy 414.493956 -16.15566) (xy 414.570165 -16.11166)
			(xy 414.65006 -16.074773) (xy 414.732979 -16.045304) (xy 414.818234 -16.023497) (xy 414.905118 -16.009533)
			(xy 414.992912 -16.003527) (xy 415.080889 -16.005531) (xy 415.168319 -16.015526) (xy 415.254478 -16.03343)
			(xy 415.338652 -16.059094) (xy 415.420143 -16.092307) (xy 415.498277 -16.132793) (xy 415.572405 -16.180215)
			(xy 415.641913 -16.234182) (xy 415.706227 -16.294247) (xy 415.764811 -16.359911) (xy 415.817182 -16.43063)
			(xy 415.862905 -16.505818) (xy 415.901602 -16.584853) (xy 415.932951 -16.667079) (xy 415.956693 -16.751815)
			(xy 415.972631 -16.838359) (xy 415.980633 -16.925994) (xy 415.981134 -16.969994) (xy 415.980633 -17.013994)
			(xy 415.972631 -17.101629) (xy 415.956693 -17.188173) (xy 415.932951 -17.272909) (xy 415.901602 -17.355135)
			(xy 415.862905 -17.43417) (xy 415.817182 -17.509358) (xy 415.764811 -17.580077) (xy 415.706227 -17.645741)
			(xy 415.641913 -17.705806) (xy 415.572405 -17.759773) (xy 415.498277 -17.807195) (xy 415.420143 -17.847681)
			(xy 415.338652 -17.880894) (xy 415.254478 -17.906558) (xy 415.168319 -17.924462) (xy 415.080889 -17.934457)
			(xy 414.992912 -17.936461) (xy 414.905118 -17.930455) (xy 414.818234 -17.916491) (xy 414.732979 -17.894684)
			(xy 414.65006 -17.865215) (xy 414.570165 -17.828328) (xy 414.493956 -17.784328) (xy 414.422063 -17.73358)
			(xy 414.355082 -17.676506) (xy 414.29357 -17.613576) (xy 414.238034 -17.545314) (xy 414.188936 -17.472285)
			(xy 414.146683 -17.395093) (xy 414.111624 -17.314379) (xy 414.084049 -17.230811) (xy 414.064189 -17.145082)
			(xy 414.052206 -17.057902) (xy 414.048201 -16.969994) (xy 394.596351 -16.969994) (xy 394.541003 -17.038775)
			(xy 394.452431 -17.135934) (xy 394.358046 -17.227455) (xy 394.258207 -17.312993) (xy 394.15329 -17.392222)
			(xy 394.112012 -17.419574) (xy 398.584164 -17.419574) (xy 398.588235 -17.363952) (xy 398.600361 -17.309515)
			(xy 398.620284 -17.257424) (xy 398.64758 -17.208789) (xy 398.681666 -17.164646) (xy 398.721815 -17.125937)
			(xy 398.767173 -17.093486) (xy 398.816773 -17.067985) (xy 398.869557 -17.049978) (xy 398.9244 -17.039848)
			(xy 398.980134 -17.037811) (xy 399.035571 -17.043911) (xy 399.089528 -17.058017) (xy 399.140857 -17.079829)
			(xy 399.188463 -17.108883) (xy 399.231331 -17.144558) (xy 399.268548 -17.186095) (xy 399.299321 -17.232608)
			(xy 399.322993 -17.283105) (xy 399.339061 -17.336512) (xy 399.347181 -17.391688) (xy 399.34769 -17.419574)
			(xy 399.347181 -17.44746) (xy 399.339061 -17.502636) (xy 399.322993 -17.556043) (xy 399.299321 -17.60654)
			(xy 399.268548 -17.653053) (xy 399.231331 -17.69459) (xy 399.188463 -17.730265) (xy 399.140857 -17.759319)
			(xy 399.089528 -17.781131) (xy 399.035571 -17.795237) (xy 398.980134 -17.801337) (xy 398.9244 -17.7993)
			(xy 398.869557 -17.78917) (xy 398.816773 -17.771163) (xy 398.767173 -17.745662) (xy 398.721815 -17.713211)
			(xy 398.681666 -17.674502) (xy 398.64758 -17.630359) (xy 398.620284 -17.581724) (xy 398.600361 -17.529633)
			(xy 398.588235 -17.475196) (xy 398.584164 -17.419574) (xy 394.112012 -17.419574) (xy 394.043696 -17.464842)
			(xy 393.929838 -17.530577) (xy 393.81215 -17.589179) (xy 393.691078 -17.640425) (xy 393.56708 -17.68412)
			(xy 393.440628 -17.720099) (xy 393.3122 -17.748225) (xy 393.182285 -17.768391) (xy 393.051375 -17.780522)
			(xy 392.919966 -17.784571) (xy 392.788557 -17.780522) (xy 392.657647 -17.768391) (xy 392.527732 -17.748225)
			(xy 392.399304 -17.720099) (xy 392.272852 -17.68412) (xy 392.148854 -17.640425) (xy 392.027782 -17.589179)
			(xy 391.910094 -17.530577) (xy 391.796236 -17.464842) (xy 391.686642 -17.392222) (xy 391.581725 -17.312993)
			(xy 391.481886 -17.227455) (xy 391.387501 -17.135934) (xy 391.298929 -17.038775) (xy 391.216507 -16.936349)
			(xy 391.140546 -16.829042) (xy 391.071336 -16.717263) (xy 391.009137 -16.601436) (xy 390.954188 -16.481999)
			(xy 390.906695 -16.359405) (xy 390.866839 -16.234121) (xy 390.834771 -16.106621) (xy 390.810614 -15.977388)
			(xy 390.794457 -15.846913) (xy 390.786364 -15.715692) (xy 390.785858 -15.649956) (xy 390.785858 -15.649702)
			(xy 390.78634 -15.585384) (xy 390.794089 -15.456983) (xy 390.809559 -15.329281) (xy 390.832693 -15.202743)
			(xy 390.863408 -15.077828) (xy 390.901591 -14.954991) (xy 390.947106 -14.834676) (xy 390.999785 -14.717322)
			(xy 391.02919 -14.660118) (xy 391.031222 -14.656054) (xy 391.033106 -14.651126) (xy 391.035037 -14.640756)
			(xy 391.035032 -14.63548) (xy 391.034524 -14.621764) (xy 390.982454 -14.535912) (xy 390.977636 -14.528653)
			(xy 390.964134 -14.517661) (xy 390.947726 -14.511841) (xy 390.93902 -14.511528) (xy 381.378206 -14.511528)
			(xy 381.368135 -14.511107) (xy 381.349526 -14.503397) (xy 381.342138 -14.496542) (xy 380.62789 -13.782294)
			(xy 380.621035 -13.774899) (xy 380.613288 -13.7563) (xy 380.612904 -13.746226) (xy 380.612904 -9.323832)
			(xy 380.611126 -9.310624) (xy 380.609634 -9.305601) (xy 380.604893 -9.296258) (xy 380.601728 -9.292082)
			(xy 380.596394 -9.285478) (xy 380.581662 -9.276588) (xy 380.572518 -9.274556) (xy 380.572264 -9.274556)
			(xy 380.545469 -9.268515) (xy 380.49384 -9.249773) (xy 380.44543 -9.223823) (xy 380.401242 -9.191199)
			(xy 380.362188 -9.152578) (xy 380.329074 -9.108756) (xy 380.302585 -9.060639) (xy 380.283269 -9.009221)
			(xy 380.271524 -8.955565) (xy 380.267594 -8.90078) (xy 380.271559 -8.845997) (xy 380.283337 -8.792349)
			(xy 380.302686 -8.740943) (xy 380.329205 -8.692843) (xy 380.362346 -8.649042) (xy 380.401425 -8.610445)
			(xy 380.445633 -8.577849) (xy 380.494059 -8.551929) (xy 380.5457 -8.533219) (xy 380.572518 -8.527288)
			(xy 380.575058 -8.52678) (xy 380.582883 -8.524458) (xy 380.596625 -8.515665) (xy 380.601982 -8.509508)
			(xy 380.607062 -8.502904) (xy 380.609856 -8.49503) (xy 380.611263 -8.490851) (xy 380.612792 -8.482167)
			(xy 380.612904 -8.477758) (xy 380.612904 -8.307832) (xy 380.611126 -8.294624) (xy 380.609634 -8.289601)
			(xy 380.604893 -8.280258) (xy 380.601728 -8.276082) (xy 380.596394 -8.269478) (xy 380.581662 -8.260588)
			(xy 380.572518 -8.258556) (xy 380.572264 -8.258556) (xy 380.545469 -8.252515) (xy 380.49384 -8.233773)
			(xy 380.44543 -8.207823) (xy 380.401242 -8.175199) (xy 380.362188 -8.136578) (xy 380.329074 -8.092756)
			(xy 380.302585 -8.044639) (xy 380.283269 -7.993221) (xy 380.271524 -7.939565) (xy 380.267594 -7.88478)
			(xy 380.271559 -7.829997) (xy 380.283337 -7.776349) (xy 380.302686 -7.724943) (xy 380.329205 -7.676843)
			(xy 380.362346 -7.633042) (xy 380.401425 -7.594445) (xy 380.445633 -7.561849) (xy 380.494059 -7.535929)
			(xy 380.5457 -7.517219) (xy 380.572518 -7.511288) (xy 380.575058 -7.51078) (xy 380.582883 -7.508458)
			(xy 380.596625 -7.499665) (xy 380.601982 -7.493508) (xy 380.607062 -7.486904) (xy 380.609856 -7.47903)
			(xy 380.611263 -7.474851) (xy 380.612792 -7.466167) (xy 380.612904 -7.461758) (xy 380.612904 -7.291832)
			(xy 380.611126 -7.278624) (xy 380.609634 -7.273601) (xy 380.604893 -7.264258) (xy 380.601728 -7.260082)
			(xy 380.596394 -7.253478) (xy 380.581662 -7.244588) (xy 380.572518 -7.242556) (xy 380.572264 -7.242556)
			(xy 380.545469 -7.236515) (xy 380.49384 -7.217773) (xy 380.44543 -7.191823) (xy 380.401242 -7.159199)
			(xy 380.362188 -7.120578) (xy 380.329074 -7.076756) (xy 380.302585 -7.028639) (xy 380.283269 -6.977221)
			(xy 380.271524 -6.923565) (xy 380.267594 -6.86878) (xy 380.271559 -6.813997) (xy 380.283337 -6.760349)
			(xy 380.302686 -6.708943) (xy 380.329205 -6.660843) (xy 380.362346 -6.617042) (xy 380.401425 -6.578445)
			(xy 380.445633 -6.545849) (xy 380.494059 -6.519929) (xy 380.5457 -6.501219) (xy 380.572518 -6.495288)
			(xy 380.575058 -6.49478) (xy 380.582883 -6.492458) (xy 380.596625 -6.483665) (xy 380.601982 -6.477508)
			(xy 380.607062 -6.470904) (xy 380.609856 -6.46303) (xy 380.611263 -6.458851) (xy 380.612792 -6.450167)
			(xy 380.612904 -6.445758) (xy 380.612904 -6.275832) (xy 380.611126 -6.262624) (xy 380.609634 -6.257601)
			(xy 380.604893 -6.248258) (xy 380.601728 -6.244082) (xy 380.596394 -6.237478) (xy 380.581662 -6.228588)
			(xy 380.572518 -6.226556) (xy 380.572264 -6.226556) (xy 380.545469 -6.220515) (xy 380.49384 -6.201773)
			(xy 380.44543 -6.175823) (xy 380.401242 -6.143199) (xy 380.362188 -6.104578) (xy 380.329074 -6.060756)
			(xy 380.302585 -6.012639) (xy 380.283269 -5.961221) (xy 380.271524 -5.907565) (xy 380.267594 -5.85278)
			(xy 380.271559 -5.797997) (xy 380.283337 -5.744349) (xy 380.302686 -5.692943) (xy 380.329205 -5.644843)
			(xy 380.362346 -5.601042) (xy 380.401425 -5.562445) (xy 380.445633 -5.529849) (xy 380.494059 -5.503929)
			(xy 380.5457 -5.485219) (xy 380.572518 -5.479288) (xy 380.575058 -5.47878) (xy 380.582883 -5.476458)
			(xy 380.596625 -5.467665) (xy 380.601982 -5.461508) (xy 380.607062 -5.454904) (xy 380.609856 -5.44703)
			(xy 380.611263 -5.442851) (xy 380.612792 -5.434167) (xy 380.612904 -5.429758) (xy 380.612904 -5.259832)
			(xy 380.611126 -5.246624) (xy 380.609634 -5.241601) (xy 380.604893 -5.232258) (xy 380.601728 -5.228082)
			(xy 380.596394 -5.221478) (xy 380.581662 -5.212588) (xy 380.572518 -5.210556) (xy 380.572264 -5.210556)
			(xy 380.545469 -5.204515) (xy 380.49384 -5.185773) (xy 380.44543 -5.159823) (xy 380.401242 -5.127199)
			(xy 380.362188 -5.088578) (xy 380.329074 -5.044756) (xy 380.302585 -4.996639) (xy 380.283269 -4.945221)
			(xy 380.271524 -4.891565) (xy 380.267594 -4.83678) (xy 380.271559 -4.781997) (xy 380.283337 -4.728349)
			(xy 380.302686 -4.676943) (xy 380.329205 -4.628843) (xy 380.362346 -4.585042) (xy 380.401425 -4.546445)
			(xy 380.445633 -4.513849) (xy 380.494059 -4.487929) (xy 380.5457 -4.469219) (xy 380.572518 -4.463288)
			(xy 380.575058 -4.46278) (xy 380.582883 -4.460458) (xy 380.596625 -4.451665) (xy 380.601982 -4.445508)
			(xy 380.607062 -4.438904) (xy 380.609856 -4.43103) (xy 380.611263 -4.426851) (xy 380.612792 -4.418167)
			(xy 380.612904 -4.413758) (xy 380.612904 -4.243832) (xy 380.611126 -4.230624) (xy 380.609634 -4.225601)
			(xy 380.604893 -4.216258) (xy 380.601728 -4.212082) (xy 380.596394 -4.205478) (xy 380.581662 -4.196588)
			(xy 380.572518 -4.194556) (xy 380.572264 -4.194556) (xy 380.545469 -4.188515) (xy 380.49384 -4.169773)
			(xy 380.44543 -4.143823) (xy 380.401242 -4.111199) (xy 380.362188 -4.072578) (xy 380.329074 -4.028756)
			(xy 380.302585 -3.980639) (xy 380.283269 -3.929221) (xy 380.271524 -3.875565) (xy 380.267594 -3.82078)
			(xy 380.271559 -3.765997) (xy 380.283337 -3.712349) (xy 380.302686 -3.660943) (xy 380.329205 -3.612843)
			(xy 380.362346 -3.569042) (xy 380.401425 -3.530445) (xy 380.445633 -3.497849) (xy 380.494059 -3.471929)
			(xy 380.5457 -3.453219) (xy 380.572518 -3.447288) (xy 380.575058 -3.44678) (xy 380.582883 -3.444458)
			(xy 380.596625 -3.435665) (xy 380.601982 -3.429508) (xy 380.607062 -3.422904) (xy 380.609856 -3.41503)
			(xy 380.611263 -3.410851) (xy 380.612792 -3.402167) (xy 380.612904 -3.397758) (xy 380.612904 -1.941322)
			(xy 380.612734 -1.935313) (xy 380.609904 -1.923634) (xy 380.607316 -1.918208) (xy 380.605478 -1.914732)
			(xy 380.600888 -1.90835) (xy 380.598172 -1.905508) (xy 380.073154 -1.38049) (xy 380.0703 -1.377788)
			(xy 380.063917 -1.373204) (xy 380.060454 -1.371346) (xy 380.055028 -1.368761) (xy 380.043348 -1.365935)
			(xy 380.03734 -1.365758) (xy 368.298984 -1.365758) (xy 368.292973 -1.365921) (xy 368.281286 -1.368736)
			(xy 368.27587 -1.371346) (xy 368.272397 -1.373188) (xy 368.266022 -1.377785) (xy 368.26317 -1.38049)
			(xy 367.795556 -1.848104) (xy 367.792849 -1.850954) (xy 367.788255 -1.857332) (xy 367.786412 -1.860804)
			(xy 367.783824 -1.86623) (xy 367.780991 -1.877909) (xy 367.780824 -1.883918) (xy 367.780824 -4.48183)
			(xy 377.965206 -4.48183) (xy 377.969277 -4.426208) (xy 377.981403 -4.371771) (xy 378.001326 -4.31968)
			(xy 378.028622 -4.271045) (xy 378.062708 -4.226902) (xy 378.102857 -4.188193) (xy 378.148215 -4.155742)
			(xy 378.197815 -4.130241) (xy 378.250599 -4.112234) (xy 378.305442 -4.102104) (xy 378.361176 -4.100067)
			(xy 378.416613 -4.106167) (xy 378.47057 -4.120273) (xy 378.521899 -4.142085) (xy 378.569505 -4.171139)
			(xy 378.612373 -4.206814) (xy 378.64959 -4.248351) (xy 378.680363 -4.294864) (xy 378.704035 -4.345361)
			(xy 378.720103 -4.398768) (xy 378.728223 -4.453944) (xy 378.728732 -4.48183) (xy 378.728223 -4.509716)
			(xy 378.720103 -4.564892) (xy 378.704035 -4.618299) (xy 378.680363 -4.668796) (xy 378.64959 -4.715309)
			(xy 378.612373 -4.756846) (xy 378.569505 -4.792521) (xy 378.521899 -4.821575) (xy 378.47057 -4.843387)
			(xy 378.416613 -4.857493) (xy 378.361176 -4.863593) (xy 378.305442 -4.861556) (xy 378.250599 -4.851426)
			(xy 378.197815 -4.833419) (xy 378.148215 -4.807918) (xy 378.102857 -4.775467) (xy 378.062708 -4.736758)
			(xy 378.028622 -4.692615) (xy 378.001326 -4.64398) (xy 377.981403 -4.591889) (xy 377.969277 -4.537452)
			(xy 377.965206 -4.48183) (xy 367.780824 -4.48183) (xy 367.780824 -5.852922) (xy 378.220984 -5.852922)
			(xy 378.225055 -5.7973) (xy 378.237181 -5.742863) (xy 378.257104 -5.690772) (xy 378.2844 -5.642137)
			(xy 378.318486 -5.597994) (xy 378.358635 -5.559285) (xy 378.403993 -5.526834) (xy 378.453593 -5.501333)
			(xy 378.506377 -5.483326) (xy 378.56122 -5.473196) (xy 378.616954 -5.471159) (xy 378.672391 -5.477259)
			(xy 378.726348 -5.491365) (xy 378.777677 -5.513177) (xy 378.825283 -5.542231) (xy 378.868151 -5.577906)
			(xy 378.905368 -5.619443) (xy 378.936141 -5.665956) (xy 378.959813 -5.716453) (xy 378.975881 -5.76986)
			(xy 378.984001 -5.825036) (xy 378.98451 -5.852922) (xy 378.984001 -5.880808) (xy 378.975881 -5.935984)
			(xy 378.959813 -5.989391) (xy 378.936141 -6.039888) (xy 378.905368 -6.086401) (xy 378.868151 -6.127938)
			(xy 378.825283 -6.163613) (xy 378.777677 -6.192667) (xy 378.726348 -6.214479) (xy 378.672391 -6.228585)
			(xy 378.616954 -6.234685) (xy 378.56122 -6.232648) (xy 378.506377 -6.222518) (xy 378.453593 -6.204511)
			(xy 378.403993 -6.17901) (xy 378.358635 -6.146559) (xy 378.318486 -6.10785) (xy 378.2844 -6.063707)
			(xy 378.257104 -6.015072) (xy 378.237181 -5.962981) (xy 378.225055 -5.908544) (xy 378.220984 -5.852922)
			(xy 367.780824 -5.852922) (xy 367.780824 -6.71195) (xy 369.906548 -6.71195) (xy 369.910619 -6.656328)
			(xy 369.922745 -6.601891) (xy 369.942668 -6.5498) (xy 369.969964 -6.501165) (xy 370.00405 -6.457022)
			(xy 370.044199 -6.418313) (xy 370.089557 -6.385862) (xy 370.139157 -6.360361) (xy 370.191941 -6.342354)
			(xy 370.246784 -6.332224) (xy 370.302518 -6.330187) (xy 370.357955 -6.336287) (xy 370.411912 -6.350393)
			(xy 370.463241 -6.372205) (xy 370.510847 -6.401259) (xy 370.553715 -6.436934) (xy 370.590932 -6.478471)
			(xy 370.621705 -6.524984) (xy 370.645377 -6.575481) (xy 370.661445 -6.628888) (xy 370.669565 -6.684064)
			(xy 370.670074 -6.71195) (xy 370.669565 -6.739836) (xy 370.661445 -6.795012) (xy 370.645377 -6.848419)
			(xy 370.621705 -6.898916) (xy 370.590932 -6.945429) (xy 370.553715 -6.986966) (xy 370.510847 -7.022641)
			(xy 370.463241 -7.051695) (xy 370.411912 -7.073507) (xy 370.357955 -7.087613) (xy 370.302518 -7.093713)
			(xy 370.246784 -7.091676) (xy 370.191941 -7.081546) (xy 370.139157 -7.063539) (xy 370.089557 -7.038038)
			(xy 370.044199 -7.005587) (xy 370.00405 -6.966878) (xy 369.969964 -6.922735) (xy 369.942668 -6.8741)
			(xy 369.922745 -6.822009) (xy 369.910619 -6.767572) (xy 369.906548 -6.71195) (xy 367.780824 -6.71195)
			(xy 367.780824 -7.473696) (xy 378.034548 -7.473696) (xy 378.038619 -7.418074) (xy 378.050745 -7.363637)
			(xy 378.070668 -7.311546) (xy 378.097964 -7.262911) (xy 378.13205 -7.218768) (xy 378.172199 -7.180059)
			(xy 378.217557 -7.147608) (xy 378.267157 -7.122107) (xy 378.319941 -7.1041) (xy 378.374784 -7.09397)
			(xy 378.430518 -7.091933) (xy 378.485955 -7.098033) (xy 378.539912 -7.112139) (xy 378.591241 -7.133951)
			(xy 378.638847 -7.163005) (xy 378.681715 -7.19868) (xy 378.718932 -7.240217) (xy 378.749705 -7.28673)
			(xy 378.773377 -7.337227) (xy 378.789445 -7.390634) (xy 378.797565 -7.44581) (xy 378.798074 -7.473696)
			(xy 378.797565 -7.501582) (xy 378.789445 -7.556758) (xy 378.773377 -7.610165) (xy 378.749705 -7.660662)
			(xy 378.718932 -7.707175) (xy 378.681715 -7.748712) (xy 378.638847 -7.784387) (xy 378.591241 -7.813441)
			(xy 378.539912 -7.835253) (xy 378.485955 -7.849359) (xy 378.430518 -7.855459) (xy 378.374784 -7.853422)
			(xy 378.319941 -7.843292) (xy 378.267157 -7.825285) (xy 378.217557 -7.799784) (xy 378.172199 -7.767333)
			(xy 378.13205 -7.728624) (xy 378.097964 -7.684481) (xy 378.070668 -7.635846) (xy 378.050745 -7.583755)
			(xy 378.038619 -7.529318) (xy 378.034548 -7.473696) (xy 367.780824 -7.473696) (xy 367.780824 -7.759446)
			(xy 367.781072 -7.76686) (xy 367.785325 -7.781064) (xy 367.789206 -7.787386) (xy 367.79327 -7.793482)
			(xy 367.804446 -7.80288) (xy 367.811558 -7.805928) (xy 367.836942 -7.817339) (xy 367.884382 -7.846437)
			(xy 367.92709 -7.88212) (xy 367.96416 -7.923631) (xy 367.994803 -7.970088) (xy 368.011389 -8.005572)
			(xy 369.78412 -8.005572) (xy 369.788191 -7.94995) (xy 369.800317 -7.895513) (xy 369.82024 -7.843422)
			(xy 369.847536 -7.794787) (xy 369.881622 -7.750644) (xy 369.921771 -7.711935) (xy 369.967129 -7.679484)
			(xy 370.016729 -7.653983) (xy 370.069513 -7.635976) (xy 370.124356 -7.625846) (xy 370.18009 -7.623809)
			(xy 370.235527 -7.629909) (xy 370.289484 -7.644015) (xy 370.340813 -7.665827) (xy 370.388419 -7.694881)
			(xy 370.431287 -7.730556) (xy 370.468504 -7.772093) (xy 370.499277 -7.818606) (xy 370.522949 -7.869103)
			(xy 370.539017 -7.92251) (xy 370.547137 -7.977686) (xy 370.547646 -8.005572) (xy 370.547137 -8.033458)
			(xy 370.539017 -8.088634) (xy 370.522949 -8.142041) (xy 370.499277 -8.192538) (xy 370.468504 -8.239051)
			(xy 370.431287 -8.280588) (xy 370.388419 -8.316263) (xy 370.340813 -8.345317) (xy 370.289484 -8.367129)
			(xy 370.235527 -8.381235) (xy 370.18009 -8.387335) (xy 370.124356 -8.385298) (xy 370.069513 -8.375168)
			(xy 370.016729 -8.357161) (xy 369.967129 -8.33166) (xy 369.921771 -8.299209) (xy 369.881622 -8.2605)
			(xy 369.847536 -8.216357) (xy 369.82024 -8.167722) (xy 369.800317 -8.115631) (xy 369.788191 -8.061194)
			(xy 369.78412 -8.005572) (xy 368.011389 -8.005572) (xy 368.018369 -8.020505) (xy 368.034359 -8.073811)
			(xy 368.042432 -8.128875) (xy 368.042952 -8.156702) (xy 368.04286 -8.168737) (xy 368.041334 -8.192758)
			(xy 368.039904 -8.204708) (xy 368.039396 -8.209534) (xy 368.03838 -8.216646) (xy 368.042444 -8.228076)
			(xy 368.044281 -8.232756) (xy 368.049521 -8.241334) (xy 368.052858 -8.245094) (xy 368.114326 -8.30453)
			(xy 368.11866 -8.308348) (xy 368.128664 -8.314115) (xy 368.134138 -8.31596) (xy 368.141758 -8.318246)
			(xy 368.152934 -8.318246) (xy 368.157506 -8.317484) (xy 368.173016 -8.315094) (xy 368.204298 -8.312552)
			(xy 368.21999 -8.312404) (xy 368.247564 -8.31289) (xy 368.302138 -8.320831) (xy 368.354998 -8.33655)
			(xy 368.405044 -8.359718) (xy 368.451231 -8.389852) (xy 368.492596 -8.426324) (xy 368.51082 -8.447024)
			(xy 368.511074 -8.447278) (xy 368.514929 -8.451524) (xy 368.52416 -8.458326) (xy 368.529362 -8.46074)
			(xy 368.534696 -8.463026) (xy 368.54638 -8.465312) (xy 368.63528 -8.459978) (xy 368.640121 -8.459383)
			(xy 368.649461 -8.456574) (xy 368.653822 -8.45439) (xy 368.661696 -8.449818) (xy 368.668808 -8.443214)
			(xy 368.672618 -8.437626) (xy 368.687857 -8.415575) (xy 368.723531 -8.37557) (xy 368.764455 -8.340955)
			(xy 368.809822 -8.31241) (xy 368.858739 -8.290499) (xy 368.910243 -8.275652) (xy 368.963318 -8.268164)
			(xy 368.990118 -8.2677) (xy 369.017368 -8.268187) (xy 369.071312 -8.275945) (xy 369.123604 -8.291302)
			(xy 369.173178 -8.313943) (xy 369.219025 -8.34341) (xy 369.260212 -8.3791) (xy 369.295901 -8.420289)
			(xy 369.325365 -8.466138) (xy 369.348005 -8.515713) (xy 369.363358 -8.568005) (xy 369.371114 -8.62195)
			(xy 369.371114 -8.67645) (xy 369.363358 -8.730395) (xy 369.348005 -8.782687) (xy 369.325365 -8.832262)
			(xy 369.295901 -8.878111) (xy 369.260212 -8.9193) (xy 369.219025 -8.95499) (xy 369.173178 -8.984457)
			(xy 369.123604 -9.007098) (xy 369.071312 -9.022455) (xy 369.017368 -9.030213) (xy 368.990118 -9.030716)
			(xy 368.962543 -9.030231) (xy 368.907969 -9.022291) (xy 368.855107 -9.006574) (xy 368.80506 -8.983407)
			(xy 368.758871 -8.953274) (xy 368.717503 -8.916804) (xy 368.699288 -8.896096) (xy 368.699034 -8.895842)
			(xy 368.69518 -8.891594) (xy 368.685951 -8.884788) (xy 368.680746 -8.88238) (xy 368.675412 -8.880094)
			(xy 368.663728 -8.877808) (xy 368.574828 -8.883142) (xy 368.569987 -8.883736) (xy 368.560647 -8.886545)
			(xy 368.556286 -8.88873) (xy 368.548412 -8.893302) (xy 368.5413 -8.899906) (xy 368.53749 -8.905494)
			(xy 368.522251 -8.927544) (xy 368.486576 -8.967548) (xy 368.445652 -9.002163) (xy 368.400284 -9.030707)
			(xy 368.351367 -9.052618) (xy 368.299864 -9.067464) (xy 368.24679 -9.074953) (xy 368.21999 -9.07542)
			(xy 368.190548 -9.074874) (xy 368.132364 -9.065827) (xy 368.07626 -9.047952) (xy 368.023567 -9.02167)
			(xy 367.975537 -8.987607) (xy 367.954052 -8.96747) (xy 367.953544 -8.966962) (xy 367.95075 -8.964422)
			(xy 367.947194 -8.961374) (xy 367.942114 -8.95858) (xy 367.938452 -8.956654) (xy 367.930667 -8.953852)
			(xy 367.92662 -8.952992) (xy 367.912396 -8.950452) (xy 367.909856 -8.951468) (xy 367.88598 -8.961374)
			(xy 367.811812 -8.992616) (xy 367.804494 -8.995955) (xy 367.792306 -9.006438) (xy 367.787936 -9.01319)
			(xy 367.786158 -9.016492) (xy 367.78383 -9.021394) (xy 367.781132 -9.031903) (xy 367.780824 -9.03732)
			(xy 367.780824 -10.35812) (xy 375.53087 -10.35812) (xy 375.534941 -10.302498) (xy 375.547067 -10.248061)
			(xy 375.56699 -10.19597) (xy 375.594286 -10.147335) (xy 375.628372 -10.103192) (xy 375.668521 -10.064483)
			(xy 375.713879 -10.032032) (xy 375.763479 -10.006531) (xy 375.816263 -9.988524) (xy 375.871106 -9.978394)
			(xy 375.92684 -9.976357) (xy 375.982277 -9.982457) (xy 376.036234 -9.996563) (xy 376.087563 -10.018375)
			(xy 376.135169 -10.047429) (xy 376.178037 -10.083104) (xy 376.215254 -10.124641) (xy 376.246027 -10.171154)
			(xy 376.269699 -10.221651) (xy 376.285767 -10.275058) (xy 376.293887 -10.330234) (xy 376.294396 -10.35812)
			(xy 376.293887 -10.386006) (xy 376.285767 -10.441182) (xy 376.269699 -10.494589) (xy 376.246027 -10.545086)
			(xy 376.215254 -10.591599) (xy 376.178037 -10.633136) (xy 376.135169 -10.668811) (xy 376.087563 -10.697865)
			(xy 376.036234 -10.719677) (xy 375.982277 -10.733783) (xy 375.92684 -10.739883) (xy 375.871106 -10.737846)
			(xy 375.816263 -10.727716) (xy 375.763479 -10.709709) (xy 375.713879 -10.684208) (xy 375.668521 -10.651757)
			(xy 375.628372 -10.613048) (xy 375.594286 -10.568905) (xy 375.56699 -10.52027) (xy 375.547067 -10.468179)
			(xy 375.534941 -10.413742) (xy 375.53087 -10.35812) (xy 367.780824 -10.35812) (xy 367.780824 -10.954512)
			(xy 369.191284 -10.954512) (xy 369.195355 -10.89889) (xy 369.207481 -10.844453) (xy 369.227404 -10.792362)
			(xy 369.2547 -10.743727) (xy 369.288786 -10.699584) (xy 369.328935 -10.660875) (xy 369.374293 -10.628424)
			(xy 369.423893 -10.602923) (xy 369.476677 -10.584916) (xy 369.53152 -10.574786) (xy 369.587254 -10.572749)
			(xy 369.642691 -10.578849) (xy 369.696648 -10.592955) (xy 369.747977 -10.614767) (xy 369.795583 -10.643821)
			(xy 369.838451 -10.679496) (xy 369.875668 -10.721033) (xy 369.906441 -10.767546) (xy 369.930113 -10.818043)
			(xy 369.946181 -10.87145) (xy 369.954301 -10.926626) (xy 369.95481 -10.954512) (xy 369.954301 -10.982398)
			(xy 369.946181 -11.037574) (xy 369.930113 -11.090981) (xy 369.906441 -11.141478) (xy 369.875668 -11.187991)
			(xy 369.838451 -11.229528) (xy 369.795583 -11.265203) (xy 369.747977 -11.294257) (xy 369.696648 -11.316069)
			(xy 369.642691 -11.330175) (xy 369.587254 -11.336275) (xy 369.53152 -11.334238) (xy 369.476677 -11.324108)
			(xy 369.423893 -11.306101) (xy 369.374293 -11.2806) (xy 369.328935 -11.248149) (xy 369.288786 -11.20944)
			(xy 369.2547 -11.165297) (xy 369.227404 -11.116662) (xy 369.207481 -11.064571) (xy 369.195355 -11.010134)
			(xy 369.191284 -10.954512) (xy 367.780824 -10.954512) (xy 367.780824 -13.648944) (xy 367.781078 -13.654786)
			(xy 367.783364 -13.664946) (xy 367.789206 -13.676884) (xy 367.799112 -13.692124) (xy 367.808256 -13.702538)
			(xy 367.81867 -13.711682) (xy 367.830354 -13.719302) (xy 367.892699 -13.749302) (xy 368.013773 -13.816291)
			(xy 368.130252 -13.890984) (xy 368.241647 -13.973067) (xy 368.347489 -14.062195) (xy 368.387839 -14.100302)
			(xy 373.543066 -14.100302) (xy 373.547137 -14.04468) (xy 373.559263 -13.990243) (xy 373.579186 -13.938152)
			(xy 373.606482 -13.889517) (xy 373.640568 -13.845374) (xy 373.680717 -13.806665) (xy 373.726075 -13.774214)
			(xy 373.775675 -13.748713) (xy 373.828459 -13.730706) (xy 373.883302 -13.720576) (xy 373.939036 -13.718539)
			(xy 373.994473 -13.724639) (xy 374.04843 -13.738745) (xy 374.099759 -13.760557) (xy 374.147365 -13.789611)
			(xy 374.190233 -13.825286) (xy 374.22745 -13.866823) (xy 374.258223 -13.913336) (xy 374.281895 -13.963833)
			(xy 374.297963 -14.01724) (xy 374.306083 -14.072416) (xy 374.306592 -14.100302) (xy 374.306083 -14.128188)
			(xy 374.297963 -14.183364) (xy 374.281895 -14.236771) (xy 374.258223 -14.287268) (xy 374.22745 -14.333781)
			(xy 374.190233 -14.375318) (xy 374.147365 -14.410993) (xy 374.099759 -14.440047) (xy 374.04843 -14.461859)
			(xy 373.994473 -14.475965) (xy 373.939036 -14.482065) (xy 373.883302 -14.480028) (xy 373.828459 -14.469898)
			(xy 373.775675 -14.451891) (xy 373.726075 -14.42639) (xy 373.680717 -14.393939) (xy 373.640568 -14.35523)
			(xy 373.606482 -14.311087) (xy 373.579186 -14.262452) (xy 373.559263 -14.210361) (xy 373.547137 -14.155924)
			(xy 373.543066 -14.100302) (xy 368.387839 -14.100302) (xy 368.39779 -14.1097) (xy 368.444455 -14.155181)
			(xy 368.532781 -14.251005) (xy 368.615097 -14.352039) (xy 368.691097 -14.457906) (xy 368.726212 -14.512798)
			(xy 368.734086 -14.512798) (xy 368.800126 -14.639544) (xy 368.804698 -14.64818) (xy 368.804698 -14.648434)
			(xy 368.810794 -14.660118) (xy 368.840195 -14.717325) (xy 368.892876 -14.834678) (xy 368.938393 -14.954991)
			(xy 368.976579 -15.077828) (xy 369.007295 -15.202743) (xy 369.03043 -15.329281) (xy 369.038701 -15.39755)
			(xy 374.20448 -15.39755) (xy 374.20448 -15.34305) (xy 374.212236 -15.289104) (xy 374.22759 -15.23681)
			(xy 374.25023 -15.187234) (xy 374.279695 -15.141385) (xy 374.315384 -15.100195) (xy 374.356572 -15.064504)
			(xy 374.40242 -15.035038) (xy 374.451995 -15.012396) (xy 374.504288 -14.997039) (xy 374.558234 -14.989281)
			(xy 374.585484 -14.988794) (xy 374.611719 -14.989264) (xy 374.663695 -14.996457) (xy 374.714193 -15.01071)
			(xy 374.762259 -15.031752) (xy 374.806986 -15.059187) (xy 374.847529 -15.092496) (xy 374.865646 -15.111476)
			(xy 374.8659 -15.11173) (xy 374.873617 -15.119131) (xy 374.893312 -15.127394) (xy 374.904 -15.127732)
			(xy 374.991884 -15.125446) (xy 375.011442 -15.116048) (xy 375.018554 -15.107412) (xy 375.036763 -15.08626)
			(xy 375.078304 -15.048985) (xy 375.124834 -15.018164) (xy 375.175359 -14.994453) (xy 375.228801 -14.97836)
			(xy 375.284018 -14.970229) (xy 375.311924 -14.969744) (xy 375.339171 -14.970328) (xy 375.393109 -14.978086)
			(xy 375.445394 -14.993441) (xy 375.494962 -15.016081) (xy 375.540804 -15.045544) (xy 375.581986 -15.081231)
			(xy 375.61767 -15.122416) (xy 375.647131 -15.168259) (xy 375.669767 -15.217828) (xy 375.685119 -15.270115)
			(xy 375.692874 -15.324053) (xy 375.692874 -15.378547) (xy 375.685119 -15.432485) (xy 375.669767 -15.484772)
			(xy 375.647131 -15.534341) (xy 375.61767 -15.580184) (xy 375.581986 -15.621369) (xy 375.540804 -15.657056)
			(xy 375.494962 -15.686519) (xy 375.445394 -15.709159) (xy 375.393109 -15.724514) (xy 375.339171 -15.732272)
			(xy 375.311924 -15.73276) (xy 375.285688 -15.732299) (xy 375.233712 -15.725106) (xy 375.183213 -15.710853)
			(xy 375.135146 -15.689809) (xy 375.090419 -15.662372) (xy 375.049878 -15.62906) (xy 375.031762 -15.610078)
			(xy 375.031508 -15.609824) (xy 375.023794 -15.60242) (xy 375.004096 -15.59416) (xy 374.993408 -15.593822)
			(xy 374.905524 -15.596108) (xy 374.885966 -15.605506) (xy 374.878854 -15.614142) (xy 374.86063 -15.635281)
			(xy 374.819094 -15.672558) (xy 374.772567 -15.703383) (xy 374.722044 -15.727096) (xy 374.668605 -15.743191)
			(xy 374.613389 -15.751325) (xy 374.585484 -15.75181) (xy 374.558234 -15.751319) (xy 374.504288 -15.743561)
			(xy 374.451995 -15.728204) (xy 374.40242 -15.705562) (xy 374.356572 -15.676096) (xy 374.315384 -15.640405)
			(xy 374.279695 -15.599215) (xy 374.25023 -15.553366) (xy 374.22759 -15.50379) (xy 374.212236 -15.451496)
			(xy 374.20448 -15.39755) (xy 369.038701 -15.39755) (xy 369.045901 -15.456982) (xy 369.05365 -15.585384)
			(xy 369.054126 -15.649702) (xy 369.054126 -15.649956) (xy 369.05362 -15.715692) (xy 369.045527 -15.846913)
			(xy 369.02937 -15.977388) (xy 369.005213 -16.106621) (xy 368.973145 -16.234121) (xy 368.933289 -16.359405)
			(xy 368.885796 -16.481999) (xy 368.830847 -16.601436) (xy 368.768648 -16.717263) (xy 368.699438 -16.829042)
			(xy 368.623477 -16.936349) (xy 368.596403 -16.969994) (xy 388.048253 -16.969994) (xy 388.052258 -16.882086)
			(xy 388.064241 -16.794906) (xy 388.084101 -16.709177) (xy 388.111676 -16.625609) (xy 388.146735 -16.544895)
			(xy 388.188988 -16.467703) (xy 388.238086 -16.394674) (xy 388.293622 -16.326412) (xy 388.355134 -16.263482)
			(xy 388.422115 -16.206408) (xy 388.494008 -16.15566) (xy 388.570217 -16.11166) (xy 388.650112 -16.074773)
			(xy 388.733031 -16.045304) (xy 388.818286 -16.023497) (xy 388.90517 -16.009533) (xy 388.992964 -16.003527)
			(xy 389.080941 -16.005531) (xy 389.168371 -16.015526) (xy 389.25453 -16.03343) (xy 389.338704 -16.059094)
			(xy 389.420195 -16.092307) (xy 389.498329 -16.132793) (xy 389.572457 -16.180215) (xy 389.641965 -16.234182)
			(xy 389.706279 -16.294247) (xy 389.764863 -16.359911) (xy 389.817234 -16.43063) (xy 389.862957 -16.505818)
			(xy 389.901654 -16.584853) (xy 389.933003 -16.667079) (xy 389.956745 -16.751815) (xy 389.972683 -16.838359)
			(xy 389.980685 -16.925994) (xy 389.981186 -16.969994) (xy 389.980685 -17.013994) (xy 389.972683 -17.101629)
			(xy 389.956745 -17.188173) (xy 389.933003 -17.272909) (xy 389.901654 -17.355135) (xy 389.862957 -17.43417)
			(xy 389.817234 -17.509358) (xy 389.764863 -17.580077) (xy 389.706279 -17.645741) (xy 389.641965 -17.705806)
			(xy 389.572457 -17.759773) (xy 389.498329 -17.807195) (xy 389.420195 -17.847681) (xy 389.338704 -17.880894)
			(xy 389.25453 -17.906558) (xy 389.168371 -17.924462) (xy 389.080941 -17.934457) (xy 388.992964 -17.936461)
			(xy 388.90517 -17.930455) (xy 388.818286 -17.916491) (xy 388.733031 -17.894684) (xy 388.650112 -17.865215)
			(xy 388.570217 -17.828328) (xy 388.494008 -17.784328) (xy 388.422115 -17.73358) (xy 388.355134 -17.676506)
			(xy 388.293622 -17.613576) (xy 388.238086 -17.545314) (xy 388.188988 -17.472285) (xy 388.146735 -17.395093)
			(xy 388.111676 -17.314379) (xy 388.084101 -17.230811) (xy 388.064241 -17.145082) (xy 388.052258 -17.057902)
			(xy 388.048253 -16.969994) (xy 368.596403 -16.969994) (xy 368.541055 -17.038775) (xy 368.452483 -17.135934)
			(xy 368.358098 -17.227455) (xy 368.258259 -17.312993) (xy 368.153342 -17.392222) (xy 368.112064 -17.419574)
			(xy 372.584216 -17.419574) (xy 372.588287 -17.363952) (xy 372.600413 -17.309515) (xy 372.620336 -17.257424)
			(xy 372.647632 -17.208789) (xy 372.681718 -17.164646) (xy 372.721867 -17.125937) (xy 372.767225 -17.093486)
			(xy 372.816825 -17.067985) (xy 372.869609 -17.049978) (xy 372.924452 -17.039848) (xy 372.980186 -17.037811)
			(xy 373.035623 -17.043911) (xy 373.08958 -17.058017) (xy 373.140909 -17.079829) (xy 373.188515 -17.108883)
			(xy 373.231383 -17.144558) (xy 373.2686 -17.186095) (xy 373.299373 -17.232608) (xy 373.323045 -17.283105)
			(xy 373.339113 -17.336512) (xy 373.347233 -17.391688) (xy 373.347742 -17.419574) (xy 373.347233 -17.44746)
			(xy 373.339113 -17.502636) (xy 373.323045 -17.556043) (xy 373.299373 -17.60654) (xy 373.2686 -17.653053)
			(xy 373.231383 -17.69459) (xy 373.188515 -17.730265) (xy 373.140909 -17.759319) (xy 373.08958 -17.781131)
			(xy 373.035623 -17.795237) (xy 372.980186 -17.801337) (xy 372.924452 -17.7993) (xy 372.869609 -17.78917)
			(xy 372.816825 -17.771163) (xy 372.767225 -17.745662) (xy 372.721867 -17.713211) (xy 372.681718 -17.674502)
			(xy 372.647632 -17.630359) (xy 372.620336 -17.581724) (xy 372.600413 -17.529633) (xy 372.588287 -17.475196)
			(xy 372.584216 -17.419574) (xy 368.112064 -17.419574) (xy 368.043748 -17.464842) (xy 367.92989 -17.530577)
			(xy 367.812202 -17.589179) (xy 367.69113 -17.640425) (xy 367.567132 -17.68412) (xy 367.44068 -17.720099)
			(xy 367.312252 -17.748225) (xy 367.182337 -17.768391) (xy 367.051427 -17.780522) (xy 366.920018 -17.784571)
			(xy 366.788609 -17.780522) (xy 366.657699 -17.768391) (xy 366.527784 -17.748225) (xy 366.399356 -17.720099)
			(xy 366.272904 -17.68412) (xy 366.148906 -17.640425) (xy 366.027834 -17.589179) (xy 365.910146 -17.530577)
			(xy 365.796288 -17.464842) (xy 365.686694 -17.392222) (xy 365.581777 -17.312993) (xy 365.481938 -17.227455)
			(xy 365.387553 -17.135934) (xy 365.298981 -17.038775) (xy 365.216559 -16.936349) (xy 365.140598 -16.829042)
			(xy 365.071388 -16.717263) (xy 365.009189 -16.601436) (xy 364.95424 -16.481999) (xy 364.906747 -16.359405)
			(xy 364.866891 -16.234121) (xy 364.834823 -16.106621) (xy 364.810666 -15.977388) (xy 364.794509 -15.846913)
			(xy 364.786416 -15.715692) (xy 364.78591 -15.649956) (xy 364.78591 -15.649702) (xy 364.786392 -15.585384)
			(xy 364.794141 -15.456983) (xy 364.809611 -15.329281) (xy 364.832746 -15.202743) (xy 364.863461 -15.077829)
			(xy 364.901646 -14.954992) (xy 364.947161 -14.834678) (xy 364.999841 -14.717325) (xy 365.029242 -14.660118)
			(xy 365.031274 -14.656054) (xy 365.033157 -14.651126) (xy 365.035085 -14.640755) (xy 365.035084 -14.63548)
			(xy 365.034576 -14.621764) (xy 364.982506 -14.535912) (xy 364.977686 -14.528658) (xy 364.964182 -14.517679)
			(xy 364.947775 -14.511874) (xy 364.939072 -14.511528) (xy 355.303836 -14.511528) (xy 355.293784 -14.511025)
			(xy 355.275219 -14.503308) (xy 355.267768 -14.496542) (xy 354.697284 -13.926058) (xy 354.690435 -13.918661)
			(xy 354.682702 -13.900062) (xy 354.682298 -13.88999) (xy 354.682298 -2.64922) (xy 354.682127 -2.643211)
			(xy 354.679297 -2.631532) (xy 354.67671 -2.626106) (xy 354.674872 -2.622631) (xy 354.670281 -2.616249)
			(xy 354.667566 -2.613406) (xy 353.434904 -1.380744) (xy 353.432053 -1.378038) (xy 353.425676 -1.373443)
			(xy 353.422204 -1.3716) (xy 353.416776 -1.369022) (xy 353.405096 -1.366211) (xy 353.39909 -1.366012)
			(xy 330.198984 -1.366012) (xy 330.192973 -1.366175) (xy 330.181288 -1.368993) (xy 330.17587 -1.3716)
			(xy 330.172396 -1.37344) (xy 330.166018 -1.378035) (xy 330.16317 -1.380744) (xy 329.695556 -1.848358)
			(xy 329.692847 -1.851207) (xy 329.688248 -1.857582) (xy 329.686412 -1.861058) (xy 329.68383 -1.866485)
			(xy 329.681009 -1.878165) (xy 329.680824 -1.884172) (xy 329.680824 -5.776468) (xy 335.944462 -5.776468)
			(xy 335.948533 -5.720846) (xy 335.960659 -5.666409) (xy 335.980582 -5.614318) (xy 336.007878 -5.565683)
			(xy 336.041964 -5.52154) (xy 336.082113 -5.482831) (xy 336.127471 -5.45038) (xy 336.177071 -5.424879)
			(xy 336.229855 -5.406872) (xy 336.284698 -5.396742) (xy 336.340432 -5.394705) (xy 336.395869 -5.400805)
			(xy 336.449826 -5.414911) (xy 336.501155 -5.436723) (xy 336.548761 -5.465777) (xy 336.591629 -5.501452)
			(xy 336.628846 -5.542989) (xy 336.659619 -5.589502) (xy 336.683291 -5.639999) (xy 336.699359 -5.693406)
			(xy 336.707284 -5.747258) (xy 339.126066 -5.747258) (xy 339.130137 -5.691636) (xy 339.142263 -5.637199)
			(xy 339.162186 -5.585108) (xy 339.189482 -5.536473) (xy 339.223568 -5.49233) (xy 339.263717 -5.453621)
			(xy 339.309075 -5.42117) (xy 339.358675 -5.395669) (xy 339.411459 -5.377662) (xy 339.466302 -5.367532)
			(xy 339.522036 -5.365495) (xy 339.577473 -5.371595) (xy 339.63143 -5.385701) (xy 339.682759 -5.407513)
			(xy 339.730365 -5.436567) (xy 339.773233 -5.472242) (xy 339.81045 -5.513779) (xy 339.841223 -5.560292)
			(xy 339.864895 -5.610789) (xy 339.880963 -5.664196) (xy 339.889083 -5.719372) (xy 339.889592 -5.747258)
			(xy 339.889083 -5.775144) (xy 339.880963 -5.83032) (xy 339.864895 -5.883727) (xy 339.841223 -5.934224)
			(xy 339.81045 -5.980737) (xy 339.773233 -6.022274) (xy 339.730365 -6.057949) (xy 339.682759 -6.087003)
			(xy 339.63143 -6.108815) (xy 339.577473 -6.122921) (xy 339.522036 -6.129021) (xy 339.466302 -6.126984)
			(xy 339.411459 -6.116854) (xy 339.358675 -6.098847) (xy 339.309075 -6.073346) (xy 339.263717 -6.040895)
			(xy 339.223568 -6.002186) (xy 339.189482 -5.958043) (xy 339.162186 -5.909408) (xy 339.142263 -5.857317)
			(xy 339.130137 -5.80288) (xy 339.126066 -5.747258) (xy 336.707284 -5.747258) (xy 336.707479 -5.748582)
			(xy 336.707988 -5.776468) (xy 336.707479 -5.804354) (xy 336.699359 -5.85953) (xy 336.683291 -5.912937)
			(xy 336.659619 -5.963434) (xy 336.628846 -6.009947) (xy 336.591629 -6.051484) (xy 336.548761 -6.087159)
			(xy 336.501155 -6.116213) (xy 336.449826 -6.138025) (xy 336.395869 -6.152131) (xy 336.340432 -6.158231)
			(xy 336.284698 -6.156194) (xy 336.229855 -6.146064) (xy 336.177071 -6.128057) (xy 336.127471 -6.102556)
			(xy 336.082113 -6.070105) (xy 336.041964 -6.031396) (xy 336.007878 -5.987253) (xy 335.980582 -5.938618)
			(xy 335.960659 -5.886527) (xy 335.948533 -5.83209) (xy 335.944462 -5.776468) (xy 329.680824 -5.776468)
			(xy 329.680824 -6.68655) (xy 330.361288 -6.68655) (xy 330.365359 -6.630928) (xy 330.377485 -6.576491)
			(xy 330.397408 -6.5244) (xy 330.424704 -6.475765) (xy 330.45879 -6.431622) (xy 330.498939 -6.392913)
			(xy 330.544297 -6.360462) (xy 330.593897 -6.334961) (xy 330.646681 -6.316954) (xy 330.701524 -6.306824)
			(xy 330.757258 -6.304787) (xy 330.812695 -6.310887) (xy 330.866652 -6.324993) (xy 330.917981 -6.346805)
			(xy 330.965587 -6.375859) (xy 331.008455 -6.411534) (xy 331.045672 -6.453071) (xy 331.076445 -6.499584)
			(xy 331.100117 -6.550081) (xy 331.116185 -6.603488) (xy 331.124305 -6.658664) (xy 331.124814 -6.68655)
			(xy 331.124305 -6.714436) (xy 331.116185 -6.769612) (xy 331.100117 -6.823019) (xy 331.076445 -6.873516)
			(xy 331.045672 -6.920029) (xy 331.025465 -6.942582) (xy 337.010754 -6.942582) (xy 337.014825 -6.88696)
			(xy 337.026951 -6.832523) (xy 337.046874 -6.780432) (xy 337.07417 -6.731797) (xy 337.108256 -6.687654)
			(xy 337.148405 -6.648945) (xy 337.193763 -6.616494) (xy 337.243363 -6.590993) (xy 337.296147 -6.572986)
			(xy 337.35099 -6.562856) (xy 337.406724 -6.560819) (xy 337.462161 -6.566919) (xy 337.516118 -6.581025)
			(xy 337.567447 -6.602837) (xy 337.615053 -6.631891) (xy 337.657921 -6.667566) (xy 337.695138 -6.709103)
			(xy 337.715339 -6.739636) (xy 339.101936 -6.739636) (xy 339.106007 -6.684014) (xy 339.118133 -6.629577)
			(xy 339.138056 -6.577486) (xy 339.165352 -6.528851) (xy 339.199438 -6.484708) (xy 339.239587 -6.445999)
			(xy 339.284945 -6.413548) (xy 339.334545 -6.388047) (xy 339.387329 -6.37004) (xy 339.442172 -6.35991)
			(xy 339.497906 -6.357873) (xy 339.553343 -6.363973) (xy 339.6073 -6.378079) (xy 339.658629 -6.399891)
			(xy 339.706235 -6.428945) (xy 339.749103 -6.46462) (xy 339.78632 -6.506157) (xy 339.817093 -6.55267)
			(xy 339.840765 -6.603167) (xy 339.856833 -6.656574) (xy 339.864953 -6.71175) (xy 339.865462 -6.739636)
			(xy 339.864953 -6.767522) (xy 339.856833 -6.822698) (xy 339.840765 -6.876105) (xy 339.817093 -6.926602)
			(xy 339.78632 -6.973115) (xy 339.749103 -7.014652) (xy 339.706235 -7.050327) (xy 339.658629 -7.079381)
			(xy 339.6073 -7.101193) (xy 339.553343 -7.115299) (xy 339.497906 -7.121399) (xy 339.442172 -7.119362)
			(xy 339.387329 -7.109232) (xy 339.334545 -7.091225) (xy 339.284945 -7.065724) (xy 339.239587 -7.033273)
			(xy 339.199438 -6.994564) (xy 339.165352 -6.950421) (xy 339.138056 -6.901786) (xy 339.118133 -6.849695)
			(xy 339.106007 -6.795258) (xy 339.101936 -6.739636) (xy 337.715339 -6.739636) (xy 337.725911 -6.755616)
			(xy 337.749583 -6.806113) (xy 337.765651 -6.85952) (xy 337.773771 -6.914696) (xy 337.77428 -6.942582)
			(xy 337.773771 -6.970468) (xy 337.765651 -7.025644) (xy 337.749583 -7.079051) (xy 337.725911 -7.129548)
			(xy 337.695138 -7.176061) (xy 337.657921 -7.217598) (xy 337.615053 -7.253273) (xy 337.567447 -7.282327)
			(xy 337.516118 -7.304139) (xy 337.462161 -7.318245) (xy 337.406724 -7.324345) (xy 337.35099 -7.322308)
			(xy 337.296147 -7.312178) (xy 337.243363 -7.294171) (xy 337.193763 -7.26867) (xy 337.148405 -7.236219)
			(xy 337.108256 -7.19751) (xy 337.07417 -7.153367) (xy 337.046874 -7.104732) (xy 337.026951 -7.052641)
			(xy 337.014825 -6.998204) (xy 337.010754 -6.942582) (xy 331.025465 -6.942582) (xy 331.008455 -6.961566)
			(xy 330.965587 -6.997241) (xy 330.917981 -7.026295) (xy 330.866652 -7.048107) (xy 330.812695 -7.062213)
			(xy 330.757258 -7.068313) (xy 330.701524 -7.066276) (xy 330.646681 -7.056146) (xy 330.593897 -7.038139)
			(xy 330.544297 -7.012638) (xy 330.498939 -6.980187) (xy 330.45879 -6.941478) (xy 330.424704 -6.897335)
			(xy 330.397408 -6.8487) (xy 330.377485 -6.796609) (xy 330.365359 -6.742172) (xy 330.361288 -6.68655)
			(xy 329.680824 -6.68655) (xy 329.680824 -7.355078) (xy 329.68121 -7.363434) (xy 329.686658 -7.379239)
			(xy 329.691492 -7.386066) (xy 329.697588 -7.393686) (xy 329.711812 -7.402576) (xy 329.720448 -7.404608)
			(xy 329.748307 -7.411348) (xy 329.801754 -7.432052) (xy 329.851503 -7.460517) (xy 329.896434 -7.496103)
			(xy 329.935536 -7.53801) (xy 329.967931 -7.585294) (xy 329.992887 -7.636892) (xy 330.009846 -7.691643)
			(xy 330.018423 -7.748314) (xy 330.018898 -7.776972) (xy 330.018474 -7.802795) (xy 330.011521 -7.853971)
			(xy 329.997738 -7.903744) (xy 329.992192 -7.916672) (xy 330.525372 -7.916672) (xy 330.529443 -7.86105)
			(xy 330.541569 -7.806613) (xy 330.561492 -7.754522) (xy 330.588788 -7.705887) (xy 330.622874 -7.661744)
			(xy 330.663023 -7.623035) (xy 330.708381 -7.590584) (xy 330.757981 -7.565083) (xy 330.810765 -7.547076)
			(xy 330.865608 -7.536946) (xy 330.921342 -7.534909) (xy 330.976779 -7.541009) (xy 331.030736 -7.555115)
			(xy 331.082065 -7.576927) (xy 331.129671 -7.605981) (xy 331.172539 -7.641656) (xy 331.209756 -7.683193)
			(xy 331.240529 -7.729706) (xy 331.246612 -7.742682) (xy 339.120224 -7.742682) (xy 339.124295 -7.68706)
			(xy 339.136421 -7.632623) (xy 339.156344 -7.580532) (xy 339.18364 -7.531897) (xy 339.217726 -7.487754)
			(xy 339.257875 -7.449045) (xy 339.303233 -7.416594) (xy 339.352833 -7.391093) (xy 339.405617 -7.373086)
			(xy 339.46046 -7.362956) (xy 339.516194 -7.360919) (xy 339.571631 -7.367019) (xy 339.625588 -7.381125)
			(xy 339.676917 -7.402937) (xy 339.724523 -7.431991) (xy 339.767391 -7.467666) (xy 339.804608 -7.509203)
			(xy 339.835381 -7.555716) (xy 339.859053 -7.606213) (xy 339.875121 -7.65962) (xy 339.883241 -7.714796)
			(xy 339.88375 -7.742682) (xy 339.883241 -7.770568) (xy 339.875121 -7.825744) (xy 339.859053 -7.879151)
			(xy 339.835381 -7.929648) (xy 339.804608 -7.976161) (xy 339.767391 -8.017698) (xy 339.724523 -8.053373)
			(xy 339.676917 -8.082427) (xy 339.625588 -8.104239) (xy 339.571631 -8.118345) (xy 339.516194 -8.124445)
			(xy 339.46046 -8.122408) (xy 339.405617 -8.112278) (xy 339.352833 -8.094271) (xy 339.303233 -8.06877)
			(xy 339.257875 -8.036319) (xy 339.217726 -7.99761) (xy 339.18364 -7.953467) (xy 339.156344 -7.904832)
			(xy 339.136421 -7.852741) (xy 339.124295 -7.798304) (xy 339.120224 -7.742682) (xy 331.246612 -7.742682)
			(xy 331.264201 -7.780203) (xy 331.280269 -7.83361) (xy 331.288389 -7.888786) (xy 331.288898 -7.916672)
			(xy 331.288389 -7.944558) (xy 331.280269 -7.999734) (xy 331.264201 -8.053141) (xy 331.240529 -8.103638)
			(xy 331.209756 -8.150151) (xy 331.172539 -8.191688) (xy 331.129671 -8.227363) (xy 331.082065 -8.256417)
			(xy 331.079159 -8.257652) (xy 336.93174 -8.257652) (xy 336.93174 -8.203148) (xy 336.939496 -8.149198)
			(xy 336.954851 -8.096901) (xy 336.977491 -8.047321) (xy 337.006957 -8.001468) (xy 337.042648 -7.960275)
			(xy 337.083838 -7.92458) (xy 337.129688 -7.89511) (xy 337.179265 -7.872464) (xy 337.231561 -7.857104)
			(xy 337.28551 -7.849342) (xy 337.312762 -7.848854) (xy 337.340914 -7.849367) (xy 337.396609 -7.857623)
			(xy 337.450485 -7.873978) (xy 337.501372 -7.898075) (xy 337.548163 -7.929391) (xy 337.589843 -7.967245)
			(xy 337.625504 -8.010815) (xy 337.654374 -8.059155) (xy 337.675823 -8.111213) (xy 337.683094 -8.138414)
			(xy 337.687124 -8.152573) (xy 337.702124 -8.177891) (xy 337.723719 -8.197883) (xy 337.750117 -8.210889)
			(xy 337.779127 -8.215831) (xy 337.808343 -8.212299) (xy 337.835339 -8.200585) (xy 337.846924 -8.1915)
			(xy 337.867602 -8.174655) (xy 337.912819 -8.146369) (xy 337.961536 -8.12466) (xy 338.012804 -8.109952)
			(xy 338.06562 -8.102531) (xy 338.092288 -8.102092) (xy 338.092542 -8.102092) (xy 338.119791 -8.102581)
			(xy 338.173734 -8.110342) (xy 338.226024 -8.125701) (xy 338.275596 -8.148344) (xy 338.321441 -8.177812)
			(xy 338.362626 -8.213503) (xy 338.398313 -8.254692) (xy 338.427776 -8.300541) (xy 338.450414 -8.350115)
			(xy 338.465767 -8.402407) (xy 338.473522 -8.456351) (xy 338.473522 -8.510849) (xy 338.465767 -8.564793)
			(xy 338.450414 -8.617085) (xy 338.427776 -8.666659) (xy 338.398313 -8.712508) (xy 338.362626 -8.753697)
			(xy 338.321441 -8.789388) (xy 338.275596 -8.818856) (xy 338.226024 -8.841499) (xy 338.173734 -8.856858)
			(xy 338.119791 -8.864619) (xy 338.092542 -8.865108) (xy 338.064389 -8.864621) (xy 338.008691 -8.856363)
			(xy 337.954813 -8.840007) (xy 337.903924 -8.815908) (xy 337.857132 -8.784589) (xy 337.815453 -8.746731)
			(xy 337.779792 -8.703157) (xy 337.750925 -8.654813) (xy 337.729479 -8.602751) (xy 337.72221 -8.575548)
			(xy 337.718189 -8.561387) (xy 337.703183 -8.536074) (xy 337.681585 -8.516087) (xy 337.655187 -8.503084)
			(xy 337.626178 -8.498142) (xy 337.596964 -8.501671) (xy 337.569966 -8.51338) (xy 337.55838 -8.522462)
			(xy 337.537696 -8.539299) (xy 337.492481 -8.567588) (xy 337.443766 -8.589299) (xy 337.392499 -8.604009)
			(xy 337.339683 -8.61143) (xy 337.313016 -8.61187) (xy 337.312762 -8.61187) (xy 337.28551 -8.611458)
			(xy 337.231561 -8.603696) (xy 337.179265 -8.588336) (xy 337.129688 -8.56569) (xy 337.083838 -8.53622)
			(xy 337.042648 -8.500525) (xy 337.006957 -8.459332) (xy 336.977491 -8.413479) (xy 336.954851 -8.363899)
			(xy 336.939496 -8.311602) (xy 336.93174 -8.257652) (xy 331.079159 -8.257652) (xy 331.030736 -8.278229)
			(xy 330.976779 -8.292335) (xy 330.921342 -8.298435) (xy 330.865608 -8.296398) (xy 330.810765 -8.286268)
			(xy 330.757981 -8.268261) (xy 330.708381 -8.24276) (xy 330.663023 -8.210309) (xy 330.622874 -8.1716)
			(xy 330.588788 -8.127457) (xy 330.561492 -8.078822) (xy 330.541569 -8.026731) (xy 330.529443 -7.972294)
			(xy 330.525372 -7.916672) (xy 329.992192 -7.916672) (xy 329.977376 -7.951207) (xy 329.950807 -7.995494)
			(xy 329.918514 -8.0358) (xy 329.881087 -8.071388) (xy 329.860402 -8.086852) (xy 329.855576 -8.090408)
			(xy 329.847956 -8.09879) (xy 329.833478 -8.125968) (xy 329.831367 -8.130916) (xy 329.829059 -8.141419)
			(xy 329.828906 -8.146796) (xy 329.828906 -8.20674) (xy 329.830684 -8.219694) (xy 329.834748 -8.230362)
			(xy 329.839828 -8.23976) (xy 329.847956 -8.255) (xy 329.85583 -8.26389) (xy 329.860402 -8.267192)
			(xy 329.881087 -8.282655) (xy 329.918503 -8.318253) (xy 329.950787 -8.358562) (xy 329.977353 -8.402849)
			(xy 329.997717 -8.450309) (xy 330.011508 -8.500078) (xy 330.018476 -8.55125) (xy 330.018898 -8.577072)
			(xy 330.018385 -8.60573) (xy 330.009815 -8.6624) (xy 329.992864 -8.717152) (xy 329.967914 -8.768751)
			(xy 329.935525 -8.816037) (xy 329.896427 -8.857946) (xy 329.851499 -8.893535) (xy 329.801754 -8.922002)
			(xy 329.748309 -8.942707) (xy 329.720448 -8.949436) (xy 329.711812 -8.951468) (xy 329.697588 -8.960358)
			(xy 329.691492 -8.967978) (xy 329.686571 -8.974761) (xy 329.681103 -8.990592) (xy 329.680824 -8.998966)
			(xy 329.680824 -9.535922) (xy 332.574644 -9.535922) (xy 332.578715 -9.4803) (xy 332.590841 -9.425863)
			(xy 332.610764 -9.373772) (xy 332.63806 -9.325137) (xy 332.672146 -9.280994) (xy 332.712295 -9.242285)
			(xy 332.757653 -9.209834) (xy 332.807253 -9.184333) (xy 332.860037 -9.166326) (xy 332.91488 -9.156196)
			(xy 332.970614 -9.154159) (xy 333.026051 -9.160259) (xy 333.080008 -9.174365) (xy 333.131337 -9.196177)
			(xy 333.178943 -9.225231) (xy 333.221811 -9.260906) (xy 333.259028 -9.302443) (xy 333.289801 -9.348956)
			(xy 333.313473 -9.399453) (xy 333.329541 -9.45286) (xy 333.337661 -9.508036) (xy 333.33811 -9.53262)
			(xy 335.622644 -9.53262) (xy 335.626715 -9.476998) (xy 335.638841 -9.422561) (xy 335.658764 -9.37047)
			(xy 335.68606 -9.321835) (xy 335.720146 -9.277692) (xy 335.760295 -9.238983) (xy 335.805653 -9.206532)
			(xy 335.855253 -9.181031) (xy 335.908037 -9.163024) (xy 335.96288 -9.152894) (xy 336.018614 -9.150857)
			(xy 336.074051 -9.156957) (xy 336.128008 -9.171063) (xy 336.179337 -9.192875) (xy 336.226943 -9.221929)
			(xy 336.269811 -9.257604) (xy 336.307028 -9.299141) (xy 336.337801 -9.345654) (xy 336.361473 -9.396151)
			(xy 336.377541 -9.449558) (xy 336.385661 -9.504734) (xy 336.38617 -9.53262) (xy 336.385661 -9.560506)
			(xy 336.377541 -9.615682) (xy 336.361473 -9.669089) (xy 336.337801 -9.719586) (xy 336.307028 -9.766099)
			(xy 336.269811 -9.807636) (xy 336.226943 -9.843311) (xy 336.179337 -9.872365) (xy 336.128008 -9.894177)
			(xy 336.074051 -9.908283) (xy 336.018614 -9.914383) (xy 335.96288 -9.912346) (xy 335.908037 -9.902216)
			(xy 335.855253 -9.884209) (xy 335.805653 -9.858708) (xy 335.760295 -9.826257) (xy 335.720146 -9.787548)
			(xy 335.68606 -9.743405) (xy 335.658764 -9.69477) (xy 335.638841 -9.642679) (xy 335.626715 -9.588242)
			(xy 335.622644 -9.53262) (xy 333.33811 -9.53262) (xy 333.33817 -9.535922) (xy 333.337661 -9.563808)
			(xy 333.329541 -9.618984) (xy 333.313473 -9.672391) (xy 333.289801 -9.722888) (xy 333.259028 -9.769401)
			(xy 333.221811 -9.810938) (xy 333.178943 -9.846613) (xy 333.131337 -9.875667) (xy 333.080008 -9.897479)
			(xy 333.026051 -9.911585) (xy 332.970614 -9.917685) (xy 332.91488 -9.915648) (xy 332.860037 -9.905518)
			(xy 332.807253 -9.887511) (xy 332.757653 -9.86201) (xy 332.712295 -9.829559) (xy 332.672146 -9.79085)
			(xy 332.63806 -9.746707) (xy 332.610764 -9.698072) (xy 332.590841 -9.645981) (xy 332.578715 -9.591544)
			(xy 332.574644 -9.535922) (xy 329.680824 -9.535922) (xy 329.680824 -11.543792) (xy 333.59928 -11.543792)
			(xy 333.603351 -11.48817) (xy 333.615477 -11.433733) (xy 333.6354 -11.381642) (xy 333.662696 -11.333007)
			(xy 333.696782 -11.288864) (xy 333.736931 -11.250155) (xy 333.782289 -11.217704) (xy 333.831889 -11.192203)
			(xy 333.884673 -11.174196) (xy 333.939516 -11.164066) (xy 333.99525 -11.162029) (xy 334.050687 -11.168129)
			(xy 334.104644 -11.182235) (xy 334.155973 -11.204047) (xy 334.203579 -11.233101) (xy 334.246447 -11.268776)
			(xy 334.283664 -11.310313) (xy 334.314437 -11.356826) (xy 334.338109 -11.407323) (xy 334.354177 -11.46073)
			(xy 334.362297 -11.515906) (xy 334.362806 -11.543792) (xy 334.608168 -11.543792) (xy 334.612239 -11.48817)
			(xy 334.624365 -11.433733) (xy 334.644288 -11.381642) (xy 334.671584 -11.333007) (xy 334.70567 -11.288864)
			(xy 334.745819 -11.250155) (xy 334.791177 -11.217704) (xy 334.840777 -11.192203) (xy 334.893561 -11.174196)
			(xy 334.948404 -11.164066) (xy 335.004138 -11.162029) (xy 335.059575 -11.168129) (xy 335.113532 -11.182235)
			(xy 335.164861 -11.204047) (xy 335.212467 -11.233101) (xy 335.255335 -11.268776) (xy 335.292552 -11.310313)
			(xy 335.323325 -11.356826) (xy 335.346997 -11.407323) (xy 335.363065 -11.46073) (xy 335.371185 -11.515906)
			(xy 335.371694 -11.543792) (xy 335.371185 -11.571678) (xy 335.363065 -11.626854) (xy 335.346997 -11.680261)
			(xy 335.323325 -11.730758) (xy 335.292552 -11.777271) (xy 335.255335 -11.818808) (xy 335.212467 -11.854483)
			(xy 335.164861 -11.883537) (xy 335.113532 -11.905349) (xy 335.059575 -11.919455) (xy 335.004138 -11.925555)
			(xy 334.948404 -11.923518) (xy 334.893561 -11.913388) (xy 334.840777 -11.895381) (xy 334.791177 -11.86988)
			(xy 334.745819 -11.837429) (xy 334.70567 -11.79872) (xy 334.671584 -11.754577) (xy 334.644288 -11.705942)
			(xy 334.624365 -11.653851) (xy 334.612239 -11.599414) (xy 334.608168 -11.543792) (xy 334.362806 -11.543792)
			(xy 334.362297 -11.571678) (xy 334.354177 -11.626854) (xy 334.338109 -11.680261) (xy 334.314437 -11.730758)
			(xy 334.283664 -11.777271) (xy 334.246447 -11.818808) (xy 334.203579 -11.854483) (xy 334.155973 -11.883537)
			(xy 334.104644 -11.905349) (xy 334.050687 -11.919455) (xy 333.99525 -11.925555) (xy 333.939516 -11.923518)
			(xy 333.884673 -11.913388) (xy 333.831889 -11.895381) (xy 333.782289 -11.86988) (xy 333.736931 -11.837429)
			(xy 333.696782 -11.79872) (xy 333.662696 -11.754577) (xy 333.6354 -11.705942) (xy 333.615477 -11.653851)
			(xy 333.603351 -11.599414) (xy 333.59928 -11.543792) (xy 329.680824 -11.543792) (xy 329.680824 -13.649198)
			(xy 329.681056 -13.656468) (xy 329.685188 -13.670406) (xy 329.688952 -13.67663) (xy 329.706478 -13.704316)
			(xy 329.717146 -13.71346) (xy 329.72375 -13.716508) (xy 329.780794 -13.743684) (xy 329.891909 -13.803874)
			(xy 329.999268 -13.870533) (xy 330.102493 -13.943429) (xy 330.201224 -14.022307) (xy 330.295113 -14.106889)
			(xy 330.383833 -14.196879) (xy 330.467071 -14.291962) (xy 330.544536 -14.391805) (xy 330.615957 -14.496057)
			(xy 330.681083 -14.604352) (xy 330.710794 -14.660118) (xy 330.713334 -14.665198) (xy 330.716636 -14.671548)
			(xy 330.745264 -14.72805) (xy 330.796559 -14.843878) (xy 330.840893 -14.962545) (xy 330.87811 -15.083634)
			(xy 330.908077 -15.206716) (xy 330.930691 -15.33136) (xy 330.94587 -15.457125) (xy 330.953562 -15.58357)
			(xy 330.954126 -15.646908) (xy 330.954126 -15.665958) (xy 330.953139 -15.731376) (xy 330.944143 -15.861914)
			(xy 330.927167 -15.991656) (xy 330.902273 -16.120113) (xy 330.869556 -16.246804) (xy 330.829139 -16.371253)
			(xy 330.781172 -16.492992) (xy 330.725837 -16.611563) (xy 330.663342 -16.726521) (xy 330.593921 -16.837434)
			(xy 330.517835 -16.943886) (xy 330.496642 -16.969994) (xy 362.048305 -16.969994) (xy 362.05231 -16.882086)
			(xy 362.064293 -16.794906) (xy 362.084153 -16.709177) (xy 362.111728 -16.625609) (xy 362.146787 -16.544895)
			(xy 362.18904 -16.467703) (xy 362.238138 -16.394674) (xy 362.293674 -16.326412) (xy 362.355186 -16.263482)
			(xy 362.422167 -16.206408) (xy 362.49406 -16.15566) (xy 362.570269 -16.11166) (xy 362.650164 -16.074773)
			(xy 362.733083 -16.045304) (xy 362.818338 -16.023497) (xy 362.905222 -16.009533) (xy 362.993016 -16.003527)
			(xy 363.080993 -16.005531) (xy 363.168423 -16.015526) (xy 363.254582 -16.03343) (xy 363.338756 -16.059094)
			(xy 363.420247 -16.092307) (xy 363.498381 -16.132793) (xy 363.572509 -16.180215) (xy 363.642017 -16.234182)
			(xy 363.706331 -16.294247) (xy 363.764915 -16.359911) (xy 363.817286 -16.43063) (xy 363.863009 -16.505818)
			(xy 363.901706 -16.584853) (xy 363.933055 -16.667079) (xy 363.956797 -16.751815) (xy 363.972735 -16.838359)
			(xy 363.980737 -16.925994) (xy 363.981238 -16.969994) (xy 363.980737 -17.013994) (xy 363.972735 -17.101629)
			(xy 363.956797 -17.188173) (xy 363.933055 -17.272909) (xy 363.901706 -17.355135) (xy 363.863009 -17.43417)
			(xy 363.817286 -17.509358) (xy 363.764915 -17.580077) (xy 363.706331 -17.645741) (xy 363.642017 -17.705806)
			(xy 363.572509 -17.759773) (xy 363.498381 -17.807195) (xy 363.420247 -17.847681) (xy 363.338756 -17.880894)
			(xy 363.254582 -17.906558) (xy 363.168423 -17.924462) (xy 363.080993 -17.934457) (xy 362.993016 -17.936461)
			(xy 362.905222 -17.930455) (xy 362.818338 -17.916491) (xy 362.733083 -17.894684) (xy 362.650164 -17.865215)
			(xy 362.570269 -17.828328) (xy 362.49406 -17.784328) (xy 362.422167 -17.73358) (xy 362.355186 -17.676506)
			(xy 362.293674 -17.613576) (xy 362.238138 -17.545314) (xy 362.18904 -17.472285) (xy 362.146787 -17.395093)
			(xy 362.111728 -17.314379) (xy 362.084153 -17.230811) (xy 362.064293 -17.145082) (xy 362.05231 -17.057902)
			(xy 362.048305 -16.969994) (xy 330.496642 -16.969994) (xy 330.435369 -17.045476) (xy 330.346835 -17.141823)
			(xy 330.252564 -17.232564) (xy 330.15291 -17.317359) (xy 330.048249 -17.39589) (xy 329.938972 -17.46786)
			(xy 329.825492 -17.533001) (xy 329.708234 -17.591066) (xy 329.587638 -17.641838) (xy 329.464159 -17.685126)
			(xy 329.338259 -17.720768) (xy 329.210412 -17.748629) (xy 329.081099 -17.768605) (xy 328.950804 -17.78062)
			(xy 328.820018 -17.78463) (xy 328.689232 -17.78062) (xy 328.558937 -17.768605) (xy 328.429624 -17.748629)
			(xy 328.301777 -17.720768) (xy 328.175877 -17.685126) (xy 328.052398 -17.641838) (xy 327.931802 -17.591066)
			(xy 327.814544 -17.533001) (xy 327.701064 -17.46786) (xy 327.591787 -17.39589) (xy 327.487126 -17.317359)
			(xy 327.387472 -17.232564) (xy 327.293201 -17.141823) (xy 327.204667 -17.045476) (xy 327.122201 -16.943886)
			(xy 327.046115 -16.837434) (xy 326.976694 -16.726521) (xy 326.914199 -16.611563) (xy 326.858864 -16.492992)
			(xy 326.810897 -16.371253) (xy 326.77048 -16.246804) (xy 326.737763 -16.120113) (xy 326.712869 -15.991656)
			(xy 326.695893 -15.861914) (xy 326.686897 -15.731376) (xy 326.68591 -15.665958) (xy 326.68591 -15.649702)
			(xy 326.686401 -15.585401) (xy 326.694164 -15.457032) (xy 326.709644 -15.329365) (xy 326.732785 -15.202861)
			(xy 326.763503 -15.07798) (xy 326.801686 -14.955177) (xy 326.847195 -14.834895) (xy 326.899866 -14.717573)
			(xy 326.929242 -14.660372) (xy 326.930766 -14.657324) (xy 326.93291 -14.652127) (xy 326.9351 -14.641102)
			(xy 326.935084 -14.63548) (xy 326.934576 -14.622018) (xy 326.91832 -14.595094) (xy 326.91832 -14.594586)
			(xy 326.882252 -14.535658) (xy 326.878697 -14.530155) (xy 326.869308 -14.521026) (xy 326.86371 -14.517624)
			(xy 326.858376 -14.51483) (xy 326.850248 -14.512798) (xy 326.839326 -14.511528) (xy 317.278004 -14.511528)
			(xy 317.267933 -14.511106) (xy 317.249325 -14.503396) (xy 317.241936 -14.496542) (xy 316.527942 -13.782548)
			(xy 316.521099 -13.775149) (xy 316.513377 -13.75655) (xy 316.512956 -13.74648) (xy 316.512956 -1.941576)
			(xy 316.512793 -1.935565) (xy 316.509977 -1.923879) (xy 316.507368 -1.918462) (xy 316.505526 -1.914989)
			(xy 316.500929 -1.908614) (xy 316.498224 -1.905762) (xy 315.973206 -1.380744) (xy 315.970355 -1.378037)
			(xy 315.963978 -1.373443) (xy 315.960506 -1.3716) (xy 315.955078 -1.369022) (xy 315.943398 -1.36621)
			(xy 315.937392 -1.366012) (xy 304.199036 -1.366012) (xy 304.193027 -1.366181) (xy 304.181346 -1.369008)
			(xy 304.175922 -1.3716) (xy 304.172446 -1.373437) (xy 304.166064 -1.378027) (xy 304.163222 -1.380744)
			(xy 303.695608 -1.848358) (xy 303.692901 -1.851208) (xy 303.688306 -1.857586) (xy 303.686464 -1.861058)
			(xy 303.68388 -1.866485) (xy 303.681056 -1.878164) (xy 303.680876 -1.884172) (xy 303.680876 -13.649198)
			(xy 303.681108 -13.656467) (xy 303.685245 -13.670404) (xy 303.689004 -13.67663) (xy 303.70653 -13.704316)
			(xy 303.717198 -13.71346) (xy 303.723802 -13.716508) (xy 303.780845 -13.743686) (xy 303.891958 -13.803877)
			(xy 303.999315 -13.870538) (xy 304.102538 -13.943436) (xy 304.201267 -14.022314) (xy 304.287833 -14.100302)
			(xy 309.442864 -14.100302) (xy 309.446935 -14.04468) (xy 309.459061 -13.990243) (xy 309.478984 -13.938152)
			(xy 309.50628 -13.889517) (xy 309.540366 -13.845374) (xy 309.580515 -13.806665) (xy 309.625873 -13.774214)
			(xy 309.675473 -13.748713) (xy 309.728257 -13.730706) (xy 309.7831 -13.720576) (xy 309.838834 -13.718539)
			(xy 309.894271 -13.724639) (xy 309.948228 -13.738745) (xy 309.999557 -13.760557) (xy 310.047163 -13.789611)
			(xy 310.090031 -13.825286) (xy 310.127248 -13.866823) (xy 310.158021 -13.913336) (xy 310.181693 -13.963833)
			(xy 310.197761 -14.01724) (xy 310.205881 -14.072416) (xy 310.20639 -14.100302) (xy 310.205881 -14.128188)
			(xy 310.197761 -14.183364) (xy 310.181693 -14.236771) (xy 310.158021 -14.287268) (xy 310.127248 -14.333781)
			(xy 310.090031 -14.375318) (xy 310.047163 -14.410993) (xy 309.999557 -14.440047) (xy 309.948228 -14.461859)
			(xy 309.894271 -14.475965) (xy 309.838834 -14.482065) (xy 309.7831 -14.480028) (xy 309.728257 -14.469898)
			(xy 309.675473 -14.451891) (xy 309.625873 -14.42639) (xy 309.580515 -14.393939) (xy 309.540366 -14.35523)
			(xy 309.50628 -14.311087) (xy 309.478984 -14.262452) (xy 309.459061 -14.210361) (xy 309.446935 -14.155924)
			(xy 309.442864 -14.100302) (xy 304.287833 -14.100302) (xy 304.295154 -14.106898) (xy 304.383872 -14.196889)
			(xy 304.467108 -14.291973) (xy 304.544571 -14.391815) (xy 304.61599 -14.496068) (xy 304.681114 -14.604364)
			(xy 304.710846 -14.660118) (xy 304.713386 -14.665198) (xy 304.716688 -14.671548) (xy 304.745315 -14.728051)
			(xy 304.796609 -14.843879) (xy 304.840942 -14.962546) (xy 304.878158 -15.083634) (xy 304.908125 -15.206717)
			(xy 304.930738 -15.33136) (xy 304.938727 -15.39755) (xy 310.10428 -15.39755) (xy 310.10428 -15.34305)
			(xy 310.112036 -15.289104) (xy 310.12739 -15.236811) (xy 310.15003 -15.187235) (xy 310.179494 -15.141386)
			(xy 310.215183 -15.100196) (xy 310.256371 -15.064505) (xy 310.302219 -15.035038) (xy 310.351794 -15.012396)
			(xy 310.404086 -14.99704) (xy 310.458032 -14.989281) (xy 310.485282 -14.988794) (xy 310.511517 -14.989266)
			(xy 310.563493 -14.996458) (xy 310.613991 -15.01071) (xy 310.662057 -15.031752) (xy 310.706784 -15.059187)
			(xy 310.747327 -15.092496) (xy 310.765444 -15.111476) (xy 310.765698 -15.11173) (xy 310.773416 -15.11913)
			(xy 310.79311 -15.127394) (xy 310.803798 -15.127732) (xy 310.891682 -15.125446) (xy 310.91124 -15.116048)
			(xy 310.918352 -15.107412) (xy 310.936563 -15.086261) (xy 310.978103 -15.048986) (xy 311.024632 -15.018164)
			(xy 311.075158 -14.994454) (xy 311.128599 -14.978361) (xy 311.183816 -14.970229) (xy 311.211722 -14.969744)
			(xy 311.238969 -14.970328) (xy 311.292907 -14.978086) (xy 311.345193 -14.993441) (xy 311.394761 -15.01608)
			(xy 311.440603 -15.045543) (xy 311.481785 -15.08123) (xy 311.51747 -15.122415) (xy 311.54693 -15.168258)
			(xy 311.569567 -15.217828) (xy 311.584919 -15.270114) (xy 311.592674 -15.324053) (xy 311.592674 -15.378547)
			(xy 311.584919 -15.432486) (xy 311.569567 -15.484772) (xy 311.54693 -15.534342) (xy 311.51747 -15.580185)
			(xy 311.481785 -15.62137) (xy 311.440603 -15.657057) (xy 311.394761 -15.68652) (xy 311.345193 -15.709159)
			(xy 311.292907 -15.724514) (xy 311.238969 -15.732272) (xy 311.211722 -15.73276) (xy 311.185486 -15.7323)
			(xy 311.13351 -15.725107) (xy 311.083011 -15.710854) (xy 311.034944 -15.68981) (xy 310.990217 -15.662372)
			(xy 310.949676 -15.62906) (xy 310.93156 -15.610078) (xy 310.931306 -15.609824) (xy 310.923593 -15.602419)
			(xy 310.903894 -15.59416) (xy 310.893206 -15.593822) (xy 310.805322 -15.596108) (xy 310.785764 -15.605506)
			(xy 310.778652 -15.614142) (xy 310.760429 -15.635282) (xy 310.718892 -15.672559) (xy 310.672366 -15.703384)
			(xy 310.621843 -15.727097) (xy 310.568403 -15.743192) (xy 310.513188 -15.751325) (xy 310.485282 -15.75181)
			(xy 310.458032 -15.751319) (xy 310.404086 -15.74356) (xy 310.351794 -15.728204) (xy 310.302219 -15.705562)
			(xy 310.256371 -15.676095) (xy 310.215183 -15.640404) (xy 310.179494 -15.599214) (xy 310.15003 -15.553365)
			(xy 310.12739 -15.503789) (xy 310.112036 -15.451496) (xy 310.10428 -15.39755) (xy 304.938727 -15.39755)
			(xy 304.945917 -15.457125) (xy 304.953609 -15.58357) (xy 304.954178 -15.646908) (xy 304.954178 -15.665958)
			(xy 304.953191 -15.731376) (xy 304.944195 -15.861914) (xy 304.927219 -15.991656) (xy 304.902325 -16.120113)
			(xy 304.869608 -16.246804) (xy 304.829191 -16.371253) (xy 304.781224 -16.492992) (xy 304.725889 -16.611563)
			(xy 304.663394 -16.726521) (xy 304.593973 -16.837434) (xy 304.517887 -16.943886) (xy 304.496694 -16.969994)
			(xy 323.948051 -16.969994) (xy 323.952056 -16.882086) (xy 323.964039 -16.794906) (xy 323.983899 -16.709177)
			(xy 324.011474 -16.625609) (xy 324.046533 -16.544895) (xy 324.088786 -16.467703) (xy 324.137884 -16.394674)
			(xy 324.19342 -16.326412) (xy 324.254932 -16.263482) (xy 324.321913 -16.206408) (xy 324.393806 -16.15566)
			(xy 324.470015 -16.11166) (xy 324.54991 -16.074773) (xy 324.632829 -16.045304) (xy 324.718084 -16.023497)
			(xy 324.804968 -16.009533) (xy 324.892762 -16.003527) (xy 324.980739 -16.005531) (xy 325.068169 -16.015526)
			(xy 325.154328 -16.03343) (xy 325.238502 -16.059094) (xy 325.319993 -16.092307) (xy 325.398127 -16.132793)
			(xy 325.472255 -16.180215) (xy 325.541763 -16.234182) (xy 325.606077 -16.294247) (xy 325.664661 -16.359911)
			(xy 325.717032 -16.43063) (xy 325.762755 -16.505818) (xy 325.801452 -16.584853) (xy 325.832801 -16.667079)
			(xy 325.856543 -16.751815) (xy 325.872481 -16.838359) (xy 325.880483 -16.925994) (xy 325.880984 -16.969994)
			(xy 325.880483 -17.013994) (xy 325.872481 -17.101629) (xy 325.856543 -17.188173) (xy 325.832801 -17.272909)
			(xy 325.801452 -17.355135) (xy 325.762755 -17.43417) (xy 325.717032 -17.509358) (xy 325.664661 -17.580077)
			(xy 325.606077 -17.645741) (xy 325.541763 -17.705806) (xy 325.472255 -17.759773) (xy 325.398127 -17.807195)
			(xy 325.319993 -17.847681) (xy 325.238502 -17.880894) (xy 325.154328 -17.906558) (xy 325.068169 -17.924462)
			(xy 324.980739 -17.934457) (xy 324.892762 -17.936461) (xy 324.804968 -17.930455) (xy 324.718084 -17.916491)
			(xy 324.632829 -17.894684) (xy 324.54991 -17.865215) (xy 324.470015 -17.828328) (xy 324.393806 -17.784328)
			(xy 324.321913 -17.73358) (xy 324.254932 -17.676506) (xy 324.19342 -17.613576) (xy 324.137884 -17.545314)
			(xy 324.088786 -17.472285) (xy 324.046533 -17.395093) (xy 324.011474 -17.314379) (xy 323.983899 -17.230811)
			(xy 323.964039 -17.145082) (xy 323.952056 -17.057902) (xy 323.948051 -16.969994) (xy 304.496694 -16.969994)
			(xy 304.435421 -17.045476) (xy 304.346887 -17.141823) (xy 304.252616 -17.232564) (xy 304.152962 -17.317359)
			(xy 304.048301 -17.39589) (xy 304.01234 -17.419574) (xy 308.484014 -17.419574) (xy 308.488085 -17.363952)
			(xy 308.500211 -17.309515) (xy 308.520134 -17.257424) (xy 308.54743 -17.208789) (xy 308.581516 -17.164646)
			(xy 308.621665 -17.125937) (xy 308.667023 -17.093486) (xy 308.716623 -17.067985) (xy 308.769407 -17.049978)
			(xy 308.82425 -17.039848) (xy 308.879984 -17.037811) (xy 308.935421 -17.043911) (xy 308.989378 -17.058017)
			(xy 309.040707 -17.079829) (xy 309.088313 -17.108883) (xy 309.131181 -17.144558) (xy 309.168398 -17.186095)
			(xy 309.199171 -17.232608) (xy 309.222843 -17.283105) (xy 309.238911 -17.336512) (xy 309.247031 -17.391688)
			(xy 309.24754 -17.419574) (xy 309.247031 -17.44746) (xy 309.238911 -17.502636) (xy 309.222843 -17.556043)
			(xy 309.199171 -17.60654) (xy 309.168398 -17.653053) (xy 309.131181 -17.69459) (xy 309.088313 -17.730265)
			(xy 309.040707 -17.759319) (xy 308.989378 -17.781131) (xy 308.935421 -17.795237) (xy 308.879984 -17.801337)
			(xy 308.82425 -17.7993) (xy 308.769407 -17.78917) (xy 308.716623 -17.771163) (xy 308.667023 -17.745662)
			(xy 308.621665 -17.713211) (xy 308.581516 -17.674502) (xy 308.54743 -17.630359) (xy 308.520134 -17.581724)
			(xy 308.500211 -17.529633) (xy 308.488085 -17.475196) (xy 308.484014 -17.419574) (xy 304.01234 -17.419574)
			(xy 303.939024 -17.46786) (xy 303.825544 -17.533001) (xy 303.708286 -17.591066) (xy 303.58769 -17.641838)
			(xy 303.464211 -17.685126) (xy 303.338311 -17.720768) (xy 303.210464 -17.748629) (xy 303.081151 -17.768605)
			(xy 302.950856 -17.78062) (xy 302.82007 -17.78463) (xy 302.689284 -17.78062) (xy 302.558989 -17.768605)
			(xy 302.429676 -17.748629) (xy 302.301829 -17.720768) (xy 302.175929 -17.685126) (xy 302.05245 -17.641838)
			(xy 301.931854 -17.591066) (xy 301.814596 -17.533001) (xy 301.701116 -17.46786) (xy 301.591839 -17.39589)
			(xy 301.487178 -17.317359) (xy 301.387524 -17.232564) (xy 301.293253 -17.141823) (xy 301.204719 -17.045476)
			(xy 301.122253 -16.943886) (xy 301.046167 -16.837434) (xy 300.976746 -16.726521) (xy 300.914251 -16.611563)
			(xy 300.858916 -16.492992) (xy 300.810949 -16.371253) (xy 300.770532 -16.246804) (xy 300.737815 -16.120113)
			(xy 300.712921 -15.991656) (xy 300.695945 -15.861914) (xy 300.686949 -15.731376) (xy 300.685962 -15.665958)
			(xy 300.685962 -15.649702) (xy 300.686453 -15.585401) (xy 300.694216 -15.457032) (xy 300.709696 -15.329364)
			(xy 300.732836 -15.20286) (xy 300.763553 -15.07798) (xy 300.801735 -14.955175) (xy 300.847244 -14.834894)
			(xy 300.899914 -14.717571) (xy 300.929294 -14.660372) (xy 300.930818 -14.657324) (xy 300.93296 -14.652126)
			(xy 300.935147 -14.641101) (xy 300.935136 -14.63548) (xy 300.934628 -14.622018) (xy 300.918372 -14.595094)
			(xy 300.918372 -14.594586) (xy 300.882304 -14.535658) (xy 300.878752 -14.530152) (xy 300.869368 -14.521015)
			(xy 300.863762 -14.517624) (xy 300.858428 -14.51483) (xy 300.8503 -14.512798) (xy 300.839378 -14.511528)
			(xy 291.27831 -14.511528) (xy 291.268238 -14.511107) (xy 291.249629 -14.503399) (xy 291.242242 -14.496542)
			(xy 290.527994 -13.782294) (xy 290.521149 -13.774895) (xy 290.513418 -13.756297) (xy 290.513008 -13.746226)
			(xy 290.513008 -1.941322) (xy 290.512671 -1.932719) (xy 290.506957 -1.91649) (xy 290.501832 -1.909572)
			(xy 290.501324 -1.909064) (xy 290.498276 -1.905508) (xy 289.973258 -1.38049) (xy 289.969527 -1.37697)
			(xy 289.960951 -1.371344) (xy 289.95624 -1.369314) (xy 289.947604 -1.365758) (xy 278.199088 -1.365758)
			(xy 278.190482 -1.366085) (xy 278.174244 -1.371789) (xy 278.167338 -1.376934) (xy 278.16683 -1.377442)
			(xy 278.163274 -1.38049) (xy 277.69566 -1.848104) (xy 277.692139 -1.851835) (xy 277.68651 -1.860409)
			(xy 277.684484 -1.865122) (xy 277.680928 -1.873758) (xy 277.680928 -13.649198) (xy 277.681165 -13.655945)
			(xy 277.684762 -13.668951) (xy 277.68804 -13.674852) (xy 277.702772 -13.697712) (xy 277.711916 -13.708634)
			(xy 277.71725 -13.713206) (xy 277.723854 -13.716254) (xy 277.78505 -13.745442) (xy 277.903996 -13.810544)
			(xy 278.018568 -13.883067) (xy 278.128305 -13.962718) (xy 278.232763 -14.049176) (xy 278.331521 -14.142091)
			(xy 278.42418 -14.241089) (xy 278.510367 -14.345771) (xy 278.589733 -14.455714) (xy 278.626316 -14.512798)
			(xy 278.63419 -14.512798) (xy 278.70023 -14.639544) (xy 278.704802 -14.64818) (xy 278.704802 -14.648434)
			(xy 278.710898 -14.660118) (xy 278.740298 -14.717325) (xy 278.748368 -14.735302) (xy 282.772356 -14.735302)
			(xy 282.776427 -14.67968) (xy 282.788553 -14.625243) (xy 282.808476 -14.573152) (xy 282.835772 -14.524517)
			(xy 282.869858 -14.480374) (xy 282.910007 -14.441665) (xy 282.955365 -14.409214) (xy 283.004965 -14.383713)
			(xy 283.057749 -14.365706) (xy 283.112592 -14.355576) (xy 283.168326 -14.353539) (xy 283.223763 -14.359639)
			(xy 283.27772 -14.373745) (xy 283.329049 -14.395557) (xy 283.376655 -14.424611) (xy 283.419523 -14.460286)
			(xy 283.45674 -14.501823) (xy 283.487513 -14.548336) (xy 283.511185 -14.598833) (xy 283.527253 -14.65224)
			(xy 283.535373 -14.707416) (xy 283.535882 -14.735302) (xy 283.535373 -14.763188) (xy 283.527253 -14.818364)
			(xy 283.511185 -14.871771) (xy 283.487513 -14.922268) (xy 283.45674 -14.968781) (xy 283.419523 -15.010318)
			(xy 283.376655 -15.045993) (xy 283.329049 -15.075047) (xy 283.27772 -15.096859) (xy 283.223763 -15.110965)
			(xy 283.168326 -15.117065) (xy 283.112592 -15.115028) (xy 283.057749 -15.104898) (xy 283.004965 -15.086891)
			(xy 282.955365 -15.06139) (xy 282.910007 -15.028939) (xy 282.869858 -14.99023) (xy 282.835772 -14.946087)
			(xy 282.808476 -14.897452) (xy 282.788553 -14.845361) (xy 282.776427 -14.790924) (xy 282.772356 -14.735302)
			(xy 278.748368 -14.735302) (xy 278.79298 -14.834678) (xy 278.838497 -14.954991) (xy 278.876682 -15.077828)
			(xy 278.907399 -15.202743) (xy 278.930534 -15.329281) (xy 278.938805 -15.397554) (xy 284.104257 -15.397554)
			(xy 284.104257 -15.343046) (xy 284.112015 -15.289092) (xy 284.127373 -15.236792) (xy 284.150018 -15.18721)
			(xy 284.179489 -15.141355) (xy 284.215186 -15.100162) (xy 284.256382 -15.064468) (xy 284.30224 -15.035001)
			(xy 284.351824 -15.012361) (xy 284.404125 -14.997008) (xy 284.45808 -14.989255) (xy 284.485334 -14.988794)
			(xy 284.511571 -14.989231) (xy 284.563547 -14.996431) (xy 284.614046 -15.01069) (xy 284.662112 -15.031738)
			(xy 284.706839 -15.059179) (xy 284.74738 -15.092493) (xy 284.765496 -15.111476) (xy 284.76575 -15.11173)
			(xy 284.773486 -15.119108) (xy 284.793167 -15.127385) (xy 284.80385 -15.127732) (xy 284.891734 -15.125446)
			(xy 284.911292 -15.116048) (xy 284.918404 -15.107412) (xy 284.936587 -15.086236) (xy 284.978133 -15.048963)
			(xy 285.024668 -15.018144) (xy 285.075199 -14.994438) (xy 285.128646 -14.97835) (xy 285.183866 -14.970225)
			(xy 285.211774 -14.969744) (xy 285.239025 -14.970301) (xy 285.292972 -14.978054) (xy 285.345266 -14.993406)
			(xy 285.394843 -15.016044) (xy 285.440694 -15.045508) (xy 285.481884 -15.081197) (xy 285.517576 -15.122385)
			(xy 285.547043 -15.168234) (xy 285.569685 -15.21781) (xy 285.58504 -15.270103) (xy 285.592797 -15.324049)
			(xy 285.592797 -15.378551) (xy 285.58504 -15.432497) (xy 285.569685 -15.48479) (xy 285.547043 -15.534366)
			(xy 285.517576 -15.580215) (xy 285.481884 -15.621403) (xy 285.440694 -15.657092) (xy 285.394843 -15.686556)
			(xy 285.345266 -15.709194) (xy 285.292972 -15.724546) (xy 285.239025 -15.732299) (xy 285.211774 -15.73276)
			(xy 285.185537 -15.732332) (xy 285.133559 -15.725133) (xy 285.08306 -15.710873) (xy 285.034993 -15.689823)
			(xy 284.990267 -15.66238) (xy 284.949727 -15.629063) (xy 284.931612 -15.610078) (xy 284.931358 -15.609824)
			(xy 284.923625 -15.602443) (xy 284.903942 -15.59417) (xy 284.893258 -15.593822) (xy 284.805374 -15.596108)
			(xy 284.785816 -15.605506) (xy 284.778704 -15.614142) (xy 284.760506 -15.635305) (xy 284.718965 -15.672581)
			(xy 284.672433 -15.703402) (xy 284.621905 -15.727111) (xy 284.56846 -15.743201) (xy 284.513241 -15.751328)
			(xy 284.485334 -15.75181) (xy 284.45808 -15.751345) (xy 284.404125 -15.743592) (xy 284.351824 -15.728239)
			(xy 284.30224 -15.705599) (xy 284.256382 -15.676132) (xy 284.215186 -15.640438) (xy 284.179489 -15.599245)
			(xy 284.150018 -15.55339) (xy 284.127373 -15.503808) (xy 284.112015 -15.451508) (xy 284.104257 -15.397554)
			(xy 278.938805 -15.397554) (xy 278.946004 -15.456982) (xy 278.953754 -15.585384) (xy 278.95423 -15.649702)
			(xy 278.95423 -15.649956) (xy 278.953724 -15.715692) (xy 278.945631 -15.846913) (xy 278.929474 -15.977388)
			(xy 278.905317 -16.106621) (xy 278.873249 -16.234121) (xy 278.833393 -16.359405) (xy 278.7859 -16.481999)
			(xy 278.730951 -16.601436) (xy 278.668752 -16.717263) (xy 278.599542 -16.829042) (xy 278.523581 -16.936349)
			(xy 278.496507 -16.969994) (xy 297.948103 -16.969994) (xy 297.952108 -16.882086) (xy 297.964091 -16.794906)
			(xy 297.983951 -16.709177) (xy 298.011526 -16.625609) (xy 298.046585 -16.544895) (xy 298.088838 -16.467703)
			(xy 298.137936 -16.394674) (xy 298.193472 -16.326412) (xy 298.254984 -16.263482) (xy 298.321965 -16.206408)
			(xy 298.393858 -16.15566) (xy 298.470067 -16.11166) (xy 298.549962 -16.074773) (xy 298.632881 -16.045304)
			(xy 298.718136 -16.023497) (xy 298.80502 -16.009533) (xy 298.892814 -16.003527) (xy 298.980791 -16.005531)
			(xy 299.068221 -16.015526) (xy 299.15438 -16.03343) (xy 299.238554 -16.059094) (xy 299.320045 -16.092307)
			(xy 299.398179 -16.132793) (xy 299.472307 -16.180215) (xy 299.541815 -16.234182) (xy 299.606129 -16.294247)
			(xy 299.664713 -16.359911) (xy 299.717084 -16.43063) (xy 299.762807 -16.505818) (xy 299.801504 -16.584853)
			(xy 299.832853 -16.667079) (xy 299.856595 -16.751815) (xy 299.872533 -16.838359) (xy 299.880535 -16.925994)
			(xy 299.881036 -16.969994) (xy 299.880535 -17.013994) (xy 299.872533 -17.101629) (xy 299.856595 -17.188173)
			(xy 299.832853 -17.272909) (xy 299.801504 -17.355135) (xy 299.762807 -17.43417) (xy 299.717084 -17.509358)
			(xy 299.664713 -17.580077) (xy 299.606129 -17.645741) (xy 299.541815 -17.705806) (xy 299.472307 -17.759773)
			(xy 299.398179 -17.807195) (xy 299.320045 -17.847681) (xy 299.238554 -17.880894) (xy 299.15438 -17.906558)
			(xy 299.068221 -17.924462) (xy 298.980791 -17.934457) (xy 298.892814 -17.936461) (xy 298.80502 -17.930455)
			(xy 298.718136 -17.916491) (xy 298.632881 -17.894684) (xy 298.549962 -17.865215) (xy 298.470067 -17.828328)
			(xy 298.393858 -17.784328) (xy 298.321965 -17.73358) (xy 298.254984 -17.676506) (xy 298.193472 -17.613576)
			(xy 298.137936 -17.545314) (xy 298.088838 -17.472285) (xy 298.046585 -17.395093) (xy 298.011526 -17.314379)
			(xy 297.983951 -17.230811) (xy 297.964091 -17.145082) (xy 297.952108 -17.057902) (xy 297.948103 -16.969994)
			(xy 278.496507 -16.969994) (xy 278.441159 -17.038775) (xy 278.352587 -17.135934) (xy 278.258202 -17.227455)
			(xy 278.158363 -17.312993) (xy 278.053446 -17.392222) (xy 278.012168 -17.419574) (xy 282.484066 -17.419574)
			(xy 282.488137 -17.363952) (xy 282.500263 -17.309515) (xy 282.520186 -17.257424) (xy 282.547482 -17.208789)
			(xy 282.581568 -17.164646) (xy 282.621717 -17.125937) (xy 282.667075 -17.093486) (xy 282.716675 -17.067985)
			(xy 282.769459 -17.049978) (xy 282.824302 -17.039848) (xy 282.880036 -17.037811) (xy 282.935473 -17.043911)
			(xy 282.98943 -17.058017) (xy 283.040759 -17.079829) (xy 283.088365 -17.108883) (xy 283.131233 -17.144558)
			(xy 283.16845 -17.186095) (xy 283.199223 -17.232608) (xy 283.222895 -17.283105) (xy 283.238963 -17.336512)
			(xy 283.247083 -17.391688) (xy 283.247592 -17.419574) (xy 283.247083 -17.44746) (xy 283.238963 -17.502636)
			(xy 283.222895 -17.556043) (xy 283.199223 -17.60654) (xy 283.16845 -17.653053) (xy 283.131233 -17.69459)
			(xy 283.088365 -17.730265) (xy 283.040759 -17.759319) (xy 282.98943 -17.781131) (xy 282.935473 -17.795237)
			(xy 282.880036 -17.801337) (xy 282.824302 -17.7993) (xy 282.769459 -17.78917) (xy 282.716675 -17.771163)
			(xy 282.667075 -17.745662) (xy 282.621717 -17.713211) (xy 282.581568 -17.674502) (xy 282.547482 -17.630359)
			(xy 282.520186 -17.581724) (xy 282.500263 -17.529633) (xy 282.488137 -17.475196) (xy 282.484066 -17.419574)
			(xy 278.012168 -17.419574) (xy 277.943852 -17.464842) (xy 277.829994 -17.530577) (xy 277.712306 -17.589179)
			(xy 277.591234 -17.640425) (xy 277.467236 -17.68412) (xy 277.340784 -17.720099) (xy 277.212356 -17.748225)
			(xy 277.082441 -17.768391) (xy 276.951531 -17.780522) (xy 276.820122 -17.784571) (xy 276.688713 -17.780522)
			(xy 276.557803 -17.768391) (xy 276.427888 -17.748225) (xy 276.29946 -17.720099) (xy 276.173008 -17.68412)
			(xy 276.04901 -17.640425) (xy 275.927938 -17.589179) (xy 275.81025 -17.530577) (xy 275.696392 -17.464842)
			(xy 275.586798 -17.392222) (xy 275.481881 -17.312993) (xy 275.382042 -17.227455) (xy 275.287657 -17.135934)
			(xy 275.199085 -17.038775) (xy 275.116663 -16.936349) (xy 275.040702 -16.829042) (xy 274.971492 -16.717263)
			(xy 274.909293 -16.601436) (xy 274.854344 -16.481999) (xy 274.806851 -16.359405) (xy 274.766995 -16.234121)
			(xy 274.734927 -16.106621) (xy 274.71077 -15.977388) (xy 274.694613 -15.846913) (xy 274.68652 -15.715692)
			(xy 274.686014 -15.649956) (xy 274.686014 -15.649702) (xy 274.686496 -15.585384) (xy 274.694245 -15.456982)
			(xy 274.709714 -15.32928) (xy 274.732848 -15.202742) (xy 274.763562 -15.077827) (xy 274.801745 -14.954989)
			(xy 274.847259 -14.834675) (xy 274.899937 -14.71732) (xy 274.929346 -14.660118) (xy 274.931378 -14.656054)
			(xy 274.933261 -14.651126) (xy 274.935189 -14.640755) (xy 274.935188 -14.63548) (xy 274.93468 -14.621764)
			(xy 274.88261 -14.535912) (xy 274.87779 -14.528658) (xy 274.864287 -14.517677) (xy 274.847879 -14.511871)
			(xy 274.839176 -14.511528) (xy 265.273028 -14.511528) (xy 265.262977 -14.511024) (xy 265.244414 -14.503305)
			(xy 265.23696 -14.496542) (xy 264.522966 -13.782548) (xy 264.51612 -13.77515) (xy 264.508395 -13.756551)
			(xy 264.50798 -13.74648) (xy 264.50798 -1.941576) (xy 264.507816 -1.935566) (xy 264.504996 -1.923881)
			(xy 264.502392 -1.918462) (xy 264.500551 -1.914989) (xy 264.495955 -1.908612) (xy 264.493248 -1.905762)
			(xy 263.96823 -1.380744) (xy 263.96538 -1.378036) (xy 263.959004 -1.373439) (xy 263.95553 -1.3716)
			(xy 263.950103 -1.36902) (xy 263.938423 -1.366202) (xy 263.932416 -1.366012) (xy 252.19406 -1.366012)
			(xy 252.18805 -1.366178) (xy 252.176367 -1.369001) (xy 252.170946 -1.3716) (xy 252.167473 -1.373442)
			(xy 252.161098 -1.378038) (xy 252.158246 -1.380744) (xy 251.690632 -1.848358) (xy 251.687924 -1.851208)
			(xy 251.683327 -1.857584) (xy 251.681488 -1.861058) (xy 251.678907 -1.866485) (xy 251.676087 -1.878165)
			(xy 251.6759 -1.884172) (xy 251.6759 -13.556234) (xy 251.67616 -13.563644) (xy 251.680432 -13.577836)
			(xy 251.684282 -13.584174) (xy 251.698252 -13.605256) (xy 251.702415 -13.611284) (xy 251.713516 -13.620832)
			(xy 251.720096 -13.624052) (xy 251.781831 -13.652043) (xy 251.902121 -13.71456) (xy 252.018367 -13.784309)
			(xy 252.130134 -13.86103) (xy 252.237005 -13.944436) (xy 252.338581 -14.034216) (xy 252.404724 -14.100302)
			(xy 257.442968 -14.100302) (xy 257.447039 -14.04468) (xy 257.459165 -13.990243) (xy 257.479088 -13.938152)
			(xy 257.506384 -13.889517) (xy 257.54047 -13.845374) (xy 257.580619 -13.806665) (xy 257.625977 -13.774214)
			(xy 257.675577 -13.748713) (xy 257.728361 -13.730706) (xy 257.783204 -13.720576) (xy 257.838938 -13.718539)
			(xy 257.894375 -13.724639) (xy 257.948332 -13.738745) (xy 257.999661 -13.760557) (xy 258.047267 -13.789611)
			(xy 258.090135 -13.825286) (xy 258.127352 -13.866823) (xy 258.158125 -13.913336) (xy 258.181797 -13.963833)
			(xy 258.197865 -14.01724) (xy 258.205985 -14.072416) (xy 258.206494 -14.100302) (xy 258.205985 -14.128188)
			(xy 258.197865 -14.183364) (xy 258.181797 -14.236771) (xy 258.158125 -14.287268) (xy 258.127352 -14.333781)
			(xy 258.090135 -14.375318) (xy 258.047267 -14.410993) (xy 257.999661 -14.440047) (xy 257.948332 -14.461859)
			(xy 257.894375 -14.475965) (xy 257.838938 -14.482065) (xy 257.783204 -14.480028) (xy 257.728361 -14.469898)
			(xy 257.675577 -14.451891) (xy 257.625977 -14.42639) (xy 257.580619 -14.393939) (xy 257.54047 -14.35523)
			(xy 257.506384 -14.311087) (xy 257.479088 -14.262452) (xy 257.459165 -14.210361) (xy 257.447039 -14.155924)
			(xy 257.442968 -14.100302) (xy 252.404724 -14.100302) (xy 252.434481 -14.130034) (xy 252.524348 -14.231533)
			(xy 252.607846 -14.338332) (xy 252.684663 -14.450033) (xy 252.754512 -14.566219) (xy 252.817131 -14.686456)
			(xy 252.872288 -14.810293) (xy 252.919775 -14.93727) (xy 252.959416 -15.06691) (xy 252.991062 -15.19873)
			(xy 253.003304 -15.2654) (xy 253.01067 -15.30731) (xy 253.019814 -15.30731) (xy 253.025767 -15.346967)
			(xy 253.031738 -15.39755) (xy 258.10438 -15.39755) (xy 258.10438 -15.34305) (xy 258.112136 -15.289103)
			(xy 258.12749 -15.23681) (xy 258.15013 -15.187234) (xy 258.179595 -15.141384) (xy 258.215285 -15.100195)
			(xy 258.256473 -15.064503) (xy 258.302322 -15.035037) (xy 258.351897 -15.012395) (xy 258.40419 -14.997039)
			(xy 258.458136 -14.989281) (xy 258.485386 -14.988794) (xy 258.511621 -14.989263) (xy 258.563597 -14.996456)
			(xy 258.614095 -15.010709) (xy 258.662161 -15.031751) (xy 258.706889 -15.059186) (xy 258.747431 -15.092496)
			(xy 258.765548 -15.111476) (xy 258.765802 -15.11173) (xy 258.773518 -15.119132) (xy 258.793214 -15.127395)
			(xy 258.803902 -15.127732) (xy 258.891786 -15.125446) (xy 258.911344 -15.116048) (xy 258.918456 -15.107412)
			(xy 258.936664 -15.086259) (xy 258.978205 -15.048984) (xy 259.024735 -15.018163) (xy 259.075261 -14.994453)
			(xy 259.128703 -14.97836) (xy 259.18392 -14.970229) (xy 259.211826 -14.969744) (xy 259.239073 -14.970328)
			(xy 259.293011 -14.978086) (xy 259.345296 -14.993442) (xy 259.394863 -15.016082) (xy 259.440705 -15.045545)
			(xy 259.481887 -15.081232) (xy 259.517571 -15.122416) (xy 259.547031 -15.16826) (xy 259.569667 -15.217829)
			(xy 259.585019 -15.270115) (xy 259.592774 -15.324053) (xy 259.592774 -15.378547) (xy 259.585019 -15.432485)
			(xy 259.569667 -15.484771) (xy 259.547031 -15.53434) (xy 259.517571 -15.580184) (xy 259.481887 -15.621368)
			(xy 259.440705 -15.657055) (xy 259.394863 -15.686518) (xy 259.345296 -15.709158) (xy 259.293011 -15.724514)
			(xy 259.239073 -15.732272) (xy 259.211826 -15.73276) (xy 259.18559 -15.732298) (xy 259.133614 -15.725105)
			(xy 259.083115 -15.710852) (xy 259.035048 -15.689809) (xy 258.990321 -15.662372) (xy 258.94978 -15.62906)
			(xy 258.931664 -15.610078) (xy 258.93141 -15.609824) (xy 258.923695 -15.602421) (xy 258.903998 -15.59416)
			(xy 258.89331 -15.593822) (xy 258.805426 -15.596108) (xy 258.785868 -15.605506) (xy 258.778756 -15.614142)
			(xy 258.760531 -15.63528) (xy 258.718995 -15.672558) (xy 258.672469 -15.703382) (xy 258.621946 -15.727096)
			(xy 258.568506 -15.743191) (xy 258.513291 -15.751324) (xy 258.485386 -15.75181) (xy 258.458136 -15.751319)
			(xy 258.40419 -15.743561) (xy 258.351897 -15.728205) (xy 258.302322 -15.705563) (xy 258.256473 -15.676097)
			(xy 258.215285 -15.640405) (xy 258.179595 -15.599216) (xy 258.15013 -15.553366) (xy 258.12749 -15.50379)
			(xy 258.112136 -15.451497) (xy 258.10438 -15.39755) (xy 253.031738 -15.39755) (xy 253.035169 -15.426615)
			(xy 253.03861 -15.466568) (xy 253.038864 -15.46733) (xy 253.042328 -15.512716) (xy 253.046012 -15.603676)
			(xy 253.04623 -15.649194) (xy 253.04623 -15.649956) (xy 253.045722 -15.717213) (xy 253.0376 -15.851481)
			(xy 253.021387 -15.985013) (xy 252.99714 -16.117323) (xy 252.964949 -16.247928) (xy 252.924931 -16.37635)
			(xy 252.877232 -16.502122) (xy 252.822026 -16.624785) (xy 252.759514 -16.743891) (xy 252.689925 -16.859005)
			(xy 252.613513 -16.969707) (xy 252.613288 -16.969994) (xy 271.948155 -16.969994) (xy 271.95216 -16.882086)
			(xy 271.964143 -16.794906) (xy 271.984003 -16.709177) (xy 272.011578 -16.625609) (xy 272.046637 -16.544895)
			(xy 272.08889 -16.467703) (xy 272.137988 -16.394674) (xy 272.193524 -16.326412) (xy 272.255036 -16.263482)
			(xy 272.322017 -16.206408) (xy 272.39391 -16.15566) (xy 272.470119 -16.11166) (xy 272.550014 -16.074773)
			(xy 272.632933 -16.045304) (xy 272.718188 -16.023497) (xy 272.805072 -16.009533) (xy 272.892866 -16.003527)
			(xy 272.980843 -16.005531) (xy 273.068273 -16.015526) (xy 273.154432 -16.03343) (xy 273.238606 -16.059094)
			(xy 273.320097 -16.092307) (xy 273.398231 -16.132793) (xy 273.472359 -16.180215) (xy 273.541867 -16.234182)
			(xy 273.606181 -16.294247) (xy 273.664765 -16.359911) (xy 273.717136 -16.43063) (xy 273.762859 -16.505818)
			(xy 273.801556 -16.584853) (xy 273.832905 -16.667079) (xy 273.856647 -16.751815) (xy 273.872585 -16.838359)
			(xy 273.880587 -16.925994) (xy 273.881088 -16.969994) (xy 273.880587 -17.013994) (xy 273.872585 -17.101629)
			(xy 273.856647 -17.188173) (xy 273.832905 -17.272909) (xy 273.801556 -17.355135) (xy 273.762859 -17.43417)
			(xy 273.717136 -17.509358) (xy 273.664765 -17.580077) (xy 273.606181 -17.645741) (xy 273.541867 -17.705806)
			(xy 273.472359 -17.759773) (xy 273.398231 -17.807195) (xy 273.320097 -17.847681) (xy 273.238606 -17.880894)
			(xy 273.154432 -17.906558) (xy 273.068273 -17.924462) (xy 272.980843 -17.934457) (xy 272.892866 -17.936461)
			(xy 272.805072 -17.930455) (xy 272.718188 -17.916491) (xy 272.632933 -17.894684) (xy 272.550014 -17.865215)
			(xy 272.470119 -17.828328) (xy 272.39391 -17.784328) (xy 272.322017 -17.73358) (xy 272.255036 -17.676506)
			(xy 272.193524 -17.613576) (xy 272.137988 -17.545314) (xy 272.08889 -17.472285) (xy 272.046637 -17.395093)
			(xy 272.011578 -17.314379) (xy 271.984003 -17.230811) (xy 271.964143 -17.145082) (xy 271.95216 -17.057902)
			(xy 271.948155 -16.969994) (xy 252.613288 -16.969994) (xy 252.530556 -17.075593) (xy 252.441357 -17.176278)
			(xy 252.346242 -17.271393) (xy 252.245557 -17.360592) (xy 252.170273 -17.419574) (xy 256.484118 -17.419574)
			(xy 256.488189 -17.363952) (xy 256.500315 -17.309515) (xy 256.520238 -17.257424) (xy 256.547534 -17.208789)
			(xy 256.58162 -17.164646) (xy 256.621769 -17.125937) (xy 256.667127 -17.093486) (xy 256.716727 -17.067985)
			(xy 256.769511 -17.049978) (xy 256.824354 -17.039848) (xy 256.880088 -17.037811) (xy 256.935525 -17.043911)
			(xy 256.989482 -17.058017) (xy 257.040811 -17.079829) (xy 257.088417 -17.108883) (xy 257.131285 -17.144558)
			(xy 257.168502 -17.186095) (xy 257.199275 -17.232608) (xy 257.222947 -17.283105) (xy 257.239015 -17.336512)
			(xy 257.247135 -17.391688) (xy 257.247644 -17.419574) (xy 257.247135 -17.44746) (xy 257.239015 -17.502636)
			(xy 257.222947 -17.556043) (xy 257.199275 -17.60654) (xy 257.168502 -17.653053) (xy 257.131285 -17.69459)
			(xy 257.088417 -17.730265) (xy 257.040811 -17.759319) (xy 256.989482 -17.781131) (xy 256.935525 -17.795237)
			(xy 256.880088 -17.801337) (xy 256.824354 -17.7993) (xy 256.769511 -17.78917) (xy 256.716727 -17.771163)
			(xy 256.667127 -17.745662) (xy 256.621769 -17.713211) (xy 256.58162 -17.674502) (xy 256.547534 -17.630359)
			(xy 256.520238 -17.581724) (xy 256.500315 -17.529633) (xy 256.488189 -17.475196) (xy 256.484118 -17.419574)
			(xy 252.170273 -17.419574) (xy 252.139671 -17.443549) (xy 252.028969 -17.519961) (xy 251.913855 -17.58955)
			(xy 251.794749 -17.652062) (xy 251.672086 -17.707268) (xy 251.546314 -17.754967) (xy 251.417892 -17.794985)
			(xy 251.287287 -17.827176) (xy 251.154977 -17.851423) (xy 251.021445 -17.867636) (xy 250.887177 -17.875758)
			(xy 250.752663 -17.875758) (xy 250.618395 -17.867636) (xy 250.484863 -17.851423) (xy 250.352553 -17.827176)
			(xy 250.221948 -17.794985) (xy 250.093526 -17.754967) (xy 249.967754 -17.707268) (xy 249.845091 -17.652062)
			(xy 249.725985 -17.58955) (xy 249.610871 -17.519961) (xy 249.500169 -17.443549) (xy 249.394283 -17.360592)
			(xy 249.293598 -17.271393) (xy 249.198483 -17.176278) (xy 249.109284 -17.075593) (xy 249.026327 -16.969707)
			(xy 248.949915 -16.859005) (xy 248.880326 -16.743891) (xy 248.817814 -16.624785) (xy 248.762608 -16.502122)
			(xy 248.714909 -16.37635) (xy 248.674891 -16.247928) (xy 248.6427 -16.117323) (xy 248.618453 -15.985013)
			(xy 248.60224 -15.851481) (xy 248.594118 -15.717213) (xy 248.59361 -15.649956) (xy 248.59361 -15.649448)
			(xy 248.594072 -15.585244) (xy 248.601489 -15.457049) (xy 248.616284 -15.329496) (xy 248.638407 -15.203007)
			(xy 248.667785 -15.078004) (xy 248.70432 -14.954903) (xy 248.747892 -14.834112) (xy 248.798353 -14.716034)
			(xy 248.826528 -14.65834) (xy 248.829451 -14.65222) (xy 248.832274 -14.638959) (xy 248.832116 -14.632178)
			(xy 248.831354 -14.620494) (xy 248.817892 -14.59865) (xy 248.777506 -14.533626) (xy 248.769941 -14.523871)
			(xy 248.748169 -14.512319) (xy 248.73585 -14.511528) (xy 239.181132 -14.511528) (xy 239.17108 -14.511025)
			(xy 239.152516 -14.503306) (xy 239.145064 -14.496542) (xy 238.714026 -14.065504) (xy 238.707176 -14.058107)
			(xy 238.699436 -14.039509) (xy 238.69904 -14.029436) (xy 238.69904 -2.558542) (xy 238.69898 -2.554936)
			(xy 238.697967 -2.547795) (xy 238.697008 -2.544318) (xy 238.695484 -2.539746) (xy 238.691674 -2.530602)
			(xy 237.541816 -1.380744) (xy 237.538966 -1.378037) (xy 237.532589 -1.373442) (xy 237.529116 -1.3716)
			(xy 237.523688 -1.369021) (xy 237.512009 -1.366207) (xy 237.506002 -1.366012) (xy 214.098378 -1.366012)
			(xy 214.094772 -1.366076) (xy 214.087634 -1.367097) (xy 214.084154 -1.368044) (xy 214.079582 -1.369568)
			(xy 214.070438 -1.373378) (xy 213.595458 -1.848358) (xy 213.592749 -1.851207) (xy 213.58815 -1.857582)
			(xy 213.586314 -1.861058) (xy 213.583732 -1.866485) (xy 213.580911 -1.878165) (xy 213.580726 -1.884172)
			(xy 213.580726 -7.355078) (xy 213.58087 -7.360109) (xy 213.582924 -7.369961) (xy 213.58479 -7.374636)
			(xy 213.590886 -7.385558) (xy 213.596474 -7.392924) (xy 213.61146 -7.402576) (xy 213.62035 -7.404608)
			(xy 213.648209 -7.411348) (xy 213.701656 -7.432052) (xy 213.751404 -7.460517) (xy 213.796335 -7.496104)
			(xy 213.835437 -7.53801) (xy 213.867831 -7.585295) (xy 213.892788 -7.636892) (xy 213.909746 -7.691643)
			(xy 213.918324 -7.748314) (xy 213.9188 -7.776972) (xy 213.9188 -7.777226) (xy 213.918237 -7.806928)
			(xy 213.909031 -7.865615) (xy 213.890831 -7.922163) (xy 213.864076 -7.975202) (xy 213.829416 -8.023447)
			(xy 213.78769 -8.06573) (xy 213.764114 -8.083804) (xy 213.761828 -8.085328) (xy 213.758526 -8.088376)
			(xy 213.748874 -8.098028) (xy 213.746588 -8.101838) (xy 213.737444 -8.119364) (xy 213.734142 -8.12546)
			(xy 213.731707 -8.130727) (xy 213.729023 -8.142013) (xy 213.728808 -8.147812) (xy 213.728808 -8.206232)
			(xy 213.729016 -8.212319) (xy 213.731969 -8.224131) (xy 213.73465 -8.2296) (xy 213.73465 -8.229854)
			(xy 213.745826 -8.250936) (xy 213.74735 -8.25373) (xy 213.749662 -8.257244) (xy 213.755274 -8.263509)
			(xy 213.758526 -8.266176) (xy 213.760558 -8.2677) (xy 213.781212 -8.283133) (xy 213.818573 -8.318666)
			(xy 213.850807 -8.358908) (xy 213.877326 -8.403124) (xy 213.897648 -8.45051) (xy 213.911402 -8.500201)
			(xy 213.918338 -8.551292) (xy 213.9188 -8.577072) (xy 213.918287 -8.60573) (xy 213.909718 -8.662401)
			(xy 213.892767 -8.717152) (xy 213.867816 -8.768751) (xy 213.835427 -8.816038) (xy 213.796329 -8.857947)
			(xy 213.751402 -8.893536) (xy 213.701656 -8.922003) (xy 213.648211 -8.942709) (xy 213.62035 -8.949436)
			(xy 213.61146 -8.951468) (xy 213.597744 -8.960104) (xy 213.591902 -8.967216) (xy 213.586782 -8.974137)
			(xy 213.58106 -8.990364) (xy 213.580726 -8.998966) (xy 213.580726 -13.649452) (xy 213.581488 -13.658342)
			(xy 213.582304 -13.662462) (xy 213.585108 -13.67038) (xy 213.587076 -13.67409) (xy 213.603332 -13.699236)
			(xy 213.609428 -13.706602) (xy 213.617048 -13.71346) (xy 213.623906 -13.716508) (xy 213.680938 -13.743689)
			(xy 213.79203 -13.803886) (xy 213.899365 -13.870551) (xy 214.002568 -13.943451) (xy 214.101275 -14.022331)
			(xy 214.187805 -14.100302) (xy 219.342968 -14.100302) (xy 219.347039 -14.04468) (xy 219.359165 -13.990243)
			(xy 219.379088 -13.938152) (xy 219.406384 -13.889517) (xy 219.44047 -13.845374) (xy 219.480619 -13.806665)
			(xy 219.525977 -13.774214) (xy 219.575577 -13.748713) (xy 219.628361 -13.730706) (xy 219.683204 -13.720576)
			(xy 219.738938 -13.718539) (xy 219.794375 -13.724639) (xy 219.848332 -13.738745) (xy 219.899661 -13.760557)
			(xy 219.947267 -13.789611) (xy 219.990135 -13.825286) (xy 220.027352 -13.866823) (xy 220.058125 -13.913336)
			(xy 220.081797 -13.963833) (xy 220.097865 -14.01724) (xy 220.105985 -14.072416) (xy 220.106494 -14.100302)
			(xy 220.105985 -14.128188) (xy 220.097865 -14.183364) (xy 220.081797 -14.236771) (xy 220.058125 -14.287268)
			(xy 220.027352 -14.333781) (xy 219.990135 -14.375318) (xy 219.947267 -14.410993) (xy 219.899661 -14.440047)
			(xy 219.848332 -14.461859) (xy 219.794375 -14.475965) (xy 219.738938 -14.482065) (xy 219.683204 -14.480028)
			(xy 219.628361 -14.469898) (xy 219.575577 -14.451891) (xy 219.525977 -14.42639) (xy 219.480619 -14.393939)
			(xy 219.44047 -14.35523) (xy 219.406384 -14.311087) (xy 219.379088 -14.262452) (xy 219.359165 -14.210361)
			(xy 219.347039 -14.155924) (xy 219.342968 -14.100302) (xy 214.187805 -14.100302) (xy 214.195142 -14.106913)
			(xy 214.283839 -14.196901) (xy 214.367056 -14.29198) (xy 214.444501 -14.391817) (xy 214.515902 -14.496062)
			(xy 214.58101 -14.604349) (xy 214.610696 -14.660118) (xy 214.613236 -14.665198) (xy 214.616538 -14.671548)
			(xy 214.645166 -14.72805) (xy 214.696461 -14.843878) (xy 214.740795 -14.962545) (xy 214.778012 -15.083634)
			(xy 214.807979 -15.206716) (xy 214.830593 -15.33136) (xy 214.838582 -15.39755) (xy 220.00438 -15.39755)
			(xy 220.00438 -15.34305) (xy 220.012136 -15.289103) (xy 220.02749 -15.23681) (xy 220.05013 -15.187234)
			(xy 220.079595 -15.141384) (xy 220.115285 -15.100195) (xy 220.156473 -15.064503) (xy 220.202322 -15.035037)
			(xy 220.251897 -15.012395) (xy 220.30419 -14.997039) (xy 220.358136 -14.989281) (xy 220.385386 -14.988794)
			(xy 220.411621 -14.989263) (xy 220.463597 -14.996456) (xy 220.514095 -15.010709) (xy 220.562161 -15.031751)
			(xy 220.606889 -15.059186) (xy 220.647431 -15.092496) (xy 220.665548 -15.111476) (xy 220.665802 -15.11173)
			(xy 220.673518 -15.119132) (xy 220.693214 -15.127395) (xy 220.703902 -15.127732) (xy 220.791786 -15.125446)
			(xy 220.811344 -15.116048) (xy 220.818456 -15.107412) (xy 220.836664 -15.086259) (xy 220.878205 -15.048984)
			(xy 220.924735 -15.018163) (xy 220.975261 -14.994453) (xy 221.028703 -14.97836) (xy 221.08392 -14.970229)
			(xy 221.111826 -14.969744) (xy 221.139073 -14.970328) (xy 221.193011 -14.978086) (xy 221.245296 -14.993442)
			(xy 221.294863 -15.016082) (xy 221.340705 -15.045545) (xy 221.381887 -15.081232) (xy 221.417571 -15.122416)
			(xy 221.447031 -15.16826) (xy 221.469667 -15.217829) (xy 221.485019 -15.270115) (xy 221.492774 -15.324053)
			(xy 221.492774 -15.378547) (xy 221.485019 -15.432485) (xy 221.469667 -15.484771) (xy 221.447031 -15.53434)
			(xy 221.417571 -15.580184) (xy 221.381887 -15.621368) (xy 221.340705 -15.657055) (xy 221.294863 -15.686518)
			(xy 221.245296 -15.709158) (xy 221.193011 -15.724514) (xy 221.139073 -15.732272) (xy 221.111826 -15.73276)
			(xy 221.08559 -15.732298) (xy 221.033614 -15.725105) (xy 220.983115 -15.710852) (xy 220.935048 -15.689809)
			(xy 220.890321 -15.662372) (xy 220.84978 -15.62906) (xy 220.831664 -15.610078) (xy 220.83141 -15.609824)
			(xy 220.823695 -15.602421) (xy 220.803998 -15.59416) (xy 220.79331 -15.593822) (xy 220.705426 -15.596108)
			(xy 220.685868 -15.605506) (xy 220.678756 -15.614142) (xy 220.660531 -15.63528) (xy 220.618995 -15.672558)
			(xy 220.572469 -15.703382) (xy 220.521946 -15.727096) (xy 220.468506 -15.743191) (xy 220.413291 -15.751324)
			(xy 220.385386 -15.75181) (xy 220.358136 -15.751319) (xy 220.30419 -15.743561) (xy 220.251897 -15.728205)
			(xy 220.202322 -15.705563) (xy 220.156473 -15.676097) (xy 220.115285 -15.640405) (xy 220.079595 -15.599216)
			(xy 220.05013 -15.553366) (xy 220.02749 -15.50379) (xy 220.012136 -15.451497) (xy 220.00438 -15.39755)
			(xy 214.838582 -15.39755) (xy 214.845772 -15.457125) (xy 214.853464 -15.58357) (xy 214.854028 -15.646908)
			(xy 214.854028 -15.665958) (xy 214.853041 -15.731376) (xy 214.844045 -15.861914) (xy 214.827069 -15.991656)
			(xy 214.802175 -16.120113) (xy 214.769458 -16.246804) (xy 214.729041 -16.371253) (xy 214.681074 -16.492992)
			(xy 214.625739 -16.611563) (xy 214.563244 -16.726521) (xy 214.493823 -16.837434) (xy 214.417737 -16.943886)
			(xy 214.396544 -16.969994) (xy 245.948207 -16.969994) (xy 245.952212 -16.882086) (xy 245.964195 -16.794906)
			(xy 245.984055 -16.709177) (xy 246.01163 -16.625609) (xy 246.046689 -16.544895) (xy 246.088942 -16.467703)
			(xy 246.13804 -16.394674) (xy 246.193576 -16.326412) (xy 246.255088 -16.263482) (xy 246.322069 -16.206408)
			(xy 246.393962 -16.15566) (xy 246.470171 -16.11166) (xy 246.550066 -16.074773) (xy 246.632985 -16.045304)
			(xy 246.71824 -16.023497) (xy 246.805124 -16.009533) (xy 246.892918 -16.003527) (xy 246.980895 -16.005531)
			(xy 247.068325 -16.015526) (xy 247.154484 -16.03343) (xy 247.238658 -16.059094) (xy 247.320149 -16.092307)
			(xy 247.398283 -16.132793) (xy 247.472411 -16.180215) (xy 247.541919 -16.234182) (xy 247.606233 -16.294247)
			(xy 247.664817 -16.359911) (xy 247.717188 -16.43063) (xy 247.762911 -16.505818) (xy 247.801608 -16.584853)
			(xy 247.832957 -16.667079) (xy 247.856699 -16.751815) (xy 247.872637 -16.838359) (xy 247.880639 -16.925994)
			(xy 247.88114 -16.969994) (xy 247.880639 -17.013994) (xy 247.872637 -17.101629) (xy 247.856699 -17.188173)
			(xy 247.832957 -17.272909) (xy 247.801608 -17.355135) (xy 247.762911 -17.43417) (xy 247.717188 -17.509358)
			(xy 247.664817 -17.580077) (xy 247.606233 -17.645741) (xy 247.541919 -17.705806) (xy 247.472411 -17.759773)
			(xy 247.398283 -17.807195) (xy 247.320149 -17.847681) (xy 247.238658 -17.880894) (xy 247.154484 -17.906558)
			(xy 247.068325 -17.924462) (xy 246.980895 -17.934457) (xy 246.892918 -17.936461) (xy 246.805124 -17.930455)
			(xy 246.71824 -17.916491) (xy 246.632985 -17.894684) (xy 246.550066 -17.865215) (xy 246.470171 -17.828328)
			(xy 246.393962 -17.784328) (xy 246.322069 -17.73358) (xy 246.255088 -17.676506) (xy 246.193576 -17.613576)
			(xy 246.13804 -17.545314) (xy 246.088942 -17.472285) (xy 246.046689 -17.395093) (xy 246.01163 -17.314379)
			(xy 245.984055 -17.230811) (xy 245.964195 -17.145082) (xy 245.952212 -17.057902) (xy 245.948207 -16.969994)
			(xy 214.396544 -16.969994) (xy 214.335271 -17.045476) (xy 214.246737 -17.141823) (xy 214.152466 -17.232564)
			(xy 214.052812 -17.317359) (xy 213.948151 -17.39589) (xy 213.91219 -17.419574) (xy 218.384118 -17.419574)
			(xy 218.388189 -17.363952) (xy 218.400315 -17.309515) (xy 218.420238 -17.257424) (xy 218.447534 -17.208789)
			(xy 218.48162 -17.164646) (xy 218.521769 -17.125937) (xy 218.567127 -17.093486) (xy 218.616727 -17.067985)
			(xy 218.669511 -17.049978) (xy 218.724354 -17.039848) (xy 218.780088 -17.037811) (xy 218.835525 -17.043911)
			(xy 218.889482 -17.058017) (xy 218.940811 -17.079829) (xy 218.988417 -17.108883) (xy 219.031285 -17.144558)
			(xy 219.068502 -17.186095) (xy 219.099275 -17.232608) (xy 219.122947 -17.283105) (xy 219.139015 -17.336512)
			(xy 219.147135 -17.391688) (xy 219.147644 -17.419574) (xy 219.147135 -17.44746) (xy 219.139015 -17.502636)
			(xy 219.122947 -17.556043) (xy 219.099275 -17.60654) (xy 219.068502 -17.653053) (xy 219.031285 -17.69459)
			(xy 218.988417 -17.730265) (xy 218.940811 -17.759319) (xy 218.889482 -17.781131) (xy 218.835525 -17.795237)
			(xy 218.780088 -17.801337) (xy 218.724354 -17.7993) (xy 218.669511 -17.78917) (xy 218.616727 -17.771163)
			(xy 218.567127 -17.745662) (xy 218.521769 -17.713211) (xy 218.48162 -17.674502) (xy 218.447534 -17.630359)
			(xy 218.420238 -17.581724) (xy 218.400315 -17.529633) (xy 218.388189 -17.475196) (xy 218.384118 -17.419574)
			(xy 213.91219 -17.419574) (xy 213.838874 -17.46786) (xy 213.725394 -17.533001) (xy 213.608136 -17.591066)
			(xy 213.48754 -17.641838) (xy 213.364061 -17.685126) (xy 213.238161 -17.720768) (xy 213.110314 -17.748629)
			(xy 212.981001 -17.768605) (xy 212.850706 -17.78062) (xy 212.71992 -17.78463) (xy 212.589134 -17.78062)
			(xy 212.458839 -17.768605) (xy 212.329526 -17.748629) (xy 212.201679 -17.720768) (xy 212.075779 -17.685126)
			(xy 211.9523 -17.641838) (xy 211.831704 -17.591066) (xy 211.714446 -17.533001) (xy 211.600966 -17.46786)
			(xy 211.491689 -17.39589) (xy 211.387028 -17.317359) (xy 211.287374 -17.232564) (xy 211.193103 -17.141823)
			(xy 211.104569 -17.045476) (xy 211.022103 -16.943886) (xy 210.946017 -16.837434) (xy 210.876596 -16.726521)
			(xy 210.814101 -16.611563) (xy 210.758766 -16.492992) (xy 210.710799 -16.371253) (xy 210.670382 -16.246804)
			(xy 210.637665 -16.120113) (xy 210.612771 -15.991656) (xy 210.595795 -15.861914) (xy 210.586799 -15.731376)
			(xy 210.585812 -15.665958) (xy 210.585812 -15.649702) (xy 210.586303 -15.585401) (xy 210.594066 -15.457032)
			(xy 210.609546 -15.329365) (xy 210.632687 -15.202861) (xy 210.663405 -15.07798) (xy 210.701588 -14.955177)
			(xy 210.747097 -14.834895) (xy 210.799768 -14.717573) (xy 210.829144 -14.660372) (xy 210.830668 -14.657324)
			(xy 210.832812 -14.652126) (xy 210.835002 -14.641102) (xy 210.834986 -14.63548) (xy 210.834478 -14.622018)
			(xy 210.818222 -14.595094) (xy 210.818222 -14.594586) (xy 210.782154 -14.535658) (xy 210.778599 -14.530155)
			(xy 210.769211 -14.521026) (xy 210.763612 -14.517624) (xy 210.758278 -14.51483) (xy 210.75015 -14.512798)
			(xy 210.739228 -14.511528) (xy 201.177906 -14.511528) (xy 201.167835 -14.511107) (xy 201.149226 -14.503397)
			(xy 201.141838 -14.496542) (xy 200.427844 -13.782548) (xy 200.421001 -13.775149) (xy 200.413279 -13.75655)
			(xy 200.412858 -13.74648) (xy 200.412858 -1.941576) (xy 200.412695 -1.935565) (xy 200.409879 -1.923879)
			(xy 200.40727 -1.918462) (xy 200.405428 -1.914989) (xy 200.400831 -1.908614) (xy 200.398126 -1.905762)
			(xy 199.873108 -1.380744) (xy 199.870258 -1.378037) (xy 199.86388 -1.373443) (xy 199.860408 -1.3716)
			(xy 199.85498 -1.369022) (xy 199.8433 -1.36621) (xy 199.837294 -1.366012) (xy 188.098938 -1.366012)
			(xy 188.092929 -1.366181) (xy 188.081248 -1.369008) (xy 188.075824 -1.3716) (xy 188.072348 -1.373437)
			(xy 188.065965 -1.378027) (xy 188.063124 -1.380744) (xy 187.59551 -1.848358) (xy 187.592803 -1.851208)
			(xy 187.588208 -1.857585) (xy 187.586366 -1.861058) (xy 187.583786 -1.866486) (xy 187.580968 -1.878165)
			(xy 187.580778 -1.884172) (xy 187.580778 -13.649198) (xy 187.58101 -13.656467) (xy 187.585147 -13.670403)
			(xy 187.588906 -13.67663) (xy 187.606432 -13.704316) (xy 187.6171 -13.71346) (xy 187.623704 -13.716508)
			(xy 187.680749 -13.743684) (xy 187.791866 -13.803871) (xy 187.899226 -13.870529) (xy 188.002454 -13.943424)
			(xy 188.101186 -14.0223) (xy 188.187774 -14.100302) (xy 193.34302 -14.100302) (xy 193.347091 -14.04468)
			(xy 193.359217 -13.990243) (xy 193.37914 -13.938152) (xy 193.406436 -13.889517) (xy 193.440522 -13.845374)
			(xy 193.480671 -13.806665) (xy 193.526029 -13.774214) (xy 193.575629 -13.748713) (xy 193.628413 -13.730706)
			(xy 193.683256 -13.720576) (xy 193.73899 -13.718539) (xy 193.794427 -13.724639) (xy 193.848384 -13.738745)
			(xy 193.899713 -13.760557) (xy 193.947319 -13.789611) (xy 193.990187 -13.825286) (xy 194.027404 -13.866823)
			(xy 194.058177 -13.913336) (xy 194.081849 -13.963833) (xy 194.097917 -14.01724) (xy 194.106037 -14.072416)
			(xy 194.106546 -14.100302) (xy 194.106037 -14.128188) (xy 194.097917 -14.183364) (xy 194.081849 -14.236771)
			(xy 194.058177 -14.287268) (xy 194.027404 -14.333781) (xy 193.990187 -14.375318) (xy 193.947319 -14.410993)
			(xy 193.899713 -14.440047) (xy 193.848384 -14.461859) (xy 193.794427 -14.475965) (xy 193.73899 -14.482065)
			(xy 193.683256 -14.480028) (xy 193.628413 -14.469898) (xy 193.575629 -14.451891) (xy 193.526029 -14.42639)
			(xy 193.480671 -14.393939) (xy 193.440522 -14.35523) (xy 193.406436 -14.311087) (xy 193.37914 -14.262452)
			(xy 193.359217 -14.210361) (xy 193.347091 -14.155924) (xy 193.34302 -14.100302) (xy 188.187774 -14.100302)
			(xy 188.195077 -14.106881) (xy 188.283798 -14.196871) (xy 188.367038 -14.291953) (xy 188.444505 -14.391795)
			(xy 188.515927 -14.496047) (xy 188.581055 -14.604343) (xy 188.610748 -14.660118) (xy 188.613288 -14.665198)
			(xy 188.61659 -14.671548) (xy 188.645217 -14.728051) (xy 188.696511 -14.843879) (xy 188.740844 -14.962546)
			(xy 188.77806 -15.083634) (xy 188.808027 -15.206717) (xy 188.830639 -15.33136) (xy 188.838629 -15.397554)
			(xy 194.004357 -15.397554) (xy 194.004357 -15.343046) (xy 194.012115 -15.289092) (xy 194.027473 -15.236791)
			(xy 194.050118 -15.187209) (xy 194.07959 -15.141354) (xy 194.115287 -15.10016) (xy 194.156484 -15.064467)
			(xy 194.202342 -15.035) (xy 194.251927 -15.01236) (xy 194.304229 -14.997007) (xy 194.358184 -14.989255)
			(xy 194.385438 -14.988794) (xy 194.411675 -14.989228) (xy 194.463652 -14.996429) (xy 194.51415 -15.010688)
			(xy 194.562217 -15.031737) (xy 194.606943 -15.059178) (xy 194.647484 -15.092493) (xy 194.6656 -15.111476)
			(xy 194.665854 -15.11173) (xy 194.673588 -15.11911) (xy 194.69327 -15.127385) (xy 194.703954 -15.127732)
			(xy 194.791838 -15.125446) (xy 194.811396 -15.116048) (xy 194.818508 -15.107412) (xy 194.836689 -15.086234)
			(xy 194.878235 -15.048961) (xy 194.924771 -15.018143) (xy 194.975302 -14.994437) (xy 195.028749 -14.97835)
			(xy 195.08397 -14.970225) (xy 195.111878 -14.969744) (xy 195.139128 -14.970302) (xy 195.193075 -14.978055)
			(xy 195.245369 -14.993407) (xy 195.294946 -15.016046) (xy 195.340796 -15.045509) (xy 195.381986 -15.081199)
			(xy 195.417677 -15.122387) (xy 195.447144 -15.168235) (xy 195.469785 -15.21781) (xy 195.48514 -15.270104)
			(xy 195.492897 -15.32405) (xy 195.492897 -15.37855) (xy 195.48514 -15.432497) (xy 195.469785 -15.48479)
			(xy 195.447144 -15.534365) (xy 195.417677 -15.580213) (xy 195.381986 -15.621401) (xy 195.340796 -15.657091)
			(xy 195.294946 -15.686554) (xy 195.245369 -15.709193) (xy 195.193075 -15.724545) (xy 195.139128 -15.732298)
			(xy 195.111878 -15.73276) (xy 195.085641 -15.73233) (xy 195.033663 -15.725131) (xy 194.983164 -15.710872)
			(xy 194.935097 -15.689822) (xy 194.890371 -15.662379) (xy 194.849831 -15.629062) (xy 194.831716 -15.610078)
			(xy 194.831462 -15.609824) (xy 194.823728 -15.602445) (xy 194.804046 -15.594171) (xy 194.793362 -15.593822)
			(xy 194.705478 -15.596108) (xy 194.68592 -15.605506) (xy 194.678808 -15.614142) (xy 194.660608 -15.635303)
			(xy 194.619067 -15.672579) (xy 194.572535 -15.703401) (xy 194.522008 -15.72711) (xy 194.468564 -15.7432)
			(xy 194.413345 -15.751328) (xy 194.385438 -15.75181) (xy 194.358184 -15.751345) (xy 194.304229 -15.743593)
			(xy 194.251927 -15.72824) (xy 194.202342 -15.7056) (xy 194.156484 -15.676133) (xy 194.115287 -15.64044)
			(xy 194.07959 -15.599246) (xy 194.050118 -15.553391) (xy 194.027473 -15.503809) (xy 194.012115 -15.451508)
			(xy 194.004357 -15.397554) (xy 188.838629 -15.397554) (xy 188.845819 -15.457125) (xy 188.85351 -15.58357)
			(xy 188.85408 -15.646908) (xy 188.85408 -15.665958) (xy 188.853093 -15.731376) (xy 188.844097 -15.861914)
			(xy 188.827121 -15.991656) (xy 188.802227 -16.120113) (xy 188.76951 -16.246804) (xy 188.729093 -16.371253)
			(xy 188.681126 -16.492992) (xy 188.625791 -16.611563) (xy 188.563296 -16.726521) (xy 188.493875 -16.837434)
			(xy 188.417789 -16.943886) (xy 188.396596 -16.969994) (xy 207.848207 -16.969994) (xy 207.852212 -16.882086)
			(xy 207.864195 -16.794906) (xy 207.884055 -16.709177) (xy 207.91163 -16.625609) (xy 207.946689 -16.544895)
			(xy 207.988942 -16.467703) (xy 208.03804 -16.394674) (xy 208.093576 -16.326412) (xy 208.155088 -16.263482)
			(xy 208.222069 -16.206408) (xy 208.293962 -16.15566) (xy 208.370171 -16.11166) (xy 208.450066 -16.074773)
			(xy 208.532985 -16.045304) (xy 208.61824 -16.023497) (xy 208.705124 -16.009533) (xy 208.792918 -16.003527)
			(xy 208.880895 -16.005531) (xy 208.968325 -16.015526) (xy 209.054484 -16.03343) (xy 209.138658 -16.059094)
			(xy 209.220149 -16.092307) (xy 209.298283 -16.132793) (xy 209.372411 -16.180215) (xy 209.441919 -16.234182)
			(xy 209.506233 -16.294247) (xy 209.564817 -16.359911) (xy 209.617188 -16.43063) (xy 209.662911 -16.505818)
			(xy 209.701608 -16.584853) (xy 209.732957 -16.667079) (xy 209.756699 -16.751815) (xy 209.772637 -16.838359)
			(xy 209.780639 -16.925994) (xy 209.78114 -16.969994) (xy 209.780639 -17.013994) (xy 209.772637 -17.101629)
			(xy 209.756699 -17.188173) (xy 209.732957 -17.272909) (xy 209.701608 -17.355135) (xy 209.662911 -17.43417)
			(xy 209.617188 -17.509358) (xy 209.564817 -17.580077) (xy 209.506233 -17.645741) (xy 209.441919 -17.705806)
			(xy 209.372411 -17.759773) (xy 209.298283 -17.807195) (xy 209.220149 -17.847681) (xy 209.138658 -17.880894)
			(xy 209.054484 -17.906558) (xy 208.968325 -17.924462) (xy 208.880895 -17.934457) (xy 208.792918 -17.936461)
			(xy 208.705124 -17.930455) (xy 208.61824 -17.916491) (xy 208.532985 -17.894684) (xy 208.450066 -17.865215)
			(xy 208.370171 -17.828328) (xy 208.293962 -17.784328) (xy 208.222069 -17.73358) (xy 208.155088 -17.676506)
			(xy 208.093576 -17.613576) (xy 208.03804 -17.545314) (xy 207.988942 -17.472285) (xy 207.946689 -17.395093)
			(xy 207.91163 -17.314379) (xy 207.884055 -17.230811) (xy 207.864195 -17.145082) (xy 207.852212 -17.057902)
			(xy 207.848207 -16.969994) (xy 188.396596 -16.969994) (xy 188.335323 -17.045476) (xy 188.246789 -17.141823)
			(xy 188.152518 -17.232564) (xy 188.052864 -17.317359) (xy 187.948203 -17.39589) (xy 187.912242 -17.419574)
			(xy 192.38417 -17.419574) (xy 192.388241 -17.363952) (xy 192.400367 -17.309515) (xy 192.42029 -17.257424)
			(xy 192.447586 -17.208789) (xy 192.481672 -17.164646) (xy 192.521821 -17.125937) (xy 192.567179 -17.093486)
			(xy 192.616779 -17.067985) (xy 192.669563 -17.049978) (xy 192.724406 -17.039848) (xy 192.78014 -17.037811)
			(xy 192.835577 -17.043911) (xy 192.889534 -17.058017) (xy 192.940863 -17.079829) (xy 192.988469 -17.108883)
			(xy 193.031337 -17.144558) (xy 193.068554 -17.186095) (xy 193.099327 -17.232608) (xy 193.122999 -17.283105)
			(xy 193.139067 -17.336512) (xy 193.147187 -17.391688) (xy 193.147696 -17.419574) (xy 193.147187 -17.44746)
			(xy 193.139067 -17.502636) (xy 193.122999 -17.556043) (xy 193.099327 -17.60654) (xy 193.068554 -17.653053)
			(xy 193.031337 -17.69459) (xy 192.988469 -17.730265) (xy 192.940863 -17.759319) (xy 192.889534 -17.781131)
			(xy 192.835577 -17.795237) (xy 192.78014 -17.801337) (xy 192.724406 -17.7993) (xy 192.669563 -17.78917)
			(xy 192.616779 -17.771163) (xy 192.567179 -17.745662) (xy 192.521821 -17.713211) (xy 192.481672 -17.674502)
			(xy 192.447586 -17.630359) (xy 192.42029 -17.581724) (xy 192.400367 -17.529633) (xy 192.388241 -17.475196)
			(xy 192.38417 -17.419574) (xy 187.912242 -17.419574) (xy 187.838926 -17.46786) (xy 187.725446 -17.533001)
			(xy 187.608188 -17.591066) (xy 187.487592 -17.641838) (xy 187.364113 -17.685126) (xy 187.238213 -17.720768)
			(xy 187.110366 -17.748629) (xy 186.981053 -17.768605) (xy 186.850758 -17.78062) (xy 186.719972 -17.78463)
			(xy 186.589186 -17.78062) (xy 186.458891 -17.768605) (xy 186.329578 -17.748629) (xy 186.201731 -17.720768)
			(xy 186.075831 -17.685126) (xy 185.952352 -17.641838) (xy 185.831756 -17.591066) (xy 185.714498 -17.533001)
			(xy 185.601018 -17.46786) (xy 185.491741 -17.39589) (xy 185.38708 -17.317359) (xy 185.287426 -17.232564)
			(xy 185.193155 -17.141823) (xy 185.104621 -17.045476) (xy 185.022155 -16.943886) (xy 184.946069 -16.837434)
			(xy 184.876648 -16.726521) (xy 184.814153 -16.611563) (xy 184.758818 -16.492992) (xy 184.710851 -16.371253)
			(xy 184.670434 -16.246804) (xy 184.637717 -16.120113) (xy 184.612823 -15.991656) (xy 184.595847 -15.861914)
			(xy 184.586851 -15.731376) (xy 184.585864 -15.665958) (xy 184.585864 -15.649702) (xy 184.586355 -15.585401)
			(xy 184.594118 -15.457032) (xy 184.609598 -15.329364) (xy 184.632738 -15.20286) (xy 184.663455 -15.07798)
			(xy 184.701637 -14.955175) (xy 184.747146 -14.834894) (xy 184.799816 -14.717571) (xy 184.829196 -14.660372)
			(xy 184.83072 -14.657324) (xy 184.832865 -14.652127) (xy 184.835057 -14.641102) (xy 184.835038 -14.63548)
			(xy 184.83453 -14.622018) (xy 184.818274 -14.595094) (xy 184.818274 -14.594586) (xy 184.782206 -14.535658)
			(xy 184.778654 -14.530152) (xy 184.76927 -14.521014) (xy 184.763664 -14.517624) (xy 184.75833 -14.51483)
			(xy 184.750202 -14.512798) (xy 184.73928 -14.511528) (xy 175.177958 -14.511528) (xy 175.167891 -14.511098)
			(xy 175.149295 -14.503376) (xy 175.14189 -14.496542) (xy 174.427896 -13.782548) (xy 174.421058 -13.775146)
			(xy 174.413343 -13.756548) (xy 174.41291 -13.74648) (xy 174.41291 -1.941576) (xy 174.412582 -1.93297)
			(xy 174.406881 -1.91673) (xy 174.401734 -1.909826) (xy 174.401226 -1.909318) (xy 174.398178 -1.905762)
			(xy 173.87316 -1.380744) (xy 173.869427 -1.377227) (xy 173.86085 -1.371605) (xy 173.856142 -1.369568)
			(xy 173.847506 -1.366012) (xy 162.09899 -1.366012) (xy 162.090389 -1.366354) (xy 162.074168 -1.372079)
			(xy 162.06724 -1.377188) (xy 162.066732 -1.377696) (xy 162.063176 -1.380744) (xy 161.595562 -1.848358)
			(xy 161.592045 -1.852091) (xy 161.586424 -1.860669) (xy 161.584386 -1.865376) (xy 161.58083 -1.874012)
			(xy 161.58083 -13.649452) (xy 161.581592 -13.658088) (xy 161.582412 -13.662267) (xy 161.585226 -13.670305)
			(xy 161.58718 -13.67409) (xy 161.603436 -13.699236) (xy 161.609532 -13.706602) (xy 161.617152 -13.71346)
			(xy 161.62401 -13.716508) (xy 161.681042 -13.743689) (xy 161.792134 -13.803886) (xy 161.899469 -13.870552)
			(xy 162.002671 -13.943452) (xy 162.101378 -14.022331) (xy 162.195245 -14.106913) (xy 162.283942 -14.196902)
			(xy 162.367159 -14.291981) (xy 162.444604 -14.391818) (xy 162.516005 -14.496063) (xy 162.581112 -14.60435)
			(xy 162.6108 -14.660118) (xy 162.61334 -14.665198) (xy 162.616642 -14.671548) (xy 162.64527 -14.72805)
			(xy 162.648482 -14.735302) (xy 166.62476 -14.735302) (xy 166.628831 -14.67968) (xy 166.640957 -14.625243)
			(xy 166.66088 -14.573152) (xy 166.688176 -14.524517) (xy 166.722262 -14.480374) (xy 166.762411 -14.441665)
			(xy 166.807769 -14.409214) (xy 166.857369 -14.383713) (xy 166.910153 -14.365706) (xy 166.964996 -14.355576)
			(xy 167.02073 -14.353539) (xy 167.076167 -14.359639) (xy 167.130124 -14.373745) (xy 167.181453 -14.395557)
			(xy 167.229059 -14.424611) (xy 167.271927 -14.460286) (xy 167.309144 -14.501823) (xy 167.339917 -14.548336)
			(xy 167.363589 -14.598833) (xy 167.379657 -14.65224) (xy 167.387777 -14.707416) (xy 167.388286 -14.735302)
			(xy 167.387777 -14.763188) (xy 167.379657 -14.818364) (xy 167.363589 -14.871771) (xy 167.339917 -14.922268)
			(xy 167.309144 -14.968781) (xy 167.271927 -15.010318) (xy 167.229059 -15.045993) (xy 167.181453 -15.075047)
			(xy 167.130124 -15.096859) (xy 167.076167 -15.110965) (xy 167.02073 -15.117065) (xy 166.964996 -15.115028)
			(xy 166.910153 -15.104898) (xy 166.857369 -15.086891) (xy 166.807769 -15.06139) (xy 166.762411 -15.028939)
			(xy 166.722262 -14.99023) (xy 166.688176 -14.946087) (xy 166.66088 -14.897452) (xy 166.640957 -14.845361)
			(xy 166.628831 -14.790924) (xy 166.62476 -14.735302) (xy 162.648482 -14.735302) (xy 162.696565 -14.843878)
			(xy 162.740899 -14.962546) (xy 162.778115 -15.083634) (xy 162.808083 -15.206716) (xy 162.830696 -15.33136)
			(xy 162.838685 -15.397551) (xy 168.00448 -15.397551) (xy 168.00448 -15.343049) (xy 168.012236 -15.289103)
			(xy 168.02759 -15.236809) (xy 168.050231 -15.187233) (xy 168.079696 -15.141383) (xy 168.115386 -15.100193)
			(xy 168.156575 -15.064502) (xy 168.202424 -15.035036) (xy 168.252 -15.012394) (xy 168.304293 -14.997038)
			(xy 168.358239 -14.98928) (xy 168.38549 -14.988794) (xy 168.411726 -14.98926) (xy 168.463701 -14.996454)
			(xy 168.514199 -15.010707) (xy 168.562266 -15.03175) (xy 168.606993 -15.059186) (xy 168.647535 -15.092495)
			(xy 168.665652 -15.111476) (xy 168.665906 -15.11173) (xy 168.673621 -15.119134) (xy 168.693318 -15.127396)
			(xy 168.704006 -15.127732) (xy 168.79189 -15.125446) (xy 168.811448 -15.116048) (xy 168.81856 -15.107412)
			(xy 168.836766 -15.086257) (xy 168.878307 -15.048983) (xy 168.924838 -15.018161) (xy 168.975364 -14.994451)
			(xy 169.028806 -14.978359) (xy 169.084024 -14.970228) (xy 169.11193 -14.969744) (xy 169.139176 -14.970328)
			(xy 169.193114 -14.978087) (xy 169.245399 -14.993443) (xy 169.294966 -15.016083) (xy 169.340807 -15.045546)
			(xy 169.381988 -15.081233) (xy 169.417672 -15.122418) (xy 169.447131 -15.168261) (xy 169.469768 -15.21783)
			(xy 169.485119 -15.270115) (xy 169.492874 -15.324054) (xy 169.492874 -15.378546) (xy 169.485119 -15.432485)
			(xy 169.469768 -15.48477) (xy 169.447131 -15.534339) (xy 169.417672 -15.580182) (xy 169.381988 -15.621367)
			(xy 169.340807 -15.657054) (xy 169.294966 -15.686517) (xy 169.245399 -15.709157) (xy 169.193114 -15.724513)
			(xy 169.139176 -15.732272) (xy 169.11193 -15.73276) (xy 169.085692 -15.732362) (xy 169.033713 -15.725156)
			(xy 168.983213 -15.710891) (xy 168.935146 -15.689835) (xy 168.890421 -15.662387) (xy 168.849882 -15.629065)
			(xy 168.831768 -15.610078) (xy 168.831514 -15.609824) (xy 168.823798 -15.602423) (xy 168.804102 -15.594161)
			(xy 168.793414 -15.593822) (xy 168.70553 -15.596108) (xy 168.685972 -15.605506) (xy 168.67886 -15.614142)
			(xy 168.660632 -15.635278) (xy 168.619097 -15.672556) (xy 168.572571 -15.703381) (xy 168.522049 -15.727094)
			(xy 168.46861 -15.74319) (xy 168.413395 -15.751324) (xy 168.38549 -15.75181) (xy 168.358239 -15.75132)
			(xy 168.304293 -15.743562) (xy 168.252 -15.728206) (xy 168.202424 -15.705564) (xy 168.156575 -15.676098)
			(xy 168.115386 -15.640407) (xy 168.079696 -15.599217) (xy 168.050231 -15.553367) (xy 168.02759 -15.503791)
			(xy 168.012236 -15.451497) (xy 168.00448 -15.397551) (xy 162.838685 -15.397551) (xy 162.845876 -15.457125)
			(xy 162.853568 -15.58357) (xy 162.854132 -15.646908) (xy 162.854132 -15.665958) (xy 162.853145 -15.731376)
			(xy 162.844149 -15.861914) (xy 162.827173 -15.991656) (xy 162.802279 -16.120113) (xy 162.769562 -16.246804)
			(xy 162.729145 -16.371253) (xy 162.681178 -16.492992) (xy 162.625843 -16.611563) (xy 162.563348 -16.726521)
			(xy 162.493927 -16.837434) (xy 162.417841 -16.943886) (xy 162.396648 -16.969994) (xy 181.848259 -16.969994)
			(xy 181.852264 -16.882086) (xy 181.864247 -16.794906) (xy 181.884107 -16.709177) (xy 181.911682 -16.625609)
			(xy 181.946741 -16.544895) (xy 181.988994 -16.467703) (xy 182.038092 -16.394674) (xy 182.093628 -16.326412)
			(xy 182.15514 -16.263482) (xy 182.222121 -16.206408) (xy 182.294014 -16.15566) (xy 182.370223 -16.11166)
			(xy 182.450118 -16.074773) (xy 182.533037 -16.045304) (xy 182.618292 -16.023497) (xy 182.705176 -16.009533)
			(xy 182.79297 -16.003527) (xy 182.880947 -16.005531) (xy 182.968377 -16.015526) (xy 183.054536 -16.03343)
			(xy 183.13871 -16.059094) (xy 183.220201 -16.092307) (xy 183.298335 -16.132793) (xy 183.372463 -16.180215)
			(xy 183.441971 -16.234182) (xy 183.506285 -16.294247) (xy 183.564869 -16.359911) (xy 183.61724 -16.43063)
			(xy 183.662963 -16.505818) (xy 183.70166 -16.584853) (xy 183.733009 -16.667079) (xy 183.756751 -16.751815)
			(xy 183.772689 -16.838359) (xy 183.780691 -16.925994) (xy 183.781192 -16.969994) (xy 183.780691 -17.013994)
			(xy 183.772689 -17.101629) (xy 183.756751 -17.188173) (xy 183.733009 -17.272909) (xy 183.70166 -17.355135)
			(xy 183.662963 -17.43417) (xy 183.61724 -17.509358) (xy 183.564869 -17.580077) (xy 183.506285 -17.645741)
			(xy 183.441971 -17.705806) (xy 183.372463 -17.759773) (xy 183.298335 -17.807195) (xy 183.220201 -17.847681)
			(xy 183.13871 -17.880894) (xy 183.054536 -17.906558) (xy 182.968377 -17.924462) (xy 182.880947 -17.934457)
			(xy 182.79297 -17.936461) (xy 182.705176 -17.930455) (xy 182.618292 -17.916491) (xy 182.533037 -17.894684)
			(xy 182.450118 -17.865215) (xy 182.370223 -17.828328) (xy 182.294014 -17.784328) (xy 182.222121 -17.73358)
			(xy 182.15514 -17.676506) (xy 182.093628 -17.613576) (xy 182.038092 -17.545314) (xy 181.988994 -17.472285)
			(xy 181.946741 -17.395093) (xy 181.911682 -17.314379) (xy 181.884107 -17.230811) (xy 181.864247 -17.145082)
			(xy 181.852264 -17.057902) (xy 181.848259 -16.969994) (xy 162.396648 -16.969994) (xy 162.335375 -17.045476)
			(xy 162.246841 -17.141823) (xy 162.15257 -17.232564) (xy 162.052916 -17.317359) (xy 161.948255 -17.39589)
			(xy 161.912294 -17.419574) (xy 166.384222 -17.419574) (xy 166.388293 -17.363952) (xy 166.400419 -17.309515)
			(xy 166.420342 -17.257424) (xy 166.447638 -17.208789) (xy 166.481724 -17.164646) (xy 166.521873 -17.125937)
			(xy 166.567231 -17.093486) (xy 166.616831 -17.067985) (xy 166.669615 -17.049978) (xy 166.724458 -17.039848)
			(xy 166.780192 -17.037811) (xy 166.835629 -17.043911) (xy 166.889586 -17.058017) (xy 166.940915 -17.079829)
			(xy 166.988521 -17.108883) (xy 167.031389 -17.144558) (xy 167.068606 -17.186095) (xy 167.099379 -17.232608)
			(xy 167.123051 -17.283105) (xy 167.139119 -17.336512) (xy 167.147239 -17.391688) (xy 167.147748 -17.419574)
			(xy 167.147239 -17.44746) (xy 167.139119 -17.502636) (xy 167.123051 -17.556043) (xy 167.099379 -17.60654)
			(xy 167.068606 -17.653053) (xy 167.031389 -17.69459) (xy 166.988521 -17.730265) (xy 166.940915 -17.759319)
			(xy 166.889586 -17.781131) (xy 166.835629 -17.795237) (xy 166.780192 -17.801337) (xy 166.724458 -17.7993)
			(xy 166.669615 -17.78917) (xy 166.616831 -17.771163) (xy 166.567231 -17.745662) (xy 166.521873 -17.713211)
			(xy 166.481724 -17.674502) (xy 166.447638 -17.630359) (xy 166.420342 -17.581724) (xy 166.400419 -17.529633)
			(xy 166.388293 -17.475196) (xy 166.384222 -17.419574) (xy 161.912294 -17.419574) (xy 161.838978 -17.46786)
			(xy 161.725498 -17.533001) (xy 161.60824 -17.591066) (xy 161.487644 -17.641838) (xy 161.364165 -17.685126)
			(xy 161.238265 -17.720768) (xy 161.110418 -17.748629) (xy 160.981105 -17.768605) (xy 160.85081 -17.78062)
			(xy 160.720024 -17.78463) (xy 160.589238 -17.78062) (xy 160.458943 -17.768605) (xy 160.32963 -17.748629)
			(xy 160.201783 -17.720768) (xy 160.075883 -17.685126) (xy 159.952404 -17.641838) (xy 159.831808 -17.591066)
			(xy 159.71455 -17.533001) (xy 159.60107 -17.46786) (xy 159.491793 -17.39589) (xy 159.387132 -17.317359)
			(xy 159.287478 -17.232564) (xy 159.193207 -17.141823) (xy 159.104673 -17.045476) (xy 159.022207 -16.943886)
			(xy 158.946121 -16.837434) (xy 158.8767 -16.726521) (xy 158.814205 -16.611563) (xy 158.75887 -16.492992)
			(xy 158.710903 -16.371253) (xy 158.670486 -16.246804) (xy 158.637769 -16.120113) (xy 158.612875 -15.991656)
			(xy 158.595899 -15.861914) (xy 158.586903 -15.731376) (xy 158.585916 -15.665958) (xy 158.585916 -15.649702)
			(xy 158.586407 -15.585401) (xy 158.59417 -15.457032) (xy 158.60965 -15.329365) (xy 158.632791 -15.202861)
			(xy 158.663509 -15.07798) (xy 158.701692 -14.955177) (xy 158.747202 -14.834896) (xy 158.799873 -14.717574)
			(xy 158.829248 -14.660372) (xy 158.830772 -14.657324) (xy 158.832915 -14.652126) (xy 158.835105 -14.641102)
			(xy 158.83509 -14.63548) (xy 158.834582 -14.622018) (xy 158.818326 -14.595094) (xy 158.818326 -14.594586)
			(xy 158.782258 -14.535658) (xy 158.778704 -14.530155) (xy 158.769315 -14.521025) (xy 158.763716 -14.517624)
			(xy 158.758382 -14.51483) (xy 158.750254 -14.512798) (xy 158.739332 -14.511528) (xy 149.17801 -14.511528)
			(xy 149.167938 -14.511107) (xy 149.149329 -14.503399) (xy 149.141942 -14.496542) (xy 148.427948 -13.782548)
			(xy 148.421105 -13.775149) (xy 148.413382 -13.75655) (xy 148.412962 -13.74648) (xy 148.412962 -1.941576)
			(xy 148.412798 -1.935566) (xy 148.409977 -1.923881) (xy 148.407374 -1.918462) (xy 148.405533 -1.914989)
			(xy 148.400936 -1.908614) (xy 148.39823 -1.905762) (xy 147.873212 -1.380744) (xy 147.870362 -1.378037)
			(xy 147.863984 -1.373442) (xy 147.860512 -1.3716) (xy 147.855084 -1.369022) (xy 147.843405 -1.366208)
			(xy 147.837398 -1.366012) (xy 136.099042 -1.366012) (xy 136.093033 -1.36618) (xy 136.081351 -1.369006)
			(xy 136.075928 -1.3716) (xy 136.072452 -1.373437) (xy 136.066069 -1.378026) (xy 136.063228 -1.380744)
			(xy 135.595614 -1.848358) (xy 135.592907 -1.851208) (xy 135.588311 -1.857585) (xy 135.58647 -1.861058)
			(xy 135.58389 -1.866486) (xy 135.581071 -1.878165) (xy 135.580882 -1.884172) (xy 135.580882 -13.649198)
			(xy 135.581114 -13.656467) (xy 135.585251 -13.670403) (xy 135.58901 -13.67663) (xy 135.606536 -13.704316)
			(xy 135.617204 -13.71346) (xy 135.623808 -13.716508) (xy 135.680853 -13.743684) (xy 135.79197 -13.803871)
			(xy 135.89933 -13.870529) (xy 136.002557 -13.943424) (xy 136.101289 -14.022301) (xy 136.187876 -14.100302)
			(xy 141.343124 -14.100302) (xy 141.347195 -14.04468) (xy 141.359321 -13.990243) (xy 141.379244 -13.938152)
			(xy 141.40654 -13.889517) (xy 141.440626 -13.845374) (xy 141.480775 -13.806665) (xy 141.526133 -13.774214)
			(xy 141.575733 -13.748713) (xy 141.628517 -13.730706) (xy 141.68336 -13.720576) (xy 141.739094 -13.718539)
			(xy 141.794531 -13.724639) (xy 141.848488 -13.738745) (xy 141.899817 -13.760557) (xy 141.947423 -13.789611)
			(xy 141.990291 -13.825286) (xy 142.027508 -13.866823) (xy 142.058281 -13.913336) (xy 142.081953 -13.963833)
			(xy 142.098021 -14.01724) (xy 142.106141 -14.072416) (xy 142.10665 -14.100302) (xy 142.106141 -14.128188)
			(xy 142.098021 -14.183364) (xy 142.081953 -14.236771) (xy 142.058281 -14.287268) (xy 142.027508 -14.333781)
			(xy 141.990291 -14.375318) (xy 141.947423 -14.410993) (xy 141.899817 -14.440047) (xy 141.848488 -14.461859)
			(xy 141.794531 -14.475965) (xy 141.739094 -14.482065) (xy 141.68336 -14.480028) (xy 141.628517 -14.469898)
			(xy 141.575733 -14.451891) (xy 141.526133 -14.42639) (xy 141.480775 -14.393939) (xy 141.440626 -14.35523)
			(xy 141.40654 -14.311087) (xy 141.379244 -14.262452) (xy 141.359321 -14.210361) (xy 141.347195 -14.155924)
			(xy 141.343124 -14.100302) (xy 136.187876 -14.100302) (xy 136.19518 -14.106882) (xy 136.283901 -14.196871)
			(xy 136.367141 -14.291954) (xy 136.444608 -14.391796) (xy 136.51603 -14.496048) (xy 136.581157 -14.604343)
			(xy 136.610852 -14.660118) (xy 136.613392 -14.665198) (xy 136.616694 -14.671548) (xy 136.645321 -14.728051)
			(xy 136.696615 -14.843879) (xy 136.740948 -14.962546) (xy 136.778163 -15.083634) (xy 136.80813 -15.206717)
			(xy 136.830743 -15.33136) (xy 136.838732 -15.397555) (xy 142.004457 -15.397555) (xy 142.004457 -15.343045)
			(xy 142.012215 -15.289091) (xy 142.027574 -15.23679) (xy 142.050219 -15.187207) (xy 142.079691 -15.141353)
			(xy 142.115389 -15.100159) (xy 142.156586 -15.064466) (xy 142.202444 -15.034999) (xy 142.25203 -15.012359)
			(xy 142.304332 -14.997007) (xy 142.358287 -14.989254) (xy 142.385542 -14.988794) (xy 142.411779 -14.989226)
			(xy 142.463756 -14.996426) (xy 142.514254 -15.010686) (xy 142.562321 -15.031736) (xy 142.607047 -15.059178)
			(xy 142.647588 -15.092493) (xy 142.665704 -15.111476) (xy 142.665958 -15.11173) (xy 142.673691 -15.119112)
			(xy 142.693374 -15.127386) (xy 142.704058 -15.127732) (xy 142.791942 -15.125446) (xy 142.8115 -15.116048)
			(xy 142.818612 -15.107412) (xy 142.83679 -15.086232) (xy 142.878337 -15.048959) (xy 142.924874 -15.018141)
			(xy 142.975405 -14.994435) (xy 143.028853 -14.978349) (xy 143.084074 -14.970225) (xy 143.111982 -14.969744)
			(xy 143.139232 -14.970302) (xy 143.193178 -14.978056) (xy 143.245472 -14.993408) (xy 143.295048 -15.016047)
			(xy 143.340898 -15.045511) (xy 143.382087 -15.0812) (xy 143.417778 -15.122388) (xy 143.447244 -15.168236)
			(xy 143.469885 -15.217811) (xy 143.48524 -15.270104) (xy 143.492997 -15.32405) (xy 143.492997 -15.37855)
			(xy 143.48524 -15.432496) (xy 143.469885 -15.484789) (xy 143.447244 -15.534364) (xy 143.417778 -15.580212)
			(xy 143.382087 -15.6214) (xy 143.340898 -15.657089) (xy 143.295048 -15.686553) (xy 143.245472 -15.709192)
			(xy 143.193178 -15.724544) (xy 143.139232 -15.732298) (xy 143.111982 -15.73276) (xy 143.085745 -15.732327)
			(xy 143.033768 -15.725129) (xy 142.983268 -15.71087) (xy 142.935202 -15.689821) (xy 142.890475 -15.662379)
			(xy 142.849935 -15.629062) (xy 142.83182 -15.610078) (xy 142.831566 -15.609824) (xy 142.82383 -15.602446)
			(xy 142.804149 -15.594171) (xy 142.793466 -15.593822) (xy 142.705582 -15.596108) (xy 142.686024 -15.605506)
			(xy 142.678912 -15.614142) (xy 142.66071 -15.635301) (xy 142.619169 -15.672577) (xy 142.572638 -15.703399)
			(xy 142.522111 -15.727109) (xy 142.468667 -15.7432) (xy 142.413449 -15.751328) (xy 142.385542 -15.75181)
			(xy 142.358287 -15.751346) (xy 142.304332 -15.743593) (xy 142.25203 -15.728241) (xy 142.202444 -15.705601)
			(xy 142.156586 -15.676134) (xy 142.115389 -15.640441) (xy 142.079691 -15.599247) (xy 142.050219 -15.553393)
			(xy 142.027574 -15.50381) (xy 142.012215 -15.451509) (xy 142.004457 -15.397555) (xy 136.838732 -15.397555)
			(xy 136.845922 -15.457125) (xy 136.853614 -15.58357) (xy 136.854184 -15.646908) (xy 136.854184 -15.665958)
			(xy 136.853197 -15.731376) (xy 136.844201 -15.861914) (xy 136.827225 -15.991656) (xy 136.802331 -16.120113)
			(xy 136.769614 -16.246804) (xy 136.729197 -16.371253) (xy 136.68123 -16.492992) (xy 136.625895 -16.611563)
			(xy 136.5634 -16.726521) (xy 136.493979 -16.837434) (xy 136.417893 -16.943886) (xy 136.3967 -16.969994)
			(xy 155.848311 -16.969994) (xy 155.852316 -16.882086) (xy 155.864299 -16.794906) (xy 155.884159 -16.709177)
			(xy 155.911734 -16.625609) (xy 155.946793 -16.544895) (xy 155.989046 -16.467703) (xy 156.038144 -16.394674)
			(xy 156.09368 -16.326412) (xy 156.155192 -16.263482) (xy 156.222173 -16.206408) (xy 156.294066 -16.15566)
			(xy 156.370275 -16.11166) (xy 156.45017 -16.074773) (xy 156.533089 -16.045304) (xy 156.618344 -16.023497)
			(xy 156.705228 -16.009533) (xy 156.793022 -16.003527) (xy 156.880999 -16.005531) (xy 156.968429 -16.015526)
			(xy 157.054588 -16.03343) (xy 157.138762 -16.059094) (xy 157.220253 -16.092307) (xy 157.298387 -16.132793)
			(xy 157.372515 -16.180215) (xy 157.442023 -16.234182) (xy 157.506337 -16.294247) (xy 157.564921 -16.359911)
			(xy 157.617292 -16.43063) (xy 157.663015 -16.505818) (xy 157.701712 -16.584853) (xy 157.733061 -16.667079)
			(xy 157.756803 -16.751815) (xy 157.772741 -16.838359) (xy 157.780743 -16.925994) (xy 157.781244 -16.969994)
			(xy 157.780743 -17.013994) (xy 157.772741 -17.101629) (xy 157.756803 -17.188173) (xy 157.733061 -17.272909)
			(xy 157.701712 -17.355135) (xy 157.663015 -17.43417) (xy 157.617292 -17.509358) (xy 157.564921 -17.580077)
			(xy 157.506337 -17.645741) (xy 157.442023 -17.705806) (xy 157.372515 -17.759773) (xy 157.298387 -17.807195)
			(xy 157.220253 -17.847681) (xy 157.138762 -17.880894) (xy 157.054588 -17.906558) (xy 156.968429 -17.924462)
			(xy 156.880999 -17.934457) (xy 156.793022 -17.936461) (xy 156.705228 -17.930455) (xy 156.618344 -17.916491)
			(xy 156.533089 -17.894684) (xy 156.45017 -17.865215) (xy 156.370275 -17.828328) (xy 156.294066 -17.784328)
			(xy 156.222173 -17.73358) (xy 156.155192 -17.676506) (xy 156.09368 -17.613576) (xy 156.038144 -17.545314)
			(xy 155.989046 -17.472285) (xy 155.946793 -17.395093) (xy 155.911734 -17.314379) (xy 155.884159 -17.230811)
			(xy 155.864299 -17.145082) (xy 155.852316 -17.057902) (xy 155.848311 -16.969994) (xy 136.3967 -16.969994)
			(xy 136.335427 -17.045476) (xy 136.246893 -17.141823) (xy 136.152622 -17.232564) (xy 136.052968 -17.317359)
			(xy 135.948307 -17.39589) (xy 135.912346 -17.419574) (xy 140.384274 -17.419574) (xy 140.388345 -17.363952)
			(xy 140.400471 -17.309515) (xy 140.420394 -17.257424) (xy 140.44769 -17.208789) (xy 140.481776 -17.164646)
			(xy 140.521925 -17.125937) (xy 140.567283 -17.093486) (xy 140.616883 -17.067985) (xy 140.669667 -17.049978)
			(xy 140.72451 -17.039848) (xy 140.780244 -17.037811) (xy 140.835681 -17.043911) (xy 140.889638 -17.058017)
			(xy 140.940967 -17.079829) (xy 140.988573 -17.108883) (xy 141.031441 -17.144558) (xy 141.068658 -17.186095)
			(xy 141.099431 -17.232608) (xy 141.123103 -17.283105) (xy 141.139171 -17.336512) (xy 141.147291 -17.391688)
			(xy 141.1478 -17.419574) (xy 141.147291 -17.44746) (xy 141.139171 -17.502636) (xy 141.123103 -17.556043)
			(xy 141.099431 -17.60654) (xy 141.068658 -17.653053) (xy 141.031441 -17.69459) (xy 140.988573 -17.730265)
			(xy 140.940967 -17.759319) (xy 140.889638 -17.781131) (xy 140.835681 -17.795237) (xy 140.780244 -17.801337)
			(xy 140.72451 -17.7993) (xy 140.669667 -17.78917) (xy 140.616883 -17.771163) (xy 140.567283 -17.745662)
			(xy 140.521925 -17.713211) (xy 140.481776 -17.674502) (xy 140.44769 -17.630359) (xy 140.420394 -17.581724)
			(xy 140.400471 -17.529633) (xy 140.388345 -17.475196) (xy 140.384274 -17.419574) (xy 135.912346 -17.419574)
			(xy 135.83903 -17.46786) (xy 135.72555 -17.533001) (xy 135.608292 -17.591066) (xy 135.487696 -17.641838)
			(xy 135.364217 -17.685126) (xy 135.238317 -17.720768) (xy 135.11047 -17.748629) (xy 134.981157 -17.768605)
			(xy 134.850862 -17.78062) (xy 134.720076 -17.78463) (xy 134.58929 -17.78062) (xy 134.458995 -17.768605)
			(xy 134.329682 -17.748629) (xy 134.201835 -17.720768) (xy 134.075935 -17.685126) (xy 133.952456 -17.641838)
			(xy 133.83186 -17.591066) (xy 133.714602 -17.533001) (xy 133.601122 -17.46786) (xy 133.491845 -17.39589)
			(xy 133.387184 -17.317359) (xy 133.28753 -17.232564) (xy 133.193259 -17.141823) (xy 133.104725 -17.045476)
			(xy 133.022259 -16.943886) (xy 132.946173 -16.837434) (xy 132.876752 -16.726521) (xy 132.814257 -16.611563)
			(xy 132.758922 -16.492992) (xy 132.710955 -16.371253) (xy 132.670538 -16.246804) (xy 132.637821 -16.120113)
			(xy 132.612927 -15.991656) (xy 132.595951 -15.861914) (xy 132.586955 -15.731376) (xy 132.585968 -15.665958)
			(xy 132.585968 -15.649702) (xy 132.586459 -15.585401) (xy 132.594222 -15.457032) (xy 132.609702 -15.329364)
			(xy 132.632842 -15.20286) (xy 132.663559 -15.07798) (xy 132.701742 -14.955176) (xy 132.74725 -14.834894)
			(xy 132.79992 -14.717571) (xy 132.8293 -14.660372) (xy 132.830824 -14.657324) (xy 132.832969 -14.652127)
			(xy 132.835161 -14.641102) (xy 132.835142 -14.63548) (xy 132.834634 -14.622018) (xy 132.818378 -14.595094)
			(xy 132.818378 -14.594586) (xy 132.78231 -14.535658) (xy 132.778758 -14.530152) (xy 132.769375 -14.521014)
			(xy 132.763768 -14.517624) (xy 132.758434 -14.51483) (xy 132.750306 -14.512798) (xy 132.739384 -14.511528)
			(xy 123.081288 -14.511528) (xy 123.071218 -14.511103) (xy 123.052614 -14.503389) (xy 123.04522 -14.496542)
			(xy 122.614182 -14.065504) (xy 122.607326 -14.05811) (xy 122.599577 -14.039511) (xy 122.599196 -14.029436)
			(xy 122.599196 -2.55905) (xy 122.599029 -2.55304) (xy 122.596205 -2.541358) (xy 122.593608 -2.535936)
			(xy 122.591772 -2.532459) (xy 122.587184 -2.526075) (xy 122.584464 -2.523236) (xy 121.441972 -1.380744)
			(xy 121.43912 -1.378039) (xy 121.432741 -1.373448) (xy 121.429272 -1.3716) (xy 121.423845 -1.369015)
			(xy 121.412166 -1.366188) (xy 121.406158 -1.366012) (xy 97.999042 -1.366012) (xy 97.993033 -1.36618)
			(xy 97.981351 -1.369006) (xy 97.975928 -1.3716) (xy 97.972452 -1.373437) (xy 97.966069 -1.378026)
			(xy 97.963228 -1.380744) (xy 97.495614 -1.848358) (xy 97.492907 -1.851208) (xy 97.488311 -1.857585)
			(xy 97.48647 -1.861058) (xy 97.48389 -1.866486) (xy 97.481071 -1.878165) (xy 97.480882 -1.884172)
			(xy 97.480882 -5.747258) (xy 103.958388 -5.747258) (xy 103.962459 -5.691636) (xy 103.974585 -5.637199)
			(xy 103.994508 -5.585108) (xy 104.021804 -5.536473) (xy 104.05589 -5.49233) (xy 104.096039 -5.453621)
			(xy 104.141397 -5.42117) (xy 104.190997 -5.395669) (xy 104.243781 -5.377662) (xy 104.298624 -5.367532)
			(xy 104.354358 -5.365495) (xy 104.409795 -5.371595) (xy 104.463752 -5.385701) (xy 104.515081 -5.407513)
			(xy 104.562687 -5.436567) (xy 104.605555 -5.472242) (xy 104.642772 -5.513779) (xy 104.673545 -5.560292)
			(xy 104.697217 -5.610789) (xy 104.713285 -5.664196) (xy 104.721405 -5.719372) (xy 104.721914 -5.747258)
			(xy 106.926124 -5.747258) (xy 106.930195 -5.691636) (xy 106.942321 -5.637199) (xy 106.962244 -5.585108)
			(xy 106.98954 -5.536473) (xy 107.023626 -5.49233) (xy 107.063775 -5.453621) (xy 107.109133 -5.42117)
			(xy 107.158733 -5.395669) (xy 107.211517 -5.377662) (xy 107.26636 -5.367532) (xy 107.322094 -5.365495)
			(xy 107.377531 -5.371595) (xy 107.431488 -5.385701) (xy 107.482817 -5.407513) (xy 107.530423 -5.436567)
			(xy 107.573291 -5.472242) (xy 107.610508 -5.513779) (xy 107.641281 -5.560292) (xy 107.664953 -5.610789)
			(xy 107.681021 -5.664196) (xy 107.689141 -5.719372) (xy 107.68965 -5.747258) (xy 107.689141 -5.775144)
			(xy 107.681021 -5.83032) (xy 107.664953 -5.883727) (xy 107.641281 -5.934224) (xy 107.610508 -5.980737)
			(xy 107.573291 -6.022274) (xy 107.530423 -6.057949) (xy 107.482817 -6.087003) (xy 107.431488 -6.108815)
			(xy 107.377531 -6.122921) (xy 107.322094 -6.129021) (xy 107.26636 -6.126984) (xy 107.211517 -6.116854)
			(xy 107.158733 -6.098847) (xy 107.109133 -6.073346) (xy 107.063775 -6.040895) (xy 107.023626 -6.002186)
			(xy 106.98954 -5.958043) (xy 106.962244 -5.909408) (xy 106.942321 -5.857317) (xy 106.930195 -5.80288)
			(xy 106.926124 -5.747258) (xy 104.721914 -5.747258) (xy 104.721405 -5.775144) (xy 104.713285 -5.83032)
			(xy 104.697217 -5.883727) (xy 104.673545 -5.934224) (xy 104.642772 -5.980737) (xy 104.605555 -6.022274)
			(xy 104.562687 -6.057949) (xy 104.515081 -6.087003) (xy 104.463752 -6.108815) (xy 104.409795 -6.122921)
			(xy 104.354358 -6.129021) (xy 104.298624 -6.126984) (xy 104.243781 -6.116854) (xy 104.190997 -6.098847)
			(xy 104.141397 -6.073346) (xy 104.096039 -6.040895) (xy 104.05589 -6.002186) (xy 104.021804 -5.958043)
			(xy 103.994508 -5.909408) (xy 103.974585 -5.857317) (xy 103.962459 -5.80288) (xy 103.958388 -5.747258)
			(xy 97.480882 -5.747258) (xy 97.480882 -6.931152) (xy 98.156774 -6.931152) (xy 98.160845 -6.87553)
			(xy 98.172971 -6.821093) (xy 98.192894 -6.769002) (xy 98.22019 -6.720367) (xy 98.254276 -6.676224)
			(xy 98.294425 -6.637515) (xy 98.339783 -6.605064) (xy 98.389383 -6.579563) (xy 98.442167 -6.561556)
			(xy 98.49701 -6.551426) (xy 98.552744 -6.549389) (xy 98.608181 -6.555489) (xy 98.662138 -6.569595)
			(xy 98.713467 -6.591407) (xy 98.761073 -6.620461) (xy 98.803941 -6.656136) (xy 98.841158 -6.697673)
			(xy 98.871931 -6.744186) (xy 98.895603 -6.794683) (xy 98.911671 -6.84809) (xy 98.919791 -6.903266)
			(xy 98.9203 -6.931152) (xy 98.919791 -6.959038) (xy 98.916494 -6.981444) (xy 104.810812 -6.981444)
			(xy 104.814883 -6.925822) (xy 104.827009 -6.871385) (xy 104.846932 -6.819294) (xy 104.874228 -6.770659)
			(xy 104.908314 -6.726516) (xy 104.948463 -6.687807) (xy 104.993821 -6.655356) (xy 105.043421 -6.629855)
			(xy 105.096205 -6.611848) (xy 105.151048 -6.601718) (xy 105.206782 -6.599681) (xy 105.262219 -6.605781)
			(xy 105.316176 -6.619887) (xy 105.367505 -6.641699) (xy 105.415111 -6.670753) (xy 105.457979 -6.706428)
			(xy 105.487733 -6.739636) (xy 106.901994 -6.739636) (xy 106.906065 -6.684014) (xy 106.918191 -6.629577)
			(xy 106.938114 -6.577486) (xy 106.96541 -6.528851) (xy 106.999496 -6.484708) (xy 107.039645 -6.445999)
			(xy 107.085003 -6.413548) (xy 107.134603 -6.388047) (xy 107.187387 -6.37004) (xy 107.24223 -6.35991)
			(xy 107.297964 -6.357873) (xy 107.353401 -6.363973) (xy 107.407358 -6.378079) (xy 107.458687 -6.399891)
			(xy 107.506293 -6.428945) (xy 107.549161 -6.46462) (xy 107.586378 -6.506157) (xy 107.617151 -6.55267)
			(xy 107.640823 -6.603167) (xy 107.656891 -6.656574) (xy 107.665011 -6.71175) (xy 107.66552 -6.739636)
			(xy 107.665011 -6.767522) (xy 107.656891 -6.822698) (xy 107.640823 -6.876105) (xy 107.617151 -6.926602)
			(xy 107.586378 -6.973115) (xy 107.549161 -7.014652) (xy 107.506293 -7.050327) (xy 107.458687 -7.079381)
			(xy 107.407358 -7.101193) (xy 107.353401 -7.115299) (xy 107.297964 -7.121399) (xy 107.24223 -7.119362)
			(xy 107.187387 -7.109232) (xy 107.134603 -7.091225) (xy 107.085003 -7.065724) (xy 107.039645 -7.033273)
			(xy 106.999496 -6.994564) (xy 106.96541 -6.950421) (xy 106.938114 -6.901786) (xy 106.918191 -6.849695)
			(xy 106.906065 -6.795258) (xy 106.901994 -6.739636) (xy 105.487733 -6.739636) (xy 105.495196 -6.747965)
			(xy 105.525969 -6.794478) (xy 105.549641 -6.844975) (xy 105.565709 -6.898382) (xy 105.573829 -6.953558)
			(xy 105.574338 -6.981444) (xy 105.573829 -7.00933) (xy 105.565709 -7.064506) (xy 105.549641 -7.117913)
			(xy 105.525969 -7.16841) (xy 105.495196 -7.214923) (xy 105.457979 -7.25646) (xy 105.415111 -7.292135)
			(xy 105.367505 -7.321189) (xy 105.316176 -7.343001) (xy 105.262219 -7.357107) (xy 105.206782 -7.363207)
			(xy 105.151048 -7.36117) (xy 105.096205 -7.35104) (xy 105.043421 -7.333033) (xy 104.993821 -7.307532)
			(xy 104.948463 -7.275081) (xy 104.908314 -7.236372) (xy 104.874228 -7.192229) (xy 104.846932 -7.143594)
			(xy 104.827009 -7.091503) (xy 104.814883 -7.037066) (xy 104.810812 -6.981444) (xy 98.916494 -6.981444)
			(xy 98.911671 -7.014214) (xy 98.895603 -7.067621) (xy 98.871931 -7.118118) (xy 98.841158 -7.164631)
			(xy 98.803941 -7.206168) (xy 98.761073 -7.241843) (xy 98.713467 -7.270897) (xy 98.662138 -7.292709)
			(xy 98.608181 -7.306815) (xy 98.552744 -7.312915) (xy 98.49701 -7.310878) (xy 98.442167 -7.300748)
			(xy 98.389383 -7.282741) (xy 98.339783 -7.25724) (xy 98.294425 -7.224789) (xy 98.254276 -7.18608)
			(xy 98.22019 -7.141937) (xy 98.192894 -7.093302) (xy 98.172971 -7.041211) (xy 98.160845 -6.986774)
			(xy 98.156774 -6.931152) (xy 97.480882 -6.931152) (xy 97.480882 -7.355078) (xy 97.481269 -7.363433)
			(xy 97.486722 -7.379235) (xy 97.49155 -7.386066) (xy 97.497646 -7.393686) (xy 97.51187 -7.402576)
			(xy 97.520506 -7.404608) (xy 97.548367 -7.411346) (xy 97.601819 -7.432045) (xy 97.651573 -7.460508)
			(xy 97.696509 -7.496093) (xy 97.735616 -7.538) (xy 97.768015 -7.585285) (xy 97.792975 -7.636885)
			(xy 97.809935 -7.691638) (xy 97.818514 -7.748312) (xy 97.818956 -7.776972) (xy 97.818532 -7.802795)
			(xy 97.811578 -7.85397) (xy 97.797794 -7.903742) (xy 97.792246 -7.916672) (xy 98.32543 -7.916672)
			(xy 98.329501 -7.86105) (xy 98.341627 -7.806613) (xy 98.36155 -7.754522) (xy 98.388846 -7.705887)
			(xy 98.422932 -7.661744) (xy 98.463081 -7.623035) (xy 98.508439 -7.590584) (xy 98.558039 -7.565083)
			(xy 98.610823 -7.547076) (xy 98.665666 -7.536946) (xy 98.7214 -7.534909) (xy 98.776837 -7.541009)
			(xy 98.830794 -7.555115) (xy 98.882123 -7.576927) (xy 98.929729 -7.605981) (xy 98.972597 -7.641656)
			(xy 99.009814 -7.683193) (xy 99.040587 -7.729706) (xy 99.04667 -7.742682) (xy 106.920282 -7.742682)
			(xy 106.924353 -7.68706) (xy 106.936479 -7.632623) (xy 106.956402 -7.580532) (xy 106.983698 -7.531897)
			(xy 107.017784 -7.487754) (xy 107.057933 -7.449045) (xy 107.103291 -7.416594) (xy 107.152891 -7.391093)
			(xy 107.205675 -7.373086) (xy 107.260518 -7.362956) (xy 107.316252 -7.360919) (xy 107.371689 -7.367019)
			(xy 107.425646 -7.381125) (xy 107.476975 -7.402937) (xy 107.524581 -7.431991) (xy 107.567449 -7.467666)
			(xy 107.604666 -7.509203) (xy 107.635439 -7.555716) (xy 107.659111 -7.606213) (xy 107.675179 -7.65962)
			(xy 107.683299 -7.714796) (xy 107.683808 -7.742682) (xy 107.683299 -7.770568) (xy 107.675179 -7.825744)
			(xy 107.659111 -7.879151) (xy 107.635439 -7.929648) (xy 107.604666 -7.976161) (xy 107.567449 -8.017698)
			(xy 107.524581 -8.053373) (xy 107.476975 -8.082427) (xy 107.425646 -8.104239) (xy 107.371689 -8.118345)
			(xy 107.316252 -8.124445) (xy 107.260518 -8.122408) (xy 107.205675 -8.112278) (xy 107.152891 -8.094271)
			(xy 107.103291 -8.06877) (xy 107.057933 -8.036319) (xy 107.017784 -7.99761) (xy 106.983698 -7.953467)
			(xy 106.956402 -7.904832) (xy 106.936479 -7.852741) (xy 106.924353 -7.798304) (xy 106.920282 -7.742682)
			(xy 99.04667 -7.742682) (xy 99.064259 -7.780203) (xy 99.080327 -7.83361) (xy 99.088447 -7.888786)
			(xy 99.088956 -7.916672) (xy 99.088447 -7.944558) (xy 99.080327 -7.999734) (xy 99.064259 -8.053141)
			(xy 99.040587 -8.103638) (xy 99.009814 -8.150151) (xy 98.972597 -8.191688) (xy 98.929729 -8.227363)
			(xy 98.882123 -8.256417) (xy 98.830794 -8.278229) (xy 98.776837 -8.292335) (xy 98.7214 -8.298435)
			(xy 98.665666 -8.296398) (xy 98.610823 -8.286268) (xy 98.558039 -8.268261) (xy 98.508439 -8.24276)
			(xy 98.463081 -8.210309) (xy 98.422932 -8.1716) (xy 98.388846 -8.127457) (xy 98.36155 -8.078822)
			(xy 98.341627 -8.026731) (xy 98.329501 -7.972294) (xy 98.32543 -7.916672) (xy 97.792246 -7.916672)
			(xy 97.777431 -7.951203) (xy 97.75086 -7.995488) (xy 97.718565 -8.035791) (xy 97.681136 -8.071376)
			(xy 97.66046 -8.086852) (xy 97.655634 -8.090408) (xy 97.648014 -8.09879) (xy 97.633536 -8.125968)
			(xy 97.631426 -8.130916) (xy 97.62912 -8.14142) (xy 97.628964 -8.146796) (xy 97.628964 -8.20674)
			(xy 97.630742 -8.219694) (xy 97.634806 -8.230362) (xy 97.639886 -8.23976) (xy 97.648014 -8.255) (xy 97.655888 -8.26389)
			(xy 97.66046 -8.267192) (xy 97.681142 -8.282657) (xy 97.699107 -8.299752) (xy 104.750581 -8.299752)
			(xy 104.750581 -8.245248) (xy 104.758338 -8.1913) (xy 104.773694 -8.139004) (xy 104.796336 -8.089426)
			(xy 104.825804 -8.043575) (xy 104.861497 -8.002385) (xy 104.902688 -7.966694) (xy 104.94854 -7.937228)
			(xy 104.998119 -7.914588) (xy 105.050415 -7.899235) (xy 105.104364 -7.89148) (xy 105.131616 -7.891018)
			(xy 105.16089 -7.891548) (xy 105.218749 -7.900509) (xy 105.27456 -7.918202) (xy 105.327014 -7.944212)
			(xy 105.374879 -7.977929) (xy 105.417033 -8.018562) (xy 105.452485 -8.065157) (xy 105.480405 -8.11662)
			(xy 105.490772 -8.144002) (xy 105.495899 -8.156931) (xy 105.512004 -8.179593) (xy 105.53362 -8.197078)
			(xy 105.559148 -8.208091) (xy 105.586699 -8.211819) (xy 105.614236 -8.207984) (xy 105.63972 -8.196871)
			(xy 105.650792 -8.188452) (xy 105.671338 -8.172191) (xy 105.71604 -8.144855) (xy 105.76406 -8.123891)
			(xy 105.814497 -8.109692) (xy 105.866401 -8.102525) (xy 105.8926 -8.102092) (xy 105.919851 -8.102578)
			(xy 105.973799 -8.110334) (xy 106.026094 -8.125689) (xy 106.075671 -8.148331) (xy 106.121521 -8.177797)
			(xy 106.162712 -8.213488) (xy 106.198403 -8.254679) (xy 106.227869 -8.300529) (xy 106.250511 -8.350106)
			(xy 106.265866 -8.402401) (xy 106.273622 -8.456349) (xy 106.273622 -8.510851) (xy 106.265866 -8.564799)
			(xy 106.250511 -8.617094) (xy 106.227869 -8.666671) (xy 106.198403 -8.712521) (xy 106.162712 -8.753712)
			(xy 106.121521 -8.789403) (xy 106.075671 -8.818869) (xy 106.026094 -8.841511) (xy 105.973799 -8.856866)
			(xy 105.919851 -8.864622) (xy 105.8926 -8.865108) (xy 105.863327 -8.864547) (xy 105.805471 -8.85559)
			(xy 105.749661 -8.8379) (xy 105.697208 -8.811894) (xy 105.649343 -8.778181) (xy 105.607189 -8.737553)
			(xy 105.571735 -8.690963) (xy 105.543813 -8.639504) (xy 105.533444 -8.612124) (xy 105.528286 -8.599208)
			(xy 105.512189 -8.576544) (xy 105.490579 -8.559057) (xy 105.465056 -8.548042) (xy 105.437509 -8.544312)
			(xy 105.409976 -8.548145) (xy 105.384494 -8.559256) (xy 105.373424 -8.567674) (xy 105.352864 -8.583917)
			(xy 105.308167 -8.611257) (xy 105.260151 -8.632227) (xy 105.209717 -8.64643) (xy 105.157814 -8.6536)
			(xy 105.131616 -8.654034) (xy 105.104364 -8.65352) (xy 105.050415 -8.645765) (xy 104.998119 -8.630412)
			(xy 104.94854 -8.607772) (xy 104.902688 -8.578306) (xy 104.861497 -8.542615) (xy 104.825804 -8.501425)
			(xy 104.796336 -8.455574) (xy 104.773694 -8.405996) (xy 104.758338 -8.3537) (xy 104.750581 -8.299752)
			(xy 97.699107 -8.299752) (xy 97.718553 -8.318257) (xy 97.750832 -8.358567) (xy 97.777394 -8.402855)
			(xy 97.797755 -8.450314) (xy 97.811544 -8.500081) (xy 97.81851 -8.551251) (xy 97.818956 -8.577072)
			(xy 97.818443 -8.605731) (xy 97.809874 -8.662404) (xy 97.792924 -8.717158) (xy 97.767975 -8.768761)
			(xy 97.735588 -8.816051) (xy 97.696492 -8.857965) (xy 97.651566 -8.89356) (xy 97.601821 -8.922034)
			(xy 97.548377 -8.942747) (xy 97.520506 -8.949436) (xy 97.51187 -8.951468) (xy 97.497646 -8.960358)
			(xy 97.49155 -8.967978) (xy 97.486632 -8.974762) (xy 97.481169 -8.990593) (xy 97.480882 -8.998966)
			(xy 97.480882 -9.535922) (xy 100.374702 -9.535922) (xy 100.378773 -9.4803) (xy 100.390899 -9.425863)
			(xy 100.410822 -9.373772) (xy 100.438118 -9.325137) (xy 100.472204 -9.280994) (xy 100.512353 -9.242285)
			(xy 100.557711 -9.209834) (xy 100.607311 -9.184333) (xy 100.660095 -9.166326) (xy 100.714938 -9.156196)
			(xy 100.770672 -9.154159) (xy 100.826109 -9.160259) (xy 100.880066 -9.174365) (xy 100.931395 -9.196177)
			(xy 100.979001 -9.225231) (xy 101.021869 -9.260906) (xy 101.059086 -9.302443) (xy 101.089859 -9.348956)
			(xy 101.113531 -9.399453) (xy 101.129599 -9.45286) (xy 101.137719 -9.508036) (xy 101.138168 -9.53262)
			(xy 103.422702 -9.53262) (xy 103.426773 -9.476998) (xy 103.438899 -9.422561) (xy 103.458822 -9.37047)
			(xy 103.486118 -9.321835) (xy 103.520204 -9.277692) (xy 103.560353 -9.238983) (xy 103.605711 -9.206532)
			(xy 103.655311 -9.181031) (xy 103.708095 -9.163024) (xy 103.762938 -9.152894) (xy 103.818672 -9.150857)
			(xy 103.874109 -9.156957) (xy 103.928066 -9.171063) (xy 103.979395 -9.192875) (xy 104.027001 -9.221929)
			(xy 104.069869 -9.257604) (xy 104.107086 -9.299141) (xy 104.137859 -9.345654) (xy 104.161531 -9.396151)
			(xy 104.177599 -9.449558) (xy 104.185719 -9.504734) (xy 104.186228 -9.53262) (xy 104.185719 -9.560506)
			(xy 104.177599 -9.615682) (xy 104.161531 -9.669089) (xy 104.137859 -9.719586) (xy 104.107086 -9.766099)
			(xy 104.069869 -9.807636) (xy 104.027001 -9.843311) (xy 103.979395 -9.872365) (xy 103.928066 -9.894177)
			(xy 103.874109 -9.908283) (xy 103.818672 -9.914383) (xy 103.762938 -9.912346) (xy 103.708095 -9.902216)
			(xy 103.655311 -9.884209) (xy 103.605711 -9.858708) (xy 103.560353 -9.826257) (xy 103.520204 -9.787548)
			(xy 103.486118 -9.743405) (xy 103.458822 -9.69477) (xy 103.438899 -9.642679) (xy 103.426773 -9.588242)
			(xy 103.422702 -9.53262) (xy 101.138168 -9.53262) (xy 101.138228 -9.535922) (xy 101.137719 -9.563808)
			(xy 101.129599 -9.618984) (xy 101.113531 -9.672391) (xy 101.089859 -9.722888) (xy 101.059086 -9.769401)
			(xy 101.021869 -9.810938) (xy 100.979001 -9.846613) (xy 100.931395 -9.875667) (xy 100.880066 -9.897479)
			(xy 100.826109 -9.911585) (xy 100.770672 -9.917685) (xy 100.714938 -9.915648) (xy 100.660095 -9.905518)
			(xy 100.607311 -9.887511) (xy 100.557711 -9.86201) (xy 100.512353 -9.829559) (xy 100.472204 -9.79085)
			(xy 100.438118 -9.746707) (xy 100.410822 -9.698072) (xy 100.390899 -9.645981) (xy 100.378773 -9.591544)
			(xy 100.374702 -9.535922) (xy 97.480882 -9.535922) (xy 97.480882 -11.543792) (xy 101.399338 -11.543792)
			(xy 101.403409 -11.48817) (xy 101.415535 -11.433733) (xy 101.435458 -11.381642) (xy 101.462754 -11.333007)
			(xy 101.49684 -11.288864) (xy 101.536989 -11.250155) (xy 101.582347 -11.217704) (xy 101.631947 -11.192203)
			(xy 101.684731 -11.174196) (xy 101.739574 -11.164066) (xy 101.795308 -11.162029) (xy 101.850745 -11.168129)
			(xy 101.904702 -11.182235) (xy 101.956031 -11.204047) (xy 102.003637 -11.233101) (xy 102.046505 -11.268776)
			(xy 102.083722 -11.310313) (xy 102.114495 -11.356826) (xy 102.138167 -11.407323) (xy 102.154235 -11.46073)
			(xy 102.162355 -11.515906) (xy 102.162864 -11.543792) (xy 102.408226 -11.543792) (xy 102.412297 -11.48817)
			(xy 102.424423 -11.433733) (xy 102.444346 -11.381642) (xy 102.471642 -11.333007) (xy 102.505728 -11.288864)
			(xy 102.545877 -11.250155) (xy 102.591235 -11.217704) (xy 102.640835 -11.192203) (xy 102.693619 -11.174196)
			(xy 102.748462 -11.164066) (xy 102.804196 -11.162029) (xy 102.859633 -11.168129) (xy 102.91359 -11.182235)
			(xy 102.964919 -11.204047) (xy 103.012525 -11.233101) (xy 103.055393 -11.268776) (xy 103.09261 -11.310313)
			(xy 103.123383 -11.356826) (xy 103.147055 -11.407323) (xy 103.163123 -11.46073) (xy 103.171243 -11.515906)
			(xy 103.171752 -11.543792) (xy 103.171243 -11.571678) (xy 103.163123 -11.626854) (xy 103.147055 -11.680261)
			(xy 103.123383 -11.730758) (xy 103.09261 -11.777271) (xy 103.055393 -11.818808) (xy 103.012525 -11.854483)
			(xy 102.964919 -11.883537) (xy 102.91359 -11.905349) (xy 102.859633 -11.919455) (xy 102.804196 -11.925555)
			(xy 102.748462 -11.923518) (xy 102.693619 -11.913388) (xy 102.640835 -11.895381) (xy 102.591235 -11.86988)
			(xy 102.545877 -11.837429) (xy 102.505728 -11.79872) (xy 102.471642 -11.754577) (xy 102.444346 -11.705942)
			(xy 102.424423 -11.653851) (xy 102.412297 -11.599414) (xy 102.408226 -11.543792) (xy 102.162864 -11.543792)
			(xy 102.162355 -11.571678) (xy 102.154235 -11.626854) (xy 102.138167 -11.680261) (xy 102.114495 -11.730758)
			(xy 102.083722 -11.777271) (xy 102.046505 -11.818808) (xy 102.003637 -11.854483) (xy 101.956031 -11.883537)
			(xy 101.904702 -11.905349) (xy 101.850745 -11.919455) (xy 101.795308 -11.925555) (xy 101.739574 -11.923518)
			(xy 101.684731 -11.913388) (xy 101.631947 -11.895381) (xy 101.582347 -11.86988) (xy 101.536989 -11.837429)
			(xy 101.49684 -11.79872) (xy 101.462754 -11.754577) (xy 101.435458 -11.705942) (xy 101.415535 -11.653851)
			(xy 101.403409 -11.599414) (xy 101.399338 -11.543792) (xy 97.480882 -11.543792) (xy 97.480882 -13.649198)
			(xy 97.481114 -13.656467) (xy 97.485251 -13.670403) (xy 97.48901 -13.67663) (xy 97.506536 -13.704316)
			(xy 97.517204 -13.71346) (xy 97.523808 -13.716508) (xy 97.580853 -13.743684) (xy 97.69197 -13.803871)
			(xy 97.79933 -13.870529) (xy 97.902557 -13.943424) (xy 98.001289 -14.022301) (xy 98.09518 -14.106882)
			(xy 98.183901 -14.196871) (xy 98.267141 -14.291954) (xy 98.344608 -14.391796) (xy 98.41603 -14.496048)
			(xy 98.481157 -14.604343) (xy 98.510852 -14.660118) (xy 98.513392 -14.665198) (xy 98.516694 -14.671548)
			(xy 98.545321 -14.728051) (xy 98.596615 -14.843879) (xy 98.640948 -14.962546) (xy 98.678163 -15.083634)
			(xy 98.70813 -15.206717) (xy 98.730743 -15.33136) (xy 98.745922 -15.457125) (xy 98.753614 -15.58357)
			(xy 98.754184 -15.646908) (xy 98.754184 -15.665958) (xy 98.753197 -15.731376) (xy 98.744201 -15.861914)
			(xy 98.727225 -15.991656) (xy 98.702331 -16.120113) (xy 98.669614 -16.246804) (xy 98.629197 -16.371253)
			(xy 98.58123 -16.492992) (xy 98.525895 -16.611563) (xy 98.4634 -16.726521) (xy 98.393979 -16.837434)
			(xy 98.317893 -16.943886) (xy 98.2967 -16.969994) (xy 129.848363 -16.969994) (xy 129.852368 -16.882086)
			(xy 129.864351 -16.794906) (xy 129.884211 -16.709177) (xy 129.911786 -16.625609) (xy 129.946845 -16.544895)
			(xy 129.989098 -16.467703) (xy 130.038196 -16.394674) (xy 130.093732 -16.326412) (xy 130.155244 -16.263482)
			(xy 130.222225 -16.206408) (xy 130.294118 -16.15566) (xy 130.370327 -16.11166) (xy 130.450222 -16.074773)
			(xy 130.533141 -16.045304) (xy 130.618396 -16.023497) (xy 130.70528 -16.009533) (xy 130.793074 -16.003527)
			(xy 130.881051 -16.005531) (xy 130.968481 -16.015526) (xy 131.05464 -16.03343) (xy 131.138814 -16.059094)
			(xy 131.220305 -16.092307) (xy 131.298439 -16.132793) (xy 131.372567 -16.180215) (xy 131.442075 -16.234182)
			(xy 131.506389 -16.294247) (xy 131.564973 -16.359911) (xy 131.617344 -16.43063) (xy 131.663067 -16.505818)
			(xy 131.701764 -16.584853) (xy 131.733113 -16.667079) (xy 131.756855 -16.751815) (xy 131.772793 -16.838359)
			(xy 131.780795 -16.925994) (xy 131.781296 -16.969994) (xy 131.780795 -17.013994) (xy 131.772793 -17.101629)
			(xy 131.756855 -17.188173) (xy 131.733113 -17.272909) (xy 131.701764 -17.355135) (xy 131.663067 -17.43417)
			(xy 131.617344 -17.509358) (xy 131.564973 -17.580077) (xy 131.506389 -17.645741) (xy 131.442075 -17.705806)
			(xy 131.372567 -17.759773) (xy 131.298439 -17.807195) (xy 131.220305 -17.847681) (xy 131.138814 -17.880894)
			(xy 131.05464 -17.906558) (xy 130.968481 -17.924462) (xy 130.881051 -17.934457) (xy 130.793074 -17.936461)
			(xy 130.70528 -17.930455) (xy 130.618396 -17.916491) (xy 130.533141 -17.894684) (xy 130.450222 -17.865215)
			(xy 130.370327 -17.828328) (xy 130.294118 -17.784328) (xy 130.222225 -17.73358) (xy 130.155244 -17.676506)
			(xy 130.093732 -17.613576) (xy 130.038196 -17.545314) (xy 129.989098 -17.472285) (xy 129.946845 -17.395093)
			(xy 129.911786 -17.314379) (xy 129.884211 -17.230811) (xy 129.864351 -17.145082) (xy 129.852368 -17.057902)
			(xy 129.848363 -16.969994) (xy 98.2967 -16.969994) (xy 98.235427 -17.045476) (xy 98.146893 -17.141823)
			(xy 98.052622 -17.232564) (xy 97.952968 -17.317359) (xy 97.848307 -17.39589) (xy 97.73903 -17.46786)
			(xy 97.62555 -17.533001) (xy 97.508292 -17.591066) (xy 97.387696 -17.641838) (xy 97.264217 -17.685126)
			(xy 97.138317 -17.720768) (xy 97.01047 -17.748629) (xy 96.881157 -17.768605) (xy 96.750862 -17.78062)
			(xy 96.620076 -17.78463) (xy 96.48929 -17.78062) (xy 96.358995 -17.768605) (xy 96.229682 -17.748629)
			(xy 96.101835 -17.720768) (xy 95.975935 -17.685126) (xy 95.852456 -17.641838) (xy 95.73186 -17.591066)
			(xy 95.614602 -17.533001) (xy 95.501122 -17.46786) (xy 95.391845 -17.39589) (xy 95.287184 -17.317359)
			(xy 95.18753 -17.232564) (xy 95.093259 -17.141823) (xy 95.004725 -17.045476) (xy 94.922259 -16.943886)
			(xy 94.846173 -16.837434) (xy 94.776752 -16.726521) (xy 94.714257 -16.611563) (xy 94.658922 -16.492992)
			(xy 94.610955 -16.371253) (xy 94.570538 -16.246804) (xy 94.537821 -16.120113) (xy 94.512927 -15.991656)
			(xy 94.495951 -15.861914) (xy 94.486955 -15.731376) (xy 94.485968 -15.665958) (xy 94.485968 -15.649702)
			(xy 94.486459 -15.585401) (xy 94.494222 -15.457032) (xy 94.509702 -15.329364) (xy 94.532842 -15.20286)
			(xy 94.563559 -15.07798) (xy 94.601742 -14.955176) (xy 94.64725 -14.834894) (xy 94.69992 -14.717571)
			(xy 94.7293 -14.660372) (xy 94.730824 -14.657324) (xy 94.732969 -14.652127) (xy 94.735161 -14.641102)
			(xy 94.735142 -14.63548) (xy 94.734634 -14.622018) (xy 94.718378 -14.595094) (xy 94.718378 -14.594586)
			(xy 94.68231 -14.535658) (xy 94.678758 -14.530152) (xy 94.669375 -14.521014) (xy 94.663768 -14.517624)
			(xy 94.658434 -14.51483) (xy 94.650306 -14.512798) (xy 94.639384 -14.511528) (xy 85.077808 -14.511528)
			(xy 85.067737 -14.511107) (xy 85.049127 -14.503398) (xy 85.04174 -14.496542) (xy 84.327746 -13.782548)
			(xy 84.320903 -13.775149) (xy 84.31318 -13.75655) (xy 84.31276 -13.74648) (xy 84.31276 -7.517892)
			(xy 84.312252 -7.510272) (xy 84.31026 -7.500219) (xy 84.299503 -7.482798) (xy 84.291424 -7.47649)
			(xy 84.29117 -7.47649) (xy 84.243418 -7.442454) (xy 84.24291 -7.442454) (xy 84.22132 -7.427214) (xy 84.216654 -7.424346)
			(xy 84.206401 -7.420504) (xy 84.201 -7.419594) (xy 84.189062 -7.41807) (xy 84.177124 -7.422388) (xy 84.146308 -7.432602)
			(xy 84.082328 -7.443586) (xy 84.04987 -7.444232) (xy 84.022618 -7.443744) (xy 83.968671 -7.435984)
			(xy 83.916376 -7.420625) (xy 83.8668 -7.397981) (xy 83.82095 -7.368512) (xy 83.779761 -7.332818)
			(xy 83.74407 -7.291626) (xy 83.714605 -7.245774) (xy 83.691965 -7.196196) (xy 83.67661 -7.1439) (xy 83.668854 -7.089952)
			(xy 83.668854 -7.035448) (xy 83.67661 -6.9815) (xy 83.691965 -6.929204) (xy 83.714605 -6.879626)
			(xy 83.74407 -6.833774) (xy 83.779761 -6.792582) (xy 83.82095 -6.756888) (xy 83.8668 -6.727419) (xy 83.916376 -6.704775)
			(xy 83.968671 -6.689416) (xy 84.022618 -6.681656) (xy 84.04987 -6.681216) (xy 84.050378 -6.681216)
			(xy 84.082705 -6.681936) (xy 84.146423 -6.692912) (xy 84.177124 -6.70306) (xy 84.177378 -6.70306)
			(xy 84.183204 -6.704994) (xy 84.195408 -6.706288) (xy 84.201508 -6.7056) (xy 84.213192 -6.704076)
			(xy 84.228686 -6.693154) (xy 84.29117 -6.648958) (xy 84.295986 -6.645375) (xy 84.303943 -6.636392)
			(xy 84.306918 -6.631178) (xy 84.307172 -6.630416) (xy 84.309717 -6.625043) (xy 84.312531 -6.613497)
			(xy 84.31276 -6.607556) (xy 84.31276 -5.485892) (xy 84.312252 -5.478272) (xy 84.31026 -5.468219)
			(xy 84.299503 -5.450798) (xy 84.291424 -5.44449) (xy 84.29117 -5.44449) (xy 84.243418 -5.410454)
			(xy 84.24291 -5.410454) (xy 84.22132 -5.395214) (xy 84.216654 -5.392346) (xy 84.206401 -5.388504)
			(xy 84.201 -5.387594) (xy 84.189062 -5.38607) (xy 84.177124 -5.390388) (xy 84.146308 -5.400602) (xy 84.082328 -5.411586)
			(xy 84.04987 -5.412232) (xy 84.022618 -5.411744) (xy 83.968671 -5.403984) (xy 83.916376 -5.388625)
			(xy 83.8668 -5.365981) (xy 83.82095 -5.336512) (xy 83.779761 -5.300818) (xy 83.74407 -5.259626) (xy 83.714605 -5.213774)
			(xy 83.691965 -5.164196) (xy 83.67661 -5.1119) (xy 83.668854 -5.057952) (xy 83.668854 -5.003448)
			(xy 83.67661 -4.9495) (xy 83.691965 -4.897204) (xy 83.714605 -4.847626) (xy 83.74407 -4.801774) (xy 83.779761 -4.760582)
			(xy 83.82095 -4.724888) (xy 83.8668 -4.695419) (xy 83.916376 -4.672775) (xy 83.968671 -4.657416)
			(xy 84.022618 -4.649656) (xy 84.04987 -4.649216) (xy 84.050378 -4.649216) (xy 84.082705 -4.649936)
			(xy 84.146423 -4.660912) (xy 84.177124 -4.67106) (xy 84.177378 -4.67106) (xy 84.183204 -4.672994)
			(xy 84.195408 -4.674288) (xy 84.201508 -4.6736) (xy 84.213192 -4.672076) (xy 84.228686 -4.661154)
			(xy 84.29117 -4.616958) (xy 84.295986 -4.613375) (xy 84.303943 -4.604392) (xy 84.306918 -4.599178)
			(xy 84.307172 -4.598416) (xy 84.309717 -4.593043) (xy 84.312531 -4.581497) (xy 84.31276 -4.575556)
			(xy 84.31276 -4.469892) (xy 84.312252 -4.462272) (xy 84.31026 -4.452219) (xy 84.299503 -4.434798)
			(xy 84.291424 -4.42849) (xy 84.29117 -4.42849) (xy 84.243418 -4.394454) (xy 84.24291 -4.394454) (xy 84.22132 -4.379214)
			(xy 84.216654 -4.376346) (xy 84.206401 -4.372504) (xy 84.201 -4.371594) (xy 84.189062 -4.37007) (xy 84.177124 -4.374388)
			(xy 84.146308 -4.384602) (xy 84.082328 -4.395586) (xy 84.04987 -4.396232) (xy 84.022618 -4.395744)
			(xy 83.968671 -4.387984) (xy 83.916376 -4.372625) (xy 83.8668 -4.349981) (xy 83.82095 -4.320512)
			(xy 83.779761 -4.284818) (xy 83.74407 -4.243626) (xy 83.714605 -4.197774) (xy 83.691965 -4.148196)
			(xy 83.67661 -4.0959) (xy 83.668854 -4.041952) (xy 83.668854 -3.987448) (xy 83.67661 -3.9335) (xy 83.691965 -3.881204)
			(xy 83.714605 -3.831626) (xy 83.74407 -3.785774) (xy 83.779761 -3.744582) (xy 83.82095 -3.708888)
			(xy 83.8668 -3.679419) (xy 83.916376 -3.656775) (xy 83.968671 -3.641416) (xy 84.022618 -3.633656)
			(xy 84.04987 -3.633216) (xy 84.050378 -3.633216) (xy 84.082705 -3.633936) (xy 84.146423 -3.644912)
			(xy 84.177124 -3.65506) (xy 84.177378 -3.65506) (xy 84.183204 -3.656994) (xy 84.195408 -3.658288)
			(xy 84.201508 -3.6576) (xy 84.213192 -3.656076) (xy 84.228686 -3.645154) (xy 84.29117 -3.600958)
			(xy 84.295986 -3.597375) (xy 84.303943 -3.588392) (xy 84.306918 -3.583178) (xy 84.307172 -3.582416)
			(xy 84.309717 -3.577043) (xy 84.312531 -3.565497) (xy 84.31276 -3.559556) (xy 84.31276 -1.941576)
			(xy 84.312597 -1.935565) (xy 84.309781 -1.923879) (xy 84.307172 -1.918462) (xy 84.30533 -1.914989)
			(xy 84.300733 -1.908614) (xy 84.298028 -1.905762) (xy 83.77301 -1.380744) (xy 83.77016 -1.378037)
			(xy 83.763782 -1.373442) (xy 83.76031 -1.3716) (xy 83.754882 -1.369022) (xy 83.743202 -1.366209)
			(xy 83.737196 -1.366012) (xy 71.99884 -1.366012) (xy 71.992831 -1.36618) (xy 71.98115 -1.369007)
			(xy 71.975726 -1.3716) (xy 71.97225 -1.373437) (xy 71.965867 -1.378027) (xy 71.963026 -1.380744)
			(xy 71.495412 -1.848358) (xy 71.492705 -1.851208) (xy 71.488109 -1.857585) (xy 71.486268 -1.861058)
			(xy 71.483688 -1.866486) (xy 71.480869 -1.878165) (xy 71.48068 -1.884172) (xy 71.48068 -3.659632)
			(xy 81.365342 -3.659632) (xy 81.369413 -3.60401) (xy 81.381539 -3.549573) (xy 81.401462 -3.497482)
			(xy 81.428758 -3.448847) (xy 81.462844 -3.404704) (xy 81.502993 -3.365995) (xy 81.548351 -3.333544)
			(xy 81.597951 -3.308043) (xy 81.650735 -3.290036) (xy 81.705578 -3.279906) (xy 81.761312 -3.277869)
			(xy 81.816749 -3.283969) (xy 81.870706 -3.298075) (xy 81.922035 -3.319887) (xy 81.969641 -3.348941)
			(xy 82.012509 -3.384616) (xy 82.049726 -3.426153) (xy 82.080499 -3.472666) (xy 82.104171 -3.523163)
			(xy 82.120239 -3.57657) (xy 82.128359 -3.631746) (xy 82.128868 -3.659632) (xy 82.128359 -3.687518)
			(xy 82.120239 -3.742694) (xy 82.104171 -3.796101) (xy 82.080499 -3.846598) (xy 82.049726 -3.893111)
			(xy 82.012509 -3.934648) (xy 81.969641 -3.970323) (xy 81.922035 -3.999377) (xy 81.870706 -4.021189)
			(xy 81.816749 -4.035295) (xy 81.761312 -4.041395) (xy 81.705578 -4.039358) (xy 81.650735 -4.029228)
			(xy 81.597951 -4.011221) (xy 81.548351 -3.98572) (xy 81.502993 -3.953269) (xy 81.462844 -3.91456)
			(xy 81.428758 -3.870417) (xy 81.401462 -3.821782) (xy 81.381539 -3.769691) (xy 81.369413 -3.715254)
			(xy 81.365342 -3.659632) (xy 71.48068 -3.659632) (xy 71.48068 -4.558538) (xy 71.481033 -4.567226)
			(xy 71.48689 -4.583586) (xy 71.49211 -4.590542) (xy 71.497444 -4.597146) (xy 71.512176 -4.606036)
			(xy 71.52132 -4.608068) (xy 71.521574 -4.608068) (xy 71.549871 -4.614448) (xy 71.604258 -4.634613)
			(xy 71.654966 -4.662777) (xy 71.700827 -4.698291) (xy 71.740785 -4.740338) (xy 71.773918 -4.787947)
			(xy 71.799464 -4.840023) (xy 71.816835 -4.895366) (xy 71.825628 -4.9527) (xy 71.82612 -4.981702)
			(xy 71.825578 -5.010702) (xy 71.822511 -5.030724) (xy 81.62112 -5.030724) (xy 81.625191 -4.975102)
			(xy 81.637317 -4.920665) (xy 81.65724 -4.868574) (xy 81.684536 -4.819939) (xy 81.718622 -4.775796)
			(xy 81.758771 -4.737087) (xy 81.804129 -4.704636) (xy 81.853729 -4.679135) (xy 81.906513 -4.661128)
			(xy 81.961356 -4.650998) (xy 82.01709 -4.648961) (xy 82.072527 -4.655061) (xy 82.126484 -4.669167)
			(xy 82.177813 -4.690979) (xy 82.225419 -4.720033) (xy 82.268287 -4.755708) (xy 82.305504 -4.797245)
			(xy 82.336277 -4.843758) (xy 82.359949 -4.894255) (xy 82.376017 -4.947662) (xy 82.384137 -5.002838)
			(xy 82.384646 -5.030724) (xy 82.384137 -5.05861) (xy 82.376017 -5.113786) (xy 82.359949 -5.167193)
			(xy 82.336277 -5.21769) (xy 82.305504 -5.264203) (xy 82.268287 -5.30574) (xy 82.225419 -5.341415)
			(xy 82.177813 -5.370469) (xy 82.126484 -5.392281) (xy 82.072527 -5.406387) (xy 82.01709 -5.412487)
			(xy 81.961356 -5.41045) (xy 81.906513 -5.40032) (xy 81.853729 -5.382313) (xy 81.804129 -5.356812)
			(xy 81.758771 -5.324361) (xy 81.718622 -5.285652) (xy 81.684536 -5.241509) (xy 81.65724 -5.192874)
			(xy 81.637317 -5.140783) (xy 81.625191 -5.086346) (xy 81.62112 -5.030724) (xy 71.822511 -5.030724)
			(xy 71.816797 -5.068033) (xy 71.799436 -5.123374) (xy 71.773897 -5.175449) (xy 71.740768 -5.223056)
			(xy 71.700814 -5.2651) (xy 71.654954 -5.300609) (xy 71.604247 -5.328765) (xy 71.549861 -5.34892)
			(xy 71.521574 -5.355336) (xy 71.52132 -5.355336) (xy 71.518018 -5.356098) (xy 71.510409 -5.35843)
			(xy 71.497076 -5.367108) (xy 71.491856 -5.373116) (xy 71.486522 -5.37972) (xy 71.483728 -5.387594)
			(xy 71.482321 -5.391773) (xy 71.480794 -5.400458) (xy 71.48068 -5.404866) (xy 71.48068 -5.889752)
			(xy 73.306684 -5.889752) (xy 73.310755 -5.83413) (xy 73.322881 -5.779693) (xy 73.342804 -5.727602)
			(xy 73.3701 -5.678967) (xy 73.404186 -5.634824) (xy 73.444335 -5.596115) (xy 73.489693 -5.563664)
			(xy 73.539293 -5.538163) (xy 73.592077 -5.520156) (xy 73.64692 -5.510026) (xy 73.702654 -5.507989)
			(xy 73.758091 -5.514089) (xy 73.812048 -5.528195) (xy 73.863377 -5.550007) (xy 73.910983 -5.579061)
			(xy 73.953851 -5.614736) (xy 73.991068 -5.656273) (xy 74.021841 -5.702786) (xy 74.045513 -5.753283)
			(xy 74.061581 -5.80669) (xy 74.069701 -5.861866) (xy 74.07021 -5.889752) (xy 74.069701 -5.917638)
			(xy 74.061581 -5.972814) (xy 74.045513 -6.026221) (xy 74.021841 -6.076718) (xy 73.991068 -6.123231)
			(xy 73.953851 -6.164768) (xy 73.910983 -6.200443) (xy 73.863377 -6.229497) (xy 73.812048 -6.251309)
			(xy 73.758091 -6.265415) (xy 73.702654 -6.271515) (xy 73.64692 -6.269478) (xy 73.592077 -6.259348)
			(xy 73.539293 -6.241341) (xy 73.489693 -6.21584) (xy 73.444335 -6.183389) (xy 73.404186 -6.14468)
			(xy 73.3701 -6.100537) (xy 73.342804 -6.051902) (xy 73.322881 -5.999811) (xy 73.310755 -5.945374)
			(xy 73.306684 -5.889752) (xy 71.48068 -5.889752) (xy 71.48068 -6.651498) (xy 81.434684 -6.651498)
			(xy 81.438755 -6.595876) (xy 81.450881 -6.541439) (xy 81.470804 -6.489348) (xy 81.4981 -6.440713)
			(xy 81.532186 -6.39657) (xy 81.572335 -6.357861) (xy 81.617693 -6.32541) (xy 81.667293 -6.299909)
			(xy 81.720077 -6.281902) (xy 81.77492 -6.271772) (xy 81.830654 -6.269735) (xy 81.886091 -6.275835)
			(xy 81.940048 -6.289941) (xy 81.991377 -6.311753) (xy 82.038983 -6.340807) (xy 82.081851 -6.376482)
			(xy 82.119068 -6.418019) (xy 82.149841 -6.464532) (xy 82.173513 -6.515029) (xy 82.189581 -6.568436)
			(xy 82.197701 -6.623612) (xy 82.19821 -6.651498) (xy 82.197701 -6.679384) (xy 82.189581 -6.73456)
			(xy 82.173513 -6.787967) (xy 82.149841 -6.838464) (xy 82.119068 -6.884977) (xy 82.081851 -6.926514)
			(xy 82.038983 -6.962189) (xy 81.991377 -6.991243) (xy 81.940048 -7.013055) (xy 81.886091 -7.027161)
			(xy 81.830654 -7.033261) (xy 81.77492 -7.031224) (xy 81.720077 -7.021094) (xy 81.667293 -7.003087)
			(xy 81.617693 -6.977586) (xy 81.572335 -6.945135) (xy 81.532186 -6.906426) (xy 81.4981 -6.862283)
			(xy 81.470804 -6.813648) (xy 81.450881 -6.761557) (xy 81.438755 -6.70712) (xy 81.434684 -6.651498)
			(xy 71.48068 -6.651498) (xy 71.48068 -7.183374) (xy 73.184256 -7.183374) (xy 73.188327 -7.127752)
			(xy 73.200453 -7.073315) (xy 73.220376 -7.021224) (xy 73.247672 -6.972589) (xy 73.281758 -6.928446)
			(xy 73.321907 -6.889737) (xy 73.367265 -6.857286) (xy 73.416865 -6.831785) (xy 73.469649 -6.813778)
			(xy 73.524492 -6.803648) (xy 73.580226 -6.801611) (xy 73.635663 -6.807711) (xy 73.68962 -6.821817)
			(xy 73.740949 -6.843629) (xy 73.788555 -6.872683) (xy 73.831423 -6.908358) (xy 73.86864 -6.949895)
			(xy 73.899413 -6.996408) (xy 73.923085 -7.046905) (xy 73.939153 -7.100312) (xy 73.947273 -7.155488)
			(xy 73.947782 -7.183374) (xy 73.947273 -7.21126) (xy 73.939153 -7.266436) (xy 73.923085 -7.319843)
			(xy 73.899413 -7.37034) (xy 73.86864 -7.416853) (xy 73.831423 -7.45839) (xy 73.788555 -7.494065)
			(xy 73.740949 -7.523119) (xy 73.68962 -7.544931) (xy 73.635663 -7.559037) (xy 73.580226 -7.565137)
			(xy 73.524492 -7.5631) (xy 73.469649 -7.55297) (xy 73.416865 -7.534963) (xy 73.367265 -7.509462)
			(xy 73.321907 -7.477011) (xy 73.281758 -7.438302) (xy 73.247672 -7.394159) (xy 73.220376 -7.345524)
			(xy 73.200453 -7.293433) (xy 73.188327 -7.238996) (xy 73.184256 -7.183374) (xy 71.48068 -7.183374)
			(xy 71.48068 -8.653272) (xy 71.923146 -8.653272) (xy 71.927217 -8.59765) (xy 71.939343 -8.543213)
			(xy 71.959266 -8.491122) (xy 71.986562 -8.442487) (xy 72.020648 -8.398344) (xy 72.060797 -8.359635)
			(xy 72.106155 -8.327184) (xy 72.155755 -8.301683) (xy 72.208539 -8.283676) (xy 72.263382 -8.273546)
			(xy 72.319116 -8.271509) (xy 72.374553 -8.277609) (xy 72.42851 -8.291715) (xy 72.479839 -8.313527)
			(xy 72.527445 -8.342581) (xy 72.570313 -8.378256) (xy 72.60753 -8.419793) (xy 72.638303 -8.466306)
			(xy 72.661975 -8.516803) (xy 72.678043 -8.57021) (xy 72.686163 -8.625386) (xy 72.686672 -8.653272)
			(xy 72.686163 -8.681158) (xy 72.678043 -8.736334) (xy 72.661975 -8.789741) (xy 72.638303 -8.840238)
			(xy 72.60753 -8.886751) (xy 72.570313 -8.928288) (xy 72.527445 -8.963963) (xy 72.479839 -8.993017)
			(xy 72.42851 -9.014829) (xy 72.374553 -9.028935) (xy 72.319116 -9.035035) (xy 72.263382 -9.032998)
			(xy 72.208539 -9.022868) (xy 72.155755 -9.004861) (xy 72.106155 -8.97936) (xy 72.060797 -8.946909)
			(xy 72.020648 -8.9082) (xy 71.986562 -8.864057) (xy 71.959266 -8.815422) (xy 71.939343 -8.763331)
			(xy 71.927217 -8.708894) (xy 71.923146 -8.653272) (xy 71.48068 -8.653272) (xy 71.48068 -9.33069)
			(xy 73.22642 -9.33069) (xy 73.230491 -9.275068) (xy 73.242617 -9.220631) (xy 73.26254 -9.16854) (xy 73.289836 -9.119905)
			(xy 73.323922 -9.075762) (xy 73.364071 -9.037053) (xy 73.409429 -9.004602) (xy 73.459029 -8.979101)
			(xy 73.511813 -8.961094) (xy 73.566656 -8.950964) (xy 73.62239 -8.948927) (xy 73.677827 -8.955027)
			(xy 73.731784 -8.969133) (xy 73.783113 -8.990945) (xy 73.830719 -9.019999) (xy 73.873587 -9.055674)
			(xy 73.910804 -9.097211) (xy 73.941577 -9.143724) (xy 73.965249 -9.194221) (xy 73.981317 -9.247628)
			(xy 73.989437 -9.302804) (xy 73.989946 -9.33069) (xy 73.989437 -9.358576) (xy 73.981317 -9.413752)
			(xy 73.965249 -9.467159) (xy 73.941577 -9.517656) (xy 73.929492 -9.535922) (xy 78.931006 -9.535922)
			(xy 78.935077 -9.4803) (xy 78.947203 -9.425863) (xy 78.967126 -9.373772) (xy 78.994422 -9.325137)
			(xy 79.028508 -9.280994) (xy 79.068657 -9.242285) (xy 79.114015 -9.209834) (xy 79.163615 -9.184333)
			(xy 79.216399 -9.166326) (xy 79.271242 -9.156196) (xy 79.326976 -9.154159) (xy 79.382413 -9.160259)
			(xy 79.43637 -9.174365) (xy 79.487699 -9.196177) (xy 79.535305 -9.225231) (xy 79.578173 -9.260906)
			(xy 79.61539 -9.302443) (xy 79.646163 -9.348956) (xy 79.669835 -9.399453) (xy 79.685903 -9.45286)
			(xy 79.694023 -9.508036) (xy 79.694532 -9.535922) (xy 79.694023 -9.563808) (xy 79.685903 -9.618984)
			(xy 79.669835 -9.672391) (xy 79.646163 -9.722888) (xy 79.61539 -9.769401) (xy 79.578173 -9.810938)
			(xy 79.535305 -9.846613) (xy 79.487699 -9.875667) (xy 79.43637 -9.897479) (xy 79.382413 -9.911585)
			(xy 79.326976 -9.917685) (xy 79.271242 -9.915648) (xy 79.216399 -9.905518) (xy 79.163615 -9.887511)
			(xy 79.114015 -9.86201) (xy 79.068657 -9.829559) (xy 79.028508 -9.79085) (xy 78.994422 -9.746707)
			(xy 78.967126 -9.698072) (xy 78.947203 -9.645981) (xy 78.935077 -9.591544) (xy 78.931006 -9.535922)
			(xy 73.929492 -9.535922) (xy 73.910804 -9.564169) (xy 73.873587 -9.605706) (xy 73.830719 -9.641381)
			(xy 73.783113 -9.670435) (xy 73.731784 -9.692247) (xy 73.677827 -9.706353) (xy 73.62239 -9.712453)
			(xy 73.566656 -9.710416) (xy 73.511813 -9.700286) (xy 73.459029 -9.682279) (xy 73.409429 -9.656778)
			(xy 73.364071 -9.624327) (xy 73.323922 -9.585618) (xy 73.289836 -9.541475) (xy 73.26254 -9.49284)
			(xy 73.242617 -9.440749) (xy 73.230491 -9.386312) (xy 73.22642 -9.33069) (xy 71.48068 -9.33069) (xy 71.48068 -13.649198)
			(xy 71.481188 -13.655802) (xy 71.482051 -13.661394) (xy 71.485893 -13.672035) (xy 71.488808 -13.676884)
			(xy 71.502524 -13.69822) (xy 71.506553 -13.703935) (xy 71.517122 -13.71308) (xy 71.523352 -13.716254)
			(xy 71.523606 -13.716508) (xy 71.53148 -13.720064) (xy 71.588075 -13.747292) (xy 71.698304 -13.807514)
			(xy 71.804798 -13.874115) (xy 71.90719 -13.946867) (xy 72.005125 -14.025515) (xy 72.087778 -14.100302)
			(xy 77.242922 -14.100302) (xy 77.246993 -14.04468) (xy 77.259119 -13.990243) (xy 77.279042 -13.938152)
			(xy 77.306338 -13.889517) (xy 77.340424 -13.845374) (xy 77.380573 -13.806665) (xy 77.425931 -13.774214)
			(xy 77.475531 -13.748713) (xy 77.528315 -13.730706) (xy 77.583158 -13.720576) (xy 77.638892 -13.718539)
			(xy 77.694329 -13.724639) (xy 77.748286 -13.738745) (xy 77.799615 -13.760557) (xy 77.847221 -13.789611)
			(xy 77.890089 -13.825286) (xy 77.927306 -13.866823) (xy 77.958079 -13.913336) (xy 77.981751 -13.963833)
			(xy 77.997819 -14.01724) (xy 78.005939 -14.072416) (xy 78.006448 -14.100302) (xy 78.005939 -14.128188)
			(xy 77.997819 -14.183364) (xy 77.981751 -14.236771) (xy 77.958079 -14.287268) (xy 77.927306 -14.333781)
			(xy 77.890089 -14.375318) (xy 77.847221 -14.410993) (xy 77.799615 -14.440047) (xy 77.748286 -14.461859)
			(xy 77.694329 -14.475965) (xy 77.638892 -14.482065) (xy 77.583158 -14.480028) (xy 77.528315 -14.469898)
			(xy 77.475531 -14.451891) (xy 77.425931 -14.42639) (xy 77.380573 -14.393939) (xy 77.340424 -14.35523)
			(xy 77.306338 -14.311087) (xy 77.279042 -14.262452) (xy 77.259119 -14.210361) (xy 77.246993 -14.155924)
			(xy 77.242922 -14.100302) (xy 72.087778 -14.100302) (xy 72.098263 -14.109789) (xy 72.186283 -14.199396)
			(xy 72.268878 -14.294026) (xy 72.345764 -14.393352) (xy 72.416673 -14.497028) (xy 72.48136 -14.604696)
			(xy 72.510904 -14.660118) (xy 72.51192 -14.66215) (xy 72.512174 -14.662404) (xy 72.541258 -14.719163)
			(xy 72.593408 -14.835563) (xy 72.638511 -14.954871) (xy 72.676406 -15.076661) (xy 72.706957 -15.200497)
			(xy 72.730055 -15.325937) (xy 72.739362 -15.401652) (xy 77.829644 -15.401652) (xy 77.829644 -15.347148)
			(xy 77.8374 -15.293199) (xy 77.852755 -15.240902) (xy 77.875395 -15.191323) (xy 77.904861 -15.14547)
			(xy 77.940552 -15.104277) (xy 77.981741 -15.068582) (xy 78.027591 -15.039113) (xy 78.077168 -15.016467)
			(xy 78.129463 -15.001108) (xy 78.183412 -14.993346) (xy 78.210664 -14.992858) (xy 78.236798 -14.993271)
			(xy 78.288576 -15.00042) (xy 78.338895 -15.014563) (xy 78.386816 -15.035434) (xy 78.431443 -15.062645)
			(xy 78.471943 -15.095687) (xy 78.490064 -15.114524) (xy 78.497684 -15.122906) (xy 78.518258 -15.131288)
			(xy 78.618588 -15.126462) (xy 78.638146 -15.116302) (xy 78.645004 -15.107412) (xy 78.663187 -15.084652)
			(xy 78.705279 -15.044382) (xy 78.753006 -15.010982) (xy 78.805256 -14.985228) (xy 78.860816 -14.96772)
			(xy 78.918392 -14.958864) (xy 78.947518 -14.958314) (xy 78.97477 -14.958757) (xy 79.028719 -14.966516)
			(xy 79.081014 -14.981874) (xy 79.130592 -15.004517) (xy 79.176443 -15.033986) (xy 79.217634 -15.069679)
			(xy 79.253325 -15.110871) (xy 79.282791 -15.156724) (xy 79.305433 -15.206302) (xy 79.320788 -15.258599)
			(xy 79.328544 -15.312548) (xy 79.328544 -15.367052) (xy 79.320788 -15.421001) (xy 79.305433 -15.473298)
			(xy 79.282791 -15.522876) (xy 79.253325 -15.568729) (xy 79.217634 -15.609921) (xy 79.176443 -15.645614)
			(xy 79.130592 -15.675083) (xy 79.081014 -15.697726) (xy 79.028719 -15.713084) (xy 78.97477 -15.720843)
			(xy 78.947518 -15.72133) (xy 78.921385 -15.720867) (xy 78.86961 -15.713728) (xy 78.819292 -15.699596)
			(xy 78.771371 -15.678734) (xy 78.726742 -15.651531) (xy 78.68624 -15.618497) (xy 78.668118 -15.599664)
			(xy 78.660498 -15.591282) (xy 78.639924 -15.5829) (xy 78.539594 -15.587726) (xy 78.520036 -15.597886)
			(xy 78.513178 -15.606776) (xy 78.495002 -15.629542) (xy 78.452909 -15.669812) (xy 78.405181 -15.703212)
			(xy 78.352929 -15.728965) (xy 78.297368 -15.746472) (xy 78.239791 -15.755326) (xy 78.210664 -15.755874)
			(xy 78.183412 -15.755454) (xy 78.129463 -15.747692) (xy 78.077168 -15.732333) (xy 78.027591 -15.709687)
			(xy 77.981741 -15.680218) (xy 77.940552 -15.644523) (xy 77.904861 -15.60333) (xy 77.875395 -15.557477)
			(xy 77.852755 -15.507898) (xy 77.8374 -15.455601) (xy 77.829644 -15.401652) (xy 72.739362 -15.401652)
			(xy 72.745617 -15.452533) (xy 72.753589 -15.579833) (xy 72.754236 -15.643606) (xy 72.754236 -15.653004)
			(xy 72.75366 -15.717417) (xy 72.745708 -15.845999) (xy 72.730013 -15.973867) (xy 72.706634 -16.100556)
			(xy 72.675655 -16.225603) (xy 72.637189 -16.348554) (xy 72.591376 -16.468961) (xy 72.538383 -16.586384)
			(xy 72.478403 -16.700398) (xy 72.411654 -16.810585) (xy 72.338381 -16.916545) (xy 72.296436 -16.969994)
			(xy 91.748109 -16.969994) (xy 91.752114 -16.882086) (xy 91.764097 -16.794906) (xy 91.783957 -16.709177)
			(xy 91.811532 -16.625609) (xy 91.846591 -16.544895) (xy 91.888844 -16.467703) (xy 91.937942 -16.394674)
			(xy 91.993478 -16.326412) (xy 92.05499 -16.263482) (xy 92.121971 -16.206408) (xy 92.193864 -16.15566)
			(xy 92.270073 -16.11166) (xy 92.349968 -16.074773) (xy 92.432887 -16.045304) (xy 92.518142 -16.023497)
			(xy 92.605026 -16.009533) (xy 92.69282 -16.003527) (xy 92.780797 -16.005531) (xy 92.868227 -16.015526)
			(xy 92.954386 -16.03343) (xy 93.03856 -16.059094) (xy 93.120051 -16.092307) (xy 93.198185 -16.132793)
			(xy 93.272313 -16.180215) (xy 93.341821 -16.234182) (xy 93.406135 -16.294247) (xy 93.464719 -16.359911)
			(xy 93.51709 -16.43063) (xy 93.562813 -16.505818) (xy 93.60151 -16.584853) (xy 93.632859 -16.667079)
			(xy 93.656601 -16.751815) (xy 93.672539 -16.838359) (xy 93.680541 -16.925994) (xy 93.681042 -16.969994)
			(xy 93.680541 -17.013994) (xy 93.672539 -17.101629) (xy 93.656601 -17.188173) (xy 93.632859 -17.272909)
			(xy 93.60151 -17.355135) (xy 93.562813 -17.43417) (xy 93.51709 -17.509358) (xy 93.464719 -17.580077)
			(xy 93.406135 -17.645741) (xy 93.341821 -17.705806) (xy 93.272313 -17.759773) (xy 93.198185 -17.807195)
			(xy 93.120051 -17.847681) (xy 93.03856 -17.880894) (xy 92.954386 -17.906558) (xy 92.868227 -17.924462)
			(xy 92.780797 -17.934457) (xy 92.69282 -17.936461) (xy 92.605026 -17.930455) (xy 92.518142 -17.916491)
			(xy 92.432887 -17.894684) (xy 92.349968 -17.865215) (xy 92.270073 -17.828328) (xy 92.193864 -17.784328)
			(xy 92.121971 -17.73358) (xy 92.05499 -17.676506) (xy 91.993478 -17.613576) (xy 91.937942 -17.545314)
			(xy 91.888844 -17.472285) (xy 91.846591 -17.395093) (xy 91.811532 -17.314379) (xy 91.783957 -17.230811)
			(xy 91.764097 -17.145082) (xy 91.752114 -17.057902) (xy 91.748109 -16.969994) (xy 72.296436 -16.969994)
			(xy 72.258848 -17.017892) (xy 72.173347 -17.114256) (xy 72.082189 -17.205288) (xy 71.985705 -17.290654)
			(xy 71.884247 -17.370045) (xy 71.81241 -17.419574) (xy 76.284072 -17.419574) (xy 76.288143 -17.363952)
			(xy 76.300269 -17.309515) (xy 76.320192 -17.257424) (xy 76.347488 -17.208789) (xy 76.381574 -17.164646)
			(xy 76.421723 -17.125937) (xy 76.467081 -17.093486) (xy 76.516681 -17.067985) (xy 76.569465 -17.049978)
			(xy 76.624308 -17.039848) (xy 76.680042 -17.037811) (xy 76.735479 -17.043911) (xy 76.789436 -17.058017)
			(xy 76.840765 -17.079829) (xy 76.888371 -17.108883) (xy 76.931239 -17.144558) (xy 76.968456 -17.186095)
			(xy 76.999229 -17.232608) (xy 77.022901 -17.283105) (xy 77.038969 -17.336512) (xy 77.047089 -17.391688)
			(xy 77.047598 -17.419574) (xy 77.047089 -17.44746) (xy 77.038969 -17.502636) (xy 77.022901 -17.556043)
			(xy 76.999229 -17.60654) (xy 76.968456 -17.653053) (xy 76.931239 -17.69459) (xy 76.888371 -17.730265)
			(xy 76.840765 -17.759319) (xy 76.789436 -17.781131) (xy 76.735479 -17.795237) (xy 76.680042 -17.801337)
			(xy 76.624308 -17.7993) (xy 76.569465 -17.78917) (xy 76.516681 -17.771163) (xy 76.467081 -17.745662)
			(xy 76.421723 -17.713211) (xy 76.381574 -17.674502) (xy 76.347488 -17.630359) (xy 76.320192 -17.581724)
			(xy 76.300269 -17.529633) (xy 76.288143 -17.475196) (xy 76.284072 -17.419574) (xy 71.81241 -17.419574)
			(xy 71.778185 -17.443171) (xy 71.667905 -17.509766) (xy 71.553809 -17.569587) (xy 71.436311 -17.622416)
			(xy 71.315841 -17.668061) (xy 71.192836 -17.706355) (xy 71.067746 -17.73716) (xy 70.941025 -17.760363)
			(xy 70.813135 -17.775879) (xy 70.684542 -17.783652) (xy 70.620128 -17.784064) (xy 70.619874 -17.784064)
			(xy 70.55571 -17.783586) (xy 70.427615 -17.775873) (xy 70.300214 -17.760477) (xy 70.173969 -17.737454)
			(xy 70.049336 -17.706886) (xy 69.926764 -17.668884) (xy 69.806698 -17.623586) (xy 69.68957 -17.571155)
			(xy 69.575804 -17.511781) (xy 69.465812 -17.445677) (xy 69.359991 -17.373084) (xy 69.258723 -17.294264)
			(xy 69.162374 -17.2095) (xy 69.071293 -17.119101) (xy 68.985808 -17.023391) (xy 68.906229 -16.922718)
			(xy 68.832843 -16.817445) (xy 68.765915 -16.707953) (xy 68.705688 -16.594636) (xy 68.652378 -16.477906)
			(xy 68.606179 -16.358183) (xy 68.567258 -16.2359) (xy 68.535755 -16.1115) (xy 68.511784 -15.985431)
			(xy 68.495431 -15.85815) (xy 68.486757 -15.730116) (xy 68.485766 -15.665958) (xy 68.485766 -15.649702)
			(xy 68.486257 -15.585401) (xy 68.49402 -15.457032) (xy 68.5095 -15.329364) (xy 68.53264 -15.20286)
			(xy 68.563357 -15.07798) (xy 68.601539 -14.955176) (xy 68.647048 -14.834894) (xy 68.699718 -14.717571)
			(xy 68.729098 -14.660372) (xy 68.730622 -14.657324) (xy 68.732767 -14.652127) (xy 68.734959 -14.641102)
			(xy 68.73494 -14.63548) (xy 68.734432 -14.622018) (xy 68.718176 -14.595094) (xy 68.718176 -14.594586)
			(xy 68.682108 -14.535658) (xy 68.678556 -14.530152) (xy 68.669172 -14.521014) (xy 68.663566 -14.517624)
			(xy 68.658232 -14.51483) (xy 68.650104 -14.512798) (xy 68.639182 -14.511528) (xy 59.07786 -14.511528)
			(xy 59.067792 -14.511098) (xy 59.049196 -14.503377) (xy 59.041792 -14.496542) (xy 58.327798 -13.782548)
			(xy 58.32096 -13.775147) (xy 58.313245 -13.756548) (xy 58.312812 -13.74648) (xy 58.312812 -1.941576)
			(xy 58.312648 -1.935566) (xy 58.30983 -1.92388) (xy 58.307224 -1.918462) (xy 58.305384 -1.914988)
			(xy 58.30079 -1.908609) (xy 58.29808 -1.905762) (xy 57.773062 -1.380744) (xy 57.77021 -1.37804) (xy 57.76383 -1.37345)
			(xy 57.760362 -1.3716) (xy 57.754935 -1.369016) (xy 57.743256 -1.366191) (xy 57.737248 -1.366012)
			(xy 45.998892 -1.366012) (xy 45.992881 -1.366174) (xy 45.981195 -1.36899) (xy 45.975778 -1.3716)
			(xy 45.972304 -1.37344) (xy 45.965925 -1.378034) (xy 45.963078 -1.380744) (xy 45.495464 -1.848358)
			(xy 45.492755 -1.851207) (xy 45.488155 -1.857582) (xy 45.48632 -1.861058) (xy 45.483738 -1.866485)
			(xy 45.480916 -1.878165) (xy 45.480732 -1.884172) (xy 45.480732 -13.649198) (xy 45.480964 -13.656468)
			(xy 45.485097 -13.670406) (xy 45.48886 -13.67663) (xy 45.506386 -13.704316) (xy 45.517054 -13.71346)
			(xy 45.523658 -13.716508) (xy 45.580702 -13.743685) (xy 45.691817 -13.803874) (xy 45.799175 -13.870534)
			(xy 45.9024 -13.94343) (xy 46.001131 -14.022308) (xy 46.087707 -14.100302) (xy 51.242974 -14.100302)
			(xy 51.247045 -14.04468) (xy 51.259171 -13.990243) (xy 51.279094 -13.938152) (xy 51.30639 -13.889517)
			(xy 51.340476 -13.845374) (xy 51.380625 -13.806665) (xy 51.425983 -13.774214) (xy 51.475583 -13.748713)
			(xy 51.528367 -13.730706) (xy 51.58321 -13.720576) (xy 51.638944 -13.718539) (xy 51.694381 -13.724639)
			(xy 51.748338 -13.738745) (xy 51.799667 -13.760557) (xy 51.847273 -13.789611) (xy 51.890141 -13.825286)
			(xy 51.927358 -13.866823) (xy 51.958131 -13.913336) (xy 51.981803 -13.963833) (xy 51.997871 -14.01724)
			(xy 52.005991 -14.072416) (xy 52.0065 -14.100302) (xy 52.005991 -14.128188) (xy 51.997871 -14.183364)
			(xy 51.981803 -14.236771) (xy 51.958131 -14.287268) (xy 51.927358 -14.333781) (xy 51.890141 -14.375318)
			(xy 51.847273 -14.410993) (xy 51.799667 -14.440047) (xy 51.748338 -14.461859) (xy 51.694381 -14.475965)
			(xy 51.638944 -14.482065) (xy 51.58321 -14.480028) (xy 51.528367 -14.469898) (xy 51.475583 -14.451891)
			(xy 51.425983 -14.42639) (xy 51.380625 -14.393939) (xy 51.340476 -14.35523) (xy 51.30639 -14.311087)
			(xy 51.279094 -14.262452) (xy 51.259171 -14.210361) (xy 51.247045 -14.155924) (xy 51.242974 -14.100302)
			(xy 46.087707 -14.100302) (xy 46.09502 -14.10689) (xy 46.183739 -14.196881) (xy 46.266977 -14.291964)
			(xy 46.344442 -14.391806) (xy 46.415862 -14.496058) (xy 46.480988 -14.604354) (xy 46.510702 -14.660118)
			(xy 46.513242 -14.665198) (xy 46.516544 -14.671548) (xy 46.522386 -14.682978) (xy 46.529244 -14.69644)
			(xy 46.531022 -14.70025) (xy 46.557921 -14.755366) (xy 46.606107 -14.868162) (xy 46.647736 -14.983539)
			(xy 46.682672 -15.101116) (xy 46.7108 -15.220504) (xy 46.732027 -15.341311) (xy 46.738608 -15.397551)
			(xy 51.90438 -15.397551) (xy 51.90438 -15.343049) (xy 51.912136 -15.289103) (xy 51.927491 -15.236809)
			(xy 51.950131 -15.187232) (xy 51.979596 -15.141382) (xy 52.015287 -15.100193) (xy 52.056476 -15.064501)
			(xy 52.102325 -15.035035) (xy 52.151901 -15.012393) (xy 52.204195 -14.997038) (xy 52.258141 -14.98928)
			(xy 52.285392 -14.988794) (xy 52.31501 -14.989396) (xy 52.373535 -14.998549) (xy 52.429941 -15.016637)
			(xy 52.482876 -15.043224) (xy 52.531065 -15.077673) (xy 52.5526 -15.098014) (xy 52.560524 -15.105065)
			(xy 52.580347 -15.112546) (xy 52.590954 -15.112492) (xy 52.676298 -15.10792) (xy 52.695094 -15.098522)
			(xy 52.701952 -15.090394) (xy 52.720189 -15.069186) (xy 52.761774 -15.031783) (xy 52.808373 -15.000848)
			(xy 52.858987 -14.977046) (xy 52.912533 -14.960886) (xy 52.967864 -14.952713) (xy 52.99583 -14.952218)
			(xy 53.023082 -14.952654) (xy 53.07703 -14.960414) (xy 53.129325 -14.975773) (xy 53.178901 -14.998418)
			(xy 53.224751 -15.027887) (xy 53.265941 -15.063581) (xy 53.301631 -15.104773) (xy 53.331097 -15.150625)
			(xy 53.353737 -15.200204) (xy 53.369092 -15.252499) (xy 53.376848 -15.306448) (xy 53.376848 -15.360952)
			(xy 53.369092 -15.414901) (xy 53.353737 -15.467196) (xy 53.331097 -15.516775) (xy 53.301631 -15.562627)
			(xy 53.265941 -15.603819) (xy 53.224751 -15.639513) (xy 53.178901 -15.668982) (xy 53.129325 -15.691627)
			(xy 53.07703 -15.706986) (xy 53.023082 -15.714746) (xy 52.99583 -15.715234) (xy 52.966209 -15.714701)
			(xy 52.90768 -15.705534) (xy 52.851272 -15.687431) (xy 52.798339 -15.660828) (xy 52.750154 -15.626363)
			(xy 52.728622 -15.606014) (xy 52.720697 -15.598964) (xy 52.700875 -15.591485) (xy 52.690268 -15.591536)
			(xy 52.604924 -15.596108) (xy 52.586128 -15.605506) (xy 52.57927 -15.613634) (xy 52.561081 -15.634885)
			(xy 52.519485 -15.672284) (xy 52.472876 -15.703212) (xy 52.422253 -15.727007) (xy 52.368699 -15.743158)
			(xy 52.31336 -15.751321) (xy 52.285392 -15.75181) (xy 52.258141 -15.75132) (xy 52.204195 -15.743562)
			(xy 52.151901 -15.728207) (xy 52.102325 -15.705565) (xy 52.056476 -15.676099) (xy 52.015287 -15.640407)
			(xy 51.979596 -15.599218) (xy 51.950131 -15.553368) (xy 51.927491 -15.503791) (xy 51.912136 -15.451497)
			(xy 51.90438 -15.397551) (xy 46.738608 -15.397551) (xy 46.746282 -15.463137) (xy 46.753519 -15.58558)
			(xy 46.754034 -15.646908) (xy 46.754034 -15.665958) (xy 46.753047 -15.731376) (xy 46.744051 -15.861914)
			(xy 46.727075 -15.991656) (xy 46.702181 -16.120113) (xy 46.669464 -16.246804) (xy 46.629047 -16.371253)
			(xy 46.58108 -16.492992) (xy 46.525745 -16.611563) (xy 46.46325 -16.726521) (xy 46.393829 -16.837434)
			(xy 46.317743 -16.943886) (xy 46.29655 -16.969994) (xy 65.748161 -16.969994) (xy 65.752166 -16.882086)
			(xy 65.764149 -16.794906) (xy 65.784009 -16.709177) (xy 65.811584 -16.625609) (xy 65.846643 -16.544895)
			(xy 65.888896 -16.467703) (xy 65.937994 -16.394674) (xy 65.99353 -16.326412) (xy 66.055042 -16.263482)
			(xy 66.122023 -16.206408) (xy 66.193916 -16.15566) (xy 66.270125 -16.11166) (xy 66.35002 -16.074773)
			(xy 66.432939 -16.045304) (xy 66.518194 -16.023497) (xy 66.605078 -16.009533) (xy 66.692872 -16.003527)
			(xy 66.780849 -16.005531) (xy 66.868279 -16.015526) (xy 66.954438 -16.03343) (xy 67.038612 -16.059094)
			(xy 67.120103 -16.092307) (xy 67.198237 -16.132793) (xy 67.272365 -16.180215) (xy 67.341873 -16.234182)
			(xy 67.406187 -16.294247) (xy 67.464771 -16.359911) (xy 67.517142 -16.43063) (xy 67.562865 -16.505818)
			(xy 67.601562 -16.584853) (xy 67.632911 -16.667079) (xy 67.656653 -16.751815) (xy 67.672591 -16.838359)
			(xy 67.680593 -16.925994) (xy 67.681094 -16.969994) (xy 67.680593 -17.013994) (xy 67.672591 -17.101629)
			(xy 67.656653 -17.188173) (xy 67.632911 -17.272909) (xy 67.601562 -17.355135) (xy 67.562865 -17.43417)
			(xy 67.517142 -17.509358) (xy 67.464771 -17.580077) (xy 67.406187 -17.645741) (xy 67.341873 -17.705806)
			(xy 67.272365 -17.759773) (xy 67.198237 -17.807195) (xy 67.120103 -17.847681) (xy 67.038612 -17.880894)
			(xy 66.954438 -17.906558) (xy 66.868279 -17.924462) (xy 66.780849 -17.934457) (xy 66.692872 -17.936461)
			(xy 66.605078 -17.930455) (xy 66.518194 -17.916491) (xy 66.432939 -17.894684) (xy 66.35002 -17.865215)
			(xy 66.270125 -17.828328) (xy 66.193916 -17.784328) (xy 66.122023 -17.73358) (xy 66.055042 -17.676506)
			(xy 65.99353 -17.613576) (xy 65.937994 -17.545314) (xy 65.888896 -17.472285) (xy 65.846643 -17.395093)
			(xy 65.811584 -17.314379) (xy 65.784009 -17.230811) (xy 65.764149 -17.145082) (xy 65.752166 -17.057902)
			(xy 65.748161 -16.969994) (xy 46.29655 -16.969994) (xy 46.235277 -17.045476) (xy 46.146743 -17.141823)
			(xy 46.052472 -17.232564) (xy 45.952818 -17.317359) (xy 45.848157 -17.39589) (xy 45.812196 -17.419574)
			(xy 50.284124 -17.419574) (xy 50.288195 -17.363952) (xy 50.300321 -17.309515) (xy 50.320244 -17.257424)
			(xy 50.34754 -17.208789) (xy 50.381626 -17.164646) (xy 50.421775 -17.125937) (xy 50.467133 -17.093486)
			(xy 50.516733 -17.067985) (xy 50.569517 -17.049978) (xy 50.62436 -17.039848) (xy 50.680094 -17.037811)
			(xy 50.735531 -17.043911) (xy 50.789488 -17.058017) (xy 50.840817 -17.079829) (xy 50.888423 -17.108883)
			(xy 50.931291 -17.144558) (xy 50.968508 -17.186095) (xy 50.999281 -17.232608) (xy 51.022953 -17.283105)
			(xy 51.039021 -17.336512) (xy 51.047141 -17.391688) (xy 51.04765 -17.419574) (xy 51.047141 -17.44746)
			(xy 51.039021 -17.502636) (xy 51.022953 -17.556043) (xy 50.999281 -17.60654) (xy 50.968508 -17.653053)
			(xy 50.931291 -17.69459) (xy 50.888423 -17.730265) (xy 50.840817 -17.759319) (xy 50.789488 -17.781131)
			(xy 50.735531 -17.795237) (xy 50.680094 -17.801337) (xy 50.62436 -17.7993) (xy 50.569517 -17.78917)
			(xy 50.516733 -17.771163) (xy 50.467133 -17.745662) (xy 50.421775 -17.713211) (xy 50.381626 -17.674502)
			(xy 50.34754 -17.630359) (xy 50.320244 -17.581724) (xy 50.300321 -17.529633) (xy 50.288195 -17.475196)
			(xy 50.284124 -17.419574) (xy 45.812196 -17.419574) (xy 45.73888 -17.46786) (xy 45.6254 -17.533001)
			(xy 45.508142 -17.591066) (xy 45.387546 -17.641838) (xy 45.264067 -17.685126) (xy 45.138167 -17.720768)
			(xy 45.01032 -17.748629) (xy 44.881007 -17.768605) (xy 44.750712 -17.78062) (xy 44.619926 -17.78463)
			(xy 44.48914 -17.78062) (xy 44.358845 -17.768605) (xy 44.229532 -17.748629) (xy 44.101685 -17.720768)
			(xy 43.975785 -17.685126) (xy 43.852306 -17.641838) (xy 43.73171 -17.591066) (xy 43.614452 -17.533001)
			(xy 43.500972 -17.46786) (xy 43.391695 -17.39589) (xy 43.287034 -17.317359) (xy 43.18738 -17.232564)
			(xy 43.093109 -17.141823) (xy 43.004575 -17.045476) (xy 42.922109 -16.943886) (xy 42.846023 -16.837434)
			(xy 42.776602 -16.726521) (xy 42.714107 -16.611563) (xy 42.658772 -16.492992) (xy 42.610805 -16.371253)
			(xy 42.570388 -16.246804) (xy 42.537671 -16.120113) (xy 42.512777 -15.991656) (xy 42.495801 -15.861914)
			(xy 42.486805 -15.731376) (xy 42.485818 -15.665958) (xy 42.485818 -15.649702) (xy 42.486309 -15.585401)
			(xy 42.494072 -15.457032) (xy 42.509552 -15.329365) (xy 42.532693 -15.202861) (xy 42.563411 -15.07798)
			(xy 42.601594 -14.955177) (xy 42.647104 -14.834896) (xy 42.699775 -14.717574) (xy 42.72915 -14.660372)
			(xy 42.730674 -14.657324) (xy 42.732817 -14.652126) (xy 42.735007 -14.641102) (xy 42.734992 -14.63548)
			(xy 42.734484 -14.622018) (xy 42.718228 -14.595094) (xy 42.718228 -14.594586) (xy 42.68216 -14.535658)
			(xy 42.678606 -14.530155) (xy 42.669218 -14.521024) (xy 42.663618 -14.517624) (xy 42.658284 -14.51483)
			(xy 42.650156 -14.512798) (xy 42.639234 -14.511528) (xy 33.077912 -14.511528) (xy 33.06784 -14.511108)
			(xy 33.04923 -14.5034) (xy 33.041844 -14.496542) (xy 32.32785 -13.782548) (xy 32.321006 -13.775149)
			(xy 32.313283 -13.75655) (xy 32.312864 -13.74648) (xy 32.312864 -1.941576) (xy 32.3127 -1.935566)
			(xy 32.309879 -1.923881) (xy 32.307276 -1.918462) (xy 32.305435 -1.914989) (xy 32.300838 -1.908614)
			(xy 32.298132 -1.905762) (xy 31.773114 -1.380744) (xy 31.770264 -1.378037) (xy 31.763887 -1.373442)
			(xy 31.760414 -1.3716) (xy 31.754986 -1.369021) (xy 31.743307 -1.366208) (xy 31.7373 -1.366012) (xy 19.998944 -1.366012)
			(xy 19.992935 -1.36618) (xy 19.981253 -1.369006) (xy 19.97583 -1.3716) (xy 19.972354 -1.373437) (xy 19.965971 -1.378026)
			(xy 19.96313 -1.380744) (xy 19.495516 -1.848358) (xy 19.492809 -1.851208) (xy 19.488213 -1.857585)
			(xy 19.486372 -1.861058) (xy 19.483792 -1.866486) (xy 19.480973 -1.878165) (xy 19.480784 -1.884172)
			(xy 19.480784 -13.649198) (xy 19.481016 -13.656467) (xy 19.485153 -13.670403) (xy 19.488912 -13.67663)
			(xy 19.506438 -13.704316) (xy 19.517106 -13.71346) (xy 19.52371 -13.716508) (xy 19.580755 -13.743684)
			(xy 19.691871 -13.803871) (xy 19.799232 -13.870529) (xy 19.902459 -13.943425) (xy 20.001191 -14.022301)
			(xy 20.095082 -14.106882) (xy 20.183803 -14.196872) (xy 20.267043 -14.291954) (xy 20.344509 -14.391796)
			(xy 20.415931 -14.496048) (xy 20.481058 -14.604344) (xy 20.510754 -14.660118) (xy 20.513294 -14.665198)
			(xy 20.516596 -14.671548) (xy 20.522438 -14.682978) (xy 20.529296 -14.69644) (xy 20.531074 -14.70025)
			(xy 20.557974 -14.755366) (xy 20.60616 -14.868162) (xy 20.647791 -14.983539) (xy 20.682728 -15.101115)
			(xy 20.710856 -15.220504) (xy 20.732083 -15.34131) (xy 20.746339 -15.463136) (xy 20.753576 -15.58558)
			(xy 20.754086 -15.646908) (xy 20.754086 -15.665958) (xy 20.753099 -15.731376) (xy 20.744103 -15.861914)
			(xy 20.727127 -15.991656) (xy 20.702233 -16.120113) (xy 20.669516 -16.246804) (xy 20.629099 -16.371253)
			(xy 20.581132 -16.492992) (xy 20.525797 -16.611563) (xy 20.463302 -16.726521) (xy 20.393881 -16.837434)
			(xy 20.317795 -16.943886) (xy 20.296602 -16.969994) (xy 39.748213 -16.969994) (xy 39.752218 -16.882086)
			(xy 39.764201 -16.794906) (xy 39.784061 -16.709177) (xy 39.811636 -16.625609) (xy 39.846695 -16.544895)
			(xy 39.888948 -16.467703) (xy 39.938046 -16.394674) (xy 39.993582 -16.326412) (xy 40.055094 -16.263482)
			(xy 40.122075 -16.206408) (xy 40.193968 -16.15566) (xy 40.270177 -16.11166) (xy 40.350072 -16.074773)
			(xy 40.432991 -16.045304) (xy 40.518246 -16.023497) (xy 40.60513 -16.009533) (xy 40.692924 -16.003527)
			(xy 40.780901 -16.005531) (xy 40.868331 -16.015526) (xy 40.95449 -16.03343) (xy 41.038664 -16.059094)
			(xy 41.120155 -16.092307) (xy 41.198289 -16.132793) (xy 41.272417 -16.180215) (xy 41.341925 -16.234182)
			(xy 41.406239 -16.294247) (xy 41.464823 -16.359911) (xy 41.517194 -16.43063) (xy 41.562917 -16.505818)
			(xy 41.601614 -16.584853) (xy 41.632963 -16.667079) (xy 41.656705 -16.751815) (xy 41.672643 -16.838359)
			(xy 41.680645 -16.925994) (xy 41.681146 -16.969994) (xy 41.680645 -17.013994) (xy 41.672643 -17.101629)
			(xy 41.656705 -17.188173) (xy 41.632963 -17.272909) (xy 41.601614 -17.355135) (xy 41.562917 -17.43417)
			(xy 41.517194 -17.509358) (xy 41.464823 -17.580077) (xy 41.406239 -17.645741) (xy 41.341925 -17.705806)
			(xy 41.272417 -17.759773) (xy 41.198289 -17.807195) (xy 41.120155 -17.847681) (xy 41.038664 -17.880894)
			(xy 40.95449 -17.906558) (xy 40.868331 -17.924462) (xy 40.780901 -17.934457) (xy 40.692924 -17.936461)
			(xy 40.60513 -17.930455) (xy 40.518246 -17.916491) (xy 40.432991 -17.894684) (xy 40.350072 -17.865215)
			(xy 40.270177 -17.828328) (xy 40.193968 -17.784328) (xy 40.122075 -17.73358) (xy 40.055094 -17.676506)
			(xy 39.993582 -17.613576) (xy 39.938046 -17.545314) (xy 39.888948 -17.472285) (xy 39.846695 -17.395093)
			(xy 39.811636 -17.314379) (xy 39.784061 -17.230811) (xy 39.764201 -17.145082) (xy 39.752218 -17.057902)
			(xy 39.748213 -16.969994) (xy 20.296602 -16.969994) (xy 20.235329 -17.045476) (xy 20.146795 -17.141823)
			(xy 20.052524 -17.232564) (xy 19.95287 -17.317359) (xy 19.848209 -17.39589) (xy 19.738932 -17.46786)
			(xy 19.625452 -17.533001) (xy 19.508194 -17.591066) (xy 19.387598 -17.641838) (xy 19.264119 -17.685126)
			(xy 19.138219 -17.720768) (xy 19.010372 -17.748629) (xy 18.881059 -17.768605) (xy 18.750764 -17.78062)
			(xy 18.619978 -17.78463) (xy 18.489192 -17.78062) (xy 18.358897 -17.768605) (xy 18.229584 -17.748629)
			(xy 18.101737 -17.720768) (xy 17.975837 -17.685126) (xy 17.852358 -17.641838) (xy 17.731762 -17.591066)
			(xy 17.614504 -17.533001) (xy 17.501024 -17.46786) (xy 17.391747 -17.39589) (xy 17.287086 -17.317359)
			(xy 17.187432 -17.232564) (xy 17.093161 -17.141823) (xy 17.004627 -17.045476) (xy 16.922161 -16.943886)
			(xy 16.846075 -16.837434) (xy 16.776654 -16.726521) (xy 16.714159 -16.611563) (xy 16.658824 -16.492992)
			(xy 16.610857 -16.371253) (xy 16.57044 -16.246804) (xy 16.537723 -16.120113) (xy 16.512829 -15.991656)
			(xy 16.495853 -15.861914) (xy 16.486857 -15.731376) (xy 16.48587 -15.665958) (xy 16.48587 -15.649702)
			(xy 16.486361 -15.585401) (xy 16.494124 -15.457032) (xy 16.509604 -15.329364) (xy 16.532744 -15.20286)
			(xy 16.563461 -15.07798) (xy 16.601644 -14.955176) (xy 16.647152 -14.834894) (xy 16.699823 -14.717571)
			(xy 16.729202 -14.660372) (xy 16.730726 -14.657324) (xy 16.732871 -14.652127) (xy 16.735063 -14.641102)
			(xy 16.735044 -14.63548) (xy 16.734536 -14.622018) (xy 16.71828 -14.595094) (xy 16.71828 -14.594586)
			(xy 16.682212 -14.535658) (xy 16.67866 -14.530152) (xy 16.669277 -14.521013) (xy 16.66367 -14.517624)
			(xy 16.658336 -14.51483) (xy 16.650208 -14.512798) (xy 16.639286 -14.511528) (xy 3.121406 -14.511528)
			(xy 3.113123 -14.511843) (xy 3.097431 -14.517147) (xy 3.090672 -14.521942) (xy 3.089148 -14.523212)
			(xy 3.086608 -14.525752) (xy 3.084322 -14.528038) (xy 3.082544 -14.529308) (xy 2.483104 -15.128748)
			(xy 7.834882 -15.128748) (xy 7.838953 -15.073126) (xy 7.851079 -15.018689) (xy 7.871002 -14.966598)
			(xy 7.898298 -14.917963) (xy 7.932384 -14.87382) (xy 7.972533 -14.835111) (xy 8.017891 -14.80266)
			(xy 8.067491 -14.777159) (xy 8.120275 -14.759152) (xy 8.175118 -14.749022) (xy 8.230852 -14.746985)
			(xy 8.286289 -14.753085) (xy 8.340246 -14.767191) (xy 8.391575 -14.789003) (xy 8.439181 -14.818057)
			(xy 8.482049 -14.853732) (xy 8.519266 -14.895269) (xy 8.550039 -14.941782) (xy 8.573711 -14.992279)
			(xy 8.589779 -15.045686) (xy 8.597899 -15.100862) (xy 8.598408 -15.128748) (xy 8.597899 -15.156634)
			(xy 8.589779 -15.21181) (xy 8.573711 -15.265217) (xy 8.550039 -15.315714) (xy 8.519266 -15.362227)
			(xy 8.482049 -15.403764) (xy 8.439181 -15.439439) (xy 8.391575 -15.468493) (xy 8.340246 -15.490305)
			(xy 8.286289 -15.504411) (xy 8.230852 -15.510511) (xy 8.175118 -15.508474) (xy 8.120275 -15.498344)
			(xy 8.067491 -15.480337) (xy 8.017891 -15.454836) (xy 7.972533 -15.422385) (xy 7.932384 -15.383676)
			(xy 7.898298 -15.339533) (xy 7.871002 -15.290898) (xy 7.851079 -15.238807) (xy 7.838953 -15.18437)
			(xy 7.834882 -15.128748) (xy 2.483104 -15.128748) (xy 1.467104 -16.144748) (xy 7.834882 -16.144748)
			(xy 7.838953 -16.089126) (xy 7.851079 -16.034689) (xy 7.871002 -15.982598) (xy 7.898298 -15.933963)
			(xy 7.932384 -15.88982) (xy 7.972533 -15.851111) (xy 8.017891 -15.81866) (xy 8.067491 -15.793159)
			(xy 8.120275 -15.775152) (xy 8.175118 -15.765022) (xy 8.230852 -15.762985) (xy 8.286289 -15.769085)
			(xy 8.340246 -15.783191) (xy 8.391575 -15.805003) (xy 8.439181 -15.834057) (xy 8.482049 -15.869732)
			(xy 8.519266 -15.911269) (xy 8.550039 -15.957782) (xy 8.573711 -16.008279) (xy 8.589779 -16.061686)
			(xy 8.597899 -16.116862) (xy 8.598408 -16.144748) (xy 8.597899 -16.172634) (xy 8.589779 -16.22781)
			(xy 8.573711 -16.281217) (xy 8.550039 -16.331714) (xy 8.519266 -16.378227) (xy 8.482049 -16.419764)
			(xy 8.439181 -16.455439) (xy 8.391575 -16.484493) (xy 8.340246 -16.506305) (xy 8.286289 -16.520411)
			(xy 8.230852 -16.526511) (xy 8.175118 -16.524474) (xy 8.120275 -16.514344) (xy 8.067491 -16.496337)
			(xy 8.017891 -16.470836) (xy 7.972533 -16.438385) (xy 7.932384 -16.399676) (xy 7.898298 -16.355533)
			(xy 7.871002 -16.306898) (xy 7.851079 -16.254807) (xy 7.838953 -16.20037) (xy 7.834882 -16.144748)
			(xy 1.467104 -16.144748) (xy 1.321308 -16.290544) (xy 1.317787 -16.294275) (xy 1.31216 -16.30285)
			(xy 1.310132 -16.307562) (xy 1.306576 -16.316198) (xy 1.306576 -17.160748) (xy 7.834882 -17.160748)
			(xy 7.838953 -17.105126) (xy 7.851079 -17.050689) (xy 7.871002 -16.998598) (xy 7.898298 -16.949963)
			(xy 7.932384 -16.90582) (xy 7.972533 -16.867111) (xy 8.017891 -16.83466) (xy 8.067491 -16.809159)
			(xy 8.120275 -16.791152) (xy 8.175118 -16.781022) (xy 8.230852 -16.778985) (xy 8.286289 -16.785085)
			(xy 8.340246 -16.799191) (xy 8.391575 -16.821003) (xy 8.439181 -16.850057) (xy 8.482049 -16.885732)
			(xy 8.519266 -16.927269) (xy 8.547533 -16.969994) (xy 13.748265 -16.969994) (xy 13.75227 -16.882086)
			(xy 13.764253 -16.794906) (xy 13.784113 -16.709177) (xy 13.811688 -16.625609) (xy 13.846747 -16.544895)
			(xy 13.889 -16.467703) (xy 13.938098 -16.394674) (xy 13.993634 -16.326412) (xy 14.055146 -16.263482)
			(xy 14.122127 -16.206408) (xy 14.19402 -16.15566) (xy 14.270229 -16.11166) (xy 14.350124 -16.074773)
			(xy 14.433043 -16.045304) (xy 14.518298 -16.023497) (xy 14.605182 -16.009533) (xy 14.692976 -16.003527)
			(xy 14.780953 -16.005531) (xy 14.868383 -16.015526) (xy 14.954542 -16.03343) (xy 15.038716 -16.059094)
			(xy 15.120207 -16.092307) (xy 15.198341 -16.132793) (xy 15.272469 -16.180215) (xy 15.341977 -16.234182)
			(xy 15.406291 -16.294247) (xy 15.464875 -16.359911) (xy 15.517246 -16.43063) (xy 15.562969 -16.505818)
			(xy 15.601666 -16.584853) (xy 15.633015 -16.667079) (xy 15.656757 -16.751815) (xy 15.672695 -16.838359)
			(xy 15.680697 -16.925994) (xy 15.681198 -16.969994) (xy 15.680697 -17.013994) (xy 15.672695 -17.101629)
			(xy 15.656757 -17.188173) (xy 15.633015 -17.272909) (xy 15.601666 -17.355135) (xy 15.562969 -17.43417)
			(xy 15.517246 -17.509358) (xy 15.464875 -17.580077) (xy 15.406291 -17.645741) (xy 15.341977 -17.705806)
			(xy 15.272469 -17.759773) (xy 15.198341 -17.807195) (xy 15.120207 -17.847681) (xy 15.038716 -17.880894)
			(xy 14.954542 -17.906558) (xy 14.868383 -17.924462) (xy 14.780953 -17.934457) (xy 14.692976 -17.936461)
			(xy 14.605182 -17.930455) (xy 14.518298 -17.916491) (xy 14.433043 -17.894684) (xy 14.350124 -17.865215)
			(xy 14.270229 -17.828328) (xy 14.19402 -17.784328) (xy 14.122127 -17.73358) (xy 14.055146 -17.676506)
			(xy 13.993634 -17.613576) (xy 13.938098 -17.545314) (xy 13.889 -17.472285) (xy 13.846747 -17.395093)
			(xy 13.811688 -17.314379) (xy 13.784113 -17.230811) (xy 13.764253 -17.145082) (xy 13.75227 -17.057902)
			(xy 13.748265 -16.969994) (xy 8.547533 -16.969994) (xy 8.550039 -16.973782) (xy 8.573711 -17.024279)
			(xy 8.589779 -17.077686) (xy 8.597899 -17.132862) (xy 8.598408 -17.160748) (xy 8.597899 -17.188634)
			(xy 8.589779 -17.24381) (xy 8.573711 -17.297217) (xy 8.550039 -17.347714) (xy 8.519266 -17.394227)
			(xy 8.482049 -17.435764) (xy 8.439181 -17.471439) (xy 8.391575 -17.500493) (xy 8.340246 -17.522305)
			(xy 8.286289 -17.536411) (xy 8.230852 -17.542511) (xy 8.175118 -17.540474) (xy 8.120275 -17.530344)
			(xy 8.067491 -17.512337) (xy 8.017891 -17.486836) (xy 7.972533 -17.454385) (xy 7.932384 -17.415676)
			(xy 7.898298 -17.371533) (xy 7.871002 -17.322898) (xy 7.851079 -17.270807) (xy 7.838953 -17.21637)
			(xy 7.834882 -17.160748) (xy 1.306576 -17.160748) (xy 1.306576 -18.029174) (xy 1.464816 -18.029174)
			(xy 1.468887 -17.973552) (xy 1.481013 -17.919115) (xy 1.500936 -17.867024) (xy 1.528232 -17.818389)
			(xy 1.562318 -17.774246) (xy 1.602467 -17.735537) (xy 1.647825 -17.703086) (xy 1.697425 -17.677585)
			(xy 1.750209 -17.659578) (xy 1.805052 -17.649448) (xy 1.860786 -17.647411) (xy 1.916223 -17.653511)
			(xy 1.97018 -17.667617) (xy 2.021509 -17.689429) (xy 2.069115 -17.718483) (xy 2.111983 -17.754158)
			(xy 2.1492 -17.795695) (xy 2.179973 -17.842208) (xy 2.203645 -17.892705) (xy 2.219713 -17.946112)
			(xy 2.227833 -18.001288) (xy 2.228342 -18.029174) (xy 2.227833 -18.05706) (xy 2.219713 -18.112236)
			(xy 2.203645 -18.165643) (xy 2.179973 -18.21614) (xy 2.1492 -18.262653) (xy 2.111983 -18.30419) (xy 2.069115 -18.339865)
			(xy 2.021509 -18.368919) (xy 1.97018 -18.390731) (xy 1.916223 -18.404837) (xy 1.860786 -18.410937)
			(xy 1.805052 -18.4089) (xy 1.750209 -18.39877) (xy 1.697425 -18.380763) (xy 1.647825 -18.355262)
			(xy 1.602467 -18.322811) (xy 1.562318 -18.284102) (xy 1.528232 -18.239959) (xy 1.500936 -18.191324)
			(xy 1.481013 -18.139233) (xy 1.468887 -18.084796) (xy 1.464816 -18.029174) (xy 1.306576 -18.029174)
			(xy 1.306576 -18.44421) (xy 48.276254 -18.44421) (xy 48.280325 -18.388588) (xy 48.292451 -18.334151)
			(xy 48.312374 -18.28206) (xy 48.33967 -18.233425) (xy 48.373756 -18.189282) (xy 48.413905 -18.150573)
			(xy 48.459263 -18.118122) (xy 48.508863 -18.092621) (xy 48.561647 -18.074614) (xy 48.61649 -18.064484)
			(xy 48.672224 -18.062447) (xy 48.727661 -18.068547) (xy 48.781618 -18.082653) (xy 48.832947 -18.104465)
			(xy 48.880553 -18.133519) (xy 48.923421 -18.169194) (xy 48.960638 -18.210731) (xy 48.991411 -18.257244)
			(xy 49.015083 -18.307741) (xy 49.031151 -18.361148) (xy 49.039271 -18.416324) (xy 49.03978 -18.44421)
			(xy 74.276202 -18.44421) (xy 74.280273 -18.388588) (xy 74.292399 -18.334151) (xy 74.312322 -18.28206)
			(xy 74.339618 -18.233425) (xy 74.373704 -18.189282) (xy 74.413853 -18.150573) (xy 74.459211 -18.118122)
			(xy 74.508811 -18.092621) (xy 74.561595 -18.074614) (xy 74.616438 -18.064484) (xy 74.672172 -18.062447)
			(xy 74.727609 -18.068547) (xy 74.781566 -18.082653) (xy 74.832895 -18.104465) (xy 74.880501 -18.133519)
			(xy 74.923369 -18.169194) (xy 74.960586 -18.210731) (xy 74.991359 -18.257244) (xy 75.015031 -18.307741)
			(xy 75.031099 -18.361148) (xy 75.039219 -18.416324) (xy 75.039728 -18.44421) (xy 138.376404 -18.44421)
			(xy 138.380475 -18.388588) (xy 138.392601 -18.334151) (xy 138.412524 -18.28206) (xy 138.43982 -18.233425)
			(xy 138.473906 -18.189282) (xy 138.514055 -18.150573) (xy 138.559413 -18.118122) (xy 138.609013 -18.092621)
			(xy 138.661797 -18.074614) (xy 138.71664 -18.064484) (xy 138.772374 -18.062447) (xy 138.827811 -18.068547)
			(xy 138.881768 -18.082653) (xy 138.933097 -18.104465) (xy 138.980703 -18.133519) (xy 139.023571 -18.169194)
			(xy 139.060788 -18.210731) (xy 139.091561 -18.257244) (xy 139.115233 -18.307741) (xy 139.131301 -18.361148)
			(xy 139.139421 -18.416324) (xy 139.13993 -18.44421) (xy 164.376352 -18.44421) (xy 164.380423 -18.388588)
			(xy 164.392549 -18.334151) (xy 164.412472 -18.28206) (xy 164.439768 -18.233425) (xy 164.473854 -18.189282)
			(xy 164.514003 -18.150573) (xy 164.559361 -18.118122) (xy 164.608961 -18.092621) (xy 164.661745 -18.074614)
			(xy 164.716588 -18.064484) (xy 164.772322 -18.062447) (xy 164.827759 -18.068547) (xy 164.881716 -18.082653)
			(xy 164.933045 -18.104465) (xy 164.980651 -18.133519) (xy 165.023519 -18.169194) (xy 165.060736 -18.210731)
			(xy 165.091509 -18.257244) (xy 165.115181 -18.307741) (xy 165.131249 -18.361148) (xy 165.139369 -18.416324)
			(xy 165.139878 -18.44421) (xy 190.3763 -18.44421) (xy 190.380371 -18.388588) (xy 190.392497 -18.334151)
			(xy 190.41242 -18.28206) (xy 190.439716 -18.233425) (xy 190.473802 -18.189282) (xy 190.513951 -18.150573)
			(xy 190.559309 -18.118122) (xy 190.608909 -18.092621) (xy 190.661693 -18.074614) (xy 190.716536 -18.064484)
			(xy 190.77227 -18.062447) (xy 190.827707 -18.068547) (xy 190.881664 -18.082653) (xy 190.932993 -18.104465)
			(xy 190.980599 -18.133519) (xy 191.023467 -18.169194) (xy 191.060684 -18.210731) (xy 191.091457 -18.257244)
			(xy 191.115129 -18.307741) (xy 191.131197 -18.361148) (xy 191.139317 -18.416324) (xy 191.139826 -18.44421)
			(xy 216.376248 -18.44421) (xy 216.380319 -18.388588) (xy 216.392445 -18.334151) (xy 216.412368 -18.28206)
			(xy 216.439664 -18.233425) (xy 216.47375 -18.189282) (xy 216.513899 -18.150573) (xy 216.559257 -18.118122)
			(xy 216.608857 -18.092621) (xy 216.661641 -18.074614) (xy 216.716484 -18.064484) (xy 216.772218 -18.062447)
			(xy 216.827655 -18.068547) (xy 216.881612 -18.082653) (xy 216.932941 -18.104465) (xy 216.980547 -18.133519)
			(xy 217.023415 -18.169194) (xy 217.060632 -18.210731) (xy 217.091405 -18.257244) (xy 217.115077 -18.307741)
			(xy 217.131145 -18.361148) (xy 217.139265 -18.416324) (xy 217.139774 -18.44421) (xy 254.476248 -18.44421)
			(xy 254.480319 -18.388588) (xy 254.492445 -18.334151) (xy 254.512368 -18.28206) (xy 254.539664 -18.233425)
			(xy 254.57375 -18.189282) (xy 254.613899 -18.150573) (xy 254.659257 -18.118122) (xy 254.708857 -18.092621)
			(xy 254.761641 -18.074614) (xy 254.816484 -18.064484) (xy 254.872218 -18.062447) (xy 254.927655 -18.068547)
			(xy 254.981612 -18.082653) (xy 255.032941 -18.104465) (xy 255.080547 -18.133519) (xy 255.123415 -18.169194)
			(xy 255.160632 -18.210731) (xy 255.191405 -18.257244) (xy 255.215077 -18.307741) (xy 255.231145 -18.361148)
			(xy 255.239265 -18.416324) (xy 255.239774 -18.44421) (xy 280.476196 -18.44421) (xy 280.480267 -18.388588)
			(xy 280.492393 -18.334151) (xy 280.512316 -18.28206) (xy 280.539612 -18.233425) (xy 280.573698 -18.189282)
			(xy 280.613847 -18.150573) (xy 280.659205 -18.118122) (xy 280.708805 -18.092621) (xy 280.761589 -18.074614)
			(xy 280.816432 -18.064484) (xy 280.872166 -18.062447) (xy 280.927603 -18.068547) (xy 280.98156 -18.082653)
			(xy 281.032889 -18.104465) (xy 281.080495 -18.133519) (xy 281.123363 -18.169194) (xy 281.16058 -18.210731)
			(xy 281.191353 -18.257244) (xy 281.215025 -18.307741) (xy 281.231093 -18.361148) (xy 281.239213 -18.416324)
			(xy 281.239722 -18.44421) (xy 306.476144 -18.44421) (xy 306.480215 -18.388588) (xy 306.492341 -18.334151)
			(xy 306.512264 -18.28206) (xy 306.53956 -18.233425) (xy 306.573646 -18.189282) (xy 306.613795 -18.150573)
			(xy 306.659153 -18.118122) (xy 306.708753 -18.092621) (xy 306.761537 -18.074614) (xy 306.81638 -18.064484)
			(xy 306.872114 -18.062447) (xy 306.927551 -18.068547) (xy 306.981508 -18.082653) (xy 307.032837 -18.104465)
			(xy 307.080443 -18.133519) (xy 307.123311 -18.169194) (xy 307.160528 -18.210731) (xy 307.191301 -18.257244)
			(xy 307.214973 -18.307741) (xy 307.231041 -18.361148) (xy 307.239161 -18.416324) (xy 307.23967 -18.44421)
			(xy 370.576346 -18.44421) (xy 370.580417 -18.388588) (xy 370.592543 -18.334151) (xy 370.612466 -18.28206)
			(xy 370.639762 -18.233425) (xy 370.673848 -18.189282) (xy 370.713997 -18.150573) (xy 370.759355 -18.118122)
			(xy 370.808955 -18.092621) (xy 370.861739 -18.074614) (xy 370.916582 -18.064484) (xy 370.972316 -18.062447)
			(xy 371.027753 -18.068547) (xy 371.08171 -18.082653) (xy 371.133039 -18.104465) (xy 371.180645 -18.133519)
			(xy 371.223513 -18.169194) (xy 371.26073 -18.210731) (xy 371.291503 -18.257244) (xy 371.315175 -18.307741)
			(xy 371.331243 -18.361148) (xy 371.339363 -18.416324) (xy 371.339872 -18.44421) (xy 396.576294 -18.44421)
			(xy 396.580365 -18.388588) (xy 396.592491 -18.334151) (xy 396.612414 -18.28206) (xy 396.63971 -18.233425)
			(xy 396.673796 -18.189282) (xy 396.713945 -18.150573) (xy 396.759303 -18.118122) (xy 396.808903 -18.092621)
			(xy 396.861687 -18.074614) (xy 396.91653 -18.064484) (xy 396.972264 -18.062447) (xy 397.027701 -18.068547)
			(xy 397.081658 -18.082653) (xy 397.132987 -18.104465) (xy 397.180593 -18.133519) (xy 397.223461 -18.169194)
			(xy 397.260678 -18.210731) (xy 397.291451 -18.257244) (xy 397.315123 -18.307741) (xy 397.331191 -18.361148)
			(xy 397.339311 -18.416324) (xy 397.33982 -18.44421) (xy 422.576242 -18.44421) (xy 422.580313 -18.388588)
			(xy 422.592439 -18.334151) (xy 422.612362 -18.28206) (xy 422.639658 -18.233425) (xy 422.673744 -18.189282)
			(xy 422.713893 -18.150573) (xy 422.759251 -18.118122) (xy 422.808851 -18.092621) (xy 422.861635 -18.074614)
			(xy 422.916478 -18.064484) (xy 422.972212 -18.062447) (xy 423.027649 -18.068547) (xy 423.081606 -18.082653)
			(xy 423.132935 -18.104465) (xy 423.180541 -18.133519) (xy 423.223409 -18.169194) (xy 423.260626 -18.210731)
			(xy 423.291399 -18.257244) (xy 423.315071 -18.307741) (xy 423.331139 -18.361148) (xy 423.339259 -18.416324)
			(xy 423.339768 -18.44421) (xy 448.57619 -18.44421) (xy 448.580261 -18.388588) (xy 448.592387 -18.334151)
			(xy 448.61231 -18.28206) (xy 448.639606 -18.233425) (xy 448.673692 -18.189282) (xy 448.713841 -18.150573)
			(xy 448.759199 -18.118122) (xy 448.808799 -18.092621) (xy 448.861583 -18.074614) (xy 448.916426 -18.064484)
			(xy 448.97216 -18.062447) (xy 449.027597 -18.068547) (xy 449.081554 -18.082653) (xy 449.132883 -18.104465)
			(xy 449.180489 -18.133519) (xy 449.223357 -18.169194) (xy 449.260574 -18.210731) (xy 449.291347 -18.257244)
			(xy 449.29481 -18.264632) (xy 454.446638 -18.264632) (xy 454.450709 -18.20901) (xy 454.462835 -18.154573)
			(xy 454.482758 -18.102482) (xy 454.510054 -18.053847) (xy 454.54414 -18.009704) (xy 454.584289 -17.970995)
			(xy 454.629647 -17.938544) (xy 454.679247 -17.913043) (xy 454.732031 -17.895036) (xy 454.786874 -17.884906)
			(xy 454.842608 -17.882869) (xy 454.898045 -17.888969) (xy 454.952002 -17.903075) (xy 455.003331 -17.924887)
			(xy 455.050937 -17.953941) (xy 455.093805 -17.989616) (xy 455.131022 -18.031153) (xy 455.161795 -18.077666)
			(xy 455.185467 -18.128163) (xy 455.201535 -18.18157) (xy 455.209655 -18.236746) (xy 455.210164 -18.264632)
			(xy 455.209655 -18.292518) (xy 455.201535 -18.347694) (xy 455.185467 -18.401101) (xy 455.161795 -18.451598)
			(xy 455.131022 -18.498111) (xy 455.093805 -18.539648) (xy 455.050937 -18.575323) (xy 455.003331 -18.604377)
			(xy 454.952002 -18.626189) (xy 454.898045 -18.640295) (xy 454.842608 -18.646395) (xy 454.786874 -18.644358)
			(xy 454.732031 -18.634228) (xy 454.679247 -18.616221) (xy 454.629647 -18.59072) (xy 454.584289 -18.558269)
			(xy 454.54414 -18.51956) (xy 454.510054 -18.475417) (xy 454.482758 -18.426782) (xy 454.462835 -18.374691)
			(xy 454.450709 -18.320254) (xy 454.446638 -18.264632) (xy 449.29481 -18.264632) (xy 449.315019 -18.307741)
			(xy 449.331087 -18.361148) (xy 449.339207 -18.416324) (xy 449.339716 -18.44421) (xy 449.339207 -18.472096)
			(xy 449.331087 -18.527272) (xy 449.315019 -18.580679) (xy 449.291347 -18.631176) (xy 449.260574 -18.677689)
			(xy 449.223357 -18.719226) (xy 449.180489 -18.754901) (xy 449.132883 -18.783955) (xy 449.081554 -18.805767)
			(xy 449.027597 -18.819873) (xy 448.97216 -18.825973) (xy 448.916426 -18.823936) (xy 448.861583 -18.813806)
			(xy 448.808799 -18.795799) (xy 448.759199 -18.770298) (xy 448.713841 -18.737847) (xy 448.673692 -18.699138)
			(xy 448.639606 -18.654995) (xy 448.61231 -18.60636) (xy 448.592387 -18.554269) (xy 448.580261 -18.499832)
			(xy 448.57619 -18.44421) (xy 423.339768 -18.44421) (xy 423.339259 -18.472096) (xy 423.331139 -18.527272)
			(xy 423.315071 -18.580679) (xy 423.291399 -18.631176) (xy 423.260626 -18.677689) (xy 423.223409 -18.719226)
			(xy 423.180541 -18.754901) (xy 423.132935 -18.783955) (xy 423.081606 -18.805767) (xy 423.027649 -18.819873)
			(xy 422.972212 -18.825973) (xy 422.916478 -18.823936) (xy 422.861635 -18.813806) (xy 422.808851 -18.795799)
			(xy 422.759251 -18.770298) (xy 422.713893 -18.737847) (xy 422.673744 -18.699138) (xy 422.639658 -18.654995)
			(xy 422.612362 -18.60636) (xy 422.592439 -18.554269) (xy 422.580313 -18.499832) (xy 422.576242 -18.44421)
			(xy 397.33982 -18.44421) (xy 397.339311 -18.472096) (xy 397.331191 -18.527272) (xy 397.315123 -18.580679)
			(xy 397.291451 -18.631176) (xy 397.260678 -18.677689) (xy 397.223461 -18.719226) (xy 397.180593 -18.754901)
			(xy 397.132987 -18.783955) (xy 397.081658 -18.805767) (xy 397.027701 -18.819873) (xy 396.972264 -18.825973)
			(xy 396.91653 -18.823936) (xy 396.861687 -18.813806) (xy 396.808903 -18.795799) (xy 396.759303 -18.770298)
			(xy 396.713945 -18.737847) (xy 396.673796 -18.699138) (xy 396.63971 -18.654995) (xy 396.612414 -18.60636)
			(xy 396.592491 -18.554269) (xy 396.580365 -18.499832) (xy 396.576294 -18.44421) (xy 371.339872 -18.44421)
			(xy 371.339363 -18.472096) (xy 371.331243 -18.527272) (xy 371.315175 -18.580679) (xy 371.291503 -18.631176)
			(xy 371.26073 -18.677689) (xy 371.223513 -18.719226) (xy 371.180645 -18.754901) (xy 371.133039 -18.783955)
			(xy 371.08171 -18.805767) (xy 371.027753 -18.819873) (xy 370.972316 -18.825973) (xy 370.916582 -18.823936)
			(xy 370.861739 -18.813806) (xy 370.808955 -18.795799) (xy 370.759355 -18.770298) (xy 370.713997 -18.737847)
			(xy 370.673848 -18.699138) (xy 370.639762 -18.654995) (xy 370.612466 -18.60636) (xy 370.592543 -18.554269)
			(xy 370.580417 -18.499832) (xy 370.576346 -18.44421) (xy 307.23967 -18.44421) (xy 307.239161 -18.472096)
			(xy 307.231041 -18.527272) (xy 307.214973 -18.580679) (xy 307.191301 -18.631176) (xy 307.160528 -18.677689)
			(xy 307.123311 -18.719226) (xy 307.080443 -18.754901) (xy 307.032837 -18.783955) (xy 306.981508 -18.805767)
			(xy 306.927551 -18.819873) (xy 306.872114 -18.825973) (xy 306.81638 -18.823936) (xy 306.761537 -18.813806)
			(xy 306.708753 -18.795799) (xy 306.659153 -18.770298) (xy 306.613795 -18.737847) (xy 306.573646 -18.699138)
			(xy 306.53956 -18.654995) (xy 306.512264 -18.60636) (xy 306.492341 -18.554269) (xy 306.480215 -18.499832)
			(xy 306.476144 -18.44421) (xy 281.239722 -18.44421) (xy 281.239213 -18.472096) (xy 281.231093 -18.527272)
			(xy 281.215025 -18.580679) (xy 281.191353 -18.631176) (xy 281.16058 -18.677689) (xy 281.123363 -18.719226)
			(xy 281.080495 -18.754901) (xy 281.032889 -18.783955) (xy 280.98156 -18.805767) (xy 280.927603 -18.819873)
			(xy 280.872166 -18.825973) (xy 280.816432 -18.823936) (xy 280.761589 -18.813806) (xy 280.708805 -18.795799)
			(xy 280.659205 -18.770298) (xy 280.613847 -18.737847) (xy 280.573698 -18.699138) (xy 280.539612 -18.654995)
			(xy 280.512316 -18.60636) (xy 280.492393 -18.554269) (xy 280.480267 -18.499832) (xy 280.476196 -18.44421)
			(xy 255.239774 -18.44421) (xy 255.239265 -18.472096) (xy 255.231145 -18.527272) (xy 255.215077 -18.580679)
			(xy 255.191405 -18.631176) (xy 255.160632 -18.677689) (xy 255.123415 -18.719226) (xy 255.080547 -18.754901)
			(xy 255.032941 -18.783955) (xy 254.981612 -18.805767) (xy 254.927655 -18.819873) (xy 254.872218 -18.825973)
			(xy 254.816484 -18.823936) (xy 254.761641 -18.813806) (xy 254.708857 -18.795799) (xy 254.659257 -18.770298)
			(xy 254.613899 -18.737847) (xy 254.57375 -18.699138) (xy 254.539664 -18.654995) (xy 254.512368 -18.60636)
			(xy 254.492445 -18.554269) (xy 254.480319 -18.499832) (xy 254.476248 -18.44421) (xy 217.139774 -18.44421)
			(xy 217.139265 -18.472096) (xy 217.131145 -18.527272) (xy 217.115077 -18.580679) (xy 217.091405 -18.631176)
			(xy 217.060632 -18.677689) (xy 217.023415 -18.719226) (xy 216.980547 -18.754901) (xy 216.932941 -18.783955)
			(xy 216.881612 -18.805767) (xy 216.827655 -18.819873) (xy 216.772218 -18.825973) (xy 216.716484 -18.823936)
			(xy 216.661641 -18.813806) (xy 216.608857 -18.795799) (xy 216.559257 -18.770298) (xy 216.513899 -18.737847)
			(xy 216.47375 -18.699138) (xy 216.439664 -18.654995) (xy 216.412368 -18.60636) (xy 216.392445 -18.554269)
			(xy 216.380319 -18.499832) (xy 216.376248 -18.44421) (xy 191.139826 -18.44421) (xy 191.139317 -18.472096)
			(xy 191.131197 -18.527272) (xy 191.115129 -18.580679) (xy 191.091457 -18.631176) (xy 191.060684 -18.677689)
			(xy 191.023467 -18.719226) (xy 190.980599 -18.754901) (xy 190.932993 -18.783955) (xy 190.881664 -18.805767)
			(xy 190.827707 -18.819873) (xy 190.77227 -18.825973) (xy 190.716536 -18.823936) (xy 190.661693 -18.813806)
			(xy 190.608909 -18.795799) (xy 190.559309 -18.770298) (xy 190.513951 -18.737847) (xy 190.473802 -18.699138)
			(xy 190.439716 -18.654995) (xy 190.41242 -18.60636) (xy 190.392497 -18.554269) (xy 190.380371 -18.499832)
			(xy 190.3763 -18.44421) (xy 165.139878 -18.44421) (xy 165.139369 -18.472096) (xy 165.131249 -18.527272)
			(xy 165.115181 -18.580679) (xy 165.091509 -18.631176) (xy 165.060736 -18.677689) (xy 165.023519 -18.719226)
			(xy 164.980651 -18.754901) (xy 164.933045 -18.783955) (xy 164.881716 -18.805767) (xy 164.827759 -18.819873)
			(xy 164.772322 -18.825973) (xy 164.716588 -18.823936) (xy 164.661745 -18.813806) (xy 164.608961 -18.795799)
			(xy 164.559361 -18.770298) (xy 164.514003 -18.737847) (xy 164.473854 -18.699138) (xy 164.439768 -18.654995)
			(xy 164.412472 -18.60636) (xy 164.392549 -18.554269) (xy 164.380423 -18.499832) (xy 164.376352 -18.44421)
			(xy 139.13993 -18.44421) (xy 139.139421 -18.472096) (xy 139.131301 -18.527272) (xy 139.115233 -18.580679)
			(xy 139.091561 -18.631176) (xy 139.060788 -18.677689) (xy 139.023571 -18.719226) (xy 138.980703 -18.754901)
			(xy 138.933097 -18.783955) (xy 138.881768 -18.805767) (xy 138.827811 -18.819873) (xy 138.772374 -18.825973)
			(xy 138.71664 -18.823936) (xy 138.661797 -18.813806) (xy 138.609013 -18.795799) (xy 138.559413 -18.770298)
			(xy 138.514055 -18.737847) (xy 138.473906 -18.699138) (xy 138.43982 -18.654995) (xy 138.412524 -18.60636)
			(xy 138.392601 -18.554269) (xy 138.380475 -18.499832) (xy 138.376404 -18.44421) (xy 75.039728 -18.44421)
			(xy 75.039219 -18.472096) (xy 75.031099 -18.527272) (xy 75.015031 -18.580679) (xy 74.991359 -18.631176)
			(xy 74.960586 -18.677689) (xy 74.923369 -18.719226) (xy 74.880501 -18.754901) (xy 74.832895 -18.783955)
			(xy 74.781566 -18.805767) (xy 74.727609 -18.819873) (xy 74.672172 -18.825973) (xy 74.616438 -18.823936)
			(xy 74.561595 -18.813806) (xy 74.508811 -18.795799) (xy 74.459211 -18.770298) (xy 74.413853 -18.737847)
			(xy 74.373704 -18.699138) (xy 74.339618 -18.654995) (xy 74.312322 -18.60636) (xy 74.292399 -18.554269)
			(xy 74.280273 -18.499832) (xy 74.276202 -18.44421) (xy 49.03978 -18.44421) (xy 49.039271 -18.472096)
			(xy 49.031151 -18.527272) (xy 49.015083 -18.580679) (xy 48.991411 -18.631176) (xy 48.960638 -18.677689)
			(xy 48.923421 -18.719226) (xy 48.880553 -18.754901) (xy 48.832947 -18.783955) (xy 48.781618 -18.805767)
			(xy 48.727661 -18.819873) (xy 48.672224 -18.825973) (xy 48.61649 -18.823936) (xy 48.561647 -18.813806)
			(xy 48.508863 -18.795799) (xy 48.459263 -18.770298) (xy 48.413905 -18.737847) (xy 48.373756 -18.699138)
			(xy 48.33967 -18.654995) (xy 48.312374 -18.60636) (xy 48.292451 -18.554269) (xy 48.280325 -18.499832)
			(xy 48.276254 -18.44421) (xy 1.306576 -18.44421) (xy 1.306576 -20.24888) (xy 2.414776 -20.24888)
			(xy 2.418847 -20.193258) (xy 2.430973 -20.138821) (xy 2.450896 -20.08673) (xy 2.478192 -20.038095)
			(xy 2.512278 -19.993952) (xy 2.552427 -19.955243) (xy 2.597785 -19.922792) (xy 2.647385 -19.897291)
			(xy 2.700169 -19.879284) (xy 2.755012 -19.869154) (xy 2.810746 -19.867117) (xy 2.866183 -19.873217)
			(xy 2.92014 -19.887323) (xy 2.971469 -19.909135) (xy 3.019075 -19.938189) (xy 3.061943 -19.973864)
			(xy 3.09916 -20.015401) (xy 3.129933 -20.061914) (xy 3.153605 -20.112411) (xy 3.169673 -20.165818)
			(xy 3.177793 -20.220994) (xy 3.178302 -20.24888) (xy 3.177793 -20.276766) (xy 3.169673 -20.331942)
			(xy 3.153605 -20.385349) (xy 3.129933 -20.435846) (xy 3.09916 -20.482359) (xy 3.061943 -20.523896)
			(xy 3.019075 -20.559571) (xy 2.971469 -20.588625) (xy 2.92014 -20.610437) (xy 2.866183 -20.624543)
			(xy 2.810746 -20.630643) (xy 2.755012 -20.628606) (xy 2.700169 -20.618476) (xy 2.647385 -20.600469)
			(xy 2.597785 -20.574968) (xy 2.552427 -20.542517) (xy 2.512278 -20.503808) (xy 2.478192 -20.459665)
			(xy 2.450896 -20.41103) (xy 2.430973 -20.358939) (xy 2.418847 -20.304502) (xy 2.414776 -20.24888)
			(xy 1.306576 -20.24888) (xy 1.306576 -20.72005) (xy 5.185422 -20.72005) (xy 5.189392 -20.589916)
			(xy 5.201288 -20.460266) (xy 5.221067 -20.331583) (xy 5.248653 -20.204344) (xy 5.283946 -20.079025)
			(xy 5.326812 -19.956089) (xy 5.377094 -19.835996) (xy 5.434603 -19.719192) (xy 5.499127 -19.60611)
			(xy 5.570424 -19.497173) (xy 5.648229 -19.392785) (xy 5.732254 -19.293334) (xy 5.822186 -19.199191)
			(xy 5.91769 -19.110706) (xy 6.01841 -19.028207) (xy 6.123972 -18.952002) (xy 6.233984 -18.882375)
			(xy 6.348036 -18.819584) (xy 6.465704 -18.763862) (xy 6.58655 -18.715418) (xy 6.710125 -18.674431)
			(xy 6.835968 -18.641054) (xy 6.963613 -18.615411) (xy 7.092583 -18.597597) (xy 7.222399 -18.587679)
			(xy 7.352578 -18.585694) (xy 7.482637 -18.591648) (xy 7.61209 -18.605521) (xy 7.740457 -18.627259)
			(xy 7.86726 -18.656783) (xy 7.992027 -18.693982) (xy 8.114294 -18.738718) (xy 8.233607 -18.790826)
			(xy 8.34952 -18.850109) (xy 8.461605 -18.91635) (xy 8.569442 -18.9893) (xy 8.672631 -19.068688) (xy 8.770789 -19.15422)
			(xy 8.86355 -19.245577) (xy 8.950569 -19.342419) (xy 9.031522 -19.444386) (xy 9.106108 -19.551098)
			(xy 9.174049 -19.662159) (xy 9.235094 -19.777155) (xy 9.289015 -19.895659) (xy 9.33561 -20.01723)
			(xy 9.374708 -20.141415) (xy 9.406162 -20.267753) (xy 9.429856 -20.395774) (xy 9.4457 -20.525) (xy 9.453638 -20.654953)
			(xy 9.454134 -20.72005) (xy 9.453638 -20.785147) (xy 9.4457 -20.9151) (xy 9.429856 -21.044326) (xy 9.406162 -21.172347)
			(xy 9.374708 -21.298685) (xy 9.33561 -21.42287) (xy 9.289015 -21.544441) (xy 9.245979 -21.639022)
			(xy 16.073882 -21.639022) (xy 16.074424 -21.610284) (xy 16.083043 -21.553458) (xy 16.100089 -21.498567)
			(xy 16.125176 -21.446855) (xy 16.157737 -21.399492) (xy 16.177006 -21.378164) (xy 16.18361 -21.371306)
			(xy 16.190722 -21.353272) (xy 16.190722 -21.264372) (xy 16.18361 -21.246338) (xy 16.177006 -21.23948)
			(xy 16.157758 -21.218134) (xy 16.125193 -21.170774) (xy 16.100102 -21.119065) (xy 16.083051 -21.064178)
			(xy 16.074427 -21.007354) (xy 16.074424 -20.949879) (xy 16.083044 -20.893053) (xy 16.10009 -20.838164)
			(xy 16.125177 -20.786454) (xy 16.157738 -20.739091) (xy 16.177006 -20.717764) (xy 16.18361 -20.710906)
			(xy 16.190722 -20.692872) (xy 16.190722 -20.603972) (xy 16.18361 -20.585938) (xy 16.177006 -20.57908)
			(xy 16.157758 -20.557734) (xy 16.125193 -20.510374) (xy 16.100102 -20.458665) (xy 16.083051 -20.403778)
			(xy 16.074427 -20.346954) (xy 16.074424 -20.289479) (xy 16.083044 -20.232653) (xy 16.10009 -20.177764)
			(xy 16.125177 -20.126054) (xy 16.157738 -20.078691) (xy 16.177006 -20.057364) (xy 16.18361 -20.050506)
			(xy 16.190722 -20.032472) (xy 16.190722 -19.943572) (xy 16.18361 -19.925538) (xy 16.177006 -19.91868)
			(xy 16.157758 -19.897334) (xy 16.125193 -19.849974) (xy 16.100102 -19.798265) (xy 16.083051 -19.743378)
			(xy 16.074427 -19.686554) (xy 16.074424 -19.629079) (xy 16.083044 -19.572253) (xy 16.10009 -19.517364)
			(xy 16.125177 -19.465654) (xy 16.157738 -19.418291) (xy 16.177006 -19.396964) (xy 16.18361 -19.390106)
			(xy 16.190722 -19.372072) (xy 16.190722 -19.283172) (xy 16.18361 -19.265138) (xy 16.177006 -19.25828)
			(xy 16.157757 -19.236934) (xy 16.125186 -19.189578) (xy 16.100088 -19.137872) (xy 16.083032 -19.082985)
			(xy 16.074405 -19.02616) (xy 16.073882 -18.997422) (xy 16.074368 -18.970171) (xy 16.082124 -18.916223)
			(xy 16.097479 -18.863928) (xy 16.120121 -18.814351) (xy 16.149587 -18.768501) (xy 16.185278 -18.72731)
			(xy 16.226469 -18.691619) (xy 16.272319 -18.662153) (xy 16.321896 -18.639511) (xy 16.374191 -18.624156)
			(xy 16.428139 -18.6164) (xy 16.482641 -18.6164) (xy 16.536589 -18.624156) (xy 16.588884 -18.639511)
			(xy 16.638461 -18.662153) (xy 16.684311 -18.691619) (xy 16.725502 -18.72731) (xy 16.761193 -18.768501)
			(xy 16.790659 -18.814351) (xy 16.813301 -18.863928) (xy 16.828656 -18.916223) (xy 16.836412 -18.970171)
			(xy 16.836898 -18.997422) (xy 16.836388 -19.026161) (xy 16.827762 -19.082989) (xy 16.810709 -19.13788)
			(xy 16.785614 -19.189592) (xy 16.753046 -19.236954) (xy 16.733774 -19.25828) (xy 16.72717 -19.265138)
			(xy 16.720058 -19.283172) (xy 16.720058 -19.372072) (xy 16.72717 -19.390106) (xy 16.733774 -19.396964)
			(xy 16.753067 -19.418272) (xy 16.785631 -19.465637) (xy 16.810722 -19.517352) (xy 16.82777 -19.572246)
			(xy 16.836391 -19.629076) (xy 16.836389 -19.686556) (xy 16.827763 -19.743385) (xy 16.81071 -19.798278)
			(xy 16.785615 -19.84999) (xy 16.753047 -19.897353) (xy 16.733774 -19.91868) (xy 16.72717 -19.925538)
			(xy 16.720058 -19.943572) (xy 16.720058 -20.032472) (xy 16.72717 -20.050506) (xy 16.733774 -20.057364)
			(xy 16.753067 -20.078672) (xy 16.785631 -20.126037) (xy 16.810722 -20.177752) (xy 16.82777 -20.232646)
			(xy 16.836391 -20.289476) (xy 16.836389 -20.346956) (xy 16.827763 -20.403785) (xy 16.81071 -20.458678)
			(xy 16.785615 -20.51039) (xy 16.753047 -20.557753) (xy 16.733774 -20.57908) (xy 16.72717 -20.585938)
			(xy 16.720058 -20.603972) (xy 16.720058 -20.692872) (xy 16.72717 -20.710906) (xy 16.733774 -20.717764)
			(xy 16.735844 -20.72005) (xy 31.18537 -20.72005) (xy 31.18934 -20.589916) (xy 31.201236 -20.460266)
			(xy 31.221015 -20.331583) (xy 31.248601 -20.204344) (xy 31.283894 -20.079025) (xy 31.32676 -19.956089)
			(xy 31.377042 -19.835996) (xy 31.434551 -19.719192) (xy 31.499075 -19.60611) (xy 31.570372 -19.497173)
			(xy 31.648177 -19.392785) (xy 31.732202 -19.293334) (xy 31.822134 -19.199191) (xy 31.917638 -19.110706)
			(xy 32.018358 -19.028207) (xy 32.12392 -18.952002) (xy 32.233932 -18.882375) (xy 32.347984 -18.819584)
			(xy 32.465652 -18.763862) (xy 32.586498 -18.715418) (xy 32.710073 -18.674431) (xy 32.835916 -18.641054)
			(xy 32.963561 -18.615411) (xy 33.092531 -18.597597) (xy 33.222347 -18.587679) (xy 33.352526 -18.585694)
			(xy 33.482585 -18.591648) (xy 33.612038 -18.605521) (xy 33.740405 -18.627259) (xy 33.867208 -18.656783)
			(xy 33.991975 -18.693982) (xy 34.114242 -18.738718) (xy 34.233555 -18.790826) (xy 34.349468 -18.850109)
			(xy 34.461553 -18.91635) (xy 34.56939 -18.9893) (xy 34.672579 -19.068688) (xy 34.770737 -19.15422)
			(xy 34.863498 -19.245577) (xy 34.950517 -19.342419) (xy 35.03147 -19.444386) (xy 35.106056 -19.551098)
			(xy 35.173997 -19.662159) (xy 35.235042 -19.777155) (xy 35.288963 -19.895659) (xy 35.335558 -20.01723)
			(xy 35.374656 -20.141415) (xy 35.40611 -20.267753) (xy 35.429804 -20.395774) (xy 35.445648 -20.525)
			(xy 35.453586 -20.654953) (xy 35.454082 -20.72005) (xy 35.453586 -20.785147) (xy 35.445648 -20.9151)
			(xy 35.429804 -21.044326) (xy 35.40611 -21.172347) (xy 35.374656 -21.298685) (xy 35.335558 -21.42287)
			(xy 35.288963 -21.544441) (xy 35.245927 -21.639022) (xy 42.07383 -21.639022) (xy 42.074386 -21.610285)
			(xy 42.083003 -21.553459) (xy 42.100047 -21.49857) (xy 42.125131 -21.446858) (xy 42.157688 -21.399493)
			(xy 42.176954 -21.378164) (xy 42.183558 -21.371306) (xy 42.19067 -21.353272) (xy 42.19067 -21.264372)
			(xy 42.183558 -21.246338) (xy 42.176954 -21.23948) (xy 42.157704 -21.218135) (xy 42.125135 -21.170777)
			(xy 42.10004 -21.119068) (xy 42.082987 -21.06418) (xy 42.074362 -21.007354) (xy 42.07436 -20.949878)
			(xy 42.08298 -20.893052) (xy 42.100029 -20.838162) (xy 42.125119 -20.786451) (xy 42.157683 -20.73909)
			(xy 42.176954 -20.717764) (xy 42.183558 -20.710906) (xy 42.19067 -20.692872) (xy 42.19067 -20.603972)
			(xy 42.183558 -20.585938) (xy 42.176954 -20.57908) (xy 42.157704 -20.557735) (xy 42.125135 -20.510377)
			(xy 42.10004 -20.458668) (xy 42.082987 -20.40378) (xy 42.074362 -20.346954) (xy 42.07436 -20.289478)
			(xy 42.08298 -20.232652) (xy 42.100029 -20.177762) (xy 42.125119 -20.126051) (xy 42.157683 -20.07869)
			(xy 42.176954 -20.057364) (xy 42.183558 -20.050506) (xy 42.19067 -20.032472) (xy 42.19067 -19.943572)
			(xy 42.183558 -19.925538) (xy 42.176954 -19.91868) (xy 42.157704 -19.897335) (xy 42.125135 -19.849977)
			(xy 42.10004 -19.798268) (xy 42.082987 -19.74338) (xy 42.074362 -19.686554) (xy 42.07436 -19.629078)
			(xy 42.08298 -19.572252) (xy 42.100029 -19.517362) (xy 42.125119 -19.465651) (xy 42.157683 -19.41829)
			(xy 42.176954 -19.396964) (xy 42.183558 -19.390106) (xy 42.19067 -19.372072) (xy 42.19067 -19.283172)
			(xy 42.183558 -19.265138) (xy 42.176954 -19.25828) (xy 42.157696 -19.236942) (xy 42.125128 -19.189583)
			(xy 42.100032 -19.137874) (xy 42.082979 -19.082986) (xy 42.074353 -19.02616) (xy 42.07383 -18.997422)
			(xy 42.074316 -18.970171) (xy 42.082072 -18.916223) (xy 42.097427 -18.863928) (xy 42.120069 -18.814351)
			(xy 42.149535 -18.768501) (xy 42.185226 -18.72731) (xy 42.226417 -18.691619) (xy 42.272267 -18.662153)
			(xy 42.321844 -18.639511) (xy 42.374139 -18.624156) (xy 42.428087 -18.6164) (xy 42.482589 -18.6164)
			(xy 42.536537 -18.624156) (xy 42.588832 -18.639511) (xy 42.638409 -18.662153) (xy 42.684259 -18.691619)
			(xy 42.72545 -18.72731) (xy 42.761141 -18.768501) (xy 42.790607 -18.814351) (xy 42.813249 -18.863928)
			(xy 42.828604 -18.916223) (xy 42.83636 -18.970171) (xy 42.836846 -18.997422) (xy 42.836323 -19.026161)
			(xy 42.827699 -19.082988) (xy 42.810648 -19.137878) (xy 42.785556 -19.18959) (xy 42.752992 -19.236953)
			(xy 42.733722 -19.25828) (xy 42.727118 -19.265138) (xy 42.720006 -19.283172) (xy 42.720006 -19.372072)
			(xy 42.727118 -19.390106) (xy 42.733722 -19.396964) (xy 42.753013 -19.418273) (xy 42.776952 -19.453098)
			(xy 48.276254 -19.453098) (xy 48.280325 -19.397476) (xy 48.292451 -19.343039) (xy 48.312374 -19.290948)
			(xy 48.33967 -19.242313) (xy 48.373756 -19.19817) (xy 48.413905 -19.159461) (xy 48.459263 -19.12701)
			(xy 48.508863 -19.101509) (xy 48.561647 -19.083502) (xy 48.61649 -19.073372) (xy 48.672224 -19.071335)
			(xy 48.727661 -19.077435) (xy 48.781618 -19.091541) (xy 48.832947 -19.113353) (xy 48.880553 -19.142407)
			(xy 48.923421 -19.178082) (xy 48.960638 -19.219619) (xy 48.991411 -19.266132) (xy 49.015083 -19.316629)
			(xy 49.031151 -19.370036) (xy 49.039271 -19.425212) (xy 49.03978 -19.453098) (xy 49.039271 -19.480984)
			(xy 49.031151 -19.53616) (xy 49.015083 -19.589567) (xy 48.991411 -19.640064) (xy 48.960638 -19.686577)
			(xy 48.923421 -19.728114) (xy 48.880553 -19.763789) (xy 48.832947 -19.792843) (xy 48.781618 -19.814655)
			(xy 48.727661 -19.828761) (xy 48.672224 -19.834861) (xy 48.61649 -19.832824) (xy 48.561647 -19.822694)
			(xy 48.508863 -19.804687) (xy 48.459263 -19.779186) (xy 48.413905 -19.746735) (xy 48.373756 -19.708026)
			(xy 48.33967 -19.663883) (xy 48.312374 -19.615248) (xy 48.292451 -19.563157) (xy 48.280325 -19.50872)
			(xy 48.276254 -19.453098) (xy 42.776952 -19.453098) (xy 42.785573 -19.46564) (xy 42.810661 -19.517355)
			(xy 42.827707 -19.572248) (xy 42.836326 -19.629077) (xy 42.836324 -19.686555) (xy 42.8277 -19.743384)
			(xy 42.810649 -19.798275) (xy 42.785557 -19.849988) (xy 42.752992 -19.897352) (xy 42.733722 -19.91868)
			(xy 42.727118 -19.925538) (xy 42.720006 -19.943572) (xy 42.720006 -20.032472) (xy 42.727118 -20.050506)
			(xy 42.733722 -20.057364) (xy 42.753013 -20.078673) (xy 42.785573 -20.12604) (xy 42.810661 -20.177755)
			(xy 42.827707 -20.232648) (xy 42.836326 -20.289477) (xy 42.836324 -20.346955) (xy 42.8277 -20.403784)
			(xy 42.810649 -20.458675) (xy 42.806331 -20.467574) (xy 50.287426 -20.467574) (xy 50.291497 -20.411952)
			(xy 50.303623 -20.357515) (xy 50.323546 -20.305424) (xy 50.350842 -20.256789) (xy 50.384928 -20.212646)
			(xy 50.425077 -20.173937) (xy 50.470435 -20.141486) (xy 50.520035 -20.115985) (xy 50.572819 -20.097978)
			(xy 50.627662 -20.087848) (xy 50.683396 -20.085811) (xy 50.738833 -20.091911) (xy 50.79279 -20.106017)
			(xy 50.844119 -20.127829) (xy 50.891725 -20.156883) (xy 50.934593 -20.192558) (xy 50.97181 -20.234095)
			(xy 51.002583 -20.280608) (xy 51.026255 -20.331105) (xy 51.042323 -20.384512) (xy 51.050443 -20.439688)
			(xy 51.050952 -20.467574) (xy 51.050443 -20.49546) (xy 51.042323 -20.550636) (xy 51.026255 -20.604043)
			(xy 51.002583 -20.65454) (xy 50.97181 -20.701053) (xy 50.954789 -20.72005) (xy 57.185318 -20.72005)
			(xy 57.189288 -20.589916) (xy 57.201184 -20.460266) (xy 57.220963 -20.331583) (xy 57.248549 -20.204344)
			(xy 57.283842 -20.079025) (xy 57.326708 -19.956089) (xy 57.37699 -19.835996) (xy 57.434499 -19.719192)
			(xy 57.499023 -19.60611) (xy 57.57032 -19.497173) (xy 57.648125 -19.392785) (xy 57.73215 -19.293334)
			(xy 57.822082 -19.199191) (xy 57.917586 -19.110706) (xy 58.018306 -19.028207) (xy 58.123868 -18.952002)
			(xy 58.23388 -18.882375) (xy 58.347932 -18.819584) (xy 58.4656 -18.763862) (xy 58.586446 -18.715418)
			(xy 58.710021 -18.674431) (xy 58.835864 -18.641054) (xy 58.963509 -18.615411) (xy 59.092479 -18.597597)
			(xy 59.222295 -18.587679) (xy 59.352474 -18.585694) (xy 59.482533 -18.591648) (xy 59.611986 -18.605521)
			(xy 59.740353 -18.627259) (xy 59.867156 -18.656783) (xy 59.991923 -18.693982) (xy 60.11419 -18.738718)
			(xy 60.233503 -18.790826) (xy 60.349416 -18.850109) (xy 60.461501 -18.91635) (xy 60.569338 -18.9893)
			(xy 60.672527 -19.068688) (xy 60.770685 -19.15422) (xy 60.863446 -19.245577) (xy 60.950465 -19.342419)
			(xy 61.031418 -19.444386) (xy 61.106004 -19.551098) (xy 61.173945 -19.662159) (xy 61.23499 -19.777155)
			(xy 61.288911 -19.895659) (xy 61.335506 -20.01723) (xy 61.374604 -20.141415) (xy 61.406058 -20.267753)
			(xy 61.429752 -20.395774) (xy 61.445596 -20.525) (xy 61.453534 -20.654953) (xy 61.45403 -20.72005)
			(xy 61.453534 -20.785147) (xy 61.445596 -20.9151) (xy 61.429752 -21.044326) (xy 61.406058 -21.172347)
			(xy 61.374604 -21.298685) (xy 61.335506 -21.42287) (xy 61.288911 -21.544441) (xy 61.245875 -21.639022)
			(xy 68.073778 -21.639022) (xy 68.074321 -21.610284) (xy 68.08294 -21.553458) (xy 68.099986 -21.498567)
			(xy 68.125073 -21.446855) (xy 68.157633 -21.399492) (xy 68.176902 -21.378164) (xy 68.183506 -21.371306)
			(xy 68.190618 -21.353272) (xy 68.190618 -21.264372) (xy 68.183506 -21.246338) (xy 68.176902 -21.23948)
			(xy 68.157654 -21.218134) (xy 68.12509 -21.170774) (xy 68.099999 -21.119065) (xy 68.082948 -21.064178)
			(xy 68.074324 -21.007354) (xy 68.074321 -20.949879) (xy 68.082941 -20.893054) (xy 68.099987 -20.838165)
			(xy 68.125074 -20.786454) (xy 68.157634 -20.739091) (xy 68.176902 -20.717764) (xy 68.183506 -20.710906)
			(xy 68.190618 -20.692872) (xy 68.190618 -20.603972) (xy 68.183506 -20.585938) (xy 68.176902 -20.57908)
			(xy 68.157654 -20.557734) (xy 68.12509 -20.510374) (xy 68.099999 -20.458665) (xy 68.082948 -20.403778)
			(xy 68.074324 -20.346954) (xy 68.074321 -20.289479) (xy 68.082941 -20.232654) (xy 68.099987 -20.177765)
			(xy 68.125074 -20.126054) (xy 68.157634 -20.078691) (xy 68.176902 -20.057364) (xy 68.183506 -20.050506)
			(xy 68.190618 -20.032472) (xy 68.190618 -19.943572) (xy 68.183506 -19.925538) (xy 68.176902 -19.91868)
			(xy 68.157654 -19.897334) (xy 68.12509 -19.849974) (xy 68.099999 -19.798265) (xy 68.082948 -19.743378)
			(xy 68.074324 -19.686554) (xy 68.074321 -19.629079) (xy 68.082941 -19.572254) (xy 68.099987 -19.517365)
			(xy 68.125074 -19.465654) (xy 68.157634 -19.418291) (xy 68.176902 -19.396964) (xy 68.183506 -19.390106)
			(xy 68.190618 -19.372072) (xy 68.190618 -19.283172) (xy 68.183506 -19.265138) (xy 68.176902 -19.25828)
			(xy 68.157653 -19.236934) (xy 68.125081 -19.189578) (xy 68.099984 -19.137872) (xy 68.082928 -19.082985)
			(xy 68.074301 -19.02616) (xy 68.073778 -18.997422) (xy 68.074264 -18.970171) (xy 68.08202 -18.916223)
			(xy 68.097375 -18.863928) (xy 68.120017 -18.814351) (xy 68.149483 -18.768501) (xy 68.185174 -18.72731)
			(xy 68.226365 -18.691619) (xy 68.272215 -18.662153) (xy 68.321792 -18.639511) (xy 68.374087 -18.624156)
			(xy 68.428035 -18.6164) (xy 68.482537 -18.6164) (xy 68.536485 -18.624156) (xy 68.58878 -18.639511)
			(xy 68.638357 -18.662153) (xy 68.684207 -18.691619) (xy 68.725398 -18.72731) (xy 68.761089 -18.768501)
			(xy 68.790555 -18.814351) (xy 68.813197 -18.863928) (xy 68.828552 -18.916223) (xy 68.836308 -18.970171)
			(xy 68.836794 -18.997422) (xy 68.836285 -19.026161) (xy 68.827659 -19.08299) (xy 68.810606 -19.137881)
			(xy 68.785511 -19.189592) (xy 68.752942 -19.236954) (xy 68.73367 -19.25828) (xy 68.727066 -19.265138)
			(xy 68.719954 -19.283172) (xy 68.719954 -19.372072) (xy 68.727066 -19.390106) (xy 68.73367 -19.396964)
			(xy 68.752963 -19.418272) (xy 68.776907 -19.453098) (xy 74.276202 -19.453098) (xy 74.280273 -19.397476)
			(xy 74.292399 -19.343039) (xy 74.312322 -19.290948) (xy 74.339618 -19.242313) (xy 74.373704 -19.19817)
			(xy 74.413853 -19.159461) (xy 74.459211 -19.12701) (xy 74.508811 -19.101509) (xy 74.561595 -19.083502)
			(xy 74.616438 -19.073372) (xy 74.672172 -19.071335) (xy 74.727609 -19.077435) (xy 74.781566 -19.091541)
			(xy 74.832895 -19.113353) (xy 74.880501 -19.142407) (xy 74.923369 -19.178082) (xy 74.960586 -19.219619)
			(xy 74.991359 -19.266132) (xy 75.015031 -19.316629) (xy 75.031099 -19.370036) (xy 75.039219 -19.425212)
			(xy 75.039728 -19.453098) (xy 75.039219 -19.480984) (xy 75.031099 -19.53616) (xy 75.015031 -19.589567)
			(xy 74.991359 -19.640064) (xy 74.960586 -19.686577) (xy 74.923369 -19.728114) (xy 74.880501 -19.763789)
			(xy 74.832895 -19.792843) (xy 74.781566 -19.814655) (xy 74.727609 -19.828761) (xy 74.672172 -19.834861)
			(xy 74.616438 -19.832824) (xy 74.561595 -19.822694) (xy 74.508811 -19.804687) (xy 74.459211 -19.779186)
			(xy 74.413853 -19.746735) (xy 74.373704 -19.708026) (xy 74.339618 -19.663883) (xy 74.312322 -19.615248)
			(xy 74.292399 -19.563157) (xy 74.280273 -19.50872) (xy 74.276202 -19.453098) (xy 68.776907 -19.453098)
			(xy 68.785528 -19.465637) (xy 68.810619 -19.517352) (xy 68.827667 -19.572246) (xy 68.836288 -19.629076)
			(xy 68.836286 -19.686556) (xy 68.82766 -19.743386) (xy 68.810607 -19.798278) (xy 68.785512 -19.849991)
			(xy 68.752943 -19.897353) (xy 68.73367 -19.91868) (xy 68.727066 -19.925538) (xy 68.719954 -19.943572)
			(xy 68.719954 -20.032472) (xy 68.727066 -20.050506) (xy 68.73367 -20.057364) (xy 68.752963 -20.078672)
			(xy 68.785528 -20.126037) (xy 68.810619 -20.177752) (xy 68.827667 -20.232646) (xy 68.836288 -20.289476)
			(xy 68.836286 -20.346956) (xy 68.82766 -20.403786) (xy 68.810607 -20.458678) (xy 68.80629 -20.467574)
			(xy 76.287374 -20.467574) (xy 76.291445 -20.411952) (xy 76.303571 -20.357515) (xy 76.323494 -20.305424)
			(xy 76.35079 -20.256789) (xy 76.384876 -20.212646) (xy 76.425025 -20.173937) (xy 76.470383 -20.141486)
			(xy 76.519983 -20.115985) (xy 76.572767 -20.097978) (xy 76.62761 -20.087848) (xy 76.683344 -20.085811)
			(xy 76.738781 -20.091911) (xy 76.792738 -20.106017) (xy 76.844067 -20.127829) (xy 76.891673 -20.156883)
			(xy 76.934541 -20.192558) (xy 76.971758 -20.234095) (xy 77.002531 -20.280608) (xy 77.026203 -20.331105)
			(xy 77.042271 -20.384512) (xy 77.050391 -20.439688) (xy 77.0509 -20.467574) (xy 77.050391 -20.49546)
			(xy 77.042271 -20.550636) (xy 77.026203 -20.604043) (xy 77.002531 -20.65454) (xy 76.971758 -20.701053)
			(xy 76.954737 -20.72005) (xy 83.18552 -20.72005) (xy 83.18949 -20.589916) (xy 83.201386 -20.460266)
			(xy 83.221165 -20.331583) (xy 83.248751 -20.204344) (xy 83.284044 -20.079025) (xy 83.32691 -19.956089)
			(xy 83.377192 -19.835996) (xy 83.434701 -19.719192) (xy 83.499225 -19.60611) (xy 83.570522 -19.497173)
			(xy 83.648327 -19.392785) (xy 83.732352 -19.293334) (xy 83.822284 -19.199191) (xy 83.917788 -19.110706)
			(xy 84.018508 -19.028207) (xy 84.12407 -18.952002) (xy 84.234082 -18.882375) (xy 84.348134 -18.819584)
			(xy 84.465802 -18.763862) (xy 84.586648 -18.715418) (xy 84.710223 -18.674431) (xy 84.836066 -18.641054)
			(xy 84.963711 -18.615411) (xy 85.092681 -18.597597) (xy 85.222497 -18.587679) (xy 85.352676 -18.585694)
			(xy 85.482735 -18.591648) (xy 85.612188 -18.605521) (xy 85.740555 -18.627259) (xy 85.867358 -18.656783)
			(xy 85.992125 -18.693982) (xy 86.114392 -18.738718) (xy 86.233705 -18.790826) (xy 86.349618 -18.850109)
			(xy 86.461703 -18.91635) (xy 86.56954 -18.9893) (xy 86.672729 -19.068688) (xy 86.770887 -19.15422)
			(xy 86.863648 -19.245577) (xy 86.950667 -19.342419) (xy 87.03162 -19.444386) (xy 87.106206 -19.551098)
			(xy 87.174147 -19.662159) (xy 87.235192 -19.777155) (xy 87.289113 -19.895659) (xy 87.335708 -20.01723)
			(xy 87.374806 -20.141415) (xy 87.40626 -20.267753) (xy 87.429954 -20.395774) (xy 87.445798 -20.525)
			(xy 87.453736 -20.654953) (xy 87.454232 -20.72005) (xy 87.453736 -20.785147) (xy 87.445798 -20.9151)
			(xy 87.429954 -21.044326) (xy 87.40626 -21.172347) (xy 87.374806 -21.298685) (xy 87.335708 -21.42287)
			(xy 87.289113 -21.544441) (xy 87.246077 -21.639022) (xy 94.073726 -21.639022) (xy 94.074283 -21.610285)
			(xy 94.0829 -21.55346) (xy 94.099944 -21.49857) (xy 94.125027 -21.446858) (xy 94.157584 -21.399493)
			(xy 94.17685 -21.378164) (xy 94.183454 -21.371306) (xy 94.190566 -21.353272) (xy 94.190566 -21.264372)
			(xy 94.183454 -21.246338) (xy 94.17685 -21.23948) (xy 94.1576 -21.218135) (xy 94.125032 -21.170776)
			(xy 94.099937 -21.119068) (xy 94.082884 -21.064179) (xy 94.074259 -21.007354) (xy 94.074257 -20.949878)
			(xy 94.082877 -20.893052) (xy 94.099925 -20.838162) (xy 94.125016 -20.786451) (xy 94.15758 -20.73909)
			(xy 94.17685 -20.717764) (xy 94.183454 -20.710906) (xy 94.190566 -20.692872) (xy 94.190566 -20.603972)
			(xy 94.183454 -20.585938) (xy 94.17685 -20.57908) (xy 94.1576 -20.557735) (xy 94.125032 -20.510376)
			(xy 94.099937 -20.458668) (xy 94.082884 -20.403779) (xy 94.074259 -20.346954) (xy 94.074257 -20.289478)
			(xy 94.082877 -20.232652) (xy 94.099925 -20.177762) (xy 94.125016 -20.126051) (xy 94.15758 -20.07869)
			(xy 94.17685 -20.057364) (xy 94.183454 -20.050506) (xy 94.190566 -20.032472) (xy 94.190566 -19.943572)
			(xy 94.183454 -19.925538) (xy 94.17685 -19.91868) (xy 94.1576 -19.897335) (xy 94.125032 -19.849976)
			(xy 94.099937 -19.798268) (xy 94.082884 -19.743379) (xy 94.074259 -19.686554) (xy 94.074257 -19.629078)
			(xy 94.082877 -19.572252) (xy 94.099925 -19.517362) (xy 94.125016 -19.465651) (xy 94.15758 -19.41829)
			(xy 94.17685 -19.396964) (xy 94.183454 -19.390106) (xy 94.190566 -19.372072) (xy 94.190566 -19.283172)
			(xy 94.183454 -19.265138) (xy 94.17685 -19.25828) (xy 94.157592 -19.236942) (xy 94.125023 -19.189583)
			(xy 94.099928 -19.137874) (xy 94.082875 -19.082986) (xy 94.074249 -19.02616) (xy 94.073726 -18.997422)
			(xy 94.074212 -18.970171) (xy 94.081968 -18.916223) (xy 94.097323 -18.863928) (xy 94.119965 -18.814351)
			(xy 94.149431 -18.768501) (xy 94.185122 -18.72731) (xy 94.226313 -18.691619) (xy 94.272163 -18.662153)
			(xy 94.32174 -18.639511) (xy 94.374035 -18.624156) (xy 94.427983 -18.6164) (xy 94.482485 -18.6164)
			(xy 94.536433 -18.624156) (xy 94.588728 -18.639511) (xy 94.638305 -18.662153) (xy 94.684155 -18.691619)
			(xy 94.725346 -18.72731) (xy 94.761037 -18.768501) (xy 94.790503 -18.814351) (xy 94.813145 -18.863928)
			(xy 94.8285 -18.916223) (xy 94.836256 -18.970171) (xy 94.836742 -18.997422) (xy 94.83622 -19.026161)
			(xy 94.827596 -19.082988) (xy 94.810544 -19.137878) (xy 94.785453 -19.18959) (xy 94.752888 -19.236953)
			(xy 94.733618 -19.25828) (xy 94.727014 -19.265138) (xy 94.719902 -19.283172) (xy 94.719902 -19.372072)
			(xy 94.727014 -19.390106) (xy 94.733618 -19.396964) (xy 94.752909 -19.418273) (xy 94.78547 -19.46564)
			(xy 94.810557 -19.517355) (xy 94.827604 -19.572248) (xy 94.836223 -19.629077) (xy 94.836221 -19.686555)
			(xy 94.827597 -19.743384) (xy 94.810545 -19.798275) (xy 94.785454 -19.849988) (xy 94.752889 -19.897352)
			(xy 94.733618 -19.91868) (xy 94.727014 -19.925538) (xy 94.719902 -19.943572) (xy 94.719902 -20.032472)
			(xy 94.727014 -20.050506) (xy 94.733618 -20.057364) (xy 94.752909 -20.078673) (xy 94.78547 -20.12604)
			(xy 94.810557 -20.177755) (xy 94.827604 -20.232648) (xy 94.836223 -20.289477) (xy 94.836221 -20.346955)
			(xy 94.827597 -20.403784) (xy 94.810545 -20.458675) (xy 94.785454 -20.510388) (xy 94.752889 -20.557752)
			(xy 94.733618 -20.57908) (xy 94.727014 -20.585938) (xy 94.719902 -20.603972) (xy 94.719902 -20.692872)
			(xy 94.727014 -20.710906) (xy 94.733618 -20.717764) (xy 94.740286 -20.72513) (xy 121.28044 -20.72513)
			(xy 121.28441 -20.594996) (xy 121.296306 -20.465346) (xy 121.316085 -20.336663) (xy 121.343671 -20.209424)
			(xy 121.378964 -20.084105) (xy 121.42183 -19.961169) (xy 121.472112 -19.841076) (xy 121.529621 -19.724272)
			(xy 121.594145 -19.61119) (xy 121.665442 -19.502253) (xy 121.743247 -19.397865) (xy 121.827272 -19.298414)
			(xy 121.917204 -19.204271) (xy 122.012708 -19.115786) (xy 122.113428 -19.033287) (xy 122.21899 -18.957082)
			(xy 122.329002 -18.887455) (xy 122.443054 -18.824664) (xy 122.560722 -18.768942) (xy 122.681568 -18.720498)
			(xy 122.805143 -18.679511) (xy 122.930986 -18.646134) (xy 123.058631 -18.620491) (xy 123.187601 -18.602677)
			(xy 123.317417 -18.592759) (xy 123.447596 -18.590774) (xy 123.577655 -18.596728) (xy 123.707108 -18.610601)
			(xy 123.835475 -18.632339) (xy 123.962278 -18.661863) (xy 124.087045 -18.699062) (xy 124.209312 -18.743798)
			(xy 124.328625 -18.795906) (xy 124.444538 -18.855189) (xy 124.556623 -18.92143) (xy 124.66446 -18.99438)
			(xy 124.767649 -19.073768) (xy 124.865807 -19.1593) (xy 124.958568 -19.250657) (xy 125.045587 -19.347499)
			(xy 125.12654 -19.449466) (xy 125.201126 -19.556178) (xy 125.269067 -19.667239) (xy 125.330112 -19.782235)
			(xy 125.384033 -19.900739) (xy 125.430628 -20.02231) (xy 125.469726 -20.146495) (xy 125.50118 -20.272833)
			(xy 125.524874 -20.400854) (xy 125.540718 -20.53008) (xy 125.548656 -20.660033) (xy 125.549152 -20.72513)
			(xy 125.548656 -20.790227) (xy 125.540718 -20.92018) (xy 125.524874 -21.049406) (xy 125.50118 -21.177427)
			(xy 125.469726 -21.303765) (xy 125.430628 -21.42795) (xy 125.384033 -21.549521) (xy 125.343309 -21.639022)
			(xy 132.17398 -21.639022) (xy 132.174522 -21.610284) (xy 132.183141 -21.553458) (xy 132.200187 -21.498567)
			(xy 132.225275 -21.446855) (xy 132.257835 -21.399492) (xy 132.277104 -21.378164) (xy 132.283708 -21.371306)
			(xy 132.29082 -21.353272) (xy 132.29082 -21.264372) (xy 132.283708 -21.246338) (xy 132.277104 -21.23948)
			(xy 132.257856 -21.218134) (xy 132.225292 -21.170774) (xy 132.2002 -21.119065) (xy 132.183149 -21.064178)
			(xy 132.174525 -21.007354) (xy 132.174523 -20.949879) (xy 132.183142 -20.893054) (xy 132.200188 -20.838165)
			(xy 132.225275 -20.786454) (xy 132.257836 -20.739091) (xy 132.277104 -20.717764) (xy 132.283708 -20.710906)
			(xy 132.29082 -20.692872) (xy 132.29082 -20.603972) (xy 132.283708 -20.585938) (xy 132.277104 -20.57908)
			(xy 132.257856 -20.557734) (xy 132.225292 -20.510374) (xy 132.2002 -20.458665) (xy 132.183149 -20.403778)
			(xy 132.174525 -20.346954) (xy 132.174523 -20.289479) (xy 132.183142 -20.232654) (xy 132.200188 -20.177765)
			(xy 132.225275 -20.126054) (xy 132.257836 -20.078691) (xy 132.277104 -20.057364) (xy 132.283708 -20.050506)
			(xy 132.29082 -20.032472) (xy 132.29082 -19.943572) (xy 132.283708 -19.925538) (xy 132.277104 -19.91868)
			(xy 132.257856 -19.897334) (xy 132.225292 -19.849974) (xy 132.2002 -19.798265) (xy 132.183149 -19.743378)
			(xy 132.174525 -19.686554) (xy 132.174523 -19.629079) (xy 132.183142 -19.572254) (xy 132.200188 -19.517365)
			(xy 132.225275 -19.465654) (xy 132.257836 -19.418291) (xy 132.277104 -19.396964) (xy 132.283708 -19.390106)
			(xy 132.29082 -19.372072) (xy 132.29082 -19.283172) (xy 132.283708 -19.265138) (xy 132.277104 -19.25828)
			(xy 132.257855 -19.236934) (xy 132.225283 -19.189578) (xy 132.200186 -19.137872) (xy 132.18313 -19.082985)
			(xy 132.174503 -19.02616) (xy 132.17398 -18.997422) (xy 132.174466 -18.970171) (xy 132.182222 -18.916223)
			(xy 132.197577 -18.863928) (xy 132.220219 -18.814351) (xy 132.249685 -18.768501) (xy 132.285376 -18.72731)
			(xy 132.326567 -18.691619) (xy 132.372417 -18.662153) (xy 132.421994 -18.639511) (xy 132.474289 -18.624156)
			(xy 132.528237 -18.6164) (xy 132.582739 -18.6164) (xy 132.636687 -18.624156) (xy 132.688982 -18.639511)
			(xy 132.738559 -18.662153) (xy 132.784409 -18.691619) (xy 132.8256 -18.72731) (xy 132.861291 -18.768501)
			(xy 132.890757 -18.814351) (xy 132.913399 -18.863928) (xy 132.928754 -18.916223) (xy 132.93651 -18.970171)
			(xy 132.936996 -18.997422) (xy 132.936487 -19.026161) (xy 132.927861 -19.082989) (xy 132.910807 -19.13788)
			(xy 132.885713 -19.189592) (xy 132.853144 -19.236954) (xy 132.833872 -19.25828) (xy 132.827268 -19.265138)
			(xy 132.820156 -19.283172) (xy 132.820156 -19.372072) (xy 132.827268 -19.390106) (xy 132.833872 -19.396964)
			(xy 132.853165 -19.418272) (xy 132.877109 -19.453098) (xy 138.376404 -19.453098) (xy 138.380475 -19.397476)
			(xy 138.392601 -19.343039) (xy 138.412524 -19.290948) (xy 138.43982 -19.242313) (xy 138.473906 -19.19817)
			(xy 138.514055 -19.159461) (xy 138.559413 -19.12701) (xy 138.609013 -19.101509) (xy 138.661797 -19.083502)
			(xy 138.71664 -19.073372) (xy 138.772374 -19.071335) (xy 138.827811 -19.077435) (xy 138.881768 -19.091541)
			(xy 138.933097 -19.113353) (xy 138.980703 -19.142407) (xy 139.023571 -19.178082) (xy 139.060788 -19.219619)
			(xy 139.091561 -19.266132) (xy 139.115233 -19.316629) (xy 139.131301 -19.370036) (xy 139.139421 -19.425212)
			(xy 139.13993 -19.453098) (xy 139.139421 -19.480984) (xy 139.131301 -19.53616) (xy 139.115233 -19.589567)
			(xy 139.091561 -19.640064) (xy 139.060788 -19.686577) (xy 139.023571 -19.728114) (xy 138.980703 -19.763789)
			(xy 138.933097 -19.792843) (xy 138.881768 -19.814655) (xy 138.827811 -19.828761) (xy 138.772374 -19.834861)
			(xy 138.71664 -19.832824) (xy 138.661797 -19.822694) (xy 138.609013 -19.804687) (xy 138.559413 -19.779186)
			(xy 138.514055 -19.746735) (xy 138.473906 -19.708026) (xy 138.43982 -19.663883) (xy 138.412524 -19.615248)
			(xy 138.392601 -19.563157) (xy 138.380475 -19.50872) (xy 138.376404 -19.453098) (xy 132.877109 -19.453098)
			(xy 132.88573 -19.465637) (xy 132.91082 -19.517352) (xy 132.927869 -19.572246) (xy 132.93649 -19.629076)
			(xy 132.936487 -19.686556) (xy 132.927862 -19.743385) (xy 132.910808 -19.798278) (xy 132.885713 -19.84999)
			(xy 132.853145 -19.897353) (xy 132.833872 -19.91868) (xy 132.827268 -19.925538) (xy 132.820156 -19.943572)
			(xy 132.820156 -20.032472) (xy 132.827268 -20.050506) (xy 132.833872 -20.057364) (xy 132.853165 -20.078672)
			(xy 132.88573 -20.126037) (xy 132.91082 -20.177752) (xy 132.927869 -20.232646) (xy 132.93649 -20.289476)
			(xy 132.936487 -20.346956) (xy 132.927862 -20.403785) (xy 132.910808 -20.458678) (xy 132.906491 -20.467574)
			(xy 140.387576 -20.467574) (xy 140.391647 -20.411952) (xy 140.403773 -20.357515) (xy 140.423696 -20.305424)
			(xy 140.450992 -20.256789) (xy 140.485078 -20.212646) (xy 140.525227 -20.173937) (xy 140.570585 -20.141486)
			(xy 140.620185 -20.115985) (xy 140.672969 -20.097978) (xy 140.727812 -20.087848) (xy 140.783546 -20.085811)
			(xy 140.838983 -20.091911) (xy 140.89294 -20.106017) (xy 140.944269 -20.127829) (xy 140.991875 -20.156883)
			(xy 141.034743 -20.192558) (xy 141.07196 -20.234095) (xy 141.102733 -20.280608) (xy 141.126405 -20.331105)
			(xy 141.142473 -20.384512) (xy 141.150593 -20.439688) (xy 141.151102 -20.467574) (xy 141.150593 -20.49546)
			(xy 141.142473 -20.550636) (xy 141.126405 -20.604043) (xy 141.102733 -20.65454) (xy 141.07196 -20.701053)
			(xy 141.050615 -20.724876) (xy 147.280388 -20.724876) (xy 147.284358 -20.594742) (xy 147.296254 -20.465092)
			(xy 147.316033 -20.336409) (xy 147.343619 -20.20917) (xy 147.378912 -20.083851) (xy 147.421778 -19.960915)
			(xy 147.47206 -19.840822) (xy 147.529569 -19.724018) (xy 147.594093 -19.610936) (xy 147.66539 -19.501999)
			(xy 147.743195 -19.397611) (xy 147.82722 -19.29816) (xy 147.917152 -19.204017) (xy 148.012656 -19.115532)
			(xy 148.113376 -19.033033) (xy 148.218938 -18.956828) (xy 148.32895 -18.887201) (xy 148.443002 -18.82441)
			(xy 148.56067 -18.768688) (xy 148.681516 -18.720244) (xy 148.805091 -18.679257) (xy 148.930934 -18.64588)
			(xy 149.058579 -18.620237) (xy 149.187549 -18.602423) (xy 149.317365 -18.592505) (xy 149.447544 -18.59052)
			(xy 149.577603 -18.596474) (xy 149.707056 -18.610347) (xy 149.835423 -18.632085) (xy 149.962226 -18.661609)
			(xy 150.086993 -18.698808) (xy 150.20926 -18.743544) (xy 150.328573 -18.795652) (xy 150.444486 -18.854935)
			(xy 150.556571 -18.921176) (xy 150.664408 -18.994126) (xy 150.767597 -19.073514) (xy 150.865755 -19.159046)
			(xy 150.958516 -19.250403) (xy 151.045535 -19.347245) (xy 151.126488 -19.449212) (xy 151.201074 -19.555924)
			(xy 151.269015 -19.666985) (xy 151.33006 -19.781981) (xy 151.383981 -19.900485) (xy 151.430576 -20.022056)
			(xy 151.469674 -20.146241) (xy 151.501128 -20.272579) (xy 151.524822 -20.4006) (xy 151.540666 -20.529826)
			(xy 151.548604 -20.659779) (xy 151.5491 -20.724876) (xy 151.548604 -20.789973) (xy 151.540666 -20.919926)
			(xy 151.524822 -21.049152) (xy 151.501128 -21.177173) (xy 151.469674 -21.303511) (xy 151.430576 -21.427696)
			(xy 151.383981 -21.549267) (xy 151.343141 -21.639022) (xy 158.173928 -21.639022) (xy 158.174484 -21.610285)
			(xy 158.183102 -21.55346) (xy 158.200145 -21.49857) (xy 158.225229 -21.446858) (xy 158.257786 -21.399493)
			(xy 158.277052 -21.378164) (xy 158.283656 -21.371306) (xy 158.290768 -21.353272) (xy 158.290768 -21.264372)
			(xy 158.283656 -21.246338) (xy 158.277052 -21.23948) (xy 158.257802 -21.218135) (xy 158.225233 -21.170776)
			(xy 158.200139 -21.119068) (xy 158.183086 -21.06418) (xy 158.17446 -21.007354) (xy 158.174458 -20.949878)
			(xy 158.183079 -20.893052) (xy 158.200127 -20.838162) (xy 158.225217 -20.786451) (xy 158.257782 -20.73909)
			(xy 158.277052 -20.717764) (xy 158.283656 -20.710906) (xy 158.290768 -20.692872) (xy 158.290768 -20.603972)
			(xy 158.283656 -20.585938) (xy 158.277052 -20.57908) (xy 158.257802 -20.557735) (xy 158.225233 -20.510376)
			(xy 158.200139 -20.458668) (xy 158.183086 -20.40378) (xy 158.17446 -20.346954) (xy 158.174458 -20.289478)
			(xy 158.183079 -20.232652) (xy 158.200127 -20.177762) (xy 158.225217 -20.126051) (xy 158.257782 -20.07869)
			(xy 158.277052 -20.057364) (xy 158.283656 -20.050506) (xy 158.290768 -20.032472) (xy 158.290768 -19.943572)
			(xy 158.283656 -19.925538) (xy 158.277052 -19.91868) (xy 158.257802 -19.897335) (xy 158.225233 -19.849976)
			(xy 158.200139 -19.798268) (xy 158.183086 -19.74338) (xy 158.17446 -19.686554) (xy 158.174458 -19.629078)
			(xy 158.183079 -19.572252) (xy 158.200127 -19.517362) (xy 158.225217 -19.465651) (xy 158.257782 -19.41829)
			(xy 158.277052 -19.396964) (xy 158.283656 -19.390106) (xy 158.290768 -19.372072) (xy 158.290768 -19.283172)
			(xy 158.283656 -19.265138) (xy 158.277052 -19.25828) (xy 158.257794 -19.236942) (xy 158.225225 -19.189583)
			(xy 158.20013 -19.137874) (xy 158.183077 -19.082986) (xy 158.174451 -19.02616) (xy 158.173928 -18.997422)
			(xy 158.174414 -18.970171) (xy 158.18217 -18.916223) (xy 158.197525 -18.863928) (xy 158.220167 -18.814351)
			(xy 158.249633 -18.768501) (xy 158.285324 -18.72731) (xy 158.326515 -18.691619) (xy 158.372365 -18.662153)
			(xy 158.421942 -18.639511) (xy 158.474237 -18.624156) (xy 158.528185 -18.6164) (xy 158.582687 -18.6164)
			(xy 158.636635 -18.624156) (xy 158.68893 -18.639511) (xy 158.738507 -18.662153) (xy 158.784357 -18.691619)
			(xy 158.825548 -18.72731) (xy 158.861239 -18.768501) (xy 158.890705 -18.814351) (xy 158.913347 -18.863928)
			(xy 158.928702 -18.916223) (xy 158.936458 -18.970171) (xy 158.936944 -18.997422) (xy 158.936422 -19.026161)
			(xy 158.927797 -19.082988) (xy 158.910746 -19.137878) (xy 158.885654 -19.18959) (xy 158.85309 -19.236953)
			(xy 158.83382 -19.25828) (xy 158.827216 -19.265138) (xy 158.820104 -19.283172) (xy 158.820104 -19.372072)
			(xy 158.827216 -19.390106) (xy 158.83382 -19.396964) (xy 158.853111 -19.418273) (xy 158.87705 -19.453098)
			(xy 164.376352 -19.453098) (xy 164.380423 -19.397476) (xy 164.392549 -19.343039) (xy 164.412472 -19.290948)
			(xy 164.439768 -19.242313) (xy 164.473854 -19.19817) (xy 164.514003 -19.159461) (xy 164.559361 -19.12701)
			(xy 164.608961 -19.101509) (xy 164.661745 -19.083502) (xy 164.716588 -19.073372) (xy 164.772322 -19.071335)
			(xy 164.827759 -19.077435) (xy 164.881716 -19.091541) (xy 164.933045 -19.113353) (xy 164.980651 -19.142407)
			(xy 165.023519 -19.178082) (xy 165.060736 -19.219619) (xy 165.091509 -19.266132) (xy 165.115181 -19.316629)
			(xy 165.131249 -19.370036) (xy 165.139369 -19.425212) (xy 165.139878 -19.453098) (xy 165.139369 -19.480984)
			(xy 165.131249 -19.53616) (xy 165.115181 -19.589567) (xy 165.091509 -19.640064) (xy 165.060736 -19.686577)
			(xy 165.023519 -19.728114) (xy 164.980651 -19.763789) (xy 164.933045 -19.792843) (xy 164.881716 -19.814655)
			(xy 164.827759 -19.828761) (xy 164.772322 -19.834861) (xy 164.716588 -19.832824) (xy 164.661745 -19.822694)
			(xy 164.608961 -19.804687) (xy 164.559361 -19.779186) (xy 164.514003 -19.746735) (xy 164.473854 -19.708026)
			(xy 164.439768 -19.663883) (xy 164.412472 -19.615248) (xy 164.392549 -19.563157) (xy 164.380423 -19.50872)
			(xy 164.376352 -19.453098) (xy 158.87705 -19.453098) (xy 158.885671 -19.46564) (xy 158.910759 -19.517355)
			(xy 158.927805 -19.572248) (xy 158.936425 -19.629077) (xy 158.936422 -19.686555) (xy 158.927798 -19.743384)
			(xy 158.910747 -19.798275) (xy 158.885655 -19.849988) (xy 158.85309 -19.897352) (xy 158.83382 -19.91868)
			(xy 158.827216 -19.925538) (xy 158.820104 -19.943572) (xy 158.820104 -20.032472) (xy 158.827216 -20.050506)
			(xy 158.83382 -20.057364) (xy 158.853111 -20.078673) (xy 158.885671 -20.12604) (xy 158.910759 -20.177755)
			(xy 158.927805 -20.232648) (xy 158.936425 -20.289477) (xy 158.936422 -20.346955) (xy 158.927798 -20.403784)
			(xy 158.910747 -20.458675) (xy 158.906429 -20.467574) (xy 166.387524 -20.467574) (xy 166.391595 -20.411952)
			(xy 166.403721 -20.357515) (xy 166.423644 -20.305424) (xy 166.45094 -20.256789) (xy 166.485026 -20.212646)
			(xy 166.525175 -20.173937) (xy 166.570533 -20.141486) (xy 166.620133 -20.115985) (xy 166.672917 -20.097978)
			(xy 166.72776 -20.087848) (xy 166.783494 -20.085811) (xy 166.838931 -20.091911) (xy 166.892888 -20.106017)
			(xy 166.944217 -20.127829) (xy 166.991823 -20.156883) (xy 167.034691 -20.192558) (xy 167.071908 -20.234095)
			(xy 167.102681 -20.280608) (xy 167.126353 -20.331105) (xy 167.142421 -20.384512) (xy 167.150541 -20.439688)
			(xy 167.15105 -20.467574) (xy 167.150541 -20.49546) (xy 167.142421 -20.550636) (xy 167.126353 -20.604043)
			(xy 167.102681 -20.65454) (xy 167.071908 -20.701053) (xy 167.050335 -20.72513) (xy 173.28059 -20.72513)
			(xy 173.28456 -20.594996) (xy 173.296456 -20.465346) (xy 173.316235 -20.336663) (xy 173.343821 -20.209424)
			(xy 173.379114 -20.084105) (xy 173.42198 -19.961169) (xy 173.472262 -19.841076) (xy 173.529771 -19.724272)
			(xy 173.594295 -19.61119) (xy 173.665592 -19.502253) (xy 173.743397 -19.397865) (xy 173.827422 -19.298414)
			(xy 173.917354 -19.204271) (xy 174.012858 -19.115786) (xy 174.113578 -19.033287) (xy 174.21914 -18.957082)
			(xy 174.329152 -18.887455) (xy 174.443204 -18.824664) (xy 174.560872 -18.768942) (xy 174.681718 -18.720498)
			(xy 174.805293 -18.679511) (xy 174.931136 -18.646134) (xy 175.058781 -18.620491) (xy 175.187751 -18.602677)
			(xy 175.317567 -18.592759) (xy 175.447746 -18.590774) (xy 175.577805 -18.596728) (xy 175.707258 -18.610601)
			(xy 175.835625 -18.632339) (xy 175.962428 -18.661863) (xy 176.087195 -18.699062) (xy 176.209462 -18.743798)
			(xy 176.328775 -18.795906) (xy 176.444688 -18.855189) (xy 176.556773 -18.92143) (xy 176.66461 -18.99438)
			(xy 176.767799 -19.073768) (xy 176.865957 -19.1593) (xy 176.958718 -19.250657) (xy 177.045737 -19.347499)
			(xy 177.12669 -19.449466) (xy 177.201276 -19.556178) (xy 177.269217 -19.667239) (xy 177.330262 -19.782235)
			(xy 177.384183 -19.900739) (xy 177.430778 -20.02231) (xy 177.469876 -20.146495) (xy 177.50133 -20.272833)
			(xy 177.525024 -20.400854) (xy 177.540868 -20.53008) (xy 177.548806 -20.660033) (xy 177.549302 -20.72513)
			(xy 177.548806 -20.790227) (xy 177.540868 -20.92018) (xy 177.525024 -21.049406) (xy 177.50133 -21.177427)
			(xy 177.469876 -21.303765) (xy 177.430778 -21.42795) (xy 177.384183 -21.549521) (xy 177.343459 -21.639022)
			(xy 184.173876 -21.639022) (xy 184.17442 -21.610284) (xy 184.183038 -21.553458) (xy 184.200084 -21.498567)
			(xy 184.225171 -21.446855) (xy 184.257732 -21.399492) (xy 184.277 -21.378164) (xy 184.283604 -21.371306)
			(xy 184.290716 -21.353272) (xy 184.290716 -21.264372) (xy 184.283604 -21.246338) (xy 184.277 -21.23948)
			(xy 184.257752 -21.218134) (xy 184.225188 -21.170774) (xy 184.200097 -21.119065) (xy 184.183046 -21.064178)
			(xy 184.174422 -21.007353) (xy 184.17442 -20.949879) (xy 184.183039 -20.893054) (xy 184.200085 -20.838165)
			(xy 184.225172 -20.786454) (xy 184.257732 -20.739091) (xy 184.277 -20.717764) (xy 184.283604 -20.710906)
			(xy 184.290716 -20.692872) (xy 184.290716 -20.603972) (xy 184.283604 -20.585938) (xy 184.277 -20.57908)
			(xy 184.257752 -20.557734) (xy 184.225188 -20.510374) (xy 184.200097 -20.458665) (xy 184.183046 -20.403778)
			(xy 184.174422 -20.346953) (xy 184.17442 -20.289479) (xy 184.183039 -20.232654) (xy 184.200085 -20.177765)
			(xy 184.225172 -20.126054) (xy 184.257732 -20.078691) (xy 184.277 -20.057364) (xy 184.283604 -20.050506)
			(xy 184.290716 -20.032472) (xy 184.290716 -19.943572) (xy 184.283604 -19.925538) (xy 184.277 -19.91868)
			(xy 184.257752 -19.897334) (xy 184.225188 -19.849974) (xy 184.200097 -19.798265) (xy 184.183046 -19.743378)
			(xy 184.174422 -19.686553) (xy 184.17442 -19.629079) (xy 184.183039 -19.572254) (xy 184.200085 -19.517365)
			(xy 184.225172 -19.465654) (xy 184.257732 -19.418291) (xy 184.277 -19.396964) (xy 184.283604 -19.390106)
			(xy 184.290716 -19.372072) (xy 184.290716 -19.283172) (xy 184.283604 -19.265138) (xy 184.277 -19.25828)
			(xy 184.25775 -19.236935) (xy 184.225179 -19.189579) (xy 184.200081 -19.137872) (xy 184.183026 -19.082985)
			(xy 184.174399 -19.02616) (xy 184.173876 -18.997422) (xy 184.174362 -18.970171) (xy 184.182118 -18.916223)
			(xy 184.197473 -18.863928) (xy 184.220115 -18.814351) (xy 184.249581 -18.768501) (xy 184.285272 -18.72731)
			(xy 184.326463 -18.691619) (xy 184.372313 -18.662153) (xy 184.42189 -18.639511) (xy 184.474185 -18.624156)
			(xy 184.528133 -18.6164) (xy 184.582635 -18.6164) (xy 184.636583 -18.624156) (xy 184.688878 -18.639511)
			(xy 184.738455 -18.662153) (xy 184.784305 -18.691619) (xy 184.825496 -18.72731) (xy 184.861187 -18.768501)
			(xy 184.890653 -18.814351) (xy 184.913295 -18.863928) (xy 184.92865 -18.916223) (xy 184.936406 -18.970171)
			(xy 184.936892 -18.997422) (xy 184.936384 -19.026162) (xy 184.927758 -19.08299) (xy 184.910704 -19.137881)
			(xy 184.885609 -19.189592) (xy 184.85304 -19.236954) (xy 184.833768 -19.25828) (xy 184.827164 -19.265138)
			(xy 184.820052 -19.283172) (xy 184.820052 -19.372072) (xy 184.827164 -19.390106) (xy 184.833768 -19.396964)
			(xy 184.853061 -19.418272) (xy 184.877005 -19.453098) (xy 190.3763 -19.453098) (xy 190.380371 -19.397476)
			(xy 190.392497 -19.343039) (xy 190.41242 -19.290948) (xy 190.439716 -19.242313) (xy 190.473802 -19.19817)
			(xy 190.513951 -19.159461) (xy 190.559309 -19.12701) (xy 190.608909 -19.101509) (xy 190.661693 -19.083502)
			(xy 190.716536 -19.073372) (xy 190.77227 -19.071335) (xy 190.827707 -19.077435) (xy 190.881664 -19.091541)
			(xy 190.932993 -19.113353) (xy 190.980599 -19.142407) (xy 191.023467 -19.178082) (xy 191.060684 -19.219619)
			(xy 191.091457 -19.266132) (xy 191.115129 -19.316629) (xy 191.131197 -19.370036) (xy 191.139317 -19.425212)
			(xy 191.139826 -19.453098) (xy 191.139317 -19.480984) (xy 191.131197 -19.53616) (xy 191.115129 -19.589567)
			(xy 191.091457 -19.640064) (xy 191.060684 -19.686577) (xy 191.023467 -19.728114) (xy 190.980599 -19.763789)
			(xy 190.932993 -19.792843) (xy 190.881664 -19.814655) (xy 190.827707 -19.828761) (xy 190.77227 -19.834861)
			(xy 190.716536 -19.832824) (xy 190.661693 -19.822694) (xy 190.608909 -19.804687) (xy 190.559309 -19.779186)
			(xy 190.513951 -19.746735) (xy 190.473802 -19.708026) (xy 190.439716 -19.663883) (xy 190.41242 -19.615248)
			(xy 190.392497 -19.563157) (xy 190.380371 -19.50872) (xy 190.3763 -19.453098) (xy 184.877005 -19.453098)
			(xy 184.885626 -19.465637) (xy 184.910717 -19.517352) (xy 184.927766 -19.572246) (xy 184.936387 -19.629076)
			(xy 184.936384 -19.686556) (xy 184.927759 -19.743386) (xy 184.910705 -19.798278) (xy 184.88561 -19.849991)
			(xy 184.853041 -19.897353) (xy 184.833768 -19.91868) (xy 184.827164 -19.925538) (xy 184.820052 -19.943572)
			(xy 184.820052 -20.032472) (xy 184.827164 -20.050506) (xy 184.833768 -20.057364) (xy 184.853061 -20.078672)
			(xy 184.885626 -20.126037) (xy 184.910717 -20.177752) (xy 184.927766 -20.232646) (xy 184.936387 -20.289476)
			(xy 184.936384 -20.346956) (xy 184.927759 -20.403786) (xy 184.910705 -20.458678) (xy 184.906388 -20.467574)
			(xy 192.387472 -20.467574) (xy 192.391543 -20.411952) (xy 192.403669 -20.357515) (xy 192.423592 -20.305424)
			(xy 192.450888 -20.256789) (xy 192.484974 -20.212646) (xy 192.525123 -20.173937) (xy 192.570481 -20.141486)
			(xy 192.620081 -20.115985) (xy 192.672865 -20.097978) (xy 192.727708 -20.087848) (xy 192.783442 -20.085811)
			(xy 192.838879 -20.091911) (xy 192.892836 -20.106017) (xy 192.944165 -20.127829) (xy 192.991771 -20.156883)
			(xy 193.034639 -20.192558) (xy 193.071856 -20.234095) (xy 193.102629 -20.280608) (xy 193.126301 -20.331105)
			(xy 193.142369 -20.384512) (xy 193.150489 -20.439688) (xy 193.150998 -20.467574) (xy 193.150489 -20.49546)
			(xy 193.142369 -20.550636) (xy 193.126301 -20.604043) (xy 193.102629 -20.65454) (xy 193.071856 -20.701053)
			(xy 193.050283 -20.72513) (xy 199.280538 -20.72513) (xy 199.284508 -20.594996) (xy 199.296404 -20.465346)
			(xy 199.316183 -20.336663) (xy 199.343769 -20.209424) (xy 199.379062 -20.084105) (xy 199.421928 -19.961169)
			(xy 199.47221 -19.841076) (xy 199.529719 -19.724272) (xy 199.594243 -19.61119) (xy 199.66554 -19.502253)
			(xy 199.743345 -19.397865) (xy 199.82737 -19.298414) (xy 199.917302 -19.204271) (xy 200.012806 -19.115786)
			(xy 200.113526 -19.033287) (xy 200.219088 -18.957082) (xy 200.3291 -18.887455) (xy 200.443152 -18.824664)
			(xy 200.56082 -18.768942) (xy 200.681666 -18.720498) (xy 200.805241 -18.679511) (xy 200.931084 -18.646134)
			(xy 201.058729 -18.620491) (xy 201.187699 -18.602677) (xy 201.317515 -18.592759) (xy 201.447694 -18.590774)
			(xy 201.577753 -18.596728) (xy 201.707206 -18.610601) (xy 201.835573 -18.632339) (xy 201.962376 -18.661863)
			(xy 202.087143 -18.699062) (xy 202.20941 -18.743798) (xy 202.328723 -18.795906) (xy 202.444636 -18.855189)
			(xy 202.556721 -18.92143) (xy 202.664558 -18.99438) (xy 202.767747 -19.073768) (xy 202.865905 -19.1593)
			(xy 202.958666 -19.250657) (xy 203.045685 -19.347499) (xy 203.126638 -19.449466) (xy 203.201224 -19.556178)
			(xy 203.269165 -19.667239) (xy 203.33021 -19.782235) (xy 203.384131 -19.900739) (xy 203.430726 -20.02231)
			(xy 203.469824 -20.146495) (xy 203.501278 -20.272833) (xy 203.524972 -20.400854) (xy 203.540816 -20.53008)
			(xy 203.548754 -20.660033) (xy 203.54925 -20.72513) (xy 203.548754 -20.790227) (xy 203.540816 -20.92018)
			(xy 203.524972 -21.049406) (xy 203.501278 -21.177427) (xy 203.469824 -21.303765) (xy 203.430726 -21.42795)
			(xy 203.384131 -21.549521) (xy 203.343407 -21.639022) (xy 210.173824 -21.639022) (xy 210.174381 -21.610285)
			(xy 210.182999 -21.55346) (xy 210.200042 -21.49857) (xy 210.225126 -21.446858) (xy 210.257682 -21.399493)
			(xy 210.276948 -21.378164) (xy 210.283552 -21.371306) (xy 210.290664 -21.353272) (xy 210.290664 -21.264372)
			(xy 210.283552 -21.246338) (xy 210.276948 -21.23948) (xy 210.257698 -21.218135) (xy 210.22513 -21.170776)
			(xy 210.200036 -21.119068) (xy 210.182983 -21.064179) (xy 210.174358 -21.007354) (xy 210.174355 -20.949878)
			(xy 210.182976 -20.893052) (xy 210.200024 -20.838162) (xy 210.225114 -20.786452) (xy 210.257678 -20.73909)
			(xy 210.276948 -20.717764) (xy 210.283552 -20.710906) (xy 210.290664 -20.692872) (xy 210.290664 -20.603972)
			(xy 210.283552 -20.585938) (xy 210.276948 -20.57908) (xy 210.257698 -20.557735) (xy 210.22513 -20.510376)
			(xy 210.200036 -20.458668) (xy 210.182983 -20.403779) (xy 210.174358 -20.346954) (xy 210.174355 -20.289478)
			(xy 210.182976 -20.232652) (xy 210.200024 -20.177762) (xy 210.225114 -20.126052) (xy 210.257678 -20.07869)
			(xy 210.276948 -20.057364) (xy 210.283552 -20.050506) (xy 210.290664 -20.032472) (xy 210.290664 -19.943572)
			(xy 210.283552 -19.925538) (xy 210.276948 -19.91868) (xy 210.257698 -19.897335) (xy 210.22513 -19.849976)
			(xy 210.200036 -19.798268) (xy 210.182983 -19.743379) (xy 210.174358 -19.686554) (xy 210.174355 -19.629078)
			(xy 210.182976 -19.572252) (xy 210.200024 -19.517362) (xy 210.225114 -19.465652) (xy 210.257678 -19.41829)
			(xy 210.276948 -19.396964) (xy 210.283552 -19.390106) (xy 210.290664 -19.372072) (xy 210.290664 -19.283172)
			(xy 210.283552 -19.265138) (xy 210.276948 -19.25828) (xy 210.257689 -19.236942) (xy 210.225121 -19.189584)
			(xy 210.200026 -19.137875) (xy 210.182973 -19.082986) (xy 210.174347 -19.02616) (xy 210.173824 -18.997422)
			(xy 210.17431 -18.970171) (xy 210.182066 -18.916223) (xy 210.197421 -18.863928) (xy 210.220063 -18.814351)
			(xy 210.249529 -18.768501) (xy 210.28522 -18.72731) (xy 210.326411 -18.691619) (xy 210.372261 -18.662153)
			(xy 210.421838 -18.639511) (xy 210.474133 -18.624156) (xy 210.528081 -18.6164) (xy 210.582583 -18.6164)
			(xy 210.636531 -18.624156) (xy 210.688826 -18.639511) (xy 210.738403 -18.662153) (xy 210.784253 -18.691619)
			(xy 210.825444 -18.72731) (xy 210.861135 -18.768501) (xy 210.890601 -18.814351) (xy 210.913243 -18.863928)
			(xy 210.928598 -18.916223) (xy 210.936354 -18.970171) (xy 210.93684 -18.997422) (xy 210.936319 -19.026161)
			(xy 210.927694 -19.082988) (xy 210.910643 -19.137878) (xy 210.885551 -19.18959) (xy 210.852986 -19.236953)
			(xy 210.833716 -19.25828) (xy 210.827112 -19.265138) (xy 210.82 -19.283172) (xy 210.82 -19.372072)
			(xy 210.827112 -19.390106) (xy 210.833716 -19.396964) (xy 210.853007 -19.418273) (xy 210.876947 -19.453098)
			(xy 216.376248 -19.453098) (xy 216.380319 -19.397476) (xy 216.392445 -19.343039) (xy 216.412368 -19.290948)
			(xy 216.439664 -19.242313) (xy 216.47375 -19.19817) (xy 216.513899 -19.159461) (xy 216.559257 -19.12701)
			(xy 216.608857 -19.101509) (xy 216.661641 -19.083502) (xy 216.716484 -19.073372) (xy 216.772218 -19.071335)
			(xy 216.827655 -19.077435) (xy 216.881612 -19.091541) (xy 216.932941 -19.113353) (xy 216.980547 -19.142407)
			(xy 217.023415 -19.178082) (xy 217.060632 -19.219619) (xy 217.091405 -19.266132) (xy 217.115077 -19.316629)
			(xy 217.131145 -19.370036) (xy 217.139265 -19.425212) (xy 217.139774 -19.453098) (xy 217.139265 -19.480984)
			(xy 217.131145 -19.53616) (xy 217.115077 -19.589567) (xy 217.091405 -19.640064) (xy 217.060632 -19.686577)
			(xy 217.023415 -19.728114) (xy 216.980547 -19.763789) (xy 216.932941 -19.792843) (xy 216.881612 -19.814655)
			(xy 216.827655 -19.828761) (xy 216.772218 -19.834861) (xy 216.716484 -19.832824) (xy 216.661641 -19.822694)
			(xy 216.608857 -19.804687) (xy 216.559257 -19.779186) (xy 216.513899 -19.746735) (xy 216.47375 -19.708026)
			(xy 216.439664 -19.663883) (xy 216.412368 -19.615248) (xy 216.392445 -19.563157) (xy 216.380319 -19.50872)
			(xy 216.376248 -19.453098) (xy 210.876947 -19.453098) (xy 210.885568 -19.465639) (xy 210.910656 -19.517354)
			(xy 210.927702 -19.572248) (xy 210.936322 -19.629077) (xy 210.936319 -19.686556) (xy 210.927695 -19.743384)
			(xy 210.910644 -19.798275) (xy 210.885552 -19.849988) (xy 210.852987 -19.897352) (xy 210.833716 -19.91868)
			(xy 210.827112 -19.925538) (xy 210.82 -19.943572) (xy 210.82 -20.032472) (xy 210.827112 -20.050506)
			(xy 210.833716 -20.057364) (xy 210.853007 -20.078673) (xy 210.885568 -20.126039) (xy 210.910656 -20.177754)
			(xy 210.927702 -20.232648) (xy 210.936322 -20.289477) (xy 210.936319 -20.346956) (xy 210.927695 -20.403784)
			(xy 210.910644 -20.458675) (xy 210.906326 -20.467574) (xy 218.38742 -20.467574) (xy 218.391491 -20.411952)
			(xy 218.403617 -20.357515) (xy 218.42354 -20.305424) (xy 218.450836 -20.256789) (xy 218.484922 -20.212646)
			(xy 218.525071 -20.173937) (xy 218.570429 -20.141486) (xy 218.620029 -20.115985) (xy 218.672813 -20.097978)
			(xy 218.727656 -20.087848) (xy 218.78339 -20.085811) (xy 218.838827 -20.091911) (xy 218.892784 -20.106017)
			(xy 218.944113 -20.127829) (xy 218.991719 -20.156883) (xy 219.034587 -20.192558) (xy 219.071804 -20.234095)
			(xy 219.102577 -20.280608) (xy 219.126249 -20.331105) (xy 219.142317 -20.384512) (xy 219.150437 -20.439688)
			(xy 219.150946 -20.467574) (xy 219.150437 -20.49546) (xy 219.142317 -20.550636) (xy 219.126249 -20.604043)
			(xy 219.102577 -20.65454) (xy 219.071804 -20.701053) (xy 219.050231 -20.72513) (xy 237.380538 -20.72513)
			(xy 237.384508 -20.594996) (xy 237.396404 -20.465346) (xy 237.416183 -20.336663) (xy 237.443769 -20.209424)
			(xy 237.479062 -20.084105) (xy 237.521928 -19.961169) (xy 237.57221 -19.841076) (xy 237.629719 -19.724272)
			(xy 237.694243 -19.61119) (xy 237.76554 -19.502253) (xy 237.843345 -19.397865) (xy 237.92737 -19.298414)
			(xy 238.017302 -19.204271) (xy 238.112806 -19.115786) (xy 238.213526 -19.033287) (xy 238.319088 -18.957082)
			(xy 238.4291 -18.887455) (xy 238.543152 -18.824664) (xy 238.66082 -18.768942) (xy 238.781666 -18.720498)
			(xy 238.905241 -18.679511) (xy 239.031084 -18.646134) (xy 239.158729 -18.620491) (xy 239.287699 -18.602677)
			(xy 239.417515 -18.592759) (xy 239.547694 -18.590774) (xy 239.677753 -18.596728) (xy 239.807206 -18.610601)
			(xy 239.935573 -18.632339) (xy 240.062376 -18.661863) (xy 240.187143 -18.699062) (xy 240.30941 -18.743798)
			(xy 240.428723 -18.795906) (xy 240.544636 -18.855189) (xy 240.656721 -18.92143) (xy 240.764558 -18.99438)
			(xy 240.867747 -19.073768) (xy 240.965905 -19.1593) (xy 241.058666 -19.250657) (xy 241.145685 -19.347499)
			(xy 241.226638 -19.449466) (xy 241.301224 -19.556178) (xy 241.369165 -19.667239) (xy 241.43021 -19.782235)
			(xy 241.484131 -19.900739) (xy 241.530726 -20.02231) (xy 241.569824 -20.146495) (xy 241.601278 -20.272833)
			(xy 241.624972 -20.400854) (xy 241.640816 -20.53008) (xy 241.648754 -20.660033) (xy 241.64925 -20.72513)
			(xy 241.648754 -20.790227) (xy 241.640816 -20.92018) (xy 241.624972 -21.049406) (xy 241.601278 -21.177427)
			(xy 241.569824 -21.303765) (xy 241.530726 -21.42795) (xy 241.484131 -21.549521) (xy 241.443407 -21.639022)
			(xy 248.273824 -21.639022) (xy 248.274381 -21.610285) (xy 248.282999 -21.55346) (xy 248.300042 -21.49857)
			(xy 248.325126 -21.446858) (xy 248.357682 -21.399493) (xy 248.376948 -21.378164) (xy 248.383552 -21.371306)
			(xy 248.390664 -21.353272) (xy 248.390664 -21.264372) (xy 248.383552 -21.246338) (xy 248.376948 -21.23948)
			(xy 248.357698 -21.218135) (xy 248.32513 -21.170776) (xy 248.300036 -21.119068) (xy 248.282983 -21.064179)
			(xy 248.274358 -21.007354) (xy 248.274355 -20.949878) (xy 248.282976 -20.893052) (xy 248.300024 -20.838162)
			(xy 248.325114 -20.786452) (xy 248.357678 -20.73909) (xy 248.376948 -20.717764) (xy 248.383552 -20.710906)
			(xy 248.390664 -20.692872) (xy 248.390664 -20.603972) (xy 248.383552 -20.585938) (xy 248.376948 -20.57908)
			(xy 248.357698 -20.557735) (xy 248.32513 -20.510376) (xy 248.300036 -20.458668) (xy 248.282983 -20.403779)
			(xy 248.274358 -20.346954) (xy 248.274355 -20.289478) (xy 248.282976 -20.232652) (xy 248.300024 -20.177762)
			(xy 248.325114 -20.126052) (xy 248.357678 -20.07869) (xy 248.376948 -20.057364) (xy 248.383552 -20.050506)
			(xy 248.390664 -20.032472) (xy 248.390664 -19.943572) (xy 248.383552 -19.925538) (xy 248.376948 -19.91868)
			(xy 248.357698 -19.897335) (xy 248.32513 -19.849976) (xy 248.300036 -19.798268) (xy 248.282983 -19.743379)
			(xy 248.274358 -19.686554) (xy 248.274355 -19.629078) (xy 248.282976 -19.572252) (xy 248.300024 -19.517362)
			(xy 248.325114 -19.465652) (xy 248.357678 -19.41829) (xy 248.376948 -19.396964) (xy 248.383552 -19.390106)
			(xy 248.390664 -19.372072) (xy 248.390664 -19.283172) (xy 248.383552 -19.265138) (xy 248.376948 -19.25828)
			(xy 248.357689 -19.236942) (xy 248.325121 -19.189584) (xy 248.300026 -19.137875) (xy 248.282973 -19.082986)
			(xy 248.274347 -19.02616) (xy 248.273824 -18.997422) (xy 248.27431 -18.970171) (xy 248.282066 -18.916223)
			(xy 248.297421 -18.863928) (xy 248.320063 -18.814351) (xy 248.349529 -18.768501) (xy 248.38522 -18.72731)
			(xy 248.426411 -18.691619) (xy 248.472261 -18.662153) (xy 248.521838 -18.639511) (xy 248.574133 -18.624156)
			(xy 248.628081 -18.6164) (xy 248.682583 -18.6164) (xy 248.736531 -18.624156) (xy 248.788826 -18.639511)
			(xy 248.838403 -18.662153) (xy 248.884253 -18.691619) (xy 248.925444 -18.72731) (xy 248.961135 -18.768501)
			(xy 248.990601 -18.814351) (xy 249.013243 -18.863928) (xy 249.028598 -18.916223) (xy 249.036354 -18.970171)
			(xy 249.03684 -18.997422) (xy 249.036319 -19.026161) (xy 249.027694 -19.082988) (xy 249.010643 -19.137878)
			(xy 248.985551 -19.18959) (xy 248.952986 -19.236953) (xy 248.933716 -19.25828) (xy 248.927112 -19.265138)
			(xy 248.92 -19.283172) (xy 248.92 -19.372072) (xy 248.927112 -19.390106) (xy 248.933716 -19.396964)
			(xy 248.953007 -19.418273) (xy 248.976947 -19.453098) (xy 254.476248 -19.453098) (xy 254.480319 -19.397476)
			(xy 254.492445 -19.343039) (xy 254.512368 -19.290948) (xy 254.539664 -19.242313) (xy 254.57375 -19.19817)
			(xy 254.613899 -19.159461) (xy 254.659257 -19.12701) (xy 254.708857 -19.101509) (xy 254.761641 -19.083502)
			(xy 254.816484 -19.073372) (xy 254.872218 -19.071335) (xy 254.927655 -19.077435) (xy 254.981612 -19.091541)
			(xy 255.032941 -19.113353) (xy 255.080547 -19.142407) (xy 255.123415 -19.178082) (xy 255.160632 -19.219619)
			(xy 255.191405 -19.266132) (xy 255.215077 -19.316629) (xy 255.231145 -19.370036) (xy 255.239265 -19.425212)
			(xy 255.239774 -19.453098) (xy 255.239265 -19.480984) (xy 255.231145 -19.53616) (xy 255.215077 -19.589567)
			(xy 255.191405 -19.640064) (xy 255.160632 -19.686577) (xy 255.123415 -19.728114) (xy 255.080547 -19.763789)
			(xy 255.032941 -19.792843) (xy 254.981612 -19.814655) (xy 254.927655 -19.828761) (xy 254.872218 -19.834861)
			(xy 254.816484 -19.832824) (xy 254.761641 -19.822694) (xy 254.708857 -19.804687) (xy 254.659257 -19.779186)
			(xy 254.613899 -19.746735) (xy 254.57375 -19.708026) (xy 254.539664 -19.663883) (xy 254.512368 -19.615248)
			(xy 254.492445 -19.563157) (xy 254.480319 -19.50872) (xy 254.476248 -19.453098) (xy 248.976947 -19.453098)
			(xy 248.985568 -19.465639) (xy 249.010656 -19.517354) (xy 249.027702 -19.572248) (xy 249.036322 -19.629077)
			(xy 249.036319 -19.686556) (xy 249.027695 -19.743384) (xy 249.010644 -19.798275) (xy 248.985552 -19.849988)
			(xy 248.952987 -19.897352) (xy 248.933716 -19.91868) (xy 248.927112 -19.925538) (xy 248.92 -19.943572)
			(xy 248.92 -20.032472) (xy 248.927112 -20.050506) (xy 248.933716 -20.057364) (xy 248.953007 -20.078673)
			(xy 248.985568 -20.126039) (xy 249.010656 -20.177754) (xy 249.027702 -20.232648) (xy 249.036322 -20.289477)
			(xy 249.036319 -20.346956) (xy 249.027695 -20.403784) (xy 249.010644 -20.458675) (xy 249.006326 -20.467574)
			(xy 256.48742 -20.467574) (xy 256.491491 -20.411952) (xy 256.503617 -20.357515) (xy 256.52354 -20.305424)
			(xy 256.550836 -20.256789) (xy 256.584922 -20.212646) (xy 256.625071 -20.173937) (xy 256.670429 -20.141486)
			(xy 256.720029 -20.115985) (xy 256.772813 -20.097978) (xy 256.827656 -20.087848) (xy 256.88339 -20.085811)
			(xy 256.938827 -20.091911) (xy 256.992784 -20.106017) (xy 257.044113 -20.127829) (xy 257.091719 -20.156883)
			(xy 257.134587 -20.192558) (xy 257.171804 -20.234095) (xy 257.202577 -20.280608) (xy 257.226249 -20.331105)
			(xy 257.242317 -20.384512) (xy 257.250437 -20.439688) (xy 257.250946 -20.467574) (xy 257.250437 -20.49546)
			(xy 257.242317 -20.550636) (xy 257.226249 -20.604043) (xy 257.202577 -20.65454) (xy 257.171804 -20.701053)
			(xy 257.150231 -20.72513) (xy 263.380486 -20.72513) (xy 263.384456 -20.594996) (xy 263.396352 -20.465346)
			(xy 263.416131 -20.336663) (xy 263.443717 -20.209424) (xy 263.47901 -20.084105) (xy 263.521876 -19.961169)
			(xy 263.572158 -19.841076) (xy 263.629667 -19.724272) (xy 263.694191 -19.61119) (xy 263.765488 -19.502253)
			(xy 263.843293 -19.397865) (xy 263.927318 -19.298414) (xy 264.01725 -19.204271) (xy 264.112754 -19.115786)
			(xy 264.213474 -19.033287) (xy 264.319036 -18.957082) (xy 264.429048 -18.887455) (xy 264.5431 -18.824664)
			(xy 264.660768 -18.768942) (xy 264.781614 -18.720498) (xy 264.905189 -18.679511) (xy 265.031032 -18.646134)
			(xy 265.158677 -18.620491) (xy 265.287647 -18.602677) (xy 265.417463 -18.592759) (xy 265.547642 -18.590774)
			(xy 265.677701 -18.596728) (xy 265.807154 -18.610601) (xy 265.935521 -18.632339) (xy 266.062324 -18.661863)
			(xy 266.187091 -18.699062) (xy 266.309358 -18.743798) (xy 266.428671 -18.795906) (xy 266.544584 -18.855189)
			(xy 266.656669 -18.92143) (xy 266.764506 -18.99438) (xy 266.867695 -19.073768) (xy 266.965853 -19.1593)
			(xy 267.058614 -19.250657) (xy 267.145633 -19.347499) (xy 267.226586 -19.449466) (xy 267.301172 -19.556178)
			(xy 267.369113 -19.667239) (xy 267.430158 -19.782235) (xy 267.484079 -19.900739) (xy 267.530674 -20.02231)
			(xy 267.569772 -20.146495) (xy 267.601226 -20.272833) (xy 267.62492 -20.400854) (xy 267.640764 -20.53008)
			(xy 267.648702 -20.660033) (xy 267.649198 -20.72513) (xy 267.648702 -20.790227) (xy 267.640764 -20.92018)
			(xy 267.62492 -21.049406) (xy 267.601226 -21.177427) (xy 267.569772 -21.303765) (xy 267.530674 -21.42795)
			(xy 267.484079 -21.549521) (xy 267.443355 -21.639022) (xy 274.273772 -21.639022) (xy 274.274317 -21.610284)
			(xy 274.282935 -21.553458) (xy 274.299981 -21.498568) (xy 274.325068 -21.446856) (xy 274.357628 -21.399492)
			(xy 274.376896 -21.378164) (xy 274.3835 -21.371306) (xy 274.390612 -21.353272) (xy 274.390612 -21.264372)
			(xy 274.3835 -21.246338) (xy 274.376896 -21.23948) (xy 274.357648 -21.218134) (xy 274.325085 -21.170774)
			(xy 274.299994 -21.119065) (xy 274.282943 -21.064178) (xy 274.274319 -21.007353) (xy 274.274317 -20.949879)
			(xy 274.282936 -20.893054) (xy 274.299982 -20.838165) (xy 274.325068 -20.786454) (xy 274.357628 -20.739091)
			(xy 274.376896 -20.717764) (xy 274.3835 -20.710906) (xy 274.390612 -20.692872) (xy 274.390612 -20.603972)
			(xy 274.3835 -20.585938) (xy 274.376896 -20.57908) (xy 274.357648 -20.557734) (xy 274.325085 -20.510374)
			(xy 274.299994 -20.458665) (xy 274.282943 -20.403778) (xy 274.274319 -20.346953) (xy 274.274317 -20.289479)
			(xy 274.282936 -20.232654) (xy 274.299982 -20.177765) (xy 274.325068 -20.126054) (xy 274.357628 -20.078691)
			(xy 274.376896 -20.057364) (xy 274.3835 -20.050506) (xy 274.390612 -20.032472) (xy 274.390612 -19.943572)
			(xy 274.3835 -19.925538) (xy 274.376896 -19.91868) (xy 274.357648 -19.897334) (xy 274.325085 -19.849974)
			(xy 274.299994 -19.798265) (xy 274.282943 -19.743378) (xy 274.274319 -19.686553) (xy 274.274317 -19.629079)
			(xy 274.282936 -19.572254) (xy 274.299982 -19.517365) (xy 274.325068 -19.465654) (xy 274.357628 -19.418291)
			(xy 274.376896 -19.396964) (xy 274.3835 -19.390106) (xy 274.390612 -19.372072) (xy 274.390612 -19.283172)
			(xy 274.3835 -19.265138) (xy 274.376896 -19.25828) (xy 274.357646 -19.236935) (xy 274.325075 -19.189579)
			(xy 274.299977 -19.137872) (xy 274.282922 -19.082985) (xy 274.274295 -19.02616) (xy 274.273772 -18.997422)
			(xy 274.274258 -18.970171) (xy 274.282014 -18.916223) (xy 274.297369 -18.863928) (xy 274.320011 -18.814351)
			(xy 274.349477 -18.768501) (xy 274.385168 -18.72731) (xy 274.426359 -18.691619) (xy 274.472209 -18.662153)
			(xy 274.521786 -18.639511) (xy 274.574081 -18.624156) (xy 274.628029 -18.6164) (xy 274.682531 -18.6164)
			(xy 274.736479 -18.624156) (xy 274.788774 -18.639511) (xy 274.838351 -18.662153) (xy 274.884201 -18.691619)
			(xy 274.925392 -18.72731) (xy 274.961083 -18.768501) (xy 274.990549 -18.814351) (xy 275.013191 -18.863928)
			(xy 275.028546 -18.916223) (xy 275.036302 -18.970171) (xy 275.036788 -18.997422) (xy 275.036281 -19.026162)
			(xy 275.027655 -19.08299) (xy 275.010601 -19.137881) (xy 274.985506 -19.189592) (xy 274.952937 -19.236954)
			(xy 274.933664 -19.25828) (xy 274.92706 -19.265138) (xy 274.919948 -19.283172) (xy 274.919948 -19.372072)
			(xy 274.92706 -19.390106) (xy 274.933664 -19.396964) (xy 274.952957 -19.418272) (xy 274.976902 -19.453098)
			(xy 280.476196 -19.453098) (xy 280.480267 -19.397476) (xy 280.492393 -19.343039) (xy 280.512316 -19.290948)
			(xy 280.539612 -19.242313) (xy 280.573698 -19.19817) (xy 280.613847 -19.159461) (xy 280.659205 -19.12701)
			(xy 280.708805 -19.101509) (xy 280.761589 -19.083502) (xy 280.816432 -19.073372) (xy 280.872166 -19.071335)
			(xy 280.927603 -19.077435) (xy 280.98156 -19.091541) (xy 281.032889 -19.113353) (xy 281.080495 -19.142407)
			(xy 281.123363 -19.178082) (xy 281.16058 -19.219619) (xy 281.191353 -19.266132) (xy 281.215025 -19.316629)
			(xy 281.231093 -19.370036) (xy 281.239213 -19.425212) (xy 281.239722 -19.453098) (xy 281.239213 -19.480984)
			(xy 281.231093 -19.53616) (xy 281.215025 -19.589567) (xy 281.191353 -19.640064) (xy 281.16058 -19.686577)
			(xy 281.123363 -19.728114) (xy 281.080495 -19.763789) (xy 281.032889 -19.792843) (xy 280.98156 -19.814655)
			(xy 280.927603 -19.828761) (xy 280.872166 -19.834861) (xy 280.816432 -19.832824) (xy 280.761589 -19.822694)
			(xy 280.708805 -19.804687) (xy 280.659205 -19.779186) (xy 280.613847 -19.746735) (xy 280.573698 -19.708026)
			(xy 280.539612 -19.663883) (xy 280.512316 -19.615248) (xy 280.492393 -19.563157) (xy 280.480267 -19.50872)
			(xy 280.476196 -19.453098) (xy 274.976902 -19.453098) (xy 274.985523 -19.465637) (xy 275.010614 -19.517352)
			(xy 275.027663 -19.572246) (xy 275.036284 -19.629076) (xy 275.036281 -19.686556) (xy 275.027656 -19.743386)
			(xy 275.010602 -19.798278) (xy 274.985506 -19.849991) (xy 274.952937 -19.897353) (xy 274.933664 -19.91868)
			(xy 274.92706 -19.925538) (xy 274.919948 -19.943572) (xy 274.919948 -20.032472) (xy 274.92706 -20.050506)
			(xy 274.933664 -20.057364) (xy 274.952957 -20.078672) (xy 274.985523 -20.126037) (xy 275.010614 -20.177752)
			(xy 275.027663 -20.232646) (xy 275.036284 -20.289476) (xy 275.036281 -20.346956) (xy 275.027656 -20.403786)
			(xy 275.010602 -20.458678) (xy 275.006285 -20.467574) (xy 282.487368 -20.467574) (xy 282.491439 -20.411952)
			(xy 282.503565 -20.357515) (xy 282.523488 -20.305424) (xy 282.550784 -20.256789) (xy 282.58487 -20.212646)
			(xy 282.625019 -20.173937) (xy 282.670377 -20.141486) (xy 282.719977 -20.115985) (xy 282.772761 -20.097978)
			(xy 282.827604 -20.087848) (xy 282.883338 -20.085811) (xy 282.938775 -20.091911) (xy 282.992732 -20.106017)
			(xy 283.044061 -20.127829) (xy 283.091667 -20.156883) (xy 283.134535 -20.192558) (xy 283.171752 -20.234095)
			(xy 283.202525 -20.280608) (xy 283.226197 -20.331105) (xy 283.242265 -20.384512) (xy 283.250385 -20.439688)
			(xy 283.250894 -20.467574) (xy 283.250385 -20.49546) (xy 283.242265 -20.550636) (xy 283.226197 -20.604043)
			(xy 283.202525 -20.65454) (xy 283.171752 -20.701053) (xy 283.150179 -20.72513) (xy 289.380434 -20.72513)
			(xy 289.384404 -20.594996) (xy 289.3963 -20.465346) (xy 289.416079 -20.336663) (xy 289.443665 -20.209424)
			(xy 289.478958 -20.084105) (xy 289.521824 -19.961169) (xy 289.572106 -19.841076) (xy 289.629615 -19.724272)
			(xy 289.694139 -19.61119) (xy 289.765436 -19.502253) (xy 289.843241 -19.397865) (xy 289.927266 -19.298414)
			(xy 290.017198 -19.204271) (xy 290.112702 -19.115786) (xy 290.213422 -19.033287) (xy 290.318984 -18.957082)
			(xy 290.428996 -18.887455) (xy 290.543048 -18.824664) (xy 290.660716 -18.768942) (xy 290.781562 -18.720498)
			(xy 290.905137 -18.679511) (xy 291.03098 -18.646134) (xy 291.158625 -18.620491) (xy 291.287595 -18.602677)
			(xy 291.417411 -18.592759) (xy 291.54759 -18.590774) (xy 291.677649 -18.596728) (xy 291.807102 -18.610601)
			(xy 291.935469 -18.632339) (xy 292.062272 -18.661863) (xy 292.187039 -18.699062) (xy 292.309306 -18.743798)
			(xy 292.428619 -18.795906) (xy 292.544532 -18.855189) (xy 292.656617 -18.92143) (xy 292.764454 -18.99438)
			(xy 292.867643 -19.073768) (xy 292.965801 -19.1593) (xy 293.058562 -19.250657) (xy 293.145581 -19.347499)
			(xy 293.226534 -19.449466) (xy 293.30112 -19.556178) (xy 293.369061 -19.667239) (xy 293.430106 -19.782235)
			(xy 293.484027 -19.900739) (xy 293.530622 -20.02231) (xy 293.56972 -20.146495) (xy 293.601174 -20.272833)
			(xy 293.624868 -20.400854) (xy 293.640712 -20.53008) (xy 293.64865 -20.660033) (xy 293.649146 -20.72513)
			(xy 293.64865 -20.790227) (xy 293.640712 -20.92018) (xy 293.624868 -21.049406) (xy 293.601174 -21.177427)
			(xy 293.56972 -21.303765) (xy 293.530622 -21.42795) (xy 293.484027 -21.549521) (xy 293.443303 -21.639022)
			(xy 300.27372 -21.639022) (xy 300.274279 -21.610285) (xy 300.282896 -21.55346) (xy 300.299939 -21.49857)
			(xy 300.325022 -21.446858) (xy 300.357578 -21.399493) (xy 300.376844 -21.378164) (xy 300.383448 -21.371306)
			(xy 300.39056 -21.353272) (xy 300.39056 -21.264372) (xy 300.383448 -21.246338) (xy 300.376844 -21.23948)
			(xy 300.357594 -21.218135) (xy 300.325026 -21.170776) (xy 300.299932 -21.119067) (xy 300.28288 -21.064179)
			(xy 300.274255 -21.007354) (xy 300.274252 -20.949878) (xy 300.282873 -20.893052) (xy 300.299921 -20.838162)
			(xy 300.32501 -20.786452) (xy 300.357574 -20.73909) (xy 300.376844 -20.717764) (xy 300.383448 -20.710906)
			(xy 300.39056 -20.692872) (xy 300.39056 -20.603972) (xy 300.383448 -20.585938) (xy 300.376844 -20.57908)
			(xy 300.357594 -20.557735) (xy 300.325026 -20.510376) (xy 300.299932 -20.458667) (xy 300.28288 -20.403779)
			(xy 300.274255 -20.346954) (xy 300.274252 -20.289478) (xy 300.282873 -20.232652) (xy 300.299921 -20.177762)
			(xy 300.32501 -20.126052) (xy 300.357574 -20.07869) (xy 300.376844 -20.057364) (xy 300.383448 -20.050506)
			(xy 300.39056 -20.032472) (xy 300.39056 -19.943572) (xy 300.383448 -19.925538) (xy 300.376844 -19.91868)
			(xy 300.357594 -19.897335) (xy 300.325026 -19.849976) (xy 300.299932 -19.798267) (xy 300.28288 -19.743379)
			(xy 300.274255 -19.686554) (xy 300.274252 -19.629078) (xy 300.282873 -19.572252) (xy 300.299921 -19.517362)
			(xy 300.32501 -19.465652) (xy 300.357574 -19.41829) (xy 300.376844 -19.396964) (xy 300.383448 -19.390106)
			(xy 300.39056 -19.372072) (xy 300.39056 -19.283172) (xy 300.383448 -19.265138) (xy 300.376844 -19.25828)
			(xy 300.357585 -19.236943) (xy 300.325017 -19.189584) (xy 300.299922 -19.137875) (xy 300.282869 -19.082986)
			(xy 300.274243 -19.02616) (xy 300.27372 -18.997422) (xy 300.274206 -18.970171) (xy 300.281962 -18.916223)
			(xy 300.297317 -18.863928) (xy 300.319959 -18.814351) (xy 300.349425 -18.768501) (xy 300.385116 -18.72731)
			(xy 300.426307 -18.691619) (xy 300.472157 -18.662153) (xy 300.521734 -18.639511) (xy 300.574029 -18.624156)
			(xy 300.627977 -18.6164) (xy 300.682479 -18.6164) (xy 300.736427 -18.624156) (xy 300.788722 -18.639511)
			(xy 300.838299 -18.662153) (xy 300.884149 -18.691619) (xy 300.92534 -18.72731) (xy 300.961031 -18.768501)
			(xy 300.990497 -18.814351) (xy 301.013139 -18.863928) (xy 301.028494 -18.916223) (xy 301.03625 -18.970171)
			(xy 301.036736 -18.997422) (xy 301.036216 -19.026161) (xy 301.027591 -19.082988) (xy 301.01054 -19.137878)
			(xy 300.985447 -19.18959) (xy 300.952882 -19.236953) (xy 300.933612 -19.25828) (xy 300.927008 -19.265138)
			(xy 300.919896 -19.283172) (xy 300.919896 -19.372072) (xy 300.927008 -19.390106) (xy 300.933612 -19.396964)
			(xy 300.952903 -19.418273) (xy 300.976844 -19.453098) (xy 306.476144 -19.453098) (xy 306.480215 -19.397476)
			(xy 306.492341 -19.343039) (xy 306.512264 -19.290948) (xy 306.53956 -19.242313) (xy 306.573646 -19.19817)
			(xy 306.613795 -19.159461) (xy 306.659153 -19.12701) (xy 306.708753 -19.101509) (xy 306.761537 -19.083502)
			(xy 306.81638 -19.073372) (xy 306.872114 -19.071335) (xy 306.927551 -19.077435) (xy 306.981508 -19.091541)
			(xy 307.032837 -19.113353) (xy 307.080443 -19.142407) (xy 307.123311 -19.178082) (xy 307.160528 -19.219619)
			(xy 307.191301 -19.266132) (xy 307.214973 -19.316629) (xy 307.231041 -19.370036) (xy 307.239161 -19.425212)
			(xy 307.23967 -19.453098) (xy 307.239161 -19.480984) (xy 307.231041 -19.53616) (xy 307.214973 -19.589567)
			(xy 307.191301 -19.640064) (xy 307.160528 -19.686577) (xy 307.123311 -19.728114) (xy 307.080443 -19.763789)
			(xy 307.032837 -19.792843) (xy 306.981508 -19.814655) (xy 306.927551 -19.828761) (xy 306.872114 -19.834861)
			(xy 306.81638 -19.832824) (xy 306.761537 -19.822694) (xy 306.708753 -19.804687) (xy 306.659153 -19.779186)
			(xy 306.613795 -19.746735) (xy 306.573646 -19.708026) (xy 306.53956 -19.663883) (xy 306.512264 -19.615248)
			(xy 306.492341 -19.563157) (xy 306.480215 -19.50872) (xy 306.476144 -19.453098) (xy 300.976844 -19.453098)
			(xy 300.985465 -19.465639) (xy 301.010552 -19.517354) (xy 301.027599 -19.572247) (xy 301.036219 -19.629076)
			(xy 301.036216 -19.686556) (xy 301.027592 -19.743384) (xy 301.010541 -19.798276) (xy 300.985448 -19.849989)
			(xy 300.952883 -19.897352) (xy 300.933612 -19.91868) (xy 300.927008 -19.925538) (xy 300.919896 -19.943572)
			(xy 300.919896 -20.032472) (xy 300.927008 -20.050506) (xy 300.933612 -20.057364) (xy 300.952903 -20.078673)
			(xy 300.985465 -20.126039) (xy 301.010552 -20.177754) (xy 301.027599 -20.232647) (xy 301.036219 -20.289476)
			(xy 301.036216 -20.346956) (xy 301.027592 -20.403784) (xy 301.010541 -20.458676) (xy 301.006223 -20.467574)
			(xy 308.487316 -20.467574) (xy 308.491387 -20.411952) (xy 308.503513 -20.357515) (xy 308.523436 -20.305424)
			(xy 308.550732 -20.256789) (xy 308.584818 -20.212646) (xy 308.624967 -20.173937) (xy 308.670325 -20.141486)
			(xy 308.719925 -20.115985) (xy 308.772709 -20.097978) (xy 308.827552 -20.087848) (xy 308.883286 -20.085811)
			(xy 308.938723 -20.091911) (xy 308.99268 -20.106017) (xy 309.044009 -20.127829) (xy 309.091615 -20.156883)
			(xy 309.134483 -20.192558) (xy 309.1717 -20.234095) (xy 309.202473 -20.280608) (xy 309.226145 -20.331105)
			(xy 309.242213 -20.384512) (xy 309.250333 -20.439688) (xy 309.250842 -20.467574) (xy 309.250333 -20.49546)
			(xy 309.242213 -20.550636) (xy 309.226145 -20.604043) (xy 309.202473 -20.65454) (xy 309.1717 -20.701053)
			(xy 309.150127 -20.72513) (xy 315.380636 -20.72513) (xy 315.384606 -20.594996) (xy 315.396502 -20.465346)
			(xy 315.416281 -20.336663) (xy 315.443867 -20.209424) (xy 315.47916 -20.084105) (xy 315.522026 -19.961169)
			(xy 315.572308 -19.841076) (xy 315.629817 -19.724272) (xy 315.694341 -19.61119) (xy 315.765638 -19.502253)
			(xy 315.843443 -19.397865) (xy 315.927468 -19.298414) (xy 316.0174 -19.204271) (xy 316.112904 -19.115786)
			(xy 316.213624 -19.033287) (xy 316.319186 -18.957082) (xy 316.429198 -18.887455) (xy 316.54325 -18.824664)
			(xy 316.660918 -18.768942) (xy 316.781764 -18.720498) (xy 316.905339 -18.679511) (xy 317.031182 -18.646134)
			(xy 317.158827 -18.620491) (xy 317.287797 -18.602677) (xy 317.417613 -18.592759) (xy 317.547792 -18.590774)
			(xy 317.677851 -18.596728) (xy 317.807304 -18.610601) (xy 317.935671 -18.632339) (xy 318.062474 -18.661863)
			(xy 318.187241 -18.699062) (xy 318.309508 -18.743798) (xy 318.428821 -18.795906) (xy 318.544734 -18.855189)
			(xy 318.656819 -18.92143) (xy 318.764656 -18.99438) (xy 318.867845 -19.073768) (xy 318.966003 -19.1593)
			(xy 319.058764 -19.250657) (xy 319.145783 -19.347499) (xy 319.226736 -19.449466) (xy 319.301322 -19.556178)
			(xy 319.369263 -19.667239) (xy 319.430308 -19.782235) (xy 319.484229 -19.900739) (xy 319.530824 -20.02231)
			(xy 319.569922 -20.146495) (xy 319.601376 -20.272833) (xy 319.62507 -20.400854) (xy 319.640914 -20.53008)
			(xy 319.648852 -20.660033) (xy 319.649348 -20.72513) (xy 319.648852 -20.790227) (xy 319.640914 -20.92018)
			(xy 319.62507 -21.049406) (xy 319.601376 -21.177427) (xy 319.569922 -21.303765) (xy 319.530824 -21.42795)
			(xy 319.484229 -21.549521) (xy 319.430308 -21.668025) (xy 319.399051 -21.726906) (xy 326.273668 -21.726906)
			(xy 326.274204 -21.698168) (xy 326.282825 -21.641341) (xy 326.299873 -21.586451) (xy 326.324961 -21.534739)
			(xy 326.357523 -21.487376) (xy 326.376792 -21.466048) (xy 326.383396 -21.45919) (xy 326.390508 -21.441156)
			(xy 326.390508 -21.352256) (xy 326.383396 -21.334222) (xy 326.376792 -21.327364) (xy 326.357529 -21.306031)
			(xy 326.324966 -21.258669) (xy 326.299876 -21.206958) (xy 326.282827 -21.152068) (xy 326.274205 -21.095243)
			(xy 326.274204 -21.037766) (xy 326.282825 -20.98094) (xy 326.299873 -20.92605) (xy 326.324961 -20.874339)
			(xy 326.357523 -20.826975) (xy 326.376792 -20.805648) (xy 326.383396 -20.79879) (xy 326.390508 -20.780756)
			(xy 326.390508 -20.691856) (xy 326.383396 -20.673822) (xy 326.376792 -20.666964) (xy 326.357529 -20.645631)
			(xy 326.324966 -20.598269) (xy 326.299876 -20.546558) (xy 326.282827 -20.491668) (xy 326.274205 -20.434843)
			(xy 326.274204 -20.377366) (xy 326.282825 -20.32054) (xy 326.299873 -20.26565) (xy 326.324961 -20.213939)
			(xy 326.357523 -20.166575) (xy 326.376792 -20.145248) (xy 326.383396 -20.13839) (xy 326.390508 -20.120356)
			(xy 326.390508 -20.031456) (xy 326.383396 -20.013422) (xy 326.376792 -20.006564) (xy 326.357529 -19.985231)
			(xy 326.324966 -19.937869) (xy 326.299876 -19.886158) (xy 326.282827 -19.831268) (xy 326.274205 -19.774443)
			(xy 326.274204 -19.716966) (xy 326.282825 -19.66014) (xy 326.299873 -19.60525) (xy 326.324961 -19.553539)
			(xy 326.357523 -19.506175) (xy 326.376792 -19.484848) (xy 326.383396 -19.47799) (xy 326.390508 -19.459956)
			(xy 326.390508 -19.371056) (xy 326.383396 -19.353022) (xy 326.376792 -19.346164) (xy 326.357533 -19.324826)
			(xy 326.324964 -19.277468) (xy 326.299868 -19.225759) (xy 326.282815 -19.170871) (xy 326.27419 -19.114044)
			(xy 326.273668 -19.085306) (xy 326.274154 -19.058055) (xy 326.28191 -19.004107) (xy 326.297265 -18.951812)
			(xy 326.319907 -18.902235) (xy 326.349373 -18.856385) (xy 326.385064 -18.815194) (xy 326.426255 -18.779503)
			(xy 326.472105 -18.750037) (xy 326.521682 -18.727395) (xy 326.573977 -18.71204) (xy 326.627925 -18.704284)
			(xy 326.682427 -18.704284) (xy 326.736375 -18.71204) (xy 326.78867 -18.727395) (xy 326.838247 -18.750037)
			(xy 326.884097 -18.779503) (xy 326.925288 -18.815194) (xy 326.960979 -18.856385) (xy 326.990445 -18.902235)
			(xy 327.013087 -18.951812) (xy 327.028442 -19.004107) (xy 327.036198 -19.058055) (xy 327.036684 -19.085306)
			(xy 327.036141 -19.114044) (xy 327.02752 -19.170869) (xy 327.010473 -19.225759) (xy 326.985386 -19.277471)
			(xy 326.952827 -19.324835) (xy 326.93356 -19.346164) (xy 326.926956 -19.353022) (xy 326.919844 -19.371056)
			(xy 326.919844 -19.459956) (xy 326.926956 -19.47799) (xy 326.93356 -19.484848) (xy 326.952837 -19.506169)
			(xy 326.985404 -19.553532) (xy 327.010496 -19.605245) (xy 327.027547 -19.660137) (xy 327.036169 -19.716965)
			(xy 327.036168 -19.774444) (xy 327.027545 -19.831272) (xy 327.010493 -19.886163) (xy 326.985399 -19.937875)
			(xy 326.952832 -19.985238) (xy 326.93356 -20.006564) (xy 326.926956 -20.013422) (xy 326.919844 -20.031456)
			(xy 326.919844 -20.120356) (xy 326.926956 -20.13839) (xy 326.93356 -20.145248) (xy 326.952837 -20.166569)
			(xy 326.985404 -20.213932) (xy 327.010496 -20.265645) (xy 327.027547 -20.320537) (xy 327.036169 -20.377365)
			(xy 327.036168 -20.434844) (xy 327.027545 -20.491672) (xy 327.010493 -20.546563) (xy 326.985399 -20.598275)
			(xy 326.952832 -20.645638) (xy 326.93356 -20.666964) (xy 326.926956 -20.673822) (xy 326.919844 -20.691856)
			(xy 326.919844 -20.72513) (xy 353.480636 -20.72513) (xy 353.484606 -20.594996) (xy 353.496502 -20.465346)
			(xy 353.516281 -20.336663) (xy 353.543867 -20.209424) (xy 353.57916 -20.084105) (xy 353.622026 -19.961169)
			(xy 353.672308 -19.841076) (xy 353.729817 -19.724272) (xy 353.794341 -19.61119) (xy 353.865638 -19.502253)
			(xy 353.943443 -19.397865) (xy 354.027468 -19.298414) (xy 354.1174 -19.204271) (xy 354.212904 -19.115786)
			(xy 354.313624 -19.033287) (xy 354.419186 -18.957082) (xy 354.529198 -18.887455) (xy 354.64325 -18.824664)
			(xy 354.760918 -18.768942) (xy 354.881764 -18.720498) (xy 355.005339 -18.679511) (xy 355.131182 -18.646134)
			(xy 355.258827 -18.620491) (xy 355.387797 -18.602677) (xy 355.517613 -18.592759) (xy 355.647792 -18.590774)
			(xy 355.777851 -18.596728) (xy 355.907304 -18.610601) (xy 356.035671 -18.632339) (xy 356.162474 -18.661863)
			(xy 356.287241 -18.699062) (xy 356.409508 -18.743798) (xy 356.528821 -18.795906) (xy 356.644734 -18.855189)
			(xy 356.756819 -18.92143) (xy 356.864656 -18.99438) (xy 356.967845 -19.073768) (xy 357.066003 -19.1593)
			(xy 357.158764 -19.250657) (xy 357.245783 -19.347499) (xy 357.326736 -19.449466) (xy 357.401322 -19.556178)
			(xy 357.469263 -19.667239) (xy 357.530308 -19.782235) (xy 357.584229 -19.900739) (xy 357.630824 -20.02231)
			(xy 357.669922 -20.146495) (xy 357.701376 -20.272833) (xy 357.72507 -20.400854) (xy 357.740914 -20.53008)
			(xy 357.748852 -20.660033) (xy 357.749348 -20.72513) (xy 357.748852 -20.790227) (xy 357.740914 -20.92018)
			(xy 357.72507 -21.049406) (xy 357.701376 -21.177427) (xy 357.669922 -21.303765) (xy 357.630824 -21.42795)
			(xy 357.584229 -21.549521) (xy 357.543505 -21.639022) (xy 364.373922 -21.639022) (xy 364.37448 -21.610285)
			(xy 364.383097 -21.55346) (xy 364.400141 -21.49857) (xy 364.425224 -21.446858) (xy 364.45778 -21.399493)
			(xy 364.477046 -21.378164) (xy 364.48365 -21.371306) (xy 364.490762 -21.353272) (xy 364.490762 -21.264372)
			(xy 364.48365 -21.246338) (xy 364.477046 -21.23948) (xy 364.457796 -21.218135) (xy 364.425228 -21.170776)
			(xy 364.400134 -21.119068) (xy 364.383081 -21.064179) (xy 364.374456 -21.007354) (xy 364.374454 -20.949878)
			(xy 364.383074 -20.893052) (xy 364.400122 -20.838162) (xy 364.425212 -20.786452) (xy 364.457776 -20.73909)
			(xy 364.477046 -20.717764) (xy 364.48365 -20.710906) (xy 364.490762 -20.692872) (xy 364.490762 -20.603972)
			(xy 364.48365 -20.585938) (xy 364.477046 -20.57908) (xy 364.457796 -20.557735) (xy 364.425228 -20.510376)
			(xy 364.400134 -20.458668) (xy 364.383081 -20.403779) (xy 364.374456 -20.346954) (xy 364.374454 -20.289478)
			(xy 364.383074 -20.232652) (xy 364.400122 -20.177762) (xy 364.425212 -20.126052) (xy 364.457776 -20.07869)
			(xy 364.477046 -20.057364) (xy 364.48365 -20.050506) (xy 364.490762 -20.032472) (xy 364.490762 -19.943572)
			(xy 364.48365 -19.925538) (xy 364.477046 -19.91868) (xy 364.457796 -19.897335) (xy 364.425228 -19.849976)
			(xy 364.400134 -19.798268) (xy 364.383081 -19.743379) (xy 364.374456 -19.686554) (xy 364.374454 -19.629078)
			(xy 364.383074 -19.572252) (xy 364.400122 -19.517362) (xy 364.425212 -19.465652) (xy 364.457776 -19.41829)
			(xy 364.477046 -19.396964) (xy 364.48365 -19.390106) (xy 364.490762 -19.372072) (xy 364.490762 -19.283172)
			(xy 364.48365 -19.265138) (xy 364.477046 -19.25828) (xy 364.457787 -19.236943) (xy 364.425219 -19.189584)
			(xy 364.400124 -19.137875) (xy 364.383071 -19.082986) (xy 364.374445 -19.02616) (xy 364.373922 -18.997422)
			(xy 364.374408 -18.970171) (xy 364.382164 -18.916223) (xy 364.397519 -18.863928) (xy 364.420161 -18.814351)
			(xy 364.449627 -18.768501) (xy 364.485318 -18.72731) (xy 364.526509 -18.691619) (xy 364.572359 -18.662153)
			(xy 364.621936 -18.639511) (xy 364.674231 -18.624156) (xy 364.728179 -18.6164) (xy 364.782681 -18.6164)
			(xy 364.836629 -18.624156) (xy 364.888924 -18.639511) (xy 364.938501 -18.662153) (xy 364.984351 -18.691619)
			(xy 365.025542 -18.72731) (xy 365.061233 -18.768501) (xy 365.090699 -18.814351) (xy 365.113341 -18.863928)
			(xy 365.128696 -18.916223) (xy 365.136452 -18.970171) (xy 365.136938 -18.997422) (xy 365.136417 -19.026161)
			(xy 365.127793 -19.082988) (xy 365.110741 -19.137878) (xy 365.085649 -19.18959) (xy 365.053084 -19.236953)
			(xy 365.033814 -19.25828) (xy 365.02721 -19.265138) (xy 365.020098 -19.283172) (xy 365.020098 -19.372072)
			(xy 365.02721 -19.390106) (xy 365.033814 -19.396964) (xy 365.053105 -19.418273) (xy 365.077045 -19.453098)
			(xy 370.576346 -19.453098) (xy 370.580417 -19.397476) (xy 370.592543 -19.343039) (xy 370.612466 -19.290948)
			(xy 370.639762 -19.242313) (xy 370.673848 -19.19817) (xy 370.713997 -19.159461) (xy 370.759355 -19.12701)
			(xy 370.808955 -19.101509) (xy 370.861739 -19.083502) (xy 370.916582 -19.073372) (xy 370.972316 -19.071335)
			(xy 371.027753 -19.077435) (xy 371.08171 -19.091541) (xy 371.133039 -19.113353) (xy 371.180645 -19.142407)
			(xy 371.223513 -19.178082) (xy 371.26073 -19.219619) (xy 371.291503 -19.266132) (xy 371.315175 -19.316629)
			(xy 371.331243 -19.370036) (xy 371.339363 -19.425212) (xy 371.339872 -19.453098) (xy 371.339363 -19.480984)
			(xy 371.331243 -19.53616) (xy 371.315175 -19.589567) (xy 371.291503 -19.640064) (xy 371.26073 -19.686577)
			(xy 371.223513 -19.728114) (xy 371.180645 -19.763789) (xy 371.133039 -19.792843) (xy 371.08171 -19.814655)
			(xy 371.027753 -19.828761) (xy 370.972316 -19.834861) (xy 370.916582 -19.832824) (xy 370.861739 -19.822694)
			(xy 370.808955 -19.804687) (xy 370.759355 -19.779186) (xy 370.713997 -19.746735) (xy 370.673848 -19.708026)
			(xy 370.639762 -19.663883) (xy 370.612466 -19.615248) (xy 370.592543 -19.563157) (xy 370.580417 -19.50872)
			(xy 370.576346 -19.453098) (xy 365.077045 -19.453098) (xy 365.085666 -19.465639) (xy 365.110754 -19.517354)
			(xy 365.127801 -19.572247) (xy 365.13642 -19.629077) (xy 365.136418 -19.686556) (xy 365.127793 -19.743384)
			(xy 365.110742 -19.798276) (xy 365.08565 -19.849988) (xy 365.053085 -19.897352) (xy 365.033814 -19.91868)
			(xy 365.02721 -19.925538) (xy 365.020098 -19.943572) (xy 365.020098 -20.032472) (xy 365.02721 -20.050506)
			(xy 365.033814 -20.057364) (xy 365.053105 -20.078673) (xy 365.085666 -20.126039) (xy 365.110754 -20.177754)
			(xy 365.127801 -20.232647) (xy 365.13642 -20.289477) (xy 365.136418 -20.346956) (xy 365.127793 -20.403784)
			(xy 365.110742 -20.458676) (xy 365.106424 -20.467574) (xy 372.587518 -20.467574) (xy 372.591589 -20.411952)
			(xy 372.603715 -20.357515) (xy 372.623638 -20.305424) (xy 372.650934 -20.256789) (xy 372.68502 -20.212646)
			(xy 372.725169 -20.173937) (xy 372.770527 -20.141486) (xy 372.820127 -20.115985) (xy 372.872911 -20.097978)
			(xy 372.927754 -20.087848) (xy 372.983488 -20.085811) (xy 373.038925 -20.091911) (xy 373.092882 -20.106017)
			(xy 373.144211 -20.127829) (xy 373.191817 -20.156883) (xy 373.234685 -20.192558) (xy 373.271902 -20.234095)
			(xy 373.302675 -20.280608) (xy 373.326347 -20.331105) (xy 373.342415 -20.384512) (xy 373.350535 -20.439688)
			(xy 373.351044 -20.467574) (xy 373.350535 -20.49546) (xy 373.342415 -20.550636) (xy 373.326347 -20.604043)
			(xy 373.302675 -20.65454) (xy 373.271902 -20.701053) (xy 373.254881 -20.72005) (xy 379.48541 -20.72005)
			(xy 379.48938 -20.589916) (xy 379.501276 -20.460266) (xy 379.521055 -20.331583) (xy 379.548641 -20.204344)
			(xy 379.583934 -20.079025) (xy 379.6268 -19.956089) (xy 379.677082 -19.835996) (xy 379.734591 -19.719192)
			(xy 379.799115 -19.60611) (xy 379.870412 -19.497173) (xy 379.948217 -19.392785) (xy 380.032242 -19.293334)
			(xy 380.122174 -19.199191) (xy 380.217678 -19.110706) (xy 380.318398 -19.028207) (xy 380.42396 -18.952002)
			(xy 380.533972 -18.882375) (xy 380.648024 -18.819584) (xy 380.765692 -18.763862) (xy 380.886538 -18.715418)
			(xy 381.010113 -18.674431) (xy 381.135956 -18.641054) (xy 381.263601 -18.615411) (xy 381.392571 -18.597597)
			(xy 381.522387 -18.587679) (xy 381.652566 -18.585694) (xy 381.782625 -18.591648) (xy 381.912078 -18.605521)
			(xy 382.040445 -18.627259) (xy 382.167248 -18.656783) (xy 382.292015 -18.693982) (xy 382.414282 -18.738718)
			(xy 382.533595 -18.790826) (xy 382.649508 -18.850109) (xy 382.761593 -18.91635) (xy 382.86943 -18.9893)
			(xy 382.972619 -19.068688) (xy 383.070777 -19.15422) (xy 383.163538 -19.245577) (xy 383.250557 -19.342419)
			(xy 383.33151 -19.444386) (xy 383.406096 -19.551098) (xy 383.474037 -19.662159) (xy 383.535082 -19.777155)
			(xy 383.589003 -19.895659) (xy 383.635598 -20.01723) (xy 383.674696 -20.141415) (xy 383.70615 -20.267753)
			(xy 383.729844 -20.395774) (xy 383.745688 -20.525) (xy 383.753626 -20.654953) (xy 383.754122 -20.72005)
			(xy 383.753626 -20.785147) (xy 383.745688 -20.9151) (xy 383.729844 -21.044326) (xy 383.70615 -21.172347)
			(xy 383.674696 -21.298685) (xy 383.635598 -21.42287) (xy 383.589003 -21.544441) (xy 383.535082 -21.662945)
			(xy 383.501129 -21.726906) (xy 390.37387 -21.726906) (xy 390.374405 -21.698168) (xy 390.383026 -21.641341)
			(xy 390.400074 -21.586451) (xy 390.425163 -21.534739) (xy 390.457725 -21.487376) (xy 390.476994 -21.466048)
			(xy 390.483598 -21.45919) (xy 390.49071 -21.441156) (xy 390.49071 -21.352256) (xy 390.483598 -21.334222)
			(xy 390.476994 -21.327364) (xy 390.45773 -21.306031) (xy 390.425168 -21.258669) (xy 390.400078 -21.206958)
			(xy 390.383029 -21.152068) (xy 390.374406 -21.095243) (xy 390.374406 -21.037766) (xy 390.383027 -20.98094)
			(xy 390.400074 -20.92605) (xy 390.425163 -20.874339) (xy 390.457725 -20.826975) (xy 390.476994 -20.805648)
			(xy 390.483598 -20.79879) (xy 390.49071 -20.780756) (xy 390.49071 -20.691856) (xy 390.483598 -20.673822)
			(xy 390.476994 -20.666964) (xy 390.45773 -20.645631) (xy 390.425168 -20.598269) (xy 390.400078 -20.546558)
			(xy 390.383029 -20.491668) (xy 390.374406 -20.434843) (xy 390.374406 -20.377366) (xy 390.383027 -20.32054)
			(xy 390.400074 -20.26565) (xy 390.425163 -20.213939) (xy 390.457725 -20.166575) (xy 390.476994 -20.145248)
			(xy 390.483598 -20.13839) (xy 390.49071 -20.120356) (xy 390.49071 -20.031456) (xy 390.483598 -20.013422)
			(xy 390.476994 -20.006564) (xy 390.45773 -19.985231) (xy 390.425168 -19.937869) (xy 390.400078 -19.886158)
			(xy 390.383029 -19.831268) (xy 390.374406 -19.774443) (xy 390.374406 -19.716966) (xy 390.383027 -19.66014)
			(xy 390.400074 -19.60525) (xy 390.425163 -19.553539) (xy 390.457725 -19.506175) (xy 390.476994 -19.484848)
			(xy 390.483598 -19.47799) (xy 390.49071 -19.459956) (xy 390.49071 -19.371056) (xy 390.483598 -19.353022)
			(xy 390.476994 -19.346164) (xy 390.457736 -19.324826) (xy 390.425166 -19.277468) (xy 390.40007 -19.225759)
			(xy 390.383017 -19.17087) (xy 390.374392 -19.114044) (xy 390.37387 -19.085306) (xy 390.374356 -19.058055)
			(xy 390.382112 -19.004107) (xy 390.397467 -18.951812) (xy 390.420109 -18.902235) (xy 390.449575 -18.856385)
			(xy 390.485266 -18.815194) (xy 390.526457 -18.779503) (xy 390.572307 -18.750037) (xy 390.621884 -18.727395)
			(xy 390.674179 -18.71204) (xy 390.728127 -18.704284) (xy 390.782629 -18.704284) (xy 390.836577 -18.71204)
			(xy 390.888872 -18.727395) (xy 390.938449 -18.750037) (xy 390.984299 -18.779503) (xy 391.02549 -18.815194)
			(xy 391.061181 -18.856385) (xy 391.090647 -18.902235) (xy 391.113289 -18.951812) (xy 391.128644 -19.004107)
			(xy 391.1364 -19.058055) (xy 391.136886 -19.085306) (xy 391.136343 -19.114044) (xy 391.127722 -19.170869)
			(xy 391.110675 -19.225759) (xy 391.085588 -19.277471) (xy 391.053029 -19.324835) (xy 391.033762 -19.346164)
			(xy 391.027158 -19.353022) (xy 391.020046 -19.371056) (xy 391.020046 -19.453098) (xy 396.576294 -19.453098)
			(xy 396.580365 -19.397476) (xy 396.592491 -19.343039) (xy 396.612414 -19.290948) (xy 396.63971 -19.242313)
			(xy 396.673796 -19.19817) (xy 396.713945 -19.159461) (xy 396.759303 -19.12701) (xy 396.808903 -19.101509)
			(xy 396.861687 -19.083502) (xy 396.91653 -19.073372) (xy 396.972264 -19.071335) (xy 397.027701 -19.077435)
			(xy 397.081658 -19.091541) (xy 397.132987 -19.113353) (xy 397.180593 -19.142407) (xy 397.223461 -19.178082)
			(xy 397.260678 -19.219619) (xy 397.291451 -19.266132) (xy 397.315123 -19.316629) (xy 397.331191 -19.370036)
			(xy 397.339311 -19.425212) (xy 397.33982 -19.453098) (xy 397.339311 -19.480984) (xy 397.331191 -19.53616)
			(xy 397.315123 -19.589567) (xy 397.291451 -19.640064) (xy 397.260678 -19.686577) (xy 397.223461 -19.728114)
			(xy 397.180593 -19.763789) (xy 397.132987 -19.792843) (xy 397.081658 -19.814655) (xy 397.027701 -19.828761)
			(xy 396.972264 -19.834861) (xy 396.91653 -19.832824) (xy 396.861687 -19.822694) (xy 396.808903 -19.804687)
			(xy 396.759303 -19.779186) (xy 396.713945 -19.746735) (xy 396.673796 -19.708026) (xy 396.63971 -19.663883)
			(xy 396.612414 -19.615248) (xy 396.592491 -19.563157) (xy 396.580365 -19.50872) (xy 396.576294 -19.453098)
			(xy 391.020046 -19.453098) (xy 391.020046 -19.459956) (xy 391.027158 -19.47799) (xy 391.033762 -19.484848)
			(xy 391.053039 -19.506169) (xy 391.085606 -19.553532) (xy 391.110698 -19.605245) (xy 391.127748 -19.660137)
			(xy 391.13637 -19.716965) (xy 391.13637 -19.774444) (xy 391.127746 -19.831272) (xy 391.110695 -19.886163)
			(xy 391.085601 -19.937875) (xy 391.053034 -19.985238) (xy 391.033762 -20.006564) (xy 391.027158 -20.013422)
			(xy 391.020046 -20.031456) (xy 391.020046 -20.120356) (xy 391.027158 -20.13839) (xy 391.033762 -20.145248)
			(xy 391.053039 -20.166569) (xy 391.085606 -20.213932) (xy 391.110698 -20.265645) (xy 391.127748 -20.320537)
			(xy 391.13637 -20.377365) (xy 391.13637 -20.434844) (xy 391.131403 -20.467574) (xy 398.587466 -20.467574)
			(xy 398.591537 -20.411952) (xy 398.603663 -20.357515) (xy 398.623586 -20.305424) (xy 398.650882 -20.256789)
			(xy 398.684968 -20.212646) (xy 398.725117 -20.173937) (xy 398.770475 -20.141486) (xy 398.820075 -20.115985)
			(xy 398.872859 -20.097978) (xy 398.927702 -20.087848) (xy 398.983436 -20.085811) (xy 399.038873 -20.091911)
			(xy 399.09283 -20.106017) (xy 399.144159 -20.127829) (xy 399.191765 -20.156883) (xy 399.234633 -20.192558)
			(xy 399.27185 -20.234095) (xy 399.302623 -20.280608) (xy 399.326295 -20.331105) (xy 399.342363 -20.384512)
			(xy 399.350483 -20.439688) (xy 399.350992 -20.467574) (xy 399.350483 -20.49546) (xy 399.342363 -20.550636)
			(xy 399.326295 -20.604043) (xy 399.302623 -20.65454) (xy 399.27185 -20.701053) (xy 399.250277 -20.72513)
			(xy 405.480532 -20.72513) (xy 405.484502 -20.594996) (xy 405.496398 -20.465346) (xy 405.516177 -20.336663)
			(xy 405.543763 -20.209424) (xy 405.579056 -20.084105) (xy 405.621922 -19.961169) (xy 405.672204 -19.841076)
			(xy 405.729713 -19.724272) (xy 405.794237 -19.61119) (xy 405.865534 -19.502253) (xy 405.943339 -19.397865)
			(xy 406.027364 -19.298414) (xy 406.117296 -19.204271) (xy 406.2128 -19.115786) (xy 406.31352 -19.033287)
			(xy 406.419082 -18.957082) (xy 406.529094 -18.887455) (xy 406.643146 -18.824664) (xy 406.760814 -18.768942)
			(xy 406.88166 -18.720498) (xy 407.005235 -18.679511) (xy 407.131078 -18.646134) (xy 407.258723 -18.620491)
			(xy 407.387693 -18.602677) (xy 407.517509 -18.592759) (xy 407.647688 -18.590774) (xy 407.777747 -18.596728)
			(xy 407.9072 -18.610601) (xy 408.035567 -18.632339) (xy 408.16237 -18.661863) (xy 408.287137 -18.699062)
			(xy 408.409404 -18.743798) (xy 408.528717 -18.795906) (xy 408.64463 -18.855189) (xy 408.756715 -18.92143)
			(xy 408.864552 -18.99438) (xy 408.967741 -19.073768) (xy 409.065899 -19.1593) (xy 409.15866 -19.250657)
			(xy 409.245679 -19.347499) (xy 409.326632 -19.449466) (xy 409.401218 -19.556178) (xy 409.469159 -19.667239)
			(xy 409.530204 -19.782235) (xy 409.584125 -19.900739) (xy 409.63072 -20.02231) (xy 409.669818 -20.146495)
			(xy 409.701272 -20.272833) (xy 409.724966 -20.400854) (xy 409.74081 -20.53008) (xy 409.748748 -20.660033)
			(xy 409.749244 -20.72513) (xy 409.748748 -20.790227) (xy 409.74081 -20.92018) (xy 409.724966 -21.049406)
			(xy 409.701272 -21.177427) (xy 409.669818 -21.303765) (xy 409.63072 -21.42795) (xy 409.584125 -21.549521)
			(xy 409.530204 -21.668025) (xy 409.498947 -21.726906) (xy 416.373818 -21.726906) (xy 416.374367 -21.698168)
			(xy 416.382987 -21.641343) (xy 416.400032 -21.586453) (xy 416.425118 -21.534741) (xy 416.457675 -21.487377)
			(xy 416.476942 -21.466048) (xy 416.483546 -21.45919) (xy 416.490658 -21.441156) (xy 416.490658 -21.352256)
			(xy 416.483546 -21.334222) (xy 416.476942 -21.327364) (xy 416.457676 -21.306032) (xy 416.425109 -21.258671)
			(xy 416.400016 -21.20696) (xy 416.382965 -21.15207) (xy 416.374341 -21.095243) (xy 416.374341 -21.037766)
			(xy 416.382963 -20.980938) (xy 416.400013 -20.926048) (xy 416.425105 -20.874336) (xy 416.457671 -20.826974)
			(xy 416.476942 -20.805648) (xy 416.483546 -20.79879) (xy 416.490658 -20.780756) (xy 416.490658 -20.691856)
			(xy 416.483546 -20.673822) (xy 416.476942 -20.666964) (xy 416.457676 -20.645632) (xy 416.425109 -20.598271)
			(xy 416.400016 -20.54656) (xy 416.382965 -20.49167) (xy 416.374341 -20.434843) (xy 416.374341 -20.377366)
			(xy 416.382963 -20.320538) (xy 416.400013 -20.265648) (xy 416.425105 -20.213936) (xy 416.457671 -20.166574)
			(xy 416.476942 -20.145248) (xy 416.483546 -20.13839) (xy 416.490658 -20.120356) (xy 416.490658 -20.031456)
			(xy 416.483546 -20.013422) (xy 416.476942 -20.006564) (xy 416.457676 -19.985232) (xy 416.425109 -19.937871)
			(xy 416.400016 -19.88616) (xy 416.382965 -19.83127) (xy 416.374341 -19.774443) (xy 416.374341 -19.716966)
			(xy 416.382963 -19.660138) (xy 416.400013 -19.605248) (xy 416.425105 -19.553536) (xy 416.457671 -19.506174)
			(xy 416.476942 -19.484848) (xy 416.483546 -19.47799) (xy 416.490658 -19.459956) (xy 416.490658 -19.371056)
			(xy 416.483546 -19.353022) (xy 416.476942 -19.346164) (xy 416.457675 -19.324834) (xy 416.425108 -19.277473)
			(xy 416.400015 -19.225762) (xy 416.382963 -19.170872) (xy 416.374339 -19.114045) (xy 416.373818 -19.085306)
			(xy 416.374304 -19.058055) (xy 416.38206 -19.004107) (xy 416.397415 -18.951812) (xy 416.420057 -18.902235)
			(xy 416.449523 -18.856385) (xy 416.485214 -18.815194) (xy 416.526405 -18.779503) (xy 416.572255 -18.750037)
			(xy 416.621832 -18.727395) (xy 416.674127 -18.71204) (xy 416.728075 -18.704284) (xy 416.782577 -18.704284)
			(xy 416.836525 -18.71204) (xy 416.88882 -18.727395) (xy 416.938397 -18.750037) (xy 416.984247 -18.779503)
			(xy 417.025438 -18.815194) (xy 417.061129 -18.856385) (xy 417.090595 -18.902235) (xy 417.113237 -18.951812)
			(xy 417.128592 -19.004107) (xy 417.136348 -19.058055) (xy 417.136834 -19.085306) (xy 417.136305 -19.114045)
			(xy 417.127682 -19.170871) (xy 417.110633 -19.225762) (xy 417.085543 -19.277473) (xy 417.05298 -19.324837)
			(xy 417.03371 -19.346164) (xy 417.027106 -19.353022) (xy 417.019994 -19.371056) (xy 417.019994 -19.453098)
			(xy 422.576242 -19.453098) (xy 422.580313 -19.397476) (xy 422.592439 -19.343039) (xy 422.612362 -19.290948)
			(xy 422.639658 -19.242313) (xy 422.673744 -19.19817) (xy 422.713893 -19.159461) (xy 422.759251 -19.12701)
			(xy 422.808851 -19.101509) (xy 422.861635 -19.083502) (xy 422.916478 -19.073372) (xy 422.972212 -19.071335)
			(xy 423.027649 -19.077435) (xy 423.081606 -19.091541) (xy 423.132935 -19.113353) (xy 423.180541 -19.142407)
			(xy 423.223409 -19.178082) (xy 423.260626 -19.219619) (xy 423.291399 -19.266132) (xy 423.315071 -19.316629)
			(xy 423.331139 -19.370036) (xy 423.339259 -19.425212) (xy 423.339768 -19.453098) (xy 423.339259 -19.480984)
			(xy 423.331139 -19.53616) (xy 423.315071 -19.589567) (xy 423.291399 -19.640064) (xy 423.260626 -19.686577)
			(xy 423.223409 -19.728114) (xy 423.180541 -19.763789) (xy 423.132935 -19.792843) (xy 423.081606 -19.814655)
			(xy 423.027649 -19.828761) (xy 422.972212 -19.834861) (xy 422.916478 -19.832824) (xy 422.861635 -19.822694)
			(xy 422.808851 -19.804687) (xy 422.759251 -19.779186) (xy 422.713893 -19.746735) (xy 422.673744 -19.708026)
			(xy 422.639658 -19.663883) (xy 422.612362 -19.615248) (xy 422.592439 -19.563157) (xy 422.580313 -19.50872)
			(xy 422.576242 -19.453098) (xy 417.019994 -19.453098) (xy 417.019994 -19.459956) (xy 417.027106 -19.47799)
			(xy 417.03371 -19.484848) (xy 417.052985 -19.50617) (xy 417.085547 -19.553535) (xy 417.110636 -19.605247)
			(xy 417.127684 -19.660138) (xy 417.136306 -19.716966) (xy 417.136305 -19.774443) (xy 417.127682 -19.83127)
			(xy 417.110633 -19.886161) (xy 417.085543 -19.937873) (xy 417.05298 -19.985236) (xy 417.03371 -20.006564)
			(xy 417.027106 -20.013422) (xy 417.019994 -20.031456) (xy 417.019994 -20.120356) (xy 417.027106 -20.13839)
			(xy 417.03371 -20.145248) (xy 417.052985 -20.16657) (xy 417.085547 -20.213935) (xy 417.110636 -20.265647)
			(xy 417.127684 -20.320538) (xy 417.136306 -20.377366) (xy 417.136305 -20.434843) (xy 417.131338 -20.467574)
			(xy 424.587414 -20.467574) (xy 424.591485 -20.411952) (xy 424.603611 -20.357515) (xy 424.623534 -20.305424)
			(xy 424.65083 -20.256789) (xy 424.684916 -20.212646) (xy 424.725065 -20.173937) (xy 424.770423 -20.141486)
			(xy 424.820023 -20.115985) (xy 424.872807 -20.097978) (xy 424.92765 -20.087848) (xy 424.983384 -20.085811)
			(xy 425.038821 -20.091911) (xy 425.092778 -20.106017) (xy 425.144107 -20.127829) (xy 425.191713 -20.156883)
			(xy 425.234581 -20.192558) (xy 425.271798 -20.234095) (xy 425.302571 -20.280608) (xy 425.326243 -20.331105)
			(xy 425.342311 -20.384512) (xy 425.350431 -20.439688) (xy 425.35094 -20.467574) (xy 425.350431 -20.49546)
			(xy 425.342311 -20.550636) (xy 425.326243 -20.604043) (xy 425.302571 -20.65454) (xy 425.271798 -20.701053)
			(xy 425.250225 -20.72513) (xy 431.48048 -20.72513) (xy 431.48445 -20.594996) (xy 431.496346 -20.465346)
			(xy 431.516125 -20.336663) (xy 431.543711 -20.209424) (xy 431.579004 -20.084105) (xy 431.62187 -19.961169)
			(xy 431.672152 -19.841076) (xy 431.729661 -19.724272) (xy 431.794185 -19.61119) (xy 431.865482 -19.502253)
			(xy 431.943287 -19.397865) (xy 432.027312 -19.298414) (xy 432.117244 -19.204271) (xy 432.212748 -19.115786)
			(xy 432.313468 -19.033287) (xy 432.41903 -18.957082) (xy 432.529042 -18.887455) (xy 432.643094 -18.824664)
			(xy 432.760762 -18.768942) (xy 432.881608 -18.720498) (xy 433.005183 -18.679511) (xy 433.131026 -18.646134)
			(xy 433.258671 -18.620491) (xy 433.387641 -18.602677) (xy 433.517457 -18.592759) (xy 433.647636 -18.590774)
			(xy 433.777695 -18.596728) (xy 433.907148 -18.610601) (xy 434.035515 -18.632339) (xy 434.162318 -18.661863)
			(xy 434.287085 -18.699062) (xy 434.409352 -18.743798) (xy 434.528665 -18.795906) (xy 434.644578 -18.855189)
			(xy 434.756663 -18.92143) (xy 434.8645 -18.99438) (xy 434.967689 -19.073768) (xy 435.065847 -19.1593)
			(xy 435.158608 -19.250657) (xy 435.245627 -19.347499) (xy 435.32658 -19.449466) (xy 435.401166 -19.556178)
			(xy 435.469107 -19.667239) (xy 435.530152 -19.782235) (xy 435.584073 -19.900739) (xy 435.630668 -20.02231)
			(xy 435.669766 -20.146495) (xy 435.70122 -20.272833) (xy 435.724914 -20.400854) (xy 435.740758 -20.53008)
			(xy 435.748696 -20.660033) (xy 435.749192 -20.72513) (xy 435.748696 -20.790227) (xy 435.740758 -20.92018)
			(xy 435.724914 -21.049406) (xy 435.70122 -21.177427) (xy 435.669766 -21.303765) (xy 435.630668 -21.42795)
			(xy 435.584073 -21.549521) (xy 435.530152 -21.668025) (xy 435.498895 -21.726906) (xy 442.373766 -21.726906)
			(xy 442.374302 -21.698168) (xy 442.382923 -21.641341) (xy 442.399971 -21.586451) (xy 442.425059 -21.534739)
			(xy 442.457621 -21.487376) (xy 442.47689 -21.466048) (xy 442.483494 -21.45919) (xy 442.490606 -21.441156)
			(xy 442.490606 -21.352256) (xy 442.483494 -21.334222) (xy 442.47689 -21.327364) (xy 442.457627 -21.306031)
			(xy 442.425064 -21.258669) (xy 442.399974 -21.206958) (xy 442.382926 -21.152068) (xy 442.374303 -21.095243)
			(xy 442.374303 -21.037766) (xy 442.382924 -20.98094) (xy 442.399971 -20.92605) (xy 442.42506 -20.874339)
			(xy 442.457621 -20.826976) (xy 442.47689 -20.805648) (xy 442.483494 -20.79879) (xy 442.490606 -20.780756)
			(xy 442.490606 -20.691856) (xy 442.483494 -20.673822) (xy 442.47689 -20.666964) (xy 442.457627 -20.645631)
			(xy 442.425064 -20.598269) (xy 442.399974 -20.546558) (xy 442.382926 -20.491668) (xy 442.374303 -20.434843)
			(xy 442.374303 -20.377366) (xy 442.382924 -20.32054) (xy 442.399971 -20.26565) (xy 442.42506 -20.213939)
			(xy 442.457621 -20.166576) (xy 442.47689 -20.145248) (xy 442.483494 -20.13839) (xy 442.490606 -20.120356)
			(xy 442.490606 -20.031456) (xy 442.483494 -20.013422) (xy 442.47689 -20.006564) (xy 442.457627 -19.985231)
			(xy 442.425064 -19.937869) (xy 442.399974 -19.886158) (xy 442.382926 -19.831268) (xy 442.374303 -19.774443)
			(xy 442.374303 -19.716966) (xy 442.382924 -19.66014) (xy 442.399971 -19.60525) (xy 442.42506 -19.553539)
			(xy 442.457621 -19.506176) (xy 442.47689 -19.484848) (xy 442.483494 -19.47799) (xy 442.490606 -19.459956)
			(xy 442.490606 -19.371056) (xy 442.483494 -19.353022) (xy 442.47689 -19.346164) (xy 442.457631 -19.324827)
			(xy 442.425061 -19.277468) (xy 442.399966 -19.225759) (xy 442.382913 -19.170871) (xy 442.374288 -19.114044)
			(xy 442.373766 -19.085306) (xy 442.374252 -19.058055) (xy 442.382008 -19.004107) (xy 442.397363 -18.951812)
			(xy 442.420005 -18.902235) (xy 442.449471 -18.856385) (xy 442.485162 -18.815194) (xy 442.526353 -18.779503)
			(xy 442.572203 -18.750037) (xy 442.62178 -18.727395) (xy 442.674075 -18.71204) (xy 442.728023 -18.704284)
			(xy 442.782525 -18.704284) (xy 442.836473 -18.71204) (xy 442.888768 -18.727395) (xy 442.938345 -18.750037)
			(xy 442.984195 -18.779503) (xy 443.025386 -18.815194) (xy 443.061077 -18.856385) (xy 443.090543 -18.902235)
			(xy 443.113185 -18.951812) (xy 443.12854 -19.004107) (xy 443.136296 -19.058055) (xy 443.136782 -19.085306)
			(xy 443.13624 -19.114044) (xy 443.127619 -19.17087) (xy 443.110572 -19.225759) (xy 443.085485 -19.277471)
			(xy 443.052925 -19.324835) (xy 443.033658 -19.346164) (xy 443.027054 -19.353022) (xy 443.019942 -19.371056)
			(xy 443.019942 -19.453098) (xy 448.57619 -19.453098) (xy 448.580261 -19.397476) (xy 448.592387 -19.343039)
			(xy 448.61231 -19.290948) (xy 448.639606 -19.242313) (xy 448.673692 -19.19817) (xy 448.713841 -19.159461)
			(xy 448.759199 -19.12701) (xy 448.808799 -19.101509) (xy 448.861583 -19.083502) (xy 448.916426 -19.073372)
			(xy 448.97216 -19.071335) (xy 449.027597 -19.077435) (xy 449.081554 -19.091541) (xy 449.132883 -19.113353)
			(xy 449.180489 -19.142407) (xy 449.223357 -19.178082) (xy 449.260574 -19.219619) (xy 449.291347 -19.266132)
			(xy 449.315019 -19.316629) (xy 449.331087 -19.370036) (xy 449.339207 -19.425212) (xy 449.339716 -19.453098)
			(xy 449.339207 -19.480984) (xy 449.331087 -19.53616) (xy 449.315019 -19.589567) (xy 449.294572 -19.633184)
			(xy 454.554334 -19.633184) (xy 454.558405 -19.577562) (xy 454.570531 -19.523125) (xy 454.590454 -19.471034)
			(xy 454.61775 -19.422399) (xy 454.651836 -19.378256) (xy 454.691985 -19.339547) (xy 454.737343 -19.307096)
			(xy 454.786943 -19.281595) (xy 454.839727 -19.263588) (xy 454.89457 -19.253458) (xy 454.950304 -19.251421)
			(xy 455.005741 -19.257521) (xy 455.059698 -19.271627) (xy 455.111027 -19.293439) (xy 455.158633 -19.322493)
			(xy 455.201501 -19.358168) (xy 455.238718 -19.399705) (xy 455.269491 -19.446218) (xy 455.293163 -19.496715)
			(xy 455.309231 -19.550122) (xy 455.317351 -19.605298) (xy 455.31786 -19.633184) (xy 455.317351 -19.66107)
			(xy 455.309231 -19.716246) (xy 455.293163 -19.769653) (xy 455.269491 -19.82015) (xy 455.238718 -19.866663)
			(xy 455.201501 -19.9082) (xy 455.158633 -19.943875) (xy 455.111027 -19.972929) (xy 455.059698 -19.994741)
			(xy 455.005741 -20.008847) (xy 454.950304 -20.014947) (xy 454.89457 -20.01291) (xy 454.839727 -20.00278)
			(xy 454.786943 -19.984773) (xy 454.737343 -19.959272) (xy 454.691985 -19.926821) (xy 454.651836 -19.888112)
			(xy 454.61775 -19.843969) (xy 454.590454 -19.795334) (xy 454.570531 -19.743243) (xy 454.558405 -19.688806)
			(xy 454.554334 -19.633184) (xy 449.294572 -19.633184) (xy 449.291347 -19.640064) (xy 449.260574 -19.686577)
			(xy 449.223357 -19.728114) (xy 449.180489 -19.763789) (xy 449.132883 -19.792843) (xy 449.081554 -19.814655)
			(xy 449.027597 -19.828761) (xy 448.97216 -19.834861) (xy 448.916426 -19.832824) (xy 448.861583 -19.822694)
			(xy 448.808799 -19.804687) (xy 448.759199 -19.779186) (xy 448.713841 -19.746735) (xy 448.673692 -19.708026)
			(xy 448.639606 -19.663883) (xy 448.61231 -19.615248) (xy 448.592387 -19.563157) (xy 448.580261 -19.50872)
			(xy 448.57619 -19.453098) (xy 443.019942 -19.453098) (xy 443.019942 -19.459956) (xy 443.027054 -19.47799)
			(xy 443.033658 -19.484848) (xy 443.052936 -19.506169) (xy 443.085502 -19.553532) (xy 443.110595 -19.605245)
			(xy 443.127645 -19.660136) (xy 443.136267 -19.716965) (xy 443.136267 -19.774444) (xy 443.127643 -19.831272)
			(xy 443.110591 -19.886163) (xy 443.085498 -19.937875) (xy 443.05293 -19.985238) (xy 443.033658 -20.006564)
			(xy 443.027054 -20.013422) (xy 443.019942 -20.031456) (xy 443.019942 -20.120356) (xy 443.027054 -20.13839)
			(xy 443.033658 -20.145248) (xy 443.052936 -20.166569) (xy 443.085502 -20.213932) (xy 443.110595 -20.265645)
			(xy 443.127645 -20.320536) (xy 443.136267 -20.377365) (xy 443.136267 -20.434844) (xy 443.1313 -20.467574)
			(xy 450.587362 -20.467574) (xy 450.591433 -20.411952) (xy 450.603559 -20.357515) (xy 450.623482 -20.305424)
			(xy 450.650778 -20.256789) (xy 450.684864 -20.212646) (xy 450.725013 -20.173937) (xy 450.770371 -20.141486)
			(xy 450.819971 -20.115985) (xy 450.872755 -20.097978) (xy 450.927598 -20.087848) (xy 450.983332 -20.085811)
			(xy 451.038769 -20.091911) (xy 451.092726 -20.106017) (xy 451.144055 -20.127829) (xy 451.191661 -20.156883)
			(xy 451.234529 -20.192558) (xy 451.271746 -20.234095) (xy 451.302519 -20.280608) (xy 451.326191 -20.331105)
			(xy 451.342259 -20.384512) (xy 451.350379 -20.439688) (xy 451.350888 -20.467574) (xy 451.350379 -20.49546)
			(xy 451.342259 -20.550636) (xy 451.326191 -20.604043) (xy 451.302519 -20.65454) (xy 451.271746 -20.701053)
			(xy 451.234529 -20.74259) (xy 451.219494 -20.755102) (xy 454.45883 -20.755102) (xy 454.462901 -20.69948)
			(xy 454.475027 -20.645043) (xy 454.49495 -20.592952) (xy 454.522246 -20.544317) (xy 454.556332 -20.500174)
			(xy 454.596481 -20.461465) (xy 454.641839 -20.429014) (xy 454.691439 -20.403513) (xy 454.744223 -20.385506)
			(xy 454.799066 -20.375376) (xy 454.8548 -20.373339) (xy 454.910237 -20.379439) (xy 454.964194 -20.393545)
			(xy 455.015523 -20.415357) (xy 455.063129 -20.444411) (xy 455.105997 -20.480086) (xy 455.143214 -20.521623)
			(xy 455.173987 -20.568136) (xy 455.197659 -20.618633) (xy 455.213727 -20.67204) (xy 455.221847 -20.727216)
			(xy 455.222356 -20.755102) (xy 455.221847 -20.782988) (xy 455.213727 -20.838164) (xy 455.197659 -20.891571)
			(xy 455.173987 -20.942068) (xy 455.143214 -20.988581) (xy 455.105997 -21.030118) (xy 455.063129 -21.065793)
			(xy 455.015523 -21.094847) (xy 454.964194 -21.116659) (xy 454.910237 -21.130765) (xy 454.8548 -21.136865)
			(xy 454.799066 -21.134828) (xy 454.744223 -21.124698) (xy 454.691439 -21.106691) (xy 454.641839 -21.08119)
			(xy 454.596481 -21.048739) (xy 454.556332 -21.01003) (xy 454.522246 -20.965887) (xy 454.49495 -20.917252)
			(xy 454.475027 -20.865161) (xy 454.462901 -20.810724) (xy 454.45883 -20.755102) (xy 451.219494 -20.755102)
			(xy 451.191661 -20.778265) (xy 451.144055 -20.807319) (xy 451.092726 -20.829131) (xy 451.038769 -20.843237)
			(xy 450.983332 -20.849337) (xy 450.927598 -20.8473) (xy 450.872755 -20.83717) (xy 450.819971 -20.819163)
			(xy 450.770371 -20.793662) (xy 450.725013 -20.761211) (xy 450.684864 -20.722502) (xy 450.650778 -20.678359)
			(xy 450.623482 -20.629724) (xy 450.603559 -20.577633) (xy 450.591433 -20.523196) (xy 450.587362 -20.467574)
			(xy 443.1313 -20.467574) (xy 443.127643 -20.491672) (xy 443.110591 -20.546563) (xy 443.085498 -20.598275)
			(xy 443.05293 -20.645638) (xy 443.033658 -20.666964) (xy 443.027054 -20.673822) (xy 443.019942 -20.691856)
			(xy 443.019942 -20.780756) (xy 443.027054 -20.79879) (xy 443.033658 -20.805648) (xy 443.052936 -20.826969)
			(xy 443.085502 -20.874332) (xy 443.110595 -20.926045) (xy 443.127645 -20.980936) (xy 443.136267 -21.037765)
			(xy 443.136267 -21.095244) (xy 443.127643 -21.152072) (xy 443.110591 -21.206963) (xy 443.085498 -21.258675)
			(xy 443.05293 -21.306038) (xy 443.033658 -21.327364) (xy 443.027054 -21.334222) (xy 443.019942 -21.352256)
			(xy 443.019942 -21.441156) (xy 443.027054 -21.45919) (xy 443.033658 -21.466048) (xy 443.052931 -21.487373)
			(xy 443.085497 -21.534736) (xy 443.110589 -21.586448) (xy 443.127639 -21.641339) (xy 443.136261 -21.698167)
			(xy 443.136782 -21.726906) (xy 443.136296 -21.754157) (xy 443.133203 -21.775674) (xy 452.235822 -21.775674)
			(xy 452.239893 -21.720052) (xy 452.252019 -21.665615) (xy 452.271942 -21.613524) (xy 452.299238 -21.564889)
			(xy 452.333324 -21.520746) (xy 452.373473 -21.482037) (xy 452.418831 -21.449586) (xy 452.468431 -21.424085)
			(xy 452.521215 -21.406078) (xy 452.576058 -21.395948) (xy 452.631792 -21.393911) (xy 452.687229 -21.400011)
			(xy 452.741186 -21.414117) (xy 452.792515 -21.435929) (xy 452.840121 -21.464983) (xy 452.882989 -21.500658)
			(xy 452.920206 -21.542195) (xy 452.950979 -21.588708) (xy 452.974651 -21.639205) (xy 452.990719 -21.692612)
			(xy 452.998839 -21.747788) (xy 452.999348 -21.775674) (xy 452.998839 -21.80356) (xy 452.995766 -21.824442)
			(xy 453.380346 -21.824442) (xy 453.384417 -21.76882) (xy 453.396543 -21.714383) (xy 453.416466 -21.662292)
			(xy 453.443762 -21.613657) (xy 453.477848 -21.569514) (xy 453.517997 -21.530805) (xy 453.563355 -21.498354)
			(xy 453.612955 -21.472853) (xy 453.665739 -21.454846) (xy 453.720582 -21.444716) (xy 453.776316 -21.442679)
			(xy 453.831753 -21.448779) (xy 453.88571 -21.462885) (xy 453.937039 -21.484697) (xy 453.984645 -21.513751)
			(xy 454.027513 -21.549426) (xy 454.06473 -21.590963) (xy 454.095503 -21.637476) (xy 454.119175 -21.687973)
			(xy 454.135243 -21.74138) (xy 454.143363 -21.796556) (xy 454.143872 -21.824442) (xy 454.143363 -21.852328)
			(xy 454.135243 -21.907504) (xy 454.119175 -21.960911) (xy 454.095503 -22.011408) (xy 454.06473 -22.057921)
			(xy 454.027513 -22.099458) (xy 453.984645 -22.135133) (xy 453.937039 -22.164187) (xy 453.88571 -22.185999)
			(xy 453.831753 -22.200105) (xy 453.776316 -22.206205) (xy 453.720582 -22.204168) (xy 453.665739 -22.194038)
			(xy 453.612955 -22.176031) (xy 453.563355 -22.15053) (xy 453.517997 -22.118079) (xy 453.477848 -22.07937)
			(xy 453.443762 -22.035227) (xy 453.416466 -21.986592) (xy 453.396543 -21.934501) (xy 453.384417 -21.880064)
			(xy 453.380346 -21.824442) (xy 452.995766 -21.824442) (xy 452.990719 -21.858736) (xy 452.974651 -21.912143)
			(xy 452.950979 -21.96264) (xy 452.920206 -22.009153) (xy 452.882989 -22.05069) (xy 452.840121 -22.086365)
			(xy 452.792515 -22.115419) (xy 452.741186 -22.137231) (xy 452.687229 -22.151337) (xy 452.631792 -22.157437)
			(xy 452.576058 -22.1554) (xy 452.521215 -22.14527) (xy 452.468431 -22.127263) (xy 452.418831 -22.101762)
			(xy 452.373473 -22.069311) (xy 452.333324 -22.030602) (xy 452.299238 -21.986459) (xy 452.271942 -21.937824)
			(xy 452.252019 -21.885733) (xy 452.239893 -21.831296) (xy 452.235822 -21.775674) (xy 443.133203 -21.775674)
			(xy 443.12854 -21.808105) (xy 443.113185 -21.8604) (xy 443.090543 -21.909977) (xy 443.061077 -21.955827)
			(xy 443.025386 -21.997018) (xy 442.984195 -22.032709) (xy 442.938345 -22.062175) (xy 442.888768 -22.084817)
			(xy 442.836473 -22.100172) (xy 442.782525 -22.107928) (xy 442.728023 -22.107928) (xy 442.674075 -22.100172)
			(xy 442.62178 -22.084817) (xy 442.572203 -22.062175) (xy 442.526353 -22.032709) (xy 442.485162 -21.997018)
			(xy 442.449471 -21.955827) (xy 442.420005 -21.909977) (xy 442.397363 -21.8604) (xy 442.382008 -21.808105)
			(xy 442.374252 -21.754157) (xy 442.373766 -21.726906) (xy 435.498895 -21.726906) (xy 435.469107 -21.783021)
			(xy 435.401166 -21.894082) (xy 435.32658 -22.000794) (xy 435.245627 -22.102761) (xy 435.158608 -22.199603)
			(xy 435.065847 -22.29096) (xy 434.967689 -22.376492) (xy 434.8645 -22.45588) (xy 434.756663 -22.52883)
			(xy 434.711613 -22.555454) (xy 451.636382 -22.555454) (xy 451.640453 -22.499832) (xy 451.652579 -22.445395)
			(xy 451.672502 -22.393304) (xy 451.699798 -22.344669) (xy 451.733884 -22.300526) (xy 451.774033 -22.261817)
			(xy 451.819391 -22.229366) (xy 451.868991 -22.203865) (xy 451.921775 -22.185858) (xy 451.976618 -22.175728)
			(xy 452.032352 -22.173691) (xy 452.087789 -22.179791) (xy 452.141746 -22.193897) (xy 452.193075 -22.215709)
			(xy 452.240681 -22.244763) (xy 452.283549 -22.280438) (xy 452.320766 -22.321975) (xy 452.351539 -22.368488)
			(xy 452.375211 -22.418985) (xy 452.391279 -22.472392) (xy 452.399399 -22.527568) (xy 452.399908 -22.555454)
			(xy 452.399399 -22.58334) (xy 452.391279 -22.638516) (xy 452.375211 -22.691923) (xy 452.351539 -22.74242)
			(xy 452.320766 -22.788933) (xy 452.283549 -22.83047) (xy 452.240681 -22.866145) (xy 452.193075 -22.895199)
			(xy 452.141746 -22.917011) (xy 452.087789 -22.931117) (xy 452.032352 -22.937217) (xy 451.976618 -22.93518)
			(xy 451.921775 -22.92505) (xy 451.868991 -22.907043) (xy 451.819391 -22.881542) (xy 451.774033 -22.849091)
			(xy 451.733884 -22.810382) (xy 451.699798 -22.766239) (xy 451.672502 -22.717604) (xy 451.652579 -22.665513)
			(xy 451.640453 -22.611076) (xy 451.636382 -22.555454) (xy 434.711613 -22.555454) (xy 434.644578 -22.595071)
			(xy 434.528665 -22.654354) (xy 434.409352 -22.706462) (xy 434.287085 -22.751198) (xy 434.162318 -22.788397)
			(xy 434.035515 -22.817921) (xy 433.907148 -22.839659) (xy 433.777695 -22.853532) (xy 433.647636 -22.859486)
			(xy 433.517457 -22.857501) (xy 433.387641 -22.847583) (xy 433.258671 -22.829769) (xy 433.131026 -22.804126)
			(xy 433.005183 -22.770749) (xy 432.881608 -22.729762) (xy 432.760762 -22.681318) (xy 432.643094 -22.625596)
			(xy 432.529042 -22.562805) (xy 432.41903 -22.493178) (xy 432.313468 -22.416973) (xy 432.212748 -22.334474)
			(xy 432.117244 -22.245989) (xy 432.027312 -22.151846) (xy 431.943287 -22.052395) (xy 431.865482 -21.948007)
			(xy 431.794185 -21.83907) (xy 431.729661 -21.725988) (xy 431.672152 -21.609184) (xy 431.62187 -21.489091)
			(xy 431.579004 -21.366155) (xy 431.543711 -21.240836) (xy 431.516125 -21.113597) (xy 431.496346 -20.984914)
			(xy 431.48445 -20.855264) (xy 431.48048 -20.72513) (xy 425.250225 -20.72513) (xy 425.234581 -20.74259)
			(xy 425.191713 -20.778265) (xy 425.144107 -20.807319) (xy 425.092778 -20.829131) (xy 425.038821 -20.843237)
			(xy 424.983384 -20.849337) (xy 424.92765 -20.8473) (xy 424.872807 -20.83717) (xy 424.820023 -20.819163)
			(xy 424.770423 -20.793662) (xy 424.725065 -20.761211) (xy 424.684916 -20.722502) (xy 424.65083 -20.678359)
			(xy 424.623534 -20.629724) (xy 424.603611 -20.577633) (xy 424.591485 -20.523196) (xy 424.587414 -20.467574)
			(xy 417.131338 -20.467574) (xy 417.127682 -20.49167) (xy 417.110633 -20.546561) (xy 417.085543 -20.598273)
			(xy 417.05298 -20.645636) (xy 417.03371 -20.666964) (xy 417.027106 -20.673822) (xy 417.019994 -20.691856)
			(xy 417.019994 -20.780756) (xy 417.027106 -20.79879) (xy 417.03371 -20.805648) (xy 417.052985 -20.82697)
			(xy 417.085547 -20.874335) (xy 417.110636 -20.926047) (xy 417.127684 -20.980938) (xy 417.136306 -21.037766)
			(xy 417.136305 -21.095243) (xy 417.127682 -21.15207) (xy 417.110633 -21.206961) (xy 417.085543 -21.258673)
			(xy 417.05298 -21.306036) (xy 417.03371 -21.327364) (xy 417.027106 -21.334222) (xy 417.019994 -21.352256)
			(xy 417.019994 -21.441156) (xy 417.027106 -21.45919) (xy 417.03371 -21.466048) (xy 417.052975 -21.487381)
			(xy 417.085544 -21.53474) (xy 417.110638 -21.58645) (xy 417.12769 -21.64134) (xy 417.136313 -21.698167)
			(xy 417.136834 -21.726906) (xy 417.136348 -21.754157) (xy 417.133255 -21.775674) (xy 426.235874 -21.775674)
			(xy 426.239945 -21.720052) (xy 426.252071 -21.665615) (xy 426.271994 -21.613524) (xy 426.29929 -21.564889)
			(xy 426.333376 -21.520746) (xy 426.373525 -21.482037) (xy 426.418883 -21.449586) (xy 426.468483 -21.424085)
			(xy 426.521267 -21.406078) (xy 426.57611 -21.395948) (xy 426.631844 -21.393911) (xy 426.687281 -21.400011)
			(xy 426.741238 -21.414117) (xy 426.792567 -21.435929) (xy 426.840173 -21.464983) (xy 426.883041 -21.500658)
			(xy 426.920258 -21.542195) (xy 426.951031 -21.588708) (xy 426.974703 -21.639205) (xy 426.990771 -21.692612)
			(xy 426.998891 -21.747788) (xy 426.9994 -21.775674) (xy 426.998891 -21.80356) (xy 426.99122 -21.855684)
			(xy 427.13859 -21.855684) (xy 427.142661 -21.800062) (xy 427.154787 -21.745625) (xy 427.17471 -21.693534)
			(xy 427.202006 -21.644899) (xy 427.236092 -21.600756) (xy 427.276241 -21.562047) (xy 427.321599 -21.529596)
			(xy 427.371199 -21.504095) (xy 427.423983 -21.486088) (xy 427.478826 -21.475958) (xy 427.53456 -21.473921)
			(xy 427.589997 -21.480021) (xy 427.643954 -21.494127) (xy 427.695283 -21.515939) (xy 427.742889 -21.544993)
			(xy 427.785757 -21.580668) (xy 427.822974 -21.622205) (xy 427.853747 -21.668718) (xy 427.877419 -21.719215)
			(xy 427.893487 -21.772622) (xy 427.901607 -21.827798) (xy 427.901958 -21.847048) (xy 428.372776 -21.847048)
			(xy 428.376847 -21.791426) (xy 428.388973 -21.736989) (xy 428.408896 -21.684898) (xy 428.436192 -21.636263)
			(xy 428.470278 -21.59212) (xy 428.510427 -21.553411) (xy 428.555785 -21.52096) (xy 428.605385 -21.495459)
			(xy 428.658169 -21.477452) (xy 428.713012 -21.467322) (xy 428.768746 -21.465285) (xy 428.824183 -21.471385)
			(xy 428.87814 -21.485491) (xy 428.929469 -21.507303) (xy 428.977075 -21.536357) (xy 429.019943 -21.572032)
			(xy 429.05716 -21.613569) (xy 429.087933 -21.660082) (xy 429.111605 -21.710579) (xy 429.127673 -21.763986)
			(xy 429.135793 -21.819162) (xy 429.136302 -21.847048) (xy 429.135793 -21.874934) (xy 429.127673 -21.93011)
			(xy 429.111605 -21.983517) (xy 429.087933 -22.034014) (xy 429.05716 -22.080527) (xy 429.019943 -22.122064)
			(xy 428.977075 -22.157739) (xy 428.929469 -22.186793) (xy 428.87814 -22.208605) (xy 428.824183 -22.222711)
			(xy 428.768746 -22.228811) (xy 428.713012 -22.226774) (xy 428.658169 -22.216644) (xy 428.605385 -22.198637)
			(xy 428.555785 -22.173136) (xy 428.510427 -22.140685) (xy 428.470278 -22.101976) (xy 428.436192 -22.057833)
			(xy 428.408896 -22.009198) (xy 428.388973 -21.957107) (xy 428.376847 -21.90267) (xy 428.372776 -21.847048)
			(xy 427.901958 -21.847048) (xy 427.902116 -21.855684) (xy 427.901607 -21.88357) (xy 427.893487 -21.938746)
			(xy 427.877419 -21.992153) (xy 427.853747 -22.04265) (xy 427.822974 -22.089163) (xy 427.785757 -22.1307)
			(xy 427.742889 -22.166375) (xy 427.695283 -22.195429) (xy 427.643954 -22.217241) (xy 427.589997 -22.231347)
			(xy 427.53456 -22.237447) (xy 427.478826 -22.23541) (xy 427.423983 -22.22528) (xy 427.371199 -22.207273)
			(xy 427.321599 -22.181772) (xy 427.276241 -22.149321) (xy 427.236092 -22.110612) (xy 427.202006 -22.066469)
			(xy 427.17471 -22.017834) (xy 427.154787 -21.965743) (xy 427.142661 -21.911306) (xy 427.13859 -21.855684)
			(xy 426.99122 -21.855684) (xy 426.990771 -21.858736) (xy 426.974703 -21.912143) (xy 426.951031 -21.96264)
			(xy 426.920258 -22.009153) (xy 426.883041 -22.05069) (xy 426.840173 -22.086365) (xy 426.792567 -22.115419)
			(xy 426.741238 -22.137231) (xy 426.687281 -22.151337) (xy 426.631844 -22.157437) (xy 426.57611 -22.1554)
			(xy 426.521267 -22.14527) (xy 426.468483 -22.127263) (xy 426.418883 -22.101762) (xy 426.373525 -22.069311)
			(xy 426.333376 -22.030602) (xy 426.29929 -21.986459) (xy 426.271994 -21.937824) (xy 426.252071 -21.885733)
			(xy 426.239945 -21.831296) (xy 426.235874 -21.775674) (xy 417.133255 -21.775674) (xy 417.128592 -21.808105)
			(xy 417.113237 -21.8604) (xy 417.090595 -21.909977) (xy 417.061129 -21.955827) (xy 417.025438 -21.997018)
			(xy 416.984247 -22.032709) (xy 416.938397 -22.062175) (xy 416.88882 -22.084817) (xy 416.836525 -22.100172)
			(xy 416.782577 -22.107928) (xy 416.728075 -22.107928) (xy 416.674127 -22.100172) (xy 416.621832 -22.084817)
			(xy 416.572255 -22.062175) (xy 416.526405 -22.032709) (xy 416.485214 -21.997018) (xy 416.449523 -21.955827)
			(xy 416.420057 -21.909977) (xy 416.397415 -21.8604) (xy 416.38206 -21.808105) (xy 416.374304 -21.754157)
			(xy 416.373818 -21.726906) (xy 409.498947 -21.726906) (xy 409.469159 -21.783021) (xy 409.401218 -21.894082)
			(xy 409.326632 -22.000794) (xy 409.245679 -22.102761) (xy 409.15866 -22.199603) (xy 409.065899 -22.29096)
			(xy 408.967741 -22.376492) (xy 408.864552 -22.45588) (xy 408.756715 -22.52883) (xy 408.711665 -22.555454)
			(xy 425.636434 -22.555454) (xy 425.640505 -22.499832) (xy 425.652631 -22.445395) (xy 425.672554 -22.393304)
			(xy 425.69985 -22.344669) (xy 425.733936 -22.300526) (xy 425.774085 -22.261817) (xy 425.819443 -22.229366)
			(xy 425.869043 -22.203865) (xy 425.921827 -22.185858) (xy 425.97667 -22.175728) (xy 426.032404 -22.173691)
			(xy 426.087841 -22.179791) (xy 426.141798 -22.193897) (xy 426.193127 -22.215709) (xy 426.240733 -22.244763)
			(xy 426.283601 -22.280438) (xy 426.320818 -22.321975) (xy 426.351591 -22.368488) (xy 426.375263 -22.418985)
			(xy 426.391331 -22.472392) (xy 426.399451 -22.527568) (xy 426.39996 -22.555454) (xy 426.399451 -22.58334)
			(xy 426.391331 -22.638516) (xy 426.375263 -22.691923) (xy 426.351591 -22.74242) (xy 426.320818 -22.788933)
			(xy 426.283601 -22.83047) (xy 426.240733 -22.866145) (xy 426.193127 -22.895199) (xy 426.141798 -22.917011)
			(xy 426.087841 -22.931117) (xy 426.032404 -22.937217) (xy 425.97667 -22.93518) (xy 425.921827 -22.92505)
			(xy 425.869043 -22.907043) (xy 425.819443 -22.881542) (xy 425.774085 -22.849091) (xy 425.733936 -22.810382)
			(xy 425.69985 -22.766239) (xy 425.672554 -22.717604) (xy 425.652631 -22.665513) (xy 425.640505 -22.611076)
			(xy 425.636434 -22.555454) (xy 408.711665 -22.555454) (xy 408.64463 -22.595071) (xy 408.528717 -22.654354)
			(xy 408.409404 -22.706462) (xy 408.287137 -22.751198) (xy 408.16237 -22.788397) (xy 408.035567 -22.817921)
			(xy 407.9072 -22.839659) (xy 407.777747 -22.853532) (xy 407.647688 -22.859486) (xy 407.517509 -22.857501)
			(xy 407.387693 -22.847583) (xy 407.258723 -22.829769) (xy 407.131078 -22.804126) (xy 407.005235 -22.770749)
			(xy 406.88166 -22.729762) (xy 406.760814 -22.681318) (xy 406.643146 -22.625596) (xy 406.529094 -22.562805)
			(xy 406.419082 -22.493178) (xy 406.31352 -22.416973) (xy 406.2128 -22.334474) (xy 406.117296 -22.245989)
			(xy 406.027364 -22.151846) (xy 405.943339 -22.052395) (xy 405.865534 -21.948007) (xy 405.794237 -21.83907)
			(xy 405.729713 -21.725988) (xy 405.672204 -21.609184) (xy 405.621922 -21.489091) (xy 405.579056 -21.366155)
			(xy 405.543763 -21.240836) (xy 405.516177 -21.113597) (xy 405.496398 -20.984914) (xy 405.484502 -20.855264)
			(xy 405.480532 -20.72513) (xy 399.250277 -20.72513) (xy 399.234633 -20.74259) (xy 399.191765 -20.778265)
			(xy 399.144159 -20.807319) (xy 399.09283 -20.829131) (xy 399.038873 -20.843237) (xy 398.983436 -20.849337)
			(xy 398.927702 -20.8473) (xy 398.872859 -20.83717) (xy 398.820075 -20.819163) (xy 398.770475 -20.793662)
			(xy 398.725117 -20.761211) (xy 398.684968 -20.722502) (xy 398.650882 -20.678359) (xy 398.623586 -20.629724)
			(xy 398.603663 -20.577633) (xy 398.591537 -20.523196) (xy 398.587466 -20.467574) (xy 391.131403 -20.467574)
			(xy 391.127746 -20.491672) (xy 391.110695 -20.546563) (xy 391.085601 -20.598275) (xy 391.053034 -20.645638)
			(xy 391.033762 -20.666964) (xy 391.027158 -20.673822) (xy 391.020046 -20.691856) (xy 391.020046 -20.780756)
			(xy 391.027158 -20.79879) (xy 391.033762 -20.805648) (xy 391.053039 -20.826969) (xy 391.085606 -20.874332)
			(xy 391.110698 -20.926045) (xy 391.127748 -20.980937) (xy 391.13637 -21.037765) (xy 391.13637 -21.095244)
			(xy 391.127746 -21.152072) (xy 391.110695 -21.206963) (xy 391.085601 -21.258675) (xy 391.053034 -21.306038)
			(xy 391.033762 -21.327364) (xy 391.027158 -21.334222) (xy 391.020046 -21.352256) (xy 391.020046 -21.441156)
			(xy 391.027158 -21.45919) (xy 391.033762 -21.466048) (xy 391.053036 -21.487373) (xy 391.085601 -21.534735)
			(xy 391.110693 -21.586448) (xy 391.127743 -21.641339) (xy 391.136365 -21.698167) (xy 391.136886 -21.726906)
			(xy 391.1364 -21.754157) (xy 391.133307 -21.775674) (xy 400.235926 -21.775674) (xy 400.239997 -21.720052)
			(xy 400.252123 -21.665615) (xy 400.272046 -21.613524) (xy 400.299342 -21.564889) (xy 400.333428 -21.520746)
			(xy 400.373577 -21.482037) (xy 400.418935 -21.449586) (xy 400.468535 -21.424085) (xy 400.521319 -21.406078)
			(xy 400.576162 -21.395948) (xy 400.631896 -21.393911) (xy 400.687333 -21.400011) (xy 400.74129 -21.414117)
			(xy 400.792619 -21.435929) (xy 400.840225 -21.464983) (xy 400.883093 -21.500658) (xy 400.92031 -21.542195)
			(xy 400.951083 -21.588708) (xy 400.974755 -21.639205) (xy 400.990823 -21.692612) (xy 400.998943 -21.747788)
			(xy 400.999452 -21.775674) (xy 400.998943 -21.80356) (xy 400.991272 -21.855684) (xy 401.138642 -21.855684)
			(xy 401.142713 -21.800062) (xy 401.154839 -21.745625) (xy 401.174762 -21.693534) (xy 401.202058 -21.644899)
			(xy 401.236144 -21.600756) (xy 401.276293 -21.562047) (xy 401.321651 -21.529596) (xy 401.371251 -21.504095)
			(xy 401.424035 -21.486088) (xy 401.478878 -21.475958) (xy 401.534612 -21.473921) (xy 401.590049 -21.480021)
			(xy 401.644006 -21.494127) (xy 401.695335 -21.515939) (xy 401.742941 -21.544993) (xy 401.785809 -21.580668)
			(xy 401.823026 -21.622205) (xy 401.853799 -21.668718) (xy 401.877471 -21.719215) (xy 401.893539 -21.772622)
			(xy 401.901659 -21.827798) (xy 401.90201 -21.847048) (xy 402.372828 -21.847048) (xy 402.376899 -21.791426)
			(xy 402.389025 -21.736989) (xy 402.408948 -21.684898) (xy 402.436244 -21.636263) (xy 402.47033 -21.59212)
			(xy 402.510479 -21.553411) (xy 402.555837 -21.52096) (xy 402.605437 -21.495459) (xy 402.658221 -21.477452)
			(xy 402.713064 -21.467322) (xy 402.768798 -21.465285) (xy 402.824235 -21.471385) (xy 402.878192 -21.485491)
			(xy 402.929521 -21.507303) (xy 402.977127 -21.536357) (xy 403.019995 -21.572032) (xy 403.057212 -21.613569)
			(xy 403.087985 -21.660082) (xy 403.111657 -21.710579) (xy 403.127725 -21.763986) (xy 403.135845 -21.819162)
			(xy 403.136354 -21.847048) (xy 403.135845 -21.874934) (xy 403.127725 -21.93011) (xy 403.111657 -21.983517)
			(xy 403.087985 -22.034014) (xy 403.057212 -22.080527) (xy 403.019995 -22.122064) (xy 402.977127 -22.157739)
			(xy 402.929521 -22.186793) (xy 402.878192 -22.208605) (xy 402.824235 -22.222711) (xy 402.768798 -22.228811)
			(xy 402.713064 -22.226774) (xy 402.658221 -22.216644) (xy 402.605437 -22.198637) (xy 402.555837 -22.173136)
			(xy 402.510479 -22.140685) (xy 402.47033 -22.101976) (xy 402.436244 -22.057833) (xy 402.408948 -22.009198)
			(xy 402.389025 -21.957107) (xy 402.376899 -21.90267) (xy 402.372828 -21.847048) (xy 401.90201 -21.847048)
			(xy 401.902168 -21.855684) (xy 401.901659 -21.88357) (xy 401.893539 -21.938746) (xy 401.877471 -21.992153)
			(xy 401.853799 -22.04265) (xy 401.823026 -22.089163) (xy 401.785809 -22.1307) (xy 401.742941 -22.166375)
			(xy 401.695335 -22.195429) (xy 401.644006 -22.217241) (xy 401.590049 -22.231347) (xy 401.534612 -22.237447)
			(xy 401.478878 -22.23541) (xy 401.424035 -22.22528) (xy 401.371251 -22.207273) (xy 401.321651 -22.181772)
			(xy 401.276293 -22.149321) (xy 401.236144 -22.110612) (xy 401.202058 -22.066469) (xy 401.174762 -22.017834)
			(xy 401.154839 -21.965743) (xy 401.142713 -21.911306) (xy 401.138642 -21.855684) (xy 400.991272 -21.855684)
			(xy 400.990823 -21.858736) (xy 400.974755 -21.912143) (xy 400.951083 -21.96264) (xy 400.92031 -22.009153)
			(xy 400.883093 -22.05069) (xy 400.840225 -22.086365) (xy 400.792619 -22.115419) (xy 400.74129 -22.137231)
			(xy 400.687333 -22.151337) (xy 400.631896 -22.157437) (xy 400.576162 -22.1554) (xy 400.521319 -22.14527)
			(xy 400.468535 -22.127263) (xy 400.418935 -22.101762) (xy 400.373577 -22.069311) (xy 400.333428 -22.030602)
			(xy 400.299342 -21.986459) (xy 400.272046 -21.937824) (xy 400.252123 -21.885733) (xy 400.239997 -21.831296)
			(xy 400.235926 -21.775674) (xy 391.133307 -21.775674) (xy 391.128644 -21.808105) (xy 391.113289 -21.8604)
			(xy 391.090647 -21.909977) (xy 391.061181 -21.955827) (xy 391.02549 -21.997018) (xy 390.984299 -22.032709)
			(xy 390.938449 -22.062175) (xy 390.888872 -22.084817) (xy 390.836577 -22.100172) (xy 390.782629 -22.107928)
			(xy 390.728127 -22.107928) (xy 390.674179 -22.100172) (xy 390.621884 -22.084817) (xy 390.572307 -22.062175)
			(xy 390.526457 -22.032709) (xy 390.485266 -21.997018) (xy 390.449575 -21.955827) (xy 390.420109 -21.909977)
			(xy 390.397467 -21.8604) (xy 390.382112 -21.808105) (xy 390.374356 -21.754157) (xy 390.37387 -21.726906)
			(xy 383.501129 -21.726906) (xy 383.474037 -21.777941) (xy 383.406096 -21.889002) (xy 383.33151 -21.995714)
			(xy 383.250557 -22.097681) (xy 383.163538 -22.194523) (xy 383.070777 -22.28588) (xy 382.972619 -22.371412)
			(xy 382.86943 -22.4508) (xy 382.761593 -22.52375) (xy 382.707947 -22.555454) (xy 399.636486 -22.555454)
			(xy 399.640557 -22.499832) (xy 399.652683 -22.445395) (xy 399.672606 -22.393304) (xy 399.699902 -22.344669)
			(xy 399.733988 -22.300526) (xy 399.774137 -22.261817) (xy 399.819495 -22.229366) (xy 399.869095 -22.203865)
			(xy 399.921879 -22.185858) (xy 399.976722 -22.175728) (xy 400.032456 -22.173691) (xy 400.087893 -22.179791)
			(xy 400.14185 -22.193897) (xy 400.193179 -22.215709) (xy 400.240785 -22.244763) (xy 400.283653 -22.280438)
			(xy 400.32087 -22.321975) (xy 400.351643 -22.368488) (xy 400.375315 -22.418985) (xy 400.391383 -22.472392)
			(xy 400.399503 -22.527568) (xy 400.400012 -22.555454) (xy 400.399503 -22.58334) (xy 400.391383 -22.638516)
			(xy 400.375315 -22.691923) (xy 400.351643 -22.74242) (xy 400.32087 -22.788933) (xy 400.283653 -22.83047)
			(xy 400.240785 -22.866145) (xy 400.193179 -22.895199) (xy 400.14185 -22.917011) (xy 400.087893 -22.931117)
			(xy 400.032456 -22.937217) (xy 399.976722 -22.93518) (xy 399.921879 -22.92505) (xy 399.869095 -22.907043)
			(xy 399.819495 -22.881542) (xy 399.774137 -22.849091) (xy 399.733988 -22.810382) (xy 399.699902 -22.766239)
			(xy 399.672606 -22.717604) (xy 399.652683 -22.665513) (xy 399.640557 -22.611076) (xy 399.636486 -22.555454)
			(xy 382.707947 -22.555454) (xy 382.649508 -22.589991) (xy 382.533595 -22.649274) (xy 382.414282 -22.701382)
			(xy 382.292015 -22.746118) (xy 382.167248 -22.783317) (xy 382.040445 -22.812841) (xy 381.912078 -22.834579)
			(xy 381.782625 -22.848452) (xy 381.652566 -22.854406) (xy 381.522387 -22.852421) (xy 381.392571 -22.842503)
			(xy 381.263601 -22.824689) (xy 381.135956 -22.799046) (xy 381.010113 -22.765669) (xy 380.886538 -22.724682)
			(xy 380.765692 -22.676238) (xy 380.648024 -22.620516) (xy 380.533972 -22.557725) (xy 380.42396 -22.488098)
			(xy 380.318398 -22.411893) (xy 380.217678 -22.329394) (xy 380.122174 -22.240909) (xy 380.032242 -22.146766)
			(xy 379.948217 -22.047315) (xy 379.870412 -21.942927) (xy 379.799115 -21.83399) (xy 379.734591 -21.720908)
			(xy 379.677082 -21.604104) (xy 379.6268 -21.484011) (xy 379.583934 -21.361075) (xy 379.548641 -21.235756)
			(xy 379.521055 -21.108517) (xy 379.501276 -20.979834) (xy 379.48938 -20.850184) (xy 379.48541 -20.72005)
			(xy 373.254881 -20.72005) (xy 373.234685 -20.74259) (xy 373.191817 -20.778265) (xy 373.144211 -20.807319)
			(xy 373.092882 -20.829131) (xy 373.038925 -20.843237) (xy 372.983488 -20.849337) (xy 372.927754 -20.8473)
			(xy 372.872911 -20.83717) (xy 372.820127 -20.819163) (xy 372.770527 -20.793662) (xy 372.725169 -20.761211)
			(xy 372.68502 -20.722502) (xy 372.650934 -20.678359) (xy 372.623638 -20.629724) (xy 372.603715 -20.577633)
			(xy 372.591589 -20.523196) (xy 372.587518 -20.467574) (xy 365.106424 -20.467574) (xy 365.08565 -20.510388)
			(xy 365.053085 -20.557752) (xy 365.033814 -20.57908) (xy 365.02721 -20.585938) (xy 365.020098 -20.603972)
			(xy 365.020098 -20.692872) (xy 365.02721 -20.710906) (xy 365.033814 -20.717764) (xy 365.053105 -20.739073)
			(xy 365.085666 -20.786439) (xy 365.110754 -20.838154) (xy 365.127801 -20.893047) (xy 365.13642 -20.949877)
			(xy 365.136418 -21.007356) (xy 365.127793 -21.064184) (xy 365.110742 -21.119076) (xy 365.08565 -21.170788)
			(xy 365.053085 -21.218152) (xy 365.033814 -21.23948) (xy 365.02721 -21.246338) (xy 365.020098 -21.264372)
			(xy 365.020098 -21.353272) (xy 365.02721 -21.371306) (xy 365.033814 -21.378164) (xy 365.053087 -21.399489)
			(xy 365.085655 -21.446851) (xy 365.110748 -21.498563) (xy 365.127798 -21.553454) (xy 365.136419 -21.610283)
			(xy 365.136938 -21.639022) (xy 365.136452 -21.666273) (xy 365.128696 -21.720221) (xy 365.113341 -21.772516)
			(xy 365.111899 -21.775674) (xy 374.235978 -21.775674) (xy 374.240049 -21.720052) (xy 374.252175 -21.665615)
			(xy 374.272098 -21.613524) (xy 374.299394 -21.564889) (xy 374.33348 -21.520746) (xy 374.373629 -21.482037)
			(xy 374.418987 -21.449586) (xy 374.468587 -21.424085) (xy 374.521371 -21.406078) (xy 374.576214 -21.395948)
			(xy 374.631948 -21.393911) (xy 374.687385 -21.400011) (xy 374.741342 -21.414117) (xy 374.792671 -21.435929)
			(xy 374.840277 -21.464983) (xy 374.883145 -21.500658) (xy 374.920362 -21.542195) (xy 374.951135 -21.588708)
			(xy 374.974807 -21.639205) (xy 374.990875 -21.692612) (xy 374.998995 -21.747788) (xy 374.999504 -21.775674)
			(xy 374.998995 -21.80356) (xy 374.991324 -21.855684) (xy 375.138694 -21.855684) (xy 375.142765 -21.800062)
			(xy 375.154891 -21.745625) (xy 375.174814 -21.693534) (xy 375.20211 -21.644899) (xy 375.236196 -21.600756)
			(xy 375.276345 -21.562047) (xy 375.321703 -21.529596) (xy 375.371303 -21.504095) (xy 375.424087 -21.486088)
			(xy 375.47893 -21.475958) (xy 375.534664 -21.473921) (xy 375.590101 -21.480021) (xy 375.644058 -21.494127)
			(xy 375.695387 -21.515939) (xy 375.742993 -21.544993) (xy 375.785861 -21.580668) (xy 375.823078 -21.622205)
			(xy 375.853851 -21.668718) (xy 375.877523 -21.719215) (xy 375.893591 -21.772622) (xy 375.901711 -21.827798)
			(xy 375.902062 -21.847048) (xy 376.37288 -21.847048) (xy 376.376951 -21.791426) (xy 376.389077 -21.736989)
			(xy 376.409 -21.684898) (xy 376.436296 -21.636263) (xy 376.470382 -21.59212) (xy 376.510531 -21.553411)
			(xy 376.555889 -21.52096) (xy 376.605489 -21.495459) (xy 376.658273 -21.477452) (xy 376.713116 -21.467322)
			(xy 376.76885 -21.465285) (xy 376.824287 -21.471385) (xy 376.878244 -21.485491) (xy 376.929573 -21.507303)
			(xy 376.977179 -21.536357) (xy 377.020047 -21.572032) (xy 377.057264 -21.613569) (xy 377.088037 -21.660082)
			(xy 377.111709 -21.710579) (xy 377.127777 -21.763986) (xy 377.135897 -21.819162) (xy 377.136406 -21.847048)
			(xy 377.135897 -21.874934) (xy 377.127777 -21.93011) (xy 377.111709 -21.983517) (xy 377.088037 -22.034014)
			(xy 377.057264 -22.080527) (xy 377.020047 -22.122064) (xy 376.977179 -22.157739) (xy 376.929573 -22.186793)
			(xy 376.878244 -22.208605) (xy 376.824287 -22.222711) (xy 376.76885 -22.228811) (xy 376.713116 -22.226774)
			(xy 376.658273 -22.216644) (xy 376.605489 -22.198637) (xy 376.555889 -22.173136) (xy 376.510531 -22.140685)
			(xy 376.470382 -22.101976) (xy 376.436296 -22.057833) (xy 376.409 -22.009198) (xy 376.389077 -21.957107)
			(xy 376.376951 -21.90267) (xy 376.37288 -21.847048) (xy 375.902062 -21.847048) (xy 375.90222 -21.855684)
			(xy 375.901711 -21.88357) (xy 375.893591 -21.938746) (xy 375.877523 -21.992153) (xy 375.853851 -22.04265)
			(xy 375.823078 -22.089163) (xy 375.785861 -22.1307) (xy 375.742993 -22.166375) (xy 375.695387 -22.195429)
			(xy 375.644058 -22.217241) (xy 375.590101 -22.231347) (xy 375.534664 -22.237447) (xy 375.47893 -22.23541)
			(xy 375.424087 -22.22528) (xy 375.371303 -22.207273) (xy 375.321703 -22.181772) (xy 375.276345 -22.149321)
			(xy 375.236196 -22.110612) (xy 375.20211 -22.066469) (xy 375.174814 -22.017834) (xy 375.154891 -21.965743)
			(xy 375.142765 -21.911306) (xy 375.138694 -21.855684) (xy 374.991324 -21.855684) (xy 374.990875 -21.858736)
			(xy 374.974807 -21.912143) (xy 374.951135 -21.96264) (xy 374.920362 -22.009153) (xy 374.883145 -22.05069)
			(xy 374.840277 -22.086365) (xy 374.792671 -22.115419) (xy 374.741342 -22.137231) (xy 374.687385 -22.151337)
			(xy 374.631948 -22.157437) (xy 374.576214 -22.1554) (xy 374.521371 -22.14527) (xy 374.468587 -22.127263)
			(xy 374.418987 -22.101762) (xy 374.373629 -22.069311) (xy 374.33348 -22.030602) (xy 374.299394 -21.986459)
			(xy 374.272098 -21.937824) (xy 374.252175 -21.885733) (xy 374.240049 -21.831296) (xy 374.235978 -21.775674)
			(xy 365.111899 -21.775674) (xy 365.090699 -21.822093) (xy 365.061233 -21.867943) (xy 365.025542 -21.909134)
			(xy 364.984351 -21.944825) (xy 364.938501 -21.974291) (xy 364.888924 -21.996933) (xy 364.836629 -22.012288)
			(xy 364.782681 -22.020044) (xy 364.728179 -22.020044) (xy 364.674231 -22.012288) (xy 364.621936 -21.996933)
			(xy 364.572359 -21.974291) (xy 364.526509 -21.944825) (xy 364.485318 -21.909134) (xy 364.449627 -21.867943)
			(xy 364.420161 -21.822093) (xy 364.397519 -21.772516) (xy 364.382164 -21.720221) (xy 364.374408 -21.666273)
			(xy 364.373922 -21.639022) (xy 357.543505 -21.639022) (xy 357.530308 -21.668025) (xy 357.469263 -21.783021)
			(xy 357.401322 -21.894082) (xy 357.326736 -22.000794) (xy 357.245783 -22.102761) (xy 357.158764 -22.199603)
			(xy 357.066003 -22.29096) (xy 356.967845 -22.376492) (xy 356.864656 -22.45588) (xy 356.756819 -22.52883)
			(xy 356.711769 -22.555454) (xy 373.636538 -22.555454) (xy 373.640609 -22.499832) (xy 373.652735 -22.445395)
			(xy 373.672658 -22.393304) (xy 373.699954 -22.344669) (xy 373.73404 -22.300526) (xy 373.774189 -22.261817)
			(xy 373.819547 -22.229366) (xy 373.869147 -22.203865) (xy 373.921931 -22.185858) (xy 373.976774 -22.175728)
			(xy 374.032508 -22.173691) (xy 374.087945 -22.179791) (xy 374.141902 -22.193897) (xy 374.193231 -22.215709)
			(xy 374.240837 -22.244763) (xy 374.283705 -22.280438) (xy 374.320922 -22.321975) (xy 374.351695 -22.368488)
			(xy 374.375367 -22.418985) (xy 374.391435 -22.472392) (xy 374.399555 -22.527568) (xy 374.400064 -22.555454)
			(xy 374.399555 -22.58334) (xy 374.391435 -22.638516) (xy 374.375367 -22.691923) (xy 374.351695 -22.74242)
			(xy 374.320922 -22.788933) (xy 374.283705 -22.83047) (xy 374.240837 -22.866145) (xy 374.193231 -22.895199)
			(xy 374.141902 -22.917011) (xy 374.087945 -22.931117) (xy 374.032508 -22.937217) (xy 373.976774 -22.93518)
			(xy 373.921931 -22.92505) (xy 373.869147 -22.907043) (xy 373.819547 -22.881542) (xy 373.774189 -22.849091)
			(xy 373.73404 -22.810382) (xy 373.699954 -22.766239) (xy 373.672658 -22.717604) (xy 373.652735 -22.665513)
			(xy 373.640609 -22.611076) (xy 373.636538 -22.555454) (xy 356.711769 -22.555454) (xy 356.644734 -22.595071)
			(xy 356.528821 -22.654354) (xy 356.409508 -22.706462) (xy 356.287241 -22.751198) (xy 356.162474 -22.788397)
			(xy 356.035671 -22.817921) (xy 355.907304 -22.839659) (xy 355.777851 -22.853532) (xy 355.647792 -22.859486)
			(xy 355.517613 -22.857501) (xy 355.387797 -22.847583) (xy 355.258827 -22.829769) (xy 355.131182 -22.804126)
			(xy 355.005339 -22.770749) (xy 354.881764 -22.729762) (xy 354.760918 -22.681318) (xy 354.64325 -22.625596)
			(xy 354.529198 -22.562805) (xy 354.419186 -22.493178) (xy 354.313624 -22.416973) (xy 354.212904 -22.334474)
			(xy 354.1174 -22.245989) (xy 354.027468 -22.151846) (xy 353.943443 -22.052395) (xy 353.865638 -21.948007)
			(xy 353.794341 -21.83907) (xy 353.729817 -21.725988) (xy 353.672308 -21.609184) (xy 353.622026 -21.489091)
			(xy 353.57916 -21.366155) (xy 353.543867 -21.240836) (xy 353.516281 -21.113597) (xy 353.496502 -20.984914)
			(xy 353.484606 -20.855264) (xy 353.480636 -20.72513) (xy 326.919844 -20.72513) (xy 326.919844 -20.780756)
			(xy 326.926956 -20.79879) (xy 326.93356 -20.805648) (xy 326.952837 -20.826969) (xy 326.985404 -20.874332)
			(xy 327.010496 -20.926045) (xy 327.027547 -20.980937) (xy 327.036169 -21.037765) (xy 327.036168 -21.095244)
			(xy 327.027545 -21.152072) (xy 327.010493 -21.206963) (xy 326.985399 -21.258675) (xy 326.952832 -21.306038)
			(xy 326.93356 -21.327364) (xy 326.926956 -21.334222) (xy 326.919844 -21.352256) (xy 326.919844 -21.441156)
			(xy 326.926956 -21.45919) (xy 326.93356 -21.466048) (xy 326.952833 -21.487373) (xy 326.985399 -21.534735)
			(xy 327.010491 -21.586448) (xy 327.027541 -21.641339) (xy 327.036163 -21.698167) (xy 327.036684 -21.726906)
			(xy 327.036198 -21.754157) (xy 327.028442 -21.808105) (xy 327.013087 -21.8604) (xy 326.990445 -21.909977)
			(xy 326.960979 -21.955827) (xy 326.925288 -21.997018) (xy 326.884097 -22.032709) (xy 326.838247 -22.062175)
			(xy 326.78867 -22.084817) (xy 326.736375 -22.100172) (xy 326.682427 -22.107928) (xy 326.627925 -22.107928)
			(xy 326.573977 -22.100172) (xy 326.521682 -22.084817) (xy 326.472105 -22.062175) (xy 326.426255 -22.032709)
			(xy 326.385064 -21.997018) (xy 326.349373 -21.955827) (xy 326.319907 -21.909977) (xy 326.297265 -21.8604)
			(xy 326.28191 -21.808105) (xy 326.274154 -21.754157) (xy 326.273668 -21.726906) (xy 319.399051 -21.726906)
			(xy 319.369263 -21.783021) (xy 319.301322 -21.894082) (xy 319.226736 -22.000794) (xy 319.145783 -22.102761)
			(xy 319.058764 -22.199603) (xy 318.966003 -22.29096) (xy 318.867845 -22.376492) (xy 318.764656 -22.45588)
			(xy 318.656819 -22.52883) (xy 318.544734 -22.595071) (xy 318.428821 -22.654354) (xy 318.309508 -22.706462)
			(xy 318.187241 -22.751198) (xy 318.062474 -22.788397) (xy 317.935671 -22.817921) (xy 317.807304 -22.839659)
			(xy 317.677851 -22.853532) (xy 317.547792 -22.859486) (xy 317.417613 -22.857501) (xy 317.287797 -22.847583)
			(xy 317.158827 -22.829769) (xy 317.031182 -22.804126) (xy 316.905339 -22.770749) (xy 316.781764 -22.729762)
			(xy 316.660918 -22.681318) (xy 316.54325 -22.625596) (xy 316.429198 -22.562805) (xy 316.319186 -22.493178)
			(xy 316.213624 -22.416973) (xy 316.112904 -22.334474) (xy 316.0174 -22.245989) (xy 315.927468 -22.151846)
			(xy 315.843443 -22.052395) (xy 315.765638 -21.948007) (xy 315.694341 -21.83907) (xy 315.629817 -21.725988)
			(xy 315.572308 -21.609184) (xy 315.522026 -21.489091) (xy 315.47916 -21.366155) (xy 315.443867 -21.240836)
			(xy 315.416281 -21.113597) (xy 315.396502 -20.984914) (xy 315.384606 -20.855264) (xy 315.380636 -20.72513)
			(xy 309.150127 -20.72513) (xy 309.134483 -20.74259) (xy 309.091615 -20.778265) (xy 309.044009 -20.807319)
			(xy 308.99268 -20.829131) (xy 308.938723 -20.843237) (xy 308.883286 -20.849337) (xy 308.827552 -20.8473)
			(xy 308.772709 -20.83717) (xy 308.719925 -20.819163) (xy 308.670325 -20.793662) (xy 308.624967 -20.761211)
			(xy 308.584818 -20.722502) (xy 308.550732 -20.678359) (xy 308.523436 -20.629724) (xy 308.503513 -20.577633)
			(xy 308.491387 -20.523196) (xy 308.487316 -20.467574) (xy 301.006223 -20.467574) (xy 300.985448 -20.510389)
			(xy 300.952883 -20.557752) (xy 300.933612 -20.57908) (xy 300.927008 -20.585938) (xy 300.919896 -20.603972)
			(xy 300.919896 -20.692872) (xy 300.927008 -20.710906) (xy 300.933612 -20.717764) (xy 300.952903 -20.739073)
			(xy 300.985465 -20.786439) (xy 301.010552 -20.838154) (xy 301.027599 -20.893047) (xy 301.036219 -20.949876)
			(xy 301.036216 -21.007356) (xy 301.027592 -21.064184) (xy 301.010541 -21.119076) (xy 300.985448 -21.170789)
			(xy 300.952883 -21.218152) (xy 300.933612 -21.23948) (xy 300.927008 -21.246338) (xy 300.919896 -21.264372)
			(xy 300.919896 -21.353272) (xy 300.927008 -21.371306) (xy 300.933612 -21.378164) (xy 300.952885 -21.399489)
			(xy 300.985453 -21.446851) (xy 301.010546 -21.498563) (xy 301.027596 -21.553454) (xy 301.036217 -21.610283)
			(xy 301.036736 -21.639022) (xy 301.03625 -21.666273) (xy 301.028494 -21.720221) (xy 301.013139 -21.772516)
			(xy 301.011697 -21.775674) (xy 310.135776 -21.775674) (xy 310.139847 -21.720052) (xy 310.151973 -21.665615)
			(xy 310.171896 -21.613524) (xy 310.199192 -21.564889) (xy 310.233278 -21.520746) (xy 310.273427 -21.482037)
			(xy 310.318785 -21.449586) (xy 310.368385 -21.424085) (xy 310.421169 -21.406078) (xy 310.476012 -21.395948)
			(xy 310.531746 -21.393911) (xy 310.587183 -21.400011) (xy 310.64114 -21.414117) (xy 310.692469 -21.435929)
			(xy 310.740075 -21.464983) (xy 310.782943 -21.500658) (xy 310.82016 -21.542195) (xy 310.850933 -21.588708)
			(xy 310.874605 -21.639205) (xy 310.890673 -21.692612) (xy 310.898793 -21.747788) (xy 310.899302 -21.775674)
			(xy 310.898793 -21.80356) (xy 310.891122 -21.855684) (xy 311.038492 -21.855684) (xy 311.042563 -21.800062)
			(xy 311.054689 -21.745625) (xy 311.074612 -21.693534) (xy 311.101908 -21.644899) (xy 311.135994 -21.600756)
			(xy 311.176143 -21.562047) (xy 311.221501 -21.529596) (xy 311.271101 -21.504095) (xy 311.323885 -21.486088)
			(xy 311.378728 -21.475958) (xy 311.434462 -21.473921) (xy 311.489899 -21.480021) (xy 311.543856 -21.494127)
			(xy 311.595185 -21.515939) (xy 311.642791 -21.544993) (xy 311.685659 -21.580668) (xy 311.722876 -21.622205)
			(xy 311.753649 -21.668718) (xy 311.777321 -21.719215) (xy 311.793389 -21.772622) (xy 311.801509 -21.827798)
			(xy 311.80186 -21.847048) (xy 312.272678 -21.847048) (xy 312.276749 -21.791426) (xy 312.288875 -21.736989)
			(xy 312.308798 -21.684898) (xy 312.336094 -21.636263) (xy 312.37018 -21.59212) (xy 312.410329 -21.553411)
			(xy 312.455687 -21.52096) (xy 312.505287 -21.495459) (xy 312.558071 -21.477452) (xy 312.612914 -21.467322)
			(xy 312.668648 -21.465285) (xy 312.724085 -21.471385) (xy 312.778042 -21.485491) (xy 312.829371 -21.507303)
			(xy 312.876977 -21.536357) (xy 312.919845 -21.572032) (xy 312.957062 -21.613569) (xy 312.987835 -21.660082)
			(xy 313.011507 -21.710579) (xy 313.027575 -21.763986) (xy 313.035695 -21.819162) (xy 313.036204 -21.847048)
			(xy 313.035695 -21.874934) (xy 313.027575 -21.93011) (xy 313.011507 -21.983517) (xy 312.987835 -22.034014)
			(xy 312.957062 -22.080527) (xy 312.919845 -22.122064) (xy 312.876977 -22.157739) (xy 312.829371 -22.186793)
			(xy 312.778042 -22.208605) (xy 312.724085 -22.222711) (xy 312.668648 -22.228811) (xy 312.612914 -22.226774)
			(xy 312.558071 -22.216644) (xy 312.505287 -22.198637) (xy 312.455687 -22.173136) (xy 312.410329 -22.140685)
			(xy 312.37018 -22.101976) (xy 312.336094 -22.057833) (xy 312.308798 -22.009198) (xy 312.288875 -21.957107)
			(xy 312.276749 -21.90267) (xy 312.272678 -21.847048) (xy 311.80186 -21.847048) (xy 311.802018 -21.855684)
			(xy 311.801509 -21.88357) (xy 311.793389 -21.938746) (xy 311.777321 -21.992153) (xy 311.753649 -22.04265)
			(xy 311.722876 -22.089163) (xy 311.685659 -22.1307) (xy 311.642791 -22.166375) (xy 311.595185 -22.195429)
			(xy 311.543856 -22.217241) (xy 311.489899 -22.231347) (xy 311.434462 -22.237447) (xy 311.378728 -22.23541)
			(xy 311.323885 -22.22528) (xy 311.271101 -22.207273) (xy 311.221501 -22.181772) (xy 311.176143 -22.149321)
			(xy 311.135994 -22.110612) (xy 311.101908 -22.066469) (xy 311.074612 -22.017834) (xy 311.054689 -21.965743)
			(xy 311.042563 -21.911306) (xy 311.038492 -21.855684) (xy 310.891122 -21.855684) (xy 310.890673 -21.858736)
			(xy 310.874605 -21.912143) (xy 310.850933 -21.96264) (xy 310.82016 -22.009153) (xy 310.782943 -22.05069)
			(xy 310.740075 -22.086365) (xy 310.692469 -22.115419) (xy 310.64114 -22.137231) (xy 310.587183 -22.151337)
			(xy 310.531746 -22.157437) (xy 310.476012 -22.1554) (xy 310.421169 -22.14527) (xy 310.368385 -22.127263)
			(xy 310.318785 -22.101762) (xy 310.273427 -22.069311) (xy 310.233278 -22.030602) (xy 310.199192 -21.986459)
			(xy 310.171896 -21.937824) (xy 310.151973 -21.885733) (xy 310.139847 -21.831296) (xy 310.135776 -21.775674)
			(xy 301.011697 -21.775674) (xy 300.990497 -21.822093) (xy 300.961031 -21.867943) (xy 300.92534 -21.909134)
			(xy 300.884149 -21.944825) (xy 300.838299 -21.974291) (xy 300.788722 -21.996933) (xy 300.736427 -22.012288)
			(xy 300.682479 -22.020044) (xy 300.627977 -22.020044) (xy 300.574029 -22.012288) (xy 300.521734 -21.996933)
			(xy 300.472157 -21.974291) (xy 300.426307 -21.944825) (xy 300.385116 -21.909134) (xy 300.349425 -21.867943)
			(xy 300.319959 -21.822093) (xy 300.297317 -21.772516) (xy 300.281962 -21.720221) (xy 300.274206 -21.666273)
			(xy 300.27372 -21.639022) (xy 293.443303 -21.639022) (xy 293.430106 -21.668025) (xy 293.369061 -21.783021)
			(xy 293.30112 -21.894082) (xy 293.226534 -22.000794) (xy 293.145581 -22.102761) (xy 293.058562 -22.199603)
			(xy 292.965801 -22.29096) (xy 292.867643 -22.376492) (xy 292.764454 -22.45588) (xy 292.656617 -22.52883)
			(xy 292.611567 -22.555454) (xy 309.536336 -22.555454) (xy 309.540407 -22.499832) (xy 309.552533 -22.445395)
			(xy 309.572456 -22.393304) (xy 309.599752 -22.344669) (xy 309.633838 -22.300526) (xy 309.673987 -22.261817)
			(xy 309.719345 -22.229366) (xy 309.768945 -22.203865) (xy 309.821729 -22.185858) (xy 309.876572 -22.175728)
			(xy 309.932306 -22.173691) (xy 309.987743 -22.179791) (xy 310.0417 -22.193897) (xy 310.093029 -22.215709)
			(xy 310.140635 -22.244763) (xy 310.183503 -22.280438) (xy 310.22072 -22.321975) (xy 310.251493 -22.368488)
			(xy 310.275165 -22.418985) (xy 310.291233 -22.472392) (xy 310.299353 -22.527568) (xy 310.299862 -22.555454)
			(xy 310.299353 -22.58334) (xy 310.291233 -22.638516) (xy 310.275165 -22.691923) (xy 310.251493 -22.74242)
			(xy 310.22072 -22.788933) (xy 310.183503 -22.83047) (xy 310.140635 -22.866145) (xy 310.093029 -22.895199)
			(xy 310.0417 -22.917011) (xy 309.987743 -22.931117) (xy 309.932306 -22.937217) (xy 309.876572 -22.93518)
			(xy 309.821729 -22.92505) (xy 309.768945 -22.907043) (xy 309.719345 -22.881542) (xy 309.673987 -22.849091)
			(xy 309.633838 -22.810382) (xy 309.599752 -22.766239) (xy 309.572456 -22.717604) (xy 309.552533 -22.665513)
			(xy 309.540407 -22.611076) (xy 309.536336 -22.555454) (xy 292.611567 -22.555454) (xy 292.544532 -22.595071)
			(xy 292.428619 -22.654354) (xy 292.309306 -22.706462) (xy 292.187039 -22.751198) (xy 292.062272 -22.788397)
			(xy 291.935469 -22.817921) (xy 291.807102 -22.839659) (xy 291.677649 -22.853532) (xy 291.54759 -22.859486)
			(xy 291.417411 -22.857501) (xy 291.287595 -22.847583) (xy 291.158625 -22.829769) (xy 291.03098 -22.804126)
			(xy 290.905137 -22.770749) (xy 290.781562 -22.729762) (xy 290.660716 -22.681318) (xy 290.543048 -22.625596)
			(xy 290.428996 -22.562805) (xy 290.318984 -22.493178) (xy 290.213422 -22.416973) (xy 290.112702 -22.334474)
			(xy 290.017198 -22.245989) (xy 289.927266 -22.151846) (xy 289.843241 -22.052395) (xy 289.765436 -21.948007)
			(xy 289.694139 -21.83907) (xy 289.629615 -21.725988) (xy 289.572106 -21.609184) (xy 289.521824 -21.489091)
			(xy 289.478958 -21.366155) (xy 289.443665 -21.240836) (xy 289.416079 -21.113597) (xy 289.3963 -20.984914)
			(xy 289.384404 -20.855264) (xy 289.380434 -20.72513) (xy 283.150179 -20.72513) (xy 283.134535 -20.74259)
			(xy 283.091667 -20.778265) (xy 283.044061 -20.807319) (xy 282.992732 -20.829131) (xy 282.938775 -20.843237)
			(xy 282.883338 -20.849337) (xy 282.827604 -20.8473) (xy 282.772761 -20.83717) (xy 282.719977 -20.819163)
			(xy 282.670377 -20.793662) (xy 282.625019 -20.761211) (xy 282.58487 -20.722502) (xy 282.550784 -20.678359)
			(xy 282.523488 -20.629724) (xy 282.503565 -20.577633) (xy 282.491439 -20.523196) (xy 282.487368 -20.467574)
			(xy 275.006285 -20.467574) (xy 274.985506 -20.510391) (xy 274.952937 -20.557753) (xy 274.933664 -20.57908)
			(xy 274.92706 -20.585938) (xy 274.919948 -20.603972) (xy 274.919948 -20.692872) (xy 274.92706 -20.710906)
			(xy 274.933664 -20.717764) (xy 274.952957 -20.739072) (xy 274.985523 -20.786437) (xy 275.010614 -20.838152)
			(xy 275.027663 -20.893046) (xy 275.036284 -20.949876) (xy 275.036281 -21.007356) (xy 275.027656 -21.064186)
			(xy 275.010602 -21.119078) (xy 274.985506 -21.170791) (xy 274.952937 -21.218153) (xy 274.933664 -21.23948)
			(xy 274.92706 -21.246338) (xy 274.919948 -21.264372) (xy 274.919948 -21.353272) (xy 274.92706 -21.371306)
			(xy 274.933664 -21.378164) (xy 274.952945 -21.399482) (xy 274.98551 -21.446846) (xy 275.010601 -21.49856)
			(xy 275.027649 -21.553453) (xy 275.036269 -21.610282) (xy 275.036788 -21.639022) (xy 275.036302 -21.666273)
			(xy 275.028546 -21.720221) (xy 275.013191 -21.772516) (xy 275.011749 -21.775674) (xy 284.135828 -21.775674)
			(xy 284.139899 -21.720052) (xy 284.152025 -21.665615) (xy 284.171948 -21.613524) (xy 284.199244 -21.564889)
			(xy 284.23333 -21.520746) (xy 284.273479 -21.482037) (xy 284.318837 -21.449586) (xy 284.368437 -21.424085)
			(xy 284.421221 -21.406078) (xy 284.476064 -21.395948) (xy 284.531798 -21.393911) (xy 284.587235 -21.400011)
			(xy 284.641192 -21.414117) (xy 284.692521 -21.435929) (xy 284.740127 -21.464983) (xy 284.782995 -21.500658)
			(xy 284.820212 -21.542195) (xy 284.850985 -21.588708) (xy 284.874657 -21.639205) (xy 284.890725 -21.692612)
			(xy 284.898845 -21.747788) (xy 284.899354 -21.775674) (xy 284.898845 -21.80356) (xy 284.891174 -21.855684)
			(xy 285.038544 -21.855684) (xy 285.042615 -21.800062) (xy 285.054741 -21.745625) (xy 285.074664 -21.693534)
			(xy 285.10196 -21.644899) (xy 285.136046 -21.600756) (xy 285.176195 -21.562047) (xy 285.221553 -21.529596)
			(xy 285.271153 -21.504095) (xy 285.323937 -21.486088) (xy 285.37878 -21.475958) (xy 285.434514 -21.473921)
			(xy 285.489951 -21.480021) (xy 285.543908 -21.494127) (xy 285.595237 -21.515939) (xy 285.642843 -21.544993)
			(xy 285.685711 -21.580668) (xy 285.722928 -21.622205) (xy 285.753701 -21.668718) (xy 285.777373 -21.719215)
			(xy 285.793441 -21.772622) (xy 285.801561 -21.827798) (xy 285.801912 -21.847048) (xy 286.27273 -21.847048)
			(xy 286.276801 -21.791426) (xy 286.288927 -21.736989) (xy 286.30885 -21.684898) (xy 286.336146 -21.636263)
			(xy 286.370232 -21.59212) (xy 286.410381 -21.553411) (xy 286.455739 -21.52096) (xy 286.505339 -21.495459)
			(xy 286.558123 -21.477452) (xy 286.612966 -21.467322) (xy 286.6687 -21.465285) (xy 286.724137 -21.471385)
			(xy 286.778094 -21.485491) (xy 286.829423 -21.507303) (xy 286.877029 -21.536357) (xy 286.919897 -21.572032)
			(xy 286.957114 -21.613569) (xy 286.987887 -21.660082) (xy 287.011559 -21.710579) (xy 287.027627 -21.763986)
			(xy 287.035747 -21.819162) (xy 287.036256 -21.847048) (xy 287.035747 -21.874934) (xy 287.027627 -21.93011)
			(xy 287.011559 -21.983517) (xy 286.987887 -22.034014) (xy 286.957114 -22.080527) (xy 286.919897 -22.122064)
			(xy 286.877029 -22.157739) (xy 286.829423 -22.186793) (xy 286.778094 -22.208605) (xy 286.724137 -22.222711)
			(xy 286.6687 -22.228811) (xy 286.612966 -22.226774) (xy 286.558123 -22.216644) (xy 286.505339 -22.198637)
			(xy 286.455739 -22.173136) (xy 286.410381 -22.140685) (xy 286.370232 -22.101976) (xy 286.336146 -22.057833)
			(xy 286.30885 -22.009198) (xy 286.288927 -21.957107) (xy 286.276801 -21.90267) (xy 286.27273 -21.847048)
			(xy 285.801912 -21.847048) (xy 285.80207 -21.855684) (xy 285.801561 -21.88357) (xy 285.793441 -21.938746)
			(xy 285.777373 -21.992153) (xy 285.753701 -22.04265) (xy 285.722928 -22.089163) (xy 285.685711 -22.1307)
			(xy 285.642843 -22.166375) (xy 285.595237 -22.195429) (xy 285.543908 -22.217241) (xy 285.489951 -22.231347)
			(xy 285.434514 -22.237447) (xy 285.37878 -22.23541) (xy 285.323937 -22.22528) (xy 285.271153 -22.207273)
			(xy 285.221553 -22.181772) (xy 285.176195 -22.149321) (xy 285.136046 -22.110612) (xy 285.10196 -22.066469)
			(xy 285.074664 -22.017834) (xy 285.054741 -21.965743) (xy 285.042615 -21.911306) (xy 285.038544 -21.855684)
			(xy 284.891174 -21.855684) (xy 284.890725 -21.858736) (xy 284.874657 -21.912143) (xy 284.850985 -21.96264)
			(xy 284.820212 -22.009153) (xy 284.782995 -22.05069) (xy 284.740127 -22.086365) (xy 284.692521 -22.115419)
			(xy 284.641192 -22.137231) (xy 284.587235 -22.151337) (xy 284.531798 -22.157437) (xy 284.476064 -22.1554)
			(xy 284.421221 -22.14527) (xy 284.368437 -22.127263) (xy 284.318837 -22.101762) (xy 284.273479 -22.069311)
			(xy 284.23333 -22.030602) (xy 284.199244 -21.986459) (xy 284.171948 -21.937824) (xy 284.152025 -21.885733)
			(xy 284.139899 -21.831296) (xy 284.135828 -21.775674) (xy 275.011749 -21.775674) (xy 274.990549 -21.822093)
			(xy 274.961083 -21.867943) (xy 274.925392 -21.909134) (xy 274.884201 -21.944825) (xy 274.838351 -21.974291)
			(xy 274.788774 -21.996933) (xy 274.736479 -22.012288) (xy 274.682531 -22.020044) (xy 274.628029 -22.020044)
			(xy 274.574081 -22.012288) (xy 274.521786 -21.996933) (xy 274.472209 -21.974291) (xy 274.426359 -21.944825)
			(xy 274.385168 -21.909134) (xy 274.349477 -21.867943) (xy 274.320011 -21.822093) (xy 274.297369 -21.772516)
			(xy 274.282014 -21.720221) (xy 274.274258 -21.666273) (xy 274.273772 -21.639022) (xy 267.443355 -21.639022)
			(xy 267.430158 -21.668025) (xy 267.369113 -21.783021) (xy 267.301172 -21.894082) (xy 267.226586 -22.000794)
			(xy 267.145633 -22.102761) (xy 267.058614 -22.199603) (xy 266.965853 -22.29096) (xy 266.867695 -22.376492)
			(xy 266.764506 -22.45588) (xy 266.656669 -22.52883) (xy 266.611619 -22.555454) (xy 283.536388 -22.555454)
			(xy 283.540459 -22.499832) (xy 283.552585 -22.445395) (xy 283.572508 -22.393304) (xy 283.599804 -22.344669)
			(xy 283.63389 -22.300526) (xy 283.674039 -22.261817) (xy 283.719397 -22.229366) (xy 283.768997 -22.203865)
			(xy 283.821781 -22.185858) (xy 283.876624 -22.175728) (xy 283.932358 -22.173691) (xy 283.987795 -22.179791)
			(xy 284.041752 -22.193897) (xy 284.093081 -22.215709) (xy 284.140687 -22.244763) (xy 284.183555 -22.280438)
			(xy 284.220772 -22.321975) (xy 284.251545 -22.368488) (xy 284.275217 -22.418985) (xy 284.291285 -22.472392)
			(xy 284.299405 -22.527568) (xy 284.299914 -22.555454) (xy 284.299405 -22.58334) (xy 284.291285 -22.638516)
			(xy 284.275217 -22.691923) (xy 284.251545 -22.74242) (xy 284.220772 -22.788933) (xy 284.183555 -22.83047)
			(xy 284.140687 -22.866145) (xy 284.093081 -22.895199) (xy 284.041752 -22.917011) (xy 283.987795 -22.931117)
			(xy 283.932358 -22.937217) (xy 283.876624 -22.93518) (xy 283.821781 -22.92505) (xy 283.768997 -22.907043)
			(xy 283.719397 -22.881542) (xy 283.674039 -22.849091) (xy 283.63389 -22.810382) (xy 283.599804 -22.766239)
			(xy 283.572508 -22.717604) (xy 283.552585 -22.665513) (xy 283.540459 -22.611076) (xy 283.536388 -22.555454)
			(xy 266.611619 -22.555454) (xy 266.544584 -22.595071) (xy 266.428671 -22.654354) (xy 266.309358 -22.706462)
			(xy 266.187091 -22.751198) (xy 266.062324 -22.788397) (xy 265.935521 -22.817921) (xy 265.807154 -22.839659)
			(xy 265.677701 -22.853532) (xy 265.547642 -22.859486) (xy 265.417463 -22.857501) (xy 265.287647 -22.847583)
			(xy 265.158677 -22.829769) (xy 265.031032 -22.804126) (xy 264.905189 -22.770749) (xy 264.781614 -22.729762)
			(xy 264.660768 -22.681318) (xy 264.5431 -22.625596) (xy 264.429048 -22.562805) (xy 264.319036 -22.493178)
			(xy 264.213474 -22.416973) (xy 264.112754 -22.334474) (xy 264.01725 -22.245989) (xy 263.927318 -22.151846)
			(xy 263.843293 -22.052395) (xy 263.765488 -21.948007) (xy 263.694191 -21.83907) (xy 263.629667 -21.725988)
			(xy 263.572158 -21.609184) (xy 263.521876 -21.489091) (xy 263.47901 -21.366155) (xy 263.443717 -21.240836)
			(xy 263.416131 -21.113597) (xy 263.396352 -20.984914) (xy 263.384456 -20.855264) (xy 263.380486 -20.72513)
			(xy 257.150231 -20.72513) (xy 257.134587 -20.74259) (xy 257.091719 -20.778265) (xy 257.044113 -20.807319)
			(xy 256.992784 -20.829131) (xy 256.938827 -20.843237) (xy 256.88339 -20.849337) (xy 256.827656 -20.8473)
			(xy 256.772813 -20.83717) (xy 256.720029 -20.819163) (xy 256.670429 -20.793662) (xy 256.625071 -20.761211)
			(xy 256.584922 -20.722502) (xy 256.550836 -20.678359) (xy 256.52354 -20.629724) (xy 256.503617 -20.577633)
			(xy 256.491491 -20.523196) (xy 256.48742 -20.467574) (xy 249.006326 -20.467574) (xy 248.985552 -20.510388)
			(xy 248.952987 -20.557752) (xy 248.933716 -20.57908) (xy 248.927112 -20.585938) (xy 248.92 -20.603972)
			(xy 248.92 -20.692872) (xy 248.927112 -20.710906) (xy 248.933716 -20.717764) (xy 248.953007 -20.739073)
			(xy 248.985568 -20.786439) (xy 249.010656 -20.838154) (xy 249.027702 -20.893048) (xy 249.036322 -20.949877)
			(xy 249.036319 -21.007356) (xy 249.027695 -21.064184) (xy 249.010644 -21.119075) (xy 248.985552 -21.170788)
			(xy 248.952987 -21.218152) (xy 248.933716 -21.23948) (xy 248.927112 -21.246338) (xy 248.92 -21.264372)
			(xy 248.92 -21.353272) (xy 248.927112 -21.371306) (xy 248.933716 -21.378164) (xy 248.95299 -21.399489)
			(xy 248.985557 -21.446851) (xy 249.01065 -21.498563) (xy 249.0277 -21.553454) (xy 249.036321 -21.610283)
			(xy 249.03684 -21.639022) (xy 249.036354 -21.666273) (xy 249.028598 -21.720221) (xy 249.013243 -21.772516)
			(xy 249.011801 -21.775674) (xy 258.13588 -21.775674) (xy 258.139951 -21.720052) (xy 258.152077 -21.665615)
			(xy 258.172 -21.613524) (xy 258.199296 -21.564889) (xy 258.233382 -21.520746) (xy 258.273531 -21.482037)
			(xy 258.318889 -21.449586) (xy 258.368489 -21.424085) (xy 258.421273 -21.406078) (xy 258.476116 -21.395948)
			(xy 258.53185 -21.393911) (xy 258.587287 -21.400011) (xy 258.641244 -21.414117) (xy 258.692573 -21.435929)
			(xy 258.740179 -21.464983) (xy 258.783047 -21.500658) (xy 258.820264 -21.542195) (xy 258.851037 -21.588708)
			(xy 258.874709 -21.639205) (xy 258.890777 -21.692612) (xy 258.898897 -21.747788) (xy 258.899406 -21.775674)
			(xy 258.898897 -21.80356) (xy 258.891226 -21.855684) (xy 259.038596 -21.855684) (xy 259.042667 -21.800062)
			(xy 259.054793 -21.745625) (xy 259.074716 -21.693534) (xy 259.102012 -21.644899) (xy 259.136098 -21.600756)
			(xy 259.176247 -21.562047) (xy 259.221605 -21.529596) (xy 259.271205 -21.504095) (xy 259.323989 -21.486088)
			(xy 259.378832 -21.475958) (xy 259.434566 -21.473921) (xy 259.490003 -21.480021) (xy 259.54396 -21.494127)
			(xy 259.595289 -21.515939) (xy 259.642895 -21.544993) (xy 259.685763 -21.580668) (xy 259.72298 -21.622205)
			(xy 259.753753 -21.668718) (xy 259.777425 -21.719215) (xy 259.793493 -21.772622) (xy 259.801613 -21.827798)
			(xy 259.801964 -21.847048) (xy 260.272782 -21.847048) (xy 260.276853 -21.791426) (xy 260.288979 -21.736989)
			(xy 260.308902 -21.684898) (xy 260.336198 -21.636263) (xy 260.370284 -21.59212) (xy 260.410433 -21.553411)
			(xy 260.455791 -21.52096) (xy 260.505391 -21.495459) (xy 260.558175 -21.477452) (xy 260.613018 -21.467322)
			(xy 260.668752 -21.465285) (xy 260.724189 -21.471385) (xy 260.778146 -21.485491) (xy 260.829475 -21.507303)
			(xy 260.877081 -21.536357) (xy 260.919949 -21.572032) (xy 260.957166 -21.613569) (xy 260.987939 -21.660082)
			(xy 261.011611 -21.710579) (xy 261.027679 -21.763986) (xy 261.035799 -21.819162) (xy 261.036308 -21.847048)
			(xy 261.035799 -21.874934) (xy 261.027679 -21.93011) (xy 261.011611 -21.983517) (xy 260.987939 -22.034014)
			(xy 260.957166 -22.080527) (xy 260.919949 -22.122064) (xy 260.877081 -22.157739) (xy 260.829475 -22.186793)
			(xy 260.778146 -22.208605) (xy 260.724189 -22.222711) (xy 260.668752 -22.228811) (xy 260.613018 -22.226774)
			(xy 260.558175 -22.216644) (xy 260.505391 -22.198637) (xy 260.455791 -22.173136) (xy 260.410433 -22.140685)
			(xy 260.370284 -22.101976) (xy 260.336198 -22.057833) (xy 260.308902 -22.009198) (xy 260.288979 -21.957107)
			(xy 260.276853 -21.90267) (xy 260.272782 -21.847048) (xy 259.801964 -21.847048) (xy 259.802122 -21.855684)
			(xy 259.801613 -21.88357) (xy 259.793493 -21.938746) (xy 259.777425 -21.992153) (xy 259.753753 -22.04265)
			(xy 259.72298 -22.089163) (xy 259.685763 -22.1307) (xy 259.642895 -22.166375) (xy 259.595289 -22.195429)
			(xy 259.54396 -22.217241) (xy 259.490003 -22.231347) (xy 259.434566 -22.237447) (xy 259.378832 -22.23541)
			(xy 259.323989 -22.22528) (xy 259.271205 -22.207273) (xy 259.221605 -22.181772) (xy 259.176247 -22.149321)
			(xy 259.136098 -22.110612) (xy 259.102012 -22.066469) (xy 259.074716 -22.017834) (xy 259.054793 -21.965743)
			(xy 259.042667 -21.911306) (xy 259.038596 -21.855684) (xy 258.891226 -21.855684) (xy 258.890777 -21.858736)
			(xy 258.874709 -21.912143) (xy 258.851037 -21.96264) (xy 258.820264 -22.009153) (xy 258.783047 -22.05069)
			(xy 258.740179 -22.086365) (xy 258.692573 -22.115419) (xy 258.641244 -22.137231) (xy 258.587287 -22.151337)
			(xy 258.53185 -22.157437) (xy 258.476116 -22.1554) (xy 258.421273 -22.14527) (xy 258.368489 -22.127263)
			(xy 258.318889 -22.101762) (xy 258.273531 -22.069311) (xy 258.233382 -22.030602) (xy 258.199296 -21.986459)
			(xy 258.172 -21.937824) (xy 258.152077 -21.885733) (xy 258.139951 -21.831296) (xy 258.13588 -21.775674)
			(xy 249.011801 -21.775674) (xy 248.990601 -21.822093) (xy 248.961135 -21.867943) (xy 248.925444 -21.909134)
			(xy 248.884253 -21.944825) (xy 248.838403 -21.974291) (xy 248.788826 -21.996933) (xy 248.736531 -22.012288)
			(xy 248.682583 -22.020044) (xy 248.628081 -22.020044) (xy 248.574133 -22.012288) (xy 248.521838 -21.996933)
			(xy 248.472261 -21.974291) (xy 248.426411 -21.944825) (xy 248.38522 -21.909134) (xy 248.349529 -21.867943)
			(xy 248.320063 -21.822093) (xy 248.297421 -21.772516) (xy 248.282066 -21.720221) (xy 248.27431 -21.666273)
			(xy 248.273824 -21.639022) (xy 241.443407 -21.639022) (xy 241.43021 -21.668025) (xy 241.369165 -21.783021)
			(xy 241.301224 -21.894082) (xy 241.226638 -22.000794) (xy 241.145685 -22.102761) (xy 241.058666 -22.199603)
			(xy 240.965905 -22.29096) (xy 240.867747 -22.376492) (xy 240.764558 -22.45588) (xy 240.656721 -22.52883)
			(xy 240.611671 -22.555454) (xy 257.53644 -22.555454) (xy 257.540511 -22.499832) (xy 257.552637 -22.445395)
			(xy 257.57256 -22.393304) (xy 257.599856 -22.344669) (xy 257.633942 -22.300526) (xy 257.674091 -22.261817)
			(xy 257.719449 -22.229366) (xy 257.769049 -22.203865) (xy 257.821833 -22.185858) (xy 257.876676 -22.175728)
			(xy 257.93241 -22.173691) (xy 257.987847 -22.179791) (xy 258.041804 -22.193897) (xy 258.093133 -22.215709)
			(xy 258.140739 -22.244763) (xy 258.183607 -22.280438) (xy 258.220824 -22.321975) (xy 258.251597 -22.368488)
			(xy 258.275269 -22.418985) (xy 258.291337 -22.472392) (xy 258.299457 -22.527568) (xy 258.299966 -22.555454)
			(xy 258.299457 -22.58334) (xy 258.291337 -22.638516) (xy 258.275269 -22.691923) (xy 258.251597 -22.74242)
			(xy 258.220824 -22.788933) (xy 258.183607 -22.83047) (xy 258.140739 -22.866145) (xy 258.093133 -22.895199)
			(xy 258.041804 -22.917011) (xy 257.987847 -22.931117) (xy 257.93241 -22.937217) (xy 257.876676 -22.93518)
			(xy 257.821833 -22.92505) (xy 257.769049 -22.907043) (xy 257.719449 -22.881542) (xy 257.674091 -22.849091)
			(xy 257.633942 -22.810382) (xy 257.599856 -22.766239) (xy 257.57256 -22.717604) (xy 257.552637 -22.665513)
			(xy 257.540511 -22.611076) (xy 257.53644 -22.555454) (xy 240.611671 -22.555454) (xy 240.544636 -22.595071)
			(xy 240.428723 -22.654354) (xy 240.30941 -22.706462) (xy 240.187143 -22.751198) (xy 240.062376 -22.788397)
			(xy 239.935573 -22.817921) (xy 239.807206 -22.839659) (xy 239.677753 -22.853532) (xy 239.547694 -22.859486)
			(xy 239.417515 -22.857501) (xy 239.287699 -22.847583) (xy 239.158729 -22.829769) (xy 239.031084 -22.804126)
			(xy 238.905241 -22.770749) (xy 238.781666 -22.729762) (xy 238.66082 -22.681318) (xy 238.543152 -22.625596)
			(xy 238.4291 -22.562805) (xy 238.319088 -22.493178) (xy 238.213526 -22.416973) (xy 238.112806 -22.334474)
			(xy 238.017302 -22.245989) (xy 237.92737 -22.151846) (xy 237.843345 -22.052395) (xy 237.76554 -21.948007)
			(xy 237.694243 -21.83907) (xy 237.629719 -21.725988) (xy 237.57221 -21.609184) (xy 237.521928 -21.489091)
			(xy 237.479062 -21.366155) (xy 237.443769 -21.240836) (xy 237.416183 -21.113597) (xy 237.396404 -20.984914)
			(xy 237.384508 -20.855264) (xy 237.380538 -20.72513) (xy 219.050231 -20.72513) (xy 219.034587 -20.74259)
			(xy 218.991719 -20.778265) (xy 218.944113 -20.807319) (xy 218.892784 -20.829131) (xy 218.838827 -20.843237)
			(xy 218.78339 -20.849337) (xy 218.727656 -20.8473) (xy 218.672813 -20.83717) (xy 218.620029 -20.819163)
			(xy 218.570429 -20.793662) (xy 218.525071 -20.761211) (xy 218.484922 -20.722502) (xy 218.450836 -20.678359)
			(xy 218.42354 -20.629724) (xy 218.403617 -20.577633) (xy 218.391491 -20.523196) (xy 218.38742 -20.467574)
			(xy 210.906326 -20.467574) (xy 210.885552 -20.510388) (xy 210.852987 -20.557752) (xy 210.833716 -20.57908)
			(xy 210.827112 -20.585938) (xy 210.82 -20.603972) (xy 210.82 -20.692872) (xy 210.827112 -20.710906)
			(xy 210.833716 -20.717764) (xy 210.853007 -20.739073) (xy 210.885568 -20.786439) (xy 210.910656 -20.838154)
			(xy 210.927702 -20.893048) (xy 210.936322 -20.949877) (xy 210.936319 -21.007356) (xy 210.927695 -21.064184)
			(xy 210.910644 -21.119075) (xy 210.885552 -21.170788) (xy 210.852987 -21.218152) (xy 210.833716 -21.23948)
			(xy 210.827112 -21.246338) (xy 210.82 -21.264372) (xy 210.82 -21.353272) (xy 210.827112 -21.371306)
			(xy 210.833716 -21.378164) (xy 210.85299 -21.399489) (xy 210.885557 -21.446851) (xy 210.91065 -21.498563)
			(xy 210.9277 -21.553454) (xy 210.936321 -21.610283) (xy 210.93684 -21.639022) (xy 210.936354 -21.666273)
			(xy 210.928598 -21.720221) (xy 210.913243 -21.772516) (xy 210.911801 -21.775674) (xy 220.03588 -21.775674)
			(xy 220.039951 -21.720052) (xy 220.052077 -21.665615) (xy 220.072 -21.613524) (xy 220.099296 -21.564889)
			(xy 220.133382 -21.520746) (xy 220.173531 -21.482037) (xy 220.218889 -21.449586) (xy 220.268489 -21.424085)
			(xy 220.321273 -21.406078) (xy 220.376116 -21.395948) (xy 220.43185 -21.393911) (xy 220.487287 -21.400011)
			(xy 220.541244 -21.414117) (xy 220.592573 -21.435929) (xy 220.640179 -21.464983) (xy 220.683047 -21.500658)
			(xy 220.720264 -21.542195) (xy 220.751037 -21.588708) (xy 220.774709 -21.639205) (xy 220.790777 -21.692612)
			(xy 220.798897 -21.747788) (xy 220.799406 -21.775674) (xy 220.798897 -21.80356) (xy 220.791226 -21.855684)
			(xy 220.938596 -21.855684) (xy 220.942667 -21.800062) (xy 220.954793 -21.745625) (xy 220.974716 -21.693534)
			(xy 221.002012 -21.644899) (xy 221.036098 -21.600756) (xy 221.076247 -21.562047) (xy 221.121605 -21.529596)
			(xy 221.171205 -21.504095) (xy 221.223989 -21.486088) (xy 221.278832 -21.475958) (xy 221.334566 -21.473921)
			(xy 221.390003 -21.480021) (xy 221.44396 -21.494127) (xy 221.495289 -21.515939) (xy 221.542895 -21.544993)
			(xy 221.585763 -21.580668) (xy 221.62298 -21.622205) (xy 221.653753 -21.668718) (xy 221.677425 -21.719215)
			(xy 221.693493 -21.772622) (xy 221.701613 -21.827798) (xy 221.701964 -21.847048) (xy 222.172782 -21.847048)
			(xy 222.176853 -21.791426) (xy 222.188979 -21.736989) (xy 222.208902 -21.684898) (xy 222.236198 -21.636263)
			(xy 222.270284 -21.59212) (xy 222.310433 -21.553411) (xy 222.355791 -21.52096) (xy 222.405391 -21.495459)
			(xy 222.458175 -21.477452) (xy 222.513018 -21.467322) (xy 222.568752 -21.465285) (xy 222.624189 -21.471385)
			(xy 222.678146 -21.485491) (xy 222.729475 -21.507303) (xy 222.777081 -21.536357) (xy 222.819949 -21.572032)
			(xy 222.857166 -21.613569) (xy 222.887939 -21.660082) (xy 222.911611 -21.710579) (xy 222.927679 -21.763986)
			(xy 222.935799 -21.819162) (xy 222.936308 -21.847048) (xy 222.935799 -21.874934) (xy 222.927679 -21.93011)
			(xy 222.911611 -21.983517) (xy 222.887939 -22.034014) (xy 222.857166 -22.080527) (xy 222.819949 -22.122064)
			(xy 222.777081 -22.157739) (xy 222.729475 -22.186793) (xy 222.678146 -22.208605) (xy 222.624189 -22.222711)
			(xy 222.568752 -22.228811) (xy 222.513018 -22.226774) (xy 222.458175 -22.216644) (xy 222.405391 -22.198637)
			(xy 222.355791 -22.173136) (xy 222.310433 -22.140685) (xy 222.270284 -22.101976) (xy 222.236198 -22.057833)
			(xy 222.208902 -22.009198) (xy 222.188979 -21.957107) (xy 222.176853 -21.90267) (xy 222.172782 -21.847048)
			(xy 221.701964 -21.847048) (xy 221.702122 -21.855684) (xy 221.701613 -21.88357) (xy 221.693493 -21.938746)
			(xy 221.677425 -21.992153) (xy 221.653753 -22.04265) (xy 221.62298 -22.089163) (xy 221.585763 -22.1307)
			(xy 221.542895 -22.166375) (xy 221.495289 -22.195429) (xy 221.44396 -22.217241) (xy 221.390003 -22.231347)
			(xy 221.334566 -22.237447) (xy 221.278832 -22.23541) (xy 221.223989 -22.22528) (xy 221.171205 -22.207273)
			(xy 221.121605 -22.181772) (xy 221.076247 -22.149321) (xy 221.036098 -22.110612) (xy 221.002012 -22.066469)
			(xy 220.974716 -22.017834) (xy 220.954793 -21.965743) (xy 220.942667 -21.911306) (xy 220.938596 -21.855684)
			(xy 220.791226 -21.855684) (xy 220.790777 -21.858736) (xy 220.774709 -21.912143) (xy 220.751037 -21.96264)
			(xy 220.720264 -22.009153) (xy 220.683047 -22.05069) (xy 220.640179 -22.086365) (xy 220.592573 -22.115419)
			(xy 220.541244 -22.137231) (xy 220.487287 -22.151337) (xy 220.43185 -22.157437) (xy 220.376116 -22.1554)
			(xy 220.321273 -22.14527) (xy 220.268489 -22.127263) (xy 220.218889 -22.101762) (xy 220.173531 -22.069311)
			(xy 220.133382 -22.030602) (xy 220.099296 -21.986459) (xy 220.072 -21.937824) (xy 220.052077 -21.885733)
			(xy 220.039951 -21.831296) (xy 220.03588 -21.775674) (xy 210.911801 -21.775674) (xy 210.890601 -21.822093)
			(xy 210.861135 -21.867943) (xy 210.825444 -21.909134) (xy 210.784253 -21.944825) (xy 210.738403 -21.974291)
			(xy 210.688826 -21.996933) (xy 210.636531 -22.012288) (xy 210.582583 -22.020044) (xy 210.528081 -22.020044)
			(xy 210.474133 -22.012288) (xy 210.421838 -21.996933) (xy 210.372261 -21.974291) (xy 210.326411 -21.944825)
			(xy 210.28522 -21.909134) (xy 210.249529 -21.867943) (xy 210.220063 -21.822093) (xy 210.197421 -21.772516)
			(xy 210.182066 -21.720221) (xy 210.17431 -21.666273) (xy 210.173824 -21.639022) (xy 203.343407 -21.639022)
			(xy 203.33021 -21.668025) (xy 203.269165 -21.783021) (xy 203.201224 -21.894082) (xy 203.126638 -22.000794)
			(xy 203.045685 -22.102761) (xy 202.958666 -22.199603) (xy 202.865905 -22.29096) (xy 202.767747 -22.376492)
			(xy 202.664558 -22.45588) (xy 202.556721 -22.52883) (xy 202.511671 -22.555454) (xy 219.43644 -22.555454)
			(xy 219.440511 -22.499832) (xy 219.452637 -22.445395) (xy 219.47256 -22.393304) (xy 219.499856 -22.344669)
			(xy 219.533942 -22.300526) (xy 219.574091 -22.261817) (xy 219.619449 -22.229366) (xy 219.669049 -22.203865)
			(xy 219.721833 -22.185858) (xy 219.776676 -22.175728) (xy 219.83241 -22.173691) (xy 219.887847 -22.179791)
			(xy 219.941804 -22.193897) (xy 219.993133 -22.215709) (xy 220.040739 -22.244763) (xy 220.083607 -22.280438)
			(xy 220.120824 -22.321975) (xy 220.151597 -22.368488) (xy 220.175269 -22.418985) (xy 220.191337 -22.472392)
			(xy 220.199457 -22.527568) (xy 220.199966 -22.555454) (xy 220.199457 -22.58334) (xy 220.191337 -22.638516)
			(xy 220.175269 -22.691923) (xy 220.151597 -22.74242) (xy 220.120824 -22.788933) (xy 220.083607 -22.83047)
			(xy 220.040739 -22.866145) (xy 219.993133 -22.895199) (xy 219.941804 -22.917011) (xy 219.887847 -22.931117)
			(xy 219.83241 -22.937217) (xy 219.776676 -22.93518) (xy 219.721833 -22.92505) (xy 219.669049 -22.907043)
			(xy 219.619449 -22.881542) (xy 219.574091 -22.849091) (xy 219.533942 -22.810382) (xy 219.499856 -22.766239)
			(xy 219.47256 -22.717604) (xy 219.452637 -22.665513) (xy 219.440511 -22.611076) (xy 219.43644 -22.555454)
			(xy 202.511671 -22.555454) (xy 202.444636 -22.595071) (xy 202.328723 -22.654354) (xy 202.20941 -22.706462)
			(xy 202.087143 -22.751198) (xy 201.962376 -22.788397) (xy 201.835573 -22.817921) (xy 201.707206 -22.839659)
			(xy 201.577753 -22.853532) (xy 201.447694 -22.859486) (xy 201.317515 -22.857501) (xy 201.187699 -22.847583)
			(xy 201.058729 -22.829769) (xy 200.931084 -22.804126) (xy 200.805241 -22.770749) (xy 200.681666 -22.729762)
			(xy 200.56082 -22.681318) (xy 200.443152 -22.625596) (xy 200.3291 -22.562805) (xy 200.219088 -22.493178)
			(xy 200.113526 -22.416973) (xy 200.012806 -22.334474) (xy 199.917302 -22.245989) (xy 199.82737 -22.151846)
			(xy 199.743345 -22.052395) (xy 199.66554 -21.948007) (xy 199.594243 -21.83907) (xy 199.529719 -21.725988)
			(xy 199.47221 -21.609184) (xy 199.421928 -21.489091) (xy 199.379062 -21.366155) (xy 199.343769 -21.240836)
			(xy 199.316183 -21.113597) (xy 199.296404 -20.984914) (xy 199.284508 -20.855264) (xy 199.280538 -20.72513)
			(xy 193.050283 -20.72513) (xy 193.034639 -20.74259) (xy 192.991771 -20.778265) (xy 192.944165 -20.807319)
			(xy 192.892836 -20.829131) (xy 192.838879 -20.843237) (xy 192.783442 -20.849337) (xy 192.727708 -20.8473)
			(xy 192.672865 -20.83717) (xy 192.620081 -20.819163) (xy 192.570481 -20.793662) (xy 192.525123 -20.761211)
			(xy 192.484974 -20.722502) (xy 192.450888 -20.678359) (xy 192.423592 -20.629724) (xy 192.403669 -20.577633)
			(xy 192.391543 -20.523196) (xy 192.387472 -20.467574) (xy 184.906388 -20.467574) (xy 184.88561 -20.510391)
			(xy 184.853041 -20.557753) (xy 184.833768 -20.57908) (xy 184.827164 -20.585938) (xy 184.820052 -20.603972)
			(xy 184.820052 -20.692872) (xy 184.827164 -20.710906) (xy 184.833768 -20.717764) (xy 184.853061 -20.739072)
			(xy 184.885626 -20.786437) (xy 184.910717 -20.838152) (xy 184.927766 -20.893046) (xy 184.936387 -20.949876)
			(xy 184.936384 -21.007356) (xy 184.927759 -21.064186) (xy 184.910705 -21.119078) (xy 184.88561 -21.170791)
			(xy 184.853041 -21.218153) (xy 184.833768 -21.23948) (xy 184.827164 -21.246338) (xy 184.820052 -21.264372)
			(xy 184.820052 -21.353272) (xy 184.827164 -21.371306) (xy 184.833768 -21.378164) (xy 184.85305 -21.399481)
			(xy 184.885615 -21.446846) (xy 184.910705 -21.49856) (xy 184.927753 -21.553453) (xy 184.936373 -21.610282)
			(xy 184.936892 -21.639022) (xy 184.936406 -21.666273) (xy 184.92865 -21.720221) (xy 184.913295 -21.772516)
			(xy 184.911853 -21.775674) (xy 194.035932 -21.775674) (xy 194.040003 -21.720052) (xy 194.052129 -21.665615)
			(xy 194.072052 -21.613524) (xy 194.099348 -21.564889) (xy 194.133434 -21.520746) (xy 194.173583 -21.482037)
			(xy 194.218941 -21.449586) (xy 194.268541 -21.424085) (xy 194.321325 -21.406078) (xy 194.376168 -21.395948)
			(xy 194.431902 -21.393911) (xy 194.487339 -21.400011) (xy 194.541296 -21.414117) (xy 194.592625 -21.435929)
			(xy 194.640231 -21.464983) (xy 194.683099 -21.500658) (xy 194.720316 -21.542195) (xy 194.751089 -21.588708)
			(xy 194.774761 -21.639205) (xy 194.790829 -21.692612) (xy 194.798949 -21.747788) (xy 194.799458 -21.775674)
			(xy 194.798949 -21.80356) (xy 194.791278 -21.855684) (xy 194.938648 -21.855684) (xy 194.942719 -21.800062)
			(xy 194.954845 -21.745625) (xy 194.974768 -21.693534) (xy 195.002064 -21.644899) (xy 195.03615 -21.600756)
			(xy 195.076299 -21.562047) (xy 195.121657 -21.529596) (xy 195.171257 -21.504095) (xy 195.224041 -21.486088)
			(xy 195.278884 -21.475958) (xy 195.334618 -21.473921) (xy 195.390055 -21.480021) (xy 195.444012 -21.494127)
			(xy 195.495341 -21.515939) (xy 195.542947 -21.544993) (xy 195.585815 -21.580668) (xy 195.623032 -21.622205)
			(xy 195.653805 -21.668718) (xy 195.677477 -21.719215) (xy 195.693545 -21.772622) (xy 195.701665 -21.827798)
			(xy 195.702016 -21.847048) (xy 196.172834 -21.847048) (xy 196.176905 -21.791426) (xy 196.189031 -21.736989)
			(xy 196.208954 -21.684898) (xy 196.23625 -21.636263) (xy 196.270336 -21.59212) (xy 196.310485 -21.553411)
			(xy 196.355843 -21.52096) (xy 196.405443 -21.495459) (xy 196.458227 -21.477452) (xy 196.51307 -21.467322)
			(xy 196.568804 -21.465285) (xy 196.624241 -21.471385) (xy 196.678198 -21.485491) (xy 196.729527 -21.507303)
			(xy 196.777133 -21.536357) (xy 196.820001 -21.572032) (xy 196.857218 -21.613569) (xy 196.887991 -21.660082)
			(xy 196.911663 -21.710579) (xy 196.927731 -21.763986) (xy 196.935851 -21.819162) (xy 196.93636 -21.847048)
			(xy 196.935851 -21.874934) (xy 196.927731 -21.93011) (xy 196.911663 -21.983517) (xy 196.887991 -22.034014)
			(xy 196.857218 -22.080527) (xy 196.820001 -22.122064) (xy 196.777133 -22.157739) (xy 196.729527 -22.186793)
			(xy 196.678198 -22.208605) (xy 196.624241 -22.222711) (xy 196.568804 -22.228811) (xy 196.51307 -22.226774)
			(xy 196.458227 -22.216644) (xy 196.405443 -22.198637) (xy 196.355843 -22.173136) (xy 196.310485 -22.140685)
			(xy 196.270336 -22.101976) (xy 196.23625 -22.057833) (xy 196.208954 -22.009198) (xy 196.189031 -21.957107)
			(xy 196.176905 -21.90267) (xy 196.172834 -21.847048) (xy 195.702016 -21.847048) (xy 195.702174 -21.855684)
			(xy 195.701665 -21.88357) (xy 195.693545 -21.938746) (xy 195.677477 -21.992153) (xy 195.653805 -22.04265)
			(xy 195.623032 -22.089163) (xy 195.585815 -22.1307) (xy 195.542947 -22.166375) (xy 195.495341 -22.195429)
			(xy 195.444012 -22.217241) (xy 195.390055 -22.231347) (xy 195.334618 -22.237447) (xy 195.278884 -22.23541)
			(xy 195.224041 -22.22528) (xy 195.171257 -22.207273) (xy 195.121657 -22.181772) (xy 195.076299 -22.149321)
			(xy 195.03615 -22.110612) (xy 195.002064 -22.066469) (xy 194.974768 -22.017834) (xy 194.954845 -21.965743)
			(xy 194.942719 -21.911306) (xy 194.938648 -21.855684) (xy 194.791278 -21.855684) (xy 194.790829 -21.858736)
			(xy 194.774761 -21.912143) (xy 194.751089 -21.96264) (xy 194.720316 -22.009153) (xy 194.683099 -22.05069)
			(xy 194.640231 -22.086365) (xy 194.592625 -22.115419) (xy 194.541296 -22.137231) (xy 194.487339 -22.151337)
			(xy 194.431902 -22.157437) (xy 194.376168 -22.1554) (xy 194.321325 -22.14527) (xy 194.268541 -22.127263)
			(xy 194.218941 -22.101762) (xy 194.173583 -22.069311) (xy 194.133434 -22.030602) (xy 194.099348 -21.986459)
			(xy 194.072052 -21.937824) (xy 194.052129 -21.885733) (xy 194.040003 -21.831296) (xy 194.035932 -21.775674)
			(xy 184.911853 -21.775674) (xy 184.890653 -21.822093) (xy 184.861187 -21.867943) (xy 184.825496 -21.909134)
			(xy 184.784305 -21.944825) (xy 184.738455 -21.974291) (xy 184.688878 -21.996933) (xy 184.636583 -22.012288)
			(xy 184.582635 -22.020044) (xy 184.528133 -22.020044) (xy 184.474185 -22.012288) (xy 184.42189 -21.996933)
			(xy 184.372313 -21.974291) (xy 184.326463 -21.944825) (xy 184.285272 -21.909134) (xy 184.249581 -21.867943)
			(xy 184.220115 -21.822093) (xy 184.197473 -21.772516) (xy 184.182118 -21.720221) (xy 184.174362 -21.666273)
			(xy 184.173876 -21.639022) (xy 177.343459 -21.639022) (xy 177.330262 -21.668025) (xy 177.269217 -21.783021)
			(xy 177.201276 -21.894082) (xy 177.12669 -22.000794) (xy 177.045737 -22.102761) (xy 176.958718 -22.199603)
			(xy 176.865957 -22.29096) (xy 176.767799 -22.376492) (xy 176.66461 -22.45588) (xy 176.556773 -22.52883)
			(xy 176.511723 -22.555454) (xy 193.436492 -22.555454) (xy 193.440563 -22.499832) (xy 193.452689 -22.445395)
			(xy 193.472612 -22.393304) (xy 193.499908 -22.344669) (xy 193.533994 -22.300526) (xy 193.574143 -22.261817)
			(xy 193.619501 -22.229366) (xy 193.669101 -22.203865) (xy 193.721885 -22.185858) (xy 193.776728 -22.175728)
			(xy 193.832462 -22.173691) (xy 193.887899 -22.179791) (xy 193.941856 -22.193897) (xy 193.993185 -22.215709)
			(xy 194.040791 -22.244763) (xy 194.083659 -22.280438) (xy 194.120876 -22.321975) (xy 194.151649 -22.368488)
			(xy 194.175321 -22.418985) (xy 194.191389 -22.472392) (xy 194.199509 -22.527568) (xy 194.200018 -22.555454)
			(xy 194.199509 -22.58334) (xy 194.191389 -22.638516) (xy 194.175321 -22.691923) (xy 194.151649 -22.74242)
			(xy 194.120876 -22.788933) (xy 194.083659 -22.83047) (xy 194.040791 -22.866145) (xy 193.993185 -22.895199)
			(xy 193.941856 -22.917011) (xy 193.887899 -22.931117) (xy 193.832462 -22.937217) (xy 193.776728 -22.93518)
			(xy 193.721885 -22.92505) (xy 193.669101 -22.907043) (xy 193.619501 -22.881542) (xy 193.574143 -22.849091)
			(xy 193.533994 -22.810382) (xy 193.499908 -22.766239) (xy 193.472612 -22.717604) (xy 193.452689 -22.665513)
			(xy 193.440563 -22.611076) (xy 193.436492 -22.555454) (xy 176.511723 -22.555454) (xy 176.444688 -22.595071)
			(xy 176.328775 -22.654354) (xy 176.209462 -22.706462) (xy 176.087195 -22.751198) (xy 175.962428 -22.788397)
			(xy 175.835625 -22.817921) (xy 175.707258 -22.839659) (xy 175.577805 -22.853532) (xy 175.447746 -22.859486)
			(xy 175.317567 -22.857501) (xy 175.187751 -22.847583) (xy 175.058781 -22.829769) (xy 174.931136 -22.804126)
			(xy 174.805293 -22.770749) (xy 174.681718 -22.729762) (xy 174.560872 -22.681318) (xy 174.443204 -22.625596)
			(xy 174.329152 -22.562805) (xy 174.21914 -22.493178) (xy 174.113578 -22.416973) (xy 174.012858 -22.334474)
			(xy 173.917354 -22.245989) (xy 173.827422 -22.151846) (xy 173.743397 -22.052395) (xy 173.665592 -21.948007)
			(xy 173.594295 -21.83907) (xy 173.529771 -21.725988) (xy 173.472262 -21.609184) (xy 173.42198 -21.489091)
			(xy 173.379114 -21.366155) (xy 173.343821 -21.240836) (xy 173.316235 -21.113597) (xy 173.296456 -20.984914)
			(xy 173.28456 -20.855264) (xy 173.28059 -20.72513) (xy 167.050335 -20.72513) (xy 167.034691 -20.74259)
			(xy 166.991823 -20.778265) (xy 166.944217 -20.807319) (xy 166.892888 -20.829131) (xy 166.838931 -20.843237)
			(xy 166.783494 -20.849337) (xy 166.72776 -20.8473) (xy 166.672917 -20.83717) (xy 166.620133 -20.819163)
			(xy 166.570533 -20.793662) (xy 166.525175 -20.761211) (xy 166.485026 -20.722502) (xy 166.45094 -20.678359)
			(xy 166.423644 -20.629724) (xy 166.403721 -20.577633) (xy 166.391595 -20.523196) (xy 166.387524 -20.467574)
			(xy 158.906429 -20.467574) (xy 158.885655 -20.510388) (xy 158.85309 -20.557752) (xy 158.83382 -20.57908)
			(xy 158.827216 -20.585938) (xy 158.820104 -20.603972) (xy 158.820104 -20.692872) (xy 158.827216 -20.710906)
			(xy 158.83382 -20.717764) (xy 158.853111 -20.739073) (xy 158.885671 -20.78644) (xy 158.910759 -20.838155)
			(xy 158.927805 -20.893048) (xy 158.936425 -20.949877) (xy 158.936422 -21.007355) (xy 158.927798 -21.064184)
			(xy 158.910747 -21.119075) (xy 158.885655 -21.170788) (xy 158.85309 -21.218152) (xy 158.83382 -21.23948)
			(xy 158.827216 -21.246338) (xy 158.820104 -21.264372) (xy 158.820104 -21.353272) (xy 158.827216 -21.371306)
			(xy 158.83382 -21.378164) (xy 158.853094 -21.399488) (xy 158.885662 -21.44685) (xy 158.910754 -21.498562)
			(xy 158.927804 -21.553454) (xy 158.936425 -21.610283) (xy 158.936944 -21.639022) (xy 158.936458 -21.666273)
			(xy 158.928702 -21.720221) (xy 158.913347 -21.772516) (xy 158.911905 -21.775674) (xy 168.035984 -21.775674)
			(xy 168.040055 -21.720052) (xy 168.052181 -21.665615) (xy 168.072104 -21.613524) (xy 168.0994 -21.564889)
			(xy 168.133486 -21.520746) (xy 168.173635 -21.482037) (xy 168.218993 -21.449586) (xy 168.268593 -21.424085)
			(xy 168.321377 -21.406078) (xy 168.37622 -21.395948) (xy 168.431954 -21.393911) (xy 168.487391 -21.400011)
			(xy 168.541348 -21.414117) (xy 168.592677 -21.435929) (xy 168.640283 -21.464983) (xy 168.683151 -21.500658)
			(xy 168.720368 -21.542195) (xy 168.751141 -21.588708) (xy 168.774813 -21.639205) (xy 168.790881 -21.692612)
			(xy 168.799001 -21.747788) (xy 168.79951 -21.775674) (xy 168.799001 -21.80356) (xy 168.79133 -21.855684)
			(xy 168.9387 -21.855684) (xy 168.942771 -21.800062) (xy 168.954897 -21.745625) (xy 168.97482 -21.693534)
			(xy 169.002116 -21.644899) (xy 169.036202 -21.600756) (xy 169.076351 -21.562047) (xy 169.121709 -21.529596)
			(xy 169.171309 -21.504095) (xy 169.224093 -21.486088) (xy 169.278936 -21.475958) (xy 169.33467 -21.473921)
			(xy 169.390107 -21.480021) (xy 169.444064 -21.494127) (xy 169.495393 -21.515939) (xy 169.542999 -21.544993)
			(xy 169.585867 -21.580668) (xy 169.623084 -21.622205) (xy 169.653857 -21.668718) (xy 169.677529 -21.719215)
			(xy 169.693597 -21.772622) (xy 169.701717 -21.827798) (xy 169.702068 -21.847048) (xy 170.172886 -21.847048)
			(xy 170.176957 -21.791426) (xy 170.189083 -21.736989) (xy 170.209006 -21.684898) (xy 170.236302 -21.636263)
			(xy 170.270388 -21.59212) (xy 170.310537 -21.553411) (xy 170.355895 -21.52096) (xy 170.405495 -21.495459)
			(xy 170.458279 -21.477452) (xy 170.513122 -21.467322) (xy 170.568856 -21.465285) (xy 170.624293 -21.471385)
			(xy 170.67825 -21.485491) (xy 170.729579 -21.507303) (xy 170.777185 -21.536357) (xy 170.820053 -21.572032)
			(xy 170.85727 -21.613569) (xy 170.888043 -21.660082) (xy 170.911715 -21.710579) (xy 170.927783 -21.763986)
			(xy 170.935903 -21.819162) (xy 170.936412 -21.847048) (xy 170.935903 -21.874934) (xy 170.927783 -21.93011)
			(xy 170.911715 -21.983517) (xy 170.888043 -22.034014) (xy 170.85727 -22.080527) (xy 170.820053 -22.122064)
			(xy 170.777185 -22.157739) (xy 170.729579 -22.186793) (xy 170.67825 -22.208605) (xy 170.624293 -22.222711)
			(xy 170.568856 -22.228811) (xy 170.513122 -22.226774) (xy 170.458279 -22.216644) (xy 170.405495 -22.198637)
			(xy 170.355895 -22.173136) (xy 170.310537 -22.140685) (xy 170.270388 -22.101976) (xy 170.236302 -22.057833)
			(xy 170.209006 -22.009198) (xy 170.189083 -21.957107) (xy 170.176957 -21.90267) (xy 170.172886 -21.847048)
			(xy 169.702068 -21.847048) (xy 169.702226 -21.855684) (xy 169.701717 -21.88357) (xy 169.693597 -21.938746)
			(xy 169.677529 -21.992153) (xy 169.653857 -22.04265) (xy 169.623084 -22.089163) (xy 169.585867 -22.1307)
			(xy 169.542999 -22.166375) (xy 169.495393 -22.195429) (xy 169.444064 -22.217241) (xy 169.390107 -22.231347)
			(xy 169.33467 -22.237447) (xy 169.278936 -22.23541) (xy 169.224093 -22.22528) (xy 169.171309 -22.207273)
			(xy 169.121709 -22.181772) (xy 169.076351 -22.149321) (xy 169.036202 -22.110612) (xy 169.002116 -22.066469)
			(xy 168.97482 -22.017834) (xy 168.954897 -21.965743) (xy 168.942771 -21.911306) (xy 168.9387 -21.855684)
			(xy 168.79133 -21.855684) (xy 168.790881 -21.858736) (xy 168.774813 -21.912143) (xy 168.751141 -21.96264)
			(xy 168.720368 -22.009153) (xy 168.683151 -22.05069) (xy 168.640283 -22.086365) (xy 168.592677 -22.115419)
			(xy 168.541348 -22.137231) (xy 168.487391 -22.151337) (xy 168.431954 -22.157437) (xy 168.37622 -22.1554)
			(xy 168.321377 -22.14527) (xy 168.268593 -22.127263) (xy 168.218993 -22.101762) (xy 168.173635 -22.069311)
			(xy 168.133486 -22.030602) (xy 168.0994 -21.986459) (xy 168.072104 -21.937824) (xy 168.052181 -21.885733)
			(xy 168.040055 -21.831296) (xy 168.035984 -21.775674) (xy 158.911905 -21.775674) (xy 158.890705 -21.822093)
			(xy 158.861239 -21.867943) (xy 158.825548 -21.909134) (xy 158.784357 -21.944825) (xy 158.738507 -21.974291)
			(xy 158.68893 -21.996933) (xy 158.636635 -22.012288) (xy 158.582687 -22.020044) (xy 158.528185 -22.020044)
			(xy 158.474237 -22.012288) (xy 158.421942 -21.996933) (xy 158.372365 -21.974291) (xy 158.326515 -21.944825)
			(xy 158.285324 -21.909134) (xy 158.249633 -21.867943) (xy 158.220167 -21.822093) (xy 158.197525 -21.772516)
			(xy 158.18217 -21.720221) (xy 158.174414 -21.666273) (xy 158.173928 -21.639022) (xy 151.343141 -21.639022)
			(xy 151.33006 -21.667771) (xy 151.269015 -21.782767) (xy 151.201074 -21.893828) (xy 151.126488 -22.00054)
			(xy 151.045535 -22.102507) (xy 150.958516 -22.199349) (xy 150.865755 -22.290706) (xy 150.767597 -22.376238)
			(xy 150.664408 -22.455626) (xy 150.556571 -22.528576) (xy 150.511091 -22.555454) (xy 167.436544 -22.555454)
			(xy 167.440615 -22.499832) (xy 167.452741 -22.445395) (xy 167.472664 -22.393304) (xy 167.49996 -22.344669)
			(xy 167.534046 -22.300526) (xy 167.574195 -22.261817) (xy 167.619553 -22.229366) (xy 167.669153 -22.203865)
			(xy 167.721937 -22.185858) (xy 167.77678 -22.175728) (xy 167.832514 -22.173691) (xy 167.887951 -22.179791)
			(xy 167.941908 -22.193897) (xy 167.993237 -22.215709) (xy 168.040843 -22.244763) (xy 168.083711 -22.280438)
			(xy 168.120928 -22.321975) (xy 168.151701 -22.368488) (xy 168.175373 -22.418985) (xy 168.191441 -22.472392)
			(xy 168.199561 -22.527568) (xy 168.20007 -22.555454) (xy 168.199561 -22.58334) (xy 168.191441 -22.638516)
			(xy 168.175373 -22.691923) (xy 168.151701 -22.74242) (xy 168.120928 -22.788933) (xy 168.083711 -22.83047)
			(xy 168.040843 -22.866145) (xy 167.993237 -22.895199) (xy 167.941908 -22.917011) (xy 167.887951 -22.931117)
			(xy 167.832514 -22.937217) (xy 167.77678 -22.93518) (xy 167.721937 -22.92505) (xy 167.669153 -22.907043)
			(xy 167.619553 -22.881542) (xy 167.574195 -22.849091) (xy 167.534046 -22.810382) (xy 167.49996 -22.766239)
			(xy 167.472664 -22.717604) (xy 167.452741 -22.665513) (xy 167.440615 -22.611076) (xy 167.436544 -22.555454)
			(xy 150.511091 -22.555454) (xy 150.444486 -22.594817) (xy 150.328573 -22.6541) (xy 150.20926 -22.706208)
			(xy 150.086993 -22.750944) (xy 149.962226 -22.788143) (xy 149.835423 -22.817667) (xy 149.707056 -22.839405)
			(xy 149.577603 -22.853278) (xy 149.447544 -22.859232) (xy 149.317365 -22.857247) (xy 149.187549 -22.847329)
			(xy 149.058579 -22.829515) (xy 148.930934 -22.803872) (xy 148.805091 -22.770495) (xy 148.681516 -22.729508)
			(xy 148.56067 -22.681064) (xy 148.443002 -22.625342) (xy 148.32895 -22.562551) (xy 148.218938 -22.492924)
			(xy 148.113376 -22.416719) (xy 148.012656 -22.33422) (xy 147.917152 -22.245735) (xy 147.82722 -22.151592)
			(xy 147.743195 -22.052141) (xy 147.66539 -21.947753) (xy 147.594093 -21.838816) (xy 147.529569 -21.725734)
			(xy 147.47206 -21.60893) (xy 147.421778 -21.488837) (xy 147.378912 -21.365901) (xy 147.343619 -21.240582)
			(xy 147.316033 -21.113343) (xy 147.296254 -20.98466) (xy 147.284358 -20.85501) (xy 147.280388 -20.724876)
			(xy 141.050615 -20.724876) (xy 141.034743 -20.74259) (xy 140.991875 -20.778265) (xy 140.944269 -20.807319)
			(xy 140.89294 -20.829131) (xy 140.838983 -20.843237) (xy 140.783546 -20.849337) (xy 140.727812 -20.8473)
			(xy 140.672969 -20.83717) (xy 140.620185 -20.819163) (xy 140.570585 -20.793662) (xy 140.525227 -20.761211)
			(xy 140.485078 -20.722502) (xy 140.450992 -20.678359) (xy 140.423696 -20.629724) (xy 140.403773 -20.577633)
			(xy 140.391647 -20.523196) (xy 140.387576 -20.467574) (xy 132.906491 -20.467574) (xy 132.885713 -20.51039)
			(xy 132.853145 -20.557753) (xy 132.833872 -20.57908) (xy 132.827268 -20.585938) (xy 132.820156 -20.603972)
			(xy 132.820156 -20.692872) (xy 132.827268 -20.710906) (xy 132.833872 -20.717764) (xy 132.853165 -20.739072)
			(xy 132.88573 -20.786437) (xy 132.91082 -20.838152) (xy 132.927869 -20.893046) (xy 132.93649 -20.949876)
			(xy 132.936487 -21.007356) (xy 132.927862 -21.064185) (xy 132.910808 -21.119078) (xy 132.885713 -21.17079)
			(xy 132.853145 -21.218153) (xy 132.833872 -21.23948) (xy 132.827268 -21.246338) (xy 132.820156 -21.264372)
			(xy 132.820156 -21.353272) (xy 132.827268 -21.371306) (xy 132.833872 -21.378164) (xy 132.853155 -21.399481)
			(xy 132.885719 -21.446846) (xy 132.910809 -21.49856) (xy 132.927857 -21.553453) (xy 132.936477 -21.610282)
			(xy 132.936996 -21.639022) (xy 132.93651 -21.666273) (xy 132.928754 -21.720221) (xy 132.913399 -21.772516)
			(xy 132.911957 -21.775674) (xy 142.036036 -21.775674) (xy 142.040107 -21.720052) (xy 142.052233 -21.665615)
			(xy 142.072156 -21.613524) (xy 142.099452 -21.564889) (xy 142.133538 -21.520746) (xy 142.173687 -21.482037)
			(xy 142.219045 -21.449586) (xy 142.268645 -21.424085) (xy 142.321429 -21.406078) (xy 142.376272 -21.395948)
			(xy 142.432006 -21.393911) (xy 142.487443 -21.400011) (xy 142.5414 -21.414117) (xy 142.592729 -21.435929)
			(xy 142.640335 -21.464983) (xy 142.683203 -21.500658) (xy 142.72042 -21.542195) (xy 142.751193 -21.588708)
			(xy 142.774865 -21.639205) (xy 142.790933 -21.692612) (xy 142.799053 -21.747788) (xy 142.799562 -21.775674)
			(xy 142.799053 -21.80356) (xy 142.791382 -21.855684) (xy 142.938752 -21.855684) (xy 142.942823 -21.800062)
			(xy 142.954949 -21.745625) (xy 142.974872 -21.693534) (xy 143.002168 -21.644899) (xy 143.036254 -21.600756)
			(xy 143.076403 -21.562047) (xy 143.121761 -21.529596) (xy 143.171361 -21.504095) (xy 143.224145 -21.486088)
			(xy 143.278988 -21.475958) (xy 143.334722 -21.473921) (xy 143.390159 -21.480021) (xy 143.444116 -21.494127)
			(xy 143.495445 -21.515939) (xy 143.543051 -21.544993) (xy 143.585919 -21.580668) (xy 143.623136 -21.622205)
			(xy 143.653909 -21.668718) (xy 143.677581 -21.719215) (xy 143.693649 -21.772622) (xy 143.701769 -21.827798)
			(xy 143.70212 -21.847048) (xy 144.172938 -21.847048) (xy 144.177009 -21.791426) (xy 144.189135 -21.736989)
			(xy 144.209058 -21.684898) (xy 144.236354 -21.636263) (xy 144.27044 -21.59212) (xy 144.310589 -21.553411)
			(xy 144.355947 -21.52096) (xy 144.405547 -21.495459) (xy 144.458331 -21.477452) (xy 144.513174 -21.467322)
			(xy 144.568908 -21.465285) (xy 144.624345 -21.471385) (xy 144.678302 -21.485491) (xy 144.729631 -21.507303)
			(xy 144.777237 -21.536357) (xy 144.820105 -21.572032) (xy 144.857322 -21.613569) (xy 144.888095 -21.660082)
			(xy 144.911767 -21.710579) (xy 144.927835 -21.763986) (xy 144.935955 -21.819162) (xy 144.936464 -21.847048)
			(xy 144.935955 -21.874934) (xy 144.927835 -21.93011) (xy 144.911767 -21.983517) (xy 144.888095 -22.034014)
			(xy 144.857322 -22.080527) (xy 144.820105 -22.122064) (xy 144.777237 -22.157739) (xy 144.729631 -22.186793)
			(xy 144.678302 -22.208605) (xy 144.624345 -22.222711) (xy 144.568908 -22.228811) (xy 144.513174 -22.226774)
			(xy 144.458331 -22.216644) (xy 144.405547 -22.198637) (xy 144.355947 -22.173136) (xy 144.310589 -22.140685)
			(xy 144.27044 -22.101976) (xy 144.236354 -22.057833) (xy 144.209058 -22.009198) (xy 144.189135 -21.957107)
			(xy 144.177009 -21.90267) (xy 144.172938 -21.847048) (xy 143.70212 -21.847048) (xy 143.702278 -21.855684)
			(xy 143.701769 -21.88357) (xy 143.693649 -21.938746) (xy 143.677581 -21.992153) (xy 143.653909 -22.04265)
			(xy 143.623136 -22.089163) (xy 143.585919 -22.1307) (xy 143.543051 -22.166375) (xy 143.495445 -22.195429)
			(xy 143.444116 -22.217241) (xy 143.390159 -22.231347) (xy 143.334722 -22.237447) (xy 143.278988 -22.23541)
			(xy 143.224145 -22.22528) (xy 143.171361 -22.207273) (xy 143.121761 -22.181772) (xy 143.076403 -22.149321)
			(xy 143.036254 -22.110612) (xy 143.002168 -22.066469) (xy 142.974872 -22.017834) (xy 142.954949 -21.965743)
			(xy 142.942823 -21.911306) (xy 142.938752 -21.855684) (xy 142.791382 -21.855684) (xy 142.790933 -21.858736)
			(xy 142.774865 -21.912143) (xy 142.751193 -21.96264) (xy 142.72042 -22.009153) (xy 142.683203 -22.05069)
			(xy 142.640335 -22.086365) (xy 142.592729 -22.115419) (xy 142.5414 -22.137231) (xy 142.487443 -22.151337)
			(xy 142.432006 -22.157437) (xy 142.376272 -22.1554) (xy 142.321429 -22.14527) (xy 142.268645 -22.127263)
			(xy 142.219045 -22.101762) (xy 142.173687 -22.069311) (xy 142.133538 -22.030602) (xy 142.099452 -21.986459)
			(xy 142.072156 -21.937824) (xy 142.052233 -21.885733) (xy 142.040107 -21.831296) (xy 142.036036 -21.775674)
			(xy 132.911957 -21.775674) (xy 132.890757 -21.822093) (xy 132.861291 -21.867943) (xy 132.8256 -21.909134)
			(xy 132.784409 -21.944825) (xy 132.738559 -21.974291) (xy 132.688982 -21.996933) (xy 132.636687 -22.012288)
			(xy 132.582739 -22.020044) (xy 132.528237 -22.020044) (xy 132.474289 -22.012288) (xy 132.421994 -21.996933)
			(xy 132.372417 -21.974291) (xy 132.326567 -21.944825) (xy 132.285376 -21.909134) (xy 132.249685 -21.867943)
			(xy 132.220219 -21.822093) (xy 132.197577 -21.772516) (xy 132.182222 -21.720221) (xy 132.174466 -21.666273)
			(xy 132.17398 -21.639022) (xy 125.343309 -21.639022) (xy 125.330112 -21.668025) (xy 125.269067 -21.783021)
			(xy 125.201126 -21.894082) (xy 125.12654 -22.000794) (xy 125.045587 -22.102761) (xy 124.958568 -22.199603)
			(xy 124.865807 -22.29096) (xy 124.767649 -22.376492) (xy 124.66446 -22.45588) (xy 124.556623 -22.52883)
			(xy 124.511573 -22.555454) (xy 141.436596 -22.555454) (xy 141.440667 -22.499832) (xy 141.452793 -22.445395)
			(xy 141.472716 -22.393304) (xy 141.500012 -22.344669) (xy 141.534098 -22.300526) (xy 141.574247 -22.261817)
			(xy 141.619605 -22.229366) (xy 141.669205 -22.203865) (xy 141.721989 -22.185858) (xy 141.776832 -22.175728)
			(xy 141.832566 -22.173691) (xy 141.888003 -22.179791) (xy 141.94196 -22.193897) (xy 141.993289 -22.215709)
			(xy 142.040895 -22.244763) (xy 142.083763 -22.280438) (xy 142.12098 -22.321975) (xy 142.151753 -22.368488)
			(xy 142.175425 -22.418985) (xy 142.191493 -22.472392) (xy 142.199613 -22.527568) (xy 142.200122 -22.555454)
			(xy 142.199613 -22.58334) (xy 142.191493 -22.638516) (xy 142.175425 -22.691923) (xy 142.151753 -22.74242)
			(xy 142.12098 -22.788933) (xy 142.083763 -22.83047) (xy 142.040895 -22.866145) (xy 141.993289 -22.895199)
			(xy 141.94196 -22.917011) (xy 141.888003 -22.931117) (xy 141.832566 -22.937217) (xy 141.776832 -22.93518)
			(xy 141.721989 -22.92505) (xy 141.669205 -22.907043) (xy 141.619605 -22.881542) (xy 141.574247 -22.849091)
			(xy 141.534098 -22.810382) (xy 141.500012 -22.766239) (xy 141.472716 -22.717604) (xy 141.452793 -22.665513)
			(xy 141.440667 -22.611076) (xy 141.436596 -22.555454) (xy 124.511573 -22.555454) (xy 124.444538 -22.595071)
			(xy 124.328625 -22.654354) (xy 124.209312 -22.706462) (xy 124.087045 -22.751198) (xy 123.962278 -22.788397)
			(xy 123.835475 -22.817921) (xy 123.707108 -22.839659) (xy 123.577655 -22.853532) (xy 123.447596 -22.859486)
			(xy 123.317417 -22.857501) (xy 123.187601 -22.847583) (xy 123.058631 -22.829769) (xy 122.930986 -22.804126)
			(xy 122.805143 -22.770749) (xy 122.681568 -22.729762) (xy 122.560722 -22.681318) (xy 122.443054 -22.625596)
			(xy 122.329002 -22.562805) (xy 122.21899 -22.493178) (xy 122.113428 -22.416973) (xy 122.012708 -22.334474)
			(xy 121.917204 -22.245989) (xy 121.827272 -22.151846) (xy 121.743247 -22.052395) (xy 121.665442 -21.948007)
			(xy 121.594145 -21.83907) (xy 121.529621 -21.725988) (xy 121.472112 -21.609184) (xy 121.42183 -21.489091)
			(xy 121.378964 -21.366155) (xy 121.343671 -21.240836) (xy 121.316085 -21.113597) (xy 121.296306 -20.984914)
			(xy 121.28441 -20.855264) (xy 121.28044 -20.72513) (xy 94.740286 -20.72513) (xy 94.752909 -20.739073)
			(xy 94.78547 -20.78644) (xy 94.810557 -20.838155) (xy 94.827604 -20.893048) (xy 94.836223 -20.949877)
			(xy 94.836221 -21.007355) (xy 94.827597 -21.064184) (xy 94.810545 -21.119075) (xy 94.785454 -21.170788)
			(xy 94.752889 -21.218152) (xy 94.733618 -21.23948) (xy 94.727014 -21.246338) (xy 94.719902 -21.264372)
			(xy 94.719902 -21.353272) (xy 94.727014 -21.371306) (xy 94.733618 -21.378164) (xy 94.752892 -21.399489)
			(xy 94.785459 -21.44685) (xy 94.810552 -21.498563) (xy 94.827602 -21.553454) (xy 94.836223 -21.610283)
			(xy 94.836742 -21.639022) (xy 94.836256 -21.666273) (xy 94.8285 -21.720221) (xy 94.813145 -21.772516)
			(xy 94.790503 -21.822093) (xy 94.761037 -21.867943) (xy 94.725346 -21.909134) (xy 94.684155 -21.944825)
			(xy 94.638305 -21.974291) (xy 94.588728 -21.996933) (xy 94.536433 -22.012288) (xy 94.482485 -22.020044)
			(xy 94.427983 -22.020044) (xy 94.374035 -22.012288) (xy 94.32174 -21.996933) (xy 94.272163 -21.974291)
			(xy 94.226313 -21.944825) (xy 94.185122 -21.909134) (xy 94.149431 -21.867943) (xy 94.119965 -21.822093)
			(xy 94.097323 -21.772516) (xy 94.081968 -21.720221) (xy 94.074212 -21.666273) (xy 94.073726 -21.639022)
			(xy 87.246077 -21.639022) (xy 87.235192 -21.662945) (xy 87.174147 -21.777941) (xy 87.106206 -21.889002)
			(xy 87.03162 -21.995714) (xy 86.950667 -22.097681) (xy 86.863648 -22.194523) (xy 86.770887 -22.28588)
			(xy 86.672729 -22.371412) (xy 86.56954 -22.4508) (xy 86.461703 -22.52375) (xy 86.349618 -22.589991)
			(xy 86.233705 -22.649274) (xy 86.114392 -22.701382) (xy 85.992125 -22.746118) (xy 85.867358 -22.783317)
			(xy 85.740555 -22.812841) (xy 85.612188 -22.834579) (xy 85.482735 -22.848452) (xy 85.352676 -22.854406)
			(xy 85.222497 -22.852421) (xy 85.092681 -22.842503) (xy 84.963711 -22.824689) (xy 84.836066 -22.799046)
			(xy 84.710223 -22.765669) (xy 84.586648 -22.724682) (xy 84.465802 -22.676238) (xy 84.348134 -22.620516)
			(xy 84.234082 -22.557725) (xy 84.12407 -22.488098) (xy 84.018508 -22.411893) (xy 83.917788 -22.329394)
			(xy 83.822284 -22.240909) (xy 83.732352 -22.146766) (xy 83.648327 -22.047315) (xy 83.570522 -21.942927)
			(xy 83.499225 -21.83399) (xy 83.434701 -21.720908) (xy 83.377192 -21.604104) (xy 83.32691 -21.484011)
			(xy 83.284044 -21.361075) (xy 83.248751 -21.235756) (xy 83.221165 -21.108517) (xy 83.201386 -20.979834)
			(xy 83.18949 -20.850184) (xy 83.18552 -20.72005) (xy 76.954737 -20.72005) (xy 76.934541 -20.74259)
			(xy 76.891673 -20.778265) (xy 76.844067 -20.807319) (xy 76.792738 -20.829131) (xy 76.738781 -20.843237)
			(xy 76.683344 -20.849337) (xy 76.62761 -20.8473) (xy 76.572767 -20.83717) (xy 76.519983 -20.819163)
			(xy 76.470383 -20.793662) (xy 76.425025 -20.761211) (xy 76.384876 -20.722502) (xy 76.35079 -20.678359)
			(xy 76.323494 -20.629724) (xy 76.303571 -20.577633) (xy 76.291445 -20.523196) (xy 76.287374 -20.467574)
			(xy 68.80629 -20.467574) (xy 68.785512 -20.510391) (xy 68.752943 -20.557753) (xy 68.73367 -20.57908)
			(xy 68.727066 -20.585938) (xy 68.719954 -20.603972) (xy 68.719954 -20.692872) (xy 68.727066 -20.710906)
			(xy 68.73367 -20.717764) (xy 68.752963 -20.739072) (xy 68.785528 -20.786437) (xy 68.810619 -20.838152)
			(xy 68.827667 -20.893046) (xy 68.836288 -20.949876) (xy 68.836286 -21.007356) (xy 68.82766 -21.064186)
			(xy 68.810607 -21.119078) (xy 68.785512 -21.170791) (xy 68.752943 -21.218153) (xy 68.73367 -21.23948)
			(xy 68.727066 -21.246338) (xy 68.719954 -21.264372) (xy 68.719954 -21.353272) (xy 68.727066 -21.371306)
			(xy 68.73367 -21.378164) (xy 68.752952 -21.399481) (xy 68.785517 -21.446846) (xy 68.810607 -21.49856)
			(xy 68.827655 -21.553453) (xy 68.836275 -21.610282) (xy 68.836794 -21.639022) (xy 68.836308 -21.666273)
			(xy 68.828552 -21.720221) (xy 68.813197 -21.772516) (xy 68.811755 -21.775674) (xy 77.935834 -21.775674)
			(xy 77.939905 -21.720052) (xy 77.952031 -21.665615) (xy 77.971954 -21.613524) (xy 77.99925 -21.564889)
			(xy 78.033336 -21.520746) (xy 78.073485 -21.482037) (xy 78.118843 -21.449586) (xy 78.168443 -21.424085)
			(xy 78.221227 -21.406078) (xy 78.27607 -21.395948) (xy 78.331804 -21.393911) (xy 78.387241 -21.400011)
			(xy 78.441198 -21.414117) (xy 78.492527 -21.435929) (xy 78.540133 -21.464983) (xy 78.583001 -21.500658)
			(xy 78.620218 -21.542195) (xy 78.650991 -21.588708) (xy 78.674663 -21.639205) (xy 78.690731 -21.692612)
			(xy 78.698851 -21.747788) (xy 78.69936 -21.775674) (xy 78.698851 -21.80356) (xy 78.69118 -21.855684)
			(xy 78.83855 -21.855684) (xy 78.842621 -21.800062) (xy 78.854747 -21.745625) (xy 78.87467 -21.693534)
			(xy 78.901966 -21.644899) (xy 78.936052 -21.600756) (xy 78.976201 -21.562047) (xy 79.021559 -21.529596)
			(xy 79.071159 -21.504095) (xy 79.123943 -21.486088) (xy 79.178786 -21.475958) (xy 79.23452 -21.473921)
			(xy 79.289957 -21.480021) (xy 79.343914 -21.494127) (xy 79.395243 -21.515939) (xy 79.442849 -21.544993)
			(xy 79.485717 -21.580668) (xy 79.522934 -21.622205) (xy 79.553707 -21.668718) (xy 79.577379 -21.719215)
			(xy 79.593447 -21.772622) (xy 79.601567 -21.827798) (xy 79.601918 -21.847048) (xy 80.072736 -21.847048)
			(xy 80.076807 -21.791426) (xy 80.088933 -21.736989) (xy 80.108856 -21.684898) (xy 80.136152 -21.636263)
			(xy 80.170238 -21.59212) (xy 80.210387 -21.553411) (xy 80.255745 -21.52096) (xy 80.305345 -21.495459)
			(xy 80.358129 -21.477452) (xy 80.412972 -21.467322) (xy 80.468706 -21.465285) (xy 80.524143 -21.471385)
			(xy 80.5781 -21.485491) (xy 80.629429 -21.507303) (xy 80.677035 -21.536357) (xy 80.719903 -21.572032)
			(xy 80.75712 -21.613569) (xy 80.787893 -21.660082) (xy 80.811565 -21.710579) (xy 80.827633 -21.763986)
			(xy 80.835753 -21.819162) (xy 80.836262 -21.847048) (xy 80.835753 -21.874934) (xy 80.827633 -21.93011)
			(xy 80.811565 -21.983517) (xy 80.787893 -22.034014) (xy 80.75712 -22.080527) (xy 80.719903 -22.122064)
			(xy 80.677035 -22.157739) (xy 80.629429 -22.186793) (xy 80.5781 -22.208605) (xy 80.524143 -22.222711)
			(xy 80.468706 -22.228811) (xy 80.412972 -22.226774) (xy 80.358129 -22.216644) (xy 80.305345 -22.198637)
			(xy 80.255745 -22.173136) (xy 80.210387 -22.140685) (xy 80.170238 -22.101976) (xy 80.136152 -22.057833)
			(xy 80.108856 -22.009198) (xy 80.088933 -21.957107) (xy 80.076807 -21.90267) (xy 80.072736 -21.847048)
			(xy 79.601918 -21.847048) (xy 79.602076 -21.855684) (xy 79.601567 -21.88357) (xy 79.593447 -21.938746)
			(xy 79.577379 -21.992153) (xy 79.553707 -22.04265) (xy 79.522934 -22.089163) (xy 79.485717 -22.1307)
			(xy 79.442849 -22.166375) (xy 79.395243 -22.195429) (xy 79.343914 -22.217241) (xy 79.289957 -22.231347)
			(xy 79.23452 -22.237447) (xy 79.178786 -22.23541) (xy 79.123943 -22.22528) (xy 79.071159 -22.207273)
			(xy 79.021559 -22.181772) (xy 78.976201 -22.149321) (xy 78.936052 -22.110612) (xy 78.901966 -22.066469)
			(xy 78.87467 -22.017834) (xy 78.854747 -21.965743) (xy 78.842621 -21.911306) (xy 78.83855 -21.855684)
			(xy 78.69118 -21.855684) (xy 78.690731 -21.858736) (xy 78.674663 -21.912143) (xy 78.650991 -21.96264)
			(xy 78.620218 -22.009153) (xy 78.583001 -22.05069) (xy 78.540133 -22.086365) (xy 78.492527 -22.115419)
			(xy 78.441198 -22.137231) (xy 78.387241 -22.151337) (xy 78.331804 -22.157437) (xy 78.27607 -22.1554)
			(xy 78.221227 -22.14527) (xy 78.168443 -22.127263) (xy 78.118843 -22.101762) (xy 78.073485 -22.069311)
			(xy 78.033336 -22.030602) (xy 77.99925 -21.986459) (xy 77.971954 -21.937824) (xy 77.952031 -21.885733)
			(xy 77.939905 -21.831296) (xy 77.935834 -21.775674) (xy 68.811755 -21.775674) (xy 68.790555 -21.822093)
			(xy 68.761089 -21.867943) (xy 68.725398 -21.909134) (xy 68.684207 -21.944825) (xy 68.638357 -21.974291)
			(xy 68.58878 -21.996933) (xy 68.536485 -22.012288) (xy 68.482537 -22.020044) (xy 68.428035 -22.020044)
			(xy 68.374087 -22.012288) (xy 68.321792 -21.996933) (xy 68.272215 -21.974291) (xy 68.226365 -21.944825)
			(xy 68.185174 -21.909134) (xy 68.149483 -21.867943) (xy 68.120017 -21.822093) (xy 68.097375 -21.772516)
			(xy 68.08202 -21.720221) (xy 68.074264 -21.666273) (xy 68.073778 -21.639022) (xy 61.245875 -21.639022)
			(xy 61.23499 -21.662945) (xy 61.173945 -21.777941) (xy 61.106004 -21.889002) (xy 61.031418 -21.995714)
			(xy 60.950465 -22.097681) (xy 60.863446 -22.194523) (xy 60.770685 -22.28588) (xy 60.672527 -22.371412)
			(xy 60.569338 -22.4508) (xy 60.461501 -22.52375) (xy 60.407855 -22.555454) (xy 77.336394 -22.555454)
			(xy 77.340465 -22.499832) (xy 77.352591 -22.445395) (xy 77.372514 -22.393304) (xy 77.39981 -22.344669)
			(xy 77.433896 -22.300526) (xy 77.474045 -22.261817) (xy 77.519403 -22.229366) (xy 77.569003 -22.203865)
			(xy 77.621787 -22.185858) (xy 77.67663 -22.175728) (xy 77.732364 -22.173691) (xy 77.787801 -22.179791)
			(xy 77.841758 -22.193897) (xy 77.893087 -22.215709) (xy 77.940693 -22.244763) (xy 77.983561 -22.280438)
			(xy 78.020778 -22.321975) (xy 78.051551 -22.368488) (xy 78.075223 -22.418985) (xy 78.091291 -22.472392)
			(xy 78.099411 -22.527568) (xy 78.09992 -22.555454) (xy 78.099411 -22.58334) (xy 78.091291 -22.638516)
			(xy 78.075223 -22.691923) (xy 78.051551 -22.74242) (xy 78.020778 -22.788933) (xy 77.983561 -22.83047)
			(xy 77.940693 -22.866145) (xy 77.893087 -22.895199) (xy 77.841758 -22.917011) (xy 77.787801 -22.931117)
			(xy 77.732364 -22.937217) (xy 77.67663 -22.93518) (xy 77.621787 -22.92505) (xy 77.569003 -22.907043)
			(xy 77.519403 -22.881542) (xy 77.474045 -22.849091) (xy 77.433896 -22.810382) (xy 77.39981 -22.766239)
			(xy 77.372514 -22.717604) (xy 77.352591 -22.665513) (xy 77.340465 -22.611076) (xy 77.336394 -22.555454)
			(xy 60.407855 -22.555454) (xy 60.349416 -22.589991) (xy 60.233503 -22.649274) (xy 60.11419 -22.701382)
			(xy 59.991923 -22.746118) (xy 59.867156 -22.783317) (xy 59.740353 -22.812841) (xy 59.611986 -22.834579)
			(xy 59.482533 -22.848452) (xy 59.352474 -22.854406) (xy 59.222295 -22.852421) (xy 59.092479 -22.842503)
			(xy 58.963509 -22.824689) (xy 58.835864 -22.799046) (xy 58.710021 -22.765669) (xy 58.586446 -22.724682)
			(xy 58.4656 -22.676238) (xy 58.347932 -22.620516) (xy 58.23388 -22.557725) (xy 58.123868 -22.488098)
			(xy 58.018306 -22.411893) (xy 57.917586 -22.329394) (xy 57.822082 -22.240909) (xy 57.73215 -22.146766)
			(xy 57.648125 -22.047315) (xy 57.57032 -21.942927) (xy 57.499023 -21.83399) (xy 57.434499 -21.720908)
			(xy 57.37699 -21.604104) (xy 57.326708 -21.484011) (xy 57.283842 -21.361075) (xy 57.248549 -21.235756)
			(xy 57.220963 -21.108517) (xy 57.201184 -20.979834) (xy 57.189288 -20.850184) (xy 57.185318 -20.72005)
			(xy 50.954789 -20.72005) (xy 50.934593 -20.74259) (xy 50.891725 -20.778265) (xy 50.844119 -20.807319)
			(xy 50.79279 -20.829131) (xy 50.738833 -20.843237) (xy 50.683396 -20.849337) (xy 50.627662 -20.8473)
			(xy 50.572819 -20.83717) (xy 50.520035 -20.819163) (xy 50.470435 -20.793662) (xy 50.425077 -20.761211)
			(xy 50.384928 -20.722502) (xy 50.350842 -20.678359) (xy 50.323546 -20.629724) (xy 50.303623 -20.577633)
			(xy 50.291497 -20.523196) (xy 50.287426 -20.467574) (xy 42.806331 -20.467574) (xy 42.785557 -20.510388)
			(xy 42.752992 -20.557752) (xy 42.733722 -20.57908) (xy 42.727118 -20.585938) (xy 42.720006 -20.603972)
			(xy 42.720006 -20.692872) (xy 42.727118 -20.710906) (xy 42.733722 -20.717764) (xy 42.753013 -20.739073)
			(xy 42.785573 -20.78644) (xy 42.810661 -20.838155) (xy 42.827707 -20.893048) (xy 42.836326 -20.949877)
			(xy 42.836324 -21.007355) (xy 42.8277 -21.064184) (xy 42.810649 -21.119075) (xy 42.785557 -21.170788)
			(xy 42.752992 -21.218152) (xy 42.733722 -21.23948) (xy 42.727118 -21.246338) (xy 42.720006 -21.264372)
			(xy 42.720006 -21.353272) (xy 42.727118 -21.371306) (xy 42.733722 -21.378164) (xy 42.752997 -21.399488)
			(xy 42.785564 -21.44685) (xy 42.810656 -21.498562) (xy 42.827706 -21.553454) (xy 42.836327 -21.610283)
			(xy 42.836846 -21.639022) (xy 42.83636 -21.666273) (xy 42.828604 -21.720221) (xy 42.813249 -21.772516)
			(xy 42.811807 -21.775674) (xy 51.935886 -21.775674) (xy 51.939957 -21.720052) (xy 51.952083 -21.665615)
			(xy 51.972006 -21.613524) (xy 51.999302 -21.564889) (xy 52.033388 -21.520746) (xy 52.073537 -21.482037)
			(xy 52.118895 -21.449586) (xy 52.168495 -21.424085) (xy 52.221279 -21.406078) (xy 52.276122 -21.395948)
			(xy 52.331856 -21.393911) (xy 52.387293 -21.400011) (xy 52.44125 -21.414117) (xy 52.492579 -21.435929)
			(xy 52.540185 -21.464983) (xy 52.583053 -21.500658) (xy 52.62027 -21.542195) (xy 52.651043 -21.588708)
			(xy 52.674715 -21.639205) (xy 52.690783 -21.692612) (xy 52.698903 -21.747788) (xy 52.699412 -21.775674)
			(xy 52.698903 -21.80356) (xy 52.691232 -21.855684) (xy 52.838602 -21.855684) (xy 52.842673 -21.800062)
			(xy 52.854799 -21.745625) (xy 52.874722 -21.693534) (xy 52.902018 -21.644899) (xy 52.936104 -21.600756)
			(xy 52.976253 -21.562047) (xy 53.021611 -21.529596) (xy 53.071211 -21.504095) (xy 53.123995 -21.486088)
			(xy 53.178838 -21.475958) (xy 53.234572 -21.473921) (xy 53.290009 -21.480021) (xy 53.343966 -21.494127)
			(xy 53.395295 -21.515939) (xy 53.442901 -21.544993) (xy 53.485769 -21.580668) (xy 53.522986 -21.622205)
			(xy 53.553759 -21.668718) (xy 53.577431 -21.719215) (xy 53.593499 -21.772622) (xy 53.601619 -21.827798)
			(xy 53.60197 -21.847048) (xy 54.072788 -21.847048) (xy 54.076859 -21.791426) (xy 54.088985 -21.736989)
			(xy 54.108908 -21.684898) (xy 54.136204 -21.636263) (xy 54.17029 -21.59212) (xy 54.210439 -21.553411)
			(xy 54.255797 -21.52096) (xy 54.305397 -21.495459) (xy 54.358181 -21.477452) (xy 54.413024 -21.467322)
			(xy 54.468758 -21.465285) (xy 54.524195 -21.471385) (xy 54.578152 -21.485491) (xy 54.629481 -21.507303)
			(xy 54.677087 -21.536357) (xy 54.719955 -21.572032) (xy 54.757172 -21.613569) (xy 54.787945 -21.660082)
			(xy 54.811617 -21.710579) (xy 54.827685 -21.763986) (xy 54.835805 -21.819162) (xy 54.836314 -21.847048)
			(xy 54.835805 -21.874934) (xy 54.827685 -21.93011) (xy 54.811617 -21.983517) (xy 54.787945 -22.034014)
			(xy 54.757172 -22.080527) (xy 54.719955 -22.122064) (xy 54.677087 -22.157739) (xy 54.629481 -22.186793)
			(xy 54.578152 -22.208605) (xy 54.524195 -22.222711) (xy 54.468758 -22.228811) (xy 54.413024 -22.226774)
			(xy 54.358181 -22.216644) (xy 54.305397 -22.198637) (xy 54.255797 -22.173136) (xy 54.210439 -22.140685)
			(xy 54.17029 -22.101976) (xy 54.136204 -22.057833) (xy 54.108908 -22.009198) (xy 54.088985 -21.957107)
			(xy 54.076859 -21.90267) (xy 54.072788 -21.847048) (xy 53.60197 -21.847048) (xy 53.602128 -21.855684)
			(xy 53.601619 -21.88357) (xy 53.593499 -21.938746) (xy 53.577431 -21.992153) (xy 53.553759 -22.04265)
			(xy 53.522986 -22.089163) (xy 53.485769 -22.1307) (xy 53.442901 -22.166375) (xy 53.395295 -22.195429)
			(xy 53.343966 -22.217241) (xy 53.290009 -22.231347) (xy 53.234572 -22.237447) (xy 53.178838 -22.23541)
			(xy 53.123995 -22.22528) (xy 53.071211 -22.207273) (xy 53.021611 -22.181772) (xy 52.976253 -22.149321)
			(xy 52.936104 -22.110612) (xy 52.902018 -22.066469) (xy 52.874722 -22.017834) (xy 52.854799 -21.965743)
			(xy 52.842673 -21.911306) (xy 52.838602 -21.855684) (xy 52.691232 -21.855684) (xy 52.690783 -21.858736)
			(xy 52.674715 -21.912143) (xy 52.651043 -21.96264) (xy 52.62027 -22.009153) (xy 52.583053 -22.05069)
			(xy 52.540185 -22.086365) (xy 52.492579 -22.115419) (xy 52.44125 -22.137231) (xy 52.387293 -22.151337)
			(xy 52.331856 -22.157437) (xy 52.276122 -22.1554) (xy 52.221279 -22.14527) (xy 52.168495 -22.127263)
			(xy 52.118895 -22.101762) (xy 52.073537 -22.069311) (xy 52.033388 -22.030602) (xy 51.999302 -21.986459)
			(xy 51.972006 -21.937824) (xy 51.952083 -21.885733) (xy 51.939957 -21.831296) (xy 51.935886 -21.775674)
			(xy 42.811807 -21.775674) (xy 42.790607 -21.822093) (xy 42.761141 -21.867943) (xy 42.72545 -21.909134)
			(xy 42.684259 -21.944825) (xy 42.638409 -21.974291) (xy 42.588832 -21.996933) (xy 42.536537 -22.012288)
			(xy 42.482589 -22.020044) (xy 42.428087 -22.020044) (xy 42.374139 -22.012288) (xy 42.321844 -21.996933)
			(xy 42.272267 -21.974291) (xy 42.226417 -21.944825) (xy 42.185226 -21.909134) (xy 42.149535 -21.867943)
			(xy 42.120069 -21.822093) (xy 42.097427 -21.772516) (xy 42.082072 -21.720221) (xy 42.074316 -21.666273)
			(xy 42.07383 -21.639022) (xy 35.245927 -21.639022) (xy 35.235042 -21.662945) (xy 35.173997 -21.777941)
			(xy 35.106056 -21.889002) (xy 35.03147 -21.995714) (xy 34.950517 -22.097681) (xy 34.863498 -22.194523)
			(xy 34.770737 -22.28588) (xy 34.672579 -22.371412) (xy 34.56939 -22.4508) (xy 34.461553 -22.52375)
			(xy 34.407907 -22.555454) (xy 51.336446 -22.555454) (xy 51.340517 -22.499832) (xy 51.352643 -22.445395)
			(xy 51.372566 -22.393304) (xy 51.399862 -22.344669) (xy 51.433948 -22.300526) (xy 51.474097 -22.261817)
			(xy 51.519455 -22.229366) (xy 51.569055 -22.203865) (xy 51.621839 -22.185858) (xy 51.676682 -22.175728)
			(xy 51.732416 -22.173691) (xy 51.787853 -22.179791) (xy 51.84181 -22.193897) (xy 51.893139 -22.215709)
			(xy 51.940745 -22.244763) (xy 51.983613 -22.280438) (xy 52.02083 -22.321975) (xy 52.051603 -22.368488)
			(xy 52.075275 -22.418985) (xy 52.091343 -22.472392) (xy 52.099463 -22.527568) (xy 52.099972 -22.555454)
			(xy 52.099463 -22.58334) (xy 52.091343 -22.638516) (xy 52.075275 -22.691923) (xy 52.051603 -22.74242)
			(xy 52.02083 -22.788933) (xy 51.983613 -22.83047) (xy 51.940745 -22.866145) (xy 51.893139 -22.895199)
			(xy 51.84181 -22.917011) (xy 51.787853 -22.931117) (xy 51.732416 -22.937217) (xy 51.676682 -22.93518)
			(xy 51.621839 -22.92505) (xy 51.569055 -22.907043) (xy 51.519455 -22.881542) (xy 51.474097 -22.849091)
			(xy 51.433948 -22.810382) (xy 51.399862 -22.766239) (xy 51.372566 -22.717604) (xy 51.352643 -22.665513)
			(xy 51.340517 -22.611076) (xy 51.336446 -22.555454) (xy 34.407907 -22.555454) (xy 34.349468 -22.589991)
			(xy 34.233555 -22.649274) (xy 34.114242 -22.701382) (xy 33.991975 -22.746118) (xy 33.867208 -22.783317)
			(xy 33.740405 -22.812841) (xy 33.612038 -22.834579) (xy 33.482585 -22.848452) (xy 33.352526 -22.854406)
			(xy 33.222347 -22.852421) (xy 33.092531 -22.842503) (xy 32.963561 -22.824689) (xy 32.835916 -22.799046)
			(xy 32.710073 -22.765669) (xy 32.586498 -22.724682) (xy 32.465652 -22.676238) (xy 32.347984 -22.620516)
			(xy 32.233932 -22.557725) (xy 32.12392 -22.488098) (xy 32.018358 -22.411893) (xy 31.917638 -22.329394)
			(xy 31.822134 -22.240909) (xy 31.732202 -22.146766) (xy 31.648177 -22.047315) (xy 31.570372 -21.942927)
			(xy 31.499075 -21.83399) (xy 31.434551 -21.720908) (xy 31.377042 -21.604104) (xy 31.32676 -21.484011)
			(xy 31.283894 -21.361075) (xy 31.248601 -21.235756) (xy 31.221015 -21.108517) (xy 31.201236 -20.979834)
			(xy 31.18934 -20.850184) (xy 31.18537 -20.72005) (xy 16.735844 -20.72005) (xy 16.753067 -20.739072)
			(xy 16.785631 -20.786437) (xy 16.810722 -20.838152) (xy 16.82777 -20.893046) (xy 16.836391 -20.949876)
			(xy 16.836389 -21.007356) (xy 16.827763 -21.064185) (xy 16.81071 -21.119078) (xy 16.785615 -21.17079)
			(xy 16.753047 -21.218153) (xy 16.733774 -21.23948) (xy 16.72717 -21.246338) (xy 16.720058 -21.264372)
			(xy 16.720058 -21.353272) (xy 16.72717 -21.371306) (xy 16.733774 -21.378164) (xy 16.753057 -21.39948)
			(xy 16.785621 -21.446845) (xy 16.810711 -21.49856) (xy 16.827759 -21.553453) (xy 16.836379 -21.610282)
			(xy 16.836898 -21.639022) (xy 16.836412 -21.666273) (xy 16.828656 -21.720221) (xy 16.813301 -21.772516)
			(xy 16.790659 -21.822093) (xy 16.761193 -21.867943) (xy 16.725502 -21.909134) (xy 16.684311 -21.944825)
			(xy 16.638461 -21.974291) (xy 16.588884 -21.996933) (xy 16.536589 -22.012288) (xy 16.482641 -22.020044)
			(xy 16.428139 -22.020044) (xy 16.374191 -22.012288) (xy 16.321896 -21.996933) (xy 16.272319 -21.974291)
			(xy 16.226469 -21.944825) (xy 16.185278 -21.909134) (xy 16.149587 -21.867943) (xy 16.120121 -21.822093)
			(xy 16.097479 -21.772516) (xy 16.082124 -21.720221) (xy 16.074368 -21.666273) (xy 16.073882 -21.639022)
			(xy 9.245979 -21.639022) (xy 9.235094 -21.662945) (xy 9.174049 -21.777941) (xy 9.106108 -21.889002)
			(xy 9.031522 -21.995714) (xy 8.950569 -22.097681) (xy 8.86355 -22.194523) (xy 8.770789 -22.28588)
			(xy 8.672631 -22.371412) (xy 8.569442 -22.4508) (xy 8.461605 -22.52375) (xy 8.34952 -22.589991) (xy 8.233607 -22.649274)
			(xy 8.114294 -22.701382) (xy 7.992027 -22.746118) (xy 7.86726 -22.783317) (xy 7.740457 -22.812841)
			(xy 7.61209 -22.834579) (xy 7.482637 -22.848452) (xy 7.352578 -22.854406) (xy 7.222399 -22.852421)
			(xy 7.092583 -22.842503) (xy 6.963613 -22.824689) (xy 6.835968 -22.799046) (xy 6.710125 -22.765669)
			(xy 6.58655 -22.724682) (xy 6.465704 -22.676238) (xy 6.348036 -22.620516) (xy 6.233984 -22.557725)
			(xy 6.123972 -22.488098) (xy 6.01841 -22.411893) (xy 5.91769 -22.329394) (xy 5.822186 -22.240909)
			(xy 5.732254 -22.146766) (xy 5.648229 -22.047315) (xy 5.570424 -21.942927) (xy 5.499127 -21.83399)
			(xy 5.434603 -21.720908) (xy 5.377094 -21.604104) (xy 5.326812 -21.484011) (xy 5.283946 -21.361075)
			(xy 5.248653 -21.235756) (xy 5.221067 -21.108517) (xy 5.201288 -20.979834) (xy 5.189392 -20.850184)
			(xy 5.185422 -20.72005) (xy 1.306576 -20.72005) (xy 1.306576 -22.45995) (xy 1.849626 -22.45995) (xy 1.853697 -22.404328)
			(xy 1.865823 -22.349891) (xy 1.885746 -22.2978) (xy 1.913042 -22.249165) (xy 1.947128 -22.205022)
			(xy 1.987277 -22.166313) (xy 2.032635 -22.133862) (xy 2.082235 -22.108361) (xy 2.135019 -22.090354)
			(xy 2.189862 -22.080224) (xy 2.245596 -22.078187) (xy 2.301033 -22.084287) (xy 2.35499 -22.098393)
			(xy 2.406319 -22.120205) (xy 2.453925 -22.149259) (xy 2.496793 -22.184934) (xy 2.53401 -22.226471)
			(xy 2.564783 -22.272984) (xy 2.588455 -22.323481) (xy 2.589623 -22.327362) (xy 2.865626 -22.327362)
			(xy 2.869697 -22.27174) (xy 2.881823 -22.217303) (xy 2.901746 -22.165212) (xy 2.929042 -22.116577)
			(xy 2.963128 -22.072434) (xy 3.003277 -22.033725) (xy 3.048635 -22.001274) (xy 3.098235 -21.975773)
			(xy 3.151019 -21.957766) (xy 3.205862 -21.947636) (xy 3.261596 -21.945599) (xy 3.317033 -21.951699)
			(xy 3.37099 -21.965805) (xy 3.422319 -21.987617) (xy 3.469925 -22.016671) (xy 3.512793 -22.052346)
			(xy 3.55001 -22.093883) (xy 3.580783 -22.140396) (xy 3.604455 -22.190893) (xy 3.620523 -22.2443)
			(xy 3.628643 -22.299476) (xy 3.629152 -22.327362) (xy 3.628643 -22.355248) (xy 3.620523 -22.410424)
			(xy 3.604455 -22.463831) (xy 3.580783 -22.514328) (xy 3.55001 -22.560841) (xy 3.512793 -22.602378)
			(xy 3.469925 -22.638053) (xy 3.422319 -22.667107) (xy 3.37099 -22.688919) (xy 3.317033 -22.703025)
			(xy 3.261596 -22.709125) (xy 3.205862 -22.707088) (xy 3.151019 -22.696958) (xy 3.098235 -22.678951)
			(xy 3.048635 -22.65345) (xy 3.003277 -22.620999) (xy 2.963128 -22.58229) (xy 2.929042 -22.538147)
			(xy 2.901746 -22.489512) (xy 2.881823 -22.437421) (xy 2.869697 -22.382984) (xy 2.865626 -22.327362)
			(xy 2.589623 -22.327362) (xy 2.604523 -22.376888) (xy 2.612643 -22.432064) (xy 2.613152 -22.45995)
			(xy 2.612643 -22.487836) (xy 2.604523 -22.543012) (xy 2.588455 -22.596419) (xy 2.564783 -22.646916)
			(xy 2.53401 -22.693429) (xy 2.496793 -22.734966) (xy 2.453925 -22.770641) (xy 2.406319 -22.799695)
			(xy 2.35499 -22.821507) (xy 2.301033 -22.835613) (xy 2.245596 -22.841713) (xy 2.189862 -22.839676)
			(xy 2.135019 -22.829546) (xy 2.082235 -22.811539) (xy 2.032635 -22.786038) (xy 1.987277 -22.753587)
			(xy 1.947128 -22.714878) (xy 1.913042 -22.670735) (xy 1.885746 -22.6221) (xy 1.865823 -22.570009)
			(xy 1.853697 -22.515572) (xy 1.849626 -22.45995) (xy 1.306576 -22.45995) (xy 1.306576 -22.86) (xy 4.189982 -22.86)
			(xy 4.194053 -22.804378) (xy 4.206179 -22.749941) (xy 4.226102 -22.69785) (xy 4.253398 -22.649215)
			(xy 4.287484 -22.605072) (xy 4.327633 -22.566363) (xy 4.372991 -22.533912) (xy 4.422591 -22.508411)
			(xy 4.475375 -22.490404) (xy 4.530218 -22.480274) (xy 4.585952 -22.478237) (xy 4.641389 -22.484337)
			(xy 4.695346 -22.498443) (xy 4.746675 -22.520255) (xy 4.794281 -22.549309) (xy 4.837149 -22.584984)
			(xy 4.874366 -22.626521) (xy 4.905139 -22.673034) (xy 4.928811 -22.723531) (xy 4.944879 -22.776938)
			(xy 4.952999 -22.832114) (xy 4.953508 -22.86) (xy 4.952999 -22.887886) (xy 4.944879 -22.943062) (xy 4.930743 -22.990048)
			(xy 11.298934 -22.990048) (xy 11.303005 -22.934426) (xy 11.315131 -22.879989) (xy 11.335054 -22.827898)
			(xy 11.36235 -22.779263) (xy 11.396436 -22.73512) (xy 11.436585 -22.696411) (xy 11.481943 -22.66396)
			(xy 11.531543 -22.638459) (xy 11.584327 -22.620452) (xy 11.63917 -22.610322) (xy 11.694904 -22.608285)
			(xy 11.750341 -22.614385) (xy 11.804298 -22.628491) (xy 11.855627 -22.650303) (xy 11.903233 -22.679357)
			(xy 11.946101 -22.715032) (xy 11.983318 -22.756569) (xy 12.014091 -22.803082) (xy 12.037763 -22.853579)
			(xy 12.053831 -22.906986) (xy 12.061951 -22.962162) (xy 12.06246 -22.990048) (xy 12.061982 -23.01621)
			(xy 12.711682 -23.01621) (xy 12.715753 -22.960588) (xy 12.727879 -22.906151) (xy 12.747802 -22.85406)
			(xy 12.775098 -22.805425) (xy 12.809184 -22.761282) (xy 12.849333 -22.722573) (xy 12.894691 -22.690122)
			(xy 12.944291 -22.664621) (xy 12.997075 -22.646614) (xy 13.051918 -22.636484) (xy 13.107652 -22.634447)
			(xy 13.163089 -22.640547) (xy 13.217046 -22.654653) (xy 13.268375 -22.676465) (xy 13.315981 -22.705519)
			(xy 13.358849 -22.741194) (xy 13.396066 -22.782731) (xy 13.426839 -22.829244) (xy 13.450511 -22.879741)
			(xy 13.466579 -22.933148) (xy 13.474699 -22.988324) (xy 13.475208 -23.01621) (xy 13.475046 -23.0251)
			(xy 37.362382 -23.0251) (xy 37.366453 -22.969478) (xy 37.378579 -22.915041) (xy 37.398502 -22.86295)
			(xy 37.425798 -22.814315) (xy 37.459884 -22.770172) (xy 37.500033 -22.731463) (xy 37.545391 -22.699012)
			(xy 37.594991 -22.673511) (xy 37.647775 -22.655504) (xy 37.702618 -22.645374) (xy 37.758352 -22.643337)
			(xy 37.813789 -22.649437) (xy 37.867746 -22.663543) (xy 37.919075 -22.685355) (xy 37.966681 -22.714409)
			(xy 38.009549 -22.750084) (xy 38.046766 -22.791621) (xy 38.077539 -22.838134) (xy 38.101211 -22.888631)
			(xy 38.117279 -22.942038) (xy 38.125399 -22.997214) (xy 38.125746 -23.01621) (xy 38.71163 -23.01621)
			(xy 38.715701 -22.960588) (xy 38.727827 -22.906151) (xy 38.74775 -22.85406) (xy 38.775046 -22.805425)
			(xy 38.809132 -22.761282) (xy 38.849281 -22.722573) (xy 38.894639 -22.690122) (xy 38.944239 -22.664621)
			(xy 38.997023 -22.646614) (xy 39.051866 -22.636484) (xy 39.1076 -22.634447) (xy 39.163037 -22.640547)
			(xy 39.216994 -22.654653) (xy 39.268323 -22.676465) (xy 39.315929 -22.705519) (xy 39.358797 -22.741194)
			(xy 39.396014 -22.782731) (xy 39.426787 -22.829244) (xy 39.450459 -22.879741) (xy 39.466527 -22.933148)
			(xy 39.474647 -22.988324) (xy 39.475156 -23.01621) (xy 39.474994 -23.0251) (xy 63.36233 -23.0251)
			(xy 63.366401 -22.969478) (xy 63.378527 -22.915041) (xy 63.39845 -22.86295) (xy 63.425746 -22.814315)
			(xy 63.459832 -22.770172) (xy 63.499981 -22.731463) (xy 63.545339 -22.699012) (xy 63.594939 -22.673511)
			(xy 63.647723 -22.655504) (xy 63.702566 -22.645374) (xy 63.7583 -22.643337) (xy 63.813737 -22.649437)
			(xy 63.867694 -22.663543) (xy 63.919023 -22.685355) (xy 63.966629 -22.714409) (xy 64.009497 -22.750084)
			(xy 64.046714 -22.791621) (xy 64.077487 -22.838134) (xy 64.101159 -22.888631) (xy 64.117227 -22.942038)
			(xy 64.125347 -22.997214) (xy 64.125694 -23.01621) (xy 64.711578 -23.01621) (xy 64.715649 -22.960588)
			(xy 64.727775 -22.906151) (xy 64.747698 -22.85406) (xy 64.774994 -22.805425) (xy 64.80908 -22.761282)
			(xy 64.849229 -22.722573) (xy 64.894587 -22.690122) (xy 64.944187 -22.664621) (xy 64.996971 -22.646614)
			(xy 65.051814 -22.636484) (xy 65.107548 -22.634447) (xy 65.162985 -22.640547) (xy 65.216942 -22.654653)
			(xy 65.268271 -22.676465) (xy 65.315877 -22.705519) (xy 65.358745 -22.741194) (xy 65.395962 -22.782731)
			(xy 65.426735 -22.829244) (xy 65.450407 -22.879741) (xy 65.466475 -22.933148) (xy 65.474595 -22.988324)
			(xy 65.475104 -23.01621) (xy 65.474942 -23.0251) (xy 89.362278 -23.0251) (xy 89.366349 -22.969478)
			(xy 89.378475 -22.915041) (xy 89.398398 -22.86295) (xy 89.425694 -22.814315) (xy 89.45978 -22.770172)
			(xy 89.499929 -22.731463) (xy 89.545287 -22.699012) (xy 89.594887 -22.673511) (xy 89.647671 -22.655504)
			(xy 89.702514 -22.645374) (xy 89.758248 -22.643337) (xy 89.813685 -22.649437) (xy 89.867642 -22.663543)
			(xy 89.918971 -22.685355) (xy 89.966577 -22.714409) (xy 90.009445 -22.750084) (xy 90.046662 -22.791621)
			(xy 90.077435 -22.838134) (xy 90.101107 -22.888631) (xy 90.117175 -22.942038) (xy 90.125295 -22.997214)
			(xy 90.125642 -23.01621) (xy 90.711526 -23.01621) (xy 90.715597 -22.960588) (xy 90.727723 -22.906151)
			(xy 90.747646 -22.85406) (xy 90.774942 -22.805425) (xy 90.809028 -22.761282) (xy 90.849177 -22.722573)
			(xy 90.894535 -22.690122) (xy 90.944135 -22.664621) (xy 90.996919 -22.646614) (xy 91.051762 -22.636484)
			(xy 91.107496 -22.634447) (xy 91.162933 -22.640547) (xy 91.21689 -22.654653) (xy 91.268219 -22.676465)
			(xy 91.315825 -22.705519) (xy 91.358693 -22.741194) (xy 91.39591 -22.782731) (xy 91.426683 -22.829244)
			(xy 91.450355 -22.879741) (xy 91.466423 -22.933148) (xy 91.474543 -22.988324) (xy 91.475052 -23.01621)
			(xy 91.47489 -23.0251) (xy 127.462532 -23.0251) (xy 127.466603 -22.969478) (xy 127.478729 -22.915041)
			(xy 127.498652 -22.86295) (xy 127.525948 -22.814315) (xy 127.560034 -22.770172) (xy 127.600183 -22.731463)
			(xy 127.645541 -22.699012) (xy 127.695141 -22.673511) (xy 127.747925 -22.655504) (xy 127.802768 -22.645374)
			(xy 127.858502 -22.643337) (xy 127.913939 -22.649437) (xy 127.967896 -22.663543) (xy 128.019225 -22.685355)
			(xy 128.066831 -22.714409) (xy 128.109699 -22.750084) (xy 128.146916 -22.791621) (xy 128.177689 -22.838134)
			(xy 128.201361 -22.888631) (xy 128.217429 -22.942038) (xy 128.225549 -22.997214) (xy 128.225896 -23.01621)
			(xy 128.81178 -23.01621) (xy 128.815851 -22.960588) (xy 128.827977 -22.906151) (xy 128.8479 -22.85406)
			(xy 128.875196 -22.805425) (xy 128.909282 -22.761282) (xy 128.949431 -22.722573) (xy 128.994789 -22.690122)
			(xy 129.044389 -22.664621) (xy 129.097173 -22.646614) (xy 129.152016 -22.636484) (xy 129.20775 -22.634447)
			(xy 129.263187 -22.640547) (xy 129.317144 -22.654653) (xy 129.368473 -22.676465) (xy 129.416079 -22.705519)
			(xy 129.458947 -22.741194) (xy 129.496164 -22.782731) (xy 129.526937 -22.829244) (xy 129.550609 -22.879741)
			(xy 129.566677 -22.933148) (xy 129.574797 -22.988324) (xy 129.575306 -23.01621) (xy 129.575144 -23.0251)
			(xy 153.46248 -23.0251) (xy 153.466551 -22.969478) (xy 153.478677 -22.915041) (xy 153.4986 -22.86295)
			(xy 153.525896 -22.814315) (xy 153.559982 -22.770172) (xy 153.600131 -22.731463) (xy 153.645489 -22.699012)
			(xy 153.695089 -22.673511) (xy 153.747873 -22.655504) (xy 153.802716 -22.645374) (xy 153.85845 -22.643337)
			(xy 153.913887 -22.649437) (xy 153.967844 -22.663543) (xy 154.019173 -22.685355) (xy 154.066779 -22.714409)
			(xy 154.109647 -22.750084) (xy 154.146864 -22.791621) (xy 154.177637 -22.838134) (xy 154.201309 -22.888631)
			(xy 154.217377 -22.942038) (xy 154.225497 -22.997214) (xy 154.225844 -23.01621) (xy 154.811728 -23.01621)
			(xy 154.815799 -22.960588) (xy 154.827925 -22.906151) (xy 154.847848 -22.85406) (xy 154.875144 -22.805425)
			(xy 154.90923 -22.761282) (xy 154.949379 -22.722573) (xy 154.994737 -22.690122) (xy 155.044337 -22.664621)
			(xy 155.097121 -22.646614) (xy 155.151964 -22.636484) (xy 155.207698 -22.634447) (xy 155.263135 -22.640547)
			(xy 155.317092 -22.654653) (xy 155.368421 -22.676465) (xy 155.416027 -22.705519) (xy 155.458895 -22.741194)
			(xy 155.496112 -22.782731) (xy 155.526885 -22.829244) (xy 155.550557 -22.879741) (xy 155.566625 -22.933148)
			(xy 155.574745 -22.988324) (xy 155.575254 -23.01621) (xy 155.575092 -23.0251) (xy 179.462428 -23.0251)
			(xy 179.466499 -22.969478) (xy 179.478625 -22.915041) (xy 179.498548 -22.86295) (xy 179.525844 -22.814315)
			(xy 179.55993 -22.770172) (xy 179.600079 -22.731463) (xy 179.645437 -22.699012) (xy 179.695037 -22.673511)
			(xy 179.747821 -22.655504) (xy 179.802664 -22.645374) (xy 179.858398 -22.643337) (xy 179.913835 -22.649437)
			(xy 179.967792 -22.663543) (xy 180.019121 -22.685355) (xy 180.066727 -22.714409) (xy 180.109595 -22.750084)
			(xy 180.146812 -22.791621) (xy 180.177585 -22.838134) (xy 180.201257 -22.888631) (xy 180.217325 -22.942038)
			(xy 180.225445 -22.997214) (xy 180.225792 -23.01621) (xy 180.811676 -23.01621) (xy 180.815747 -22.960588)
			(xy 180.827873 -22.906151) (xy 180.847796 -22.85406) (xy 180.875092 -22.805425) (xy 180.909178 -22.761282)
			(xy 180.949327 -22.722573) (xy 180.994685 -22.690122) (xy 181.044285 -22.664621) (xy 181.097069 -22.646614)
			(xy 181.151912 -22.636484) (xy 181.207646 -22.634447) (xy 181.263083 -22.640547) (xy 181.31704 -22.654653)
			(xy 181.368369 -22.676465) (xy 181.415975 -22.705519) (xy 181.458843 -22.741194) (xy 181.49606 -22.782731)
			(xy 181.526833 -22.829244) (xy 181.550505 -22.879741) (xy 181.566573 -22.933148) (xy 181.574693 -22.988324)
			(xy 181.575202 -23.01621) (xy 181.57504 -23.0251) (xy 205.462376 -23.0251) (xy 205.466447 -22.969478)
			(xy 205.478573 -22.915041) (xy 205.498496 -22.86295) (xy 205.525792 -22.814315) (xy 205.559878 -22.770172)
			(xy 205.600027 -22.731463) (xy 205.645385 -22.699012) (xy 205.694985 -22.673511) (xy 205.747769 -22.655504)
			(xy 205.802612 -22.645374) (xy 205.858346 -22.643337) (xy 205.913783 -22.649437) (xy 205.96774 -22.663543)
			(xy 206.019069 -22.685355) (xy 206.066675 -22.714409) (xy 206.109543 -22.750084) (xy 206.14676 -22.791621)
			(xy 206.177533 -22.838134) (xy 206.201205 -22.888631) (xy 206.217273 -22.942038) (xy 206.225393 -22.997214)
			(xy 206.22574 -23.01621) (xy 206.811624 -23.01621) (xy 206.815695 -22.960588) (xy 206.827821 -22.906151)
			(xy 206.847744 -22.85406) (xy 206.87504 -22.805425) (xy 206.909126 -22.761282) (xy 206.949275 -22.722573)
			(xy 206.994633 -22.690122) (xy 207.044233 -22.664621) (xy 207.097017 -22.646614) (xy 207.15186 -22.636484)
			(xy 207.207594 -22.634447) (xy 207.263031 -22.640547) (xy 207.316988 -22.654653) (xy 207.368317 -22.676465)
			(xy 207.415923 -22.705519) (xy 207.458791 -22.741194) (xy 207.496008 -22.782731) (xy 207.526781 -22.829244)
			(xy 207.550453 -22.879741) (xy 207.566521 -22.933148) (xy 207.574641 -22.988324) (xy 207.57515 -23.01621)
			(xy 207.574988 -23.0251) (xy 243.562376 -23.0251) (xy 243.566447 -22.969478) (xy 243.578573 -22.915041)
			(xy 243.598496 -22.86295) (xy 243.625792 -22.814315) (xy 243.659878 -22.770172) (xy 243.700027 -22.731463)
			(xy 243.745385 -22.699012) (xy 243.794985 -22.673511) (xy 243.847769 -22.655504) (xy 243.902612 -22.645374)
			(xy 243.958346 -22.643337) (xy 244.013783 -22.649437) (xy 244.06774 -22.663543) (xy 244.119069 -22.685355)
			(xy 244.166675 -22.714409) (xy 244.209543 -22.750084) (xy 244.24676 -22.791621) (xy 244.277533 -22.838134)
			(xy 244.301205 -22.888631) (xy 244.317273 -22.942038) (xy 244.325393 -22.997214) (xy 244.32574 -23.01621)
			(xy 244.911624 -23.01621) (xy 244.915695 -22.960588) (xy 244.927821 -22.906151) (xy 244.947744 -22.85406)
			(xy 244.97504 -22.805425) (xy 245.009126 -22.761282) (xy 245.049275 -22.722573) (xy 245.094633 -22.690122)
			(xy 245.144233 -22.664621) (xy 245.197017 -22.646614) (xy 245.25186 -22.636484) (xy 245.307594 -22.634447)
			(xy 245.363031 -22.640547) (xy 245.416988 -22.654653) (xy 245.468317 -22.676465) (xy 245.515923 -22.705519)
			(xy 245.558791 -22.741194) (xy 245.596008 -22.782731) (xy 245.626781 -22.829244) (xy 245.650453 -22.879741)
			(xy 245.666521 -22.933148) (xy 245.674641 -22.988324) (xy 245.67515 -23.01621) (xy 245.674988 -23.0251)
			(xy 269.562324 -23.0251) (xy 269.566395 -22.969478) (xy 269.578521 -22.915041) (xy 269.598444 -22.86295)
			(xy 269.62574 -22.814315) (xy 269.659826 -22.770172) (xy 269.699975 -22.731463) (xy 269.745333 -22.699012)
			(xy 269.794933 -22.673511) (xy 269.847717 -22.655504) (xy 269.90256 -22.645374) (xy 269.958294 -22.643337)
			(xy 270.013731 -22.649437) (xy 270.067688 -22.663543) (xy 270.119017 -22.685355) (xy 270.166623 -22.714409)
			(xy 270.209491 -22.750084) (xy 270.246708 -22.791621) (xy 270.277481 -22.838134) (xy 270.301153 -22.888631)
			(xy 270.317221 -22.942038) (xy 270.325341 -22.997214) (xy 270.325688 -23.01621) (xy 270.911572 -23.01621)
			(xy 270.915643 -22.960588) (xy 270.927769 -22.906151) (xy 270.947692 -22.85406) (xy 270.974988 -22.805425)
			(xy 271.009074 -22.761282) (xy 271.049223 -22.722573) (xy 271.094581 -22.690122) (xy 271.144181 -22.664621)
			(xy 271.196965 -22.646614) (xy 271.251808 -22.636484) (xy 271.307542 -22.634447) (xy 271.362979 -22.640547)
			(xy 271.416936 -22.654653) (xy 271.468265 -22.676465) (xy 271.515871 -22.705519) (xy 271.558739 -22.741194)
			(xy 271.595956 -22.782731) (xy 271.626729 -22.829244) (xy 271.650401 -22.879741) (xy 271.666469 -22.933148)
			(xy 271.674589 -22.988324) (xy 271.675098 -23.01621) (xy 271.674936 -23.0251) (xy 295.562272 -23.0251)
			(xy 295.566343 -22.969478) (xy 295.578469 -22.915041) (xy 295.598392 -22.86295) (xy 295.625688 -22.814315)
			(xy 295.659774 -22.770172) (xy 295.699923 -22.731463) (xy 295.745281 -22.699012) (xy 295.794881 -22.673511)
			(xy 295.847665 -22.655504) (xy 295.902508 -22.645374) (xy 295.958242 -22.643337) (xy 296.013679 -22.649437)
			(xy 296.067636 -22.663543) (xy 296.118965 -22.685355) (xy 296.166571 -22.714409) (xy 296.209439 -22.750084)
			(xy 296.246656 -22.791621) (xy 296.277429 -22.838134) (xy 296.301101 -22.888631) (xy 296.317169 -22.942038)
			(xy 296.325289 -22.997214) (xy 296.325636 -23.01621) (xy 296.91152 -23.01621) (xy 296.915591 -22.960588)
			(xy 296.927717 -22.906151) (xy 296.94764 -22.85406) (xy 296.974936 -22.805425) (xy 297.009022 -22.761282)
			(xy 297.049171 -22.722573) (xy 297.094529 -22.690122) (xy 297.144129 -22.664621) (xy 297.196913 -22.646614)
			(xy 297.251756 -22.636484) (xy 297.30749 -22.634447) (xy 297.362927 -22.640547) (xy 297.416884 -22.654653)
			(xy 297.468213 -22.676465) (xy 297.515819 -22.705519) (xy 297.558687 -22.741194) (xy 297.595904 -22.782731)
			(xy 297.626677 -22.829244) (xy 297.650349 -22.879741) (xy 297.666417 -22.933148) (xy 297.674537 -22.988324)
			(xy 297.675046 -23.01621) (xy 297.674884 -23.0251) (xy 321.56222 -23.0251) (xy 321.566291 -22.969478)
			(xy 321.578417 -22.915041) (xy 321.59834 -22.86295) (xy 321.625636 -22.814315) (xy 321.659722 -22.770172)
			(xy 321.699871 -22.731463) (xy 321.745229 -22.699012) (xy 321.794829 -22.673511) (xy 321.847613 -22.655504)
			(xy 321.902456 -22.645374) (xy 321.95819 -22.643337) (xy 322.013627 -22.649437) (xy 322.067584 -22.663543)
			(xy 322.118913 -22.685355) (xy 322.166519 -22.714409) (xy 322.209387 -22.750084) (xy 322.246604 -22.791621)
			(xy 322.277377 -22.838134) (xy 322.301049 -22.888631) (xy 322.317117 -22.942038) (xy 322.325237 -22.997214)
			(xy 322.325584 -23.01621) (xy 322.911468 -23.01621) (xy 322.915539 -22.960588) (xy 322.927665 -22.906151)
			(xy 322.947588 -22.85406) (xy 322.974884 -22.805425) (xy 323.00897 -22.761282) (xy 323.049119 -22.722573)
			(xy 323.094477 -22.690122) (xy 323.144077 -22.664621) (xy 323.196861 -22.646614) (xy 323.251704 -22.636484)
			(xy 323.307438 -22.634447) (xy 323.362875 -22.640547) (xy 323.416832 -22.654653) (xy 323.468161 -22.676465)
			(xy 323.515767 -22.705519) (xy 323.558635 -22.741194) (xy 323.595852 -22.782731) (xy 323.626625 -22.829244)
			(xy 323.650297 -22.879741) (xy 323.666365 -22.933148) (xy 323.674485 -22.988324) (xy 323.674994 -23.01621)
			(xy 323.674832 -23.0251) (xy 359.662474 -23.0251) (xy 359.666545 -22.969478) (xy 359.678671 -22.915041)
			(xy 359.698594 -22.86295) (xy 359.72589 -22.814315) (xy 359.759976 -22.770172) (xy 359.800125 -22.731463)
			(xy 359.845483 -22.699012) (xy 359.895083 -22.673511) (xy 359.947867 -22.655504) (xy 360.00271 -22.645374)
			(xy 360.058444 -22.643337) (xy 360.113881 -22.649437) (xy 360.167838 -22.663543) (xy 360.219167 -22.685355)
			(xy 360.266773 -22.714409) (xy 360.309641 -22.750084) (xy 360.346858 -22.791621) (xy 360.377631 -22.838134)
			(xy 360.401303 -22.888631) (xy 360.417371 -22.942038) (xy 360.425491 -22.997214) (xy 360.425838 -23.01621)
			(xy 361.011722 -23.01621) (xy 361.015793 -22.960588) (xy 361.027919 -22.906151) (xy 361.047842 -22.85406)
			(xy 361.075138 -22.805425) (xy 361.109224 -22.761282) (xy 361.149373 -22.722573) (xy 361.194731 -22.690122)
			(xy 361.244331 -22.664621) (xy 361.297115 -22.646614) (xy 361.351958 -22.636484) (xy 361.407692 -22.634447)
			(xy 361.463129 -22.640547) (xy 361.517086 -22.654653) (xy 361.568415 -22.676465) (xy 361.616021 -22.705519)
			(xy 361.658889 -22.741194) (xy 361.696106 -22.782731) (xy 361.726879 -22.829244) (xy 361.750551 -22.879741)
			(xy 361.766619 -22.933148) (xy 361.774739 -22.988324) (xy 361.775248 -23.01621) (xy 361.775086 -23.0251)
			(xy 385.662422 -23.0251) (xy 385.666493 -22.969478) (xy 385.678619 -22.915041) (xy 385.698542 -22.86295)
			(xy 385.725838 -22.814315) (xy 385.759924 -22.770172) (xy 385.800073 -22.731463) (xy 385.845431 -22.699012)
			(xy 385.895031 -22.673511) (xy 385.947815 -22.655504) (xy 386.002658 -22.645374) (xy 386.058392 -22.643337)
			(xy 386.113829 -22.649437) (xy 386.167786 -22.663543) (xy 386.219115 -22.685355) (xy 386.266721 -22.714409)
			(xy 386.309589 -22.750084) (xy 386.346806 -22.791621) (xy 386.377579 -22.838134) (xy 386.401251 -22.888631)
			(xy 386.417319 -22.942038) (xy 386.425439 -22.997214) (xy 386.425786 -23.01621) (xy 387.01167 -23.01621)
			(xy 387.015741 -22.960588) (xy 387.027867 -22.906151) (xy 387.04779 -22.85406) (xy 387.075086 -22.805425)
			(xy 387.109172 -22.761282) (xy 387.149321 -22.722573) (xy 387.194679 -22.690122) (xy 387.244279 -22.664621)
			(xy 387.297063 -22.646614) (xy 387.351906 -22.636484) (xy 387.40764 -22.634447) (xy 387.463077 -22.640547)
			(xy 387.517034 -22.654653) (xy 387.568363 -22.676465) (xy 387.615969 -22.705519) (xy 387.658837 -22.741194)
			(xy 387.696054 -22.782731) (xy 387.726827 -22.829244) (xy 387.750499 -22.879741) (xy 387.766567 -22.933148)
			(xy 387.774687 -22.988324) (xy 387.775196 -23.01621) (xy 387.775034 -23.0251) (xy 411.66237 -23.0251)
			(xy 411.666441 -22.969478) (xy 411.678567 -22.915041) (xy 411.69849 -22.86295) (xy 411.725786 -22.814315)
			(xy 411.759872 -22.770172) (xy 411.800021 -22.731463) (xy 411.845379 -22.699012) (xy 411.894979 -22.673511)
			(xy 411.947763 -22.655504) (xy 412.002606 -22.645374) (xy 412.05834 -22.643337) (xy 412.113777 -22.649437)
			(xy 412.167734 -22.663543) (xy 412.219063 -22.685355) (xy 412.266669 -22.714409) (xy 412.309537 -22.750084)
			(xy 412.346754 -22.791621) (xy 412.377527 -22.838134) (xy 412.401199 -22.888631) (xy 412.417267 -22.942038)
			(xy 412.425387 -22.997214) (xy 412.425734 -23.01621) (xy 413.011618 -23.01621) (xy 413.015689 -22.960588)
			(xy 413.027815 -22.906151) (xy 413.047738 -22.85406) (xy 413.075034 -22.805425) (xy 413.10912 -22.761282)
			(xy 413.149269 -22.722573) (xy 413.194627 -22.690122) (xy 413.244227 -22.664621) (xy 413.297011 -22.646614)
			(xy 413.351854 -22.636484) (xy 413.407588 -22.634447) (xy 413.463025 -22.640547) (xy 413.516982 -22.654653)
			(xy 413.568311 -22.676465) (xy 413.615917 -22.705519) (xy 413.658785 -22.741194) (xy 413.696002 -22.782731)
			(xy 413.726775 -22.829244) (xy 413.750447 -22.879741) (xy 413.766515 -22.933148) (xy 413.774635 -22.988324)
			(xy 413.775144 -23.01621) (xy 413.774982 -23.0251) (xy 437.662318 -23.0251) (xy 437.666389 -22.969478)
			(xy 437.678515 -22.915041) (xy 437.698438 -22.86295) (xy 437.725734 -22.814315) (xy 437.75982 -22.770172)
			(xy 437.799969 -22.731463) (xy 437.845327 -22.699012) (xy 437.894927 -22.673511) (xy 437.947711 -22.655504)
			(xy 438.002554 -22.645374) (xy 438.058288 -22.643337) (xy 438.113725 -22.649437) (xy 438.167682 -22.663543)
			(xy 438.219011 -22.685355) (xy 438.266617 -22.714409) (xy 438.309485 -22.750084) (xy 438.346702 -22.791621)
			(xy 438.377475 -22.838134) (xy 438.401147 -22.888631) (xy 438.417215 -22.942038) (xy 438.425335 -22.997214)
			(xy 438.425682 -23.01621) (xy 439.011566 -23.01621) (xy 439.015637 -22.960588) (xy 439.027763 -22.906151)
			(xy 439.047686 -22.85406) (xy 439.074982 -22.805425) (xy 439.109068 -22.761282) (xy 439.149217 -22.722573)
			(xy 439.194575 -22.690122) (xy 439.244175 -22.664621) (xy 439.296959 -22.646614) (xy 439.351802 -22.636484)
			(xy 439.407536 -22.634447) (xy 439.462973 -22.640547) (xy 439.51693 -22.654653) (xy 439.568259 -22.676465)
			(xy 439.615865 -22.705519) (xy 439.658733 -22.741194) (xy 439.69595 -22.782731) (xy 439.726723 -22.829244)
			(xy 439.750395 -22.879741) (xy 439.766463 -22.933148) (xy 439.774583 -22.988324) (xy 439.775092 -23.01621)
			(xy 439.774583 -23.044096) (xy 439.766463 -23.099272) (xy 439.750395 -23.152679) (xy 439.726723 -23.203176)
			(xy 439.69595 -23.249689) (xy 439.658733 -23.291226) (xy 439.615865 -23.326901) (xy 439.568259 -23.355955)
			(xy 439.51693 -23.377767) (xy 439.462973 -23.391873) (xy 439.407536 -23.397973) (xy 439.351802 -23.395936)
			(xy 439.296959 -23.385806) (xy 439.244175 -23.367799) (xy 439.194575 -23.342298) (xy 439.149217 -23.309847)
			(xy 439.109068 -23.271138) (xy 439.074982 -23.226995) (xy 439.047686 -23.17836) (xy 439.027763 -23.126269)
			(xy 439.015637 -23.071832) (xy 439.011566 -23.01621) (xy 438.425682 -23.01621) (xy 438.425844 -23.0251)
			(xy 438.425335 -23.052986) (xy 438.417215 -23.108162) (xy 438.401147 -23.161569) (xy 438.377475 -23.212066)
			(xy 438.346702 -23.258579) (xy 438.309485 -23.300116) (xy 438.266617 -23.335791) (xy 438.219011 -23.364845)
			(xy 438.167682 -23.386657) (xy 438.113725 -23.400763) (xy 438.058288 -23.406863) (xy 438.002554 -23.404826)
			(xy 437.947711 -23.394696) (xy 437.894927 -23.376689) (xy 437.845327 -23.351188) (xy 437.799969 -23.318737)
			(xy 437.75982 -23.280028) (xy 437.725734 -23.235885) (xy 437.698438 -23.18725) (xy 437.678515 -23.135159)
			(xy 437.666389 -23.080722) (xy 437.662318 -23.0251) (xy 413.774982 -23.0251) (xy 413.774635 -23.044096)
			(xy 413.766515 -23.099272) (xy 413.750447 -23.152679) (xy 413.726775 -23.203176) (xy 413.696002 -23.249689)
			(xy 413.658785 -23.291226) (xy 413.615917 -23.326901) (xy 413.568311 -23.355955) (xy 413.516982 -23.377767)
			(xy 413.463025 -23.391873) (xy 413.407588 -23.397973) (xy 413.351854 -23.395936) (xy 413.297011 -23.385806)
			(xy 413.244227 -23.367799) (xy 413.194627 -23.342298) (xy 413.149269 -23.309847) (xy 413.10912 -23.271138)
			(xy 413.075034 -23.226995) (xy 413.047738 -23.17836) (xy 413.027815 -23.126269) (xy 413.015689 -23.071832)
			(xy 413.011618 -23.01621) (xy 412.425734 -23.01621) (xy 412.425896 -23.0251) (xy 412.425387 -23.052986)
			(xy 412.417267 -23.108162) (xy 412.401199 -23.161569) (xy 412.377527 -23.212066) (xy 412.346754 -23.258579)
			(xy 412.309537 -23.300116) (xy 412.266669 -23.335791) (xy 412.219063 -23.364845) (xy 412.167734 -23.386657)
			(xy 412.113777 -23.400763) (xy 412.05834 -23.406863) (xy 412.002606 -23.404826) (xy 411.947763 -23.394696)
			(xy 411.894979 -23.376689) (xy 411.845379 -23.351188) (xy 411.800021 -23.318737) (xy 411.759872 -23.280028)
			(xy 411.725786 -23.235885) (xy 411.69849 -23.18725) (xy 411.678567 -23.135159) (xy 411.666441 -23.080722)
			(xy 411.66237 -23.0251) (xy 387.775034 -23.0251) (xy 387.774687 -23.044096) (xy 387.766567 -23.099272)
			(xy 387.750499 -23.152679) (xy 387.726827 -23.203176) (xy 387.696054 -23.249689) (xy 387.658837 -23.291226)
			(xy 387.615969 -23.326901) (xy 387.568363 -23.355955) (xy 387.517034 -23.377767) (xy 387.463077 -23.391873)
			(xy 387.40764 -23.397973) (xy 387.351906 -23.395936) (xy 387.297063 -23.385806) (xy 387.244279 -23.367799)
			(xy 387.194679 -23.342298) (xy 387.149321 -23.309847) (xy 387.109172 -23.271138) (xy 387.075086 -23.226995)
			(xy 387.04779 -23.17836) (xy 387.027867 -23.126269) (xy 387.015741 -23.071832) (xy 387.01167 -23.01621)
			(xy 386.425786 -23.01621) (xy 386.425948 -23.0251) (xy 386.425439 -23.052986) (xy 386.417319 -23.108162)
			(xy 386.401251 -23.161569) (xy 386.377579 -23.212066) (xy 386.346806 -23.258579) (xy 386.309589 -23.300116)
			(xy 386.266721 -23.335791) (xy 386.219115 -23.364845) (xy 386.167786 -23.386657) (xy 386.113829 -23.400763)
			(xy 386.058392 -23.406863) (xy 386.002658 -23.404826) (xy 385.947815 -23.394696) (xy 385.895031 -23.376689)
			(xy 385.845431 -23.351188) (xy 385.800073 -23.318737) (xy 385.759924 -23.280028) (xy 385.725838 -23.235885)
			(xy 385.698542 -23.18725) (xy 385.678619 -23.135159) (xy 385.666493 -23.080722) (xy 385.662422 -23.0251)
			(xy 361.775086 -23.0251) (xy 361.774739 -23.044096) (xy 361.766619 -23.099272) (xy 361.750551 -23.152679)
			(xy 361.726879 -23.203176) (xy 361.696106 -23.249689) (xy 361.658889 -23.291226) (xy 361.616021 -23.326901)
			(xy 361.568415 -23.355955) (xy 361.517086 -23.377767) (xy 361.463129 -23.391873) (xy 361.407692 -23.397973)
			(xy 361.351958 -23.395936) (xy 361.297115 -23.385806) (xy 361.244331 -23.367799) (xy 361.194731 -23.342298)
			(xy 361.149373 -23.309847) (xy 361.109224 -23.271138) (xy 361.075138 -23.226995) (xy 361.047842 -23.17836)
			(xy 361.027919 -23.126269) (xy 361.015793 -23.071832) (xy 361.011722 -23.01621) (xy 360.425838 -23.01621)
			(xy 360.426 -23.0251) (xy 360.425491 -23.052986) (xy 360.417371 -23.108162) (xy 360.401303 -23.161569)
			(xy 360.377631 -23.212066) (xy 360.346858 -23.258579) (xy 360.309641 -23.300116) (xy 360.266773 -23.335791)
			(xy 360.219167 -23.364845) (xy 360.167838 -23.386657) (xy 360.113881 -23.400763) (xy 360.058444 -23.406863)
			(xy 360.00271 -23.404826) (xy 359.947867 -23.394696) (xy 359.895083 -23.376689) (xy 359.845483 -23.351188)
			(xy 359.800125 -23.318737) (xy 359.759976 -23.280028) (xy 359.72589 -23.235885) (xy 359.698594 -23.18725)
			(xy 359.678671 -23.135159) (xy 359.666545 -23.080722) (xy 359.662474 -23.0251) (xy 323.674832 -23.0251)
			(xy 323.674485 -23.044096) (xy 323.666365 -23.099272) (xy 323.650297 -23.152679) (xy 323.626625 -23.203176)
			(xy 323.595852 -23.249689) (xy 323.558635 -23.291226) (xy 323.515767 -23.326901) (xy 323.468161 -23.355955)
			(xy 323.416832 -23.377767) (xy 323.362875 -23.391873) (xy 323.307438 -23.397973) (xy 323.251704 -23.395936)
			(xy 323.196861 -23.385806) (xy 323.144077 -23.367799) (xy 323.094477 -23.342298) (xy 323.049119 -23.309847)
			(xy 323.00897 -23.271138) (xy 322.974884 -23.226995) (xy 322.947588 -23.17836) (xy 322.927665 -23.126269)
			(xy 322.915539 -23.071832) (xy 322.911468 -23.01621) (xy 322.325584 -23.01621) (xy 322.325746 -23.0251)
			(xy 322.325237 -23.052986) (xy 322.317117 -23.108162) (xy 322.301049 -23.161569) (xy 322.277377 -23.212066)
			(xy 322.246604 -23.258579) (xy 322.209387 -23.300116) (xy 322.166519 -23.335791) (xy 322.118913 -23.364845)
			(xy 322.067584 -23.386657) (xy 322.013627 -23.400763) (xy 321.95819 -23.406863) (xy 321.902456 -23.404826)
			(xy 321.847613 -23.394696) (xy 321.794829 -23.376689) (xy 321.745229 -23.351188) (xy 321.699871 -23.318737)
			(xy 321.659722 -23.280028) (xy 321.625636 -23.235885) (xy 321.59834 -23.18725) (xy 321.578417 -23.135159)
			(xy 321.566291 -23.080722) (xy 321.56222 -23.0251) (xy 297.674884 -23.0251) (xy 297.674537 -23.044096)
			(xy 297.666417 -23.099272) (xy 297.650349 -23.152679) (xy 297.626677 -23.203176) (xy 297.595904 -23.249689)
			(xy 297.558687 -23.291226) (xy 297.515819 -23.326901) (xy 297.468213 -23.355955) (xy 297.416884 -23.377767)
			(xy 297.362927 -23.391873) (xy 297.30749 -23.397973) (xy 297.251756 -23.395936) (xy 297.196913 -23.385806)
			(xy 297.144129 -23.367799) (xy 297.094529 -23.342298) (xy 297.049171 -23.309847) (xy 297.009022 -23.271138)
			(xy 296.974936 -23.226995) (xy 296.94764 -23.17836) (xy 296.927717 -23.126269) (xy 296.915591 -23.071832)
			(xy 296.91152 -23.01621) (xy 296.325636 -23.01621) (xy 296.325798 -23.0251) (xy 296.325289 -23.052986)
			(xy 296.317169 -23.108162) (xy 296.301101 -23.161569) (xy 296.277429 -23.212066) (xy 296.246656 -23.258579)
			(xy 296.209439 -23.300116) (xy 296.166571 -23.335791) (xy 296.118965 -23.364845) (xy 296.067636 -23.386657)
			(xy 296.013679 -23.400763) (xy 295.958242 -23.406863) (xy 295.902508 -23.404826) (xy 295.847665 -23.394696)
			(xy 295.794881 -23.376689) (xy 295.745281 -23.351188) (xy 295.699923 -23.318737) (xy 295.659774 -23.280028)
			(xy 295.625688 -23.235885) (xy 295.598392 -23.18725) (xy 295.578469 -23.135159) (xy 295.566343 -23.080722)
			(xy 295.562272 -23.0251) (xy 271.674936 -23.0251) (xy 271.674589 -23.044096) (xy 271.666469 -23.099272)
			(xy 271.650401 -23.152679) (xy 271.626729 -23.203176) (xy 271.595956 -23.249689) (xy 271.558739 -23.291226)
			(xy 271.515871 -23.326901) (xy 271.468265 -23.355955) (xy 271.416936 -23.377767) (xy 271.362979 -23.391873)
			(xy 271.307542 -23.397973) (xy 271.251808 -23.395936) (xy 271.196965 -23.385806) (xy 271.144181 -23.367799)
			(xy 271.094581 -23.342298) (xy 271.049223 -23.309847) (xy 271.009074 -23.271138) (xy 270.974988 -23.226995)
			(xy 270.947692 -23.17836) (xy 270.927769 -23.126269) (xy 270.915643 -23.071832) (xy 270.911572 -23.01621)
			(xy 270.325688 -23.01621) (xy 270.32585 -23.0251) (xy 270.325341 -23.052986) (xy 270.317221 -23.108162)
			(xy 270.301153 -23.161569) (xy 270.277481 -23.212066) (xy 270.246708 -23.258579) (xy 270.209491 -23.300116)
			(xy 270.166623 -23.335791) (xy 270.119017 -23.364845) (xy 270.067688 -23.386657) (xy 270.013731 -23.400763)
			(xy 269.958294 -23.406863) (xy 269.90256 -23.404826) (xy 269.847717 -23.394696) (xy 269.794933 -23.376689)
			(xy 269.745333 -23.351188) (xy 269.699975 -23.318737) (xy 269.659826 -23.280028) (xy 269.62574 -23.235885)
			(xy 269.598444 -23.18725) (xy 269.578521 -23.135159) (xy 269.566395 -23.080722) (xy 269.562324 -23.0251)
			(xy 245.674988 -23.0251) (xy 245.674641 -23.044096) (xy 245.666521 -23.099272) (xy 245.650453 -23.152679)
			(xy 245.626781 -23.203176) (xy 245.596008 -23.249689) (xy 245.558791 -23.291226) (xy 245.515923 -23.326901)
			(xy 245.468317 -23.355955) (xy 245.416988 -23.377767) (xy 245.363031 -23.391873) (xy 245.307594 -23.397973)
			(xy 245.25186 -23.395936) (xy 245.197017 -23.385806) (xy 245.144233 -23.367799) (xy 245.094633 -23.342298)
			(xy 245.049275 -23.309847) (xy 245.009126 -23.271138) (xy 244.97504 -23.226995) (xy 244.947744 -23.17836)
			(xy 244.927821 -23.126269) (xy 244.915695 -23.071832) (xy 244.911624 -23.01621) (xy 244.32574 -23.01621)
			(xy 244.325902 -23.0251) (xy 244.325393 -23.052986) (xy 244.317273 -23.108162) (xy 244.301205 -23.161569)
			(xy 244.277533 -23.212066) (xy 244.24676 -23.258579) (xy 244.209543 -23.300116) (xy 244.166675 -23.335791)
			(xy 244.119069 -23.364845) (xy 244.06774 -23.386657) (xy 244.013783 -23.400763) (xy 243.958346 -23.406863)
			(xy 243.902612 -23.404826) (xy 243.847769 -23.394696) (xy 243.794985 -23.376689) (xy 243.745385 -23.351188)
			(xy 243.700027 -23.318737) (xy 243.659878 -23.280028) (xy 243.625792 -23.235885) (xy 243.598496 -23.18725)
			(xy 243.578573 -23.135159) (xy 243.566447 -23.080722) (xy 243.562376 -23.0251) (xy 207.574988 -23.0251)
			(xy 207.574641 -23.044096) (xy 207.566521 -23.099272) (xy 207.550453 -23.152679) (xy 207.526781 -23.203176)
			(xy 207.496008 -23.249689) (xy 207.458791 -23.291226) (xy 207.415923 -23.326901) (xy 207.368317 -23.355955)
			(xy 207.316988 -23.377767) (xy 207.263031 -23.391873) (xy 207.207594 -23.397973) (xy 207.15186 -23.395936)
			(xy 207.097017 -23.385806) (xy 207.044233 -23.367799) (xy 206.994633 -23.342298) (xy 206.949275 -23.309847)
			(xy 206.909126 -23.271138) (xy 206.87504 -23.226995) (xy 206.847744 -23.17836) (xy 206.827821 -23.126269)
			(xy 206.815695 -23.071832) (xy 206.811624 -23.01621) (xy 206.22574 -23.01621) (xy 206.225902 -23.0251)
			(xy 206.225393 -23.052986) (xy 206.217273 -23.108162) (xy 206.201205 -23.161569) (xy 206.177533 -23.212066)
			(xy 206.14676 -23.258579) (xy 206.109543 -23.300116) (xy 206.066675 -23.335791) (xy 206.019069 -23.364845)
			(xy 205.96774 -23.386657) (xy 205.913783 -23.400763) (xy 205.858346 -23.406863) (xy 205.802612 -23.404826)
			(xy 205.747769 -23.394696) (xy 205.694985 -23.376689) (xy 205.645385 -23.351188) (xy 205.600027 -23.318737)
			(xy 205.559878 -23.280028) (xy 205.525792 -23.235885) (xy 205.498496 -23.18725) (xy 205.478573 -23.135159)
			(xy 205.466447 -23.080722) (xy 205.462376 -23.0251) (xy 181.57504 -23.0251) (xy 181.574693 -23.044096)
			(xy 181.566573 -23.099272) (xy 181.550505 -23.152679) (xy 181.526833 -23.203176) (xy 181.49606 -23.249689)
			(xy 181.458843 -23.291226) (xy 181.415975 -23.326901) (xy 181.368369 -23.355955) (xy 181.31704 -23.377767)
			(xy 181.263083 -23.391873) (xy 181.207646 -23.397973) (xy 181.151912 -23.395936) (xy 181.097069 -23.385806)
			(xy 181.044285 -23.367799) (xy 180.994685 -23.342298) (xy 180.949327 -23.309847) (xy 180.909178 -23.271138)
			(xy 180.875092 -23.226995) (xy 180.847796 -23.17836) (xy 180.827873 -23.126269) (xy 180.815747 -23.071832)
			(xy 180.811676 -23.01621) (xy 180.225792 -23.01621) (xy 180.225954 -23.0251) (xy 180.225445 -23.052986)
			(xy 180.217325 -23.108162) (xy 180.201257 -23.161569) (xy 180.177585 -23.212066) (xy 180.146812 -23.258579)
			(xy 180.109595 -23.300116) (xy 180.066727 -23.335791) (xy 180.019121 -23.364845) (xy 179.967792 -23.386657)
			(xy 179.913835 -23.400763) (xy 179.858398 -23.406863) (xy 179.802664 -23.404826) (xy 179.747821 -23.394696)
			(xy 179.695037 -23.376689) (xy 179.645437 -23.351188) (xy 179.600079 -23.318737) (xy 179.55993 -23.280028)
			(xy 179.525844 -23.235885) (xy 179.498548 -23.18725) (xy 179.478625 -23.135159) (xy 179.466499 -23.080722)
			(xy 179.462428 -23.0251) (xy 155.575092 -23.0251) (xy 155.574745 -23.044096) (xy 155.566625 -23.099272)
			(xy 155.550557 -23.152679) (xy 155.526885 -23.203176) (xy 155.496112 -23.249689) (xy 155.458895 -23.291226)
			(xy 155.416027 -23.326901) (xy 155.368421 -23.355955) (xy 155.317092 -23.377767) (xy 155.263135 -23.391873)
			(xy 155.207698 -23.397973) (xy 155.151964 -23.395936) (xy 155.097121 -23.385806) (xy 155.044337 -23.367799)
			(xy 154.994737 -23.342298) (xy 154.949379 -23.309847) (xy 154.90923 -23.271138) (xy 154.875144 -23.226995)
			(xy 154.847848 -23.17836) (xy 154.827925 -23.126269) (xy 154.815799 -23.071832) (xy 154.811728 -23.01621)
			(xy 154.225844 -23.01621) (xy 154.226006 -23.0251) (xy 154.225497 -23.052986) (xy 154.217377 -23.108162)
			(xy 154.201309 -23.161569) (xy 154.177637 -23.212066) (xy 154.146864 -23.258579) (xy 154.109647 -23.300116)
			(xy 154.066779 -23.335791) (xy 154.019173 -23.364845) (xy 153.967844 -23.386657) (xy 153.913887 -23.400763)
			(xy 153.85845 -23.406863) (xy 153.802716 -23.404826) (xy 153.747873 -23.394696) (xy 153.695089 -23.376689)
			(xy 153.645489 -23.351188) (xy 153.600131 -23.318737) (xy 153.559982 -23.280028) (xy 153.525896 -23.235885)
			(xy 153.4986 -23.18725) (xy 153.478677 -23.135159) (xy 153.466551 -23.080722) (xy 153.46248 -23.0251)
			(xy 129.575144 -23.0251) (xy 129.574797 -23.044096) (xy 129.566677 -23.099272) (xy 129.550609 -23.152679)
			(xy 129.526937 -23.203176) (xy 129.496164 -23.249689) (xy 129.458947 -23.291226) (xy 129.416079 -23.326901)
			(xy 129.368473 -23.355955) (xy 129.317144 -23.377767) (xy 129.263187 -23.391873) (xy 129.20775 -23.397973)
			(xy 129.152016 -23.395936) (xy 129.097173 -23.385806) (xy 129.044389 -23.367799) (xy 128.994789 -23.342298)
			(xy 128.949431 -23.309847) (xy 128.909282 -23.271138) (xy 128.875196 -23.226995) (xy 128.8479 -23.17836)
			(xy 128.827977 -23.126269) (xy 128.815851 -23.071832) (xy 128.81178 -23.01621) (xy 128.225896 -23.01621)
			(xy 128.226058 -23.0251) (xy 128.225549 -23.052986) (xy 128.217429 -23.108162) (xy 128.201361 -23.161569)
			(xy 128.177689 -23.212066) (xy 128.146916 -23.258579) (xy 128.109699 -23.300116) (xy 128.066831 -23.335791)
			(xy 128.019225 -23.364845) (xy 127.967896 -23.386657) (xy 127.913939 -23.400763) (xy 127.858502 -23.406863)
			(xy 127.802768 -23.404826) (xy 127.747925 -23.394696) (xy 127.695141 -23.376689) (xy 127.645541 -23.351188)
			(xy 127.600183 -23.318737) (xy 127.560034 -23.280028) (xy 127.525948 -23.235885) (xy 127.498652 -23.18725)
			(xy 127.478729 -23.135159) (xy 127.466603 -23.080722) (xy 127.462532 -23.0251) (xy 91.47489 -23.0251)
			(xy 91.474543 -23.044096) (xy 91.466423 -23.099272) (xy 91.450355 -23.152679) (xy 91.426683 -23.203176)
			(xy 91.39591 -23.249689) (xy 91.358693 -23.291226) (xy 91.315825 -23.326901) (xy 91.268219 -23.355955)
			(xy 91.21689 -23.377767) (xy 91.162933 -23.391873) (xy 91.107496 -23.397973) (xy 91.051762 -23.395936)
			(xy 90.996919 -23.385806) (xy 90.944135 -23.367799) (xy 90.894535 -23.342298) (xy 90.849177 -23.309847)
			(xy 90.809028 -23.271138) (xy 90.774942 -23.226995) (xy 90.747646 -23.17836) (xy 90.727723 -23.126269)
			(xy 90.715597 -23.071832) (xy 90.711526 -23.01621) (xy 90.125642 -23.01621) (xy 90.125804 -23.0251)
			(xy 90.125295 -23.052986) (xy 90.117175 -23.108162) (xy 90.101107 -23.161569) (xy 90.077435 -23.212066)
			(xy 90.046662 -23.258579) (xy 90.009445 -23.300116) (xy 89.966577 -23.335791) (xy 89.918971 -23.364845)
			(xy 89.867642 -23.386657) (xy 89.813685 -23.400763) (xy 89.758248 -23.406863) (xy 89.702514 -23.404826)
			(xy 89.647671 -23.394696) (xy 89.594887 -23.376689) (xy 89.545287 -23.351188) (xy 89.499929 -23.318737)
			(xy 89.45978 -23.280028) (xy 89.425694 -23.235885) (xy 89.398398 -23.18725) (xy 89.378475 -23.135159)
			(xy 89.366349 -23.080722) (xy 89.362278 -23.0251) (xy 65.474942 -23.0251) (xy 65.474595 -23.044096)
			(xy 65.466475 -23.099272) (xy 65.450407 -23.152679) (xy 65.426735 -23.203176) (xy 65.395962 -23.249689)
			(xy 65.358745 -23.291226) (xy 65.315877 -23.326901) (xy 65.268271 -23.355955) (xy 65.216942 -23.377767)
			(xy 65.162985 -23.391873) (xy 65.107548 -23.397973) (xy 65.051814 -23.395936) (xy 64.996971 -23.385806)
			(xy 64.944187 -23.367799) (xy 64.894587 -23.342298) (xy 64.849229 -23.309847) (xy 64.80908 -23.271138)
			(xy 64.774994 -23.226995) (xy 64.747698 -23.17836) (xy 64.727775 -23.126269) (xy 64.715649 -23.071832)
			(xy 64.711578 -23.01621) (xy 64.125694 -23.01621) (xy 64.125856 -23.0251) (xy 64.125347 -23.052986)
			(xy 64.117227 -23.108162) (xy 64.101159 -23.161569) (xy 64.077487 -23.212066) (xy 64.046714 -23.258579)
			(xy 64.009497 -23.300116) (xy 63.966629 -23.335791) (xy 63.919023 -23.364845) (xy 63.867694 -23.386657)
			(xy 63.813737 -23.400763) (xy 63.7583 -23.406863) (xy 63.702566 -23.404826) (xy 63.647723 -23.394696)
			(xy 63.594939 -23.376689) (xy 63.545339 -23.351188) (xy 63.499981 -23.318737) (xy 63.459832 -23.280028)
			(xy 63.425746 -23.235885) (xy 63.39845 -23.18725) (xy 63.378527 -23.135159) (xy 63.366401 -23.080722)
			(xy 63.36233 -23.0251) (xy 39.474994 -23.0251) (xy 39.474647 -23.044096) (xy 39.466527 -23.099272)
			(xy 39.450459 -23.152679) (xy 39.426787 -23.203176) (xy 39.396014 -23.249689) (xy 39.358797 -23.291226)
			(xy 39.315929 -23.326901) (xy 39.268323 -23.355955) (xy 39.216994 -23.377767) (xy 39.163037 -23.391873)
			(xy 39.1076 -23.397973) (xy 39.051866 -23.395936) (xy 38.997023 -23.385806) (xy 38.944239 -23.367799)
			(xy 38.894639 -23.342298) (xy 38.849281 -23.309847) (xy 38.809132 -23.271138) (xy 38.775046 -23.226995)
			(xy 38.74775 -23.17836) (xy 38.727827 -23.126269) (xy 38.715701 -23.071832) (xy 38.71163 -23.01621)
			(xy 38.125746 -23.01621) (xy 38.125908 -23.0251) (xy 38.125399 -23.052986) (xy 38.117279 -23.108162)
			(xy 38.101211 -23.161569) (xy 38.077539 -23.212066) (xy 38.046766 -23.258579) (xy 38.009549 -23.300116)
			(xy 37.966681 -23.335791) (xy 37.919075 -23.364845) (xy 37.867746 -23.386657) (xy 37.813789 -23.400763)
			(xy 37.758352 -23.406863) (xy 37.702618 -23.404826) (xy 37.647775 -23.394696) (xy 37.594991 -23.376689)
			(xy 37.545391 -23.351188) (xy 37.500033 -23.318737) (xy 37.459884 -23.280028) (xy 37.425798 -23.235885)
			(xy 37.398502 -23.18725) (xy 37.378579 -23.135159) (xy 37.366453 -23.080722) (xy 37.362382 -23.0251)
			(xy 13.475046 -23.0251) (xy 13.474699 -23.044096) (xy 13.466579 -23.099272) (xy 13.450511 -23.152679)
			(xy 13.426839 -23.203176) (xy 13.396066 -23.249689) (xy 13.358849 -23.291226) (xy 13.315981 -23.326901)
			(xy 13.268375 -23.355955) (xy 13.217046 -23.377767) (xy 13.163089 -23.391873) (xy 13.107652 -23.397973)
			(xy 13.051918 -23.395936) (xy 12.997075 -23.385806) (xy 12.944291 -23.367799) (xy 12.894691 -23.342298)
			(xy 12.849333 -23.309847) (xy 12.809184 -23.271138) (xy 12.775098 -23.226995) (xy 12.747802 -23.17836)
			(xy 12.727879 -23.126269) (xy 12.715753 -23.071832) (xy 12.711682 -23.01621) (xy 12.061982 -23.01621)
			(xy 12.061951 -23.017934) (xy 12.053831 -23.07311) (xy 12.037763 -23.126517) (xy 12.014091 -23.177014)
			(xy 11.983318 -23.223527) (xy 11.946101 -23.265064) (xy 11.903233 -23.300739) (xy 11.855627 -23.329793)
			(xy 11.804298 -23.351605) (xy 11.750341 -23.365711) (xy 11.694904 -23.371811) (xy 11.63917 -23.369774)
			(xy 11.584327 -23.359644) (xy 11.531543 -23.341637) (xy 11.481943 -23.316136) (xy 11.436585 -23.283685)
			(xy 11.396436 -23.244976) (xy 11.36235 -23.200833) (xy 11.335054 -23.152198) (xy 11.315131 -23.100107)
			(xy 11.303005 -23.04567) (xy 11.298934 -22.990048) (xy 4.930743 -22.990048) (xy 4.928811 -22.996469)
			(xy 4.905139 -23.046966) (xy 4.874366 -23.093479) (xy 4.837149 -23.135016) (xy 4.794281 -23.170691)
			(xy 4.746675 -23.199745) (xy 4.695346 -23.221557) (xy 4.641389 -23.235663) (xy 4.585952 -23.241763)
			(xy 4.530218 -23.239726) (xy 4.475375 -23.229596) (xy 4.422591 -23.211589) (xy 4.372991 -23.186088)
			(xy 4.327633 -23.153637) (xy 4.287484 -23.114928) (xy 4.253398 -23.070785) (xy 4.226102 -23.02215)
			(xy 4.206179 -22.970059) (xy 4.194053 -22.915622) (xy 4.189982 -22.86) (xy 1.306576 -22.86) (xy 1.306576 -23.935944)
			(xy 2.23215 -23.935944) (xy 2.236221 -23.880322) (xy 2.248347 -23.825885) (xy 2.26827 -23.773794)
			(xy 2.295566 -23.725159) (xy 2.329652 -23.681016) (xy 2.369801 -23.642307) (xy 2.415159 -23.609856)
			(xy 2.464759 -23.584355) (xy 2.517543 -23.566348) (xy 2.572386 -23.556218) (xy 2.62812 -23.554181)
			(xy 2.683557 -23.560281) (xy 2.737514 -23.574387) (xy 2.788843 -23.596199) (xy 2.836449 -23.625253)
			(xy 2.879317 -23.660928) (xy 2.916534 -23.702465) (xy 2.947307 -23.748978) (xy 2.970979 -23.799475)
			(xy 2.987047 -23.852882) (xy 2.995167 -23.908058) (xy 2.995676 -23.935944) (xy 3.241038 -23.935944)
			(xy 3.245109 -23.880322) (xy 3.257235 -23.825885) (xy 3.277158 -23.773794) (xy 3.304454 -23.725159)
			(xy 3.33854 -23.681016) (xy 3.378689 -23.642307) (xy 3.424047 -23.609856) (xy 3.473647 -23.584355)
			(xy 3.526431 -23.566348) (xy 3.581274 -23.556218) (xy 3.637008 -23.554181) (xy 3.692445 -23.560281)
			(xy 3.746402 -23.574387) (xy 3.783134 -23.589996) (xy 16.084548 -23.589996) (xy 16.088619 -23.534374)
			(xy 16.100745 -23.479937) (xy 16.120668 -23.427846) (xy 16.147964 -23.379211) (xy 16.18205 -23.335068)
			(xy 16.222199 -23.296359) (xy 16.267557 -23.263908) (xy 16.317157 -23.238407) (xy 16.369941 -23.2204)
			(xy 16.424784 -23.21027) (xy 16.480518 -23.208233) (xy 16.535955 -23.214333) (xy 16.589912 -23.228439)
			(xy 16.641241 -23.250251) (xy 16.688847 -23.279305) (xy 16.731715 -23.31498) (xy 16.768932 -23.356517)
			(xy 16.799705 -23.40303) (xy 16.823377 -23.453527) (xy 16.839445 -23.506934) (xy 16.847565 -23.56211)
			(xy 16.848074 -23.589996) (xy 42.084496 -23.589996) (xy 42.088567 -23.534374) (xy 42.100693 -23.479937)
			(xy 42.120616 -23.427846) (xy 42.147912 -23.379211) (xy 42.181998 -23.335068) (xy 42.222147 -23.296359)
			(xy 42.267505 -23.263908) (xy 42.317105 -23.238407) (xy 42.369889 -23.2204) (xy 42.424732 -23.21027)
			(xy 42.480466 -23.208233) (xy 42.535903 -23.214333) (xy 42.58986 -23.228439) (xy 42.641189 -23.250251)
			(xy 42.688795 -23.279305) (xy 42.731663 -23.31498) (xy 42.76888 -23.356517) (xy 42.799653 -23.40303)
			(xy 42.823325 -23.453527) (xy 42.839393 -23.506934) (xy 42.847513 -23.56211) (xy 42.848022 -23.589996)
			(xy 42.847513 -23.617882) (xy 42.839393 -23.673058) (xy 42.823325 -23.726465) (xy 42.799653 -23.776962)
			(xy 42.76888 -23.823475) (xy 42.731663 -23.865012) (xy 42.688795 -23.900687) (xy 42.641189 -23.929741)
			(xy 42.58986 -23.951553) (xy 42.537835 -23.965154) (xy 52.077364 -23.965154) (xy 52.081435 -23.909532)
			(xy 52.093561 -23.855095) (xy 52.113484 -23.803004) (xy 52.14078 -23.754369) (xy 52.174866 -23.710226)
			(xy 52.215015 -23.671517) (xy 52.260373 -23.639066) (xy 52.309973 -23.613565) (xy 52.362757 -23.595558)
			(xy 52.4176 -23.585428) (xy 52.473334 -23.583391) (xy 52.528771 -23.589491) (xy 52.582728 -23.603597)
			(xy 52.634057 -23.625409) (xy 52.681663 -23.654463) (xy 52.724531 -23.690138) (xy 52.761748 -23.731675)
			(xy 52.792521 -23.778188) (xy 52.816193 -23.828685) (xy 52.832261 -23.882092) (xy 52.840381 -23.937268)
			(xy 52.840556 -23.946866) (xy 53.08041 -23.946866) (xy 53.084481 -23.891244) (xy 53.096607 -23.836807)
			(xy 53.11653 -23.784716) (xy 53.143826 -23.736081) (xy 53.177912 -23.691938) (xy 53.218061 -23.653229)
			(xy 53.263419 -23.620778) (xy 53.313019 -23.595277) (xy 53.365803 -23.57727) (xy 53.420646 -23.56714)
			(xy 53.47638 -23.565103) (xy 53.531817 -23.571203) (xy 53.585774 -23.585309) (xy 53.637103 -23.607121)
			(xy 53.684709 -23.636175) (xy 53.727577 -23.67185) (xy 53.764794 -23.713387) (xy 53.795567 -23.7599)
			(xy 53.819239 -23.810397) (xy 53.835307 -23.863804) (xy 53.843427 -23.91898) (xy 53.843936 -23.946866)
			(xy 53.843496 -23.970996) (xy 54.072788 -23.970996) (xy 54.076859 -23.915374) (xy 54.088985 -23.860937)
			(xy 54.108908 -23.808846) (xy 54.136204 -23.760211) (xy 54.17029 -23.716068) (xy 54.210439 -23.677359)
			(xy 54.255797 -23.644908) (xy 54.305397 -23.619407) (xy 54.358181 -23.6014) (xy 54.413024 -23.59127)
			(xy 54.468758 -23.589233) (xy 54.475692 -23.589996) (xy 68.084444 -23.589996) (xy 68.088515 -23.534374)
			(xy 68.100641 -23.479937) (xy 68.120564 -23.427846) (xy 68.14786 -23.379211) (xy 68.181946 -23.335068)
			(xy 68.222095 -23.296359) (xy 68.267453 -23.263908) (xy 68.317053 -23.238407) (xy 68.369837 -23.2204)
			(xy 68.42468 -23.21027) (xy 68.480414 -23.208233) (xy 68.535851 -23.214333) (xy 68.589808 -23.228439)
			(xy 68.641137 -23.250251) (xy 68.688743 -23.279305) (xy 68.731611 -23.31498) (xy 68.768828 -23.356517)
			(xy 68.799601 -23.40303) (xy 68.823273 -23.453527) (xy 68.839341 -23.506934) (xy 68.847461 -23.56211)
			(xy 68.84797 -23.589996) (xy 68.847461 -23.617882) (xy 68.839341 -23.673058) (xy 68.823273 -23.726465)
			(xy 68.799601 -23.776962) (xy 68.768828 -23.823475) (xy 68.731611 -23.865012) (xy 68.688743 -23.900687)
			(xy 68.641137 -23.929741) (xy 68.589808 -23.951553) (xy 68.537783 -23.965154) (xy 78.077312 -23.965154)
			(xy 78.081383 -23.909532) (xy 78.093509 -23.855095) (xy 78.113432 -23.803004) (xy 78.140728 -23.754369)
			(xy 78.174814 -23.710226) (xy 78.214963 -23.671517) (xy 78.260321 -23.639066) (xy 78.309921 -23.613565)
			(xy 78.362705 -23.595558) (xy 78.417548 -23.585428) (xy 78.473282 -23.583391) (xy 78.528719 -23.589491)
			(xy 78.582676 -23.603597) (xy 78.634005 -23.625409) (xy 78.681611 -23.654463) (xy 78.724479 -23.690138)
			(xy 78.761696 -23.731675) (xy 78.792469 -23.778188) (xy 78.816141 -23.828685) (xy 78.832209 -23.882092)
			(xy 78.840329 -23.937268) (xy 78.840504 -23.946866) (xy 79.080358 -23.946866) (xy 79.084429 -23.891244)
			(xy 79.096555 -23.836807) (xy 79.116478 -23.784716) (xy 79.143774 -23.736081) (xy 79.17786 -23.691938)
			(xy 79.218009 -23.653229) (xy 79.263367 -23.620778) (xy 79.312967 -23.595277) (xy 79.365751 -23.57727)
			(xy 79.420594 -23.56714) (xy 79.476328 -23.565103) (xy 79.531765 -23.571203) (xy 79.585722 -23.585309)
			(xy 79.637051 -23.607121) (xy 79.684657 -23.636175) (xy 79.727525 -23.67185) (xy 79.764742 -23.713387)
			(xy 79.795515 -23.7599) (xy 79.819187 -23.810397) (xy 79.835255 -23.863804) (xy 79.843375 -23.91898)
			(xy 79.843884 -23.946866) (xy 79.843444 -23.970996) (xy 80.072736 -23.970996) (xy 80.076807 -23.915374)
			(xy 80.088933 -23.860937) (xy 80.108856 -23.808846) (xy 80.136152 -23.760211) (xy 80.170238 -23.716068)
			(xy 80.210387 -23.677359) (xy 80.255745 -23.644908) (xy 80.305345 -23.619407) (xy 80.358129 -23.6014)
			(xy 80.412972 -23.59127) (xy 80.468706 -23.589233) (xy 80.47564 -23.589996) (xy 94.084392 -23.589996)
			(xy 94.088463 -23.534374) (xy 94.100589 -23.479937) (xy 94.120512 -23.427846) (xy 94.147808 -23.379211)
			(xy 94.181894 -23.335068) (xy 94.222043 -23.296359) (xy 94.267401 -23.263908) (xy 94.317001 -23.238407)
			(xy 94.369785 -23.2204) (xy 94.424628 -23.21027) (xy 94.480362 -23.208233) (xy 94.535799 -23.214333)
			(xy 94.589756 -23.228439) (xy 94.641085 -23.250251) (xy 94.688691 -23.279305) (xy 94.731559 -23.31498)
			(xy 94.768776 -23.356517) (xy 94.799549 -23.40303) (xy 94.823221 -23.453527) (xy 94.839289 -23.506934)
			(xy 94.847409 -23.56211) (xy 94.847918 -23.589996) (xy 132.184646 -23.589996) (xy 132.188717 -23.534374)
			(xy 132.200843 -23.479937) (xy 132.220766 -23.427846) (xy 132.248062 -23.379211) (xy 132.282148 -23.335068)
			(xy 132.322297 -23.296359) (xy 132.367655 -23.263908) (xy 132.417255 -23.238407) (xy 132.470039 -23.2204)
			(xy 132.524882 -23.21027) (xy 132.580616 -23.208233) (xy 132.636053 -23.214333) (xy 132.69001 -23.228439)
			(xy 132.741339 -23.250251) (xy 132.788945 -23.279305) (xy 132.831813 -23.31498) (xy 132.86903 -23.356517)
			(xy 132.899803 -23.40303) (xy 132.923475 -23.453527) (xy 132.939543 -23.506934) (xy 132.947663 -23.56211)
			(xy 132.948172 -23.589996) (xy 132.947663 -23.617882) (xy 132.939543 -23.673058) (xy 132.923475 -23.726465)
			(xy 132.899803 -23.776962) (xy 132.86903 -23.823475) (xy 132.831813 -23.865012) (xy 132.788945 -23.900687)
			(xy 132.741339 -23.929741) (xy 132.69001 -23.951553) (xy 132.637985 -23.965154) (xy 142.177514 -23.965154)
			(xy 142.181585 -23.909532) (xy 142.193711 -23.855095) (xy 142.213634 -23.803004) (xy 142.24093 -23.754369)
			(xy 142.275016 -23.710226) (xy 142.315165 -23.671517) (xy 142.360523 -23.639066) (xy 142.410123 -23.613565)
			(xy 142.462907 -23.595558) (xy 142.51775 -23.585428) (xy 142.573484 -23.583391) (xy 142.628921 -23.589491)
			(xy 142.682878 -23.603597) (xy 142.734207 -23.625409) (xy 142.781813 -23.654463) (xy 142.824681 -23.690138)
			(xy 142.861898 -23.731675) (xy 142.892671 -23.778188) (xy 142.916343 -23.828685) (xy 142.932411 -23.882092)
			(xy 142.940531 -23.937268) (xy 142.940706 -23.946866) (xy 143.18056 -23.946866) (xy 143.184631 -23.891244)
			(xy 143.196757 -23.836807) (xy 143.21668 -23.784716) (xy 143.243976 -23.736081) (xy 143.278062 -23.691938)
			(xy 143.318211 -23.653229) (xy 143.363569 -23.620778) (xy 143.413169 -23.595277) (xy 143.465953 -23.57727)
			(xy 143.520796 -23.56714) (xy 143.57653 -23.565103) (xy 143.631967 -23.571203) (xy 143.685924 -23.585309)
			(xy 143.737253 -23.607121) (xy 143.784859 -23.636175) (xy 143.827727 -23.67185) (xy 143.864944 -23.713387)
			(xy 143.895717 -23.7599) (xy 143.919389 -23.810397) (xy 143.935457 -23.863804) (xy 143.943577 -23.91898)
			(xy 143.944086 -23.946866) (xy 143.943646 -23.970996) (xy 144.172938 -23.970996) (xy 144.177009 -23.915374)
			(xy 144.189135 -23.860937) (xy 144.209058 -23.808846) (xy 144.236354 -23.760211) (xy 144.27044 -23.716068)
			(xy 144.310589 -23.677359) (xy 144.355947 -23.644908) (xy 144.405547 -23.619407) (xy 144.458331 -23.6014)
			(xy 144.513174 -23.59127) (xy 144.568908 -23.589233) (xy 144.575842 -23.589996) (xy 158.184594 -23.589996)
			(xy 158.188665 -23.534374) (xy 158.200791 -23.479937) (xy 158.220714 -23.427846) (xy 158.24801 -23.379211)
			(xy 158.282096 -23.335068) (xy 158.322245 -23.296359) (xy 158.367603 -23.263908) (xy 158.417203 -23.238407)
			(xy 158.469987 -23.2204) (xy 158.52483 -23.21027) (xy 158.580564 -23.208233) (xy 158.636001 -23.214333)
			(xy 158.689958 -23.228439) (xy 158.741287 -23.250251) (xy 158.788893 -23.279305) (xy 158.831761 -23.31498)
			(xy 158.868978 -23.356517) (xy 158.899751 -23.40303) (xy 158.923423 -23.453527) (xy 158.939491 -23.506934)
			(xy 158.947611 -23.56211) (xy 158.94812 -23.589996) (xy 158.947611 -23.617882) (xy 158.939491 -23.673058)
			(xy 158.923423 -23.726465) (xy 158.899751 -23.776962) (xy 158.868978 -23.823475) (xy 158.831761 -23.865012)
			(xy 158.788893 -23.900687) (xy 158.741287 -23.929741) (xy 158.689958 -23.951553) (xy 158.637933 -23.965154)
			(xy 168.177462 -23.965154) (xy 168.181533 -23.909532) (xy 168.193659 -23.855095) (xy 168.213582 -23.803004)
			(xy 168.240878 -23.754369) (xy 168.274964 -23.710226) (xy 168.315113 -23.671517) (xy 168.360471 -23.639066)
			(xy 168.410071 -23.613565) (xy 168.462855 -23.595558) (xy 168.517698 -23.585428) (xy 168.573432 -23.583391)
			(xy 168.628869 -23.589491) (xy 168.682826 -23.603597) (xy 168.734155 -23.625409) (xy 168.781761 -23.654463)
			(xy 168.824629 -23.690138) (xy 168.861846 -23.731675) (xy 168.892619 -23.778188) (xy 168.916291 -23.828685)
			(xy 168.932359 -23.882092) (xy 168.940479 -23.937268) (xy 168.940654 -23.946866) (xy 169.180508 -23.946866)
			(xy 169.184579 -23.891244) (xy 169.196705 -23.836807) (xy 169.216628 -23.784716) (xy 169.243924 -23.736081)
			(xy 169.27801 -23.691938) (xy 169.318159 -23.653229) (xy 169.363517 -23.620778) (xy 169.413117 -23.595277)
			(xy 169.465901 -23.57727) (xy 169.520744 -23.56714) (xy 169.576478 -23.565103) (xy 169.631915 -23.571203)
			(xy 169.685872 -23.585309) (xy 169.737201 -23.607121) (xy 169.784807 -23.636175) (xy 169.827675 -23.67185)
			(xy 169.864892 -23.713387) (xy 169.895665 -23.7599) (xy 169.919337 -23.810397) (xy 169.935405 -23.863804)
			(xy 169.943525 -23.91898) (xy 169.944034 -23.946866) (xy 169.943594 -23.970996) (xy 170.172886 -23.970996)
			(xy 170.176957 -23.915374) (xy 170.189083 -23.860937) (xy 170.209006 -23.808846) (xy 170.236302 -23.760211)
			(xy 170.270388 -23.716068) (xy 170.310537 -23.677359) (xy 170.355895 -23.644908) (xy 170.405495 -23.619407)
			(xy 170.458279 -23.6014) (xy 170.513122 -23.59127) (xy 170.568856 -23.589233) (xy 170.57579 -23.589996)
			(xy 184.184542 -23.589996) (xy 184.188613 -23.534374) (xy 184.200739 -23.479937) (xy 184.220662 -23.427846)
			(xy 184.247958 -23.379211) (xy 184.282044 -23.335068) (xy 184.322193 -23.296359) (xy 184.367551 -23.263908)
			(xy 184.417151 -23.238407) (xy 184.469935 -23.2204) (xy 184.524778 -23.21027) (xy 184.580512 -23.208233)
			(xy 184.635949 -23.214333) (xy 184.689906 -23.228439) (xy 184.741235 -23.250251) (xy 184.788841 -23.279305)
			(xy 184.831709 -23.31498) (xy 184.868926 -23.356517) (xy 184.899699 -23.40303) (xy 184.923371 -23.453527)
			(xy 184.939439 -23.506934) (xy 184.947559 -23.56211) (xy 184.948068 -23.589996) (xy 184.947559 -23.617882)
			(xy 184.939439 -23.673058) (xy 184.923371 -23.726465) (xy 184.899699 -23.776962) (xy 184.868926 -23.823475)
			(xy 184.831709 -23.865012) (xy 184.788841 -23.900687) (xy 184.741235 -23.929741) (xy 184.689906 -23.951553)
			(xy 184.637881 -23.965154) (xy 194.17741 -23.965154) (xy 194.181481 -23.909532) (xy 194.193607 -23.855095)
			(xy 194.21353 -23.803004) (xy 194.240826 -23.754369) (xy 194.274912 -23.710226) (xy 194.315061 -23.671517)
			(xy 194.360419 -23.639066) (xy 194.410019 -23.613565) (xy 194.462803 -23.595558) (xy 194.517646 -23.585428)
			(xy 194.57338 -23.583391) (xy 194.628817 -23.589491) (xy 194.682774 -23.603597) (xy 194.734103 -23.625409)
			(xy 194.781709 -23.654463) (xy 194.824577 -23.690138) (xy 194.861794 -23.731675) (xy 194.892567 -23.778188)
			(xy 194.916239 -23.828685) (xy 194.932307 -23.882092) (xy 194.940427 -23.937268) (xy 194.940602 -23.946866)
			(xy 195.180456 -23.946866) (xy 195.184527 -23.891244) (xy 195.196653 -23.836807) (xy 195.216576 -23.784716)
			(xy 195.243872 -23.736081) (xy 195.277958 -23.691938) (xy 195.318107 -23.653229) (xy 195.363465 -23.620778)
			(xy 195.413065 -23.595277) (xy 195.465849 -23.57727) (xy 195.520692 -23.56714) (xy 195.576426 -23.565103)
			(xy 195.631863 -23.571203) (xy 195.68582 -23.585309) (xy 195.737149 -23.607121) (xy 195.784755 -23.636175)
			(xy 195.827623 -23.67185) (xy 195.86484 -23.713387) (xy 195.895613 -23.7599) (xy 195.919285 -23.810397)
			(xy 195.935353 -23.863804) (xy 195.943473 -23.91898) (xy 195.943982 -23.946866) (xy 195.943542 -23.970996)
			(xy 196.172834 -23.970996) (xy 196.176905 -23.915374) (xy 196.189031 -23.860937) (xy 196.208954 -23.808846)
			(xy 196.23625 -23.760211) (xy 196.270336 -23.716068) (xy 196.310485 -23.677359) (xy 196.355843 -23.644908)
			(xy 196.405443 -23.619407) (xy 196.458227 -23.6014) (xy 196.51307 -23.59127) (xy 196.568804 -23.589233)
			(xy 196.575738 -23.589996) (xy 210.18449 -23.589996) (xy 210.188561 -23.534374) (xy 210.200687 -23.479937)
			(xy 210.22061 -23.427846) (xy 210.247906 -23.379211) (xy 210.281992 -23.335068) (xy 210.322141 -23.296359)
			(xy 210.367499 -23.263908) (xy 210.417099 -23.238407) (xy 210.469883 -23.2204) (xy 210.524726 -23.21027)
			(xy 210.58046 -23.208233) (xy 210.635897 -23.214333) (xy 210.689854 -23.228439) (xy 210.741183 -23.250251)
			(xy 210.788789 -23.279305) (xy 210.831657 -23.31498) (xy 210.868874 -23.356517) (xy 210.899647 -23.40303)
			(xy 210.923319 -23.453527) (xy 210.939387 -23.506934) (xy 210.947507 -23.56211) (xy 210.948016 -23.589996)
			(xy 210.947507 -23.617882) (xy 210.939387 -23.673058) (xy 210.923319 -23.726465) (xy 210.899647 -23.776962)
			(xy 210.868874 -23.823475) (xy 210.831657 -23.865012) (xy 210.788789 -23.900687) (xy 210.741183 -23.929741)
			(xy 210.689854 -23.951553) (xy 210.637829 -23.965154) (xy 220.177358 -23.965154) (xy 220.181429 -23.909532)
			(xy 220.193555 -23.855095) (xy 220.213478 -23.803004) (xy 220.240774 -23.754369) (xy 220.27486 -23.710226)
			(xy 220.315009 -23.671517) (xy 220.360367 -23.639066) (xy 220.409967 -23.613565) (xy 220.462751 -23.595558)
			(xy 220.517594 -23.585428) (xy 220.573328 -23.583391) (xy 220.628765 -23.589491) (xy 220.682722 -23.603597)
			(xy 220.734051 -23.625409) (xy 220.781657 -23.654463) (xy 220.824525 -23.690138) (xy 220.861742 -23.731675)
			(xy 220.892515 -23.778188) (xy 220.916187 -23.828685) (xy 220.932255 -23.882092) (xy 220.940375 -23.937268)
			(xy 220.94055 -23.946866) (xy 221.180404 -23.946866) (xy 221.184475 -23.891244) (xy 221.196601 -23.836807)
			(xy 221.216524 -23.784716) (xy 221.24382 -23.736081) (xy 221.277906 -23.691938) (xy 221.318055 -23.653229)
			(xy 221.363413 -23.620778) (xy 221.413013 -23.595277) (xy 221.465797 -23.57727) (xy 221.52064 -23.56714)
			(xy 221.576374 -23.565103) (xy 221.631811 -23.571203) (xy 221.685768 -23.585309) (xy 221.737097 -23.607121)
			(xy 221.784703 -23.636175) (xy 221.827571 -23.67185) (xy 221.864788 -23.713387) (xy 221.895561 -23.7599)
			(xy 221.919233 -23.810397) (xy 221.935301 -23.863804) (xy 221.943421 -23.91898) (xy 221.94393 -23.946866)
			(xy 221.94349 -23.970996) (xy 222.172782 -23.970996) (xy 222.176853 -23.915374) (xy 222.188979 -23.860937)
			(xy 222.208902 -23.808846) (xy 222.236198 -23.760211) (xy 222.270284 -23.716068) (xy 222.310433 -23.677359)
			(xy 222.355791 -23.644908) (xy 222.405391 -23.619407) (xy 222.458175 -23.6014) (xy 222.513018 -23.59127)
			(xy 222.568752 -23.589233) (xy 222.575686 -23.589996) (xy 248.28449 -23.589996) (xy 248.288561 -23.534374)
			(xy 248.300687 -23.479937) (xy 248.32061 -23.427846) (xy 248.347906 -23.379211) (xy 248.381992 -23.335068)
			(xy 248.422141 -23.296359) (xy 248.467499 -23.263908) (xy 248.517099 -23.238407) (xy 248.569883 -23.2204)
			(xy 248.624726 -23.21027) (xy 248.68046 -23.208233) (xy 248.735897 -23.214333) (xy 248.789854 -23.228439)
			(xy 248.841183 -23.250251) (xy 248.888789 -23.279305) (xy 248.931657 -23.31498) (xy 248.968874 -23.356517)
			(xy 248.999647 -23.40303) (xy 249.023319 -23.453527) (xy 249.039387 -23.506934) (xy 249.047507 -23.56211)
			(xy 249.048016 -23.589996) (xy 249.047507 -23.617882) (xy 249.039387 -23.673058) (xy 249.023319 -23.726465)
			(xy 248.999647 -23.776962) (xy 248.968874 -23.823475) (xy 248.931657 -23.865012) (xy 248.888789 -23.900687)
			(xy 248.841183 -23.929741) (xy 248.789854 -23.951553) (xy 248.737829 -23.965154) (xy 258.277358 -23.965154)
			(xy 258.281429 -23.909532) (xy 258.293555 -23.855095) (xy 258.313478 -23.803004) (xy 258.340774 -23.754369)
			(xy 258.37486 -23.710226) (xy 258.415009 -23.671517) (xy 258.460367 -23.639066) (xy 258.509967 -23.613565)
			(xy 258.562751 -23.595558) (xy 258.617594 -23.585428) (xy 258.673328 -23.583391) (xy 258.728765 -23.589491)
			(xy 258.782722 -23.603597) (xy 258.834051 -23.625409) (xy 258.881657 -23.654463) (xy 258.924525 -23.690138)
			(xy 258.961742 -23.731675) (xy 258.992515 -23.778188) (xy 259.016187 -23.828685) (xy 259.032255 -23.882092)
			(xy 259.040375 -23.937268) (xy 259.04055 -23.946866) (xy 259.280404 -23.946866) (xy 259.284475 -23.891244)
			(xy 259.296601 -23.836807) (xy 259.316524 -23.784716) (xy 259.34382 -23.736081) (xy 259.377906 -23.691938)
			(xy 259.418055 -23.653229) (xy 259.463413 -23.620778) (xy 259.513013 -23.595277) (xy 259.565797 -23.57727)
			(xy 259.62064 -23.56714) (xy 259.676374 -23.565103) (xy 259.731811 -23.571203) (xy 259.785768 -23.585309)
			(xy 259.837097 -23.607121) (xy 259.884703 -23.636175) (xy 259.927571 -23.67185) (xy 259.964788 -23.713387)
			(xy 259.995561 -23.7599) (xy 260.019233 -23.810397) (xy 260.035301 -23.863804) (xy 260.043421 -23.91898)
			(xy 260.04393 -23.946866) (xy 260.04349 -23.970996) (xy 260.272782 -23.970996) (xy 260.276853 -23.915374)
			(xy 260.288979 -23.860937) (xy 260.308902 -23.808846) (xy 260.336198 -23.760211) (xy 260.370284 -23.716068)
			(xy 260.410433 -23.677359) (xy 260.455791 -23.644908) (xy 260.505391 -23.619407) (xy 260.558175 -23.6014)
			(xy 260.613018 -23.59127) (xy 260.668752 -23.589233) (xy 260.675686 -23.589996) (xy 274.284438 -23.589996)
			(xy 274.288509 -23.534374) (xy 274.300635 -23.479937) (xy 274.320558 -23.427846) (xy 274.347854 -23.379211)
			(xy 274.38194 -23.335068) (xy 274.422089 -23.296359) (xy 274.467447 -23.263908) (xy 274.517047 -23.238407)
			(xy 274.569831 -23.2204) (xy 274.624674 -23.21027) (xy 274.680408 -23.208233) (xy 274.735845 -23.214333)
			(xy 274.789802 -23.228439) (xy 274.841131 -23.250251) (xy 274.888737 -23.279305) (xy 274.931605 -23.31498)
			(xy 274.968822 -23.356517) (xy 274.999595 -23.40303) (xy 275.023267 -23.453527) (xy 275.039335 -23.506934)
			(xy 275.047455 -23.56211) (xy 275.047964 -23.589996) (xy 275.047455 -23.617882) (xy 275.039335 -23.673058)
			(xy 275.023267 -23.726465) (xy 274.999595 -23.776962) (xy 274.968822 -23.823475) (xy 274.931605 -23.865012)
			(xy 274.888737 -23.900687) (xy 274.841131 -23.929741) (xy 274.789802 -23.951553) (xy 274.737777 -23.965154)
			(xy 284.277306 -23.965154) (xy 284.281377 -23.909532) (xy 284.293503 -23.855095) (xy 284.313426 -23.803004)
			(xy 284.340722 -23.754369) (xy 284.374808 -23.710226) (xy 284.414957 -23.671517) (xy 284.460315 -23.639066)
			(xy 284.509915 -23.613565) (xy 284.562699 -23.595558) (xy 284.617542 -23.585428) (xy 284.673276 -23.583391)
			(xy 284.728713 -23.589491) (xy 284.78267 -23.603597) (xy 284.833999 -23.625409) (xy 284.881605 -23.654463)
			(xy 284.924473 -23.690138) (xy 284.96169 -23.731675) (xy 284.992463 -23.778188) (xy 285.016135 -23.828685)
			(xy 285.032203 -23.882092) (xy 285.040323 -23.937268) (xy 285.040498 -23.946866) (xy 285.280352 -23.946866)
			(xy 285.284423 -23.891244) (xy 285.296549 -23.836807) (xy 285.316472 -23.784716) (xy 285.343768 -23.736081)
			(xy 285.377854 -23.691938) (xy 285.418003 -23.653229) (xy 285.463361 -23.620778) (xy 285.512961 -23.595277)
			(xy 285.565745 -23.57727) (xy 285.620588 -23.56714) (xy 285.676322 -23.565103) (xy 285.731759 -23.571203)
			(xy 285.785716 -23.585309) (xy 285.837045 -23.607121) (xy 285.884651 -23.636175) (xy 285.927519 -23.67185)
			(xy 285.964736 -23.713387) (xy 285.995509 -23.7599) (xy 286.019181 -23.810397) (xy 286.035249 -23.863804)
			(xy 286.043369 -23.91898) (xy 286.043878 -23.946866) (xy 286.043438 -23.970996) (xy 286.27273 -23.970996)
			(xy 286.276801 -23.915374) (xy 286.288927 -23.860937) (xy 286.30885 -23.808846) (xy 286.336146 -23.760211)
			(xy 286.370232 -23.716068) (xy 286.410381 -23.677359) (xy 286.455739 -23.644908) (xy 286.505339 -23.619407)
			(xy 286.558123 -23.6014) (xy 286.612966 -23.59127) (xy 286.6687 -23.589233) (xy 286.675634 -23.589996)
			(xy 300.284386 -23.589996) (xy 300.288457 -23.534374) (xy 300.300583 -23.479937) (xy 300.320506 -23.427846)
			(xy 300.347802 -23.379211) (xy 300.381888 -23.335068) (xy 300.422037 -23.296359) (xy 300.467395 -23.263908)
			(xy 300.516995 -23.238407) (xy 300.569779 -23.2204) (xy 300.624622 -23.21027) (xy 300.680356 -23.208233)
			(xy 300.735793 -23.214333) (xy 300.78975 -23.228439) (xy 300.841079 -23.250251) (xy 300.888685 -23.279305)
			(xy 300.931553 -23.31498) (xy 300.96877 -23.356517) (xy 300.999543 -23.40303) (xy 301.023215 -23.453527)
			(xy 301.039283 -23.506934) (xy 301.047403 -23.56211) (xy 301.047912 -23.589996) (xy 301.047403 -23.617882)
			(xy 301.039283 -23.673058) (xy 301.023215 -23.726465) (xy 300.999543 -23.776962) (xy 300.96877 -23.823475)
			(xy 300.931553 -23.865012) (xy 300.888685 -23.900687) (xy 300.841079 -23.929741) (xy 300.78975 -23.951553)
			(xy 300.737725 -23.965154) (xy 310.277254 -23.965154) (xy 310.281325 -23.909532) (xy 310.293451 -23.855095)
			(xy 310.313374 -23.803004) (xy 310.34067 -23.754369) (xy 310.374756 -23.710226) (xy 310.414905 -23.671517)
			(xy 310.460263 -23.639066) (xy 310.509863 -23.613565) (xy 310.562647 -23.595558) (xy 310.61749 -23.585428)
			(xy 310.673224 -23.583391) (xy 310.728661 -23.589491) (xy 310.782618 -23.603597) (xy 310.833947 -23.625409)
			(xy 310.881553 -23.654463) (xy 310.924421 -23.690138) (xy 310.961638 -23.731675) (xy 310.992411 -23.778188)
			(xy 311.016083 -23.828685) (xy 311.032151 -23.882092) (xy 311.040271 -23.937268) (xy 311.040446 -23.946866)
			(xy 311.2803 -23.946866) (xy 311.284371 -23.891244) (xy 311.296497 -23.836807) (xy 311.31642 -23.784716)
			(xy 311.343716 -23.736081) (xy 311.377802 -23.691938) (xy 311.417951 -23.653229) (xy 311.463309 -23.620778)
			(xy 311.512909 -23.595277) (xy 311.565693 -23.57727) (xy 311.620536 -23.56714) (xy 311.67627 -23.565103)
			(xy 311.731707 -23.571203) (xy 311.785664 -23.585309) (xy 311.836993 -23.607121) (xy 311.884599 -23.636175)
			(xy 311.927467 -23.67185) (xy 311.964684 -23.713387) (xy 311.995457 -23.7599) (xy 312.019129 -23.810397)
			(xy 312.035197 -23.863804) (xy 312.043317 -23.91898) (xy 312.043826 -23.946866) (xy 312.043386 -23.970996)
			(xy 312.272678 -23.970996) (xy 312.276749 -23.915374) (xy 312.288875 -23.860937) (xy 312.308798 -23.808846)
			(xy 312.336094 -23.760211) (xy 312.37018 -23.716068) (xy 312.410329 -23.677359) (xy 312.455687 -23.644908)
			(xy 312.505287 -23.619407) (xy 312.558071 -23.6014) (xy 312.612914 -23.59127) (xy 312.668648 -23.589233)
			(xy 312.675582 -23.589996) (xy 326.284334 -23.589996) (xy 326.288405 -23.534374) (xy 326.300531 -23.479937)
			(xy 326.320454 -23.427846) (xy 326.34775 -23.379211) (xy 326.381836 -23.335068) (xy 326.421985 -23.296359)
			(xy 326.467343 -23.263908) (xy 326.516943 -23.238407) (xy 326.569727 -23.2204) (xy 326.62457 -23.21027)
			(xy 326.680304 -23.208233) (xy 326.735741 -23.214333) (xy 326.789698 -23.228439) (xy 326.841027 -23.250251)
			(xy 326.888633 -23.279305) (xy 326.931501 -23.31498) (xy 326.968718 -23.356517) (xy 326.999491 -23.40303)
			(xy 327.023163 -23.453527) (xy 327.039231 -23.506934) (xy 327.047351 -23.56211) (xy 327.04786 -23.589996)
			(xy 364.384588 -23.589996) (xy 364.388659 -23.534374) (xy 364.400785 -23.479937) (xy 364.420708 -23.427846)
			(xy 364.448004 -23.379211) (xy 364.48209 -23.335068) (xy 364.522239 -23.296359) (xy 364.567597 -23.263908)
			(xy 364.617197 -23.238407) (xy 364.669981 -23.2204) (xy 364.724824 -23.21027) (xy 364.780558 -23.208233)
			(xy 364.835995 -23.214333) (xy 364.889952 -23.228439) (xy 364.941281 -23.250251) (xy 364.988887 -23.279305)
			(xy 365.031755 -23.31498) (xy 365.068972 -23.356517) (xy 365.099745 -23.40303) (xy 365.123417 -23.453527)
			(xy 365.139485 -23.506934) (xy 365.147605 -23.56211) (xy 365.148114 -23.589996) (xy 365.147605 -23.617882)
			(xy 365.139485 -23.673058) (xy 365.123417 -23.726465) (xy 365.099745 -23.776962) (xy 365.068972 -23.823475)
			(xy 365.031755 -23.865012) (xy 364.988887 -23.900687) (xy 364.941281 -23.929741) (xy 364.889952 -23.951553)
			(xy 364.837927 -23.965154) (xy 374.377456 -23.965154) (xy 374.381527 -23.909532) (xy 374.393653 -23.855095)
			(xy 374.413576 -23.803004) (xy 374.440872 -23.754369) (xy 374.474958 -23.710226) (xy 374.515107 -23.671517)
			(xy 374.560465 -23.639066) (xy 374.610065 -23.613565) (xy 374.662849 -23.595558) (xy 374.717692 -23.585428)
			(xy 374.773426 -23.583391) (xy 374.828863 -23.589491) (xy 374.88282 -23.603597) (xy 374.934149 -23.625409)
			(xy 374.981755 -23.654463) (xy 375.024623 -23.690138) (xy 375.06184 -23.731675) (xy 375.092613 -23.778188)
			(xy 375.116285 -23.828685) (xy 375.132353 -23.882092) (xy 375.140473 -23.937268) (xy 375.140648 -23.946866)
			(xy 375.380502 -23.946866) (xy 375.384573 -23.891244) (xy 375.396699 -23.836807) (xy 375.416622 -23.784716)
			(xy 375.443918 -23.736081) (xy 375.478004 -23.691938) (xy 375.518153 -23.653229) (xy 375.563511 -23.620778)
			(xy 375.613111 -23.595277) (xy 375.665895 -23.57727) (xy 375.720738 -23.56714) (xy 375.776472 -23.565103)
			(xy 375.831909 -23.571203) (xy 375.885866 -23.585309) (xy 375.937195 -23.607121) (xy 375.984801 -23.636175)
			(xy 376.027669 -23.67185) (xy 376.064886 -23.713387) (xy 376.095659 -23.7599) (xy 376.119331 -23.810397)
			(xy 376.135399 -23.863804) (xy 376.143519 -23.91898) (xy 376.144028 -23.946866) (xy 376.143588 -23.970996)
			(xy 376.37288 -23.970996) (xy 376.376951 -23.915374) (xy 376.389077 -23.860937) (xy 376.409 -23.808846)
			(xy 376.436296 -23.760211) (xy 376.470382 -23.716068) (xy 376.510531 -23.677359) (xy 376.555889 -23.644908)
			(xy 376.605489 -23.619407) (xy 376.658273 -23.6014) (xy 376.713116 -23.59127) (xy 376.76885 -23.589233)
			(xy 376.775784 -23.589996) (xy 390.384536 -23.589996) (xy 390.388607 -23.534374) (xy 390.400733 -23.479937)
			(xy 390.420656 -23.427846) (xy 390.447952 -23.379211) (xy 390.482038 -23.335068) (xy 390.522187 -23.296359)
			(xy 390.567545 -23.263908) (xy 390.617145 -23.238407) (xy 390.669929 -23.2204) (xy 390.724772 -23.21027)
			(xy 390.780506 -23.208233) (xy 390.835943 -23.214333) (xy 390.8899 -23.228439) (xy 390.941229 -23.250251)
			(xy 390.988835 -23.279305) (xy 391.031703 -23.31498) (xy 391.06892 -23.356517) (xy 391.099693 -23.40303)
			(xy 391.123365 -23.453527) (xy 391.139433 -23.506934) (xy 391.147553 -23.56211) (xy 391.148062 -23.589996)
			(xy 391.147553 -23.617882) (xy 391.139433 -23.673058) (xy 391.123365 -23.726465) (xy 391.099693 -23.776962)
			(xy 391.06892 -23.823475) (xy 391.031703 -23.865012) (xy 390.988835 -23.900687) (xy 390.941229 -23.929741)
			(xy 390.8899 -23.951553) (xy 390.837875 -23.965154) (xy 400.377404 -23.965154) (xy 400.381475 -23.909532)
			(xy 400.393601 -23.855095) (xy 400.413524 -23.803004) (xy 400.44082 -23.754369) (xy 400.474906 -23.710226)
			(xy 400.515055 -23.671517) (xy 400.560413 -23.639066) (xy 400.610013 -23.613565) (xy 400.662797 -23.595558)
			(xy 400.71764 -23.585428) (xy 400.773374 -23.583391) (xy 400.828811 -23.589491) (xy 400.882768 -23.603597)
			(xy 400.934097 -23.625409) (xy 400.981703 -23.654463) (xy 401.024571 -23.690138) (xy 401.061788 -23.731675)
			(xy 401.092561 -23.778188) (xy 401.116233 -23.828685) (xy 401.132301 -23.882092) (xy 401.140421 -23.937268)
			(xy 401.140596 -23.946866) (xy 401.38045 -23.946866) (xy 401.384521 -23.891244) (xy 401.396647 -23.836807)
			(xy 401.41657 -23.784716) (xy 401.443866 -23.736081) (xy 401.477952 -23.691938) (xy 401.518101 -23.653229)
			(xy 401.563459 -23.620778) (xy 401.613059 -23.595277) (xy 401.665843 -23.57727) (xy 401.720686 -23.56714)
			(xy 401.77642 -23.565103) (xy 401.831857 -23.571203) (xy 401.885814 -23.585309) (xy 401.937143 -23.607121)
			(xy 401.984749 -23.636175) (xy 402.027617 -23.67185) (xy 402.064834 -23.713387) (xy 402.095607 -23.7599)
			(xy 402.119279 -23.810397) (xy 402.135347 -23.863804) (xy 402.143467 -23.91898) (xy 402.143976 -23.946866)
			(xy 402.143536 -23.970996) (xy 402.372828 -23.970996) (xy 402.376899 -23.915374) (xy 402.389025 -23.860937)
			(xy 402.408948 -23.808846) (xy 402.436244 -23.760211) (xy 402.47033 -23.716068) (xy 402.510479 -23.677359)
			(xy 402.555837 -23.644908) (xy 402.605437 -23.619407) (xy 402.658221 -23.6014) (xy 402.713064 -23.59127)
			(xy 402.768798 -23.589233) (xy 402.775732 -23.589996) (xy 416.384484 -23.589996) (xy 416.388555 -23.534374)
			(xy 416.400681 -23.479937) (xy 416.420604 -23.427846) (xy 416.4479 -23.379211) (xy 416.481986 -23.335068)
			(xy 416.522135 -23.296359) (xy 416.567493 -23.263908) (xy 416.617093 -23.238407) (xy 416.669877 -23.2204)
			(xy 416.72472 -23.21027) (xy 416.780454 -23.208233) (xy 416.835891 -23.214333) (xy 416.889848 -23.228439)
			(xy 416.941177 -23.250251) (xy 416.988783 -23.279305) (xy 417.031651 -23.31498) (xy 417.068868 -23.356517)
			(xy 417.099641 -23.40303) (xy 417.123313 -23.453527) (xy 417.139381 -23.506934) (xy 417.147501 -23.56211)
			(xy 417.14801 -23.589996) (xy 417.147501 -23.617882) (xy 417.139381 -23.673058) (xy 417.123313 -23.726465)
			(xy 417.099641 -23.776962) (xy 417.068868 -23.823475) (xy 417.031651 -23.865012) (xy 416.988783 -23.900687)
			(xy 416.941177 -23.929741) (xy 416.889848 -23.951553) (xy 416.837823 -23.965154) (xy 426.377352 -23.965154)
			(xy 426.381423 -23.909532) (xy 426.393549 -23.855095) (xy 426.413472 -23.803004) (xy 426.440768 -23.754369)
			(xy 426.474854 -23.710226) (xy 426.515003 -23.671517) (xy 426.560361 -23.639066) (xy 426.609961 -23.613565)
			(xy 426.662745 -23.595558) (xy 426.717588 -23.585428) (xy 426.773322 -23.583391) (xy 426.828759 -23.589491)
			(xy 426.882716 -23.603597) (xy 426.934045 -23.625409) (xy 426.981651 -23.654463) (xy 427.024519 -23.690138)
			(xy 427.061736 -23.731675) (xy 427.092509 -23.778188) (xy 427.116181 -23.828685) (xy 427.132249 -23.882092)
			(xy 427.140369 -23.937268) (xy 427.140544 -23.946866) (xy 427.380398 -23.946866) (xy 427.384469 -23.891244)
			(xy 427.396595 -23.836807) (xy 427.416518 -23.784716) (xy 427.443814 -23.736081) (xy 427.4779 -23.691938)
			(xy 427.518049 -23.653229) (xy 427.563407 -23.620778) (xy 427.613007 -23.595277) (xy 427.665791 -23.57727)
			(xy 427.720634 -23.56714) (xy 427.776368 -23.565103) (xy 427.831805 -23.571203) (xy 427.885762 -23.585309)
			(xy 427.937091 -23.607121) (xy 427.984697 -23.636175) (xy 428.027565 -23.67185) (xy 428.064782 -23.713387)
			(xy 428.095555 -23.7599) (xy 428.119227 -23.810397) (xy 428.135295 -23.863804) (xy 428.143415 -23.91898)
			(xy 428.143924 -23.946866) (xy 428.143484 -23.970996) (xy 428.372776 -23.970996) (xy 428.376847 -23.915374)
			(xy 428.388973 -23.860937) (xy 428.408896 -23.808846) (xy 428.436192 -23.760211) (xy 428.470278 -23.716068)
			(xy 428.510427 -23.677359) (xy 428.555785 -23.644908) (xy 428.605385 -23.619407) (xy 428.658169 -23.6014)
			(xy 428.713012 -23.59127) (xy 428.768746 -23.589233) (xy 428.77568 -23.589996) (xy 442.384432 -23.589996)
			(xy 442.388503 -23.534374) (xy 442.400629 -23.479937) (xy 442.420552 -23.427846) (xy 442.447848 -23.379211)
			(xy 442.481934 -23.335068) (xy 442.522083 -23.296359) (xy 442.567441 -23.263908) (xy 442.617041 -23.238407)
			(xy 442.669825 -23.2204) (xy 442.724668 -23.21027) (xy 442.780402 -23.208233) (xy 442.835839 -23.214333)
			(xy 442.889796 -23.228439) (xy 442.941125 -23.250251) (xy 442.988731 -23.279305) (xy 443.031599 -23.31498)
			(xy 443.068816 -23.356517) (xy 443.099589 -23.40303) (xy 443.123261 -23.453527) (xy 443.139329 -23.506934)
			(xy 443.147449 -23.56211) (xy 443.147958 -23.589996) (xy 443.147449 -23.617882) (xy 443.139329 -23.673058)
			(xy 443.123261 -23.726465) (xy 443.099589 -23.776962) (xy 443.068816 -23.823475) (xy 443.031599 -23.865012)
			(xy 442.988731 -23.900687) (xy 442.941125 -23.929741) (xy 442.889796 -23.951553) (xy 442.837771 -23.965154)
			(xy 452.3773 -23.965154) (xy 452.381371 -23.909532) (xy 452.393497 -23.855095) (xy 452.41342 -23.803004)
			(xy 452.440716 -23.754369) (xy 452.474802 -23.710226) (xy 452.514951 -23.671517) (xy 452.560309 -23.639066)
			(xy 452.609909 -23.613565) (xy 452.662693 -23.595558) (xy 452.717536 -23.585428) (xy 452.77327 -23.583391)
			(xy 452.828707 -23.589491) (xy 452.882664 -23.603597) (xy 452.933993 -23.625409) (xy 452.981599 -23.654463)
			(xy 453.024467 -23.690138) (xy 453.061684 -23.731675) (xy 453.092457 -23.778188) (xy 453.116129 -23.828685)
			(xy 453.132197 -23.882092) (xy 453.140317 -23.937268) (xy 453.140492 -23.946866) (xy 453.380346 -23.946866)
			(xy 453.384417 -23.891244) (xy 453.396543 -23.836807) (xy 453.416466 -23.784716) (xy 453.443762 -23.736081)
			(xy 453.477848 -23.691938) (xy 453.517997 -23.653229) (xy 453.563355 -23.620778) (xy 453.612955 -23.595277)
			(xy 453.665739 -23.57727) (xy 453.720582 -23.56714) (xy 453.776316 -23.565103) (xy 453.831753 -23.571203)
			(xy 453.88571 -23.585309) (xy 453.937039 -23.607121) (xy 453.984645 -23.636175) (xy 454.027513 -23.67185)
			(xy 454.06473 -23.713387) (xy 454.095503 -23.7599) (xy 454.119175 -23.810397) (xy 454.135243 -23.863804)
			(xy 454.143363 -23.91898) (xy 454.143872 -23.946866) (xy 454.143363 -23.974752) (xy 454.135243 -24.029928)
			(xy 454.130888 -24.044402) (xy 454.372724 -24.044402) (xy 454.376795 -23.98878) (xy 454.388921 -23.934343)
			(xy 454.408844 -23.882252) (xy 454.43614 -23.833617) (xy 454.470226 -23.789474) (xy 454.510375 -23.750765)
			(xy 454.555733 -23.718314) (xy 454.605333 -23.692813) (xy 454.658117 -23.674806) (xy 454.71296 -23.664676)
			(xy 454.768694 -23.662639) (xy 454.824131 -23.668739) (xy 454.878088 -23.682845) (xy 454.929417 -23.704657)
			(xy 454.977023 -23.733711) (xy 455.019891 -23.769386) (xy 455.057108 -23.810923) (xy 455.087881 -23.857436)
			(xy 455.111553 -23.907933) (xy 455.127621 -23.96134) (xy 455.135741 -24.016516) (xy 455.13625 -24.044402)
			(xy 455.135741 -24.072288) (xy 455.127621 -24.127464) (xy 455.111553 -24.180871) (xy 455.087881 -24.231368)
			(xy 455.057108 -24.277881) (xy 455.019891 -24.319418) (xy 454.977023 -24.355093) (xy 454.929417 -24.384147)
			(xy 454.878088 -24.405959) (xy 454.824131 -24.420065) (xy 454.768694 -24.426165) (xy 454.71296 -24.424128)
			(xy 454.658117 -24.413998) (xy 454.605333 -24.395991) (xy 454.555733 -24.37049) (xy 454.510375 -24.338039)
			(xy 454.470226 -24.29933) (xy 454.43614 -24.255187) (xy 454.408844 -24.206552) (xy 454.388921 -24.154461)
			(xy 454.376795 -24.100024) (xy 454.372724 -24.044402) (xy 454.130888 -24.044402) (xy 454.119175 -24.083335)
			(xy 454.095503 -24.133832) (xy 454.06473 -24.180345) (xy 454.027513 -24.221882) (xy 453.984645 -24.257557)
			(xy 453.937039 -24.286611) (xy 453.88571 -24.308423) (xy 453.831753 -24.322529) (xy 453.776316 -24.328629)
			(xy 453.720582 -24.326592) (xy 453.665739 -24.316462) (xy 453.612955 -24.298455) (xy 453.563355 -24.272954)
			(xy 453.517997 -24.240503) (xy 453.477848 -24.201794) (xy 453.443762 -24.157651) (xy 453.416466 -24.109016)
			(xy 453.396543 -24.056925) (xy 453.384417 -24.002488) (xy 453.380346 -23.946866) (xy 453.140492 -23.946866)
			(xy 453.140826 -23.965154) (xy 453.140317 -23.99304) (xy 453.132197 -24.048216) (xy 453.116129 -24.101623)
			(xy 453.092457 -24.15212) (xy 453.061684 -24.198633) (xy 453.024467 -24.24017) (xy 452.981599 -24.275845)
			(xy 452.933993 -24.304899) (xy 452.882664 -24.326711) (xy 452.828707 -24.340817) (xy 452.77327 -24.346917)
			(xy 452.717536 -24.34488) (xy 452.662693 -24.33475) (xy 452.609909 -24.316743) (xy 452.560309 -24.291242)
			(xy 452.514951 -24.258791) (xy 452.474802 -24.220082) (xy 452.440716 -24.175939) (xy 452.41342 -24.127304)
			(xy 452.393497 -24.075213) (xy 452.381371 -24.020776) (xy 452.3773 -23.965154) (xy 442.837771 -23.965154)
			(xy 442.835839 -23.965659) (xy 442.780402 -23.971759) (xy 442.724668 -23.969722) (xy 442.669825 -23.959592)
			(xy 442.617041 -23.941585) (xy 442.567441 -23.916084) (xy 442.522083 -23.883633) (xy 442.481934 -23.844924)
			(xy 442.447848 -23.800781) (xy 442.420552 -23.752146) (xy 442.400629 -23.700055) (xy 442.388503 -23.645618)
			(xy 442.384432 -23.589996) (xy 428.77568 -23.589996) (xy 428.824183 -23.595333) (xy 428.87814 -23.609439)
			(xy 428.929469 -23.631251) (xy 428.977075 -23.660305) (xy 429.019943 -23.69598) (xy 429.05716 -23.737517)
			(xy 429.087933 -23.78403) (xy 429.111605 -23.834527) (xy 429.127673 -23.887934) (xy 429.135793 -23.94311)
			(xy 429.136302 -23.970996) (xy 429.135793 -23.998882) (xy 429.127673 -24.054058) (xy 429.111605 -24.107465)
			(xy 429.087933 -24.157962) (xy 429.08778 -24.158194) (xy 433.750718 -24.158194) (xy 433.754789 -24.102572)
			(xy 433.766915 -24.048135) (xy 433.786838 -23.996044) (xy 433.814134 -23.947409) (xy 433.84822 -23.903266)
			(xy 433.888369 -23.864557) (xy 433.933727 -23.832106) (xy 433.983327 -23.806605) (xy 434.036111 -23.788598)
			(xy 434.090954 -23.778468) (xy 434.146688 -23.776431) (xy 434.202125 -23.782531) (xy 434.256082 -23.796637)
			(xy 434.307411 -23.818449) (xy 434.355017 -23.847503) (xy 434.397885 -23.883178) (xy 434.435102 -23.924715)
			(xy 434.465875 -23.971228) (xy 434.489547 -24.021725) (xy 434.505615 -24.075132) (xy 434.513735 -24.130308)
			(xy 434.514244 -24.158194) (xy 434.513735 -24.18608) (xy 434.513166 -24.189944) (xy 437.598818 -24.189944)
			(xy 437.602889 -24.134322) (xy 437.615015 -24.079885) (xy 437.634938 -24.027794) (xy 437.662234 -23.979159)
			(xy 437.69632 -23.935016) (xy 437.736469 -23.896307) (xy 437.781827 -23.863856) (xy 437.831427 -23.838355)
			(xy 437.884211 -23.820348) (xy 437.939054 -23.810218) (xy 437.994788 -23.808181) (xy 438.050225 -23.814281)
			(xy 438.104182 -23.828387) (xy 438.155511 -23.850199) (xy 438.203117 -23.879253) (xy 438.245985 -23.914928)
			(xy 438.283202 -23.956465) (xy 438.313975 -24.002978) (xy 438.337647 -24.053475) (xy 438.353715 -24.106882)
			(xy 438.361835 -24.162058) (xy 438.362344 -24.189944) (xy 440.1218 -24.189944) (xy 440.125871 -24.134322)
			(xy 440.137997 -24.079885) (xy 440.15792 -24.027794) (xy 440.185216 -23.979159) (xy 440.219302 -23.935016)
			(xy 440.259451 -23.896307) (xy 440.304809 -23.863856) (xy 440.354409 -23.838355) (xy 440.407193 -23.820348)
			(xy 440.462036 -23.810218) (xy 440.51777 -23.808181) (xy 440.573207 -23.814281) (xy 440.627164 -23.828387)
			(xy 440.678493 -23.850199) (xy 440.726099 -23.879253) (xy 440.768967 -23.914928) (xy 440.806184 -23.956465)
			(xy 440.836957 -24.002978) (xy 440.860629 -24.053475) (xy 440.876697 -24.106882) (xy 440.884817 -24.162058)
			(xy 440.885326 -24.189944) (xy 440.884817 -24.21783) (xy 440.876697 -24.273006) (xy 440.860629 -24.326413)
			(xy 440.836957 -24.37691) (xy 440.806184 -24.423423) (xy 440.768967 -24.46496) (xy 440.726099 -24.500635)
			(xy 440.678493 -24.529689) (xy 440.627164 -24.551501) (xy 440.573207 -24.565607) (xy 440.51777 -24.571707)
			(xy 440.462036 -24.56967) (xy 440.407193 -24.55954) (xy 440.354409 -24.541533) (xy 440.304809 -24.516032)
			(xy 440.259451 -24.483581) (xy 440.219302 -24.444872) (xy 440.185216 -24.400729) (xy 440.15792 -24.352094)
			(xy 440.137997 -24.300003) (xy 440.125871 -24.245566) (xy 440.1218 -24.189944) (xy 438.362344 -24.189944)
			(xy 438.361835 -24.21783) (xy 438.353715 -24.273006) (xy 438.337647 -24.326413) (xy 438.313975 -24.37691)
			(xy 438.283202 -24.423423) (xy 438.245985 -24.46496) (xy 438.203117 -24.500635) (xy 438.155511 -24.529689)
			(xy 438.104182 -24.551501) (xy 438.050225 -24.565607) (xy 437.994788 -24.571707) (xy 437.939054 -24.56967)
			(xy 437.884211 -24.55954) (xy 437.831427 -24.541533) (xy 437.781827 -24.516032) (xy 437.736469 -24.483581)
			(xy 437.69632 -24.444872) (xy 437.662234 -24.400729) (xy 437.634938 -24.352094) (xy 437.615015 -24.300003)
			(xy 437.602889 -24.245566) (xy 437.598818 -24.189944) (xy 434.513166 -24.189944) (xy 434.505615 -24.241256)
			(xy 434.489547 -24.294663) (xy 434.465875 -24.34516) (xy 434.435102 -24.391673) (xy 434.397885 -24.43321)
			(xy 434.355017 -24.468885) (xy 434.307411 -24.497939) (xy 434.256082 -24.519751) (xy 434.202125 -24.533857)
			(xy 434.146688 -24.539957) (xy 434.090954 -24.53792) (xy 434.036111 -24.52779) (xy 433.983327 -24.509783)
			(xy 433.933727 -24.484282) (xy 433.888369 -24.451831) (xy 433.84822 -24.413122) (xy 433.814134 -24.368979)
			(xy 433.786838 -24.320344) (xy 433.766915 -24.268253) (xy 433.754789 -24.213816) (xy 433.750718 -24.158194)
			(xy 429.08778 -24.158194) (xy 429.05716 -24.204475) (xy 429.019943 -24.246012) (xy 428.977075 -24.281687)
			(xy 428.929469 -24.310741) (xy 428.87814 -24.332553) (xy 428.824183 -24.346659) (xy 428.768746 -24.352759)
			(xy 428.713012 -24.350722) (xy 428.658169 -24.340592) (xy 428.605385 -24.322585) (xy 428.555785 -24.297084)
			(xy 428.510427 -24.264633) (xy 428.470278 -24.225924) (xy 428.436192 -24.181781) (xy 428.408896 -24.133146)
			(xy 428.388973 -24.081055) (xy 428.376847 -24.026618) (xy 428.372776 -23.970996) (xy 428.143484 -23.970996)
			(xy 428.143415 -23.974752) (xy 428.135295 -24.029928) (xy 428.119227 -24.083335) (xy 428.095555 -24.133832)
			(xy 428.064782 -24.180345) (xy 428.027565 -24.221882) (xy 427.984697 -24.257557) (xy 427.937091 -24.286611)
			(xy 427.885762 -24.308423) (xy 427.831805 -24.322529) (xy 427.776368 -24.328629) (xy 427.720634 -24.326592)
			(xy 427.665791 -24.316462) (xy 427.613007 -24.298455) (xy 427.563407 -24.272954) (xy 427.518049 -24.240503)
			(xy 427.4779 -24.201794) (xy 427.443814 -24.157651) (xy 427.416518 -24.109016) (xy 427.396595 -24.056925)
			(xy 427.384469 -24.002488) (xy 427.380398 -23.946866) (xy 427.140544 -23.946866) (xy 427.140878 -23.965154)
			(xy 427.140369 -23.99304) (xy 427.132249 -24.048216) (xy 427.116181 -24.101623) (xy 427.092509 -24.15212)
			(xy 427.061736 -24.198633) (xy 427.024519 -24.24017) (xy 426.981651 -24.275845) (xy 426.934045 -24.304899)
			(xy 426.882716 -24.326711) (xy 426.828759 -24.340817) (xy 426.773322 -24.346917) (xy 426.717588 -24.34488)
			(xy 426.662745 -24.33475) (xy 426.609961 -24.316743) (xy 426.560361 -24.291242) (xy 426.515003 -24.258791)
			(xy 426.474854 -24.220082) (xy 426.440768 -24.175939) (xy 426.413472 -24.127304) (xy 426.393549 -24.075213)
			(xy 426.381423 -24.020776) (xy 426.377352 -23.965154) (xy 416.837823 -23.965154) (xy 416.835891 -23.965659)
			(xy 416.780454 -23.971759) (xy 416.72472 -23.969722) (xy 416.669877 -23.959592) (xy 416.617093 -23.941585)
			(xy 416.567493 -23.916084) (xy 416.522135 -23.883633) (xy 416.481986 -23.844924) (xy 416.4479 -23.800781)
			(xy 416.420604 -23.752146) (xy 416.400681 -23.700055) (xy 416.388555 -23.645618) (xy 416.384484 -23.589996)
			(xy 402.775732 -23.589996) (xy 402.824235 -23.595333) (xy 402.878192 -23.609439) (xy 402.929521 -23.631251)
			(xy 402.977127 -23.660305) (xy 403.019995 -23.69598) (xy 403.057212 -23.737517) (xy 403.087985 -23.78403)
			(xy 403.111657 -23.834527) (xy 403.127725 -23.887934) (xy 403.135845 -23.94311) (xy 403.136354 -23.970996)
			(xy 403.135845 -23.998882) (xy 403.127725 -24.054058) (xy 403.111657 -24.107465) (xy 403.087985 -24.157962)
			(xy 403.087832 -24.158194) (xy 407.75077 -24.158194) (xy 407.754841 -24.102572) (xy 407.766967 -24.048135)
			(xy 407.78689 -23.996044) (xy 407.814186 -23.947409) (xy 407.848272 -23.903266) (xy 407.888421 -23.864557)
			(xy 407.933779 -23.832106) (xy 407.983379 -23.806605) (xy 408.036163 -23.788598) (xy 408.091006 -23.778468)
			(xy 408.14674 -23.776431) (xy 408.202177 -23.782531) (xy 408.256134 -23.796637) (xy 408.307463 -23.818449)
			(xy 408.355069 -23.847503) (xy 408.397937 -23.883178) (xy 408.435154 -23.924715) (xy 408.465927 -23.971228)
			(xy 408.489599 -24.021725) (xy 408.505667 -24.075132) (xy 408.513787 -24.130308) (xy 408.514296 -24.158194)
			(xy 408.513787 -24.18608) (xy 408.513218 -24.189944) (xy 411.59887 -24.189944) (xy 411.602941 -24.134322)
			(xy 411.615067 -24.079885) (xy 411.63499 -24.027794) (xy 411.662286 -23.979159) (xy 411.696372 -23.935016)
			(xy 411.736521 -23.896307) (xy 411.781879 -23.863856) (xy 411.831479 -23.838355) (xy 411.884263 -23.820348)
			(xy 411.939106 -23.810218) (xy 411.99484 -23.808181) (xy 412.050277 -23.814281) (xy 412.104234 -23.828387)
			(xy 412.155563 -23.850199) (xy 412.203169 -23.879253) (xy 412.246037 -23.914928) (xy 412.283254 -23.956465)
			(xy 412.314027 -24.002978) (xy 412.337699 -24.053475) (xy 412.353767 -24.106882) (xy 412.361887 -24.162058)
			(xy 412.362396 -24.189944) (xy 414.121852 -24.189944) (xy 414.125923 -24.134322) (xy 414.138049 -24.079885)
			(xy 414.157972 -24.027794) (xy 414.185268 -23.979159) (xy 414.219354 -23.935016) (xy 414.259503 -23.896307)
			(xy 414.304861 -23.863856) (xy 414.354461 -23.838355) (xy 414.407245 -23.820348) (xy 414.462088 -23.810218)
			(xy 414.517822 -23.808181) (xy 414.573259 -23.814281) (xy 414.627216 -23.828387) (xy 414.678545 -23.850199)
			(xy 414.726151 -23.879253) (xy 414.769019 -23.914928) (xy 414.806236 -23.956465) (xy 414.837009 -24.002978)
			(xy 414.860681 -24.053475) (xy 414.876749 -24.106882) (xy 414.884869 -24.162058) (xy 414.885378 -24.189944)
			(xy 414.884869 -24.21783) (xy 414.876749 -24.273006) (xy 414.860681 -24.326413) (xy 414.837009 -24.37691)
			(xy 414.806236 -24.423423) (xy 414.769019 -24.46496) (xy 414.726151 -24.500635) (xy 414.678545 -24.529689)
			(xy 414.627216 -24.551501) (xy 414.573259 -24.565607) (xy 414.517822 -24.571707) (xy 414.462088 -24.56967)
			(xy 414.407245 -24.55954) (xy 414.354461 -24.541533) (xy 414.304861 -24.516032) (xy 414.259503 -24.483581)
			(xy 414.219354 -24.444872) (xy 414.185268 -24.400729) (xy 414.157972 -24.352094) (xy 414.138049 -24.300003)
			(xy 414.125923 -24.245566) (xy 414.121852 -24.189944) (xy 412.362396 -24.189944) (xy 412.361887 -24.21783)
			(xy 412.353767 -24.273006) (xy 412.337699 -24.326413) (xy 412.314027 -24.37691) (xy 412.283254 -24.423423)
			(xy 412.246037 -24.46496) (xy 412.203169 -24.500635) (xy 412.155563 -24.529689) (xy 412.104234 -24.551501)
			(xy 412.050277 -24.565607) (xy 411.99484 -24.571707) (xy 411.939106 -24.56967) (xy 411.884263 -24.55954)
			(xy 411.831479 -24.541533) (xy 411.781879 -24.516032) (xy 411.736521 -24.483581) (xy 411.696372 -24.444872)
			(xy 411.662286 -24.400729) (xy 411.63499 -24.352094) (xy 411.615067 -24.300003) (xy 411.602941 -24.245566)
			(xy 411.59887 -24.189944) (xy 408.513218 -24.189944) (xy 408.505667 -24.241256) (xy 408.489599 -24.294663)
			(xy 408.465927 -24.34516) (xy 408.435154 -24.391673) (xy 408.397937 -24.43321) (xy 408.355069 -24.468885)
			(xy 408.307463 -24.497939) (xy 408.256134 -24.519751) (xy 408.202177 -24.533857) (xy 408.14674 -24.539957)
			(xy 408.091006 -24.53792) (xy 408.036163 -24.52779) (xy 407.983379 -24.509783) (xy 407.933779 -24.484282)
			(xy 407.888421 -24.451831) (xy 407.848272 -24.413122) (xy 407.814186 -24.368979) (xy 407.78689 -24.320344)
			(xy 407.766967 -24.268253) (xy 407.754841 -24.213816) (xy 407.75077 -24.158194) (xy 403.087832 -24.158194)
			(xy 403.057212 -24.204475) (xy 403.019995 -24.246012) (xy 402.977127 -24.281687) (xy 402.929521 -24.310741)
			(xy 402.878192 -24.332553) (xy 402.824235 -24.346659) (xy 402.768798 -24.352759) (xy 402.713064 -24.350722)
			(xy 402.658221 -24.340592) (xy 402.605437 -24.322585) (xy 402.555837 -24.297084) (xy 402.510479 -24.264633)
			(xy 402.47033 -24.225924) (xy 402.436244 -24.181781) (xy 402.408948 -24.133146) (xy 402.389025 -24.081055)
			(xy 402.376899 -24.026618) (xy 402.372828 -23.970996) (xy 402.143536 -23.970996) (xy 402.143467 -23.974752)
			(xy 402.135347 -24.029928) (xy 402.119279 -24.083335) (xy 402.095607 -24.133832) (xy 402.064834 -24.180345)
			(xy 402.027617 -24.221882) (xy 401.984749 -24.257557) (xy 401.937143 -24.286611) (xy 401.885814 -24.308423)
			(xy 401.831857 -24.322529) (xy 401.77642 -24.328629) (xy 401.720686 -24.326592) (xy 401.665843 -24.316462)
			(xy 401.613059 -24.298455) (xy 401.563459 -24.272954) (xy 401.518101 -24.240503) (xy 401.477952 -24.201794)
			(xy 401.443866 -24.157651) (xy 401.41657 -24.109016) (xy 401.396647 -24.056925) (xy 401.384521 -24.002488)
			(xy 401.38045 -23.946866) (xy 401.140596 -23.946866) (xy 401.14093 -23.965154) (xy 401.140421 -23.99304)
			(xy 401.132301 -24.048216) (xy 401.116233 -24.101623) (xy 401.092561 -24.15212) (xy 401.061788 -24.198633)
			(xy 401.024571 -24.24017) (xy 400.981703 -24.275845) (xy 400.934097 -24.304899) (xy 400.882768 -24.326711)
			(xy 400.828811 -24.340817) (xy 400.773374 -24.346917) (xy 400.71764 -24.34488) (xy 400.662797 -24.33475)
			(xy 400.610013 -24.316743) (xy 400.560413 -24.291242) (xy 400.515055 -24.258791) (xy 400.474906 -24.220082)
			(xy 400.44082 -24.175939) (xy 400.413524 -24.127304) (xy 400.393601 -24.075213) (xy 400.381475 -24.020776)
			(xy 400.377404 -23.965154) (xy 390.837875 -23.965154) (xy 390.835943 -23.965659) (xy 390.780506 -23.971759)
			(xy 390.724772 -23.969722) (xy 390.669929 -23.959592) (xy 390.617145 -23.941585) (xy 390.567545 -23.916084)
			(xy 390.522187 -23.883633) (xy 390.482038 -23.844924) (xy 390.447952 -23.800781) (xy 390.420656 -23.752146)
			(xy 390.400733 -23.700055) (xy 390.388607 -23.645618) (xy 390.384536 -23.589996) (xy 376.775784 -23.589996)
			(xy 376.824287 -23.595333) (xy 376.878244 -23.609439) (xy 376.929573 -23.631251) (xy 376.977179 -23.660305)
			(xy 377.020047 -23.69598) (xy 377.057264 -23.737517) (xy 377.088037 -23.78403) (xy 377.111709 -23.834527)
			(xy 377.127777 -23.887934) (xy 377.135897 -23.94311) (xy 377.136406 -23.970996) (xy 377.135897 -23.998882)
			(xy 377.127777 -24.054058) (xy 377.111709 -24.107465) (xy 377.088037 -24.157962) (xy 377.087884 -24.158194)
			(xy 381.750822 -24.158194) (xy 381.754893 -24.102572) (xy 381.767019 -24.048135) (xy 381.786942 -23.996044)
			(xy 381.814238 -23.947409) (xy 381.848324 -23.903266) (xy 381.888473 -23.864557) (xy 381.933831 -23.832106)
			(xy 381.983431 -23.806605) (xy 382.036215 -23.788598) (xy 382.091058 -23.778468) (xy 382.146792 -23.776431)
			(xy 382.202229 -23.782531) (xy 382.256186 -23.796637) (xy 382.307515 -23.818449) (xy 382.355121 -23.847503)
			(xy 382.397989 -23.883178) (xy 382.435206 -23.924715) (xy 382.465979 -23.971228) (xy 382.489651 -24.021725)
			(xy 382.505719 -24.075132) (xy 382.513839 -24.130308) (xy 382.514348 -24.158194) (xy 382.513839 -24.18608)
			(xy 382.51327 -24.189944) (xy 385.598922 -24.189944) (xy 385.602993 -24.134322) (xy 385.615119 -24.079885)
			(xy 385.635042 -24.027794) (xy 385.662338 -23.979159) (xy 385.696424 -23.935016) (xy 385.736573 -23.896307)
			(xy 385.781931 -23.863856) (xy 385.831531 -23.838355) (xy 385.884315 -23.820348) (xy 385.939158 -23.810218)
			(xy 385.994892 -23.808181) (xy 386.050329 -23.814281) (xy 386.104286 -23.828387) (xy 386.155615 -23.850199)
			(xy 386.203221 -23.879253) (xy 386.246089 -23.914928) (xy 386.283306 -23.956465) (xy 386.314079 -24.002978)
			(xy 386.337751 -24.053475) (xy 386.353819 -24.106882) (xy 386.361939 -24.162058) (xy 386.362448 -24.189944)
			(xy 388.121904 -24.189944) (xy 388.125975 -24.134322) (xy 388.138101 -24.079885) (xy 388.158024 -24.027794)
			(xy 388.18532 -23.979159) (xy 388.219406 -23.935016) (xy 388.259555 -23.896307) (xy 388.304913 -23.863856)
			(xy 388.354513 -23.838355) (xy 388.407297 -23.820348) (xy 388.46214 -23.810218) (xy 388.517874 -23.808181)
			(xy 388.573311 -23.814281) (xy 388.627268 -23.828387) (xy 388.678597 -23.850199) (xy 388.726203 -23.879253)
			(xy 388.769071 -23.914928) (xy 388.806288 -23.956465) (xy 388.837061 -24.002978) (xy 388.860733 -24.053475)
			(xy 388.876801 -24.106882) (xy 388.884921 -24.162058) (xy 388.88543 -24.189944) (xy 388.884921 -24.21783)
			(xy 388.876801 -24.273006) (xy 388.860733 -24.326413) (xy 388.837061 -24.37691) (xy 388.806288 -24.423423)
			(xy 388.769071 -24.46496) (xy 388.726203 -24.500635) (xy 388.678597 -24.529689) (xy 388.627268 -24.551501)
			(xy 388.573311 -24.565607) (xy 388.517874 -24.571707) (xy 388.46214 -24.56967) (xy 388.407297 -24.55954)
			(xy 388.354513 -24.541533) (xy 388.304913 -24.516032) (xy 388.259555 -24.483581) (xy 388.219406 -24.444872)
			(xy 388.18532 -24.400729) (xy 388.158024 -24.352094) (xy 388.138101 -24.300003) (xy 388.125975 -24.245566)
			(xy 388.121904 -24.189944) (xy 386.362448 -24.189944) (xy 386.361939 -24.21783) (xy 386.353819 -24.273006)
			(xy 386.337751 -24.326413) (xy 386.314079 -24.37691) (xy 386.283306 -24.423423) (xy 386.246089 -24.46496)
			(xy 386.203221 -24.500635) (xy 386.155615 -24.529689) (xy 386.104286 -24.551501) (xy 386.050329 -24.565607)
			(xy 385.994892 -24.571707) (xy 385.939158 -24.56967) (xy 385.884315 -24.55954) (xy 385.831531 -24.541533)
			(xy 385.781931 -24.516032) (xy 385.736573 -24.483581) (xy 385.696424 -24.444872) (xy 385.662338 -24.400729)
			(xy 385.635042 -24.352094) (xy 385.615119 -24.300003) (xy 385.602993 -24.245566) (xy 385.598922 -24.189944)
			(xy 382.51327 -24.189944) (xy 382.505719 -24.241256) (xy 382.489651 -24.294663) (xy 382.465979 -24.34516)
			(xy 382.435206 -24.391673) (xy 382.397989 -24.43321) (xy 382.355121 -24.468885) (xy 382.307515 -24.497939)
			(xy 382.256186 -24.519751) (xy 382.202229 -24.533857) (xy 382.146792 -24.539957) (xy 382.091058 -24.53792)
			(xy 382.036215 -24.52779) (xy 381.983431 -24.509783) (xy 381.933831 -24.484282) (xy 381.888473 -24.451831)
			(xy 381.848324 -24.413122) (xy 381.814238 -24.368979) (xy 381.786942 -24.320344) (xy 381.767019 -24.268253)
			(xy 381.754893 -24.213816) (xy 381.750822 -24.158194) (xy 377.087884 -24.158194) (xy 377.057264 -24.204475)
			(xy 377.020047 -24.246012) (xy 376.977179 -24.281687) (xy 376.929573 -24.310741) (xy 376.878244 -24.332553)
			(xy 376.824287 -24.346659) (xy 376.76885 -24.352759) (xy 376.713116 -24.350722) (xy 376.658273 -24.340592)
			(xy 376.605489 -24.322585) (xy 376.555889 -24.297084) (xy 376.510531 -24.264633) (xy 376.470382 -24.225924)
			(xy 376.436296 -24.181781) (xy 376.409 -24.133146) (xy 376.389077 -24.081055) (xy 376.376951 -24.026618)
			(xy 376.37288 -23.970996) (xy 376.143588 -23.970996) (xy 376.143519 -23.974752) (xy 376.135399 -24.029928)
			(xy 376.119331 -24.083335) (xy 376.095659 -24.133832) (xy 376.064886 -24.180345) (xy 376.027669 -24.221882)
			(xy 375.984801 -24.257557) (xy 375.937195 -24.286611) (xy 375.885866 -24.308423) (xy 375.831909 -24.322529)
			(xy 375.776472 -24.328629) (xy 375.720738 -24.326592) (xy 375.665895 -24.316462) (xy 375.613111 -24.298455)
			(xy 375.563511 -24.272954) (xy 375.518153 -24.240503) (xy 375.478004 -24.201794) (xy 375.443918 -24.157651)
			(xy 375.416622 -24.109016) (xy 375.396699 -24.056925) (xy 375.384573 -24.002488) (xy 375.380502 -23.946866)
			(xy 375.140648 -23.946866) (xy 375.140982 -23.965154) (xy 375.140473 -23.99304) (xy 375.132353 -24.048216)
			(xy 375.116285 -24.101623) (xy 375.092613 -24.15212) (xy 375.06184 -24.198633) (xy 375.024623 -24.24017)
			(xy 374.981755 -24.275845) (xy 374.934149 -24.304899) (xy 374.88282 -24.326711) (xy 374.828863 -24.340817)
			(xy 374.773426 -24.346917) (xy 374.717692 -24.34488) (xy 374.662849 -24.33475) (xy 374.610065 -24.316743)
			(xy 374.560465 -24.291242) (xy 374.515107 -24.258791) (xy 374.474958 -24.220082) (xy 374.440872 -24.175939)
			(xy 374.413576 -24.127304) (xy 374.393653 -24.075213) (xy 374.381527 -24.020776) (xy 374.377456 -23.965154)
			(xy 364.837927 -23.965154) (xy 364.835995 -23.965659) (xy 364.780558 -23.971759) (xy 364.724824 -23.969722)
			(xy 364.669981 -23.959592) (xy 364.617197 -23.941585) (xy 364.567597 -23.916084) (xy 364.522239 -23.883633)
			(xy 364.48209 -23.844924) (xy 364.448004 -23.800781) (xy 364.420708 -23.752146) (xy 364.400785 -23.700055)
			(xy 364.388659 -23.645618) (xy 364.384588 -23.589996) (xy 327.04786 -23.589996) (xy 327.047351 -23.617882)
			(xy 327.039231 -23.673058) (xy 327.023163 -23.726465) (xy 326.999491 -23.776962) (xy 326.968718 -23.823475)
			(xy 326.931501 -23.865012) (xy 326.888633 -23.900687) (xy 326.841027 -23.929741) (xy 326.789698 -23.951553)
			(xy 326.735741 -23.965659) (xy 326.680304 -23.971759) (xy 326.62457 -23.969722) (xy 326.569727 -23.959592)
			(xy 326.516943 -23.941585) (xy 326.467343 -23.916084) (xy 326.421985 -23.883633) (xy 326.381836 -23.844924)
			(xy 326.34775 -23.800781) (xy 326.320454 -23.752146) (xy 326.300531 -23.700055) (xy 326.288405 -23.645618)
			(xy 326.284334 -23.589996) (xy 312.675582 -23.589996) (xy 312.724085 -23.595333) (xy 312.778042 -23.609439)
			(xy 312.829371 -23.631251) (xy 312.876977 -23.660305) (xy 312.919845 -23.69598) (xy 312.957062 -23.737517)
			(xy 312.987835 -23.78403) (xy 313.011507 -23.834527) (xy 313.027575 -23.887934) (xy 313.035695 -23.94311)
			(xy 313.036204 -23.970996) (xy 313.035695 -23.998882) (xy 313.027575 -24.054058) (xy 313.011507 -24.107465)
			(xy 312.987835 -24.157962) (xy 312.987682 -24.158194) (xy 317.65062 -24.158194) (xy 317.654691 -24.102572)
			(xy 317.666817 -24.048135) (xy 317.68674 -23.996044) (xy 317.714036 -23.947409) (xy 317.748122 -23.903266)
			(xy 317.788271 -23.864557) (xy 317.833629 -23.832106) (xy 317.883229 -23.806605) (xy 317.936013 -23.788598)
			(xy 317.990856 -23.778468) (xy 318.04659 -23.776431) (xy 318.102027 -23.782531) (xy 318.155984 -23.796637)
			(xy 318.207313 -23.818449) (xy 318.254919 -23.847503) (xy 318.297787 -23.883178) (xy 318.335004 -23.924715)
			(xy 318.365777 -23.971228) (xy 318.389449 -24.021725) (xy 318.405517 -24.075132) (xy 318.413637 -24.130308)
			(xy 318.414146 -24.158194) (xy 318.413637 -24.18608) (xy 318.413068 -24.189944) (xy 321.49872 -24.189944)
			(xy 321.502791 -24.134322) (xy 321.514917 -24.079885) (xy 321.53484 -24.027794) (xy 321.562136 -23.979159)
			(xy 321.596222 -23.935016) (xy 321.636371 -23.896307) (xy 321.681729 -23.863856) (xy 321.731329 -23.838355)
			(xy 321.784113 -23.820348) (xy 321.838956 -23.810218) (xy 321.89469 -23.808181) (xy 321.950127 -23.814281)
			(xy 322.004084 -23.828387) (xy 322.055413 -23.850199) (xy 322.103019 -23.879253) (xy 322.145887 -23.914928)
			(xy 322.183104 -23.956465) (xy 322.213877 -24.002978) (xy 322.237549 -24.053475) (xy 322.253617 -24.106882)
			(xy 322.261737 -24.162058) (xy 322.262246 -24.189944) (xy 324.021702 -24.189944) (xy 324.025773 -24.134322)
			(xy 324.037899 -24.079885) (xy 324.057822 -24.027794) (xy 324.085118 -23.979159) (xy 324.119204 -23.935016)
			(xy 324.159353 -23.896307) (xy 324.204711 -23.863856) (xy 324.254311 -23.838355) (xy 324.307095 -23.820348)
			(xy 324.361938 -23.810218) (xy 324.417672 -23.808181) (xy 324.473109 -23.814281) (xy 324.527066 -23.828387)
			(xy 324.578395 -23.850199) (xy 324.626001 -23.879253) (xy 324.668869 -23.914928) (xy 324.706086 -23.956465)
			(xy 324.736859 -24.002978) (xy 324.760531 -24.053475) (xy 324.776599 -24.106882) (xy 324.78415 -24.158194)
			(xy 355.750874 -24.158194) (xy 355.754945 -24.102572) (xy 355.767071 -24.048135) (xy 355.786994 -23.996044)
			(xy 355.81429 -23.947409) (xy 355.848376 -23.903266) (xy 355.888525 -23.864557) (xy 355.933883 -23.832106)
			(xy 355.983483 -23.806605) (xy 356.036267 -23.788598) (xy 356.09111 -23.778468) (xy 356.146844 -23.776431)
			(xy 356.202281 -23.782531) (xy 356.256238 -23.796637) (xy 356.307567 -23.818449) (xy 356.355173 -23.847503)
			(xy 356.398041 -23.883178) (xy 356.435258 -23.924715) (xy 356.466031 -23.971228) (xy 356.489703 -24.021725)
			(xy 356.505771 -24.075132) (xy 356.513891 -24.130308) (xy 356.5144 -24.158194) (xy 356.513891 -24.18608)
			(xy 356.513322 -24.189944) (xy 359.598974 -24.189944) (xy 359.603045 -24.134322) (xy 359.615171 -24.079885)
			(xy 359.635094 -24.027794) (xy 359.66239 -23.979159) (xy 359.696476 -23.935016) (xy 359.736625 -23.896307)
			(xy 359.781983 -23.863856) (xy 359.831583 -23.838355) (xy 359.884367 -23.820348) (xy 359.93921 -23.810218)
			(xy 359.994944 -23.808181) (xy 360.050381 -23.814281) (xy 360.104338 -23.828387) (xy 360.155667 -23.850199)
			(xy 360.203273 -23.879253) (xy 360.246141 -23.914928) (xy 360.283358 -23.956465) (xy 360.314131 -24.002978)
			(xy 360.337803 -24.053475) (xy 360.353871 -24.106882) (xy 360.361991 -24.162058) (xy 360.3625 -24.189944)
			(xy 362.121956 -24.189944) (xy 362.126027 -24.134322) (xy 362.138153 -24.079885) (xy 362.158076 -24.027794)
			(xy 362.185372 -23.979159) (xy 362.219458 -23.935016) (xy 362.259607 -23.896307) (xy 362.304965 -23.863856)
			(xy 362.354565 -23.838355) (xy 362.407349 -23.820348) (xy 362.462192 -23.810218) (xy 362.517926 -23.808181)
			(xy 362.573363 -23.814281) (xy 362.62732 -23.828387) (xy 362.678649 -23.850199) (xy 362.726255 -23.879253)
			(xy 362.769123 -23.914928) (xy 362.80634 -23.956465) (xy 362.837113 -24.002978) (xy 362.860785 -24.053475)
			(xy 362.876853 -24.106882) (xy 362.884973 -24.162058) (xy 362.885482 -24.189944) (xy 362.884973 -24.21783)
			(xy 362.876853 -24.273006) (xy 362.860785 -24.326413) (xy 362.837113 -24.37691) (xy 362.80634 -24.423423)
			(xy 362.769123 -24.46496) (xy 362.726255 -24.500635) (xy 362.678649 -24.529689) (xy 362.62732 -24.551501)
			(xy 362.573363 -24.565607) (xy 362.517926 -24.571707) (xy 362.462192 -24.56967) (xy 362.407349 -24.55954)
			(xy 362.354565 -24.541533) (xy 362.304965 -24.516032) (xy 362.259607 -24.483581) (xy 362.219458 -24.444872)
			(xy 362.185372 -24.400729) (xy 362.158076 -24.352094) (xy 362.138153 -24.300003) (xy 362.126027 -24.245566)
			(xy 362.121956 -24.189944) (xy 360.3625 -24.189944) (xy 360.361991 -24.21783) (xy 360.353871 -24.273006)
			(xy 360.337803 -24.326413) (xy 360.314131 -24.37691) (xy 360.283358 -24.423423) (xy 360.246141 -24.46496)
			(xy 360.203273 -24.500635) (xy 360.155667 -24.529689) (xy 360.104338 -24.551501) (xy 360.050381 -24.565607)
			(xy 359.994944 -24.571707) (xy 359.93921 -24.56967) (xy 359.884367 -24.55954) (xy 359.831583 -24.541533)
			(xy 359.781983 -24.516032) (xy 359.736625 -24.483581) (xy 359.696476 -24.444872) (xy 359.66239 -24.400729)
			(xy 359.635094 -24.352094) (xy 359.615171 -24.300003) (xy 359.603045 -24.245566) (xy 359.598974 -24.189944)
			(xy 356.513322 -24.189944) (xy 356.505771 -24.241256) (xy 356.489703 -24.294663) (xy 356.466031 -24.34516)
			(xy 356.435258 -24.391673) (xy 356.398041 -24.43321) (xy 356.355173 -24.468885) (xy 356.307567 -24.497939)
			(xy 356.256238 -24.519751) (xy 356.202281 -24.533857) (xy 356.146844 -24.539957) (xy 356.09111 -24.53792)
			(xy 356.036267 -24.52779) (xy 355.983483 -24.509783) (xy 355.933883 -24.484282) (xy 355.888525 -24.451831)
			(xy 355.848376 -24.413122) (xy 355.81429 -24.368979) (xy 355.786994 -24.320344) (xy 355.767071 -24.268253)
			(xy 355.754945 -24.213816) (xy 355.750874 -24.158194) (xy 324.78415 -24.158194) (xy 324.784719 -24.162058)
			(xy 324.785228 -24.189944) (xy 324.784719 -24.21783) (xy 324.776599 -24.273006) (xy 324.760531 -24.326413)
			(xy 324.736859 -24.37691) (xy 324.706086 -24.423423) (xy 324.668869 -24.46496) (xy 324.626001 -24.500635)
			(xy 324.578395 -24.529689) (xy 324.527066 -24.551501) (xy 324.473109 -24.565607) (xy 324.417672 -24.571707)
			(xy 324.361938 -24.56967) (xy 324.307095 -24.55954) (xy 324.254311 -24.541533) (xy 324.204711 -24.516032)
			(xy 324.159353 -24.483581) (xy 324.119204 -24.444872) (xy 324.085118 -24.400729) (xy 324.057822 -24.352094)
			(xy 324.037899 -24.300003) (xy 324.025773 -24.245566) (xy 324.021702 -24.189944) (xy 322.262246 -24.189944)
			(xy 322.261737 -24.21783) (xy 322.253617 -24.273006) (xy 322.237549 -24.326413) (xy 322.213877 -24.37691)
			(xy 322.183104 -24.423423) (xy 322.145887 -24.46496) (xy 322.103019 -24.500635) (xy 322.055413 -24.529689)
			(xy 322.004084 -24.551501) (xy 321.950127 -24.565607) (xy 321.89469 -24.571707) (xy 321.838956 -24.56967)
			(xy 321.784113 -24.55954) (xy 321.731329 -24.541533) (xy 321.681729 -24.516032) (xy 321.636371 -24.483581)
			(xy 321.596222 -24.444872) (xy 321.562136 -24.400729) (xy 321.53484 -24.352094) (xy 321.514917 -24.300003)
			(xy 321.502791 -24.245566) (xy 321.49872 -24.189944) (xy 318.413068 -24.189944) (xy 318.405517 -24.241256)
			(xy 318.389449 -24.294663) (xy 318.365777 -24.34516) (xy 318.335004 -24.391673) (xy 318.297787 -24.43321)
			(xy 318.254919 -24.468885) (xy 318.207313 -24.497939) (xy 318.155984 -24.519751) (xy 318.102027 -24.533857)
			(xy 318.04659 -24.539957) (xy 317.990856 -24.53792) (xy 317.936013 -24.52779) (xy 317.883229 -24.509783)
			(xy 317.833629 -24.484282) (xy 317.788271 -24.451831) (xy 317.748122 -24.413122) (xy 317.714036 -24.368979)
			(xy 317.68674 -24.320344) (xy 317.666817 -24.268253) (xy 317.654691 -24.213816) (xy 317.65062 -24.158194)
			(xy 312.987682 -24.158194) (xy 312.957062 -24.204475) (xy 312.919845 -24.246012) (xy 312.876977 -24.281687)
			(xy 312.829371 -24.310741) (xy 312.778042 -24.332553) (xy 312.724085 -24.346659) (xy 312.668648 -24.352759)
			(xy 312.612914 -24.350722) (xy 312.558071 -24.340592) (xy 312.505287 -24.322585) (xy 312.455687 -24.297084)
			(xy 312.410329 -24.264633) (xy 312.37018 -24.225924) (xy 312.336094 -24.181781) (xy 312.308798 -24.133146)
			(xy 312.288875 -24.081055) (xy 312.276749 -24.026618) (xy 312.272678 -23.970996) (xy 312.043386 -23.970996)
			(xy 312.043317 -23.974752) (xy 312.035197 -24.029928) (xy 312.019129 -24.083335) (xy 311.995457 -24.133832)
			(xy 311.964684 -24.180345) (xy 311.927467 -24.221882) (xy 311.884599 -24.257557) (xy 311.836993 -24.286611)
			(xy 311.785664 -24.308423) (xy 311.731707 -24.322529) (xy 311.67627 -24.328629) (xy 311.620536 -24.326592)
			(xy 311.565693 -24.316462) (xy 311.512909 -24.298455) (xy 311.463309 -24.272954) (xy 311.417951 -24.240503)
			(xy 311.377802 -24.201794) (xy 311.343716 -24.157651) (xy 311.31642 -24.109016) (xy 311.296497 -24.056925)
			(xy 311.284371 -24.002488) (xy 311.2803 -23.946866) (xy 311.040446 -23.946866) (xy 311.04078 -23.965154)
			(xy 311.040271 -23.99304) (xy 311.032151 -24.048216) (xy 311.016083 -24.101623) (xy 310.992411 -24.15212)
			(xy 310.961638 -24.198633) (xy 310.924421 -24.24017) (xy 310.881553 -24.275845) (xy 310.833947 -24.304899)
			(xy 310.782618 -24.326711) (xy 310.728661 -24.340817) (xy 310.673224 -24.346917) (xy 310.61749 -24.34488)
			(xy 310.562647 -24.33475) (xy 310.509863 -24.316743) (xy 310.460263 -24.291242) (xy 310.414905 -24.258791)
			(xy 310.374756 -24.220082) (xy 310.34067 -24.175939) (xy 310.313374 -24.127304) (xy 310.293451 -24.075213)
			(xy 310.281325 -24.020776) (xy 310.277254 -23.965154) (xy 300.737725 -23.965154) (xy 300.735793 -23.965659)
			(xy 300.680356 -23.971759) (xy 300.624622 -23.969722) (xy 300.569779 -23.959592) (xy 300.516995 -23.941585)
			(xy 300.467395 -23.916084) (xy 300.422037 -23.883633) (xy 300.381888 -23.844924) (xy 300.347802 -23.800781)
			(xy 300.320506 -23.752146) (xy 300.300583 -23.700055) (xy 300.288457 -23.645618) (xy 300.284386 -23.589996)
			(xy 286.675634 -23.589996) (xy 286.724137 -23.595333) (xy 286.778094 -23.609439) (xy 286.829423 -23.631251)
			(xy 286.877029 -23.660305) (xy 286.919897 -23.69598) (xy 286.957114 -23.737517) (xy 286.987887 -23.78403)
			(xy 287.011559 -23.834527) (xy 287.027627 -23.887934) (xy 287.035747 -23.94311) (xy 287.036256 -23.970996)
			(xy 287.035747 -23.998882) (xy 287.027627 -24.054058) (xy 287.011559 -24.107465) (xy 286.987887 -24.157962)
			(xy 286.987734 -24.158194) (xy 291.650672 -24.158194) (xy 291.654743 -24.102572) (xy 291.666869 -24.048135)
			(xy 291.686792 -23.996044) (xy 291.714088 -23.947409) (xy 291.748174 -23.903266) (xy 291.788323 -23.864557)
			(xy 291.833681 -23.832106) (xy 291.883281 -23.806605) (xy 291.936065 -23.788598) (xy 291.990908 -23.778468)
			(xy 292.046642 -23.776431) (xy 292.102079 -23.782531) (xy 292.156036 -23.796637) (xy 292.207365 -23.818449)
			(xy 292.254971 -23.847503) (xy 292.297839 -23.883178) (xy 292.335056 -23.924715) (xy 292.365829 -23.971228)
			(xy 292.389501 -24.021725) (xy 292.405569 -24.075132) (xy 292.413689 -24.130308) (xy 292.414198 -24.158194)
			(xy 292.413689 -24.18608) (xy 292.41312 -24.189944) (xy 295.498772 -24.189944) (xy 295.502843 -24.134322)
			(xy 295.514969 -24.079885) (xy 295.534892 -24.027794) (xy 295.562188 -23.979159) (xy 295.596274 -23.935016)
			(xy 295.636423 -23.896307) (xy 295.681781 -23.863856) (xy 295.731381 -23.838355) (xy 295.784165 -23.820348)
			(xy 295.839008 -23.810218) (xy 295.894742 -23.808181) (xy 295.950179 -23.814281) (xy 296.004136 -23.828387)
			(xy 296.055465 -23.850199) (xy 296.103071 -23.879253) (xy 296.145939 -23.914928) (xy 296.183156 -23.956465)
			(xy 296.213929 -24.002978) (xy 296.237601 -24.053475) (xy 296.253669 -24.106882) (xy 296.261789 -24.162058)
			(xy 296.262298 -24.189944) (xy 298.021754 -24.189944) (xy 298.025825 -24.134322) (xy 298.037951 -24.079885)
			(xy 298.057874 -24.027794) (xy 298.08517 -23.979159) (xy 298.119256 -23.935016) (xy 298.159405 -23.896307)
			(xy 298.204763 -23.863856) (xy 298.254363 -23.838355) (xy 298.307147 -23.820348) (xy 298.36199 -23.810218)
			(xy 298.417724 -23.808181) (xy 298.473161 -23.814281) (xy 298.527118 -23.828387) (xy 298.578447 -23.850199)
			(xy 298.626053 -23.879253) (xy 298.668921 -23.914928) (xy 298.706138 -23.956465) (xy 298.736911 -24.002978)
			(xy 298.760583 -24.053475) (xy 298.776651 -24.106882) (xy 298.784771 -24.162058) (xy 298.78528 -24.189944)
			(xy 298.784771 -24.21783) (xy 298.776651 -24.273006) (xy 298.760583 -24.326413) (xy 298.736911 -24.37691)
			(xy 298.706138 -24.423423) (xy 298.668921 -24.46496) (xy 298.626053 -24.500635) (xy 298.578447 -24.529689)
			(xy 298.527118 -24.551501) (xy 298.473161 -24.565607) (xy 298.417724 -24.571707) (xy 298.36199 -24.56967)
			(xy 298.307147 -24.55954) (xy 298.254363 -24.541533) (xy 298.204763 -24.516032) (xy 298.159405 -24.483581)
			(xy 298.119256 -24.444872) (xy 298.08517 -24.400729) (xy 298.057874 -24.352094) (xy 298.037951 -24.300003)
			(xy 298.025825 -24.245566) (xy 298.021754 -24.189944) (xy 296.262298 -24.189944) (xy 296.261789 -24.21783)
			(xy 296.253669 -24.273006) (xy 296.237601 -24.326413) (xy 296.213929 -24.37691) (xy 296.183156 -24.423423)
			(xy 296.145939 -24.46496) (xy 296.103071 -24.500635) (xy 296.055465 -24.529689) (xy 296.004136 -24.551501)
			(xy 295.950179 -24.565607) (xy 295.894742 -24.571707) (xy 295.839008 -24.56967) (xy 295.784165 -24.55954)
			(xy 295.731381 -24.541533) (xy 295.681781 -24.516032) (xy 295.636423 -24.483581) (xy 295.596274 -24.444872)
			(xy 295.562188 -24.400729) (xy 295.534892 -24.352094) (xy 295.514969 -24.300003) (xy 295.502843 -24.245566)
			(xy 295.498772 -24.189944) (xy 292.41312 -24.189944) (xy 292.405569 -24.241256) (xy 292.389501 -24.294663)
			(xy 292.365829 -24.34516) (xy 292.335056 -24.391673) (xy 292.297839 -24.43321) (xy 292.254971 -24.468885)
			(xy 292.207365 -24.497939) (xy 292.156036 -24.519751) (xy 292.102079 -24.533857) (xy 292.046642 -24.539957)
			(xy 291.990908 -24.53792) (xy 291.936065 -24.52779) (xy 291.883281 -24.509783) (xy 291.833681 -24.484282)
			(xy 291.788323 -24.451831) (xy 291.748174 -24.413122) (xy 291.714088 -24.368979) (xy 291.686792 -24.320344)
			(xy 291.666869 -24.268253) (xy 291.654743 -24.213816) (xy 291.650672 -24.158194) (xy 286.987734 -24.158194)
			(xy 286.957114 -24.204475) (xy 286.919897 -24.246012) (xy 286.877029 -24.281687) (xy 286.829423 -24.310741)
			(xy 286.778094 -24.332553) (xy 286.724137 -24.346659) (xy 286.6687 -24.352759) (xy 286.612966 -24.350722)
			(xy 286.558123 -24.340592) (xy 286.505339 -24.322585) (xy 286.455739 -24.297084) (xy 286.410381 -24.264633)
			(xy 286.370232 -24.225924) (xy 286.336146 -24.181781) (xy 286.30885 -24.133146) (xy 286.288927 -24.081055)
			(xy 286.276801 -24.026618) (xy 286.27273 -23.970996) (xy 286.043438 -23.970996) (xy 286.043369 -23.974752)
			(xy 286.035249 -24.029928) (xy 286.019181 -24.083335) (xy 285.995509 -24.133832) (xy 285.964736 -24.180345)
			(xy 285.927519 -24.221882) (xy 285.884651 -24.257557) (xy 285.837045 -24.286611) (xy 285.785716 -24.308423)
			(xy 285.731759 -24.322529) (xy 285.676322 -24.328629) (xy 285.620588 -24.326592) (xy 285.565745 -24.316462)
			(xy 285.512961 -24.298455) (xy 285.463361 -24.272954) (xy 285.418003 -24.240503) (xy 285.377854 -24.201794)
			(xy 285.343768 -24.157651) (xy 285.316472 -24.109016) (xy 285.296549 -24.056925) (xy 285.284423 -24.002488)
			(xy 285.280352 -23.946866) (xy 285.040498 -23.946866) (xy 285.040832 -23.965154) (xy 285.040323 -23.99304)
			(xy 285.032203 -24.048216) (xy 285.016135 -24.101623) (xy 284.992463 -24.15212) (xy 284.96169 -24.198633)
			(xy 284.924473 -24.24017) (xy 284.881605 -24.275845) (xy 284.833999 -24.304899) (xy 284.78267 -24.326711)
			(xy 284.728713 -24.340817) (xy 284.673276 -24.346917) (xy 284.617542 -24.34488) (xy 284.562699 -24.33475)
			(xy 284.509915 -24.316743) (xy 284.460315 -24.291242) (xy 284.414957 -24.258791) (xy 284.374808 -24.220082)
			(xy 284.340722 -24.175939) (xy 284.313426 -24.127304) (xy 284.293503 -24.075213) (xy 284.281377 -24.020776)
			(xy 284.277306 -23.965154) (xy 274.737777 -23.965154) (xy 274.735845 -23.965659) (xy 274.680408 -23.971759)
			(xy 274.624674 -23.969722) (xy 274.569831 -23.959592) (xy 274.517047 -23.941585) (xy 274.467447 -23.916084)
			(xy 274.422089 -23.883633) (xy 274.38194 -23.844924) (xy 274.347854 -23.800781) (xy 274.320558 -23.752146)
			(xy 274.300635 -23.700055) (xy 274.288509 -23.645618) (xy 274.284438 -23.589996) (xy 260.675686 -23.589996)
			(xy 260.724189 -23.595333) (xy 260.778146 -23.609439) (xy 260.829475 -23.631251) (xy 260.877081 -23.660305)
			(xy 260.919949 -23.69598) (xy 260.957166 -23.737517) (xy 260.987939 -23.78403) (xy 261.011611 -23.834527)
			(xy 261.027679 -23.887934) (xy 261.035799 -23.94311) (xy 261.036308 -23.970996) (xy 261.035799 -23.998882)
			(xy 261.027679 -24.054058) (xy 261.011611 -24.107465) (xy 260.987939 -24.157962) (xy 260.987786 -24.158194)
			(xy 265.650724 -24.158194) (xy 265.654795 -24.102572) (xy 265.666921 -24.048135) (xy 265.686844 -23.996044)
			(xy 265.71414 -23.947409) (xy 265.748226 -23.903266) (xy 265.788375 -23.864557) (xy 265.833733 -23.832106)
			(xy 265.883333 -23.806605) (xy 265.936117 -23.788598) (xy 265.99096 -23.778468) (xy 266.046694 -23.776431)
			(xy 266.102131 -23.782531) (xy 266.156088 -23.796637) (xy 266.207417 -23.818449) (xy 266.255023 -23.847503)
			(xy 266.297891 -23.883178) (xy 266.335108 -23.924715) (xy 266.365881 -23.971228) (xy 266.389553 -24.021725)
			(xy 266.405621 -24.075132) (xy 266.413741 -24.130308) (xy 266.41425 -24.158194) (xy 266.413741 -24.18608)
			(xy 266.413172 -24.189944) (xy 269.498824 -24.189944) (xy 269.502895 -24.134322) (xy 269.515021 -24.079885)
			(xy 269.534944 -24.027794) (xy 269.56224 -23.979159) (xy 269.596326 -23.935016) (xy 269.636475 -23.896307)
			(xy 269.681833 -23.863856) (xy 269.731433 -23.838355) (xy 269.784217 -23.820348) (xy 269.83906 -23.810218)
			(xy 269.894794 -23.808181) (xy 269.950231 -23.814281) (xy 270.004188 -23.828387) (xy 270.055517 -23.850199)
			(xy 270.103123 -23.879253) (xy 270.145991 -23.914928) (xy 270.183208 -23.956465) (xy 270.213981 -24.002978)
			(xy 270.237653 -24.053475) (xy 270.253721 -24.106882) (xy 270.261841 -24.162058) (xy 270.26235 -24.189944)
			(xy 272.021806 -24.189944) (xy 272.025877 -24.134322) (xy 272.038003 -24.079885) (xy 272.057926 -24.027794)
			(xy 272.085222 -23.979159) (xy 272.119308 -23.935016) (xy 272.159457 -23.896307) (xy 272.204815 -23.863856)
			(xy 272.254415 -23.838355) (xy 272.307199 -23.820348) (xy 272.362042 -23.810218) (xy 272.417776 -23.808181)
			(xy 272.473213 -23.814281) (xy 272.52717 -23.828387) (xy 272.578499 -23.850199) (xy 272.626105 -23.879253)
			(xy 272.668973 -23.914928) (xy 272.70619 -23.956465) (xy 272.736963 -24.002978) (xy 272.760635 -24.053475)
			(xy 272.776703 -24.106882) (xy 272.784823 -24.162058) (xy 272.785332 -24.189944) (xy 272.784823 -24.21783)
			(xy 272.776703 -24.273006) (xy 272.760635 -24.326413) (xy 272.736963 -24.37691) (xy 272.70619 -24.423423)
			(xy 272.668973 -24.46496) (xy 272.626105 -24.500635) (xy 272.578499 -24.529689) (xy 272.52717 -24.551501)
			(xy 272.473213 -24.565607) (xy 272.417776 -24.571707) (xy 272.362042 -24.56967) (xy 272.307199 -24.55954)
			(xy 272.254415 -24.541533) (xy 272.204815 -24.516032) (xy 272.159457 -24.483581) (xy 272.119308 -24.444872)
			(xy 272.085222 -24.400729) (xy 272.057926 -24.352094) (xy 272.038003 -24.300003) (xy 272.025877 -24.245566)
			(xy 272.021806 -24.189944) (xy 270.26235 -24.189944) (xy 270.261841 -24.21783) (xy 270.253721 -24.273006)
			(xy 270.237653 -24.326413) (xy 270.213981 -24.37691) (xy 270.183208 -24.423423) (xy 270.145991 -24.46496)
			(xy 270.103123 -24.500635) (xy 270.055517 -24.529689) (xy 270.004188 -24.551501) (xy 269.950231 -24.565607)
			(xy 269.894794 -24.571707) (xy 269.83906 -24.56967) (xy 269.784217 -24.55954) (xy 269.731433 -24.541533)
			(xy 269.681833 -24.516032) (xy 269.636475 -24.483581) (xy 269.596326 -24.444872) (xy 269.56224 -24.400729)
			(xy 269.534944 -24.352094) (xy 269.515021 -24.300003) (xy 269.502895 -24.245566) (xy 269.498824 -24.189944)
			(xy 266.413172 -24.189944) (xy 266.405621 -24.241256) (xy 266.389553 -24.294663) (xy 266.365881 -24.34516)
			(xy 266.335108 -24.391673) (xy 266.297891 -24.43321) (xy 266.255023 -24.468885) (xy 266.207417 -24.497939)
			(xy 266.156088 -24.519751) (xy 266.102131 -24.533857) (xy 266.046694 -24.539957) (xy 265.99096 -24.53792)
			(xy 265.936117 -24.52779) (xy 265.883333 -24.509783) (xy 265.833733 -24.484282) (xy 265.788375 -24.451831)
			(xy 265.748226 -24.413122) (xy 265.71414 -24.368979) (xy 265.686844 -24.320344) (xy 265.666921 -24.268253)
			(xy 265.654795 -24.213816) (xy 265.650724 -24.158194) (xy 260.987786 -24.158194) (xy 260.957166 -24.204475)
			(xy 260.919949 -24.246012) (xy 260.877081 -24.281687) (xy 260.829475 -24.310741) (xy 260.778146 -24.332553)
			(xy 260.724189 -24.346659) (xy 260.668752 -24.352759) (xy 260.613018 -24.350722) (xy 260.558175 -24.340592)
			(xy 260.505391 -24.322585) (xy 260.455791 -24.297084) (xy 260.410433 -24.264633) (xy 260.370284 -24.225924)
			(xy 260.336198 -24.181781) (xy 260.308902 -24.133146) (xy 260.288979 -24.081055) (xy 260.276853 -24.026618)
			(xy 260.272782 -23.970996) (xy 260.04349 -23.970996) (xy 260.043421 -23.974752) (xy 260.035301 -24.029928)
			(xy 260.019233 -24.083335) (xy 259.995561 -24.133832) (xy 259.964788 -24.180345) (xy 259.927571 -24.221882)
			(xy 259.884703 -24.257557) (xy 259.837097 -24.286611) (xy 259.785768 -24.308423) (xy 259.731811 -24.322529)
			(xy 259.676374 -24.328629) (xy 259.62064 -24.326592) (xy 259.565797 -24.316462) (xy 259.513013 -24.298455)
			(xy 259.463413 -24.272954) (xy 259.418055 -24.240503) (xy 259.377906 -24.201794) (xy 259.34382 -24.157651)
			(xy 259.316524 -24.109016) (xy 259.296601 -24.056925) (xy 259.284475 -24.002488) (xy 259.280404 -23.946866)
			(xy 259.04055 -23.946866) (xy 259.040884 -23.965154) (xy 259.040375 -23.99304) (xy 259.032255 -24.048216)
			(xy 259.016187 -24.101623) (xy 258.992515 -24.15212) (xy 258.961742 -24.198633) (xy 258.924525 -24.24017)
			(xy 258.881657 -24.275845) (xy 258.834051 -24.304899) (xy 258.782722 -24.326711) (xy 258.728765 -24.340817)
			(xy 258.673328 -24.346917) (xy 258.617594 -24.34488) (xy 258.562751 -24.33475) (xy 258.509967 -24.316743)
			(xy 258.460367 -24.291242) (xy 258.415009 -24.258791) (xy 258.37486 -24.220082) (xy 258.340774 -24.175939)
			(xy 258.313478 -24.127304) (xy 258.293555 -24.075213) (xy 258.281429 -24.020776) (xy 258.277358 -23.965154)
			(xy 248.737829 -23.965154) (xy 248.735897 -23.965659) (xy 248.68046 -23.971759) (xy 248.624726 -23.969722)
			(xy 248.569883 -23.959592) (xy 248.517099 -23.941585) (xy 248.467499 -23.916084) (xy 248.422141 -23.883633)
			(xy 248.381992 -23.844924) (xy 248.347906 -23.800781) (xy 248.32061 -23.752146) (xy 248.300687 -23.700055)
			(xy 248.288561 -23.645618) (xy 248.28449 -23.589996) (xy 222.575686 -23.589996) (xy 222.624189 -23.595333)
			(xy 222.678146 -23.609439) (xy 222.729475 -23.631251) (xy 222.777081 -23.660305) (xy 222.819949 -23.69598)
			(xy 222.857166 -23.737517) (xy 222.887939 -23.78403) (xy 222.911611 -23.834527) (xy 222.927679 -23.887934)
			(xy 222.935799 -23.94311) (xy 222.936308 -23.970996) (xy 222.935799 -23.998882) (xy 222.927679 -24.054058)
			(xy 222.911611 -24.107465) (xy 222.887939 -24.157962) (xy 222.887786 -24.158194) (xy 239.650776 -24.158194)
			(xy 239.654847 -24.102572) (xy 239.666973 -24.048135) (xy 239.686896 -23.996044) (xy 239.714192 -23.947409)
			(xy 239.748278 -23.903266) (xy 239.788427 -23.864557) (xy 239.833785 -23.832106) (xy 239.883385 -23.806605)
			(xy 239.936169 -23.788598) (xy 239.991012 -23.778468) (xy 240.046746 -23.776431) (xy 240.102183 -23.782531)
			(xy 240.15614 -23.796637) (xy 240.207469 -23.818449) (xy 240.255075 -23.847503) (xy 240.297943 -23.883178)
			(xy 240.33516 -23.924715) (xy 240.365933 -23.971228) (xy 240.389605 -24.021725) (xy 240.405673 -24.075132)
			(xy 240.413793 -24.130308) (xy 240.414302 -24.158194) (xy 240.413793 -24.18608) (xy 240.413224 -24.189944)
			(xy 243.498876 -24.189944) (xy 243.502947 -24.134322) (xy 243.515073 -24.079885) (xy 243.534996 -24.027794)
			(xy 243.562292 -23.979159) (xy 243.596378 -23.935016) (xy 243.636527 -23.896307) (xy 243.681885 -23.863856)
			(xy 243.731485 -23.838355) (xy 243.784269 -23.820348) (xy 243.839112 -23.810218) (xy 243.894846 -23.808181)
			(xy 243.950283 -23.814281) (xy 244.00424 -23.828387) (xy 244.055569 -23.850199) (xy 244.103175 -23.879253)
			(xy 244.146043 -23.914928) (xy 244.18326 -23.956465) (xy 244.214033 -24.002978) (xy 244.237705 -24.053475)
			(xy 244.253773 -24.106882) (xy 244.261893 -24.162058) (xy 244.262402 -24.189944) (xy 246.021858 -24.189944)
			(xy 246.025929 -24.134322) (xy 246.038055 -24.079885) (xy 246.057978 -24.027794) (xy 246.085274 -23.979159)
			(xy 246.11936 -23.935016) (xy 246.159509 -23.896307) (xy 246.204867 -23.863856) (xy 246.254467 -23.838355)
			(xy 246.307251 -23.820348) (xy 246.362094 -23.810218) (xy 246.417828 -23.808181) (xy 246.473265 -23.814281)
			(xy 246.527222 -23.828387) (xy 246.578551 -23.850199) (xy 246.626157 -23.879253) (xy 246.669025 -23.914928)
			(xy 246.706242 -23.956465) (xy 246.737015 -24.002978) (xy 246.760687 -24.053475) (xy 246.776755 -24.106882)
			(xy 246.784875 -24.162058) (xy 246.785384 -24.189944) (xy 246.784875 -24.21783) (xy 246.776755 -24.273006)
			(xy 246.760687 -24.326413) (xy 246.737015 -24.37691) (xy 246.706242 -24.423423) (xy 246.669025 -24.46496)
			(xy 246.626157 -24.500635) (xy 246.578551 -24.529689) (xy 246.527222 -24.551501) (xy 246.473265 -24.565607)
			(xy 246.417828 -24.571707) (xy 246.362094 -24.56967) (xy 246.307251 -24.55954) (xy 246.254467 -24.541533)
			(xy 246.204867 -24.516032) (xy 246.159509 -24.483581) (xy 246.11936 -24.444872) (xy 246.085274 -24.400729)
			(xy 246.057978 -24.352094) (xy 246.038055 -24.300003) (xy 246.025929 -24.245566) (xy 246.021858 -24.189944)
			(xy 244.262402 -24.189944) (xy 244.261893 -24.21783) (xy 244.253773 -24.273006) (xy 244.237705 -24.326413)
			(xy 244.214033 -24.37691) (xy 244.18326 -24.423423) (xy 244.146043 -24.46496) (xy 244.103175 -24.500635)
			(xy 244.055569 -24.529689) (xy 244.00424 -24.551501) (xy 243.950283 -24.565607) (xy 243.894846 -24.571707)
			(xy 243.839112 -24.56967) (xy 243.784269 -24.55954) (xy 243.731485 -24.541533) (xy 243.681885 -24.516032)
			(xy 243.636527 -24.483581) (xy 243.596378 -24.444872) (xy 243.562292 -24.400729) (xy 243.534996 -24.352094)
			(xy 243.515073 -24.300003) (xy 243.502947 -24.245566) (xy 243.498876 -24.189944) (xy 240.413224 -24.189944)
			(xy 240.405673 -24.241256) (xy 240.389605 -24.294663) (xy 240.365933 -24.34516) (xy 240.33516 -24.391673)
			(xy 240.297943 -24.43321) (xy 240.255075 -24.468885) (xy 240.207469 -24.497939) (xy 240.15614 -24.519751)
			(xy 240.102183 -24.533857) (xy 240.046746 -24.539957) (xy 239.991012 -24.53792) (xy 239.936169 -24.52779)
			(xy 239.883385 -24.509783) (xy 239.833785 -24.484282) (xy 239.788427 -24.451831) (xy 239.748278 -24.413122)
			(xy 239.714192 -24.368979) (xy 239.686896 -24.320344) (xy 239.666973 -24.268253) (xy 239.654847 -24.213816)
			(xy 239.650776 -24.158194) (xy 222.887786 -24.158194) (xy 222.857166 -24.204475) (xy 222.819949 -24.246012)
			(xy 222.777081 -24.281687) (xy 222.729475 -24.310741) (xy 222.678146 -24.332553) (xy 222.624189 -24.346659)
			(xy 222.568752 -24.352759) (xy 222.513018 -24.350722) (xy 222.458175 -24.340592) (xy 222.405391 -24.322585)
			(xy 222.355791 -24.297084) (xy 222.310433 -24.264633) (xy 222.270284 -24.225924) (xy 222.236198 -24.181781)
			(xy 222.208902 -24.133146) (xy 222.188979 -24.081055) (xy 222.176853 -24.026618) (xy 222.172782 -23.970996)
			(xy 221.94349 -23.970996) (xy 221.943421 -23.974752) (xy 221.935301 -24.029928) (xy 221.919233 -24.083335)
			(xy 221.895561 -24.133832) (xy 221.864788 -24.180345) (xy 221.827571 -24.221882) (xy 221.784703 -24.257557)
			(xy 221.737097 -24.286611) (xy 221.685768 -24.308423) (xy 221.631811 -24.322529) (xy 221.576374 -24.328629)
			(xy 221.52064 -24.326592) (xy 221.465797 -24.316462) (xy 221.413013 -24.298455) (xy 221.363413 -24.272954)
			(xy 221.318055 -24.240503) (xy 221.277906 -24.201794) (xy 221.24382 -24.157651) (xy 221.216524 -24.109016)
			(xy 221.196601 -24.056925) (xy 221.184475 -24.002488) (xy 221.180404 -23.946866) (xy 220.94055 -23.946866)
			(xy 220.940884 -23.965154) (xy 220.940375 -23.99304) (xy 220.932255 -24.048216) (xy 220.916187 -24.101623)
			(xy 220.892515 -24.15212) (xy 220.861742 -24.198633) (xy 220.824525 -24.24017) (xy 220.781657 -24.275845)
			(xy 220.734051 -24.304899) (xy 220.682722 -24.326711) (xy 220.628765 -24.340817) (xy 220.573328 -24.346917)
			(xy 220.517594 -24.34488) (xy 220.462751 -24.33475) (xy 220.409967 -24.316743) (xy 220.360367 -24.291242)
			(xy 220.315009 -24.258791) (xy 220.27486 -24.220082) (xy 220.240774 -24.175939) (xy 220.213478 -24.127304)
			(xy 220.193555 -24.075213) (xy 220.181429 -24.020776) (xy 220.177358 -23.965154) (xy 210.637829 -23.965154)
			(xy 210.635897 -23.965659) (xy 210.58046 -23.971759) (xy 210.524726 -23.969722) (xy 210.469883 -23.959592)
			(xy 210.417099 -23.941585) (xy 210.367499 -23.916084) (xy 210.322141 -23.883633) (xy 210.281992 -23.844924)
			(xy 210.247906 -23.800781) (xy 210.22061 -23.752146) (xy 210.200687 -23.700055) (xy 210.188561 -23.645618)
			(xy 210.18449 -23.589996) (xy 196.575738 -23.589996) (xy 196.624241 -23.595333) (xy 196.678198 -23.609439)
			(xy 196.729527 -23.631251) (xy 196.777133 -23.660305) (xy 196.820001 -23.69598) (xy 196.857218 -23.737517)
			(xy 196.887991 -23.78403) (xy 196.911663 -23.834527) (xy 196.927731 -23.887934) (xy 196.935851 -23.94311)
			(xy 196.93636 -23.970996) (xy 196.935851 -23.998882) (xy 196.927731 -24.054058) (xy 196.911663 -24.107465)
			(xy 196.887991 -24.157962) (xy 196.887838 -24.158194) (xy 201.550776 -24.158194) (xy 201.554847 -24.102572)
			(xy 201.566973 -24.048135) (xy 201.586896 -23.996044) (xy 201.614192 -23.947409) (xy 201.648278 -23.903266)
			(xy 201.688427 -23.864557) (xy 201.733785 -23.832106) (xy 201.783385 -23.806605) (xy 201.836169 -23.788598)
			(xy 201.891012 -23.778468) (xy 201.946746 -23.776431) (xy 202.002183 -23.782531) (xy 202.05614 -23.796637)
			(xy 202.107469 -23.818449) (xy 202.155075 -23.847503) (xy 202.197943 -23.883178) (xy 202.23516 -23.924715)
			(xy 202.265933 -23.971228) (xy 202.289605 -24.021725) (xy 202.305673 -24.075132) (xy 202.313793 -24.130308)
			(xy 202.314302 -24.158194) (xy 202.313793 -24.18608) (xy 202.313224 -24.189944) (xy 205.398876 -24.189944)
			(xy 205.402947 -24.134322) (xy 205.415073 -24.079885) (xy 205.434996 -24.027794) (xy 205.462292 -23.979159)
			(xy 205.496378 -23.935016) (xy 205.536527 -23.896307) (xy 205.581885 -23.863856) (xy 205.631485 -23.838355)
			(xy 205.684269 -23.820348) (xy 205.739112 -23.810218) (xy 205.794846 -23.808181) (xy 205.850283 -23.814281)
			(xy 205.90424 -23.828387) (xy 205.955569 -23.850199) (xy 206.003175 -23.879253) (xy 206.046043 -23.914928)
			(xy 206.08326 -23.956465) (xy 206.114033 -24.002978) (xy 206.137705 -24.053475) (xy 206.153773 -24.106882)
			(xy 206.161893 -24.162058) (xy 206.162402 -24.189944) (xy 207.921858 -24.189944) (xy 207.925929 -24.134322)
			(xy 207.938055 -24.079885) (xy 207.957978 -24.027794) (xy 207.985274 -23.979159) (xy 208.01936 -23.935016)
			(xy 208.059509 -23.896307) (xy 208.104867 -23.863856) (xy 208.154467 -23.838355) (xy 208.207251 -23.820348)
			(xy 208.262094 -23.810218) (xy 208.317828 -23.808181) (xy 208.373265 -23.814281) (xy 208.427222 -23.828387)
			(xy 208.478551 -23.850199) (xy 208.526157 -23.879253) (xy 208.569025 -23.914928) (xy 208.606242 -23.956465)
			(xy 208.637015 -24.002978) (xy 208.660687 -24.053475) (xy 208.676755 -24.106882) (xy 208.684875 -24.162058)
			(xy 208.685384 -24.189944) (xy 208.684875 -24.21783) (xy 208.676755 -24.273006) (xy 208.660687 -24.326413)
			(xy 208.637015 -24.37691) (xy 208.606242 -24.423423) (xy 208.569025 -24.46496) (xy 208.526157 -24.500635)
			(xy 208.478551 -24.529689) (xy 208.427222 -24.551501) (xy 208.373265 -24.565607) (xy 208.317828 -24.571707)
			(xy 208.262094 -24.56967) (xy 208.207251 -24.55954) (xy 208.154467 -24.541533) (xy 208.104867 -24.516032)
			(xy 208.059509 -24.483581) (xy 208.01936 -24.444872) (xy 207.985274 -24.400729) (xy 207.957978 -24.352094)
			(xy 207.938055 -24.300003) (xy 207.925929 -24.245566) (xy 207.921858 -24.189944) (xy 206.162402 -24.189944)
			(xy 206.161893 -24.21783) (xy 206.153773 -24.273006) (xy 206.137705 -24.326413) (xy 206.114033 -24.37691)
			(xy 206.08326 -24.423423) (xy 206.046043 -24.46496) (xy 206.003175 -24.500635) (xy 205.955569 -24.529689)
			(xy 205.90424 -24.551501) (xy 205.850283 -24.565607) (xy 205.794846 -24.571707) (xy 205.739112 -24.56967)
			(xy 205.684269 -24.55954) (xy 205.631485 -24.541533) (xy 205.581885 -24.516032) (xy 205.536527 -24.483581)
			(xy 205.496378 -24.444872) (xy 205.462292 -24.400729) (xy 205.434996 -24.352094) (xy 205.415073 -24.300003)
			(xy 205.402947 -24.245566) (xy 205.398876 -24.189944) (xy 202.313224 -24.189944) (xy 202.305673 -24.241256)
			(xy 202.289605 -24.294663) (xy 202.265933 -24.34516) (xy 202.23516 -24.391673) (xy 202.197943 -24.43321)
			(xy 202.155075 -24.468885) (xy 202.107469 -24.497939) (xy 202.05614 -24.519751) (xy 202.002183 -24.533857)
			(xy 201.946746 -24.539957) (xy 201.891012 -24.53792) (xy 201.836169 -24.52779) (xy 201.783385 -24.509783)
			(xy 201.733785 -24.484282) (xy 201.688427 -24.451831) (xy 201.648278 -24.413122) (xy 201.614192 -24.368979)
			(xy 201.586896 -24.320344) (xy 201.566973 -24.268253) (xy 201.554847 -24.213816) (xy 201.550776 -24.158194)
			(xy 196.887838 -24.158194) (xy 196.857218 -24.204475) (xy 196.820001 -24.246012) (xy 196.777133 -24.281687)
			(xy 196.729527 -24.310741) (xy 196.678198 -24.332553) (xy 196.624241 -24.346659) (xy 196.568804 -24.352759)
			(xy 196.51307 -24.350722) (xy 196.458227 -24.340592) (xy 196.405443 -24.322585) (xy 196.355843 -24.297084)
			(xy 196.310485 -24.264633) (xy 196.270336 -24.225924) (xy 196.23625 -24.181781) (xy 196.208954 -24.133146)
			(xy 196.189031 -24.081055) (xy 196.176905 -24.026618) (xy 196.172834 -23.970996) (xy 195.943542 -23.970996)
			(xy 195.943473 -23.974752) (xy 195.935353 -24.029928) (xy 195.919285 -24.083335) (xy 195.895613 -24.133832)
			(xy 195.86484 -24.180345) (xy 195.827623 -24.221882) (xy 195.784755 -24.257557) (xy 195.737149 -24.286611)
			(xy 195.68582 -24.308423) (xy 195.631863 -24.322529) (xy 195.576426 -24.328629) (xy 195.520692 -24.326592)
			(xy 195.465849 -24.316462) (xy 195.413065 -24.298455) (xy 195.363465 -24.272954) (xy 195.318107 -24.240503)
			(xy 195.277958 -24.201794) (xy 195.243872 -24.157651) (xy 195.216576 -24.109016) (xy 195.196653 -24.056925)
			(xy 195.184527 -24.002488) (xy 195.180456 -23.946866) (xy 194.940602 -23.946866) (xy 194.940936 -23.965154)
			(xy 194.940427 -23.99304) (xy 194.932307 -24.048216) (xy 194.916239 -24.101623) (xy 194.892567 -24.15212)
			(xy 194.861794 -24.198633) (xy 194.824577 -24.24017) (xy 194.781709 -24.275845) (xy 194.734103 -24.304899)
			(xy 194.682774 -24.326711) (xy 194.628817 -24.340817) (xy 194.57338 -24.346917) (xy 194.517646 -24.34488)
			(xy 194.462803 -24.33475) (xy 194.410019 -24.316743) (xy 194.360419 -24.291242) (xy 194.315061 -24.258791)
			(xy 194.274912 -24.220082) (xy 194.240826 -24.175939) (xy 194.21353 -24.127304) (xy 194.193607 -24.075213)
			(xy 194.181481 -24.020776) (xy 194.17741 -23.965154) (xy 184.637881 -23.965154) (xy 184.635949 -23.965659)
			(xy 184.580512 -23.971759) (xy 184.524778 -23.969722) (xy 184.469935 -23.959592) (xy 184.417151 -23.941585)
			(xy 184.367551 -23.916084) (xy 184.322193 -23.883633) (xy 184.282044 -23.844924) (xy 184.247958 -23.800781)
			(xy 184.220662 -23.752146) (xy 184.200739 -23.700055) (xy 184.188613 -23.645618) (xy 184.184542 -23.589996)
			(xy 170.57579 -23.589996) (xy 170.624293 -23.595333) (xy 170.67825 -23.609439) (xy 170.729579 -23.631251)
			(xy 170.777185 -23.660305) (xy 170.820053 -23.69598) (xy 170.85727 -23.737517) (xy 170.888043 -23.78403)
			(xy 170.911715 -23.834527) (xy 170.927783 -23.887934) (xy 170.935903 -23.94311) (xy 170.936412 -23.970996)
			(xy 170.935903 -23.998882) (xy 170.927783 -24.054058) (xy 170.911715 -24.107465) (xy 170.888043 -24.157962)
			(xy 170.88789 -24.158194) (xy 175.550828 -24.158194) (xy 175.554899 -24.102572) (xy 175.567025 -24.048135)
			(xy 175.586948 -23.996044) (xy 175.614244 -23.947409) (xy 175.64833 -23.903266) (xy 175.688479 -23.864557)
			(xy 175.733837 -23.832106) (xy 175.783437 -23.806605) (xy 175.836221 -23.788598) (xy 175.891064 -23.778468)
			(xy 175.946798 -23.776431) (xy 176.002235 -23.782531) (xy 176.056192 -23.796637) (xy 176.107521 -23.818449)
			(xy 176.155127 -23.847503) (xy 176.197995 -23.883178) (xy 176.235212 -23.924715) (xy 176.265985 -23.971228)
			(xy 176.289657 -24.021725) (xy 176.305725 -24.075132) (xy 176.313845 -24.130308) (xy 176.314354 -24.158194)
			(xy 176.313845 -24.18608) (xy 176.313276 -24.189944) (xy 179.398928 -24.189944) (xy 179.402999 -24.134322)
			(xy 179.415125 -24.079885) (xy 179.435048 -24.027794) (xy 179.462344 -23.979159) (xy 179.49643 -23.935016)
			(xy 179.536579 -23.896307) (xy 179.581937 -23.863856) (xy 179.631537 -23.838355) (xy 179.684321 -23.820348)
			(xy 179.739164 -23.810218) (xy 179.794898 -23.808181) (xy 179.850335 -23.814281) (xy 179.904292 -23.828387)
			(xy 179.955621 -23.850199) (xy 180.003227 -23.879253) (xy 180.046095 -23.914928) (xy 180.083312 -23.956465)
			(xy 180.114085 -24.002978) (xy 180.137757 -24.053475) (xy 180.153825 -24.106882) (xy 180.161945 -24.162058)
			(xy 180.162454 -24.189944) (xy 181.92191 -24.189944) (xy 181.925981 -24.134322) (xy 181.938107 -24.079885)
			(xy 181.95803 -24.027794) (xy 181.985326 -23.979159) (xy 182.019412 -23.935016) (xy 182.059561 -23.896307)
			(xy 182.104919 -23.863856) (xy 182.154519 -23.838355) (xy 182.207303 -23.820348) (xy 182.262146 -23.810218)
			(xy 182.31788 -23.808181) (xy 182.373317 -23.814281) (xy 182.427274 -23.828387) (xy 182.478603 -23.850199)
			(xy 182.526209 -23.879253) (xy 182.569077 -23.914928) (xy 182.606294 -23.956465) (xy 182.637067 -24.002978)
			(xy 182.660739 -24.053475) (xy 182.676807 -24.106882) (xy 182.684927 -24.162058) (xy 182.685436 -24.189944)
			(xy 182.684927 -24.21783) (xy 182.676807 -24.273006) (xy 182.660739 -24.326413) (xy 182.637067 -24.37691)
			(xy 182.606294 -24.423423) (xy 182.569077 -24.46496) (xy 182.526209 -24.500635) (xy 182.478603 -24.529689)
			(xy 182.427274 -24.551501) (xy 182.373317 -24.565607) (xy 182.31788 -24.571707) (xy 182.262146 -24.56967)
			(xy 182.207303 -24.55954) (xy 182.154519 -24.541533) (xy 182.104919 -24.516032) (xy 182.059561 -24.483581)
			(xy 182.019412 -24.444872) (xy 181.985326 -24.400729) (xy 181.95803 -24.352094) (xy 181.938107 -24.300003)
			(xy 181.925981 -24.245566) (xy 181.92191 -24.189944) (xy 180.162454 -24.189944) (xy 180.161945 -24.21783)
			(xy 180.153825 -24.273006) (xy 180.137757 -24.326413) (xy 180.114085 -24.37691) (xy 180.083312 -24.423423)
			(xy 180.046095 -24.46496) (xy 180.003227 -24.500635) (xy 179.955621 -24.529689) (xy 179.904292 -24.551501)
			(xy 179.850335 -24.565607) (xy 179.794898 -24.571707) (xy 179.739164 -24.56967) (xy 179.684321 -24.55954)
			(xy 179.631537 -24.541533) (xy 179.581937 -24.516032) (xy 179.536579 -24.483581) (xy 179.49643 -24.444872)
			(xy 179.462344 -24.400729) (xy 179.435048 -24.352094) (xy 179.415125 -24.300003) (xy 179.402999 -24.245566)
			(xy 179.398928 -24.189944) (xy 176.313276 -24.189944) (xy 176.305725 -24.241256) (xy 176.289657 -24.294663)
			(xy 176.265985 -24.34516) (xy 176.235212 -24.391673) (xy 176.197995 -24.43321) (xy 176.155127 -24.468885)
			(xy 176.107521 -24.497939) (xy 176.056192 -24.519751) (xy 176.002235 -24.533857) (xy 175.946798 -24.539957)
			(xy 175.891064 -24.53792) (xy 175.836221 -24.52779) (xy 175.783437 -24.509783) (xy 175.733837 -24.484282)
			(xy 175.688479 -24.451831) (xy 175.64833 -24.413122) (xy 175.614244 -24.368979) (xy 175.586948 -24.320344)
			(xy 175.567025 -24.268253) (xy 175.554899 -24.213816) (xy 175.550828 -24.158194) (xy 170.88789 -24.158194)
			(xy 170.85727 -24.204475) (xy 170.820053 -24.246012) (xy 170.777185 -24.281687) (xy 170.729579 -24.310741)
			(xy 170.67825 -24.332553) (xy 170.624293 -24.346659) (xy 170.568856 -24.352759) (xy 170.513122 -24.350722)
			(xy 170.458279 -24.340592) (xy 170.405495 -24.322585) (xy 170.355895 -24.297084) (xy 170.310537 -24.264633)
			(xy 170.270388 -24.225924) (xy 170.236302 -24.181781) (xy 170.209006 -24.133146) (xy 170.189083 -24.081055)
			(xy 170.176957 -24.026618) (xy 170.172886 -23.970996) (xy 169.943594 -23.970996) (xy 169.943525 -23.974752)
			(xy 169.935405 -24.029928) (xy 169.919337 -24.083335) (xy 169.895665 -24.133832) (xy 169.864892 -24.180345)
			(xy 169.827675 -24.221882) (xy 169.784807 -24.257557) (xy 169.737201 -24.286611) (xy 169.685872 -24.308423)
			(xy 169.631915 -24.322529) (xy 169.576478 -24.328629) (xy 169.520744 -24.326592) (xy 169.465901 -24.316462)
			(xy 169.413117 -24.298455) (xy 169.363517 -24.272954) (xy 169.318159 -24.240503) (xy 169.27801 -24.201794)
			(xy 169.243924 -24.157651) (xy 169.216628 -24.109016) (xy 169.196705 -24.056925) (xy 169.184579 -24.002488)
			(xy 169.180508 -23.946866) (xy 168.940654 -23.946866) (xy 168.940988 -23.965154) (xy 168.940479 -23.99304)
			(xy 168.932359 -24.048216) (xy 168.916291 -24.101623) (xy 168.892619 -24.15212) (xy 168.861846 -24.198633)
			(xy 168.824629 -24.24017) (xy 168.781761 -24.275845) (xy 168.734155 -24.304899) (xy 168.682826 -24.326711)
			(xy 168.628869 -24.340817) (xy 168.573432 -24.346917) (xy 168.517698 -24.34488) (xy 168.462855 -24.33475)
			(xy 168.410071 -24.316743) (xy 168.360471 -24.291242) (xy 168.315113 -24.258791) (xy 168.274964 -24.220082)
			(xy 168.240878 -24.175939) (xy 168.213582 -24.127304) (xy 168.193659 -24.075213) (xy 168.181533 -24.020776)
			(xy 168.177462 -23.965154) (xy 158.637933 -23.965154) (xy 158.636001 -23.965659) (xy 158.580564 -23.971759)
			(xy 158.52483 -23.969722) (xy 158.469987 -23.959592) (xy 158.417203 -23.941585) (xy 158.367603 -23.916084)
			(xy 158.322245 -23.883633) (xy 158.282096 -23.844924) (xy 158.24801 -23.800781) (xy 158.220714 -23.752146)
			(xy 158.200791 -23.700055) (xy 158.188665 -23.645618) (xy 158.184594 -23.589996) (xy 144.575842 -23.589996)
			(xy 144.624345 -23.595333) (xy 144.678302 -23.609439) (xy 144.729631 -23.631251) (xy 144.777237 -23.660305)
			(xy 144.820105 -23.69598) (xy 144.857322 -23.737517) (xy 144.888095 -23.78403) (xy 144.911767 -23.834527)
			(xy 144.927835 -23.887934) (xy 144.935955 -23.94311) (xy 144.936464 -23.970996) (xy 144.935955 -23.998882)
			(xy 144.927835 -24.054058) (xy 144.911767 -24.107465) (xy 144.888095 -24.157962) (xy 144.887942 -24.158194)
			(xy 149.55088 -24.158194) (xy 149.554951 -24.102572) (xy 149.567077 -24.048135) (xy 149.587 -23.996044)
			(xy 149.614296 -23.947409) (xy 149.648382 -23.903266) (xy 149.688531 -23.864557) (xy 149.733889 -23.832106)
			(xy 149.783489 -23.806605) (xy 149.836273 -23.788598) (xy 149.891116 -23.778468) (xy 149.94685 -23.776431)
			(xy 150.002287 -23.782531) (xy 150.056244 -23.796637) (xy 150.107573 -23.818449) (xy 150.155179 -23.847503)
			(xy 150.198047 -23.883178) (xy 150.235264 -23.924715) (xy 150.266037 -23.971228) (xy 150.289709 -24.021725)
			(xy 150.305777 -24.075132) (xy 150.313897 -24.130308) (xy 150.314406 -24.158194) (xy 150.313897 -24.18608)
			(xy 150.313328 -24.189944) (xy 153.39898 -24.189944) (xy 153.403051 -24.134322) (xy 153.415177 -24.079885)
			(xy 153.4351 -24.027794) (xy 153.462396 -23.979159) (xy 153.496482 -23.935016) (xy 153.536631 -23.896307)
			(xy 153.581989 -23.863856) (xy 153.631589 -23.838355) (xy 153.684373 -23.820348) (xy 153.739216 -23.810218)
			(xy 153.79495 -23.808181) (xy 153.850387 -23.814281) (xy 153.904344 -23.828387) (xy 153.955673 -23.850199)
			(xy 154.003279 -23.879253) (xy 154.046147 -23.914928) (xy 154.083364 -23.956465) (xy 154.114137 -24.002978)
			(xy 154.137809 -24.053475) (xy 154.153877 -24.106882) (xy 154.161997 -24.162058) (xy 154.162506 -24.189944)
			(xy 155.921962 -24.189944) (xy 155.926033 -24.134322) (xy 155.938159 -24.079885) (xy 155.958082 -24.027794)
			(xy 155.985378 -23.979159) (xy 156.019464 -23.935016) (xy 156.059613 -23.896307) (xy 156.104971 -23.863856)
			(xy 156.154571 -23.838355) (xy 156.207355 -23.820348) (xy 156.262198 -23.810218) (xy 156.317932 -23.808181)
			(xy 156.373369 -23.814281) (xy 156.427326 -23.828387) (xy 156.478655 -23.850199) (xy 156.526261 -23.879253)
			(xy 156.569129 -23.914928) (xy 156.606346 -23.956465) (xy 156.637119 -24.002978) (xy 156.660791 -24.053475)
			(xy 156.676859 -24.106882) (xy 156.684979 -24.162058) (xy 156.685488 -24.189944) (xy 156.684979 -24.21783)
			(xy 156.676859 -24.273006) (xy 156.660791 -24.326413) (xy 156.637119 -24.37691) (xy 156.606346 -24.423423)
			(xy 156.569129 -24.46496) (xy 156.526261 -24.500635) (xy 156.478655 -24.529689) (xy 156.427326 -24.551501)
			(xy 156.373369 -24.565607) (xy 156.317932 -24.571707) (xy 156.262198 -24.56967) (xy 156.207355 -24.55954)
			(xy 156.154571 -24.541533) (xy 156.104971 -24.516032) (xy 156.059613 -24.483581) (xy 156.019464 -24.444872)
			(xy 155.985378 -24.400729) (xy 155.958082 -24.352094) (xy 155.938159 -24.300003) (xy 155.926033 -24.245566)
			(xy 155.921962 -24.189944) (xy 154.162506 -24.189944) (xy 154.161997 -24.21783) (xy 154.153877 -24.273006)
			(xy 154.137809 -24.326413) (xy 154.114137 -24.37691) (xy 154.083364 -24.423423) (xy 154.046147 -24.46496)
			(xy 154.003279 -24.500635) (xy 153.955673 -24.529689) (xy 153.904344 -24.551501) (xy 153.850387 -24.565607)
			(xy 153.79495 -24.571707) (xy 153.739216 -24.56967) (xy 153.684373 -24.55954) (xy 153.631589 -24.541533)
			(xy 153.581989 -24.516032) (xy 153.536631 -24.483581) (xy 153.496482 -24.444872) (xy 153.462396 -24.400729)
			(xy 153.4351 -24.352094) (xy 153.415177 -24.300003) (xy 153.403051 -24.245566) (xy 153.39898 -24.189944)
			(xy 150.313328 -24.189944) (xy 150.305777 -24.241256) (xy 150.289709 -24.294663) (xy 150.266037 -24.34516)
			(xy 150.235264 -24.391673) (xy 150.198047 -24.43321) (xy 150.155179 -24.468885) (xy 150.107573 -24.497939)
			(xy 150.056244 -24.519751) (xy 150.002287 -24.533857) (xy 149.94685 -24.539957) (xy 149.891116 -24.53792)
			(xy 149.836273 -24.52779) (xy 149.783489 -24.509783) (xy 149.733889 -24.484282) (xy 149.688531 -24.451831)
			(xy 149.648382 -24.413122) (xy 149.614296 -24.368979) (xy 149.587 -24.320344) (xy 149.567077 -24.268253)
			(xy 149.554951 -24.213816) (xy 149.55088 -24.158194) (xy 144.887942 -24.158194) (xy 144.857322 -24.204475)
			(xy 144.820105 -24.246012) (xy 144.777237 -24.281687) (xy 144.729631 -24.310741) (xy 144.678302 -24.332553)
			(xy 144.624345 -24.346659) (xy 144.568908 -24.352759) (xy 144.513174 -24.350722) (xy 144.458331 -24.340592)
			(xy 144.405547 -24.322585) (xy 144.355947 -24.297084) (xy 144.310589 -24.264633) (xy 144.27044 -24.225924)
			(xy 144.236354 -24.181781) (xy 144.209058 -24.133146) (xy 144.189135 -24.081055) (xy 144.177009 -24.026618)
			(xy 144.172938 -23.970996) (xy 143.943646 -23.970996) (xy 143.943577 -23.974752) (xy 143.935457 -24.029928)
			(xy 143.919389 -24.083335) (xy 143.895717 -24.133832) (xy 143.864944 -24.180345) (xy 143.827727 -24.221882)
			(xy 143.784859 -24.257557) (xy 143.737253 -24.286611) (xy 143.685924 -24.308423) (xy 143.631967 -24.322529)
			(xy 143.57653 -24.328629) (xy 143.520796 -24.326592) (xy 143.465953 -24.316462) (xy 143.413169 -24.298455)
			(xy 143.363569 -24.272954) (xy 143.318211 -24.240503) (xy 143.278062 -24.201794) (xy 143.243976 -24.157651)
			(xy 143.21668 -24.109016) (xy 143.196757 -24.056925) (xy 143.184631 -24.002488) (xy 143.18056 -23.946866)
			(xy 142.940706 -23.946866) (xy 142.94104 -23.965154) (xy 142.940531 -23.99304) (xy 142.932411 -24.048216)
			(xy 142.916343 -24.101623) (xy 142.892671 -24.15212) (xy 142.861898 -24.198633) (xy 142.824681 -24.24017)
			(xy 142.781813 -24.275845) (xy 142.734207 -24.304899) (xy 142.682878 -24.326711) (xy 142.628921 -24.340817)
			(xy 142.573484 -24.346917) (xy 142.51775 -24.34488) (xy 142.462907 -24.33475) (xy 142.410123 -24.316743)
			(xy 142.360523 -24.291242) (xy 142.315165 -24.258791) (xy 142.275016 -24.220082) (xy 142.24093 -24.175939)
			(xy 142.213634 -24.127304) (xy 142.193711 -24.075213) (xy 142.181585 -24.020776) (xy 142.177514 -23.965154)
			(xy 132.637985 -23.965154) (xy 132.636053 -23.965659) (xy 132.580616 -23.971759) (xy 132.524882 -23.969722)
			(xy 132.470039 -23.959592) (xy 132.417255 -23.941585) (xy 132.367655 -23.916084) (xy 132.322297 -23.883633)
			(xy 132.282148 -23.844924) (xy 132.248062 -23.800781) (xy 132.220766 -23.752146) (xy 132.200843 -23.700055)
			(xy 132.188717 -23.645618) (xy 132.184646 -23.589996) (xy 94.847918 -23.589996) (xy 94.847409 -23.617882)
			(xy 94.839289 -23.673058) (xy 94.823221 -23.726465) (xy 94.799549 -23.776962) (xy 94.768776 -23.823475)
			(xy 94.731559 -23.865012) (xy 94.688691 -23.900687) (xy 94.641085 -23.929741) (xy 94.589756 -23.951553)
			(xy 94.535799 -23.965659) (xy 94.480362 -23.971759) (xy 94.424628 -23.969722) (xy 94.369785 -23.959592)
			(xy 94.317001 -23.941585) (xy 94.267401 -23.916084) (xy 94.222043 -23.883633) (xy 94.181894 -23.844924)
			(xy 94.147808 -23.800781) (xy 94.120512 -23.752146) (xy 94.100589 -23.700055) (xy 94.088463 -23.645618)
			(xy 94.084392 -23.589996) (xy 80.47564 -23.589996) (xy 80.524143 -23.595333) (xy 80.5781 -23.609439)
			(xy 80.629429 -23.631251) (xy 80.677035 -23.660305) (xy 80.719903 -23.69598) (xy 80.75712 -23.737517)
			(xy 80.787893 -23.78403) (xy 80.811565 -23.834527) (xy 80.827633 -23.887934) (xy 80.835753 -23.94311)
			(xy 80.836262 -23.970996) (xy 80.835753 -23.998882) (xy 80.827633 -24.054058) (xy 80.811565 -24.107465)
			(xy 80.787893 -24.157962) (xy 80.78774 -24.158194) (xy 85.450678 -24.158194) (xy 85.454749 -24.102572)
			(xy 85.466875 -24.048135) (xy 85.486798 -23.996044) (xy 85.514094 -23.947409) (xy 85.54818 -23.903266)
			(xy 85.588329 -23.864557) (xy 85.633687 -23.832106) (xy 85.683287 -23.806605) (xy 85.736071 -23.788598)
			(xy 85.790914 -23.778468) (xy 85.846648 -23.776431) (xy 85.902085 -23.782531) (xy 85.956042 -23.796637)
			(xy 86.007371 -23.818449) (xy 86.054977 -23.847503) (xy 86.097845 -23.883178) (xy 86.135062 -23.924715)
			(xy 86.165835 -23.971228) (xy 86.189507 -24.021725) (xy 86.205575 -24.075132) (xy 86.213695 -24.130308)
			(xy 86.214204 -24.158194) (xy 86.213695 -24.18608) (xy 86.213126 -24.189944) (xy 89.298778 -24.189944)
			(xy 89.302849 -24.134322) (xy 89.314975 -24.079885) (xy 89.334898 -24.027794) (xy 89.362194 -23.979159)
			(xy 89.39628 -23.935016) (xy 89.436429 -23.896307) (xy 89.481787 -23.863856) (xy 89.531387 -23.838355)
			(xy 89.584171 -23.820348) (xy 89.639014 -23.810218) (xy 89.694748 -23.808181) (xy 89.750185 -23.814281)
			(xy 89.804142 -23.828387) (xy 89.855471 -23.850199) (xy 89.903077 -23.879253) (xy 89.945945 -23.914928)
			(xy 89.983162 -23.956465) (xy 90.013935 -24.002978) (xy 90.037607 -24.053475) (xy 90.053675 -24.106882)
			(xy 90.061795 -24.162058) (xy 90.062304 -24.189944) (xy 91.82176 -24.189944) (xy 91.825831 -24.134322)
			(xy 91.837957 -24.079885) (xy 91.85788 -24.027794) (xy 91.885176 -23.979159) (xy 91.919262 -23.935016)
			(xy 91.959411 -23.896307) (xy 92.004769 -23.863856) (xy 92.054369 -23.838355) (xy 92.107153 -23.820348)
			(xy 92.161996 -23.810218) (xy 92.21773 -23.808181) (xy 92.273167 -23.814281) (xy 92.327124 -23.828387)
			(xy 92.378453 -23.850199) (xy 92.426059 -23.879253) (xy 92.468927 -23.914928) (xy 92.506144 -23.956465)
			(xy 92.536917 -24.002978) (xy 92.560589 -24.053475) (xy 92.576657 -24.106882) (xy 92.584208 -24.158194)
			(xy 123.550932 -24.158194) (xy 123.555003 -24.102572) (xy 123.567129 -24.048135) (xy 123.587052 -23.996044)
			(xy 123.614348 -23.947409) (xy 123.648434 -23.903266) (xy 123.688583 -23.864557) (xy 123.733941 -23.832106)
			(xy 123.783541 -23.806605) (xy 123.836325 -23.788598) (xy 123.891168 -23.778468) (xy 123.946902 -23.776431)
			(xy 124.002339 -23.782531) (xy 124.056296 -23.796637) (xy 124.107625 -23.818449) (xy 124.155231 -23.847503)
			(xy 124.198099 -23.883178) (xy 124.235316 -23.924715) (xy 124.266089 -23.971228) (xy 124.289761 -24.021725)
			(xy 124.305829 -24.075132) (xy 124.313949 -24.130308) (xy 124.314458 -24.158194) (xy 124.313949 -24.18608)
			(xy 124.31338 -24.189944) (xy 127.399032 -24.189944) (xy 127.403103 -24.134322) (xy 127.415229 -24.079885)
			(xy 127.435152 -24.027794) (xy 127.462448 -23.979159) (xy 127.496534 -23.935016) (xy 127.536683 -23.896307)
			(xy 127.582041 -23.863856) (xy 127.631641 -23.838355) (xy 127.684425 -23.820348) (xy 127.739268 -23.810218)
			(xy 127.795002 -23.808181) (xy 127.850439 -23.814281) (xy 127.904396 -23.828387) (xy 127.955725 -23.850199)
			(xy 128.003331 -23.879253) (xy 128.046199 -23.914928) (xy 128.083416 -23.956465) (xy 128.114189 -24.002978)
			(xy 128.137861 -24.053475) (xy 128.153929 -24.106882) (xy 128.162049 -24.162058) (xy 128.162558 -24.189944)
			(xy 129.922014 -24.189944) (xy 129.926085 -24.134322) (xy 129.938211 -24.079885) (xy 129.958134 -24.027794)
			(xy 129.98543 -23.979159) (xy 130.019516 -23.935016) (xy 130.059665 -23.896307) (xy 130.105023 -23.863856)
			(xy 130.154623 -23.838355) (xy 130.207407 -23.820348) (xy 130.26225 -23.810218) (xy 130.317984 -23.808181)
			(xy 130.373421 -23.814281) (xy 130.427378 -23.828387) (xy 130.478707 -23.850199) (xy 130.526313 -23.879253)
			(xy 130.569181 -23.914928) (xy 130.606398 -23.956465) (xy 130.637171 -24.002978) (xy 130.660843 -24.053475)
			(xy 130.676911 -24.106882) (xy 130.685031 -24.162058) (xy 130.68554 -24.189944) (xy 130.685031 -24.21783)
			(xy 130.676911 -24.273006) (xy 130.660843 -24.326413) (xy 130.637171 -24.37691) (xy 130.606398 -24.423423)
			(xy 130.569181 -24.46496) (xy 130.526313 -24.500635) (xy 130.478707 -24.529689) (xy 130.427378 -24.551501)
			(xy 130.373421 -24.565607) (xy 130.317984 -24.571707) (xy 130.26225 -24.56967) (xy 130.207407 -24.55954)
			(xy 130.154623 -24.541533) (xy 130.105023 -24.516032) (xy 130.059665 -24.483581) (xy 130.019516 -24.444872)
			(xy 129.98543 -24.400729) (xy 129.958134 -24.352094) (xy 129.938211 -24.300003) (xy 129.926085 -24.245566)
			(xy 129.922014 -24.189944) (xy 128.162558 -24.189944) (xy 128.162049 -24.21783) (xy 128.153929 -24.273006)
			(xy 128.137861 -24.326413) (xy 128.114189 -24.37691) (xy 128.083416 -24.423423) (xy 128.046199 -24.46496)
			(xy 128.003331 -24.500635) (xy 127.955725 -24.529689) (xy 127.904396 -24.551501) (xy 127.850439 -24.565607)
			(xy 127.795002 -24.571707) (xy 127.739268 -24.56967) (xy 127.684425 -24.55954) (xy 127.631641 -24.541533)
			(xy 127.582041 -24.516032) (xy 127.536683 -24.483581) (xy 127.496534 -24.444872) (xy 127.462448 -24.400729)
			(xy 127.435152 -24.352094) (xy 127.415229 -24.300003) (xy 127.403103 -24.245566) (xy 127.399032 -24.189944)
			(xy 124.31338 -24.189944) (xy 124.305829 -24.241256) (xy 124.289761 -24.294663) (xy 124.266089 -24.34516)
			(xy 124.235316 -24.391673) (xy 124.198099 -24.43321) (xy 124.155231 -24.468885) (xy 124.107625 -24.497939)
			(xy 124.056296 -24.519751) (xy 124.002339 -24.533857) (xy 123.946902 -24.539957) (xy 123.891168 -24.53792)
			(xy 123.836325 -24.52779) (xy 123.783541 -24.509783) (xy 123.733941 -24.484282) (xy 123.688583 -24.451831)
			(xy 123.648434 -24.413122) (xy 123.614348 -24.368979) (xy 123.587052 -24.320344) (xy 123.567129 -24.268253)
			(xy 123.555003 -24.213816) (xy 123.550932 -24.158194) (xy 92.584208 -24.158194) (xy 92.584777 -24.162058)
			(xy 92.585286 -24.189944) (xy 92.584777 -24.21783) (xy 92.576657 -24.273006) (xy 92.560589 -24.326413)
			(xy 92.536917 -24.37691) (xy 92.506144 -24.423423) (xy 92.468927 -24.46496) (xy 92.426059 -24.500635)
			(xy 92.378453 -24.529689) (xy 92.327124 -24.551501) (xy 92.273167 -24.565607) (xy 92.21773 -24.571707)
			(xy 92.161996 -24.56967) (xy 92.107153 -24.55954) (xy 92.054369 -24.541533) (xy 92.004769 -24.516032)
			(xy 91.959411 -24.483581) (xy 91.919262 -24.444872) (xy 91.885176 -24.400729) (xy 91.85788 -24.352094)
			(xy 91.837957 -24.300003) (xy 91.825831 -24.245566) (xy 91.82176 -24.189944) (xy 90.062304 -24.189944)
			(xy 90.061795 -24.21783) (xy 90.053675 -24.273006) (xy 90.037607 -24.326413) (xy 90.013935 -24.37691)
			(xy 89.983162 -24.423423) (xy 89.945945 -24.46496) (xy 89.903077 -24.500635) (xy 89.855471 -24.529689)
			(xy 89.804142 -24.551501) (xy 89.750185 -24.565607) (xy 89.694748 -24.571707) (xy 89.639014 -24.56967)
			(xy 89.584171 -24.55954) (xy 89.531387 -24.541533) (xy 89.481787 -24.516032) (xy 89.436429 -24.483581)
			(xy 89.39628 -24.444872) (xy 89.362194 -24.400729) (xy 89.334898 -24.352094) (xy 89.314975 -24.300003)
			(xy 89.302849 -24.245566) (xy 89.298778 -24.189944) (xy 86.213126 -24.189944) (xy 86.205575 -24.241256)
			(xy 86.189507 -24.294663) (xy 86.165835 -24.34516) (xy 86.135062 -24.391673) (xy 86.097845 -24.43321)
			(xy 86.054977 -24.468885) (xy 86.007371 -24.497939) (xy 85.956042 -24.519751) (xy 85.902085 -24.533857)
			(xy 85.846648 -24.539957) (xy 85.790914 -24.53792) (xy 85.736071 -24.52779) (xy 85.683287 -24.509783)
			(xy 85.633687 -24.484282) (xy 85.588329 -24.451831) (xy 85.54818 -24.413122) (xy 85.514094 -24.368979)
			(xy 85.486798 -24.320344) (xy 85.466875 -24.268253) (xy 85.454749 -24.213816) (xy 85.450678 -24.158194)
			(xy 80.78774 -24.158194) (xy 80.75712 -24.204475) (xy 80.719903 -24.246012) (xy 80.677035 -24.281687)
			(xy 80.629429 -24.310741) (xy 80.5781 -24.332553) (xy 80.524143 -24.346659) (xy 80.468706 -24.352759)
			(xy 80.412972 -24.350722) (xy 80.358129 -24.340592) (xy 80.305345 -24.322585) (xy 80.255745 -24.297084)
			(xy 80.210387 -24.264633) (xy 80.170238 -24.225924) (xy 80.136152 -24.181781) (xy 80.108856 -24.133146)
			(xy 80.088933 -24.081055) (xy 80.076807 -24.026618) (xy 80.072736 -23.970996) (xy 79.843444 -23.970996)
			(xy 79.843375 -23.974752) (xy 79.835255 -24.029928) (xy 79.819187 -24.083335) (xy 79.795515 -24.133832)
			(xy 79.764742 -24.180345) (xy 79.727525 -24.221882) (xy 79.684657 -24.257557) (xy 79.637051 -24.286611)
			(xy 79.585722 -24.308423) (xy 79.531765 -24.322529) (xy 79.476328 -24.328629) (xy 79.420594 -24.326592)
			(xy 79.365751 -24.316462) (xy 79.312967 -24.298455) (xy 79.263367 -24.272954) (xy 79.218009 -24.240503)
			(xy 79.17786 -24.201794) (xy 79.143774 -24.157651) (xy 79.116478 -24.109016) (xy 79.096555 -24.056925)
			(xy 79.084429 -24.002488) (xy 79.080358 -23.946866) (xy 78.840504 -23.946866) (xy 78.840838 -23.965154)
			(xy 78.840329 -23.99304) (xy 78.832209 -24.048216) (xy 78.816141 -24.101623) (xy 78.792469 -24.15212)
			(xy 78.761696 -24.198633) (xy 78.724479 -24.24017) (xy 78.681611 -24.275845) (xy 78.634005 -24.304899)
			(xy 78.582676 -24.326711) (xy 78.528719 -24.340817) (xy 78.473282 -24.346917) (xy 78.417548 -24.34488)
			(xy 78.362705 -24.33475) (xy 78.309921 -24.316743) (xy 78.260321 -24.291242) (xy 78.214963 -24.258791)
			(xy 78.174814 -24.220082) (xy 78.140728 -24.175939) (xy 78.113432 -24.127304) (xy 78.093509 -24.075213)
			(xy 78.081383 -24.020776) (xy 78.077312 -23.965154) (xy 68.537783 -23.965154) (xy 68.535851 -23.965659)
			(xy 68.480414 -23.971759) (xy 68.42468 -23.969722) (xy 68.369837 -23.959592) (xy 68.317053 -23.941585)
			(xy 68.267453 -23.916084) (xy 68.222095 -23.883633) (xy 68.181946 -23.844924) (xy 68.14786 -23.800781)
			(xy 68.120564 -23.752146) (xy 68.100641 -23.700055) (xy 68.088515 -23.645618) (xy 68.084444 -23.589996)
			(xy 54.475692 -23.589996) (xy 54.524195 -23.595333) (xy 54.578152 -23.609439) (xy 54.629481 -23.631251)
			(xy 54.677087 -23.660305) (xy 54.719955 -23.69598) (xy 54.757172 -23.737517) (xy 54.787945 -23.78403)
			(xy 54.811617 -23.834527) (xy 54.827685 -23.887934) (xy 54.835805 -23.94311) (xy 54.836314 -23.970996)
			(xy 54.835805 -23.998882) (xy 54.827685 -24.054058) (xy 54.811617 -24.107465) (xy 54.787945 -24.157962)
			(xy 54.787792 -24.158194) (xy 59.45073 -24.158194) (xy 59.454801 -24.102572) (xy 59.466927 -24.048135)
			(xy 59.48685 -23.996044) (xy 59.514146 -23.947409) (xy 59.548232 -23.903266) (xy 59.588381 -23.864557)
			(xy 59.633739 -23.832106) (xy 59.683339 -23.806605) (xy 59.736123 -23.788598) (xy 59.790966 -23.778468)
			(xy 59.8467 -23.776431) (xy 59.902137 -23.782531) (xy 59.956094 -23.796637) (xy 60.007423 -23.818449)
			(xy 60.055029 -23.847503) (xy 60.097897 -23.883178) (xy 60.135114 -23.924715) (xy 60.165887 -23.971228)
			(xy 60.189559 -24.021725) (xy 60.205627 -24.075132) (xy 60.213747 -24.130308) (xy 60.214256 -24.158194)
			(xy 60.213747 -24.18608) (xy 60.213178 -24.189944) (xy 63.29883 -24.189944) (xy 63.302901 -24.134322)
			(xy 63.315027 -24.079885) (xy 63.33495 -24.027794) (xy 63.362246 -23.979159) (xy 63.396332 -23.935016)
			(xy 63.436481 -23.896307) (xy 63.481839 -23.863856) (xy 63.531439 -23.838355) (xy 63.584223 -23.820348)
			(xy 63.639066 -23.810218) (xy 63.6948 -23.808181) (xy 63.750237 -23.814281) (xy 63.804194 -23.828387)
			(xy 63.855523 -23.850199) (xy 63.903129 -23.879253) (xy 63.945997 -23.914928) (xy 63.983214 -23.956465)
			(xy 64.013987 -24.002978) (xy 64.037659 -24.053475) (xy 64.053727 -24.106882) (xy 64.061847 -24.162058)
			(xy 64.062356 -24.189944) (xy 65.821812 -24.189944) (xy 65.825883 -24.134322) (xy 65.838009 -24.079885)
			(xy 65.857932 -24.027794) (xy 65.885228 -23.979159) (xy 65.919314 -23.935016) (xy 65.959463 -23.896307)
			(xy 66.004821 -23.863856) (xy 66.054421 -23.838355) (xy 66.107205 -23.820348) (xy 66.162048 -23.810218)
			(xy 66.217782 -23.808181) (xy 66.273219 -23.814281) (xy 66.327176 -23.828387) (xy 66.378505 -23.850199)
			(xy 66.426111 -23.879253) (xy 66.468979 -23.914928) (xy 66.506196 -23.956465) (xy 66.536969 -24.002978)
			(xy 66.560641 -24.053475) (xy 66.576709 -24.106882) (xy 66.584829 -24.162058) (xy 66.585338 -24.189944)
			(xy 66.584829 -24.21783) (xy 66.576709 -24.273006) (xy 66.560641 -24.326413) (xy 66.536969 -24.37691)
			(xy 66.506196 -24.423423) (xy 66.468979 -24.46496) (xy 66.426111 -24.500635) (xy 66.378505 -24.529689)
			(xy 66.327176 -24.551501) (xy 66.273219 -24.565607) (xy 66.217782 -24.571707) (xy 66.162048 -24.56967)
			(xy 66.107205 -24.55954) (xy 66.054421 -24.541533) (xy 66.004821 -24.516032) (xy 65.959463 -24.483581)
			(xy 65.919314 -24.444872) (xy 65.885228 -24.400729) (xy 65.857932 -24.352094) (xy 65.838009 -24.300003)
			(xy 65.825883 -24.245566) (xy 65.821812 -24.189944) (xy 64.062356 -24.189944) (xy 64.061847 -24.21783)
			(xy 64.053727 -24.273006) (xy 64.037659 -24.326413) (xy 64.013987 -24.37691) (xy 63.983214 -24.423423)
			(xy 63.945997 -24.46496) (xy 63.903129 -24.500635) (xy 63.855523 -24.529689) (xy 63.804194 -24.551501)
			(xy 63.750237 -24.565607) (xy 63.6948 -24.571707) (xy 63.639066 -24.56967) (xy 63.584223 -24.55954)
			(xy 63.531439 -24.541533) (xy 63.481839 -24.516032) (xy 63.436481 -24.483581) (xy 63.396332 -24.444872)
			(xy 63.362246 -24.400729) (xy 63.33495 -24.352094) (xy 63.315027 -24.300003) (xy 63.302901 -24.245566)
			(xy 63.29883 -24.189944) (xy 60.213178 -24.189944) (xy 60.205627 -24.241256) (xy 60.189559 -24.294663)
			(xy 60.165887 -24.34516) (xy 60.135114 -24.391673) (xy 60.097897 -24.43321) (xy 60.055029 -24.468885)
			(xy 60.007423 -24.497939) (xy 59.956094 -24.519751) (xy 59.902137 -24.533857) (xy 59.8467 -24.539957)
			(xy 59.790966 -24.53792) (xy 59.736123 -24.52779) (xy 59.683339 -24.509783) (xy 59.633739 -24.484282)
			(xy 59.588381 -24.451831) (xy 59.548232 -24.413122) (xy 59.514146 -24.368979) (xy 59.48685 -24.320344)
			(xy 59.466927 -24.268253) (xy 59.454801 -24.213816) (xy 59.45073 -24.158194) (xy 54.787792 -24.158194)
			(xy 54.757172 -24.204475) (xy 54.719955 -24.246012) (xy 54.677087 -24.281687) (xy 54.629481 -24.310741)
			(xy 54.578152 -24.332553) (xy 54.524195 -24.346659) (xy 54.468758 -24.352759) (xy 54.413024 -24.350722)
			(xy 54.358181 -24.340592) (xy 54.305397 -24.322585) (xy 54.255797 -24.297084) (xy 54.210439 -24.264633)
			(xy 54.17029 -24.225924) (xy 54.136204 -24.181781) (xy 54.108908 -24.133146) (xy 54.088985 -24.081055)
			(xy 54.076859 -24.026618) (xy 54.072788 -23.970996) (xy 53.843496 -23.970996) (xy 53.843427 -23.974752)
			(xy 53.835307 -24.029928) (xy 53.819239 -24.083335) (xy 53.795567 -24.133832) (xy 53.764794 -24.180345)
			(xy 53.727577 -24.221882) (xy 53.684709 -24.257557) (xy 53.637103 -24.286611) (xy 53.585774 -24.308423)
			(xy 53.531817 -24.322529) (xy 53.47638 -24.328629) (xy 53.420646 -24.326592) (xy 53.365803 -24.316462)
			(xy 53.313019 -24.298455) (xy 53.263419 -24.272954) (xy 53.218061 -24.240503) (xy 53.177912 -24.201794)
			(xy 53.143826 -24.157651) (xy 53.11653 -24.109016) (xy 53.096607 -24.056925) (xy 53.084481 -24.002488)
			(xy 53.08041 -23.946866) (xy 52.840556 -23.946866) (xy 52.84089 -23.965154) (xy 52.840381 -23.99304)
			(xy 52.832261 -24.048216) (xy 52.816193 -24.101623) (xy 52.792521 -24.15212) (xy 52.761748 -24.198633)
			(xy 52.724531 -24.24017) (xy 52.681663 -24.275845) (xy 52.634057 -24.304899) (xy 52.582728 -24.326711)
			(xy 52.528771 -24.340817) (xy 52.473334 -24.346917) (xy 52.4176 -24.34488) (xy 52.362757 -24.33475)
			(xy 52.309973 -24.316743) (xy 52.260373 -24.291242) (xy 52.215015 -24.258791) (xy 52.174866 -24.220082)
			(xy 52.14078 -24.175939) (xy 52.113484 -24.127304) (xy 52.093561 -24.075213) (xy 52.081435 -24.020776)
			(xy 52.077364 -23.965154) (xy 42.537835 -23.965154) (xy 42.535903 -23.965659) (xy 42.480466 -23.971759)
			(xy 42.424732 -23.969722) (xy 42.369889 -23.959592) (xy 42.317105 -23.941585) (xy 42.267505 -23.916084)
			(xy 42.222147 -23.883633) (xy 42.181998 -23.844924) (xy 42.147912 -23.800781) (xy 42.120616 -23.752146)
			(xy 42.100693 -23.700055) (xy 42.088567 -23.645618) (xy 42.084496 -23.589996) (xy 16.848074 -23.589996)
			(xy 16.847565 -23.617882) (xy 16.839445 -23.673058) (xy 16.823377 -23.726465) (xy 16.799705 -23.776962)
			(xy 16.768932 -23.823475) (xy 16.731715 -23.865012) (xy 16.688847 -23.900687) (xy 16.641241 -23.929741)
			(xy 16.589912 -23.951553) (xy 16.535955 -23.965659) (xy 16.480518 -23.971759) (xy 16.424784 -23.969722)
			(xy 16.369941 -23.959592) (xy 16.317157 -23.941585) (xy 16.267557 -23.916084) (xy 16.222199 -23.883633)
			(xy 16.18205 -23.844924) (xy 16.147964 -23.800781) (xy 16.120668 -23.752146) (xy 16.100745 -23.700055)
			(xy 16.088619 -23.645618) (xy 16.084548 -23.589996) (xy 3.783134 -23.589996) (xy 3.797731 -23.596199)
			(xy 3.845337 -23.625253) (xy 3.888205 -23.660928) (xy 3.925422 -23.702465) (xy 3.956195 -23.748978)
			(xy 3.979867 -23.799475) (xy 3.995935 -23.852882) (xy 4.004055 -23.908058) (xy 4.004564 -23.935944)
			(xy 4.004055 -23.96383) (xy 3.995935 -24.019006) (xy 3.979867 -24.072413) (xy 3.956195 -24.12291)
			(xy 3.925422 -24.169423) (xy 3.907035 -24.189944) (xy 13.821916 -24.189944) (xy 13.825987 -24.134322)
			(xy 13.838113 -24.079885) (xy 13.858036 -24.027794) (xy 13.885332 -23.979159) (xy 13.919418 -23.935016)
			(xy 13.959567 -23.896307) (xy 14.004925 -23.863856) (xy 14.054525 -23.838355) (xy 14.107309 -23.820348)
			(xy 14.162152 -23.810218) (xy 14.217886 -23.808181) (xy 14.273323 -23.814281) (xy 14.32728 -23.828387)
			(xy 14.378609 -23.850199) (xy 14.426215 -23.879253) (xy 14.469083 -23.914928) (xy 14.5063 -23.956465)
			(xy 14.537073 -24.002978) (xy 14.560745 -24.053475) (xy 14.576813 -24.106882) (xy 14.584933 -24.162058)
			(xy 14.585442 -24.189944) (xy 14.584933 -24.21783) (xy 14.576813 -24.273006) (xy 14.560745 -24.326413)
			(xy 14.548157 -24.353266) (xy 19.380198 -24.353266) (xy 19.384269 -24.297644) (xy 19.396395 -24.243207)
			(xy 19.416318 -24.191116) (xy 19.443614 -24.142481) (xy 19.4777 -24.098338) (xy 19.517849 -24.059629)
			(xy 19.563207 -24.027178) (xy 19.612807 -24.001677) (xy 19.665591 -23.98367) (xy 19.720434 -23.97354)
			(xy 19.776168 -23.971503) (xy 19.831605 -23.977603) (xy 19.885562 -23.991709) (xy 19.936891 -24.013521)
			(xy 19.984497 -24.042575) (xy 20.027365 -24.07825) (xy 20.064582 -24.119787) (xy 20.089992 -24.158194)
			(xy 33.450782 -24.158194) (xy 33.454853 -24.102572) (xy 33.466979 -24.048135) (xy 33.486902 -23.996044)
			(xy 33.514198 -23.947409) (xy 33.548284 -23.903266) (xy 33.588433 -23.864557) (xy 33.633791 -23.832106)
			(xy 33.683391 -23.806605) (xy 33.736175 -23.788598) (xy 33.791018 -23.778468) (xy 33.846752 -23.776431)
			(xy 33.902189 -23.782531) (xy 33.956146 -23.796637) (xy 34.007475 -23.818449) (xy 34.055081 -23.847503)
			(xy 34.097949 -23.883178) (xy 34.135166 -23.924715) (xy 34.165939 -23.971228) (xy 34.189611 -24.021725)
			(xy 34.205679 -24.075132) (xy 34.213799 -24.130308) (xy 34.214308 -24.158194) (xy 34.213799 -24.18608)
			(xy 34.21323 -24.189944) (xy 37.298882 -24.189944) (xy 37.302953 -24.134322) (xy 37.315079 -24.079885)
			(xy 37.335002 -24.027794) (xy 37.362298 -23.979159) (xy 37.396384 -23.935016) (xy 37.436533 -23.896307)
			(xy 37.481891 -23.863856) (xy 37.531491 -23.838355) (xy 37.584275 -23.820348) (xy 37.639118 -23.810218)
			(xy 37.694852 -23.808181) (xy 37.750289 -23.814281) (xy 37.804246 -23.828387) (xy 37.855575 -23.850199)
			(xy 37.903181 -23.879253) (xy 37.946049 -23.914928) (xy 37.983266 -23.956465) (xy 38.014039 -24.002978)
			(xy 38.037711 -24.053475) (xy 38.053779 -24.106882) (xy 38.061899 -24.162058) (xy 38.062408 -24.189944)
			(xy 39.821864 -24.189944) (xy 39.825935 -24.134322) (xy 39.838061 -24.079885) (xy 39.857984 -24.027794)
			(xy 39.88528 -23.979159) (xy 39.919366 -23.935016) (xy 39.959515 -23.896307) (xy 40.004873 -23.863856)
			(xy 40.054473 -23.838355) (xy 40.107257 -23.820348) (xy 40.1621 -23.810218) (xy 40.217834 -23.808181)
			(xy 40.273271 -23.814281) (xy 40.327228 -23.828387) (xy 40.378557 -23.850199) (xy 40.426163 -23.879253)
			(xy 40.469031 -23.914928) (xy 40.506248 -23.956465) (xy 40.537021 -24.002978) (xy 40.560693 -24.053475)
			(xy 40.576761 -24.106882) (xy 40.584881 -24.162058) (xy 40.58539 -24.189944) (xy 40.584881 -24.21783)
			(xy 40.576761 -24.273006) (xy 40.560693 -24.326413) (xy 40.537021 -24.37691) (xy 40.506248 -24.423423)
			(xy 40.469031 -24.46496) (xy 40.426163 -24.500635) (xy 40.378557 -24.529689) (xy 40.327228 -24.551501)
			(xy 40.273271 -24.565607) (xy 40.217834 -24.571707) (xy 40.1621 -24.56967) (xy 40.107257 -24.55954)
			(xy 40.054473 -24.541533) (xy 40.004873 -24.516032) (xy 39.959515 -24.483581) (xy 39.919366 -24.444872)
			(xy 39.88528 -24.400729) (xy 39.857984 -24.352094) (xy 39.838061 -24.300003) (xy 39.825935 -24.245566)
			(xy 39.821864 -24.189944) (xy 38.062408 -24.189944) (xy 38.061899 -24.21783) (xy 38.053779 -24.273006)
			(xy 38.037711 -24.326413) (xy 38.014039 -24.37691) (xy 37.983266 -24.423423) (xy 37.946049 -24.46496)
			(xy 37.903181 -24.500635) (xy 37.855575 -24.529689) (xy 37.804246 -24.551501) (xy 37.750289 -24.565607)
			(xy 37.694852 -24.571707) (xy 37.639118 -24.56967) (xy 37.584275 -24.55954) (xy 37.531491 -24.541533)
			(xy 37.481891 -24.516032) (xy 37.436533 -24.483581) (xy 37.396384 -24.444872) (xy 37.362298 -24.400729)
			(xy 37.335002 -24.352094) (xy 37.315079 -24.300003) (xy 37.302953 -24.245566) (xy 37.298882 -24.189944)
			(xy 34.21323 -24.189944) (xy 34.205679 -24.241256) (xy 34.189611 -24.294663) (xy 34.165939 -24.34516)
			(xy 34.135166 -24.391673) (xy 34.097949 -24.43321) (xy 34.055081 -24.468885) (xy 34.007475 -24.497939)
			(xy 33.956146 -24.519751) (xy 33.902189 -24.533857) (xy 33.846752 -24.539957) (xy 33.791018 -24.53792)
			(xy 33.736175 -24.52779) (xy 33.683391 -24.509783) (xy 33.633791 -24.484282) (xy 33.588433 -24.451831)
			(xy 33.548284 -24.413122) (xy 33.514198 -24.368979) (xy 33.486902 -24.320344) (xy 33.466979 -24.268253)
			(xy 33.454853 -24.213816) (xy 33.450782 -24.158194) (xy 20.089992 -24.158194) (xy 20.095355 -24.1663)
			(xy 20.119027 -24.216797) (xy 20.135095 -24.270204) (xy 20.143215 -24.32538) (xy 20.143724 -24.353266)
			(xy 20.143215 -24.381152) (xy 20.135095 -24.436328) (xy 20.119027 -24.489735) (xy 20.095355 -24.540232)
			(xy 20.064582 -24.586745) (xy 20.027365 -24.628282) (xy 19.984497 -24.663957) (xy 19.936891 -24.693011)
			(xy 19.885562 -24.714823) (xy 19.831605 -24.728929) (xy 19.776168 -24.735029) (xy 19.720434 -24.732992)
			(xy 19.665591 -24.722862) (xy 19.612807 -24.704855) (xy 19.563207 -24.679354) (xy 19.517849 -24.646903)
			(xy 19.4777 -24.608194) (xy 19.443614 -24.564051) (xy 19.416318 -24.515416) (xy 19.396395 -24.463325)
			(xy 19.384269 -24.408888) (xy 19.380198 -24.353266) (xy 14.548157 -24.353266) (xy 14.537073 -24.37691)
			(xy 14.5063 -24.423423) (xy 14.469083 -24.46496) (xy 14.426215 -24.500635) (xy 14.378609 -24.529689)
			(xy 14.32728 -24.551501) (xy 14.273323 -24.565607) (xy 14.217886 -24.571707) (xy 14.162152 -24.56967)
			(xy 14.107309 -24.55954) (xy 14.054525 -24.541533) (xy 14.004925 -24.516032) (xy 13.959567 -24.483581)
			(xy 13.919418 -24.444872) (xy 13.885332 -24.400729) (xy 13.858036 -24.352094) (xy 13.838113 -24.300003)
			(xy 13.825987 -24.245566) (xy 13.821916 -24.189944) (xy 3.907035 -24.189944) (xy 3.888205 -24.21096)
			(xy 3.845337 -24.246635) (xy 3.797731 -24.275689) (xy 3.746402 -24.297501) (xy 3.692445 -24.311607)
			(xy 3.637008 -24.317707) (xy 3.581274 -24.31567) (xy 3.526431 -24.30554) (xy 3.473647 -24.287533)
			(xy 3.424047 -24.262032) (xy 3.378689 -24.229581) (xy 3.33854 -24.190872) (xy 3.304454 -24.146729)
			(xy 3.277158 -24.098094) (xy 3.257235 -24.046003) (xy 3.245109 -23.991566) (xy 3.241038 -23.935944)
			(xy 2.995676 -23.935944) (xy 2.995167 -23.96383) (xy 2.987047 -24.019006) (xy 2.970979 -24.072413)
			(xy 2.947307 -24.12291) (xy 2.916534 -24.169423) (xy 2.879317 -24.21096) (xy 2.836449 -24.246635)
			(xy 2.788843 -24.275689) (xy 2.737514 -24.297501) (xy 2.683557 -24.311607) (xy 2.62812 -24.317707)
			(xy 2.572386 -24.31567) (xy 2.517543 -24.30554) (xy 2.464759 -24.287533) (xy 2.415159 -24.262032)
			(xy 2.369801 -24.229581) (xy 2.329652 -24.190872) (xy 2.295566 -24.146729) (xy 2.26827 -24.098094)
			(xy 2.248347 -24.046003) (xy 2.236221 -23.991566) (xy 2.23215 -23.935944) (xy 1.306576 -23.935944)
			(xy 1.306576 -24.807418) (xy 6.371334 -24.807418) (xy 6.375405 -24.751796) (xy 6.387531 -24.697359)
			(xy 6.407454 -24.645268) (xy 6.43475 -24.596633) (xy 6.468836 -24.55249) (xy 6.508985 -24.513781)
			(xy 6.554343 -24.48133) (xy 6.603943 -24.455829) (xy 6.656727 -24.437822) (xy 6.71157 -24.427692)
			(xy 6.767304 -24.425655) (xy 6.822741 -24.431755) (xy 6.876698 -24.445861) (xy 6.928027 -24.467673)
			(xy 6.975633 -24.496727) (xy 7.018501 -24.532402) (xy 7.055718 -24.573939) (xy 7.086491 -24.620452)
			(xy 7.110163 -24.670949) (xy 7.126231 -24.724356) (xy 7.134351 -24.779532) (xy 7.13486 -24.807418)
			(xy 8.62025 -24.807418) (xy 8.624321 -24.751796) (xy 8.636447 -24.697359) (xy 8.65637 -24.645268)
			(xy 8.683666 -24.596633) (xy 8.717752 -24.55249) (xy 8.757901 -24.513781) (xy 8.803259 -24.48133)
			(xy 8.852859 -24.455829) (xy 8.905643 -24.437822) (xy 8.960486 -24.427692) (xy 9.01622 -24.425655)
			(xy 9.071657 -24.431755) (xy 9.125614 -24.445861) (xy 9.176943 -24.467673) (xy 9.224549 -24.496727)
			(xy 9.267417 -24.532402) (xy 9.304634 -24.573939) (xy 9.335407 -24.620452) (xy 9.359079 -24.670949)
			(xy 9.375147 -24.724356) (xy 9.383267 -24.779532) (xy 9.383776 -24.807418) (xy 9.383267 -24.835304)
			(xy 9.375147 -24.89048) (xy 9.359079 -24.943887) (xy 9.335407 -24.994384) (xy 9.304634 -25.040897)
			(xy 9.267417 -25.082434) (xy 9.224549 -25.118109) (xy 9.176943 -25.147163) (xy 9.125614 -25.168975)
			(xy 9.071657 -25.183081) (xy 9.01622 -25.189181) (xy 8.960486 -25.187144) (xy 8.905643 -25.177014)
			(xy 8.852859 -25.159007) (xy 8.803259 -25.133506) (xy 8.757901 -25.101055) (xy 8.717752 -25.062346)
			(xy 8.683666 -25.018203) (xy 8.65637 -24.969568) (xy 8.636447 -24.917477) (xy 8.624321 -24.86304)
			(xy 8.62025 -24.807418) (xy 7.13486 -24.807418) (xy 7.134351 -24.835304) (xy 7.126231 -24.89048)
			(xy 7.110163 -24.943887) (xy 7.086491 -24.994384) (xy 7.055718 -25.040897) (xy 7.018501 -25.082434)
			(xy 6.975633 -25.118109) (xy 6.928027 -25.147163) (xy 6.876698 -25.168975) (xy 6.822741 -25.183081)
			(xy 6.767304 -25.189181) (xy 6.71157 -25.187144) (xy 6.656727 -25.177014) (xy 6.603943 -25.159007)
			(xy 6.554343 -25.133506) (xy 6.508985 -25.101055) (xy 6.468836 -25.062346) (xy 6.43475 -25.018203)
			(xy 6.407454 -24.969568) (xy 6.387531 -24.917477) (xy 6.375405 -24.86304) (xy 6.371334 -24.807418)
			(xy 1.306576 -24.807418) (xy 1.306576 -25.390094) (xy 13.809216 -25.390094) (xy 13.813287 -25.334472)
			(xy 13.825413 -25.280035) (xy 13.845336 -25.227944) (xy 13.872632 -25.179309) (xy 13.906718 -25.135166)
			(xy 13.946867 -25.096457) (xy 13.992225 -25.064006) (xy 14.041825 -25.038505) (xy 14.094609 -25.020498)
			(xy 14.149452 -25.010368) (xy 14.205186 -25.008331) (xy 14.260623 -25.014431) (xy 14.31458 -25.028537)
			(xy 14.322621 -25.031954) (xy 18.187922 -25.031954) (xy 18.191993 -24.976332) (xy 18.204119 -24.921895)
			(xy 18.224042 -24.869804) (xy 18.251338 -24.821169) (xy 18.285424 -24.777026) (xy 18.325573 -24.738317)
			(xy 18.370931 -24.705866) (xy 18.420531 -24.680365) (xy 18.473315 -24.662358) (xy 18.528158 -24.652228)
			(xy 18.583892 -24.650191) (xy 18.639329 -24.656291) (xy 18.693286 -24.670397) (xy 18.744615 -24.692209)
			(xy 18.792221 -24.721263) (xy 18.835089 -24.756938) (xy 18.872306 -24.798475) (xy 18.878223 -24.807418)
			(xy 32.371282 -24.807418) (xy 32.375353 -24.751796) (xy 32.387479 -24.697359) (xy 32.407402 -24.645268)
			(xy 32.434698 -24.596633) (xy 32.468784 -24.55249) (xy 32.508933 -24.513781) (xy 32.554291 -24.48133)
			(xy 32.603891 -24.455829) (xy 32.656675 -24.437822) (xy 32.711518 -24.427692) (xy 32.767252 -24.425655)
			(xy 32.822689 -24.431755) (xy 32.876646 -24.445861) (xy 32.927975 -24.467673) (xy 32.975581 -24.496727)
			(xy 33.018449 -24.532402) (xy 33.055666 -24.573939) (xy 33.086439 -24.620452) (xy 33.110111 -24.670949)
			(xy 33.126179 -24.724356) (xy 33.134299 -24.779532) (xy 33.134808 -24.807418) (xy 34.620198 -24.807418)
			(xy 34.624269 -24.751796) (xy 34.636395 -24.697359) (xy 34.656318 -24.645268) (xy 34.683614 -24.596633)
			(xy 34.7177 -24.55249) (xy 34.757849 -24.513781) (xy 34.803207 -24.48133) (xy 34.852807 -24.455829)
			(xy 34.905591 -24.437822) (xy 34.960434 -24.427692) (xy 35.016168 -24.425655) (xy 35.071605 -24.431755)
			(xy 35.125562 -24.445861) (xy 35.176891 -24.467673) (xy 35.224497 -24.496727) (xy 35.267365 -24.532402)
			(xy 35.304582 -24.573939) (xy 35.335355 -24.620452) (xy 35.359027 -24.670949) (xy 35.375095 -24.724356)
			(xy 35.383215 -24.779532) (xy 35.383724 -24.807418) (xy 35.383215 -24.835304) (xy 35.375095 -24.89048)
			(xy 35.359027 -24.943887) (xy 35.335355 -24.994384) (xy 35.304582 -25.040897) (xy 35.267365 -25.082434)
			(xy 35.224497 -25.118109) (xy 35.176891 -25.147163) (xy 35.125562 -25.168975) (xy 35.071605 -25.183081)
			(xy 35.016168 -25.189181) (xy 34.960434 -25.187144) (xy 34.905591 -25.177014) (xy 34.852807 -25.159007)
			(xy 34.803207 -25.133506) (xy 34.757849 -25.101055) (xy 34.7177 -25.062346) (xy 34.683614 -25.018203)
			(xy 34.656318 -24.969568) (xy 34.636395 -24.917477) (xy 34.624269 -24.86304) (xy 34.620198 -24.807418)
			(xy 33.134808 -24.807418) (xy 33.134299 -24.835304) (xy 33.126179 -24.89048) (xy 33.110111 -24.943887)
			(xy 33.086439 -24.994384) (xy 33.055666 -25.040897) (xy 33.018449 -25.082434) (xy 32.975581 -25.118109)
			(xy 32.927975 -25.147163) (xy 32.876646 -25.168975) (xy 32.822689 -25.183081) (xy 32.767252 -25.189181)
			(xy 32.711518 -25.187144) (xy 32.656675 -25.177014) (xy 32.603891 -25.159007) (xy 32.554291 -25.133506)
			(xy 32.508933 -25.101055) (xy 32.468784 -25.062346) (xy 32.434698 -25.018203) (xy 32.407402 -24.969568)
			(xy 32.387479 -24.917477) (xy 32.375353 -24.86304) (xy 32.371282 -24.807418) (xy 18.878223 -24.807418)
			(xy 18.903079 -24.844988) (xy 18.926751 -24.895485) (xy 18.942819 -24.948892) (xy 18.950939 -25.004068)
			(xy 18.951448 -25.031954) (xy 18.950939 -25.05984) (xy 18.942819 -25.115016) (xy 18.926751 -25.168423)
			(xy 18.903079 -25.21892) (xy 18.872306 -25.265433) (xy 18.835089 -25.30697) (xy 18.792221 -25.342645)
			(xy 18.744615 -25.371699) (xy 18.701327 -25.390094) (xy 39.809164 -25.390094) (xy 39.813235 -25.334472)
			(xy 39.825361 -25.280035) (xy 39.845284 -25.227944) (xy 39.87258 -25.179309) (xy 39.906666 -25.135166)
			(xy 39.946815 -25.096457) (xy 39.992173 -25.064006) (xy 40.041773 -25.038505) (xy 40.094557 -25.020498)
			(xy 40.1494 -25.010368) (xy 40.205134 -25.008331) (xy 40.260571 -25.014431) (xy 40.314528 -25.028537)
			(xy 40.322569 -25.031954) (xy 44.18787 -25.031954) (xy 44.191941 -24.976332) (xy 44.204067 -24.921895)
			(xy 44.22399 -24.869804) (xy 44.251286 -24.821169) (xy 44.285372 -24.777026) (xy 44.325521 -24.738317)
			(xy 44.370879 -24.705866) (xy 44.420479 -24.680365) (xy 44.473263 -24.662358) (xy 44.528106 -24.652228)
			(xy 44.58384 -24.650191) (xy 44.639277 -24.656291) (xy 44.693234 -24.670397) (xy 44.744563 -24.692209)
			(xy 44.792169 -24.721263) (xy 44.835037 -24.756938) (xy 44.836571 -24.75865) (xy 46.868586 -24.75865)
			(xy 46.872657 -24.703028) (xy 46.884783 -24.648591) (xy 46.904706 -24.5965) (xy 46.932002 -24.547865)
			(xy 46.966088 -24.503722) (xy 47.006237 -24.465013) (xy 47.051595 -24.432562) (xy 47.101195 -24.407061)
			(xy 47.153979 -24.389054) (xy 47.208822 -24.378924) (xy 47.264556 -24.376887) (xy 47.319993 -24.382987)
			(xy 47.37395 -24.397093) (xy 47.425279 -24.418905) (xy 47.472885 -24.447959) (xy 47.515753 -24.483634)
			(xy 47.55297 -24.525171) (xy 47.583743 -24.571684) (xy 47.607415 -24.622181) (xy 47.623483 -24.675588)
			(xy 47.631603 -24.730764) (xy 47.632112 -24.75865) (xy 47.631603 -24.786536) (xy 47.62853 -24.807418)
			(xy 58.37123 -24.807418) (xy 58.375301 -24.751796) (xy 58.387427 -24.697359) (xy 58.40735 -24.645268)
			(xy 58.434646 -24.596633) (xy 58.468732 -24.55249) (xy 58.508881 -24.513781) (xy 58.554239 -24.48133)
			(xy 58.603839 -24.455829) (xy 58.656623 -24.437822) (xy 58.711466 -24.427692) (xy 58.7672 -24.425655)
			(xy 58.822637 -24.431755) (xy 58.876594 -24.445861) (xy 58.927923 -24.467673) (xy 58.975529 -24.496727)
			(xy 59.018397 -24.532402) (xy 59.055614 -24.573939) (xy 59.086387 -24.620452) (xy 59.110059 -24.670949)
			(xy 59.126127 -24.724356) (xy 59.134247 -24.779532) (xy 59.134756 -24.807418) (xy 60.620146 -24.807418)
			(xy 60.624217 -24.751796) (xy 60.636343 -24.697359) (xy 60.656266 -24.645268) (xy 60.683562 -24.596633)
			(xy 60.717648 -24.55249) (xy 60.757797 -24.513781) (xy 60.803155 -24.48133) (xy 60.852755 -24.455829)
			(xy 60.905539 -24.437822) (xy 60.960382 -24.427692) (xy 61.016116 -24.425655) (xy 61.071553 -24.431755)
			(xy 61.12551 -24.445861) (xy 61.176839 -24.467673) (xy 61.224445 -24.496727) (xy 61.267313 -24.532402)
			(xy 61.30453 -24.573939) (xy 61.335303 -24.620452) (xy 61.358975 -24.670949) (xy 61.375043 -24.724356)
			(xy 61.383163 -24.779532) (xy 61.383672 -24.807418) (xy 61.383163 -24.835304) (xy 61.375043 -24.89048)
			(xy 61.358975 -24.943887) (xy 61.335303 -24.994384) (xy 61.30453 -25.040897) (xy 61.267313 -25.082434)
			(xy 61.224445 -25.118109) (xy 61.176839 -25.147163) (xy 61.12551 -25.168975) (xy 61.071553 -25.183081)
			(xy 61.016116 -25.189181) (xy 60.960382 -25.187144) (xy 60.905539 -25.177014) (xy 60.852755 -25.159007)
			(xy 60.803155 -25.133506) (xy 60.757797 -25.101055) (xy 60.717648 -25.062346) (xy 60.683562 -25.018203)
			(xy 60.656266 -24.969568) (xy 60.636343 -24.917477) (xy 60.624217 -24.86304) (xy 60.620146 -24.807418)
			(xy 59.134756 -24.807418) (xy 59.134247 -24.835304) (xy 59.126127 -24.89048) (xy 59.110059 -24.943887)
			(xy 59.086387 -24.994384) (xy 59.055614 -25.040897) (xy 59.018397 -25.082434) (xy 58.975529 -25.118109)
			(xy 58.927923 -25.147163) (xy 58.876594 -25.168975) (xy 58.822637 -25.183081) (xy 58.7672 -25.189181)
			(xy 58.711466 -25.187144) (xy 58.656623 -25.177014) (xy 58.603839 -25.159007) (xy 58.554239 -25.133506)
			(xy 58.508881 -25.101055) (xy 58.468732 -25.062346) (xy 58.434646 -25.018203) (xy 58.40735 -24.969568)
			(xy 58.387427 -24.917477) (xy 58.375301 -24.86304) (xy 58.37123 -24.807418) (xy 47.62853 -24.807418)
			(xy 47.623483 -24.841712) (xy 47.607415 -24.895119) (xy 47.583743 -24.945616) (xy 47.55297 -24.992129)
			(xy 47.515753 -25.033666) (xy 47.472885 -25.069341) (xy 47.425279 -25.098395) (xy 47.37395 -25.120207)
			(xy 47.319993 -25.134313) (xy 47.264556 -25.140413) (xy 47.208822 -25.138376) (xy 47.153979 -25.128246)
			(xy 47.101195 -25.110239) (xy 47.051595 -25.084738) (xy 47.006237 -25.052287) (xy 46.966088 -25.013578)
			(xy 46.932002 -24.969435) (xy 46.904706 -24.9208) (xy 46.884783 -24.868709) (xy 46.872657 -24.814272)
			(xy 46.868586 -24.75865) (xy 44.836571 -24.75865) (xy 44.872254 -24.798475) (xy 44.903027 -24.844988)
			(xy 44.926699 -24.895485) (xy 44.942767 -24.948892) (xy 44.950887 -25.004068) (xy 44.951396 -25.031954)
			(xy 44.950887 -25.05984) (xy 44.942767 -25.115016) (xy 44.926699 -25.168423) (xy 44.903027 -25.21892)
			(xy 44.872254 -25.265433) (xy 44.835037 -25.30697) (xy 44.792169 -25.342645) (xy 44.744563 -25.371699)
			(xy 44.693234 -25.393511) (xy 44.639277 -25.407617) (xy 44.58384 -25.413717) (xy 44.528106 -25.41168)
			(xy 44.473263 -25.40155) (xy 44.420479 -25.383543) (xy 44.370879 -25.358042) (xy 44.325521 -25.325591)
			(xy 44.285372 -25.286882) (xy 44.251286 -25.242739) (xy 44.22399 -25.194104) (xy 44.204067 -25.142013)
			(xy 44.191941 -25.087576) (xy 44.18787 -25.031954) (xy 40.322569 -25.031954) (xy 40.365857 -25.050349)
			(xy 40.413463 -25.079403) (xy 40.456331 -25.115078) (xy 40.493548 -25.156615) (xy 40.524321 -25.203128)
			(xy 40.547993 -25.253625) (xy 40.564061 -25.307032) (xy 40.572181 -25.362208) (xy 40.57269 -25.390094)
			(xy 40.572181 -25.41798) (xy 40.564061 -25.473156) (xy 40.547993 -25.526563) (xy 40.532904 -25.55875)
			(xy 48.64176 -25.55875) (xy 48.645831 -25.503128) (xy 48.657957 -25.448691) (xy 48.67788 -25.3966)
			(xy 48.705176 -25.347965) (xy 48.739262 -25.303822) (xy 48.779411 -25.265113) (xy 48.824769 -25.232662)
			(xy 48.874369 -25.207161) (xy 48.927153 -25.189154) (xy 48.981996 -25.179024) (xy 49.03773 -25.176987)
			(xy 49.093167 -25.183087) (xy 49.147124 -25.197193) (xy 49.198453 -25.219005) (xy 49.246059 -25.248059)
			(xy 49.288927 -25.283734) (xy 49.326144 -25.325271) (xy 49.356917 -25.371784) (xy 49.3655 -25.390094)
			(xy 65.809112 -25.390094) (xy 65.813183 -25.334472) (xy 65.825309 -25.280035) (xy 65.845232 -25.227944)
			(xy 65.872528 -25.179309) (xy 65.906614 -25.135166) (xy 65.946763 -25.096457) (xy 65.992121 -25.064006)
			(xy 66.041721 -25.038505) (xy 66.094505 -25.020498) (xy 66.149348 -25.010368) (xy 66.205082 -25.008331)
			(xy 66.260519 -25.014431) (xy 66.314476 -25.028537) (xy 66.322517 -25.031954) (xy 70.187818 -25.031954)
			(xy 70.191889 -24.976332) (xy 70.204015 -24.921895) (xy 70.223938 -24.869804) (xy 70.251234 -24.821169)
			(xy 70.28532 -24.777026) (xy 70.325469 -24.738317) (xy 70.370827 -24.705866) (xy 70.420427 -24.680365)
			(xy 70.473211 -24.662358) (xy 70.528054 -24.652228) (xy 70.583788 -24.650191) (xy 70.639225 -24.656291)
			(xy 70.693182 -24.670397) (xy 70.744511 -24.692209) (xy 70.792117 -24.721263) (xy 70.834985 -24.756938)
			(xy 70.836519 -24.75865) (xy 72.868534 -24.75865) (xy 72.872605 -24.703028) (xy 72.884731 -24.648591)
			(xy 72.904654 -24.5965) (xy 72.93195 -24.547865) (xy 72.966036 -24.503722) (xy 73.006185 -24.465013)
			(xy 73.051543 -24.432562) (xy 73.101143 -24.407061) (xy 73.153927 -24.389054) (xy 73.20877 -24.378924)
			(xy 73.264504 -24.376887) (xy 73.319941 -24.382987) (xy 73.373898 -24.397093) (xy 73.425227 -24.418905)
			(xy 73.472833 -24.447959) (xy 73.515701 -24.483634) (xy 73.552918 -24.525171) (xy 73.583691 -24.571684)
			(xy 73.607363 -24.622181) (xy 73.623431 -24.675588) (xy 73.631551 -24.730764) (xy 73.63206 -24.75865)
			(xy 73.631551 -24.786536) (xy 73.628478 -24.807418) (xy 84.371178 -24.807418) (xy 84.375249 -24.751796)
			(xy 84.387375 -24.697359) (xy 84.407298 -24.645268) (xy 84.434594 -24.596633) (xy 84.46868 -24.55249)
			(xy 84.508829 -24.513781) (xy 84.554187 -24.48133) (xy 84.603787 -24.455829) (xy 84.656571 -24.437822)
			(xy 84.711414 -24.427692) (xy 84.767148 -24.425655) (xy 84.822585 -24.431755) (xy 84.876542 -24.445861)
			(xy 84.927871 -24.467673) (xy 84.975477 -24.496727) (xy 85.018345 -24.532402) (xy 85.055562 -24.573939)
			(xy 85.086335 -24.620452) (xy 85.110007 -24.670949) (xy 85.126075 -24.724356) (xy 85.134195 -24.779532)
			(xy 85.134704 -24.807418) (xy 86.620094 -24.807418) (xy 86.624165 -24.751796) (xy 86.636291 -24.697359)
			(xy 86.656214 -24.645268) (xy 86.68351 -24.596633) (xy 86.717596 -24.55249) (xy 86.757745 -24.513781)
			(xy 86.803103 -24.48133) (xy 86.852703 -24.455829) (xy 86.905487 -24.437822) (xy 86.96033 -24.427692)
			(xy 87.016064 -24.425655) (xy 87.071501 -24.431755) (xy 87.125458 -24.445861) (xy 87.176787 -24.467673)
			(xy 87.224393 -24.496727) (xy 87.267261 -24.532402) (xy 87.304478 -24.573939) (xy 87.335251 -24.620452)
			(xy 87.358923 -24.670949) (xy 87.374991 -24.724356) (xy 87.383111 -24.779532) (xy 87.38362 -24.807418)
			(xy 87.383111 -24.835304) (xy 87.374991 -24.89048) (xy 87.358923 -24.943887) (xy 87.335251 -24.994384)
			(xy 87.304478 -25.040897) (xy 87.267261 -25.082434) (xy 87.224393 -25.118109) (xy 87.176787 -25.147163)
			(xy 87.125458 -25.168975) (xy 87.071501 -25.183081) (xy 87.016064 -25.189181) (xy 86.96033 -25.187144)
			(xy 86.905487 -25.177014) (xy 86.852703 -25.159007) (xy 86.803103 -25.133506) (xy 86.757745 -25.101055)
			(xy 86.717596 -25.062346) (xy 86.68351 -25.018203) (xy 86.656214 -24.969568) (xy 86.636291 -24.917477)
			(xy 86.624165 -24.86304) (xy 86.620094 -24.807418) (xy 85.134704 -24.807418) (xy 85.134195 -24.835304)
			(xy 85.126075 -24.89048) (xy 85.110007 -24.943887) (xy 85.086335 -24.994384) (xy 85.055562 -25.040897)
			(xy 85.018345 -25.082434) (xy 84.975477 -25.118109) (xy 84.927871 -25.147163) (xy 84.876542 -25.168975)
			(xy 84.822585 -25.183081) (xy 84.767148 -25.189181) (xy 84.711414 -25.187144) (xy 84.656571 -25.177014)
			(xy 84.603787 -25.159007) (xy 84.554187 -25.133506) (xy 84.508829 -25.101055) (xy 84.46868 -25.062346)
			(xy 84.434594 -25.018203) (xy 84.407298 -24.969568) (xy 84.387375 -24.917477) (xy 84.375249 -24.86304)
			(xy 84.371178 -24.807418) (xy 73.628478 -24.807418) (xy 73.623431 -24.841712) (xy 73.607363 -24.895119)
			(xy 73.583691 -24.945616) (xy 73.552918 -24.992129) (xy 73.515701 -25.033666) (xy 73.472833 -25.069341)
			(xy 73.425227 -25.098395) (xy 73.373898 -25.120207) (xy 73.319941 -25.134313) (xy 73.264504 -25.140413)
			(xy 73.20877 -25.138376) (xy 73.153927 -25.128246) (xy 73.101143 -25.110239) (xy 73.051543 -25.084738)
			(xy 73.006185 -25.052287) (xy 72.966036 -25.013578) (xy 72.93195 -24.969435) (xy 72.904654 -24.9208)
			(xy 72.884731 -24.868709) (xy 72.872605 -24.814272) (xy 72.868534 -24.75865) (xy 70.836519 -24.75865)
			(xy 70.872202 -24.798475) (xy 70.902975 -24.844988) (xy 70.926647 -24.895485) (xy 70.942715 -24.948892)
			(xy 70.950835 -25.004068) (xy 70.951344 -25.031954) (xy 70.950835 -25.05984) (xy 70.942715 -25.115016)
			(xy 70.926647 -25.168423) (xy 70.902975 -25.21892) (xy 70.872202 -25.265433) (xy 70.834985 -25.30697)
			(xy 70.792117 -25.342645) (xy 70.744511 -25.371699) (xy 70.693182 -25.393511) (xy 70.639225 -25.407617)
			(xy 70.583788 -25.413717) (xy 70.528054 -25.41168) (xy 70.473211 -25.40155) (xy 70.420427 -25.383543)
			(xy 70.370827 -25.358042) (xy 70.325469 -25.325591) (xy 70.28532 -25.286882) (xy 70.251234 -25.242739)
			(xy 70.223938 -25.194104) (xy 70.204015 -25.142013) (xy 70.191889 -25.087576) (xy 70.187818 -25.031954)
			(xy 66.322517 -25.031954) (xy 66.365805 -25.050349) (xy 66.413411 -25.079403) (xy 66.456279 -25.115078)
			(xy 66.493496 -25.156615) (xy 66.524269 -25.203128) (xy 66.547941 -25.253625) (xy 66.564009 -25.307032)
			(xy 66.572129 -25.362208) (xy 66.572638 -25.390094) (xy 66.572129 -25.41798) (xy 66.564009 -25.473156)
			(xy 66.547941 -25.526563) (xy 66.532852 -25.55875) (xy 74.641708 -25.55875) (xy 74.645779 -25.503128)
			(xy 74.657905 -25.448691) (xy 74.677828 -25.3966) (xy 74.705124 -25.347965) (xy 74.73921 -25.303822)
			(xy 74.779359 -25.265113) (xy 74.824717 -25.232662) (xy 74.874317 -25.207161) (xy 74.927101 -25.189154)
			(xy 74.981944 -25.179024) (xy 75.037678 -25.176987) (xy 75.093115 -25.183087) (xy 75.147072 -25.197193)
			(xy 75.198401 -25.219005) (xy 75.246007 -25.248059) (xy 75.288875 -25.283734) (xy 75.326092 -25.325271)
			(xy 75.356865 -25.371784) (xy 75.365448 -25.390094) (xy 91.80906 -25.390094) (xy 91.813131 -25.334472)
			(xy 91.825257 -25.280035) (xy 91.84518 -25.227944) (xy 91.872476 -25.179309) (xy 91.906562 -25.135166)
			(xy 91.946711 -25.096457) (xy 91.992069 -25.064006) (xy 92.041669 -25.038505) (xy 92.094453 -25.020498)
			(xy 92.149296 -25.010368) (xy 92.20503 -25.008331) (xy 92.260467 -25.014431) (xy 92.314424 -25.028537)
			(xy 92.322465 -25.031954) (xy 96.187766 -25.031954) (xy 96.191837 -24.976332) (xy 96.203963 -24.921895)
			(xy 96.223886 -24.869804) (xy 96.251182 -24.821169) (xy 96.285268 -24.777026) (xy 96.325417 -24.738317)
			(xy 96.370775 -24.705866) (xy 96.420375 -24.680365) (xy 96.473159 -24.662358) (xy 96.528002 -24.652228)
			(xy 96.583736 -24.650191) (xy 96.639173 -24.656291) (xy 96.69313 -24.670397) (xy 96.744459 -24.692209)
			(xy 96.792065 -24.721263) (xy 96.834933 -24.756938) (xy 96.836467 -24.75865) (xy 98.868482 -24.75865)
			(xy 98.872553 -24.703028) (xy 98.884679 -24.648591) (xy 98.904602 -24.5965) (xy 98.931898 -24.547865)
			(xy 98.965984 -24.503722) (xy 99.006133 -24.465013) (xy 99.051491 -24.432562) (xy 99.101091 -24.407061)
			(xy 99.153875 -24.389054) (xy 99.208718 -24.378924) (xy 99.264452 -24.376887) (xy 99.319889 -24.382987)
			(xy 99.373846 -24.397093) (xy 99.425175 -24.418905) (xy 99.472781 -24.447959) (xy 99.515649 -24.483634)
			(xy 99.552866 -24.525171) (xy 99.583639 -24.571684) (xy 99.607311 -24.622181) (xy 99.623379 -24.675588)
			(xy 99.631499 -24.730764) (xy 99.632008 -24.75865) (xy 99.631499 -24.786536) (xy 99.628426 -24.807418)
			(xy 122.471432 -24.807418) (xy 122.475503 -24.751796) (xy 122.487629 -24.697359) (xy 122.507552 -24.645268)
			(xy 122.534848 -24.596633) (xy 122.568934 -24.55249) (xy 122.609083 -24.513781) (xy 122.654441 -24.48133)
			(xy 122.704041 -24.455829) (xy 122.756825 -24.437822) (xy 122.811668 -24.427692) (xy 122.867402 -24.425655)
			(xy 122.922839 -24.431755) (xy 122.976796 -24.445861) (xy 123.028125 -24.467673) (xy 123.075731 -24.496727)
			(xy 123.118599 -24.532402) (xy 123.155816 -24.573939) (xy 123.186589 -24.620452) (xy 123.210261 -24.670949)
			(xy 123.226329 -24.724356) (xy 123.234449 -24.779532) (xy 123.234958 -24.807418) (xy 124.720348 -24.807418)
			(xy 124.724419 -24.751796) (xy 124.736545 -24.697359) (xy 124.756468 -24.645268) (xy 124.783764 -24.596633)
			(xy 124.81785 -24.55249) (xy 124.857999 -24.513781) (xy 124.903357 -24.48133) (xy 124.952957 -24.455829)
			(xy 125.005741 -24.437822) (xy 125.060584 -24.427692) (xy 125.116318 -24.425655) (xy 125.171755 -24.431755)
			(xy 125.225712 -24.445861) (xy 125.277041 -24.467673) (xy 125.324647 -24.496727) (xy 125.367515 -24.532402)
			(xy 125.404732 -24.573939) (xy 125.435505 -24.620452) (xy 125.459177 -24.670949) (xy 125.475245 -24.724356)
			(xy 125.483365 -24.779532) (xy 125.483874 -24.807418) (xy 125.483365 -24.835304) (xy 125.475245 -24.89048)
			(xy 125.459177 -24.943887) (xy 125.435505 -24.994384) (xy 125.404732 -25.040897) (xy 125.367515 -25.082434)
			(xy 125.324647 -25.118109) (xy 125.277041 -25.147163) (xy 125.225712 -25.168975) (xy 125.171755 -25.183081)
			(xy 125.116318 -25.189181) (xy 125.060584 -25.187144) (xy 125.005741 -25.177014) (xy 124.952957 -25.159007)
			(xy 124.903357 -25.133506) (xy 124.857999 -25.101055) (xy 124.81785 -25.062346) (xy 124.783764 -25.018203)
			(xy 124.756468 -24.969568) (xy 124.736545 -24.917477) (xy 124.724419 -24.86304) (xy 124.720348 -24.807418)
			(xy 123.234958 -24.807418) (xy 123.234449 -24.835304) (xy 123.226329 -24.89048) (xy 123.210261 -24.943887)
			(xy 123.186589 -24.994384) (xy 123.155816 -25.040897) (xy 123.118599 -25.082434) (xy 123.075731 -25.118109)
			(xy 123.028125 -25.147163) (xy 122.976796 -25.168975) (xy 122.922839 -25.183081) (xy 122.867402 -25.189181)
			(xy 122.811668 -25.187144) (xy 122.756825 -25.177014) (xy 122.704041 -25.159007) (xy 122.654441 -25.133506)
			(xy 122.609083 -25.101055) (xy 122.568934 -25.062346) (xy 122.534848 -25.018203) (xy 122.507552 -24.969568)
			(xy 122.487629 -24.917477) (xy 122.475503 -24.86304) (xy 122.471432 -24.807418) (xy 99.628426 -24.807418)
			(xy 99.623379 -24.841712) (xy 99.607311 -24.895119) (xy 99.583639 -24.945616) (xy 99.552866 -24.992129)
			(xy 99.515649 -25.033666) (xy 99.472781 -25.069341) (xy 99.425175 -25.098395) (xy 99.373846 -25.120207)
			(xy 99.319889 -25.134313) (xy 99.264452 -25.140413) (xy 99.208718 -25.138376) (xy 99.153875 -25.128246)
			(xy 99.101091 -25.110239) (xy 99.051491 -25.084738) (xy 99.006133 -25.052287) (xy 98.965984 -25.013578)
			(xy 98.931898 -24.969435) (xy 98.904602 -24.9208) (xy 98.884679 -24.868709) (xy 98.872553 -24.814272)
			(xy 98.868482 -24.75865) (xy 96.836467 -24.75865) (xy 96.87215 -24.798475) (xy 96.902923 -24.844988)
			(xy 96.926595 -24.895485) (xy 96.942663 -24.948892) (xy 96.950783 -25.004068) (xy 96.951292 -25.031954)
			(xy 96.950783 -25.05984) (xy 96.942663 -25.115016) (xy 96.926595 -25.168423) (xy 96.902923 -25.21892)
			(xy 96.87215 -25.265433) (xy 96.834933 -25.30697) (xy 96.792065 -25.342645) (xy 96.744459 -25.371699)
			(xy 96.69313 -25.393511) (xy 96.639173 -25.407617) (xy 96.583736 -25.413717) (xy 96.528002 -25.41168)
			(xy 96.473159 -25.40155) (xy 96.420375 -25.383543) (xy 96.370775 -25.358042) (xy 96.325417 -25.325591)
			(xy 96.285268 -25.286882) (xy 96.251182 -25.242739) (xy 96.223886 -25.194104) (xy 96.203963 -25.142013)
			(xy 96.191837 -25.087576) (xy 96.187766 -25.031954) (xy 92.322465 -25.031954) (xy 92.365753 -25.050349)
			(xy 92.413359 -25.079403) (xy 92.456227 -25.115078) (xy 92.493444 -25.156615) (xy 92.524217 -25.203128)
			(xy 92.547889 -25.253625) (xy 92.563957 -25.307032) (xy 92.572077 -25.362208) (xy 92.572586 -25.390094)
			(xy 92.572077 -25.41798) (xy 92.563957 -25.473156) (xy 92.547889 -25.526563) (xy 92.5328 -25.55875)
			(xy 100.641656 -25.55875) (xy 100.645727 -25.503128) (xy 100.657853 -25.448691) (xy 100.677776 -25.3966)
			(xy 100.705072 -25.347965) (xy 100.739158 -25.303822) (xy 100.779307 -25.265113) (xy 100.824665 -25.232662)
			(xy 100.874265 -25.207161) (xy 100.927049 -25.189154) (xy 100.981892 -25.179024) (xy 101.037626 -25.176987)
			(xy 101.093063 -25.183087) (xy 101.14702 -25.197193) (xy 101.198349 -25.219005) (xy 101.245955 -25.248059)
			(xy 101.288823 -25.283734) (xy 101.32604 -25.325271) (xy 101.356813 -25.371784) (xy 101.365396 -25.390094)
			(xy 129.909314 -25.390094) (xy 129.913385 -25.334472) (xy 129.925511 -25.280035) (xy 129.945434 -25.227944)
			(xy 129.97273 -25.179309) (xy 130.006816 -25.135166) (xy 130.046965 -25.096457) (xy 130.092323 -25.064006)
			(xy 130.141923 -25.038505) (xy 130.194707 -25.020498) (xy 130.24955 -25.010368) (xy 130.305284 -25.008331)
			(xy 130.360721 -25.014431) (xy 130.414678 -25.028537) (xy 130.422719 -25.031954) (xy 134.28802 -25.031954)
			(xy 134.292091 -24.976332) (xy 134.304217 -24.921895) (xy 134.32414 -24.869804) (xy 134.351436 -24.821169)
			(xy 134.385522 -24.777026) (xy 134.425671 -24.738317) (xy 134.471029 -24.705866) (xy 134.520629 -24.680365)
			(xy 134.573413 -24.662358) (xy 134.628256 -24.652228) (xy 134.68399 -24.650191) (xy 134.739427 -24.656291)
			(xy 134.793384 -24.670397) (xy 134.844713 -24.692209) (xy 134.892319 -24.721263) (xy 134.935187 -24.756938)
			(xy 134.936721 -24.75865) (xy 136.968736 -24.75865) (xy 136.972807 -24.703028) (xy 136.984933 -24.648591)
			(xy 137.004856 -24.5965) (xy 137.032152 -24.547865) (xy 137.066238 -24.503722) (xy 137.106387 -24.465013)
			(xy 137.151745 -24.432562) (xy 137.201345 -24.407061) (xy 137.254129 -24.389054) (xy 137.308972 -24.378924)
			(xy 137.364706 -24.376887) (xy 137.420143 -24.382987) (xy 137.4741 -24.397093) (xy 137.525429 -24.418905)
			(xy 137.573035 -24.447959) (xy 137.615903 -24.483634) (xy 137.65312 -24.525171) (xy 137.683893 -24.571684)
			(xy 137.707565 -24.622181) (xy 137.723633 -24.675588) (xy 137.731753 -24.730764) (xy 137.732262 -24.75865)
			(xy 137.731753 -24.786536) (xy 137.72868 -24.807418) (xy 148.47138 -24.807418) (xy 148.475451 -24.751796)
			(xy 148.487577 -24.697359) (xy 148.5075 -24.645268) (xy 148.534796 -24.596633) (xy 148.568882 -24.55249)
			(xy 148.609031 -24.513781) (xy 148.654389 -24.48133) (xy 148.703989 -24.455829) (xy 148.756773 -24.437822)
			(xy 148.811616 -24.427692) (xy 148.86735 -24.425655) (xy 148.922787 -24.431755) (xy 148.976744 -24.445861)
			(xy 149.028073 -24.467673) (xy 149.075679 -24.496727) (xy 149.118547 -24.532402) (xy 149.155764 -24.573939)
			(xy 149.186537 -24.620452) (xy 149.210209 -24.670949) (xy 149.226277 -24.724356) (xy 149.234397 -24.779532)
			(xy 149.234906 -24.807418) (xy 150.720296 -24.807418) (xy 150.724367 -24.751796) (xy 150.736493 -24.697359)
			(xy 150.756416 -24.645268) (xy 150.783712 -24.596633) (xy 150.817798 -24.55249) (xy 150.857947 -24.513781)
			(xy 150.903305 -24.48133) (xy 150.952905 -24.455829) (xy 151.005689 -24.437822) (xy 151.060532 -24.427692)
			(xy 151.116266 -24.425655) (xy 151.171703 -24.431755) (xy 151.22566 -24.445861) (xy 151.276989 -24.467673)
			(xy 151.324595 -24.496727) (xy 151.367463 -24.532402) (xy 151.40468 -24.573939) (xy 151.435453 -24.620452)
			(xy 151.459125 -24.670949) (xy 151.475193 -24.724356) (xy 151.483313 -24.779532) (xy 151.483822 -24.807418)
			(xy 151.483313 -24.835304) (xy 151.475193 -24.89048) (xy 151.459125 -24.943887) (xy 151.435453 -24.994384)
			(xy 151.40468 -25.040897) (xy 151.367463 -25.082434) (xy 151.324595 -25.118109) (xy 151.276989 -25.147163)
			(xy 151.22566 -25.168975) (xy 151.171703 -25.183081) (xy 151.116266 -25.189181) (xy 151.060532 -25.187144)
			(xy 151.005689 -25.177014) (xy 150.952905 -25.159007) (xy 150.903305 -25.133506) (xy 150.857947 -25.101055)
			(xy 150.817798 -25.062346) (xy 150.783712 -25.018203) (xy 150.756416 -24.969568) (xy 150.736493 -24.917477)
			(xy 150.724367 -24.86304) (xy 150.720296 -24.807418) (xy 149.234906 -24.807418) (xy 149.234397 -24.835304)
			(xy 149.226277 -24.89048) (xy 149.210209 -24.943887) (xy 149.186537 -24.994384) (xy 149.155764 -25.040897)
			(xy 149.118547 -25.082434) (xy 149.075679 -25.118109) (xy 149.028073 -25.147163) (xy 148.976744 -25.168975)
			(xy 148.922787 -25.183081) (xy 148.86735 -25.189181) (xy 148.811616 -25.187144) (xy 148.756773 -25.177014)
			(xy 148.703989 -25.159007) (xy 148.654389 -25.133506) (xy 148.609031 -25.101055) (xy 148.568882 -25.062346)
			(xy 148.534796 -25.018203) (xy 148.5075 -24.969568) (xy 148.487577 -24.917477) (xy 148.475451 -24.86304)
			(xy 148.47138 -24.807418) (xy 137.72868 -24.807418) (xy 137.723633 -24.841712) (xy 137.707565 -24.895119)
			(xy 137.683893 -24.945616) (xy 137.65312 -24.992129) (xy 137.615903 -25.033666) (xy 137.573035 -25.069341)
			(xy 137.525429 -25.098395) (xy 137.4741 -25.120207) (xy 137.420143 -25.134313) (xy 137.364706 -25.140413)
			(xy 137.308972 -25.138376) (xy 137.254129 -25.128246) (xy 137.201345 -25.110239) (xy 137.151745 -25.084738)
			(xy 137.106387 -25.052287) (xy 137.066238 -25.013578) (xy 137.032152 -24.969435) (xy 137.004856 -24.9208)
			(xy 136.984933 -24.868709) (xy 136.972807 -24.814272) (xy 136.968736 -24.75865) (xy 134.936721 -24.75865)
			(xy 134.972404 -24.798475) (xy 135.003177 -24.844988) (xy 135.026849 -24.895485) (xy 135.042917 -24.948892)
			(xy 135.051037 -25.004068) (xy 135.051546 -25.031954) (xy 135.051037 -25.05984) (xy 135.042917 -25.115016)
			(xy 135.026849 -25.168423) (xy 135.003177 -25.21892) (xy 134.972404 -25.265433) (xy 134.935187 -25.30697)
			(xy 134.892319 -25.342645) (xy 134.844713 -25.371699) (xy 134.793384 -25.393511) (xy 134.739427 -25.407617)
			(xy 134.68399 -25.413717) (xy 134.628256 -25.41168) (xy 134.573413 -25.40155) (xy 134.520629 -25.383543)
			(xy 134.471029 -25.358042) (xy 134.425671 -25.325591) (xy 134.385522 -25.286882) (xy 134.351436 -25.242739)
			(xy 134.32414 -25.194104) (xy 134.304217 -25.142013) (xy 134.292091 -25.087576) (xy 134.28802 -25.031954)
			(xy 130.422719 -25.031954) (xy 130.466007 -25.050349) (xy 130.513613 -25.079403) (xy 130.556481 -25.115078)
			(xy 130.593698 -25.156615) (xy 130.624471 -25.203128) (xy 130.648143 -25.253625) (xy 130.664211 -25.307032)
			(xy 130.672331 -25.362208) (xy 130.67284 -25.390094) (xy 130.672331 -25.41798) (xy 130.664211 -25.473156)
			(xy 130.648143 -25.526563) (xy 130.633054 -25.55875) (xy 138.74191 -25.55875) (xy 138.745981 -25.503128)
			(xy 138.758107 -25.448691) (xy 138.77803 -25.3966) (xy 138.805326 -25.347965) (xy 138.839412 -25.303822)
			(xy 138.879561 -25.265113) (xy 138.924919 -25.232662) (xy 138.974519 -25.207161) (xy 139.027303 -25.189154)
			(xy 139.082146 -25.179024) (xy 139.13788 -25.176987) (xy 139.193317 -25.183087) (xy 139.247274 -25.197193)
			(xy 139.298603 -25.219005) (xy 139.346209 -25.248059) (xy 139.389077 -25.283734) (xy 139.426294 -25.325271)
			(xy 139.457067 -25.371784) (xy 139.46565 -25.390094) (xy 155.909262 -25.390094) (xy 155.913333 -25.334472)
			(xy 155.925459 -25.280035) (xy 155.945382 -25.227944) (xy 155.972678 -25.179309) (xy 156.006764 -25.135166)
			(xy 156.046913 -25.096457) (xy 156.092271 -25.064006) (xy 156.141871 -25.038505) (xy 156.194655 -25.020498)
			(xy 156.249498 -25.010368) (xy 156.305232 -25.008331) (xy 156.360669 -25.014431) (xy 156.414626 -25.028537)
			(xy 156.422667 -25.031954) (xy 160.287968 -25.031954) (xy 160.292039 -24.976332) (xy 160.304165 -24.921895)
			(xy 160.324088 -24.869804) (xy 160.351384 -24.821169) (xy 160.38547 -24.777026) (xy 160.425619 -24.738317)
			(xy 160.470977 -24.705866) (xy 160.520577 -24.680365) (xy 160.573361 -24.662358) (xy 160.628204 -24.652228)
			(xy 160.683938 -24.650191) (xy 160.739375 -24.656291) (xy 160.793332 -24.670397) (xy 160.844661 -24.692209)
			(xy 160.892267 -24.721263) (xy 160.935135 -24.756938) (xy 160.936669 -24.75865) (xy 162.968684 -24.75865)
			(xy 162.972755 -24.703028) (xy 162.984881 -24.648591) (xy 163.004804 -24.5965) (xy 163.0321 -24.547865)
			(xy 163.066186 -24.503722) (xy 163.106335 -24.465013) (xy 163.151693 -24.432562) (xy 163.201293 -24.407061)
			(xy 163.254077 -24.389054) (xy 163.30892 -24.378924) (xy 163.364654 -24.376887) (xy 163.420091 -24.382987)
			(xy 163.474048 -24.397093) (xy 163.525377 -24.418905) (xy 163.572983 -24.447959) (xy 163.615851 -24.483634)
			(xy 163.653068 -24.525171) (xy 163.683841 -24.571684) (xy 163.707513 -24.622181) (xy 163.723581 -24.675588)
			(xy 163.731701 -24.730764) (xy 163.73221 -24.75865) (xy 163.731701 -24.786536) (xy 163.728628 -24.807418)
			(xy 174.471328 -24.807418) (xy 174.475399 -24.751796) (xy 174.487525 -24.697359) (xy 174.507448 -24.645268)
			(xy 174.534744 -24.596633) (xy 174.56883 -24.55249) (xy 174.608979 -24.513781) (xy 174.654337 -24.48133)
			(xy 174.703937 -24.455829) (xy 174.756721 -24.437822) (xy 174.811564 -24.427692) (xy 174.867298 -24.425655)
			(xy 174.922735 -24.431755) (xy 174.976692 -24.445861) (xy 175.028021 -24.467673) (xy 175.075627 -24.496727)
			(xy 175.118495 -24.532402) (xy 175.155712 -24.573939) (xy 175.186485 -24.620452) (xy 175.210157 -24.670949)
			(xy 175.226225 -24.724356) (xy 175.234345 -24.779532) (xy 175.234854 -24.807418) (xy 176.720244 -24.807418)
			(xy 176.724315 -24.751796) (xy 176.736441 -24.697359) (xy 176.756364 -24.645268) (xy 176.78366 -24.596633)
			(xy 176.817746 -24.55249) (xy 176.857895 -24.513781) (xy 176.903253 -24.48133) (xy 176.952853 -24.455829)
			(xy 177.005637 -24.437822) (xy 177.06048 -24.427692) (xy 177.116214 -24.425655) (xy 177.171651 -24.431755)
			(xy 177.225608 -24.445861) (xy 177.276937 -24.467673) (xy 177.324543 -24.496727) (xy 177.367411 -24.532402)
			(xy 177.404628 -24.573939) (xy 177.435401 -24.620452) (xy 177.459073 -24.670949) (xy 177.475141 -24.724356)
			(xy 177.483261 -24.779532) (xy 177.48377 -24.807418) (xy 177.483261 -24.835304) (xy 177.475141 -24.89048)
			(xy 177.459073 -24.943887) (xy 177.435401 -24.994384) (xy 177.404628 -25.040897) (xy 177.367411 -25.082434)
			(xy 177.324543 -25.118109) (xy 177.276937 -25.147163) (xy 177.225608 -25.168975) (xy 177.171651 -25.183081)
			(xy 177.116214 -25.189181) (xy 177.06048 -25.187144) (xy 177.005637 -25.177014) (xy 176.952853 -25.159007)
			(xy 176.903253 -25.133506) (xy 176.857895 -25.101055) (xy 176.817746 -25.062346) (xy 176.78366 -25.018203)
			(xy 176.756364 -24.969568) (xy 176.736441 -24.917477) (xy 176.724315 -24.86304) (xy 176.720244 -24.807418)
			(xy 175.234854 -24.807418) (xy 175.234345 -24.835304) (xy 175.226225 -24.89048) (xy 175.210157 -24.943887)
			(xy 175.186485 -24.994384) (xy 175.155712 -25.040897) (xy 175.118495 -25.082434) (xy 175.075627 -25.118109)
			(xy 175.028021 -25.147163) (xy 174.976692 -25.168975) (xy 174.922735 -25.183081) (xy 174.867298 -25.189181)
			(xy 174.811564 -25.187144) (xy 174.756721 -25.177014) (xy 174.703937 -25.159007) (xy 174.654337 -25.133506)
			(xy 174.608979 -25.101055) (xy 174.56883 -25.062346) (xy 174.534744 -25.018203) (xy 174.507448 -24.969568)
			(xy 174.487525 -24.917477) (xy 174.475399 -24.86304) (xy 174.471328 -24.807418) (xy 163.728628 -24.807418)
			(xy 163.723581 -24.841712) (xy 163.707513 -24.895119) (xy 163.683841 -24.945616) (xy 163.653068 -24.992129)
			(xy 163.615851 -25.033666) (xy 163.572983 -25.069341) (xy 163.525377 -25.098395) (xy 163.474048 -25.120207)
			(xy 163.420091 -25.134313) (xy 163.364654 -25.140413) (xy 163.30892 -25.138376) (xy 163.254077 -25.128246)
			(xy 163.201293 -25.110239) (xy 163.151693 -25.084738) (xy 163.106335 -25.052287) (xy 163.066186 -25.013578)
			(xy 163.0321 -24.969435) (xy 163.004804 -24.9208) (xy 162.984881 -24.868709) (xy 162.972755 -24.814272)
			(xy 162.968684 -24.75865) (xy 160.936669 -24.75865) (xy 160.972352 -24.798475) (xy 161.003125 -24.844988)
			(xy 161.026797 -24.895485) (xy 161.042865 -24.948892) (xy 161.050985 -25.004068) (xy 161.051494 -25.031954)
			(xy 161.050985 -25.05984) (xy 161.042865 -25.115016) (xy 161.026797 -25.168423) (xy 161.003125 -25.21892)
			(xy 160.972352 -25.265433) (xy 160.935135 -25.30697) (xy 160.892267 -25.342645) (xy 160.844661 -25.371699)
			(xy 160.793332 -25.393511) (xy 160.739375 -25.407617) (xy 160.683938 -25.413717) (xy 160.628204 -25.41168)
			(xy 160.573361 -25.40155) (xy 160.520577 -25.383543) (xy 160.470977 -25.358042) (xy 160.425619 -25.325591)
			(xy 160.38547 -25.286882) (xy 160.351384 -25.242739) (xy 160.324088 -25.194104) (xy 160.304165 -25.142013)
			(xy 160.292039 -25.087576) (xy 160.287968 -25.031954) (xy 156.422667 -25.031954) (xy 156.465955 -25.050349)
			(xy 156.513561 -25.079403) (xy 156.556429 -25.115078) (xy 156.593646 -25.156615) (xy 156.624419 -25.203128)
			(xy 156.648091 -25.253625) (xy 156.664159 -25.307032) (xy 156.672279 -25.362208) (xy 156.672788 -25.390094)
			(xy 156.672279 -25.41798) (xy 156.664159 -25.473156) (xy 156.648091 -25.526563) (xy 156.633002 -25.55875)
			(xy 164.741858 -25.55875) (xy 164.745929 -25.503128) (xy 164.758055 -25.448691) (xy 164.777978 -25.3966)
			(xy 164.805274 -25.347965) (xy 164.83936 -25.303822) (xy 164.879509 -25.265113) (xy 164.924867 -25.232662)
			(xy 164.974467 -25.207161) (xy 165.027251 -25.189154) (xy 165.082094 -25.179024) (xy 165.137828 -25.176987)
			(xy 165.193265 -25.183087) (xy 165.247222 -25.197193) (xy 165.298551 -25.219005) (xy 165.346157 -25.248059)
			(xy 165.389025 -25.283734) (xy 165.426242 -25.325271) (xy 165.457015 -25.371784) (xy 165.465598 -25.390094)
			(xy 181.90921 -25.390094) (xy 181.913281 -25.334472) (xy 181.925407 -25.280035) (xy 181.94533 -25.227944)
			(xy 181.972626 -25.179309) (xy 182.006712 -25.135166) (xy 182.046861 -25.096457) (xy 182.092219 -25.064006)
			(xy 182.141819 -25.038505) (xy 182.194603 -25.020498) (xy 182.249446 -25.010368) (xy 182.30518 -25.008331)
			(xy 182.360617 -25.014431) (xy 182.414574 -25.028537) (xy 182.422615 -25.031954) (xy 186.287916 -25.031954)
			(xy 186.291987 -24.976332) (xy 186.304113 -24.921895) (xy 186.324036 -24.869804) (xy 186.351332 -24.821169)
			(xy 186.385418 -24.777026) (xy 186.425567 -24.738317) (xy 186.470925 -24.705866) (xy 186.520525 -24.680365)
			(xy 186.573309 -24.662358) (xy 186.628152 -24.652228) (xy 186.683886 -24.650191) (xy 186.739323 -24.656291)
			(xy 186.79328 -24.670397) (xy 186.844609 -24.692209) (xy 186.892215 -24.721263) (xy 186.935083 -24.756938)
			(xy 186.936617 -24.75865) (xy 188.968632 -24.75865) (xy 188.972703 -24.703028) (xy 188.984829 -24.648591)
			(xy 189.004752 -24.5965) (xy 189.032048 -24.547865) (xy 189.066134 -24.503722) (xy 189.106283 -24.465013)
			(xy 189.151641 -24.432562) (xy 189.201241 -24.407061) (xy 189.254025 -24.389054) (xy 189.308868 -24.378924)
			(xy 189.364602 -24.376887) (xy 189.420039 -24.382987) (xy 189.473996 -24.397093) (xy 189.525325 -24.418905)
			(xy 189.572931 -24.447959) (xy 189.615799 -24.483634) (xy 189.653016 -24.525171) (xy 189.683789 -24.571684)
			(xy 189.707461 -24.622181) (xy 189.723529 -24.675588) (xy 189.731649 -24.730764) (xy 189.732158 -24.75865)
			(xy 189.731649 -24.786536) (xy 189.728576 -24.807418) (xy 200.471276 -24.807418) (xy 200.475347 -24.751796)
			(xy 200.487473 -24.697359) (xy 200.507396 -24.645268) (xy 200.534692 -24.596633) (xy 200.568778 -24.55249)
			(xy 200.608927 -24.513781) (xy 200.654285 -24.48133) (xy 200.703885 -24.455829) (xy 200.756669 -24.437822)
			(xy 200.811512 -24.427692) (xy 200.867246 -24.425655) (xy 200.922683 -24.431755) (xy 200.97664 -24.445861)
			(xy 201.027969 -24.467673) (xy 201.075575 -24.496727) (xy 201.118443 -24.532402) (xy 201.15566 -24.573939)
			(xy 201.186433 -24.620452) (xy 201.210105 -24.670949) (xy 201.226173 -24.724356) (xy 201.234293 -24.779532)
			(xy 201.234802 -24.807418) (xy 202.720192 -24.807418) (xy 202.724263 -24.751796) (xy 202.736389 -24.697359)
			(xy 202.756312 -24.645268) (xy 202.783608 -24.596633) (xy 202.817694 -24.55249) (xy 202.857843 -24.513781)
			(xy 202.903201 -24.48133) (xy 202.952801 -24.455829) (xy 203.005585 -24.437822) (xy 203.060428 -24.427692)
			(xy 203.116162 -24.425655) (xy 203.171599 -24.431755) (xy 203.225556 -24.445861) (xy 203.276885 -24.467673)
			(xy 203.324491 -24.496727) (xy 203.367359 -24.532402) (xy 203.404576 -24.573939) (xy 203.435349 -24.620452)
			(xy 203.459021 -24.670949) (xy 203.475089 -24.724356) (xy 203.483209 -24.779532) (xy 203.483718 -24.807418)
			(xy 203.483209 -24.835304) (xy 203.475089 -24.89048) (xy 203.459021 -24.943887) (xy 203.435349 -24.994384)
			(xy 203.404576 -25.040897) (xy 203.367359 -25.082434) (xy 203.324491 -25.118109) (xy 203.276885 -25.147163)
			(xy 203.225556 -25.168975) (xy 203.171599 -25.183081) (xy 203.116162 -25.189181) (xy 203.060428 -25.187144)
			(xy 203.005585 -25.177014) (xy 202.952801 -25.159007) (xy 202.903201 -25.133506) (xy 202.857843 -25.101055)
			(xy 202.817694 -25.062346) (xy 202.783608 -25.018203) (xy 202.756312 -24.969568) (xy 202.736389 -24.917477)
			(xy 202.724263 -24.86304) (xy 202.720192 -24.807418) (xy 201.234802 -24.807418) (xy 201.234293 -24.835304)
			(xy 201.226173 -24.89048) (xy 201.210105 -24.943887) (xy 201.186433 -24.994384) (xy 201.15566 -25.040897)
			(xy 201.118443 -25.082434) (xy 201.075575 -25.118109) (xy 201.027969 -25.147163) (xy 200.97664 -25.168975)
			(xy 200.922683 -25.183081) (xy 200.867246 -25.189181) (xy 200.811512 -25.187144) (xy 200.756669 -25.177014)
			(xy 200.703885 -25.159007) (xy 200.654285 -25.133506) (xy 200.608927 -25.101055) (xy 200.568778 -25.062346)
			(xy 200.534692 -25.018203) (xy 200.507396 -24.969568) (xy 200.487473 -24.917477) (xy 200.475347 -24.86304)
			(xy 200.471276 -24.807418) (xy 189.728576 -24.807418) (xy 189.723529 -24.841712) (xy 189.707461 -24.895119)
			(xy 189.683789 -24.945616) (xy 189.653016 -24.992129) (xy 189.615799 -25.033666) (xy 189.572931 -25.069341)
			(xy 189.525325 -25.098395) (xy 189.473996 -25.120207) (xy 189.420039 -25.134313) (xy 189.364602 -25.140413)
			(xy 189.308868 -25.138376) (xy 189.254025 -25.128246) (xy 189.201241 -25.110239) (xy 189.151641 -25.084738)
			(xy 189.106283 -25.052287) (xy 189.066134 -25.013578) (xy 189.032048 -24.969435) (xy 189.004752 -24.9208)
			(xy 188.984829 -24.868709) (xy 188.972703 -24.814272) (xy 188.968632 -24.75865) (xy 186.936617 -24.75865)
			(xy 186.9723 -24.798475) (xy 187.003073 -24.844988) (xy 187.026745 -24.895485) (xy 187.042813 -24.948892)
			(xy 187.050933 -25.004068) (xy 187.051442 -25.031954) (xy 187.050933 -25.05984) (xy 187.042813 -25.115016)
			(xy 187.026745 -25.168423) (xy 187.003073 -25.21892) (xy 186.9723 -25.265433) (xy 186.935083 -25.30697)
			(xy 186.892215 -25.342645) (xy 186.844609 -25.371699) (xy 186.79328 -25.393511) (xy 186.739323 -25.407617)
			(xy 186.683886 -25.413717) (xy 186.628152 -25.41168) (xy 186.573309 -25.40155) (xy 186.520525 -25.383543)
			(xy 186.470925 -25.358042) (xy 186.425567 -25.325591) (xy 186.385418 -25.286882) (xy 186.351332 -25.242739)
			(xy 186.324036 -25.194104) (xy 186.304113 -25.142013) (xy 186.291987 -25.087576) (xy 186.287916 -25.031954)
			(xy 182.422615 -25.031954) (xy 182.465903 -25.050349) (xy 182.513509 -25.079403) (xy 182.556377 -25.115078)
			(xy 182.593594 -25.156615) (xy 182.624367 -25.203128) (xy 182.648039 -25.253625) (xy 182.664107 -25.307032)
			(xy 182.672227 -25.362208) (xy 182.672736 -25.390094) (xy 182.672227 -25.41798) (xy 182.664107 -25.473156)
			(xy 182.648039 -25.526563) (xy 182.63295 -25.55875) (xy 190.741806 -25.55875) (xy 190.745877 -25.503128)
			(xy 190.758003 -25.448691) (xy 190.777926 -25.3966) (xy 190.805222 -25.347965) (xy 190.839308 -25.303822)
			(xy 190.879457 -25.265113) (xy 190.924815 -25.232662) (xy 190.974415 -25.207161) (xy 191.027199 -25.189154)
			(xy 191.082042 -25.179024) (xy 191.137776 -25.176987) (xy 191.193213 -25.183087) (xy 191.24717 -25.197193)
			(xy 191.298499 -25.219005) (xy 191.346105 -25.248059) (xy 191.388973 -25.283734) (xy 191.42619 -25.325271)
			(xy 191.456963 -25.371784) (xy 191.465546 -25.390094) (xy 207.909158 -25.390094) (xy 207.913229 -25.334472)
			(xy 207.925355 -25.280035) (xy 207.945278 -25.227944) (xy 207.972574 -25.179309) (xy 208.00666 -25.135166)
			(xy 208.046809 -25.096457) (xy 208.092167 -25.064006) (xy 208.141767 -25.038505) (xy 208.194551 -25.020498)
			(xy 208.249394 -25.010368) (xy 208.305128 -25.008331) (xy 208.360565 -25.014431) (xy 208.414522 -25.028537)
			(xy 208.422563 -25.031954) (xy 212.287864 -25.031954) (xy 212.291935 -24.976332) (xy 212.304061 -24.921895)
			(xy 212.323984 -24.869804) (xy 212.35128 -24.821169) (xy 212.385366 -24.777026) (xy 212.425515 -24.738317)
			(xy 212.470873 -24.705866) (xy 212.520473 -24.680365) (xy 212.573257 -24.662358) (xy 212.6281 -24.652228)
			(xy 212.683834 -24.650191) (xy 212.739271 -24.656291) (xy 212.793228 -24.670397) (xy 212.844557 -24.692209)
			(xy 212.892163 -24.721263) (xy 212.935031 -24.756938) (xy 212.936565 -24.75865) (xy 214.96858 -24.75865)
			(xy 214.972651 -24.703028) (xy 214.984777 -24.648591) (xy 215.0047 -24.5965) (xy 215.031996 -24.547865)
			(xy 215.066082 -24.503722) (xy 215.106231 -24.465013) (xy 215.151589 -24.432562) (xy 215.201189 -24.407061)
			(xy 215.253973 -24.389054) (xy 215.308816 -24.378924) (xy 215.36455 -24.376887) (xy 215.419987 -24.382987)
			(xy 215.473944 -24.397093) (xy 215.525273 -24.418905) (xy 215.572879 -24.447959) (xy 215.615747 -24.483634)
			(xy 215.652964 -24.525171) (xy 215.683737 -24.571684) (xy 215.707409 -24.622181) (xy 215.723477 -24.675588)
			(xy 215.731597 -24.730764) (xy 215.732106 -24.75865) (xy 215.731597 -24.786536) (xy 215.728524 -24.807418)
			(xy 238.571276 -24.807418) (xy 238.575347 -24.751796) (xy 238.587473 -24.697359) (xy 238.607396 -24.645268)
			(xy 238.634692 -24.596633) (xy 238.668778 -24.55249) (xy 238.708927 -24.513781) (xy 238.754285 -24.48133)
			(xy 238.803885 -24.455829) (xy 238.856669 -24.437822) (xy 238.911512 -24.427692) (xy 238.967246 -24.425655)
			(xy 239.022683 -24.431755) (xy 239.07664 -24.445861) (xy 239.127969 -24.467673) (xy 239.175575 -24.496727)
			(xy 239.218443 -24.532402) (xy 239.25566 -24.573939) (xy 239.286433 -24.620452) (xy 239.310105 -24.670949)
			(xy 239.326173 -24.724356) (xy 239.334293 -24.779532) (xy 239.334802 -24.807418) (xy 240.820192 -24.807418)
			(xy 240.824263 -24.751796) (xy 240.836389 -24.697359) (xy 240.856312 -24.645268) (xy 240.883608 -24.596633)
			(xy 240.917694 -24.55249) (xy 240.957843 -24.513781) (xy 241.003201 -24.48133) (xy 241.052801 -24.455829)
			(xy 241.105585 -24.437822) (xy 241.160428 -24.427692) (xy 241.216162 -24.425655) (xy 241.271599 -24.431755)
			(xy 241.325556 -24.445861) (xy 241.376885 -24.467673) (xy 241.424491 -24.496727) (xy 241.467359 -24.532402)
			(xy 241.504576 -24.573939) (xy 241.535349 -24.620452) (xy 241.559021 -24.670949) (xy 241.575089 -24.724356)
			(xy 241.583209 -24.779532) (xy 241.583718 -24.807418) (xy 241.583209 -24.835304) (xy 241.575089 -24.89048)
			(xy 241.559021 -24.943887) (xy 241.535349 -24.994384) (xy 241.504576 -25.040897) (xy 241.467359 -25.082434)
			(xy 241.424491 -25.118109) (xy 241.376885 -25.147163) (xy 241.325556 -25.168975) (xy 241.271599 -25.183081)
			(xy 241.216162 -25.189181) (xy 241.160428 -25.187144) (xy 241.105585 -25.177014) (xy 241.052801 -25.159007)
			(xy 241.003201 -25.133506) (xy 240.957843 -25.101055) (xy 240.917694 -25.062346) (xy 240.883608 -25.018203)
			(xy 240.856312 -24.969568) (xy 240.836389 -24.917477) (xy 240.824263 -24.86304) (xy 240.820192 -24.807418)
			(xy 239.334802 -24.807418) (xy 239.334293 -24.835304) (xy 239.326173 -24.89048) (xy 239.310105 -24.943887)
			(xy 239.286433 -24.994384) (xy 239.25566 -25.040897) (xy 239.218443 -25.082434) (xy 239.175575 -25.118109)
			(xy 239.127969 -25.147163) (xy 239.07664 -25.168975) (xy 239.022683 -25.183081) (xy 238.967246 -25.189181)
			(xy 238.911512 -25.187144) (xy 238.856669 -25.177014) (xy 238.803885 -25.159007) (xy 238.754285 -25.133506)
			(xy 238.708927 -25.101055) (xy 238.668778 -25.062346) (xy 238.634692 -25.018203) (xy 238.607396 -24.969568)
			(xy 238.587473 -24.917477) (xy 238.575347 -24.86304) (xy 238.571276 -24.807418) (xy 215.728524 -24.807418)
			(xy 215.723477 -24.841712) (xy 215.707409 -24.895119) (xy 215.683737 -24.945616) (xy 215.652964 -24.992129)
			(xy 215.615747 -25.033666) (xy 215.572879 -25.069341) (xy 215.525273 -25.098395) (xy 215.473944 -25.120207)
			(xy 215.419987 -25.134313) (xy 215.36455 -25.140413) (xy 215.308816 -25.138376) (xy 215.253973 -25.128246)
			(xy 215.201189 -25.110239) (xy 215.151589 -25.084738) (xy 215.106231 -25.052287) (xy 215.066082 -25.013578)
			(xy 215.031996 -24.969435) (xy 215.0047 -24.9208) (xy 214.984777 -24.868709) (xy 214.972651 -24.814272)
			(xy 214.96858 -24.75865) (xy 212.936565 -24.75865) (xy 212.972248 -24.798475) (xy 213.003021 -24.844988)
			(xy 213.026693 -24.895485) (xy 213.042761 -24.948892) (xy 213.050881 -25.004068) (xy 213.05139 -25.031954)
			(xy 213.050881 -25.05984) (xy 213.042761 -25.115016) (xy 213.026693 -25.168423) (xy 213.003021 -25.21892)
			(xy 212.972248 -25.265433) (xy 212.935031 -25.30697) (xy 212.892163 -25.342645) (xy 212.844557 -25.371699)
			(xy 212.793228 -25.393511) (xy 212.739271 -25.407617) (xy 212.683834 -25.413717) (xy 212.6281 -25.41168)
			(xy 212.573257 -25.40155) (xy 212.520473 -25.383543) (xy 212.470873 -25.358042) (xy 212.425515 -25.325591)
			(xy 212.385366 -25.286882) (xy 212.35128 -25.242739) (xy 212.323984 -25.194104) (xy 212.304061 -25.142013)
			(xy 212.291935 -25.087576) (xy 212.287864 -25.031954) (xy 208.422563 -25.031954) (xy 208.465851 -25.050349)
			(xy 208.513457 -25.079403) (xy 208.556325 -25.115078) (xy 208.593542 -25.156615) (xy 208.624315 -25.203128)
			(xy 208.647987 -25.253625) (xy 208.664055 -25.307032) (xy 208.672175 -25.362208) (xy 208.672684 -25.390094)
			(xy 208.672175 -25.41798) (xy 208.664055 -25.473156) (xy 208.647987 -25.526563) (xy 208.632898 -25.55875)
			(xy 216.741754 -25.55875) (xy 216.745825 -25.503128) (xy 216.757951 -25.448691) (xy 216.777874 -25.3966)
			(xy 216.80517 -25.347965) (xy 216.839256 -25.303822) (xy 216.879405 -25.265113) (xy 216.924763 -25.232662)
			(xy 216.974363 -25.207161) (xy 217.027147 -25.189154) (xy 217.08199 -25.179024) (xy 217.137724 -25.176987)
			(xy 217.193161 -25.183087) (xy 217.247118 -25.197193) (xy 217.298447 -25.219005) (xy 217.346053 -25.248059)
			(xy 217.388921 -25.283734) (xy 217.426138 -25.325271) (xy 217.456911 -25.371784) (xy 217.465494 -25.390094)
			(xy 246.009158 -25.390094) (xy 246.013229 -25.334472) (xy 246.025355 -25.280035) (xy 246.045278 -25.227944)
			(xy 246.072574 -25.179309) (xy 246.10666 -25.135166) (xy 246.146809 -25.096457) (xy 246.192167 -25.064006)
			(xy 246.241767 -25.038505) (xy 246.294551 -25.020498) (xy 246.349394 -25.010368) (xy 246.405128 -25.008331)
			(xy 246.460565 -25.014431) (xy 246.514522 -25.028537) (xy 246.522563 -25.031954) (xy 250.387864 -25.031954)
			(xy 250.391935 -24.976332) (xy 250.404061 -24.921895) (xy 250.423984 -24.869804) (xy 250.45128 -24.821169)
			(xy 250.485366 -24.777026) (xy 250.525515 -24.738317) (xy 250.570873 -24.705866) (xy 250.620473 -24.680365)
			(xy 250.673257 -24.662358) (xy 250.7281 -24.652228) (xy 250.783834 -24.650191) (xy 250.839271 -24.656291)
			(xy 250.893228 -24.670397) (xy 250.944557 -24.692209) (xy 250.992163 -24.721263) (xy 251.035031 -24.756938)
			(xy 251.036565 -24.75865) (xy 253.06858 -24.75865) (xy 253.072651 -24.703028) (xy 253.084777 -24.648591)
			(xy 253.1047 -24.5965) (xy 253.131996 -24.547865) (xy 253.166082 -24.503722) (xy 253.206231 -24.465013)
			(xy 253.251589 -24.432562) (xy 253.301189 -24.407061) (xy 253.353973 -24.389054) (xy 253.408816 -24.378924)
			(xy 253.46455 -24.376887) (xy 253.519987 -24.382987) (xy 253.573944 -24.397093) (xy 253.625273 -24.418905)
			(xy 253.672879 -24.447959) (xy 253.715747 -24.483634) (xy 253.752964 -24.525171) (xy 253.783737 -24.571684)
			(xy 253.807409 -24.622181) (xy 253.823477 -24.675588) (xy 253.831597 -24.730764) (xy 253.832106 -24.75865)
			(xy 253.831597 -24.786536) (xy 253.828524 -24.807418) (xy 264.571224 -24.807418) (xy 264.575295 -24.751796)
			(xy 264.587421 -24.697359) (xy 264.607344 -24.645268) (xy 264.63464 -24.596633) (xy 264.668726 -24.55249)
			(xy 264.708875 -24.513781) (xy 264.754233 -24.48133) (xy 264.803833 -24.455829) (xy 264.856617 -24.437822)
			(xy 264.91146 -24.427692) (xy 264.967194 -24.425655) (xy 265.022631 -24.431755) (xy 265.076588 -24.445861)
			(xy 265.127917 -24.467673) (xy 265.175523 -24.496727) (xy 265.218391 -24.532402) (xy 265.255608 -24.573939)
			(xy 265.286381 -24.620452) (xy 265.310053 -24.670949) (xy 265.326121 -24.724356) (xy 265.334241 -24.779532)
			(xy 265.33475 -24.807418) (xy 266.82014 -24.807418) (xy 266.824211 -24.751796) (xy 266.836337 -24.697359)
			(xy 266.85626 -24.645268) (xy 266.883556 -24.596633) (xy 266.917642 -24.55249) (xy 266.957791 -24.513781)
			(xy 267.003149 -24.48133) (xy 267.052749 -24.455829) (xy 267.105533 -24.437822) (xy 267.160376 -24.427692)
			(xy 267.21611 -24.425655) (xy 267.271547 -24.431755) (xy 267.325504 -24.445861) (xy 267.376833 -24.467673)
			(xy 267.424439 -24.496727) (xy 267.467307 -24.532402) (xy 267.504524 -24.573939) (xy 267.535297 -24.620452)
			(xy 267.558969 -24.670949) (xy 267.575037 -24.724356) (xy 267.583157 -24.779532) (xy 267.583666 -24.807418)
			(xy 267.583157 -24.835304) (xy 267.575037 -24.89048) (xy 267.558969 -24.943887) (xy 267.535297 -24.994384)
			(xy 267.504524 -25.040897) (xy 267.467307 -25.082434) (xy 267.424439 -25.118109) (xy 267.376833 -25.147163)
			(xy 267.325504 -25.168975) (xy 267.271547 -25.183081) (xy 267.21611 -25.189181) (xy 267.160376 -25.187144)
			(xy 267.105533 -25.177014) (xy 267.052749 -25.159007) (xy 267.003149 -25.133506) (xy 266.957791 -25.101055)
			(xy 266.917642 -25.062346) (xy 266.883556 -25.018203) (xy 266.85626 -24.969568) (xy 266.836337 -24.917477)
			(xy 266.824211 -24.86304) (xy 266.82014 -24.807418) (xy 265.33475 -24.807418) (xy 265.334241 -24.835304)
			(xy 265.326121 -24.89048) (xy 265.310053 -24.943887) (xy 265.286381 -24.994384) (xy 265.255608 -25.040897)
			(xy 265.218391 -25.082434) (xy 265.175523 -25.118109) (xy 265.127917 -25.147163) (xy 265.076588 -25.168975)
			(xy 265.022631 -25.183081) (xy 264.967194 -25.189181) (xy 264.91146 -25.187144) (xy 264.856617 -25.177014)
			(xy 264.803833 -25.159007) (xy 264.754233 -25.133506) (xy 264.708875 -25.101055) (xy 264.668726 -25.062346)
			(xy 264.63464 -25.018203) (xy 264.607344 -24.969568) (xy 264.587421 -24.917477) (xy 264.575295 -24.86304)
			(xy 264.571224 -24.807418) (xy 253.828524 -24.807418) (xy 253.823477 -24.841712) (xy 253.807409 -24.895119)
			(xy 253.783737 -24.945616) (xy 253.752964 -24.992129) (xy 253.715747 -25.033666) (xy 253.672879 -25.069341)
			(xy 253.625273 -25.098395) (xy 253.573944 -25.120207) (xy 253.519987 -25.134313) (xy 253.46455 -25.140413)
			(xy 253.408816 -25.138376) (xy 253.353973 -25.128246) (xy 253.301189 -25.110239) (xy 253.251589 -25.084738)
			(xy 253.206231 -25.052287) (xy 253.166082 -25.013578) (xy 253.131996 -24.969435) (xy 253.1047 -24.9208)
			(xy 253.084777 -24.868709) (xy 253.072651 -24.814272) (xy 253.06858 -24.75865) (xy 251.036565 -24.75865)
			(xy 251.072248 -24.798475) (xy 251.103021 -24.844988) (xy 251.126693 -24.895485) (xy 251.142761 -24.948892)
			(xy 251.150881 -25.004068) (xy 251.15139 -25.031954) (xy 251.150881 -25.05984) (xy 251.142761 -25.115016)
			(xy 251.126693 -25.168423) (xy 251.103021 -25.21892) (xy 251.072248 -25.265433) (xy 251.035031 -25.30697)
			(xy 250.992163 -25.342645) (xy 250.944557 -25.371699) (xy 250.893228 -25.393511) (xy 250.839271 -25.407617)
			(xy 250.783834 -25.413717) (xy 250.7281 -25.41168) (xy 250.673257 -25.40155) (xy 250.620473 -25.383543)
			(xy 250.570873 -25.358042) (xy 250.525515 -25.325591) (xy 250.485366 -25.286882) (xy 250.45128 -25.242739)
			(xy 250.423984 -25.194104) (xy 250.404061 -25.142013) (xy 250.391935 -25.087576) (xy 250.387864 -25.031954)
			(xy 246.522563 -25.031954) (xy 246.565851 -25.050349) (xy 246.613457 -25.079403) (xy 246.656325 -25.115078)
			(xy 246.693542 -25.156615) (xy 246.724315 -25.203128) (xy 246.747987 -25.253625) (xy 246.764055 -25.307032)
			(xy 246.772175 -25.362208) (xy 246.772684 -25.390094) (xy 246.772175 -25.41798) (xy 246.764055 -25.473156)
			(xy 246.747987 -25.526563) (xy 246.732898 -25.55875) (xy 254.841754 -25.55875) (xy 254.845825 -25.503128)
			(xy 254.857951 -25.448691) (xy 254.877874 -25.3966) (xy 254.90517 -25.347965) (xy 254.939256 -25.303822)
			(xy 254.979405 -25.265113) (xy 255.024763 -25.232662) (xy 255.074363 -25.207161) (xy 255.127147 -25.189154)
			(xy 255.18199 -25.179024) (xy 255.237724 -25.176987) (xy 255.293161 -25.183087) (xy 255.347118 -25.197193)
			(xy 255.398447 -25.219005) (xy 255.446053 -25.248059) (xy 255.488921 -25.283734) (xy 255.526138 -25.325271)
			(xy 255.556911 -25.371784) (xy 255.565494 -25.390094) (xy 272.009106 -25.390094) (xy 272.013177 -25.334472)
			(xy 272.025303 -25.280035) (xy 272.045226 -25.227944) (xy 272.072522 -25.179309) (xy 272.106608 -25.135166)
			(xy 272.146757 -25.096457) (xy 272.192115 -25.064006) (xy 272.241715 -25.038505) (xy 272.294499 -25.020498)
			(xy 272.349342 -25.010368) (xy 272.405076 -25.008331) (xy 272.460513 -25.014431) (xy 272.51447 -25.028537)
			(xy 272.522511 -25.031954) (xy 276.387812 -25.031954) (xy 276.391883 -24.976332) (xy 276.404009 -24.921895)
			(xy 276.423932 -24.869804) (xy 276.451228 -24.821169) (xy 276.485314 -24.777026) (xy 276.525463 -24.738317)
			(xy 276.570821 -24.705866) (xy 276.620421 -24.680365) (xy 276.673205 -24.662358) (xy 276.728048 -24.652228)
			(xy 276.783782 -24.650191) (xy 276.839219 -24.656291) (xy 276.893176 -24.670397) (xy 276.944505 -24.692209)
			(xy 276.992111 -24.721263) (xy 277.034979 -24.756938) (xy 277.036513 -24.75865) (xy 279.068528 -24.75865)
			(xy 279.072599 -24.703028) (xy 279.084725 -24.648591) (xy 279.104648 -24.5965) (xy 279.131944 -24.547865)
			(xy 279.16603 -24.503722) (xy 279.206179 -24.465013) (xy 279.251537 -24.432562) (xy 279.301137 -24.407061)
			(xy 279.353921 -24.389054) (xy 279.408764 -24.378924) (xy 279.464498 -24.376887) (xy 279.519935 -24.382987)
			(xy 279.573892 -24.397093) (xy 279.625221 -24.418905) (xy 279.672827 -24.447959) (xy 279.715695 -24.483634)
			(xy 279.752912 -24.525171) (xy 279.783685 -24.571684) (xy 279.807357 -24.622181) (xy 279.823425 -24.675588)
			(xy 279.831545 -24.730764) (xy 279.832054 -24.75865) (xy 279.831545 -24.786536) (xy 279.828472 -24.807418)
			(xy 290.571172 -24.807418) (xy 290.575243 -24.751796) (xy 290.587369 -24.697359) (xy 290.607292 -24.645268)
			(xy 290.634588 -24.596633) (xy 290.668674 -24.55249) (xy 290.708823 -24.513781) (xy 290.754181 -24.48133)
			(xy 290.803781 -24.455829) (xy 290.856565 -24.437822) (xy 290.911408 -24.427692) (xy 290.967142 -24.425655)
			(xy 291.022579 -24.431755) (xy 291.076536 -24.445861) (xy 291.127865 -24.467673) (xy 291.175471 -24.496727)
			(xy 291.218339 -24.532402) (xy 291.255556 -24.573939) (xy 291.286329 -24.620452) (xy 291.310001 -24.670949)
			(xy 291.326069 -24.724356) (xy 291.334189 -24.779532) (xy 291.334698 -24.807418) (xy 292.820088 -24.807418)
			(xy 292.824159 -24.751796) (xy 292.836285 -24.697359) (xy 292.856208 -24.645268) (xy 292.883504 -24.596633)
			(xy 292.91759 -24.55249) (xy 292.957739 -24.513781) (xy 293.003097 -24.48133) (xy 293.052697 -24.455829)
			(xy 293.105481 -24.437822) (xy 293.160324 -24.427692) (xy 293.216058 -24.425655) (xy 293.271495 -24.431755)
			(xy 293.325452 -24.445861) (xy 293.376781 -24.467673) (xy 293.424387 -24.496727) (xy 293.467255 -24.532402)
			(xy 293.504472 -24.573939) (xy 293.535245 -24.620452) (xy 293.558917 -24.670949) (xy 293.574985 -24.724356)
			(xy 293.583105 -24.779532) (xy 293.583614 -24.807418) (xy 293.583105 -24.835304) (xy 293.574985 -24.89048)
			(xy 293.558917 -24.943887) (xy 293.535245 -24.994384) (xy 293.504472 -25.040897) (xy 293.467255 -25.082434)
			(xy 293.424387 -25.118109) (xy 293.376781 -25.147163) (xy 293.325452 -25.168975) (xy 293.271495 -25.183081)
			(xy 293.216058 -25.189181) (xy 293.160324 -25.187144) (xy 293.105481 -25.177014) (xy 293.052697 -25.159007)
			(xy 293.003097 -25.133506) (xy 292.957739 -25.101055) (xy 292.91759 -25.062346) (xy 292.883504 -25.018203)
			(xy 292.856208 -24.969568) (xy 292.836285 -24.917477) (xy 292.824159 -24.86304) (xy 292.820088 -24.807418)
			(xy 291.334698 -24.807418) (xy 291.334189 -24.835304) (xy 291.326069 -24.89048) (xy 291.310001 -24.943887)
			(xy 291.286329 -24.994384) (xy 291.255556 -25.040897) (xy 291.218339 -25.082434) (xy 291.175471 -25.118109)
			(xy 291.127865 -25.147163) (xy 291.076536 -25.168975) (xy 291.022579 -25.183081) (xy 290.967142 -25.189181)
			(xy 290.911408 -25.187144) (xy 290.856565 -25.177014) (xy 290.803781 -25.159007) (xy 290.754181 -25.133506)
			(xy 290.708823 -25.101055) (xy 290.668674 -25.062346) (xy 290.634588 -25.018203) (xy 290.607292 -24.969568)
			(xy 290.587369 -24.917477) (xy 290.575243 -24.86304) (xy 290.571172 -24.807418) (xy 279.828472 -24.807418)
			(xy 279.823425 -24.841712) (xy 279.807357 -24.895119) (xy 279.783685 -24.945616) (xy 279.752912 -24.992129)
			(xy 279.715695 -25.033666) (xy 279.672827 -25.069341) (xy 279.625221 -25.098395) (xy 279.573892 -25.120207)
			(xy 279.519935 -25.134313) (xy 279.464498 -25.140413) (xy 279.408764 -25.138376) (xy 279.353921 -25.128246)
			(xy 279.301137 -25.110239) (xy 279.251537 -25.084738) (xy 279.206179 -25.052287) (xy 279.16603 -25.013578)
			(xy 279.131944 -24.969435) (xy 279.104648 -24.9208) (xy 279.084725 -24.868709) (xy 279.072599 -24.814272)
			(xy 279.068528 -24.75865) (xy 277.036513 -24.75865) (xy 277.072196 -24.798475) (xy 277.102969 -24.844988)
			(xy 277.126641 -24.895485) (xy 277.142709 -24.948892) (xy 277.150829 -25.004068) (xy 277.151338 -25.031954)
			(xy 277.150829 -25.05984) (xy 277.142709 -25.115016) (xy 277.126641 -25.168423) (xy 277.102969 -25.21892)
			(xy 277.072196 -25.265433) (xy 277.034979 -25.30697) (xy 276.992111 -25.342645) (xy 276.944505 -25.371699)
			(xy 276.893176 -25.393511) (xy 276.839219 -25.407617) (xy 276.783782 -25.413717) (xy 276.728048 -25.41168)
			(xy 276.673205 -25.40155) (xy 276.620421 -25.383543) (xy 276.570821 -25.358042) (xy 276.525463 -25.325591)
			(xy 276.485314 -25.286882) (xy 276.451228 -25.242739) (xy 276.423932 -25.194104) (xy 276.404009 -25.142013)
			(xy 276.391883 -25.087576) (xy 276.387812 -25.031954) (xy 272.522511 -25.031954) (xy 272.565799 -25.050349)
			(xy 272.613405 -25.079403) (xy 272.656273 -25.115078) (xy 272.69349 -25.156615) (xy 272.724263 -25.203128)
			(xy 272.747935 -25.253625) (xy 272.764003 -25.307032) (xy 272.772123 -25.362208) (xy 272.772632 -25.390094)
			(xy 272.772123 -25.41798) (xy 272.764003 -25.473156) (xy 272.747935 -25.526563) (xy 272.732846 -25.55875)
			(xy 280.841702 -25.55875) (xy 280.845773 -25.503128) (xy 280.857899 -25.448691) (xy 280.877822 -25.3966)
			(xy 280.905118 -25.347965) (xy 280.939204 -25.303822) (xy 280.979353 -25.265113) (xy 281.024711 -25.232662)
			(xy 281.074311 -25.207161) (xy 281.127095 -25.189154) (xy 281.181938 -25.179024) (xy 281.237672 -25.176987)
			(xy 281.293109 -25.183087) (xy 281.347066 -25.197193) (xy 281.398395 -25.219005) (xy 281.446001 -25.248059)
			(xy 281.488869 -25.283734) (xy 281.526086 -25.325271) (xy 281.556859 -25.371784) (xy 281.565442 -25.390094)
			(xy 298.009054 -25.390094) (xy 298.013125 -25.334472) (xy 298.025251 -25.280035) (xy 298.045174 -25.227944)
			(xy 298.07247 -25.179309) (xy 298.106556 -25.135166) (xy 298.146705 -25.096457) (xy 298.192063 -25.064006)
			(xy 298.241663 -25.038505) (xy 298.294447 -25.020498) (xy 298.34929 -25.010368) (xy 298.405024 -25.008331)
			(xy 298.460461 -25.014431) (xy 298.514418 -25.028537) (xy 298.522459 -25.031954) (xy 302.38776 -25.031954)
			(xy 302.391831 -24.976332) (xy 302.403957 -24.921895) (xy 302.42388 -24.869804) (xy 302.451176 -24.821169)
			(xy 302.485262 -24.777026) (xy 302.525411 -24.738317) (xy 302.570769 -24.705866) (xy 302.620369 -24.680365)
			(xy 302.673153 -24.662358) (xy 302.727996 -24.652228) (xy 302.78373 -24.650191) (xy 302.839167 -24.656291)
			(xy 302.893124 -24.670397) (xy 302.944453 -24.692209) (xy 302.992059 -24.721263) (xy 303.034927 -24.756938)
			(xy 303.036461 -24.75865) (xy 305.068476 -24.75865) (xy 305.072547 -24.703028) (xy 305.084673 -24.648591)
			(xy 305.104596 -24.5965) (xy 305.131892 -24.547865) (xy 305.165978 -24.503722) (xy 305.206127 -24.465013)
			(xy 305.251485 -24.432562) (xy 305.301085 -24.407061) (xy 305.353869 -24.389054) (xy 305.408712 -24.378924)
			(xy 305.464446 -24.376887) (xy 305.519883 -24.382987) (xy 305.57384 -24.397093) (xy 305.625169 -24.418905)
			(xy 305.672775 -24.447959) (xy 305.715643 -24.483634) (xy 305.75286 -24.525171) (xy 305.783633 -24.571684)
			(xy 305.807305 -24.622181) (xy 305.823373 -24.675588) (xy 305.831493 -24.730764) (xy 305.832002 -24.75865)
			(xy 305.831493 -24.786536) (xy 305.82842 -24.807418) (xy 316.57112 -24.807418) (xy 316.575191 -24.751796)
			(xy 316.587317 -24.697359) (xy 316.60724 -24.645268) (xy 316.634536 -24.596633) (xy 316.668622 -24.55249)
			(xy 316.708771 -24.513781) (xy 316.754129 -24.48133) (xy 316.803729 -24.455829) (xy 316.856513 -24.437822)
			(xy 316.911356 -24.427692) (xy 316.96709 -24.425655) (xy 317.022527 -24.431755) (xy 317.076484 -24.445861)
			(xy 317.127813 -24.467673) (xy 317.175419 -24.496727) (xy 317.218287 -24.532402) (xy 317.255504 -24.573939)
			(xy 317.286277 -24.620452) (xy 317.309949 -24.670949) (xy 317.326017 -24.724356) (xy 317.334137 -24.779532)
			(xy 317.334646 -24.807418) (xy 318.820036 -24.807418) (xy 318.824107 -24.751796) (xy 318.836233 -24.697359)
			(xy 318.856156 -24.645268) (xy 318.883452 -24.596633) (xy 318.917538 -24.55249) (xy 318.957687 -24.513781)
			(xy 319.003045 -24.48133) (xy 319.052645 -24.455829) (xy 319.105429 -24.437822) (xy 319.160272 -24.427692)
			(xy 319.216006 -24.425655) (xy 319.271443 -24.431755) (xy 319.3254 -24.445861) (xy 319.376729 -24.467673)
			(xy 319.424335 -24.496727) (xy 319.467203 -24.532402) (xy 319.50442 -24.573939) (xy 319.535193 -24.620452)
			(xy 319.558865 -24.670949) (xy 319.574933 -24.724356) (xy 319.583053 -24.779532) (xy 319.583562 -24.807418)
			(xy 319.583053 -24.835304) (xy 319.574933 -24.89048) (xy 319.558865 -24.943887) (xy 319.535193 -24.994384)
			(xy 319.50442 -25.040897) (xy 319.467203 -25.082434) (xy 319.424335 -25.118109) (xy 319.376729 -25.147163)
			(xy 319.3254 -25.168975) (xy 319.271443 -25.183081) (xy 319.216006 -25.189181) (xy 319.160272 -25.187144)
			(xy 319.105429 -25.177014) (xy 319.052645 -25.159007) (xy 319.003045 -25.133506) (xy 318.957687 -25.101055)
			(xy 318.917538 -25.062346) (xy 318.883452 -25.018203) (xy 318.856156 -24.969568) (xy 318.836233 -24.917477)
			(xy 318.824107 -24.86304) (xy 318.820036 -24.807418) (xy 317.334646 -24.807418) (xy 317.334137 -24.835304)
			(xy 317.326017 -24.89048) (xy 317.309949 -24.943887) (xy 317.286277 -24.994384) (xy 317.255504 -25.040897)
			(xy 317.218287 -25.082434) (xy 317.175419 -25.118109) (xy 317.127813 -25.147163) (xy 317.076484 -25.168975)
			(xy 317.022527 -25.183081) (xy 316.96709 -25.189181) (xy 316.911356 -25.187144) (xy 316.856513 -25.177014)
			(xy 316.803729 -25.159007) (xy 316.754129 -25.133506) (xy 316.708771 -25.101055) (xy 316.668622 -25.062346)
			(xy 316.634536 -25.018203) (xy 316.60724 -24.969568) (xy 316.587317 -24.917477) (xy 316.575191 -24.86304)
			(xy 316.57112 -24.807418) (xy 305.82842 -24.807418) (xy 305.823373 -24.841712) (xy 305.807305 -24.895119)
			(xy 305.783633 -24.945616) (xy 305.75286 -24.992129) (xy 305.715643 -25.033666) (xy 305.672775 -25.069341)
			(xy 305.625169 -25.098395) (xy 305.57384 -25.120207) (xy 305.519883 -25.134313) (xy 305.464446 -25.140413)
			(xy 305.408712 -25.138376) (xy 305.353869 -25.128246) (xy 305.301085 -25.110239) (xy 305.251485 -25.084738)
			(xy 305.206127 -25.052287) (xy 305.165978 -25.013578) (xy 305.131892 -24.969435) (xy 305.104596 -24.9208)
			(xy 305.084673 -24.868709) (xy 305.072547 -24.814272) (xy 305.068476 -24.75865) (xy 303.036461 -24.75865)
			(xy 303.072144 -24.798475) (xy 303.102917 -24.844988) (xy 303.126589 -24.895485) (xy 303.142657 -24.948892)
			(xy 303.150777 -25.004068) (xy 303.151286 -25.031954) (xy 303.150777 -25.05984) (xy 303.142657 -25.115016)
			(xy 303.126589 -25.168423) (xy 303.102917 -25.21892) (xy 303.072144 -25.265433) (xy 303.034927 -25.30697)
			(xy 302.992059 -25.342645) (xy 302.944453 -25.371699) (xy 302.893124 -25.393511) (xy 302.839167 -25.407617)
			(xy 302.78373 -25.413717) (xy 302.727996 -25.41168) (xy 302.673153 -25.40155) (xy 302.620369 -25.383543)
			(xy 302.570769 -25.358042) (xy 302.525411 -25.325591) (xy 302.485262 -25.286882) (xy 302.451176 -25.242739)
			(xy 302.42388 -25.194104) (xy 302.403957 -25.142013) (xy 302.391831 -25.087576) (xy 302.38776 -25.031954)
			(xy 298.522459 -25.031954) (xy 298.565747 -25.050349) (xy 298.613353 -25.079403) (xy 298.656221 -25.115078)
			(xy 298.693438 -25.156615) (xy 298.724211 -25.203128) (xy 298.747883 -25.253625) (xy 298.763951 -25.307032)
			(xy 298.772071 -25.362208) (xy 298.77258 -25.390094) (xy 298.772071 -25.41798) (xy 298.763951 -25.473156)
			(xy 298.747883 -25.526563) (xy 298.732794 -25.55875) (xy 306.84165 -25.55875) (xy 306.845721 -25.503128)
			(xy 306.857847 -25.448691) (xy 306.87777 -25.3966) (xy 306.905066 -25.347965) (xy 306.939152 -25.303822)
			(xy 306.979301 -25.265113) (xy 307.024659 -25.232662) (xy 307.074259 -25.207161) (xy 307.127043 -25.189154)
			(xy 307.181886 -25.179024) (xy 307.23762 -25.176987) (xy 307.293057 -25.183087) (xy 307.347014 -25.197193)
			(xy 307.398343 -25.219005) (xy 307.445949 -25.248059) (xy 307.488817 -25.283734) (xy 307.526034 -25.325271)
			(xy 307.556807 -25.371784) (xy 307.56539 -25.390094) (xy 324.009002 -25.390094) (xy 324.013073 -25.334472)
			(xy 324.025199 -25.280035) (xy 324.045122 -25.227944) (xy 324.072418 -25.179309) (xy 324.106504 -25.135166)
			(xy 324.146653 -25.096457) (xy 324.192011 -25.064006) (xy 324.241611 -25.038505) (xy 324.294395 -25.020498)
			(xy 324.349238 -25.010368) (xy 324.404972 -25.008331) (xy 324.460409 -25.014431) (xy 324.514366 -25.028537)
			(xy 324.522407 -25.031954) (xy 328.387708 -25.031954) (xy 328.391779 -24.976332) (xy 328.403905 -24.921895)
			(xy 328.423828 -24.869804) (xy 328.451124 -24.821169) (xy 328.48521 -24.777026) (xy 328.525359 -24.738317)
			(xy 328.570717 -24.705866) (xy 328.620317 -24.680365) (xy 328.673101 -24.662358) (xy 328.727944 -24.652228)
			(xy 328.783678 -24.650191) (xy 328.839115 -24.656291) (xy 328.893072 -24.670397) (xy 328.944401 -24.692209)
			(xy 328.992007 -24.721263) (xy 329.034875 -24.756938) (xy 329.036409 -24.75865) (xy 331.068424 -24.75865)
			(xy 331.072495 -24.703028) (xy 331.084621 -24.648591) (xy 331.104544 -24.5965) (xy 331.13184 -24.547865)
			(xy 331.165926 -24.503722) (xy 331.206075 -24.465013) (xy 331.251433 -24.432562) (xy 331.301033 -24.407061)
			(xy 331.353817 -24.389054) (xy 331.40866 -24.378924) (xy 331.464394 -24.376887) (xy 331.519831 -24.382987)
			(xy 331.573788 -24.397093) (xy 331.625117 -24.418905) (xy 331.672723 -24.447959) (xy 331.715591 -24.483634)
			(xy 331.752808 -24.525171) (xy 331.783581 -24.571684) (xy 331.807253 -24.622181) (xy 331.823321 -24.675588)
			(xy 331.831441 -24.730764) (xy 331.83195 -24.75865) (xy 331.831441 -24.786536) (xy 331.828368 -24.807418)
			(xy 354.671374 -24.807418) (xy 354.675445 -24.751796) (xy 354.687571 -24.697359) (xy 354.707494 -24.645268)
			(xy 354.73479 -24.596633) (xy 354.768876 -24.55249) (xy 354.809025 -24.513781) (xy 354.854383 -24.48133)
			(xy 354.903983 -24.455829) (xy 354.956767 -24.437822) (xy 355.01161 -24.427692) (xy 355.067344 -24.425655)
			(xy 355.122781 -24.431755) (xy 355.176738 -24.445861) (xy 355.228067 -24.467673) (xy 355.275673 -24.496727)
			(xy 355.318541 -24.532402) (xy 355.355758 -24.573939) (xy 355.386531 -24.620452) (xy 355.410203 -24.670949)
			(xy 355.426271 -24.724356) (xy 355.434391 -24.779532) (xy 355.4349 -24.807418) (xy 356.92029 -24.807418)
			(xy 356.924361 -24.751796) (xy 356.936487 -24.697359) (xy 356.95641 -24.645268) (xy 356.983706 -24.596633)
			(xy 357.017792 -24.55249) (xy 357.057941 -24.513781) (xy 357.103299 -24.48133) (xy 357.152899 -24.455829)
			(xy 357.205683 -24.437822) (xy 357.260526 -24.427692) (xy 357.31626 -24.425655) (xy 357.371697 -24.431755)
			(xy 357.425654 -24.445861) (xy 357.476983 -24.467673) (xy 357.524589 -24.496727) (xy 357.567457 -24.532402)
			(xy 357.604674 -24.573939) (xy 357.635447 -24.620452) (xy 357.659119 -24.670949) (xy 357.675187 -24.724356)
			(xy 357.683307 -24.779532) (xy 357.683816 -24.807418) (xy 357.683307 -24.835304) (xy 357.675187 -24.89048)
			(xy 357.659119 -24.943887) (xy 357.635447 -24.994384) (xy 357.604674 -25.040897) (xy 357.567457 -25.082434)
			(xy 357.524589 -25.118109) (xy 357.476983 -25.147163) (xy 357.425654 -25.168975) (xy 357.371697 -25.183081)
			(xy 357.31626 -25.189181) (xy 357.260526 -25.187144) (xy 357.205683 -25.177014) (xy 357.152899 -25.159007)
			(xy 357.103299 -25.133506) (xy 357.057941 -25.101055) (xy 357.017792 -25.062346) (xy 356.983706 -25.018203)
			(xy 356.95641 -24.969568) (xy 356.936487 -24.917477) (xy 356.924361 -24.86304) (xy 356.92029 -24.807418)
			(xy 355.4349 -24.807418) (xy 355.434391 -24.835304) (xy 355.426271 -24.89048) (xy 355.410203 -24.943887)
			(xy 355.386531 -24.994384) (xy 355.355758 -25.040897) (xy 355.318541 -25.082434) (xy 355.275673 -25.118109)
			(xy 355.228067 -25.147163) (xy 355.176738 -25.168975) (xy 355.122781 -25.183081) (xy 355.067344 -25.189181)
			(xy 355.01161 -25.187144) (xy 354.956767 -25.177014) (xy 354.903983 -25.159007) (xy 354.854383 -25.133506)
			(xy 354.809025 -25.101055) (xy 354.768876 -25.062346) (xy 354.73479 -25.018203) (xy 354.707494 -24.969568)
			(xy 354.687571 -24.917477) (xy 354.675445 -24.86304) (xy 354.671374 -24.807418) (xy 331.828368 -24.807418)
			(xy 331.823321 -24.841712) (xy 331.807253 -24.895119) (xy 331.783581 -24.945616) (xy 331.752808 -24.992129)
			(xy 331.715591 -25.033666) (xy 331.672723 -25.069341) (xy 331.625117 -25.098395) (xy 331.573788 -25.120207)
			(xy 331.519831 -25.134313) (xy 331.464394 -25.140413) (xy 331.40866 -25.138376) (xy 331.353817 -25.128246)
			(xy 331.301033 -25.110239) (xy 331.251433 -25.084738) (xy 331.206075 -25.052287) (xy 331.165926 -25.013578)
			(xy 331.13184 -24.969435) (xy 331.104544 -24.9208) (xy 331.084621 -24.868709) (xy 331.072495 -24.814272)
			(xy 331.068424 -24.75865) (xy 329.036409 -24.75865) (xy 329.072092 -24.798475) (xy 329.102865 -24.844988)
			(xy 329.126537 -24.895485) (xy 329.142605 -24.948892) (xy 329.150725 -25.004068) (xy 329.151234 -25.031954)
			(xy 329.150725 -25.05984) (xy 329.142605 -25.115016) (xy 329.126537 -25.168423) (xy 329.102865 -25.21892)
			(xy 329.072092 -25.265433) (xy 329.034875 -25.30697) (xy 328.992007 -25.342645) (xy 328.944401 -25.371699)
			(xy 328.893072 -25.393511) (xy 328.839115 -25.407617) (xy 328.783678 -25.413717) (xy 328.727944 -25.41168)
			(xy 328.673101 -25.40155) (xy 328.620317 -25.383543) (xy 328.570717 -25.358042) (xy 328.525359 -25.325591)
			(xy 328.48521 -25.286882) (xy 328.451124 -25.242739) (xy 328.423828 -25.194104) (xy 328.403905 -25.142013)
			(xy 328.391779 -25.087576) (xy 328.387708 -25.031954) (xy 324.522407 -25.031954) (xy 324.565695 -25.050349)
			(xy 324.613301 -25.079403) (xy 324.656169 -25.115078) (xy 324.693386 -25.156615) (xy 324.724159 -25.203128)
			(xy 324.747831 -25.253625) (xy 324.763899 -25.307032) (xy 324.772019 -25.362208) (xy 324.772528 -25.390094)
			(xy 324.772019 -25.41798) (xy 324.763899 -25.473156) (xy 324.747831 -25.526563) (xy 324.732742 -25.55875)
			(xy 332.841598 -25.55875) (xy 332.845669 -25.503128) (xy 332.857795 -25.448691) (xy 332.877718 -25.3966)
			(xy 332.905014 -25.347965) (xy 332.9391 -25.303822) (xy 332.979249 -25.265113) (xy 333.024607 -25.232662)
			(xy 333.074207 -25.207161) (xy 333.126991 -25.189154) (xy 333.181834 -25.179024) (xy 333.237568 -25.176987)
			(xy 333.293005 -25.183087) (xy 333.346962 -25.197193) (xy 333.398291 -25.219005) (xy 333.445897 -25.248059)
			(xy 333.488765 -25.283734) (xy 333.525982 -25.325271) (xy 333.556755 -25.371784) (xy 333.565338 -25.390094)
			(xy 362.109256 -25.390094) (xy 362.113327 -25.334472) (xy 362.125453 -25.280035) (xy 362.145376 -25.227944)
			(xy 362.172672 -25.179309) (xy 362.206758 -25.135166) (xy 362.246907 -25.096457) (xy 362.292265 -25.064006)
			(xy 362.341865 -25.038505) (xy 362.394649 -25.020498) (xy 362.449492 -25.010368) (xy 362.505226 -25.008331)
			(xy 362.560663 -25.014431) (xy 362.61462 -25.028537) (xy 362.622661 -25.031954) (xy 366.487962 -25.031954)
			(xy 366.492033 -24.976332) (xy 366.504159 -24.921895) (xy 366.524082 -24.869804) (xy 366.551378 -24.821169)
			(xy 366.585464 -24.777026) (xy 366.625613 -24.738317) (xy 366.670971 -24.705866) (xy 366.720571 -24.680365)
			(xy 366.773355 -24.662358) (xy 366.828198 -24.652228) (xy 366.883932 -24.650191) (xy 366.939369 -24.656291)
			(xy 366.993326 -24.670397) (xy 367.044655 -24.692209) (xy 367.092261 -24.721263) (xy 367.135129 -24.756938)
			(xy 367.136663 -24.75865) (xy 369.168678 -24.75865) (xy 369.172749 -24.703028) (xy 369.184875 -24.648591)
			(xy 369.204798 -24.5965) (xy 369.232094 -24.547865) (xy 369.26618 -24.503722) (xy 369.306329 -24.465013)
			(xy 369.351687 -24.432562) (xy 369.401287 -24.407061) (xy 369.454071 -24.389054) (xy 369.508914 -24.378924)
			(xy 369.564648 -24.376887) (xy 369.620085 -24.382987) (xy 369.674042 -24.397093) (xy 369.725371 -24.418905)
			(xy 369.772977 -24.447959) (xy 369.815845 -24.483634) (xy 369.853062 -24.525171) (xy 369.883835 -24.571684)
			(xy 369.907507 -24.622181) (xy 369.923575 -24.675588) (xy 369.931695 -24.730764) (xy 369.932204 -24.75865)
			(xy 369.931695 -24.786536) (xy 369.928622 -24.807418) (xy 380.671322 -24.807418) (xy 380.675393 -24.751796)
			(xy 380.687519 -24.697359) (xy 380.707442 -24.645268) (xy 380.734738 -24.596633) (xy 380.768824 -24.55249)
			(xy 380.808973 -24.513781) (xy 380.854331 -24.48133) (xy 380.903931 -24.455829) (xy 380.956715 -24.437822)
			(xy 381.011558 -24.427692) (xy 381.067292 -24.425655) (xy 381.122729 -24.431755) (xy 381.176686 -24.445861)
			(xy 381.228015 -24.467673) (xy 381.275621 -24.496727) (xy 381.318489 -24.532402) (xy 381.355706 -24.573939)
			(xy 381.386479 -24.620452) (xy 381.410151 -24.670949) (xy 381.426219 -24.724356) (xy 381.434339 -24.779532)
			(xy 381.434848 -24.807418) (xy 382.920238 -24.807418) (xy 382.924309 -24.751796) (xy 382.936435 -24.697359)
			(xy 382.956358 -24.645268) (xy 382.983654 -24.596633) (xy 383.01774 -24.55249) (xy 383.057889 -24.513781)
			(xy 383.103247 -24.48133) (xy 383.152847 -24.455829) (xy 383.205631 -24.437822) (xy 383.260474 -24.427692)
			(xy 383.316208 -24.425655) (xy 383.371645 -24.431755) (xy 383.425602 -24.445861) (xy 383.476931 -24.467673)
			(xy 383.524537 -24.496727) (xy 383.567405 -24.532402) (xy 383.604622 -24.573939) (xy 383.635395 -24.620452)
			(xy 383.659067 -24.670949) (xy 383.675135 -24.724356) (xy 383.683255 -24.779532) (xy 383.683764 -24.807418)
			(xy 383.683255 -24.835304) (xy 383.675135 -24.89048) (xy 383.659067 -24.943887) (xy 383.635395 -24.994384)
			(xy 383.604622 -25.040897) (xy 383.567405 -25.082434) (xy 383.524537 -25.118109) (xy 383.476931 -25.147163)
			(xy 383.425602 -25.168975) (xy 383.371645 -25.183081) (xy 383.316208 -25.189181) (xy 383.260474 -25.187144)
			(xy 383.205631 -25.177014) (xy 383.152847 -25.159007) (xy 383.103247 -25.133506) (xy 383.057889 -25.101055)
			(xy 383.01774 -25.062346) (xy 382.983654 -25.018203) (xy 382.956358 -24.969568) (xy 382.936435 -24.917477)
			(xy 382.924309 -24.86304) (xy 382.920238 -24.807418) (xy 381.434848 -24.807418) (xy 381.434339 -24.835304)
			(xy 381.426219 -24.89048) (xy 381.410151 -24.943887) (xy 381.386479 -24.994384) (xy 381.355706 -25.040897)
			(xy 381.318489 -25.082434) (xy 381.275621 -25.118109) (xy 381.228015 -25.147163) (xy 381.176686 -25.168975)
			(xy 381.122729 -25.183081) (xy 381.067292 -25.189181) (xy 381.011558 -25.187144) (xy 380.956715 -25.177014)
			(xy 380.903931 -25.159007) (xy 380.854331 -25.133506) (xy 380.808973 -25.101055) (xy 380.768824 -25.062346)
			(xy 380.734738 -25.018203) (xy 380.707442 -24.969568) (xy 380.687519 -24.917477) (xy 380.675393 -24.86304)
			(xy 380.671322 -24.807418) (xy 369.928622 -24.807418) (xy 369.923575 -24.841712) (xy 369.907507 -24.895119)
			(xy 369.883835 -24.945616) (xy 369.853062 -24.992129) (xy 369.815845 -25.033666) (xy 369.772977 -25.069341)
			(xy 369.725371 -25.098395) (xy 369.674042 -25.120207) (xy 369.620085 -25.134313) (xy 369.564648 -25.140413)
			(xy 369.508914 -25.138376) (xy 369.454071 -25.128246) (xy 369.401287 -25.110239) (xy 369.351687 -25.084738)
			(xy 369.306329 -25.052287) (xy 369.26618 -25.013578) (xy 369.232094 -24.969435) (xy 369.204798 -24.9208)
			(xy 369.184875 -24.868709) (xy 369.172749 -24.814272) (xy 369.168678 -24.75865) (xy 367.136663 -24.75865)
			(xy 367.172346 -24.798475) (xy 367.203119 -24.844988) (xy 367.226791 -24.895485) (xy 367.242859 -24.948892)
			(xy 367.250979 -25.004068) (xy 367.251488 -25.031954) (xy 367.250979 -25.05984) (xy 367.242859 -25.115016)
			(xy 367.226791 -25.168423) (xy 367.203119 -25.21892) (xy 367.172346 -25.265433) (xy 367.135129 -25.30697)
			(xy 367.092261 -25.342645) (xy 367.044655 -25.371699) (xy 366.993326 -25.393511) (xy 366.939369 -25.407617)
			(xy 366.883932 -25.413717) (xy 366.828198 -25.41168) (xy 366.773355 -25.40155) (xy 366.720571 -25.383543)
			(xy 366.670971 -25.358042) (xy 366.625613 -25.325591) (xy 366.585464 -25.286882) (xy 366.551378 -25.242739)
			(xy 366.524082 -25.194104) (xy 366.504159 -25.142013) (xy 366.492033 -25.087576) (xy 366.487962 -25.031954)
			(xy 362.622661 -25.031954) (xy 362.665949 -25.050349) (xy 362.713555 -25.079403) (xy 362.756423 -25.115078)
			(xy 362.79364 -25.156615) (xy 362.824413 -25.203128) (xy 362.848085 -25.253625) (xy 362.864153 -25.307032)
			(xy 362.872273 -25.362208) (xy 362.872782 -25.390094) (xy 362.872273 -25.41798) (xy 362.864153 -25.473156)
			(xy 362.848085 -25.526563) (xy 362.832996 -25.55875) (xy 370.941852 -25.55875) (xy 370.945923 -25.503128)
			(xy 370.958049 -25.448691) (xy 370.977972 -25.3966) (xy 371.005268 -25.347965) (xy 371.039354 -25.303822)
			(xy 371.079503 -25.265113) (xy 371.124861 -25.232662) (xy 371.174461 -25.207161) (xy 371.227245 -25.189154)
			(xy 371.282088 -25.179024) (xy 371.337822 -25.176987) (xy 371.393259 -25.183087) (xy 371.447216 -25.197193)
			(xy 371.498545 -25.219005) (xy 371.546151 -25.248059) (xy 371.589019 -25.283734) (xy 371.626236 -25.325271)
			(xy 371.657009 -25.371784) (xy 371.665592 -25.390094) (xy 388.109204 -25.390094) (xy 388.113275 -25.334472)
			(xy 388.125401 -25.280035) (xy 388.145324 -25.227944) (xy 388.17262 -25.179309) (xy 388.206706 -25.135166)
			(xy 388.246855 -25.096457) (xy 388.292213 -25.064006) (xy 388.341813 -25.038505) (xy 388.394597 -25.020498)
			(xy 388.44944 -25.010368) (xy 388.505174 -25.008331) (xy 388.560611 -25.014431) (xy 388.614568 -25.028537)
			(xy 388.622609 -25.031954) (xy 392.48791 -25.031954) (xy 392.491981 -24.976332) (xy 392.504107 -24.921895)
			(xy 392.52403 -24.869804) (xy 392.551326 -24.821169) (xy 392.585412 -24.777026) (xy 392.625561 -24.738317)
			(xy 392.670919 -24.705866) (xy 392.720519 -24.680365) (xy 392.773303 -24.662358) (xy 392.828146 -24.652228)
			(xy 392.88388 -24.650191) (xy 392.939317 -24.656291) (xy 392.993274 -24.670397) (xy 393.044603 -24.692209)
			(xy 393.092209 -24.721263) (xy 393.135077 -24.756938) (xy 393.136611 -24.75865) (xy 395.168626 -24.75865)
			(xy 395.172697 -24.703028) (xy 395.184823 -24.648591) (xy 395.204746 -24.5965) (xy 395.232042 -24.547865)
			(xy 395.266128 -24.503722) (xy 395.306277 -24.465013) (xy 395.351635 -24.432562) (xy 395.401235 -24.407061)
			(xy 395.454019 -24.389054) (xy 395.508862 -24.378924) (xy 395.564596 -24.376887) (xy 395.620033 -24.382987)
			(xy 395.67399 -24.397093) (xy 395.725319 -24.418905) (xy 395.772925 -24.447959) (xy 395.815793 -24.483634)
			(xy 395.85301 -24.525171) (xy 395.883783 -24.571684) (xy 395.907455 -24.622181) (xy 395.923523 -24.675588)
			(xy 395.931643 -24.730764) (xy 395.932152 -24.75865) (xy 395.931643 -24.786536) (xy 395.92857 -24.807418)
			(xy 406.67127 -24.807418) (xy 406.675341 -24.751796) (xy 406.687467 -24.697359) (xy 406.70739 -24.645268)
			(xy 406.734686 -24.596633) (xy 406.768772 -24.55249) (xy 406.808921 -24.513781) (xy 406.854279 -24.48133)
			(xy 406.903879 -24.455829) (xy 406.956663 -24.437822) (xy 407.011506 -24.427692) (xy 407.06724 -24.425655)
			(xy 407.122677 -24.431755) (xy 407.176634 -24.445861) (xy 407.227963 -24.467673) (xy 407.275569 -24.496727)
			(xy 407.318437 -24.532402) (xy 407.355654 -24.573939) (xy 407.386427 -24.620452) (xy 407.410099 -24.670949)
			(xy 407.426167 -24.724356) (xy 407.434287 -24.779532) (xy 407.434796 -24.807418) (xy 408.920186 -24.807418)
			(xy 408.924257 -24.751796) (xy 408.936383 -24.697359) (xy 408.956306 -24.645268) (xy 408.983602 -24.596633)
			(xy 409.017688 -24.55249) (xy 409.057837 -24.513781) (xy 409.103195 -24.48133) (xy 409.152795 -24.455829)
			(xy 409.205579 -24.437822) (xy 409.260422 -24.427692) (xy 409.316156 -24.425655) (xy 409.371593 -24.431755)
			(xy 409.42555 -24.445861) (xy 409.476879 -24.467673) (xy 409.524485 -24.496727) (xy 409.567353 -24.532402)
			(xy 409.60457 -24.573939) (xy 409.635343 -24.620452) (xy 409.659015 -24.670949) (xy 409.675083 -24.724356)
			(xy 409.683203 -24.779532) (xy 409.683712 -24.807418) (xy 409.683203 -24.835304) (xy 409.675083 -24.89048)
			(xy 409.659015 -24.943887) (xy 409.635343 -24.994384) (xy 409.60457 -25.040897) (xy 409.567353 -25.082434)
			(xy 409.524485 -25.118109) (xy 409.476879 -25.147163) (xy 409.42555 -25.168975) (xy 409.371593 -25.183081)
			(xy 409.316156 -25.189181) (xy 409.260422 -25.187144) (xy 409.205579 -25.177014) (xy 409.152795 -25.159007)
			(xy 409.103195 -25.133506) (xy 409.057837 -25.101055) (xy 409.017688 -25.062346) (xy 408.983602 -25.018203)
			(xy 408.956306 -24.969568) (xy 408.936383 -24.917477) (xy 408.924257 -24.86304) (xy 408.920186 -24.807418)
			(xy 407.434796 -24.807418) (xy 407.434287 -24.835304) (xy 407.426167 -24.89048) (xy 407.410099 -24.943887)
			(xy 407.386427 -24.994384) (xy 407.355654 -25.040897) (xy 407.318437 -25.082434) (xy 407.275569 -25.118109)
			(xy 407.227963 -25.147163) (xy 407.176634 -25.168975) (xy 407.122677 -25.183081) (xy 407.06724 -25.189181)
			(xy 407.011506 -25.187144) (xy 406.956663 -25.177014) (xy 406.903879 -25.159007) (xy 406.854279 -25.133506)
			(xy 406.808921 -25.101055) (xy 406.768772 -25.062346) (xy 406.734686 -25.018203) (xy 406.70739 -24.969568)
			(xy 406.687467 -24.917477) (xy 406.675341 -24.86304) (xy 406.67127 -24.807418) (xy 395.92857 -24.807418)
			(xy 395.923523 -24.841712) (xy 395.907455 -24.895119) (xy 395.883783 -24.945616) (xy 395.85301 -24.992129)
			(xy 395.815793 -25.033666) (xy 395.772925 -25.069341) (xy 395.725319 -25.098395) (xy 395.67399 -25.120207)
			(xy 395.620033 -25.134313) (xy 395.564596 -25.140413) (xy 395.508862 -25.138376) (xy 395.454019 -25.128246)
			(xy 395.401235 -25.110239) (xy 395.351635 -25.084738) (xy 395.306277 -25.052287) (xy 395.266128 -25.013578)
			(xy 395.232042 -24.969435) (xy 395.204746 -24.9208) (xy 395.184823 -24.868709) (xy 395.172697 -24.814272)
			(xy 395.168626 -24.75865) (xy 393.136611 -24.75865) (xy 393.172294 -24.798475) (xy 393.203067 -24.844988)
			(xy 393.226739 -24.895485) (xy 393.242807 -24.948892) (xy 393.250927 -25.004068) (xy 393.251436 -25.031954)
			(xy 393.250927 -25.05984) (xy 393.242807 -25.115016) (xy 393.226739 -25.168423) (xy 393.203067 -25.21892)
			(xy 393.172294 -25.265433) (xy 393.135077 -25.30697) (xy 393.092209 -25.342645) (xy 393.044603 -25.371699)
			(xy 392.993274 -25.393511) (xy 392.939317 -25.407617) (xy 392.88388 -25.413717) (xy 392.828146 -25.41168)
			(xy 392.773303 -25.40155) (xy 392.720519 -25.383543) (xy 392.670919 -25.358042) (xy 392.625561 -25.325591)
			(xy 392.585412 -25.286882) (xy 392.551326 -25.242739) (xy 392.52403 -25.194104) (xy 392.504107 -25.142013)
			(xy 392.491981 -25.087576) (xy 392.48791 -25.031954) (xy 388.622609 -25.031954) (xy 388.665897 -25.050349)
			(xy 388.713503 -25.079403) (xy 388.756371 -25.115078) (xy 388.793588 -25.156615) (xy 388.824361 -25.203128)
			(xy 388.848033 -25.253625) (xy 388.864101 -25.307032) (xy 388.872221 -25.362208) (xy 388.87273 -25.390094)
			(xy 388.872221 -25.41798) (xy 388.864101 -25.473156) (xy 388.848033 -25.526563) (xy 388.832944 -25.55875)
			(xy 396.9418 -25.55875) (xy 396.945871 -25.503128) (xy 396.957997 -25.448691) (xy 396.97792 -25.3966)
			(xy 397.005216 -25.347965) (xy 397.039302 -25.303822) (xy 397.079451 -25.265113) (xy 397.124809 -25.232662)
			(xy 397.174409 -25.207161) (xy 397.227193 -25.189154) (xy 397.282036 -25.179024) (xy 397.33777 -25.176987)
			(xy 397.393207 -25.183087) (xy 397.447164 -25.197193) (xy 397.498493 -25.219005) (xy 397.546099 -25.248059)
			(xy 397.588967 -25.283734) (xy 397.626184 -25.325271) (xy 397.656957 -25.371784) (xy 397.66554 -25.390094)
			(xy 414.109152 -25.390094) (xy 414.113223 -25.334472) (xy 414.125349 -25.280035) (xy 414.145272 -25.227944)
			(xy 414.172568 -25.179309) (xy 414.206654 -25.135166) (xy 414.246803 -25.096457) (xy 414.292161 -25.064006)
			(xy 414.341761 -25.038505) (xy 414.394545 -25.020498) (xy 414.449388 -25.010368) (xy 414.505122 -25.008331)
			(xy 414.560559 -25.014431) (xy 414.614516 -25.028537) (xy 414.622557 -25.031954) (xy 418.487858 -25.031954)
			(xy 418.491929 -24.976332) (xy 418.504055 -24.921895) (xy 418.523978 -24.869804) (xy 418.551274 -24.821169)
			(xy 418.58536 -24.777026) (xy 418.625509 -24.738317) (xy 418.670867 -24.705866) (xy 418.720467 -24.680365)
			(xy 418.773251 -24.662358) (xy 418.828094 -24.652228) (xy 418.883828 -24.650191) (xy 418.939265 -24.656291)
			(xy 418.993222 -24.670397) (xy 419.044551 -24.692209) (xy 419.092157 -24.721263) (xy 419.135025 -24.756938)
			(xy 419.136559 -24.75865) (xy 421.168574 -24.75865) (xy 421.172645 -24.703028) (xy 421.184771 -24.648591)
			(xy 421.204694 -24.5965) (xy 421.23199 -24.547865) (xy 421.266076 -24.503722) (xy 421.306225 -24.465013)
			(xy 421.351583 -24.432562) (xy 421.401183 -24.407061) (xy 421.453967 -24.389054) (xy 421.50881 -24.378924)
			(xy 421.564544 -24.376887) (xy 421.619981 -24.382987) (xy 421.673938 -24.397093) (xy 421.725267 -24.418905)
			(xy 421.772873 -24.447959) (xy 421.815741 -24.483634) (xy 421.852958 -24.525171) (xy 421.883731 -24.571684)
			(xy 421.907403 -24.622181) (xy 421.923471 -24.675588) (xy 421.931591 -24.730764) (xy 421.9321 -24.75865)
			(xy 421.931591 -24.786536) (xy 421.928518 -24.807418) (xy 432.671218 -24.807418) (xy 432.675289 -24.751796)
			(xy 432.687415 -24.697359) (xy 432.707338 -24.645268) (xy 432.734634 -24.596633) (xy 432.76872 -24.55249)
			(xy 432.808869 -24.513781) (xy 432.854227 -24.48133) (xy 432.903827 -24.455829) (xy 432.956611 -24.437822)
			(xy 433.011454 -24.427692) (xy 433.067188 -24.425655) (xy 433.122625 -24.431755) (xy 433.176582 -24.445861)
			(xy 433.227911 -24.467673) (xy 433.275517 -24.496727) (xy 433.318385 -24.532402) (xy 433.355602 -24.573939)
			(xy 433.386375 -24.620452) (xy 433.410047 -24.670949) (xy 433.426115 -24.724356) (xy 433.434235 -24.779532)
			(xy 433.434744 -24.807418) (xy 434.920134 -24.807418) (xy 434.924205 -24.751796) (xy 434.936331 -24.697359)
			(xy 434.956254 -24.645268) (xy 434.98355 -24.596633) (xy 435.017636 -24.55249) (xy 435.057785 -24.513781)
			(xy 435.103143 -24.48133) (xy 435.152743 -24.455829) (xy 435.205527 -24.437822) (xy 435.26037 -24.427692)
			(xy 435.316104 -24.425655) (xy 435.371541 -24.431755) (xy 435.425498 -24.445861) (xy 435.476827 -24.467673)
			(xy 435.524433 -24.496727) (xy 435.567301 -24.532402) (xy 435.604518 -24.573939) (xy 435.635291 -24.620452)
			(xy 435.658963 -24.670949) (xy 435.675031 -24.724356) (xy 435.683151 -24.779532) (xy 435.68366 -24.807418)
			(xy 435.683151 -24.835304) (xy 435.675031 -24.89048) (xy 435.658963 -24.943887) (xy 435.635291 -24.994384)
			(xy 435.604518 -25.040897) (xy 435.567301 -25.082434) (xy 435.524433 -25.118109) (xy 435.476827 -25.147163)
			(xy 435.425498 -25.168975) (xy 435.371541 -25.183081) (xy 435.316104 -25.189181) (xy 435.26037 -25.187144)
			(xy 435.205527 -25.177014) (xy 435.152743 -25.159007) (xy 435.103143 -25.133506) (xy 435.057785 -25.101055)
			(xy 435.017636 -25.062346) (xy 434.98355 -25.018203) (xy 434.956254 -24.969568) (xy 434.936331 -24.917477)
			(xy 434.924205 -24.86304) (xy 434.920134 -24.807418) (xy 433.434744 -24.807418) (xy 433.434235 -24.835304)
			(xy 433.426115 -24.89048) (xy 433.410047 -24.943887) (xy 433.386375 -24.994384) (xy 433.355602 -25.040897)
			(xy 433.318385 -25.082434) (xy 433.275517 -25.118109) (xy 433.227911 -25.147163) (xy 433.176582 -25.168975)
			(xy 433.122625 -25.183081) (xy 433.067188 -25.189181) (xy 433.011454 -25.187144) (xy 432.956611 -25.177014)
			(xy 432.903827 -25.159007) (xy 432.854227 -25.133506) (xy 432.808869 -25.101055) (xy 432.76872 -25.062346)
			(xy 432.734634 -25.018203) (xy 432.707338 -24.969568) (xy 432.687415 -24.917477) (xy 432.675289 -24.86304)
			(xy 432.671218 -24.807418) (xy 421.928518 -24.807418) (xy 421.923471 -24.841712) (xy 421.907403 -24.895119)
			(xy 421.883731 -24.945616) (xy 421.852958 -24.992129) (xy 421.815741 -25.033666) (xy 421.772873 -25.069341)
			(xy 421.725267 -25.098395) (xy 421.673938 -25.120207) (xy 421.619981 -25.134313) (xy 421.564544 -25.140413)
			(xy 421.50881 -25.138376) (xy 421.453967 -25.128246) (xy 421.401183 -25.110239) (xy 421.351583 -25.084738)
			(xy 421.306225 -25.052287) (xy 421.266076 -25.013578) (xy 421.23199 -24.969435) (xy 421.204694 -24.9208)
			(xy 421.184771 -24.868709) (xy 421.172645 -24.814272) (xy 421.168574 -24.75865) (xy 419.136559 -24.75865)
			(xy 419.172242 -24.798475) (xy 419.203015 -24.844988) (xy 419.226687 -24.895485) (xy 419.242755 -24.948892)
			(xy 419.250875 -25.004068) (xy 419.251384 -25.031954) (xy 419.250875 -25.05984) (xy 419.242755 -25.115016)
			(xy 419.226687 -25.168423) (xy 419.203015 -25.21892) (xy 419.172242 -25.265433) (xy 419.135025 -25.30697)
			(xy 419.092157 -25.342645) (xy 419.044551 -25.371699) (xy 418.993222 -25.393511) (xy 418.939265 -25.407617)
			(xy 418.883828 -25.413717) (xy 418.828094 -25.41168) (xy 418.773251 -25.40155) (xy 418.720467 -25.383543)
			(xy 418.670867 -25.358042) (xy 418.625509 -25.325591) (xy 418.58536 -25.286882) (xy 418.551274 -25.242739)
			(xy 418.523978 -25.194104) (xy 418.504055 -25.142013) (xy 418.491929 -25.087576) (xy 418.487858 -25.031954)
			(xy 414.622557 -25.031954) (xy 414.665845 -25.050349) (xy 414.713451 -25.079403) (xy 414.756319 -25.115078)
			(xy 414.793536 -25.156615) (xy 414.824309 -25.203128) (xy 414.847981 -25.253625) (xy 414.864049 -25.307032)
			(xy 414.872169 -25.362208) (xy 414.872678 -25.390094) (xy 414.872169 -25.41798) (xy 414.864049 -25.473156)
			(xy 414.847981 -25.526563) (xy 414.832892 -25.55875) (xy 422.941748 -25.55875) (xy 422.945819 -25.503128)
			(xy 422.957945 -25.448691) (xy 422.977868 -25.3966) (xy 423.005164 -25.347965) (xy 423.03925 -25.303822)
			(xy 423.079399 -25.265113) (xy 423.124757 -25.232662) (xy 423.174357 -25.207161) (xy 423.227141 -25.189154)
			(xy 423.281984 -25.179024) (xy 423.337718 -25.176987) (xy 423.393155 -25.183087) (xy 423.447112 -25.197193)
			(xy 423.498441 -25.219005) (xy 423.546047 -25.248059) (xy 423.588915 -25.283734) (xy 423.626132 -25.325271)
			(xy 423.656905 -25.371784) (xy 423.665488 -25.390094) (xy 440.1091 -25.390094) (xy 440.113171 -25.334472)
			(xy 440.125297 -25.280035) (xy 440.14522 -25.227944) (xy 440.172516 -25.179309) (xy 440.206602 -25.135166)
			(xy 440.246751 -25.096457) (xy 440.292109 -25.064006) (xy 440.341709 -25.038505) (xy 440.394493 -25.020498)
			(xy 440.449336 -25.010368) (xy 440.50507 -25.008331) (xy 440.560507 -25.014431) (xy 440.614464 -25.028537)
			(xy 440.622505 -25.031954) (xy 444.487806 -25.031954) (xy 444.491877 -24.976332) (xy 444.504003 -24.921895)
			(xy 444.523926 -24.869804) (xy 444.551222 -24.821169) (xy 444.585308 -24.777026) (xy 444.625457 -24.738317)
			(xy 444.670815 -24.705866) (xy 444.720415 -24.680365) (xy 444.773199 -24.662358) (xy 444.828042 -24.652228)
			(xy 444.883776 -24.650191) (xy 444.939213 -24.656291) (xy 444.99317 -24.670397) (xy 445.044499 -24.692209)
			(xy 445.092105 -24.721263) (xy 445.134973 -24.756938) (xy 445.136507 -24.75865) (xy 447.168522 -24.75865)
			(xy 447.172593 -24.703028) (xy 447.184719 -24.648591) (xy 447.204642 -24.5965) (xy 447.231938 -24.547865)
			(xy 447.266024 -24.503722) (xy 447.306173 -24.465013) (xy 447.351531 -24.432562) (xy 447.401131 -24.407061)
			(xy 447.453915 -24.389054) (xy 447.508758 -24.378924) (xy 447.564492 -24.376887) (xy 447.619929 -24.382987)
			(xy 447.673886 -24.397093) (xy 447.725215 -24.418905) (xy 447.772821 -24.447959) (xy 447.815689 -24.483634)
			(xy 447.852906 -24.525171) (xy 447.883679 -24.571684) (xy 447.907351 -24.622181) (xy 447.923419 -24.675588)
			(xy 447.931539 -24.730764) (xy 447.932048 -24.75865) (xy 447.931539 -24.786536) (xy 447.923419 -24.841712)
			(xy 447.907351 -24.895119) (xy 447.883679 -24.945616) (xy 447.852906 -24.992129) (xy 447.815689 -25.033666)
			(xy 447.772821 -25.069341) (xy 447.725215 -25.098395) (xy 447.673886 -25.120207) (xy 447.619929 -25.134313)
			(xy 447.564492 -25.140413) (xy 447.508758 -25.138376) (xy 447.453915 -25.128246) (xy 447.401131 -25.110239)
			(xy 447.351531 -25.084738) (xy 447.306173 -25.052287) (xy 447.266024 -25.013578) (xy 447.231938 -24.969435)
			(xy 447.204642 -24.9208) (xy 447.184719 -24.868709) (xy 447.172593 -24.814272) (xy 447.168522 -24.75865)
			(xy 445.136507 -24.75865) (xy 445.17219 -24.798475) (xy 445.202963 -24.844988) (xy 445.226635 -24.895485)
			(xy 445.242703 -24.948892) (xy 445.250823 -25.004068) (xy 445.251332 -25.031954) (xy 445.250823 -25.05984)
			(xy 445.242703 -25.115016) (xy 445.226635 -25.168423) (xy 445.202963 -25.21892) (xy 445.17219 -25.265433)
			(xy 445.134973 -25.30697) (xy 445.092105 -25.342645) (xy 445.044499 -25.371699) (xy 444.99317 -25.393511)
			(xy 444.939213 -25.407617) (xy 444.883776 -25.413717) (xy 444.828042 -25.41168) (xy 444.773199 -25.40155)
			(xy 444.720415 -25.383543) (xy 444.670815 -25.358042) (xy 444.625457 -25.325591) (xy 444.585308 -25.286882)
			(xy 444.551222 -25.242739) (xy 444.523926 -25.194104) (xy 444.504003 -25.142013) (xy 444.491877 -25.087576)
			(xy 444.487806 -25.031954) (xy 440.622505 -25.031954) (xy 440.665793 -25.050349) (xy 440.713399 -25.079403)
			(xy 440.756267 -25.115078) (xy 440.793484 -25.156615) (xy 440.824257 -25.203128) (xy 440.847929 -25.253625)
			(xy 440.863997 -25.307032) (xy 440.872117 -25.362208) (xy 440.872626 -25.390094) (xy 440.872117 -25.41798)
			(xy 440.863997 -25.473156) (xy 440.847929 -25.526563) (xy 440.83284 -25.55875) (xy 448.941696 -25.55875)
			(xy 448.945767 -25.503128) (xy 448.957893 -25.448691) (xy 448.977816 -25.3966) (xy 449.005112 -25.347965)
			(xy 449.039198 -25.303822) (xy 449.079347 -25.265113) (xy 449.124705 -25.232662) (xy 449.174305 -25.207161)
			(xy 449.227089 -25.189154) (xy 449.281932 -25.179024) (xy 449.337666 -25.176987) (xy 449.393103 -25.183087)
			(xy 449.44706 -25.197193) (xy 449.498389 -25.219005) (xy 449.545995 -25.248059) (xy 449.588863 -25.283734)
			(xy 449.62608 -25.325271) (xy 449.656853 -25.371784) (xy 449.680525 -25.422281) (xy 449.696593 -25.475688)
			(xy 449.704713 -25.530864) (xy 449.705222 -25.55875) (xy 449.704713 -25.586636) (xy 449.696593 -25.641812)
			(xy 449.680525 -25.695219) (xy 449.656853 -25.745716) (xy 449.62608 -25.792229) (xy 449.588863 -25.833766)
			(xy 449.545995 -25.869441) (xy 449.498389 -25.898495) (xy 449.44706 -25.920307) (xy 449.393103 -25.934413)
			(xy 449.337666 -25.940513) (xy 449.281932 -25.938476) (xy 449.227089 -25.928346) (xy 449.174305 -25.910339)
			(xy 449.124705 -25.884838) (xy 449.079347 -25.852387) (xy 449.039198 -25.813678) (xy 449.005112 -25.769535)
			(xy 448.977816 -25.7209) (xy 448.957893 -25.668809) (xy 448.945767 -25.614372) (xy 448.941696 -25.55875)
			(xy 440.83284 -25.55875) (xy 440.824257 -25.57706) (xy 440.793484 -25.623573) (xy 440.756267 -25.66511)
			(xy 440.713399 -25.700785) (xy 440.665793 -25.729839) (xy 440.614464 -25.751651) (xy 440.560507 -25.765757)
			(xy 440.50507 -25.771857) (xy 440.449336 -25.76982) (xy 440.394493 -25.75969) (xy 440.341709 -25.741683)
			(xy 440.292109 -25.716182) (xy 440.246751 -25.683731) (xy 440.206602 -25.645022) (xy 440.172516 -25.600879)
			(xy 440.14522 -25.552244) (xy 440.125297 -25.500153) (xy 440.113171 -25.445716) (xy 440.1091 -25.390094)
			(xy 423.665488 -25.390094) (xy 423.680577 -25.422281) (xy 423.696645 -25.475688) (xy 423.704765 -25.530864)
			(xy 423.705274 -25.55875) (xy 423.704765 -25.586636) (xy 423.696645 -25.641812) (xy 423.680577 -25.695219)
			(xy 423.656905 -25.745716) (xy 423.626132 -25.792229) (xy 423.588915 -25.833766) (xy 423.546047 -25.869441)
			(xy 423.498441 -25.898495) (xy 423.447112 -25.920307) (xy 423.393155 -25.934413) (xy 423.337718 -25.940513)
			(xy 423.281984 -25.938476) (xy 423.227141 -25.928346) (xy 423.174357 -25.910339) (xy 423.124757 -25.884838)
			(xy 423.079399 -25.852387) (xy 423.03925 -25.813678) (xy 423.005164 -25.769535) (xy 422.977868 -25.7209)
			(xy 422.957945 -25.668809) (xy 422.945819 -25.614372) (xy 422.941748 -25.55875) (xy 414.832892 -25.55875)
			(xy 414.824309 -25.57706) (xy 414.793536 -25.623573) (xy 414.756319 -25.66511) (xy 414.713451 -25.700785)
			(xy 414.665845 -25.729839) (xy 414.614516 -25.751651) (xy 414.560559 -25.765757) (xy 414.505122 -25.771857)
			(xy 414.449388 -25.76982) (xy 414.394545 -25.75969) (xy 414.341761 -25.741683) (xy 414.292161 -25.716182)
			(xy 414.246803 -25.683731) (xy 414.206654 -25.645022) (xy 414.172568 -25.600879) (xy 414.145272 -25.552244)
			(xy 414.125349 -25.500153) (xy 414.113223 -25.445716) (xy 414.109152 -25.390094) (xy 397.66554 -25.390094)
			(xy 397.680629 -25.422281) (xy 397.696697 -25.475688) (xy 397.704817 -25.530864) (xy 397.705326 -25.55875)
			(xy 397.704817 -25.586636) (xy 397.696697 -25.641812) (xy 397.680629 -25.695219) (xy 397.656957 -25.745716)
			(xy 397.626184 -25.792229) (xy 397.588967 -25.833766) (xy 397.546099 -25.869441) (xy 397.498493 -25.898495)
			(xy 397.447164 -25.920307) (xy 397.393207 -25.934413) (xy 397.33777 -25.940513) (xy 397.282036 -25.938476)
			(xy 397.227193 -25.928346) (xy 397.174409 -25.910339) (xy 397.124809 -25.884838) (xy 397.079451 -25.852387)
			(xy 397.039302 -25.813678) (xy 397.005216 -25.769535) (xy 396.97792 -25.7209) (xy 396.957997 -25.668809)
			(xy 396.945871 -25.614372) (xy 396.9418 -25.55875) (xy 388.832944 -25.55875) (xy 388.824361 -25.57706)
			(xy 388.793588 -25.623573) (xy 388.756371 -25.66511) (xy 388.713503 -25.700785) (xy 388.665897 -25.729839)
			(xy 388.614568 -25.751651) (xy 388.560611 -25.765757) (xy 388.505174 -25.771857) (xy 388.44944 -25.76982)
			(xy 388.394597 -25.75969) (xy 388.341813 -25.741683) (xy 388.292213 -25.716182) (xy 388.246855 -25.683731)
			(xy 388.206706 -25.645022) (xy 388.17262 -25.600879) (xy 388.145324 -25.552244) (xy 388.125401 -25.500153)
			(xy 388.113275 -25.445716) (xy 388.109204 -25.390094) (xy 371.665592 -25.390094) (xy 371.680681 -25.422281)
			(xy 371.696749 -25.475688) (xy 371.704869 -25.530864) (xy 371.705378 -25.55875) (xy 371.704869 -25.586636)
			(xy 371.696749 -25.641812) (xy 371.680681 -25.695219) (xy 371.657009 -25.745716) (xy 371.626236 -25.792229)
			(xy 371.589019 -25.833766) (xy 371.546151 -25.869441) (xy 371.498545 -25.898495) (xy 371.447216 -25.920307)
			(xy 371.393259 -25.934413) (xy 371.337822 -25.940513) (xy 371.282088 -25.938476) (xy 371.227245 -25.928346)
			(xy 371.174461 -25.910339) (xy 371.124861 -25.884838) (xy 371.079503 -25.852387) (xy 371.039354 -25.813678)
			(xy 371.005268 -25.769535) (xy 370.977972 -25.7209) (xy 370.958049 -25.668809) (xy 370.945923 -25.614372)
			(xy 370.941852 -25.55875) (xy 362.832996 -25.55875) (xy 362.824413 -25.57706) (xy 362.79364 -25.623573)
			(xy 362.756423 -25.66511) (xy 362.713555 -25.700785) (xy 362.665949 -25.729839) (xy 362.61462 -25.751651)
			(xy 362.560663 -25.765757) (xy 362.505226 -25.771857) (xy 362.449492 -25.76982) (xy 362.394649 -25.75969)
			(xy 362.341865 -25.741683) (xy 362.292265 -25.716182) (xy 362.246907 -25.683731) (xy 362.206758 -25.645022)
			(xy 362.172672 -25.600879) (xy 362.145376 -25.552244) (xy 362.125453 -25.500153) (xy 362.113327 -25.445716)
			(xy 362.109256 -25.390094) (xy 333.565338 -25.390094) (xy 333.580427 -25.422281) (xy 333.596495 -25.475688)
			(xy 333.604615 -25.530864) (xy 333.605124 -25.55875) (xy 333.604615 -25.586636) (xy 333.596495 -25.641812)
			(xy 333.580427 -25.695219) (xy 333.556755 -25.745716) (xy 333.525982 -25.792229) (xy 333.488765 -25.833766)
			(xy 333.445897 -25.869441) (xy 333.398291 -25.898495) (xy 333.346962 -25.920307) (xy 333.293005 -25.934413)
			(xy 333.237568 -25.940513) (xy 333.181834 -25.938476) (xy 333.126991 -25.928346) (xy 333.074207 -25.910339)
			(xy 333.024607 -25.884838) (xy 332.979249 -25.852387) (xy 332.9391 -25.813678) (xy 332.905014 -25.769535)
			(xy 332.877718 -25.7209) (xy 332.857795 -25.668809) (xy 332.845669 -25.614372) (xy 332.841598 -25.55875)
			(xy 324.732742 -25.55875) (xy 324.724159 -25.57706) (xy 324.693386 -25.623573) (xy 324.656169 -25.66511)
			(xy 324.613301 -25.700785) (xy 324.565695 -25.729839) (xy 324.514366 -25.751651) (xy 324.460409 -25.765757)
			(xy 324.404972 -25.771857) (xy 324.349238 -25.76982) (xy 324.294395 -25.75969) (xy 324.241611 -25.741683)
			(xy 324.192011 -25.716182) (xy 324.146653 -25.683731) (xy 324.106504 -25.645022) (xy 324.072418 -25.600879)
			(xy 324.045122 -25.552244) (xy 324.025199 -25.500153) (xy 324.013073 -25.445716) (xy 324.009002 -25.390094)
			(xy 307.56539 -25.390094) (xy 307.580479 -25.422281) (xy 307.596547 -25.475688) (xy 307.604667 -25.530864)
			(xy 307.605176 -25.55875) (xy 307.604667 -25.586636) (xy 307.596547 -25.641812) (xy 307.580479 -25.695219)
			(xy 307.556807 -25.745716) (xy 307.526034 -25.792229) (xy 307.488817 -25.833766) (xy 307.445949 -25.869441)
			(xy 307.398343 -25.898495) (xy 307.347014 -25.920307) (xy 307.293057 -25.934413) (xy 307.23762 -25.940513)
			(xy 307.181886 -25.938476) (xy 307.127043 -25.928346) (xy 307.074259 -25.910339) (xy 307.024659 -25.884838)
			(xy 306.979301 -25.852387) (xy 306.939152 -25.813678) (xy 306.905066 -25.769535) (xy 306.87777 -25.7209)
			(xy 306.857847 -25.668809) (xy 306.845721 -25.614372) (xy 306.84165 -25.55875) (xy 298.732794 -25.55875)
			(xy 298.724211 -25.57706) (xy 298.693438 -25.623573) (xy 298.656221 -25.66511) (xy 298.613353 -25.700785)
			(xy 298.565747 -25.729839) (xy 298.514418 -25.751651) (xy 298.460461 -25.765757) (xy 298.405024 -25.771857)
			(xy 298.34929 -25.76982) (xy 298.294447 -25.75969) (xy 298.241663 -25.741683) (xy 298.192063 -25.716182)
			(xy 298.146705 -25.683731) (xy 298.106556 -25.645022) (xy 298.07247 -25.600879) (xy 298.045174 -25.552244)
			(xy 298.025251 -25.500153) (xy 298.013125 -25.445716) (xy 298.009054 -25.390094) (xy 281.565442 -25.390094)
			(xy 281.580531 -25.422281) (xy 281.596599 -25.475688) (xy 281.604719 -25.530864) (xy 281.605228 -25.55875)
			(xy 281.604719 -25.586636) (xy 281.596599 -25.641812) (xy 281.580531 -25.695219) (xy 281.556859 -25.745716)
			(xy 281.526086 -25.792229) (xy 281.488869 -25.833766) (xy 281.446001 -25.869441) (xy 281.398395 -25.898495)
			(xy 281.347066 -25.920307) (xy 281.293109 -25.934413) (xy 281.237672 -25.940513) (xy 281.181938 -25.938476)
			(xy 281.127095 -25.928346) (xy 281.074311 -25.910339) (xy 281.024711 -25.884838) (xy 280.979353 -25.852387)
			(xy 280.939204 -25.813678) (xy 280.905118 -25.769535) (xy 280.877822 -25.7209) (xy 280.857899 -25.668809)
			(xy 280.845773 -25.614372) (xy 280.841702 -25.55875) (xy 272.732846 -25.55875) (xy 272.724263 -25.57706)
			(xy 272.69349 -25.623573) (xy 272.656273 -25.66511) (xy 272.613405 -25.700785) (xy 272.565799 -25.729839)
			(xy 272.51447 -25.751651) (xy 272.460513 -25.765757) (xy 272.405076 -25.771857) (xy 272.349342 -25.76982)
			(xy 272.294499 -25.75969) (xy 272.241715 -25.741683) (xy 272.192115 -25.716182) (xy 272.146757 -25.683731)
			(xy 272.106608 -25.645022) (xy 272.072522 -25.600879) (xy 272.045226 -25.552244) (xy 272.025303 -25.500153)
			(xy 272.013177 -25.445716) (xy 272.009106 -25.390094) (xy 255.565494 -25.390094) (xy 255.580583 -25.422281)
			(xy 255.596651 -25.475688) (xy 255.604771 -25.530864) (xy 255.60528 -25.55875) (xy 255.604771 -25.586636)
			(xy 255.596651 -25.641812) (xy 255.580583 -25.695219) (xy 255.556911 -25.745716) (xy 255.526138 -25.792229)
			(xy 255.488921 -25.833766) (xy 255.446053 -25.869441) (xy 255.398447 -25.898495) (xy 255.347118 -25.920307)
			(xy 255.293161 -25.934413) (xy 255.237724 -25.940513) (xy 255.18199 -25.938476) (xy 255.127147 -25.928346)
			(xy 255.074363 -25.910339) (xy 255.024763 -25.884838) (xy 254.979405 -25.852387) (xy 254.939256 -25.813678)
			(xy 254.90517 -25.769535) (xy 254.877874 -25.7209) (xy 254.857951 -25.668809) (xy 254.845825 -25.614372)
			(xy 254.841754 -25.55875) (xy 246.732898 -25.55875) (xy 246.724315 -25.57706) (xy 246.693542 -25.623573)
			(xy 246.656325 -25.66511) (xy 246.613457 -25.700785) (xy 246.565851 -25.729839) (xy 246.514522 -25.751651)
			(xy 246.460565 -25.765757) (xy 246.405128 -25.771857) (xy 246.349394 -25.76982) (xy 246.294551 -25.75969)
			(xy 246.241767 -25.741683) (xy 246.192167 -25.716182) (xy 246.146809 -25.683731) (xy 246.10666 -25.645022)
			(xy 246.072574 -25.600879) (xy 246.045278 -25.552244) (xy 246.025355 -25.500153) (xy 246.013229 -25.445716)
			(xy 246.009158 -25.390094) (xy 217.465494 -25.390094) (xy 217.480583 -25.422281) (xy 217.496651 -25.475688)
			(xy 217.504771 -25.530864) (xy 217.50528 -25.55875) (xy 217.504771 -25.586636) (xy 217.496651 -25.641812)
			(xy 217.480583 -25.695219) (xy 217.456911 -25.745716) (xy 217.426138 -25.792229) (xy 217.388921 -25.833766)
			(xy 217.346053 -25.869441) (xy 217.298447 -25.898495) (xy 217.247118 -25.920307) (xy 217.193161 -25.934413)
			(xy 217.137724 -25.940513) (xy 217.08199 -25.938476) (xy 217.027147 -25.928346) (xy 216.974363 -25.910339)
			(xy 216.924763 -25.884838) (xy 216.879405 -25.852387) (xy 216.839256 -25.813678) (xy 216.80517 -25.769535)
			(xy 216.777874 -25.7209) (xy 216.757951 -25.668809) (xy 216.745825 -25.614372) (xy 216.741754 -25.55875)
			(xy 208.632898 -25.55875) (xy 208.624315 -25.57706) (xy 208.593542 -25.623573) (xy 208.556325 -25.66511)
			(xy 208.513457 -25.700785) (xy 208.465851 -25.729839) (xy 208.414522 -25.751651) (xy 208.360565 -25.765757)
			(xy 208.305128 -25.771857) (xy 208.249394 -25.76982) (xy 208.194551 -25.75969) (xy 208.141767 -25.741683)
			(xy 208.092167 -25.716182) (xy 208.046809 -25.683731) (xy 208.00666 -25.645022) (xy 207.972574 -25.600879)
			(xy 207.945278 -25.552244) (xy 207.925355 -25.500153) (xy 207.913229 -25.445716) (xy 207.909158 -25.390094)
			(xy 191.465546 -25.390094) (xy 191.480635 -25.422281) (xy 191.496703 -25.475688) (xy 191.504823 -25.530864)
			(xy 191.505332 -25.55875) (xy 191.504823 -25.586636) (xy 191.496703 -25.641812) (xy 191.480635 -25.695219)
			(xy 191.456963 -25.745716) (xy 191.42619 -25.792229) (xy 191.388973 -25.833766) (xy 191.346105 -25.869441)
			(xy 191.298499 -25.898495) (xy 191.24717 -25.920307) (xy 191.193213 -25.934413) (xy 191.137776 -25.940513)
			(xy 191.082042 -25.938476) (xy 191.027199 -25.928346) (xy 190.974415 -25.910339) (xy 190.924815 -25.884838)
			(xy 190.879457 -25.852387) (xy 190.839308 -25.813678) (xy 190.805222 -25.769535) (xy 190.777926 -25.7209)
			(xy 190.758003 -25.668809) (xy 190.745877 -25.614372) (xy 190.741806 -25.55875) (xy 182.63295 -25.55875)
			(xy 182.624367 -25.57706) (xy 182.593594 -25.623573) (xy 182.556377 -25.66511) (xy 182.513509 -25.700785)
			(xy 182.465903 -25.729839) (xy 182.414574 -25.751651) (xy 182.360617 -25.765757) (xy 182.30518 -25.771857)
			(xy 182.249446 -25.76982) (xy 182.194603 -25.75969) (xy 182.141819 -25.741683) (xy 182.092219 -25.716182)
			(xy 182.046861 -25.683731) (xy 182.006712 -25.645022) (xy 181.972626 -25.600879) (xy 181.94533 -25.552244)
			(xy 181.925407 -25.500153) (xy 181.913281 -25.445716) (xy 181.90921 -25.390094) (xy 165.465598 -25.390094)
			(xy 165.480687 -25.422281) (xy 165.496755 -25.475688) (xy 165.504875 -25.530864) (xy 165.505384 -25.55875)
			(xy 165.504875 -25.586636) (xy 165.496755 -25.641812) (xy 165.480687 -25.695219) (xy 165.457015 -25.745716)
			(xy 165.426242 -25.792229) (xy 165.389025 -25.833766) (xy 165.346157 -25.869441) (xy 165.298551 -25.898495)
			(xy 165.247222 -25.920307) (xy 165.193265 -25.934413) (xy 165.137828 -25.940513) (xy 165.082094 -25.938476)
			(xy 165.027251 -25.928346) (xy 164.974467 -25.910339) (xy 164.924867 -25.884838) (xy 164.879509 -25.852387)
			(xy 164.83936 -25.813678) (xy 164.805274 -25.769535) (xy 164.777978 -25.7209) (xy 164.758055 -25.668809)
			(xy 164.745929 -25.614372) (xy 164.741858 -25.55875) (xy 156.633002 -25.55875) (xy 156.624419 -25.57706)
			(xy 156.593646 -25.623573) (xy 156.556429 -25.66511) (xy 156.513561 -25.700785) (xy 156.465955 -25.729839)
			(xy 156.414626 -25.751651) (xy 156.360669 -25.765757) (xy 156.305232 -25.771857) (xy 156.249498 -25.76982)
			(xy 156.194655 -25.75969) (xy 156.141871 -25.741683) (xy 156.092271 -25.716182) (xy 156.046913 -25.683731)
			(xy 156.006764 -25.645022) (xy 155.972678 -25.600879) (xy 155.945382 -25.552244) (xy 155.925459 -25.500153)
			(xy 155.913333 -25.445716) (xy 155.909262 -25.390094) (xy 139.46565 -25.390094) (xy 139.480739 -25.422281)
			(xy 139.496807 -25.475688) (xy 139.504927 -25.530864) (xy 139.505436 -25.55875) (xy 139.504927 -25.586636)
			(xy 139.496807 -25.641812) (xy 139.480739 -25.695219) (xy 139.457067 -25.745716) (xy 139.426294 -25.792229)
			(xy 139.389077 -25.833766) (xy 139.346209 -25.869441) (xy 139.298603 -25.898495) (xy 139.247274 -25.920307)
			(xy 139.193317 -25.934413) (xy 139.13788 -25.940513) (xy 139.082146 -25.938476) (xy 139.027303 -25.928346)
			(xy 138.974519 -25.910339) (xy 138.924919 -25.884838) (xy 138.879561 -25.852387) (xy 138.839412 -25.813678)
			(xy 138.805326 -25.769535) (xy 138.77803 -25.7209) (xy 138.758107 -25.668809) (xy 138.745981 -25.614372)
			(xy 138.74191 -25.55875) (xy 130.633054 -25.55875) (xy 130.624471 -25.57706) (xy 130.593698 -25.623573)
			(xy 130.556481 -25.66511) (xy 130.513613 -25.700785) (xy 130.466007 -25.729839) (xy 130.414678 -25.751651)
			(xy 130.360721 -25.765757) (xy 130.305284 -25.771857) (xy 130.24955 -25.76982) (xy 130.194707 -25.75969)
			(xy 130.141923 -25.741683) (xy 130.092323 -25.716182) (xy 130.046965 -25.683731) (xy 130.006816 -25.645022)
			(xy 129.97273 -25.600879) (xy 129.945434 -25.552244) (xy 129.925511 -25.500153) (xy 129.913385 -25.445716)
			(xy 129.909314 -25.390094) (xy 101.365396 -25.390094) (xy 101.380485 -25.422281) (xy 101.396553 -25.475688)
			(xy 101.404673 -25.530864) (xy 101.405182 -25.55875) (xy 101.404673 -25.586636) (xy 101.396553 -25.641812)
			(xy 101.380485 -25.695219) (xy 101.356813 -25.745716) (xy 101.32604 -25.792229) (xy 101.288823 -25.833766)
			(xy 101.245955 -25.869441) (xy 101.198349 -25.898495) (xy 101.14702 -25.920307) (xy 101.093063 -25.934413)
			(xy 101.037626 -25.940513) (xy 100.981892 -25.938476) (xy 100.927049 -25.928346) (xy 100.874265 -25.910339)
			(xy 100.824665 -25.884838) (xy 100.779307 -25.852387) (xy 100.739158 -25.813678) (xy 100.705072 -25.769535)
			(xy 100.677776 -25.7209) (xy 100.657853 -25.668809) (xy 100.645727 -25.614372) (xy 100.641656 -25.55875)
			(xy 92.5328 -25.55875) (xy 92.524217 -25.57706) (xy 92.493444 -25.623573) (xy 92.456227 -25.66511)
			(xy 92.413359 -25.700785) (xy 92.365753 -25.729839) (xy 92.314424 -25.751651) (xy 92.260467 -25.765757)
			(xy 92.20503 -25.771857) (xy 92.149296 -25.76982) (xy 92.094453 -25.75969) (xy 92.041669 -25.741683)
			(xy 91.992069 -25.716182) (xy 91.946711 -25.683731) (xy 91.906562 -25.645022) (xy 91.872476 -25.600879)
			(xy 91.84518 -25.552244) (xy 91.825257 -25.500153) (xy 91.813131 -25.445716) (xy 91.80906 -25.390094)
			(xy 75.365448 -25.390094) (xy 75.380537 -25.422281) (xy 75.396605 -25.475688) (xy 75.404725 -25.530864)
			(xy 75.405234 -25.55875) (xy 75.404725 -25.586636) (xy 75.396605 -25.641812) (xy 75.380537 -25.695219)
			(xy 75.356865 -25.745716) (xy 75.326092 -25.792229) (xy 75.288875 -25.833766) (xy 75.246007 -25.869441)
			(xy 75.198401 -25.898495) (xy 75.147072 -25.920307) (xy 75.093115 -25.934413) (xy 75.037678 -25.940513)
			(xy 74.981944 -25.938476) (xy 74.927101 -25.928346) (xy 74.874317 -25.910339) (xy 74.824717 -25.884838)
			(xy 74.779359 -25.852387) (xy 74.73921 -25.813678) (xy 74.705124 -25.769535) (xy 74.677828 -25.7209)
			(xy 74.657905 -25.668809) (xy 74.645779 -25.614372) (xy 74.641708 -25.55875) (xy 66.532852 -25.55875)
			(xy 66.524269 -25.57706) (xy 66.493496 -25.623573) (xy 66.456279 -25.66511) (xy 66.413411 -25.700785)
			(xy 66.365805 -25.729839) (xy 66.314476 -25.751651) (xy 66.260519 -25.765757) (xy 66.205082 -25.771857)
			(xy 66.149348 -25.76982) (xy 66.094505 -25.75969) (xy 66.041721 -25.741683) (xy 65.992121 -25.716182)
			(xy 65.946763 -25.683731) (xy 65.906614 -25.645022) (xy 65.872528 -25.600879) (xy 65.845232 -25.552244)
			(xy 65.825309 -25.500153) (xy 65.813183 -25.445716) (xy 65.809112 -25.390094) (xy 49.3655 -25.390094)
			(xy 49.380589 -25.422281) (xy 49.396657 -25.475688) (xy 49.404777 -25.530864) (xy 49.405286 -25.55875)
			(xy 49.404777 -25.586636) (xy 49.396657 -25.641812) (xy 49.380589 -25.695219) (xy 49.356917 -25.745716)
			(xy 49.326144 -25.792229) (xy 49.288927 -25.833766) (xy 49.246059 -25.869441) (xy 49.198453 -25.898495)
			(xy 49.147124 -25.920307) (xy 49.093167 -25.934413) (xy 49.03773 -25.940513) (xy 48.981996 -25.938476)
			(xy 48.927153 -25.928346) (xy 48.874369 -25.910339) (xy 48.824769 -25.884838) (xy 48.779411 -25.852387)
			(xy 48.739262 -25.813678) (xy 48.705176 -25.769535) (xy 48.67788 -25.7209) (xy 48.657957 -25.668809)
			(xy 48.645831 -25.614372) (xy 48.64176 -25.55875) (xy 40.532904 -25.55875) (xy 40.524321 -25.57706)
			(xy 40.493548 -25.623573) (xy 40.456331 -25.66511) (xy 40.413463 -25.700785) (xy 40.365857 -25.729839)
			(xy 40.314528 -25.751651) (xy 40.260571 -25.765757) (xy 40.205134 -25.771857) (xy 40.1494 -25.76982)
			(xy 40.094557 -25.75969) (xy 40.041773 -25.741683) (xy 39.992173 -25.716182) (xy 39.946815 -25.683731)
			(xy 39.906666 -25.645022) (xy 39.87258 -25.600879) (xy 39.845284 -25.552244) (xy 39.825361 -25.500153)
			(xy 39.813235 -25.445716) (xy 39.809164 -25.390094) (xy 18.701327 -25.390094) (xy 18.693286 -25.393511)
			(xy 18.639329 -25.407617) (xy 18.583892 -25.413717) (xy 18.528158 -25.41168) (xy 18.473315 -25.40155)
			(xy 18.420531 -25.383543) (xy 18.370931 -25.358042) (xy 18.325573 -25.325591) (xy 18.285424 -25.286882)
			(xy 18.251338 -25.242739) (xy 18.224042 -25.194104) (xy 18.204119 -25.142013) (xy 18.191993 -25.087576)
			(xy 18.187922 -25.031954) (xy 14.322621 -25.031954) (xy 14.365909 -25.050349) (xy 14.413515 -25.079403)
			(xy 14.456383 -25.115078) (xy 14.4936 -25.156615) (xy 14.524373 -25.203128) (xy 14.548045 -25.253625)
			(xy 14.564113 -25.307032) (xy 14.572233 -25.362208) (xy 14.572742 -25.390094) (xy 14.572233 -25.41798)
			(xy 14.564113 -25.473156) (xy 14.548045 -25.526563) (xy 14.524373 -25.57706) (xy 14.4936 -25.623573)
			(xy 14.456383 -25.66511) (xy 14.413515 -25.700785) (xy 14.365909 -25.729839) (xy 14.31458 -25.751651)
			(xy 14.260623 -25.765757) (xy 14.205186 -25.771857) (xy 14.149452 -25.76982) (xy 14.094609 -25.75969)
			(xy 14.041825 -25.741683) (xy 13.992225 -25.716182) (xy 13.946867 -25.683731) (xy 13.906718 -25.645022)
			(xy 13.872632 -25.600879) (xy 13.845336 -25.552244) (xy 13.825413 -25.500153) (xy 13.813287 -25.445716)
			(xy 13.809216 -25.390094) (xy 1.306576 -25.390094) (xy 1.306576 -26.035) (xy 1.649982 -26.035) (xy 1.654053 -25.979378)
			(xy 1.666179 -25.924941) (xy 1.686102 -25.87285) (xy 1.713398 -25.824215) (xy 1.747484 -25.780072)
			(xy 1.787633 -25.741363) (xy 1.832991 -25.708912) (xy 1.882591 -25.683411) (xy 1.935375 -25.665404)
			(xy 1.990218 -25.655274) (xy 2.045952 -25.653237) (xy 2.101389 -25.659337) (xy 2.155346 -25.673443)
			(xy 2.206675 -25.695255) (xy 2.254281 -25.724309) (xy 2.297149 -25.759984) (xy 2.334366 -25.801521)
			(xy 2.365139 -25.848034) (xy 2.388811 -25.898531) (xy 2.402435 -25.943814) (xy 4.265674 -25.943814)
			(xy 4.269745 -25.888192) (xy 4.281871 -25.833755) (xy 4.301794 -25.781664) (xy 4.32909 -25.733029)
			(xy 4.363176 -25.688886) (xy 4.403325 -25.650177) (xy 4.448683 -25.617726) (xy 4.498283 -25.592225)
			(xy 4.551067 -25.574218) (xy 4.60591 -25.564088) (xy 4.661644 -25.562051) (xy 4.717081 -25.568151)
			(xy 4.771038 -25.582257) (xy 4.822367 -25.604069) (xy 4.869973 -25.633123) (xy 4.912841 -25.668798)
			(xy 4.950058 -25.710335) (xy 4.980831 -25.756848) (xy 5.004503 -25.807345) (xy 5.020571 -25.860752)
			(xy 5.028691 -25.915928) (xy 5.0292 -25.943814) (xy 5.028691 -25.9717) (xy 5.020571 -26.026876) (xy 5.018509 -26.03373)
			(xy 5.317488 -26.03373) (xy 5.321559 -25.978108) (xy 5.333685 -25.923671) (xy 5.353608 -25.87158)
			(xy 5.380904 -25.822945) (xy 5.41499 -25.778802) (xy 5.455139 -25.740093) (xy 5.500497 -25.707642)
			(xy 5.550097 -25.682141) (xy 5.602881 -25.664134) (xy 5.657724 -25.654004) (xy 5.713458 -25.651967)
			(xy 5.768895 -25.658067) (xy 5.822852 -25.672173) (xy 5.874181 -25.693985) (xy 5.921787 -25.723039)
			(xy 5.964655 -25.758714) (xy 6.001872 -25.800251) (xy 6.032645 -25.846764) (xy 6.056317 -25.897261)
			(xy 6.072385 -25.950668) (xy 6.080505 -26.005844) (xy 6.081014 -26.03373) (xy 6.080505 -26.061616)
			(xy 6.072385 -26.116792) (xy 6.056317 -26.170199) (xy 6.032645 -26.220696) (xy 6.002411 -26.266394)
			(xy 8.520684 -26.266394) (xy 8.52117 -26.239143) (xy 8.528926 -26.185195) (xy 8.544281 -26.1329)
			(xy 8.566923 -26.083323) (xy 8.596389 -26.037473) (xy 8.63208 -25.996282) (xy 8.673271 -25.960591)
			(xy 8.719121 -25.931125) (xy 8.768698 -25.908483) (xy 8.820993 -25.893128) (xy 8.874941 -25.885372)
			(xy 8.929443 -25.885372) (xy 8.983391 -25.893128) (xy 9.035686 -25.908483) (xy 9.085263 -25.931125)
			(xy 9.131113 -25.960591) (xy 9.172304 -25.996282) (xy 9.207995 -26.037473) (xy 9.237461 -26.083323)
			(xy 9.260103 -26.1329) (xy 9.275458 -26.185195) (xy 9.283214 -26.239143) (xy 9.2837 -26.266394) (xy 9.283148 -26.295882)
			(xy 9.274053 -26.354152) (xy 9.256095 -26.410328) (xy 9.229702 -26.463068) (xy 9.195503 -26.511116)
			(xy 9.154314 -26.553325) (xy 9.131046 -26.571448) (xy 9.119897 -26.580312) (xy 9.102719 -26.603023)
			(xy 9.092477 -26.629593) (xy 9.089965 -26.657958) (xy 9.095379 -26.685914) (xy 9.108298 -26.71129)
			(xy 9.127719 -26.732115) (xy 9.139682 -26.73985) (xy 9.163414 -26.754761) (xy 9.206651 -26.790425)
			(xy 9.244203 -26.832031) (xy 9.275264 -26.878684) (xy 9.299164 -26.92938) (xy 9.31539 -26.983027)
			(xy 9.323591 -27.03847) (xy 9.324086 -27.066494) (xy 9.3236 -27.093745) (xy 9.315844 -27.147693)
			(xy 9.300489 -27.199988) (xy 9.277847 -27.249565) (xy 9.248381 -27.295415) (xy 9.21269 -27.336606)
			(xy 9.205488 -27.342846) (xy 16.523716 -27.342846) (xy 16.523716 -26.479246) (xy 16.524206 -26.449278)
			(xy 16.532029 -26.389856) (xy 16.547542 -26.331963) (xy 16.570478 -26.27659) (xy 16.600445 -26.224684)
			(xy 16.636932 -26.177134) (xy 16.679312 -26.134754) (xy 16.726862 -26.098267) (xy 16.778768 -26.0683)
			(xy 16.834141 -26.045364) (xy 16.892034 -26.029851) (xy 16.951456 -26.022028) (xy 17.011392 -26.022028)
			(xy 17.070814 -26.029851) (xy 17.128707 -26.045364) (xy 17.18408 -26.0683) (xy 17.235986 -26.098267)
			(xy 17.283536 -26.134754) (xy 17.325916 -26.177134) (xy 17.362403 -26.224684) (xy 17.39237 -26.27659)
			(xy 17.415306 -26.331963) (xy 17.423055 -26.360882) (xy 19.089622 -26.360882) (xy 19.093693 -26.30526)
			(xy 19.105819 -26.250823) (xy 19.125742 -26.198732) (xy 19.153038 -26.150097) (xy 19.187124 -26.105954)
			(xy 19.227273 -26.067245) (xy 19.272631 -26.034794) (xy 19.322231 -26.009293) (xy 19.375015 -25.991286)
			(xy 19.429858 -25.981156) (xy 19.485592 -25.979119) (xy 19.541029 -25.985219) (xy 19.594986 -25.999325)
			(xy 19.646315 -26.021137) (xy 19.666949 -26.03373) (xy 31.267906 -26.03373) (xy 31.271977 -25.978108)
			(xy 31.284103 -25.923671) (xy 31.304026 -25.87158) (xy 31.331322 -25.822945) (xy 31.365408 -25.778802)
			(xy 31.405557 -25.740093) (xy 31.450915 -25.707642) (xy 31.500515 -25.682141) (xy 31.553299 -25.664134)
			(xy 31.608142 -25.654004) (xy 31.663876 -25.651967) (xy 31.719313 -25.658067) (xy 31.77327 -25.672173)
			(xy 31.824599 -25.693985) (xy 31.872205 -25.723039) (xy 31.915073 -25.758714) (xy 31.95229 -25.800251)
			(xy 31.983063 -25.846764) (xy 32.006735 -25.897261) (xy 32.022803 -25.950668) (xy 32.030923 -26.005844)
			(xy 32.031432 -26.03373) (xy 32.030923 -26.061616) (xy 32.022803 -26.116792) (xy 32.006735 -26.170199)
			(xy 31.983063 -26.220696) (xy 31.952829 -26.266394) (xy 34.520632 -26.266394) (xy 34.521118 -26.239143)
			(xy 34.528874 -26.185195) (xy 34.544229 -26.1329) (xy 34.566871 -26.083323) (xy 34.596337 -26.037473)
			(xy 34.632028 -25.996282) (xy 34.673219 -25.960591) (xy 34.719069 -25.931125) (xy 34.768646 -25.908483)
			(xy 34.820941 -25.893128) (xy 34.874889 -25.885372) (xy 34.929391 -25.885372) (xy 34.983339 -25.893128)
			(xy 35.035634 -25.908483) (xy 35.085211 -25.931125) (xy 35.131061 -25.960591) (xy 35.172252 -25.996282)
			(xy 35.207943 -26.037473) (xy 35.237409 -26.083323) (xy 35.260051 -26.1329) (xy 35.275406 -26.185195)
			(xy 35.283162 -26.239143) (xy 35.283648 -26.266394) (xy 35.283077 -26.295881) (xy 35.273984 -26.354149)
			(xy 35.256028 -26.410324) (xy 35.229638 -26.463064) (xy 35.195444 -26.511112) (xy 35.15426 -26.553324)
			(xy 35.130994 -26.571448) (xy 35.119838 -26.580307) (xy 35.102651 -26.603017) (xy 35.092403 -26.629589)
			(xy 35.08989 -26.657958) (xy 35.095306 -26.685918) (xy 35.108232 -26.711296) (xy 35.127662 -26.732118)
			(xy 35.13963 -26.73985) (xy 35.163373 -26.754744) (xy 35.206607 -26.790413) (xy 35.244157 -26.832023)
			(xy 35.275216 -26.878679) (xy 35.299114 -26.929376) (xy 35.315339 -26.983025) (xy 35.323539 -27.03847)
			(xy 35.324034 -27.066494) (xy 35.323548 -27.093745) (xy 35.315792 -27.147693) (xy 35.300437 -27.199988)
			(xy 35.277795 -27.249565) (xy 35.248329 -27.295415) (xy 35.212638 -27.336606) (xy 35.205436 -27.342846)
			(xy 42.523664 -27.342846) (xy 42.523664 -26.479246) (xy 42.524154 -26.449278) (xy 42.531977 -26.389856)
			(xy 42.54749 -26.331963) (xy 42.570426 -26.27659) (xy 42.600393 -26.224684) (xy 42.63688 -26.177134)
			(xy 42.67926 -26.134754) (xy 42.72681 -26.098267) (xy 42.778716 -26.0683) (xy 42.834089 -26.045364)
			(xy 42.891982 -26.029851) (xy 42.951404 -26.022028) (xy 43.01134 -26.022028) (xy 43.070762 -26.029851)
			(xy 43.128655 -26.045364) (xy 43.184028 -26.0683) (xy 43.235934 -26.098267) (xy 43.283484 -26.134754)
			(xy 43.325864 -26.177134) (xy 43.362351 -26.224684) (xy 43.392318 -26.27659) (xy 43.415254 -26.331963)
			(xy 43.423003 -26.360882) (xy 45.08957 -26.360882) (xy 45.093641 -26.30526) (xy 45.105767 -26.250823)
			(xy 45.12569 -26.198732) (xy 45.152986 -26.150097) (xy 45.187072 -26.105954) (xy 45.227221 -26.067245)
			(xy 45.272579 -26.034794) (xy 45.322179 -26.009293) (xy 45.374963 -25.991286) (xy 45.429806 -25.981156)
			(xy 45.48554 -25.979119) (xy 45.540977 -25.985219) (xy 45.594934 -25.999325) (xy 45.646263 -26.021137)
			(xy 45.693869 -26.050191) (xy 45.736737 -26.085866) (xy 45.773954 -26.127403) (xy 45.804727 -26.173916)
			(xy 45.828399 -26.224413) (xy 45.844467 -26.27782) (xy 45.850635 -26.319734) (xy 50.841908 -26.319734)
			(xy 50.845979 -26.264112) (xy 50.858105 -26.209675) (xy 50.878028 -26.157584) (xy 50.905324 -26.108949)
			(xy 50.93941 -26.064806) (xy 50.979559 -26.026097) (xy 51.024917 -25.993646) (xy 51.074517 -25.968145)
			(xy 51.127301 -25.950138) (xy 51.182144 -25.940008) (xy 51.237878 -25.937971) (xy 51.293315 -25.944071)
			(xy 51.347272 -25.958177) (xy 51.398601 -25.979989) (xy 51.446207 -26.009043) (xy 51.475872 -26.03373)
			(xy 57.267854 -26.03373) (xy 57.271925 -25.978108) (xy 57.284051 -25.923671) (xy 57.303974 -25.87158)
			(xy 57.33127 -25.822945) (xy 57.365356 -25.778802) (xy 57.405505 -25.740093) (xy 57.450863 -25.707642)
			(xy 57.500463 -25.682141) (xy 57.553247 -25.664134) (xy 57.60809 -25.654004) (xy 57.663824 -25.651967)
			(xy 57.719261 -25.658067) (xy 57.773218 -25.672173) (xy 57.824547 -25.693985) (xy 57.872153 -25.723039)
			(xy 57.915021 -25.758714) (xy 57.952238 -25.800251) (xy 57.983011 -25.846764) (xy 58.006683 -25.897261)
			(xy 58.022751 -25.950668) (xy 58.030871 -26.005844) (xy 58.03138 -26.03373) (xy 58.030871 -26.061616)
			(xy 58.022751 -26.116792) (xy 58.006683 -26.170199) (xy 57.983011 -26.220696) (xy 57.952777 -26.266394)
			(xy 60.52058 -26.266394) (xy 60.521066 -26.239143) (xy 60.528822 -26.185195) (xy 60.544177 -26.1329)
			(xy 60.566819 -26.083323) (xy 60.596285 -26.037473) (xy 60.631976 -25.996282) (xy 60.673167 -25.960591)
			(xy 60.719017 -25.931125) (xy 60.768594 -25.908483) (xy 60.820889 -25.893128) (xy 60.874837 -25.885372)
			(xy 60.929339 -25.885372) (xy 60.983287 -25.893128) (xy 61.035582 -25.908483) (xy 61.085159 -25.931125)
			(xy 61.131009 -25.960591) (xy 61.1722 -25.996282) (xy 61.207891 -26.037473) (xy 61.237357 -26.083323)
			(xy 61.259999 -26.1329) (xy 61.275354 -26.185195) (xy 61.28311 -26.239143) (xy 61.283596 -26.266394)
			(xy 61.283046 -26.295882) (xy 61.273951 -26.354152) (xy 61.255992 -26.410328) (xy 61.229599 -26.463068)
			(xy 61.1954 -26.511116) (xy 61.15421 -26.553325) (xy 61.130942 -26.571448) (xy 61.119794 -26.580313)
			(xy 61.102617 -26.603024) (xy 61.092375 -26.629593) (xy 61.089863 -26.657958) (xy 61.095277 -26.685913)
			(xy 61.108195 -26.71129) (xy 61.127615 -26.732115) (xy 61.139578 -26.73985) (xy 61.16331 -26.754763)
			(xy 61.206546 -26.790426) (xy 61.244099 -26.832032) (xy 61.27516 -26.878685) (xy 61.29906 -26.92938)
			(xy 61.315286 -26.983027) (xy 61.323487 -27.038471) (xy 61.323982 -27.066494) (xy 61.323496 -27.093745)
			(xy 61.31574 -27.147693) (xy 61.300385 -27.199988) (xy 61.277743 -27.249565) (xy 61.248277 -27.295415)
			(xy 61.212586 -27.336606) (xy 61.205384 -27.342846) (xy 68.523612 -27.342846) (xy 68.523612 -26.479246)
			(xy 68.524102 -26.449278) (xy 68.531925 -26.389856) (xy 68.547438 -26.331963) (xy 68.570374 -26.27659)
			(xy 68.600341 -26.224684) (xy 68.636828 -26.177134) (xy 68.679208 -26.134754) (xy 68.726758 -26.098267)
			(xy 68.778664 -26.0683) (xy 68.834037 -26.045364) (xy 68.89193 -26.029851) (xy 68.951352 -26.022028)
			(xy 69.011288 -26.022028) (xy 69.07071 -26.029851) (xy 69.128603 -26.045364) (xy 69.183976 -26.0683)
			(xy 69.235882 -26.098267) (xy 69.283432 -26.134754) (xy 69.325812 -26.177134) (xy 69.362299 -26.224684)
			(xy 69.392266 -26.27659) (xy 69.415202 -26.331963) (xy 69.422951 -26.360882) (xy 71.089518 -26.360882)
			(xy 71.093589 -26.30526) (xy 71.105715 -26.250823) (xy 71.125638 -26.198732) (xy 71.152934 -26.150097)
			(xy 71.18702 -26.105954) (xy 71.227169 -26.067245) (xy 71.272527 -26.034794) (xy 71.322127 -26.009293)
			(xy 71.374911 -25.991286) (xy 71.429754 -25.981156) (xy 71.485488 -25.979119) (xy 71.540925 -25.985219)
			(xy 71.594882 -25.999325) (xy 71.646211 -26.021137) (xy 71.693817 -26.050191) (xy 71.736685 -26.085866)
			(xy 71.773902 -26.127403) (xy 71.804675 -26.173916) (xy 71.828347 -26.224413) (xy 71.844415 -26.27782)
			(xy 71.850583 -26.319734) (xy 76.841856 -26.319734) (xy 76.845927 -26.264112) (xy 76.858053 -26.209675)
			(xy 76.877976 -26.157584) (xy 76.905272 -26.108949) (xy 76.939358 -26.064806) (xy 76.979507 -26.026097)
			(xy 77.024865 -25.993646) (xy 77.074465 -25.968145) (xy 77.127249 -25.950138) (xy 77.182092 -25.940008)
			(xy 77.237826 -25.937971) (xy 77.293263 -25.944071) (xy 77.34722 -25.958177) (xy 77.398549 -25.979989)
			(xy 77.446155 -26.009043) (xy 77.47582 -26.03373) (xy 83.267802 -26.03373) (xy 83.271873 -25.978108)
			(xy 83.283999 -25.923671) (xy 83.303922 -25.87158) (xy 83.331218 -25.822945) (xy 83.365304 -25.778802)
			(xy 83.405453 -25.740093) (xy 83.450811 -25.707642) (xy 83.500411 -25.682141) (xy 83.553195 -25.664134)
			(xy 83.608038 -25.654004) (xy 83.663772 -25.651967) (xy 83.719209 -25.658067) (xy 83.773166 -25.672173)
			(xy 83.824495 -25.693985) (xy 83.872101 -25.723039) (xy 83.914969 -25.758714) (xy 83.952186 -25.800251)
			(xy 83.982959 -25.846764) (xy 84.006631 -25.897261) (xy 84.022699 -25.950668) (xy 84.030819 -26.005844)
			(xy 84.031328 -26.03373) (xy 84.030819 -26.061616) (xy 84.022699 -26.116792) (xy 84.006631 -26.170199)
			(xy 83.982959 -26.220696) (xy 83.952725 -26.266394) (xy 86.520528 -26.266394) (xy 86.521014 -26.239143)
			(xy 86.52877 -26.185195) (xy 86.544125 -26.1329) (xy 86.566767 -26.083323) (xy 86.596233 -26.037473)
			(xy 86.631924 -25.996282) (xy 86.673115 -25.960591) (xy 86.718965 -25.931125) (xy 86.768542 -25.908483)
			(xy 86.820837 -25.893128) (xy 86.874785 -25.885372) (xy 86.929287 -25.885372) (xy 86.983235 -25.893128)
			(xy 87.03553 -25.908483) (xy 87.085107 -25.931125) (xy 87.130957 -25.960591) (xy 87.172148 -25.996282)
			(xy 87.207839 -26.037473) (xy 87.237305 -26.083323) (xy 87.259947 -26.1329) (xy 87.275302 -26.185195)
			(xy 87.283058 -26.239143) (xy 87.283544 -26.266394) (xy 87.282975 -26.295881) (xy 87.273881 -26.35415)
			(xy 87.255925 -26.410324) (xy 87.229535 -26.463064) (xy 87.19534 -26.511112) (xy 87.154156 -26.553324)
			(xy 87.13089 -26.571448) (xy 87.119734 -26.580307) (xy 87.102549 -26.603017) (xy 87.092301 -26.629589)
			(xy 87.089788 -26.657958) (xy 87.095204 -26.685918) (xy 87.108129 -26.711295) (xy 87.127559 -26.732118)
			(xy 87.139526 -26.73985) (xy 87.163268 -26.754746) (xy 87.206502 -26.790414) (xy 87.244053 -26.832023)
			(xy 87.275111 -26.878679) (xy 87.29901 -26.929377) (xy 87.315235 -26.983025) (xy 87.323435 -27.03847)
			(xy 87.32393 -27.066494) (xy 87.323444 -27.093745) (xy 87.315688 -27.147693) (xy 87.300333 -27.199988)
			(xy 87.277691 -27.249565) (xy 87.248225 -27.295415) (xy 87.212534 -27.336606) (xy 87.205332 -27.342846)
			(xy 94.52356 -27.342846) (xy 94.52356 -26.479246) (xy 94.52405 -26.449278) (xy 94.531873 -26.389856)
			(xy 94.547386 -26.331963) (xy 94.570322 -26.27659) (xy 94.600289 -26.224684) (xy 94.636776 -26.177134)
			(xy 94.679156 -26.134754) (xy 94.726706 -26.098267) (xy 94.778612 -26.0683) (xy 94.833985 -26.045364)
			(xy 94.891878 -26.029851) (xy 94.9513 -26.022028) (xy 95.011236 -26.022028) (xy 95.070658 -26.029851)
			(xy 95.128551 -26.045364) (xy 95.183924 -26.0683) (xy 95.23583 -26.098267) (xy 95.28338 -26.134754)
			(xy 95.32576 -26.177134) (xy 95.362247 -26.224684) (xy 95.392214 -26.27659) (xy 95.41515 -26.331963)
			(xy 95.422899 -26.360882) (xy 97.089466 -26.360882) (xy 97.093537 -26.30526) (xy 97.105663 -26.250823)
			(xy 97.125586 -26.198732) (xy 97.152882 -26.150097) (xy 97.186968 -26.105954) (xy 97.227117 -26.067245)
			(xy 97.272475 -26.034794) (xy 97.322075 -26.009293) (xy 97.374859 -25.991286) (xy 97.429702 -25.981156)
			(xy 97.485436 -25.979119) (xy 97.540873 -25.985219) (xy 97.59483 -25.999325) (xy 97.646159 -26.021137)
			(xy 97.693765 -26.050191) (xy 97.736633 -26.085866) (xy 97.77385 -26.127403) (xy 97.804623 -26.173916)
			(xy 97.828295 -26.224413) (xy 97.844363 -26.27782) (xy 97.850531 -26.319734) (xy 102.841804 -26.319734)
			(xy 102.845875 -26.264112) (xy 102.858001 -26.209675) (xy 102.877924 -26.157584) (xy 102.90522 -26.108949)
			(xy 102.939306 -26.064806) (xy 102.979455 -26.026097) (xy 103.024813 -25.993646) (xy 103.074413 -25.968145)
			(xy 103.127197 -25.950138) (xy 103.18204 -25.940008) (xy 103.237774 -25.937971) (xy 103.293211 -25.944071)
			(xy 103.347168 -25.958177) (xy 103.398497 -25.979989) (xy 103.446103 -26.009043) (xy 103.475768 -26.03373)
			(xy 121.368056 -26.03373) (xy 121.372127 -25.978108) (xy 121.384253 -25.923671) (xy 121.404176 -25.87158)
			(xy 121.431472 -25.822945) (xy 121.465558 -25.778802) (xy 121.505707 -25.740093) (xy 121.551065 -25.707642)
			(xy 121.600665 -25.682141) (xy 121.653449 -25.664134) (xy 121.708292 -25.654004) (xy 121.764026 -25.651967)
			(xy 121.819463 -25.658067) (xy 121.87342 -25.672173) (xy 121.924749 -25.693985) (xy 121.972355 -25.723039)
			(xy 122.015223 -25.758714) (xy 122.05244 -25.800251) (xy 122.083213 -25.846764) (xy 122.106885 -25.897261)
			(xy 122.122953 -25.950668) (xy 122.131073 -26.005844) (xy 122.131582 -26.03373) (xy 122.131073 -26.061616)
			(xy 122.122953 -26.116792) (xy 122.106885 -26.170199) (xy 122.083213 -26.220696) (xy 122.052979 -26.266394)
			(xy 124.620782 -26.266394) (xy 124.621268 -26.239143) (xy 124.629024 -26.185195) (xy 124.644379 -26.1329)
			(xy 124.667021 -26.083323) (xy 124.696487 -26.037473) (xy 124.732178 -25.996282) (xy 124.773369 -25.960591)
			(xy 124.819219 -25.931125) (xy 124.868796 -25.908483) (xy 124.921091 -25.893128) (xy 124.975039 -25.885372)
			(xy 125.029541 -25.885372) (xy 125.083489 -25.893128) (xy 125.135784 -25.908483) (xy 125.185361 -25.931125)
			(xy 125.231211 -25.960591) (xy 125.272402 -25.996282) (xy 125.308093 -26.037473) (xy 125.337559 -26.083323)
			(xy 125.360201 -26.1329) (xy 125.375556 -26.185195) (xy 125.383312 -26.239143) (xy 125.383798 -26.266394)
			(xy 125.383247 -26.295882) (xy 125.374152 -26.354152) (xy 125.356194 -26.410328) (xy 125.3298 -26.463068)
			(xy 125.295601 -26.511116) (xy 125.254412 -26.553325) (xy 125.231144 -26.571448) (xy 125.219995 -26.580313)
			(xy 125.202818 -26.603024) (xy 125.192576 -26.629593) (xy 125.190064 -26.657958) (xy 125.195478 -26.685914)
			(xy 125.208397 -26.71129) (xy 125.227817 -26.732115) (xy 125.23978 -26.73985) (xy 125.263512 -26.754762)
			(xy 125.306748 -26.790426) (xy 125.344301 -26.832032) (xy 125.375362 -26.878684) (xy 125.399262 -26.92938)
			(xy 125.415488 -26.983027) (xy 125.423689 -27.038471) (xy 125.424184 -27.066494) (xy 125.423698 -27.093745)
			(xy 125.415942 -27.147693) (xy 125.400587 -27.199988) (xy 125.377945 -27.249565) (xy 125.348479 -27.295415)
			(xy 125.312788 -27.336606) (xy 125.305586 -27.342846) (xy 132.62356 -27.342846) (xy 132.62356 -26.479246)
			(xy 132.62405 -26.449262) (xy 132.631878 -26.389806) (xy 132.647399 -26.331881) (xy 132.670348 -26.276477)
			(xy 132.700332 -26.224543) (xy 132.736838 -26.176967) (xy 132.779243 -26.134562) (xy 132.826819 -26.098056)
			(xy 132.878753 -26.068072) (xy 132.934157 -26.045123) (xy 132.992082 -26.029602) (xy 133.051538 -26.021774)
			(xy 133.111506 -26.021774) (xy 133.170962 -26.029602) (xy 133.228887 -26.045123) (xy 133.284291 -26.068072)
			(xy 133.336225 -26.098056) (xy 133.383801 -26.134562) (xy 133.426206 -26.176967) (xy 133.462712 -26.224543)
			(xy 133.492696 -26.276477) (xy 133.515645 -26.331881) (xy 133.523416 -26.360882) (xy 135.18972 -26.360882)
			(xy 135.193791 -26.30526) (xy 135.205917 -26.250823) (xy 135.22584 -26.198732) (xy 135.253136 -26.150097)
			(xy 135.287222 -26.105954) (xy 135.327371 -26.067245) (xy 135.372729 -26.034794) (xy 135.422329 -26.009293)
			(xy 135.475113 -25.991286) (xy 135.529956 -25.981156) (xy 135.58569 -25.979119) (xy 135.641127 -25.985219)
			(xy 135.695084 -25.999325) (xy 135.746413 -26.021137) (xy 135.794019 -26.050191) (xy 135.836887 -26.085866)
			(xy 135.874104 -26.127403) (xy 135.904877 -26.173916) (xy 135.928549 -26.224413) (xy 135.944617 -26.27782)
			(xy 135.950785 -26.319734) (xy 140.942058 -26.319734) (xy 140.946129 -26.264112) (xy 140.958255 -26.209675)
			(xy 140.978178 -26.157584) (xy 141.005474 -26.108949) (xy 141.03956 -26.064806) (xy 141.079709 -26.026097)
			(xy 141.125067 -25.993646) (xy 141.174667 -25.968145) (xy 141.227451 -25.950138) (xy 141.282294 -25.940008)
			(xy 141.338028 -25.937971) (xy 141.393465 -25.944071) (xy 141.447422 -25.958177) (xy 141.498751 -25.979989)
			(xy 141.546357 -26.009043) (xy 141.576022 -26.03373) (xy 147.368004 -26.03373) (xy 147.372075 -25.978108)
			(xy 147.384201 -25.923671) (xy 147.404124 -25.87158) (xy 147.43142 -25.822945) (xy 147.465506 -25.778802)
			(xy 147.505655 -25.740093) (xy 147.551013 -25.707642) (xy 147.600613 -25.682141) (xy 147.653397 -25.664134)
			(xy 147.70824 -25.654004) (xy 147.763974 -25.651967) (xy 147.819411 -25.658067) (xy 147.873368 -25.672173)
			(xy 147.924697 -25.693985) (xy 147.972303 -25.723039) (xy 148.015171 -25.758714) (xy 148.052388 -25.800251)
			(xy 148.083161 -25.846764) (xy 148.106833 -25.897261) (xy 148.122901 -25.950668) (xy 148.131021 -26.005844)
			(xy 148.13153 -26.03373) (xy 148.131021 -26.061616) (xy 148.122901 -26.116792) (xy 148.106833 -26.170199)
			(xy 148.083161 -26.220696) (xy 148.052927 -26.266394) (xy 150.62073 -26.266394) (xy 150.621216 -26.239143)
			(xy 150.628972 -26.185195) (xy 150.644327 -26.1329) (xy 150.666969 -26.083323) (xy 150.696435 -26.037473)
			(xy 150.732126 -25.996282) (xy 150.773317 -25.960591) (xy 150.819167 -25.931125) (xy 150.868744 -25.908483)
			(xy 150.921039 -25.893128) (xy 150.974987 -25.885372) (xy 151.029489 -25.885372) (xy 151.083437 -25.893128)
			(xy 151.135732 -25.908483) (xy 151.185309 -25.931125) (xy 151.231159 -25.960591) (xy 151.27235 -25.996282)
			(xy 151.308041 -26.037473) (xy 151.337507 -26.083323) (xy 151.360149 -26.1329) (xy 151.375504 -26.185195)
			(xy 151.38326 -26.239143) (xy 151.383746 -26.266394) (xy 151.383176 -26.295881) (xy 151.374082 -26.35415)
			(xy 151.356127 -26.410324) (xy 151.329737 -26.463064) (xy 151.295542 -26.511112) (xy 151.254358 -26.553324)
			(xy 151.231092 -26.571448) (xy 151.219936 -26.580307) (xy 151.20275 -26.603017) (xy 151.192502 -26.629589)
			(xy 151.189989 -26.657958) (xy 151.195405 -26.685918) (xy 151.208331 -26.711295) (xy 151.227761 -26.732118)
			(xy 151.239728 -26.73985) (xy 151.263471 -26.754745) (xy 151.306705 -26.790413) (xy 151.344255 -26.832023)
			(xy 151.375314 -26.878679) (xy 151.399212 -26.929376) (xy 151.415437 -26.983025) (xy 151.423637 -27.03847)
			(xy 151.424132 -27.066494) (xy 151.423646 -27.093745) (xy 151.41589 -27.147693) (xy 151.400535 -27.199988)
			(xy 151.377893 -27.249565) (xy 151.348427 -27.295415) (xy 151.312736 -27.336606) (xy 151.305534 -27.342846)
			(xy 158.623508 -27.342846) (xy 158.623508 -26.479246) (xy 158.623998 -26.449262) (xy 158.631826 -26.389806)
			(xy 158.647347 -26.331881) (xy 158.670296 -26.276477) (xy 158.70028 -26.224543) (xy 158.736786 -26.176967)
			(xy 158.779191 -26.134562) (xy 158.826767 -26.098056) (xy 158.878701 -26.068072) (xy 158.934105 -26.045123)
			(xy 158.99203 -26.029602) (xy 159.051486 -26.021774) (xy 159.111454 -26.021774) (xy 159.17091 -26.029602)
			(xy 159.228835 -26.045123) (xy 159.284239 -26.068072) (xy 159.336173 -26.098056) (xy 159.383749 -26.134562)
			(xy 159.426154 -26.176967) (xy 159.46266 -26.224543) (xy 159.492644 -26.276477) (xy 159.515593 -26.331881)
			(xy 159.523364 -26.360882) (xy 161.189668 -26.360882) (xy 161.193739 -26.30526) (xy 161.205865 -26.250823)
			(xy 161.225788 -26.198732) (xy 161.253084 -26.150097) (xy 161.28717 -26.105954) (xy 161.327319 -26.067245)
			(xy 161.372677 -26.034794) (xy 161.422277 -26.009293) (xy 161.475061 -25.991286) (xy 161.529904 -25.981156)
			(xy 161.585638 -25.979119) (xy 161.641075 -25.985219) (xy 161.695032 -25.999325) (xy 161.746361 -26.021137)
			(xy 161.793967 -26.050191) (xy 161.836835 -26.085866) (xy 161.874052 -26.127403) (xy 161.904825 -26.173916)
			(xy 161.928497 -26.224413) (xy 161.944565 -26.27782) (xy 161.950733 -26.319734) (xy 166.942006 -26.319734)
			(xy 166.946077 -26.264112) (xy 166.958203 -26.209675) (xy 166.978126 -26.157584) (xy 167.005422 -26.108949)
			(xy 167.039508 -26.064806) (xy 167.079657 -26.026097) (xy 167.125015 -25.993646) (xy 167.174615 -25.968145)
			(xy 167.227399 -25.950138) (xy 167.282242 -25.940008) (xy 167.337976 -25.937971) (xy 167.393413 -25.944071)
			(xy 167.44737 -25.958177) (xy 167.498699 -25.979989) (xy 167.546305 -26.009043) (xy 167.57597 -26.03373)
			(xy 173.367952 -26.03373) (xy 173.372023 -25.978108) (xy 173.384149 -25.923671) (xy 173.404072 -25.87158)
			(xy 173.431368 -25.822945) (xy 173.465454 -25.778802) (xy 173.505603 -25.740093) (xy 173.550961 -25.707642)
			(xy 173.600561 -25.682141) (xy 173.653345 -25.664134) (xy 173.708188 -25.654004) (xy 173.763922 -25.651967)
			(xy 173.819359 -25.658067) (xy 173.873316 -25.672173) (xy 173.924645 -25.693985) (xy 173.972251 -25.723039)
			(xy 174.015119 -25.758714) (xy 174.052336 -25.800251) (xy 174.083109 -25.846764) (xy 174.106781 -25.897261)
			(xy 174.122849 -25.950668) (xy 174.130969 -26.005844) (xy 174.131478 -26.03373) (xy 174.130969 -26.061616)
			(xy 174.122849 -26.116792) (xy 174.106781 -26.170199) (xy 174.083109 -26.220696) (xy 174.052875 -26.266394)
			(xy 176.620678 -26.266394) (xy 176.621164 -26.239143) (xy 176.62892 -26.185195) (xy 176.644275 -26.1329)
			(xy 176.666917 -26.083323) (xy 176.696383 -26.037473) (xy 176.732074 -25.996282) (xy 176.773265 -25.960591)
			(xy 176.819115 -25.931125) (xy 176.868692 -25.908483) (xy 176.920987 -25.893128) (xy 176.974935 -25.885372)
			(xy 177.029437 -25.885372) (xy 177.083385 -25.893128) (xy 177.13568 -25.908483) (xy 177.185257 -25.931125)
			(xy 177.231107 -25.960591) (xy 177.272298 -25.996282) (xy 177.307989 -26.037473) (xy 177.337455 -26.083323)
			(xy 177.360097 -26.1329) (xy 177.375452 -26.185195) (xy 177.383208 -26.239143) (xy 177.383694 -26.266394)
			(xy 177.383144 -26.295882) (xy 177.37405 -26.354153) (xy 177.356091 -26.410328) (xy 177.329697 -26.463069)
			(xy 177.295498 -26.511116) (xy 177.254308 -26.553325) (xy 177.23104 -26.571448) (xy 177.219892 -26.580313)
			(xy 177.202715 -26.603024) (xy 177.192474 -26.629594) (xy 177.189962 -26.657958) (xy 177.195375 -26.685913)
			(xy 177.208294 -26.711289) (xy 177.227714 -26.732115) (xy 177.239676 -26.73985) (xy 177.263407 -26.754763)
			(xy 177.306643 -26.790427) (xy 177.344196 -26.832032) (xy 177.375257 -26.878685) (xy 177.399158 -26.92938)
			(xy 177.415384 -26.983027) (xy 177.423585 -27.038471) (xy 177.42408 -27.066494) (xy 177.423594 -27.093745)
			(xy 177.415838 -27.147693) (xy 177.400483 -27.199988) (xy 177.377841 -27.249565) (xy 177.348375 -27.295415)
			(xy 177.312684 -27.336606) (xy 177.305482 -27.342846) (xy 184.623456 -27.342846) (xy 184.623456 -26.479246)
			(xy 184.623946 -26.449262) (xy 184.631774 -26.389806) (xy 184.647295 -26.331881) (xy 184.670244 -26.276477)
			(xy 184.700228 -26.224543) (xy 184.736734 -26.176967) (xy 184.779139 -26.134562) (xy 184.826715 -26.098056)
			(xy 184.878649 -26.068072) (xy 184.934053 -26.045123) (xy 184.991978 -26.029602) (xy 185.051434 -26.021774)
			(xy 185.111402 -26.021774) (xy 185.170858 -26.029602) (xy 185.228783 -26.045123) (xy 185.284187 -26.068072)
			(xy 185.336121 -26.098056) (xy 185.383697 -26.134562) (xy 185.426102 -26.176967) (xy 185.462608 -26.224543)
			(xy 185.492592 -26.276477) (xy 185.515541 -26.331881) (xy 185.523312 -26.360882) (xy 187.189616 -26.360882)
			(xy 187.193687 -26.30526) (xy 187.205813 -26.250823) (xy 187.225736 -26.198732) (xy 187.253032 -26.150097)
			(xy 187.287118 -26.105954) (xy 187.327267 -26.067245) (xy 187.372625 -26.034794) (xy 187.422225 -26.009293)
			(xy 187.475009 -25.991286) (xy 187.529852 -25.981156) (xy 187.585586 -25.979119) (xy 187.641023 -25.985219)
			(xy 187.69498 -25.999325) (xy 187.746309 -26.021137) (xy 187.793915 -26.050191) (xy 187.836783 -26.085866)
			(xy 187.874 -26.127403) (xy 187.904773 -26.173916) (xy 187.928445 -26.224413) (xy 187.944513 -26.27782)
			(xy 187.950681 -26.319734) (xy 192.941954 -26.319734) (xy 192.946025 -26.264112) (xy 192.958151 -26.209675)
			(xy 192.978074 -26.157584) (xy 193.00537 -26.108949) (xy 193.039456 -26.064806) (xy 193.079605 -26.026097)
			(xy 193.124963 -25.993646) (xy 193.174563 -25.968145) (xy 193.227347 -25.950138) (xy 193.28219 -25.940008)
			(xy 193.337924 -25.937971) (xy 193.393361 -25.944071) (xy 193.447318 -25.958177) (xy 193.498647 -25.979989)
			(xy 193.546253 -26.009043) (xy 193.575918 -26.03373) (xy 199.3679 -26.03373) (xy 199.371971 -25.978108)
			(xy 199.384097 -25.923671) (xy 199.40402 -25.87158) (xy 199.431316 -25.822945) (xy 199.465402 -25.778802)
			(xy 199.505551 -25.740093) (xy 199.550909 -25.707642) (xy 199.600509 -25.682141) (xy 199.653293 -25.664134)
			(xy 199.708136 -25.654004) (xy 199.76387 -25.651967) (xy 199.819307 -25.658067) (xy 199.873264 -25.672173)
			(xy 199.924593 -25.693985) (xy 199.972199 -25.723039) (xy 200.015067 -25.758714) (xy 200.052284 -25.800251)
			(xy 200.083057 -25.846764) (xy 200.106729 -25.897261) (xy 200.122797 -25.950668) (xy 200.130917 -26.005844)
			(xy 200.131426 -26.03373) (xy 200.130917 -26.061616) (xy 200.122797 -26.116792) (xy 200.106729 -26.170199)
			(xy 200.083057 -26.220696) (xy 200.052823 -26.266394) (xy 202.620626 -26.266394) (xy 202.621112 -26.239143)
			(xy 202.628868 -26.185195) (xy 202.644223 -26.1329) (xy 202.666865 -26.083323) (xy 202.696331 -26.037473)
			(xy 202.732022 -25.996282) (xy 202.773213 -25.960591) (xy 202.819063 -25.931125) (xy 202.86864 -25.908483)
			(xy 202.920935 -25.893128) (xy 202.974883 -25.885372) (xy 203.029385 -25.885372) (xy 203.083333 -25.893128)
			(xy 203.135628 -25.908483) (xy 203.185205 -25.931125) (xy 203.231055 -25.960591) (xy 203.272246 -25.996282)
			(xy 203.307937 -26.037473) (xy 203.337403 -26.083323) (xy 203.360045 -26.1329) (xy 203.3754 -26.185195)
			(xy 203.383156 -26.239143) (xy 203.383642 -26.266394) (xy 203.383073 -26.295881) (xy 203.37398 -26.35415)
			(xy 203.356024 -26.410324) (xy 203.329634 -26.463064) (xy 203.295439 -26.511113) (xy 203.254254 -26.553324)
			(xy 203.230988 -26.571448) (xy 203.219833 -26.580307) (xy 203.202647 -26.603017) (xy 203.1924 -26.629589)
			(xy 203.189887 -26.657958) (xy 203.195303 -26.685917) (xy 203.208228 -26.711295) (xy 203.227657 -26.732118)
			(xy 203.239624 -26.73985) (xy 203.263366 -26.754746) (xy 203.3066 -26.790414) (xy 203.344151 -26.832024)
			(xy 203.375209 -26.878679) (xy 203.399108 -26.929377) (xy 203.415333 -26.983025) (xy 203.423533 -27.03847)
			(xy 203.424028 -27.066494) (xy 203.423542 -27.093745) (xy 203.415786 -27.147693) (xy 203.400431 -27.199988)
			(xy 203.377789 -27.249565) (xy 203.348323 -27.295415) (xy 203.312632 -27.336606) (xy 203.30543 -27.342846)
			(xy 210.623404 -27.342846) (xy 210.623404 -26.479246) (xy 210.623894 -26.449262) (xy 210.631722 -26.389806)
			(xy 210.647243 -26.331881) (xy 210.670192 -26.276477) (xy 210.700176 -26.224543) (xy 210.736682 -26.176967)
			(xy 210.779087 -26.134562) (xy 210.826663 -26.098056) (xy 210.878597 -26.068072) (xy 210.934001 -26.045123)
			(xy 210.991926 -26.029602) (xy 211.051382 -26.021774) (xy 211.11135 -26.021774) (xy 211.170806 -26.029602)
			(xy 211.228731 -26.045123) (xy 211.284135 -26.068072) (xy 211.336069 -26.098056) (xy 211.383645 -26.134562)
			(xy 211.42605 -26.176967) (xy 211.462556 -26.224543) (xy 211.49254 -26.276477) (xy 211.515489 -26.331881)
			(xy 211.52326 -26.360882) (xy 213.189564 -26.360882) (xy 213.193635 -26.30526) (xy 213.205761 -26.250823)
			(xy 213.225684 -26.198732) (xy 213.25298 -26.150097) (xy 213.287066 -26.105954) (xy 213.327215 -26.067245)
			(xy 213.372573 -26.034794) (xy 213.422173 -26.009293) (xy 213.474957 -25.991286) (xy 213.5298 -25.981156)
			(xy 213.585534 -25.979119) (xy 213.640971 -25.985219) (xy 213.694928 -25.999325) (xy 213.746257 -26.021137)
			(xy 213.793863 -26.050191) (xy 213.836731 -26.085866) (xy 213.873948 -26.127403) (xy 213.904721 -26.173916)
			(xy 213.928393 -26.224413) (xy 213.944461 -26.27782) (xy 213.950629 -26.319734) (xy 218.941902 -26.319734)
			(xy 218.945973 -26.264112) (xy 218.958099 -26.209675) (xy 218.978022 -26.157584) (xy 219.005318 -26.108949)
			(xy 219.039404 -26.064806) (xy 219.079553 -26.026097) (xy 219.124911 -25.993646) (xy 219.174511 -25.968145)
			(xy 219.227295 -25.950138) (xy 219.282138 -25.940008) (xy 219.337872 -25.937971) (xy 219.393309 -25.944071)
			(xy 219.447266 -25.958177) (xy 219.498595 -25.979989) (xy 219.546201 -26.009043) (xy 219.575866 -26.03373)
			(xy 237.4679 -26.03373) (xy 237.471971 -25.978108) (xy 237.484097 -25.923671) (xy 237.50402 -25.87158)
			(xy 237.531316 -25.822945) (xy 237.565402 -25.778802) (xy 237.605551 -25.740093) (xy 237.650909 -25.707642)
			(xy 237.700509 -25.682141) (xy 237.753293 -25.664134) (xy 237.808136 -25.654004) (xy 237.86387 -25.651967)
			(xy 237.919307 -25.658067) (xy 237.973264 -25.672173) (xy 238.024593 -25.693985) (xy 238.072199 -25.723039)
			(xy 238.115067 -25.758714) (xy 238.152284 -25.800251) (xy 238.183057 -25.846764) (xy 238.206729 -25.897261)
			(xy 238.222797 -25.950668) (xy 238.230917 -26.005844) (xy 238.231426 -26.03373) (xy 238.230917 -26.061616)
			(xy 238.222797 -26.116792) (xy 238.206729 -26.170199) (xy 238.183057 -26.220696) (xy 238.152823 -26.266394)
			(xy 240.720626 -26.266394) (xy 240.721112 -26.239143) (xy 240.728868 -26.185195) (xy 240.744223 -26.1329)
			(xy 240.766865 -26.083323) (xy 240.796331 -26.037473) (xy 240.832022 -25.996282) (xy 240.873213 -25.960591)
			(xy 240.919063 -25.931125) (xy 240.96864 -25.908483) (xy 241.020935 -25.893128) (xy 241.074883 -25.885372)
			(xy 241.129385 -25.885372) (xy 241.183333 -25.893128) (xy 241.235628 -25.908483) (xy 241.285205 -25.931125)
			(xy 241.331055 -25.960591) (xy 241.372246 -25.996282) (xy 241.407937 -26.037473) (xy 241.437403 -26.083323)
			(xy 241.460045 -26.1329) (xy 241.4754 -26.185195) (xy 241.483156 -26.239143) (xy 241.483642 -26.266394)
			(xy 241.483073 -26.295881) (xy 241.47398 -26.35415) (xy 241.456024 -26.410324) (xy 241.429634 -26.463064)
			(xy 241.395439 -26.511113) (xy 241.354254 -26.553324) (xy 241.330988 -26.571448) (xy 241.319833 -26.580307)
			(xy 241.302647 -26.603017) (xy 241.2924 -26.629589) (xy 241.289887 -26.657958) (xy 241.295303 -26.685917)
			(xy 241.308228 -26.711295) (xy 241.327657 -26.732118) (xy 241.339624 -26.73985) (xy 241.363366 -26.754746)
			(xy 241.4066 -26.790414) (xy 241.444151 -26.832024) (xy 241.475209 -26.878679) (xy 241.499108 -26.929377)
			(xy 241.515333 -26.983025) (xy 241.523533 -27.03847) (xy 241.524028 -27.066494) (xy 241.523542 -27.093745)
			(xy 241.515786 -27.147693) (xy 241.500431 -27.199988) (xy 241.477789 -27.249565) (xy 241.448323 -27.295415)
			(xy 241.412632 -27.336606) (xy 241.40543 -27.342846) (xy 248.723404 -27.342846) (xy 248.723404 -26.479246)
			(xy 248.723894 -26.449262) (xy 248.731722 -26.389806) (xy 248.747243 -26.331881) (xy 248.770192 -26.276477)
			(xy 248.800176 -26.224543) (xy 248.836682 -26.176967) (xy 248.879087 -26.134562) (xy 248.926663 -26.098056)
			(xy 248.978597 -26.068072) (xy 249.034001 -26.045123) (xy 249.091926 -26.029602) (xy 249.151382 -26.021774)
			(xy 249.21135 -26.021774) (xy 249.270806 -26.029602) (xy 249.328731 -26.045123) (xy 249.384135 -26.068072)
			(xy 249.436069 -26.098056) (xy 249.483645 -26.134562) (xy 249.52605 -26.176967) (xy 249.562556 -26.224543)
			(xy 249.59254 -26.276477) (xy 249.615489 -26.331881) (xy 249.62326 -26.360882) (xy 251.289564 -26.360882)
			(xy 251.293635 -26.30526) (xy 251.305761 -26.250823) (xy 251.325684 -26.198732) (xy 251.35298 -26.150097)
			(xy 251.387066 -26.105954) (xy 251.427215 -26.067245) (xy 251.472573 -26.034794) (xy 251.522173 -26.009293)
			(xy 251.574957 -25.991286) (xy 251.6298 -25.981156) (xy 251.685534 -25.979119) (xy 251.740971 -25.985219)
			(xy 251.794928 -25.999325) (xy 251.846257 -26.021137) (xy 251.893863 -26.050191) (xy 251.936731 -26.085866)
			(xy 251.973948 -26.127403) (xy 252.004721 -26.173916) (xy 252.028393 -26.224413) (xy 252.044461 -26.27782)
			(xy 252.050629 -26.319734) (xy 257.041902 -26.319734) (xy 257.045973 -26.264112) (xy 257.058099 -26.209675)
			(xy 257.078022 -26.157584) (xy 257.105318 -26.108949) (xy 257.139404 -26.064806) (xy 257.179553 -26.026097)
			(xy 257.224911 -25.993646) (xy 257.274511 -25.968145) (xy 257.327295 -25.950138) (xy 257.382138 -25.940008)
			(xy 257.437872 -25.937971) (xy 257.493309 -25.944071) (xy 257.547266 -25.958177) (xy 257.598595 -25.979989)
			(xy 257.646201 -26.009043) (xy 257.675866 -26.03373) (xy 263.467848 -26.03373) (xy 263.471919 -25.978108)
			(xy 263.484045 -25.923671) (xy 263.503968 -25.87158) (xy 263.531264 -25.822945) (xy 263.56535 -25.778802)
			(xy 263.605499 -25.740093) (xy 263.650857 -25.707642) (xy 263.700457 -25.682141) (xy 263.753241 -25.664134)
			(xy 263.808084 -25.654004) (xy 263.863818 -25.651967) (xy 263.919255 -25.658067) (xy 263.973212 -25.672173)
			(xy 264.024541 -25.693985) (xy 264.072147 -25.723039) (xy 264.115015 -25.758714) (xy 264.152232 -25.800251)
			(xy 264.183005 -25.846764) (xy 264.206677 -25.897261) (xy 264.222745 -25.950668) (xy 264.230865 -26.005844)
			(xy 264.231374 -26.03373) (xy 264.230865 -26.061616) (xy 264.222745 -26.116792) (xy 264.206677 -26.170199)
			(xy 264.183005 -26.220696) (xy 264.152771 -26.266394) (xy 266.720574 -26.266394) (xy 266.72106 -26.239143)
			(xy 266.728816 -26.185195) (xy 266.744171 -26.1329) (xy 266.766813 -26.083323) (xy 266.796279 -26.037473)
			(xy 266.83197 -25.996282) (xy 266.873161 -25.960591) (xy 266.919011 -25.931125) (xy 266.968588 -25.908483)
			(xy 267.020883 -25.893128) (xy 267.074831 -25.885372) (xy 267.129333 -25.885372) (xy 267.183281 -25.893128)
			(xy 267.235576 -25.908483) (xy 267.285153 -25.931125) (xy 267.331003 -25.960591) (xy 267.372194 -25.996282)
			(xy 267.407885 -26.037473) (xy 267.437351 -26.083323) (xy 267.459993 -26.1329) (xy 267.475348 -26.185195)
			(xy 267.483104 -26.239143) (xy 267.48359 -26.266394) (xy 267.483042 -26.295882) (xy 267.473947 -26.354153)
			(xy 267.455988 -26.410328) (xy 267.429594 -26.463069) (xy 267.395395 -26.511117) (xy 267.354205 -26.553326)
			(xy 267.330936 -26.571448) (xy 267.319789 -26.580314) (xy 267.302613 -26.603025) (xy 267.292371 -26.629594)
			(xy 267.28986 -26.657958) (xy 267.295273 -26.685913) (xy 267.308191 -26.711289) (xy 267.32761 -26.732114)
			(xy 267.339572 -26.73985) (xy 267.363302 -26.754765) (xy 267.406539 -26.790428) (xy 267.444092 -26.832033)
			(xy 267.475153 -26.878685) (xy 267.499054 -26.929381) (xy 267.51528 -26.983027) (xy 267.523481 -27.038471)
			(xy 267.523976 -27.066494) (xy 267.52349 -27.093745) (xy 267.515734 -27.147693) (xy 267.500379 -27.199988)
			(xy 267.477737 -27.249565) (xy 267.448271 -27.295415) (xy 267.41258 -27.336606) (xy 267.405378 -27.342846)
			(xy 274.723352 -27.342846) (xy 274.723352 -26.479246) (xy 274.723842 -26.449262) (xy 274.73167 -26.389806)
			(xy 274.747191 -26.331881) (xy 274.77014 -26.276477) (xy 274.800124 -26.224543) (xy 274.83663 -26.176967)
			(xy 274.879035 -26.134562) (xy 274.926611 -26.098056) (xy 274.978545 -26.068072) (xy 275.033949 -26.045123)
			(xy 275.091874 -26.029602) (xy 275.15133 -26.021774) (xy 275.211298 -26.021774) (xy 275.270754 -26.029602)
			(xy 275.328679 -26.045123) (xy 275.384083 -26.068072) (xy 275.436017 -26.098056) (xy 275.483593 -26.134562)
			(xy 275.525998 -26.176967) (xy 275.562504 -26.224543) (xy 275.592488 -26.276477) (xy 275.615437 -26.331881)
			(xy 275.623208 -26.360882) (xy 277.289512 -26.360882) (xy 277.293583 -26.30526) (xy 277.305709 -26.250823)
			(xy 277.325632 -26.198732) (xy 277.352928 -26.150097) (xy 277.387014 -26.105954) (xy 277.427163 -26.067245)
			(xy 277.472521 -26.034794) (xy 277.522121 -26.009293) (xy 277.574905 -25.991286) (xy 277.629748 -25.981156)
			(xy 277.685482 -25.979119) (xy 277.740919 -25.985219) (xy 277.794876 -25.999325) (xy 277.846205 -26.021137)
			(xy 277.893811 -26.050191) (xy 277.936679 -26.085866) (xy 277.973896 -26.127403) (xy 278.004669 -26.173916)
			(xy 278.028341 -26.224413) (xy 278.044409 -26.27782) (xy 278.050577 -26.319734) (xy 283.04185 -26.319734)
			(xy 283.045921 -26.264112) (xy 283.058047 -26.209675) (xy 283.07797 -26.157584) (xy 283.105266 -26.108949)
			(xy 283.139352 -26.064806) (xy 283.179501 -26.026097) (xy 283.224859 -25.993646) (xy 283.274459 -25.968145)
			(xy 283.327243 -25.950138) (xy 283.382086 -25.940008) (xy 283.43782 -25.937971) (xy 283.493257 -25.944071)
			(xy 283.547214 -25.958177) (xy 283.598543 -25.979989) (xy 283.646149 -26.009043) (xy 283.675814 -26.03373)
			(xy 289.467796 -26.03373) (xy 289.471867 -25.978108) (xy 289.483993 -25.923671) (xy 289.503916 -25.87158)
			(xy 289.531212 -25.822945) (xy 289.565298 -25.778802) (xy 289.605447 -25.740093) (xy 289.650805 -25.707642)
			(xy 289.700405 -25.682141) (xy 289.753189 -25.664134) (xy 289.808032 -25.654004) (xy 289.863766 -25.651967)
			(xy 289.919203 -25.658067) (xy 289.97316 -25.672173) (xy 290.024489 -25.693985) (xy 290.072095 -25.723039)
			(xy 290.114963 -25.758714) (xy 290.15218 -25.800251) (xy 290.182953 -25.846764) (xy 290.206625 -25.897261)
			(xy 290.222693 -25.950668) (xy 290.230813 -26.005844) (xy 290.231322 -26.03373) (xy 290.230813 -26.061616)
			(xy 290.222693 -26.116792) (xy 290.206625 -26.170199) (xy 290.182953 -26.220696) (xy 290.152719 -26.266394)
			(xy 292.720522 -26.266394) (xy 292.721008 -26.239143) (xy 292.728764 -26.185195) (xy 292.744119 -26.1329)
			(xy 292.766761 -26.083323) (xy 292.796227 -26.037473) (xy 292.831918 -25.996282) (xy 292.873109 -25.960591)
			(xy 292.918959 -25.931125) (xy 292.968536 -25.908483) (xy 293.020831 -25.893128) (xy 293.074779 -25.885372)
			(xy 293.129281 -25.885372) (xy 293.183229 -25.893128) (xy 293.235524 -25.908483) (xy 293.285101 -25.931125)
			(xy 293.330951 -25.960591) (xy 293.372142 -25.996282) (xy 293.407833 -26.037473) (xy 293.437299 -26.083323)
			(xy 293.459941 -26.1329) (xy 293.475296 -26.185195) (xy 293.483052 -26.239143) (xy 293.483538 -26.266394)
			(xy 293.482971 -26.295881) (xy 293.473877 -26.35415) (xy 293.455921 -26.410324) (xy 293.429531 -26.463064)
			(xy 293.395335 -26.511113) (xy 293.35415 -26.553324) (xy 293.330884 -26.571448) (xy 293.319729 -26.580308)
			(xy 293.302545 -26.603018) (xy 293.292298 -26.62959) (xy 293.289785 -26.657958) (xy 293.295201 -26.685917)
			(xy 293.308125 -26.711294) (xy 293.327553 -26.732118) (xy 293.33952 -26.73985) (xy 293.363261 -26.754748)
			(xy 293.406495 -26.790415) (xy 293.444046 -26.832024) (xy 293.475105 -26.87868) (xy 293.499004 -26.929377)
			(xy 293.515228 -26.983025) (xy 293.523429 -27.03847) (xy 293.523924 -27.066494) (xy 293.523438 -27.093745)
			(xy 293.515682 -27.147693) (xy 293.500327 -27.199988) (xy 293.477685 -27.249565) (xy 293.448219 -27.295415)
			(xy 293.412528 -27.336606) (xy 293.405326 -27.342846) (xy 300.7233 -27.342846) (xy 300.7233 -26.479246)
			(xy 300.72379 -26.449262) (xy 300.731618 -26.389806) (xy 300.747139 -26.331881) (xy 300.770088 -26.276477)
			(xy 300.800072 -26.224543) (xy 300.836578 -26.176967) (xy 300.878983 -26.134562) (xy 300.926559 -26.098056)
			(xy 300.978493 -26.068072) (xy 301.033897 -26.045123) (xy 301.091822 -26.029602) (xy 301.151278 -26.021774)
			(xy 301.211246 -26.021774) (xy 301.270702 -26.029602) (xy 301.328627 -26.045123) (xy 301.384031 -26.068072)
			(xy 301.435965 -26.098056) (xy 301.483541 -26.134562) (xy 301.525946 -26.176967) (xy 301.562452 -26.224543)
			(xy 301.592436 -26.276477) (xy 301.615385 -26.331881) (xy 301.623156 -26.360882) (xy 303.28946 -26.360882)
			(xy 303.293531 -26.30526) (xy 303.305657 -26.250823) (xy 303.32558 -26.198732) (xy 303.352876 -26.150097)
			(xy 303.386962 -26.105954) (xy 303.427111 -26.067245) (xy 303.472469 -26.034794) (xy 303.522069 -26.009293)
			(xy 303.574853 -25.991286) (xy 303.629696 -25.981156) (xy 303.68543 -25.979119) (xy 303.740867 -25.985219)
			(xy 303.794824 -25.999325) (xy 303.846153 -26.021137) (xy 303.893759 -26.050191) (xy 303.936627 -26.085866)
			(xy 303.973844 -26.127403) (xy 304.004617 -26.173916) (xy 304.028289 -26.224413) (xy 304.044357 -26.27782)
			(xy 304.050525 -26.319734) (xy 309.041798 -26.319734) (xy 309.045869 -26.264112) (xy 309.057995 -26.209675)
			(xy 309.077918 -26.157584) (xy 309.105214 -26.108949) (xy 309.1393 -26.064806) (xy 309.179449 -26.026097)
			(xy 309.224807 -25.993646) (xy 309.274407 -25.968145) (xy 309.327191 -25.950138) (xy 309.382034 -25.940008)
			(xy 309.437768 -25.937971) (xy 309.493205 -25.944071) (xy 309.547162 -25.958177) (xy 309.598491 -25.979989)
			(xy 309.646097 -26.009043) (xy 309.675762 -26.03373) (xy 315.467744 -26.03373) (xy 315.471815 -25.978108)
			(xy 315.483941 -25.923671) (xy 315.503864 -25.87158) (xy 315.53116 -25.822945) (xy 315.565246 -25.778802)
			(xy 315.605395 -25.740093) (xy 315.650753 -25.707642) (xy 315.700353 -25.682141) (xy 315.753137 -25.664134)
			(xy 315.80798 -25.654004) (xy 315.863714 -25.651967) (xy 315.919151 -25.658067) (xy 315.973108 -25.672173)
			(xy 316.024437 -25.693985) (xy 316.072043 -25.723039) (xy 316.114911 -25.758714) (xy 316.152128 -25.800251)
			(xy 316.182901 -25.846764) (xy 316.206573 -25.897261) (xy 316.222641 -25.950668) (xy 316.230761 -26.005844)
			(xy 316.23127 -26.03373) (xy 316.230761 -26.061616) (xy 316.222641 -26.116792) (xy 316.206573 -26.170199)
			(xy 316.182901 -26.220696) (xy 316.152667 -26.266394) (xy 318.72047 -26.266394) (xy 318.720956 -26.239143)
			(xy 318.728712 -26.185195) (xy 318.744067 -26.1329) (xy 318.766709 -26.083323) (xy 318.796175 -26.037473)
			(xy 318.831866 -25.996282) (xy 318.873057 -25.960591) (xy 318.918907 -25.931125) (xy 318.968484 -25.908483)
			(xy 319.020779 -25.893128) (xy 319.074727 -25.885372) (xy 319.129229 -25.885372) (xy 319.183177 -25.893128)
			(xy 319.235472 -25.908483) (xy 319.285049 -25.931125) (xy 319.330899 -25.960591) (xy 319.37209 -25.996282)
			(xy 319.407781 -26.037473) (xy 319.437247 -26.083323) (xy 319.459889 -26.1329) (xy 319.475244 -26.185195)
			(xy 319.483 -26.239143) (xy 319.483486 -26.266394) (xy 319.48294 -26.295882) (xy 319.473844 -26.354153)
			(xy 319.455886 -26.410329) (xy 319.429491 -26.463069) (xy 319.395291 -26.511117) (xy 319.354101 -26.553326)
			(xy 319.330832 -26.571448) (xy 319.319685 -26.580314) (xy 319.30251 -26.603025) (xy 319.292269 -26.629594)
			(xy 319.289758 -26.657958) (xy 319.295171 -26.685913) (xy 319.308088 -26.711288) (xy 319.327506 -26.732114)
			(xy 319.339468 -26.73985) (xy 319.363197 -26.754766) (xy 319.406434 -26.790429) (xy 319.443987 -26.832034)
			(xy 319.475049 -26.878686) (xy 319.49895 -26.929381) (xy 319.515176 -26.983027) (xy 319.523377 -27.038471)
			(xy 319.523872 -27.066494) (xy 319.523386 -27.093745) (xy 319.51563 -27.147693) (xy 319.500275 -27.199988)
			(xy 319.477633 -27.249565) (xy 319.448167 -27.295415) (xy 319.412476 -27.336606) (xy 319.405274 -27.342846)
			(xy 326.723248 -27.342846) (xy 326.723248 -26.479246) (xy 326.723738 -26.449262) (xy 326.731566 -26.389806)
			(xy 326.747087 -26.331881) (xy 326.770036 -26.276477) (xy 326.80002 -26.224543) (xy 326.836526 -26.176967)
			(xy 326.878931 -26.134562) (xy 326.926507 -26.098056) (xy 326.978441 -26.068072) (xy 327.033845 -26.045123)
			(xy 327.09177 -26.029602) (xy 327.151226 -26.021774) (xy 327.211194 -26.021774) (xy 327.27065 -26.029602)
			(xy 327.328575 -26.045123) (xy 327.383979 -26.068072) (xy 327.435913 -26.098056) (xy 327.483489 -26.134562)
			(xy 327.525894 -26.176967) (xy 327.5624 -26.224543) (xy 327.592384 -26.276477) (xy 327.615333 -26.331881)
			(xy 327.623104 -26.360882) (xy 329.289408 -26.360882) (xy 329.293479 -26.30526) (xy 329.305605 -26.250823)
			(xy 329.325528 -26.198732) (xy 329.352824 -26.150097) (xy 329.38691 -26.105954) (xy 329.427059 -26.067245)
			(xy 329.472417 -26.034794) (xy 329.522017 -26.009293) (xy 329.574801 -25.991286) (xy 329.629644 -25.981156)
			(xy 329.685378 -25.979119) (xy 329.740815 -25.985219) (xy 329.794772 -25.999325) (xy 329.846101 -26.021137)
			(xy 329.893707 -26.050191) (xy 329.936575 -26.085866) (xy 329.973792 -26.127403) (xy 330.004565 -26.173916)
			(xy 330.028237 -26.224413) (xy 330.044305 -26.27782) (xy 330.050473 -26.319734) (xy 335.041746 -26.319734)
			(xy 335.045817 -26.264112) (xy 335.057943 -26.209675) (xy 335.077866 -26.157584) (xy 335.105162 -26.108949)
			(xy 335.139248 -26.064806) (xy 335.179397 -26.026097) (xy 335.224755 -25.993646) (xy 335.274355 -25.968145)
			(xy 335.327139 -25.950138) (xy 335.381982 -25.940008) (xy 335.437716 -25.937971) (xy 335.493153 -25.944071)
			(xy 335.54711 -25.958177) (xy 335.598439 -25.979989) (xy 335.646045 -26.009043) (xy 335.67571 -26.03373)
			(xy 353.567998 -26.03373) (xy 353.572069 -25.978108) (xy 353.584195 -25.923671) (xy 353.604118 -25.87158)
			(xy 353.631414 -25.822945) (xy 353.6655 -25.778802) (xy 353.705649 -25.740093) (xy 353.751007 -25.707642)
			(xy 353.800607 -25.682141) (xy 353.853391 -25.664134) (xy 353.908234 -25.654004) (xy 353.963968 -25.651967)
			(xy 354.019405 -25.658067) (xy 354.073362 -25.672173) (xy 354.124691 -25.693985) (xy 354.172297 -25.723039)
			(xy 354.215165 -25.758714) (xy 354.252382 -25.800251) (xy 354.283155 -25.846764) (xy 354.306827 -25.897261)
			(xy 354.322895 -25.950668) (xy 354.331015 -26.005844) (xy 354.331524 -26.03373) (xy 354.331015 -26.061616)
			(xy 354.322895 -26.116792) (xy 354.306827 -26.170199) (xy 354.283155 -26.220696) (xy 354.252921 -26.266394)
			(xy 356.820724 -26.266394) (xy 356.82121 -26.239143) (xy 356.828966 -26.185195) (xy 356.844321 -26.1329)
			(xy 356.866963 -26.083323) (xy 356.896429 -26.037473) (xy 356.93212 -25.996282) (xy 356.973311 -25.960591)
			(xy 357.019161 -25.931125) (xy 357.068738 -25.908483) (xy 357.121033 -25.893128) (xy 357.174981 -25.885372)
			(xy 357.229483 -25.885372) (xy 357.283431 -25.893128) (xy 357.335726 -25.908483) (xy 357.385303 -25.931125)
			(xy 357.431153 -25.960591) (xy 357.472344 -25.996282) (xy 357.508035 -26.037473) (xy 357.537501 -26.083323)
			(xy 357.560143 -26.1329) (xy 357.575498 -26.185195) (xy 357.583254 -26.239143) (xy 357.58374 -26.266394)
			(xy 357.583172 -26.295881) (xy 357.574079 -26.35415) (xy 357.556122 -26.410324) (xy 357.529732 -26.463064)
			(xy 357.495537 -26.511113) (xy 357.454352 -26.553324) (xy 357.431086 -26.571448) (xy 357.419931 -26.580308)
			(xy 357.402746 -26.603018) (xy 357.392499 -26.62959) (xy 357.389986 -26.657958) (xy 357.395402 -26.685917)
			(xy 357.408327 -26.711295) (xy 357.427755 -26.732118) (xy 357.439722 -26.73985) (xy 357.463464 -26.754747)
			(xy 357.506698 -26.790415) (xy 357.544248 -26.832024) (xy 357.575307 -26.878679) (xy 357.599206 -26.929377)
			(xy 357.61543 -26.983025) (xy 357.623631 -27.03847) (xy 357.624126 -27.066494) (xy 357.62364 -27.093745)
			(xy 357.615884 -27.147693) (xy 357.600529 -27.199988) (xy 357.577887 -27.249565) (xy 357.548421 -27.295415)
			(xy 357.51273 -27.336606) (xy 357.505528 -27.342846) (xy 364.823756 -27.342846) (xy 364.823756 -26.479246)
			(xy 364.824246 -26.449278) (xy 364.832069 -26.389856) (xy 364.847582 -26.331963) (xy 364.870518 -26.27659)
			(xy 364.900485 -26.224684) (xy 364.936972 -26.177134) (xy 364.979352 -26.134754) (xy 365.026902 -26.098267)
			(xy 365.078808 -26.0683) (xy 365.134181 -26.045364) (xy 365.192074 -26.029851) (xy 365.251496 -26.022028)
			(xy 365.311432 -26.022028) (xy 365.370854 -26.029851) (xy 365.428747 -26.045364) (xy 365.48412 -26.0683)
			(xy 365.536026 -26.098267) (xy 365.583576 -26.134754) (xy 365.625956 -26.177134) (xy 365.662443 -26.224684)
			(xy 365.69241 -26.27659) (xy 365.715346 -26.331963) (xy 365.723095 -26.360882) (xy 367.389662 -26.360882)
			(xy 367.393733 -26.30526) (xy 367.405859 -26.250823) (xy 367.425782 -26.198732) (xy 367.453078 -26.150097)
			(xy 367.487164 -26.105954) (xy 367.527313 -26.067245) (xy 367.572671 -26.034794) (xy 367.622271 -26.009293)
			(xy 367.675055 -25.991286) (xy 367.729898 -25.981156) (xy 367.785632 -25.979119) (xy 367.841069 -25.985219)
			(xy 367.895026 -25.999325) (xy 367.946355 -26.021137) (xy 367.993961 -26.050191) (xy 368.036829 -26.085866)
			(xy 368.074046 -26.127403) (xy 368.104819 -26.173916) (xy 368.128491 -26.224413) (xy 368.144559 -26.27782)
			(xy 368.150727 -26.319734) (xy 373.142 -26.319734) (xy 373.146071 -26.264112) (xy 373.158197 -26.209675)
			(xy 373.17812 -26.157584) (xy 373.205416 -26.108949) (xy 373.239502 -26.064806) (xy 373.279651 -26.026097)
			(xy 373.325009 -25.993646) (xy 373.374609 -25.968145) (xy 373.427393 -25.950138) (xy 373.482236 -25.940008)
			(xy 373.53797 -25.937971) (xy 373.593407 -25.944071) (xy 373.647364 -25.958177) (xy 373.698693 -25.979989)
			(xy 373.746299 -26.009043) (xy 373.775964 -26.03373) (xy 379.567946 -26.03373) (xy 379.572017 -25.978108)
			(xy 379.584143 -25.923671) (xy 379.604066 -25.87158) (xy 379.631362 -25.822945) (xy 379.665448 -25.778802)
			(xy 379.705597 -25.740093) (xy 379.750955 -25.707642) (xy 379.800555 -25.682141) (xy 379.853339 -25.664134)
			(xy 379.908182 -25.654004) (xy 379.963916 -25.651967) (xy 380.019353 -25.658067) (xy 380.07331 -25.672173)
			(xy 380.124639 -25.693985) (xy 380.172245 -25.723039) (xy 380.215113 -25.758714) (xy 380.25233 -25.800251)
			(xy 380.283103 -25.846764) (xy 380.306775 -25.897261) (xy 380.322843 -25.950668) (xy 380.330963 -26.005844)
			(xy 380.331472 -26.03373) (xy 380.330963 -26.061616) (xy 380.322843 -26.116792) (xy 380.306775 -26.170199)
			(xy 380.283103 -26.220696) (xy 380.252869 -26.266394) (xy 382.820672 -26.266394) (xy 382.821158 -26.239143)
			(xy 382.828914 -26.185195) (xy 382.844269 -26.1329) (xy 382.866911 -26.083323) (xy 382.896377 -26.037473)
			(xy 382.932068 -25.996282) (xy 382.973259 -25.960591) (xy 383.019109 -25.931125) (xy 383.068686 -25.908483)
			(xy 383.120981 -25.893128) (xy 383.174929 -25.885372) (xy 383.229431 -25.885372) (xy 383.283379 -25.893128)
			(xy 383.335674 -25.908483) (xy 383.385251 -25.931125) (xy 383.431101 -25.960591) (xy 383.472292 -25.996282)
			(xy 383.507983 -26.037473) (xy 383.537449 -26.083323) (xy 383.560091 -26.1329) (xy 383.575446 -26.185195)
			(xy 383.583202 -26.239143) (xy 383.583688 -26.266394) (xy 383.583141 -26.295882) (xy 383.574046 -26.354153)
			(xy 383.556087 -26.410329) (xy 383.529693 -26.463069) (xy 383.495493 -26.511117) (xy 383.454303 -26.553326)
			(xy 383.431034 -26.571448) (xy 383.419887 -26.580314) (xy 383.402711 -26.603025) (xy 383.39247 -26.629594)
			(xy 383.389959 -26.657958) (xy 383.395372 -26.685913) (xy 383.40829 -26.711289) (xy 383.427708 -26.732114)
			(xy 383.43967 -26.73985) (xy 383.4634 -26.754766) (xy 383.506636 -26.790428) (xy 383.54419 -26.832033)
			(xy 383.575251 -26.878686) (xy 383.599152 -26.929381) (xy 383.615378 -26.983027) (xy 383.623579 -27.038471)
			(xy 383.624074 -27.066494) (xy 383.623588 -27.093745) (xy 383.615832 -27.147693) (xy 383.600477 -27.199988)
			(xy 383.577835 -27.249565) (xy 383.548369 -27.295415) (xy 383.512678 -27.336606) (xy 383.505476 -27.342846)
			(xy 390.823704 -27.342846) (xy 390.823704 -26.479246) (xy 390.824194 -26.449278) (xy 390.832017 -26.389856)
			(xy 390.84753 -26.331963) (xy 390.870466 -26.27659) (xy 390.900433 -26.224684) (xy 390.93692 -26.177134)
			(xy 390.9793 -26.134754) (xy 391.02685 -26.098267) (xy 391.078756 -26.0683) (xy 391.134129 -26.045364)
			(xy 391.192022 -26.029851) (xy 391.251444 -26.022028) (xy 391.31138 -26.022028) (xy 391.370802 -26.029851)
			(xy 391.428695 -26.045364) (xy 391.484068 -26.0683) (xy 391.535974 -26.098267) (xy 391.583524 -26.134754)
			(xy 391.625904 -26.177134) (xy 391.662391 -26.224684) (xy 391.692358 -26.27659) (xy 391.715294 -26.331963)
			(xy 391.723043 -26.360882) (xy 393.38961 -26.360882) (xy 393.393681 -26.30526) (xy 393.405807 -26.250823)
			(xy 393.42573 -26.198732) (xy 393.453026 -26.150097) (xy 393.487112 -26.105954) (xy 393.527261 -26.067245)
			(xy 393.572619 -26.034794) (xy 393.622219 -26.009293) (xy 393.675003 -25.991286) (xy 393.729846 -25.981156)
			(xy 393.78558 -25.979119) (xy 393.841017 -25.985219) (xy 393.894974 -25.999325) (xy 393.946303 -26.021137)
			(xy 393.993909 -26.050191) (xy 394.036777 -26.085866) (xy 394.073994 -26.127403) (xy 394.104767 -26.173916)
			(xy 394.128439 -26.224413) (xy 394.144507 -26.27782) (xy 394.150675 -26.319734) (xy 399.141948 -26.319734)
			(xy 399.146019 -26.264112) (xy 399.158145 -26.209675) (xy 399.178068 -26.157584) (xy 399.205364 -26.108949)
			(xy 399.23945 -26.064806) (xy 399.279599 -26.026097) (xy 399.324957 -25.993646) (xy 399.374557 -25.968145)
			(xy 399.427341 -25.950138) (xy 399.482184 -25.940008) (xy 399.537918 -25.937971) (xy 399.593355 -25.944071)
			(xy 399.647312 -25.958177) (xy 399.698641 -25.979989) (xy 399.746247 -26.009043) (xy 399.775912 -26.03373)
			(xy 405.567894 -26.03373) (xy 405.571965 -25.978108) (xy 405.584091 -25.923671) (xy 405.604014 -25.87158)
			(xy 405.63131 -25.822945) (xy 405.665396 -25.778802) (xy 405.705545 -25.740093) (xy 405.750903 -25.707642)
			(xy 405.800503 -25.682141) (xy 405.853287 -25.664134) (xy 405.90813 -25.654004) (xy 405.963864 -25.651967)
			(xy 406.019301 -25.658067) (xy 406.073258 -25.672173) (xy 406.124587 -25.693985) (xy 406.172193 -25.723039)
			(xy 406.215061 -25.758714) (xy 406.252278 -25.800251) (xy 406.283051 -25.846764) (xy 406.306723 -25.897261)
			(xy 406.322791 -25.950668) (xy 406.330911 -26.005844) (xy 406.33142 -26.03373) (xy 406.330911 -26.061616)
			(xy 406.322791 -26.116792) (xy 406.306723 -26.170199) (xy 406.283051 -26.220696) (xy 406.252817 -26.266394)
			(xy 408.82062 -26.266394) (xy 408.821106 -26.239143) (xy 408.828862 -26.185195) (xy 408.844217 -26.1329)
			(xy 408.866859 -26.083323) (xy 408.896325 -26.037473) (xy 408.932016 -25.996282) (xy 408.973207 -25.960591)
			(xy 409.019057 -25.931125) (xy 409.068634 -25.908483) (xy 409.120929 -25.893128) (xy 409.174877 -25.885372)
			(xy 409.229379 -25.885372) (xy 409.283327 -25.893128) (xy 409.335622 -25.908483) (xy 409.385199 -25.931125)
			(xy 409.431049 -25.960591) (xy 409.47224 -25.996282) (xy 409.507931 -26.037473) (xy 409.537397 -26.083323)
			(xy 409.560039 -26.1329) (xy 409.575394 -26.185195) (xy 409.58315 -26.239143) (xy 409.583636 -26.266394)
			(xy 409.58307 -26.295881) (xy 409.573976 -26.35415) (xy 409.55602 -26.410325) (xy 409.529629 -26.463065)
			(xy 409.495434 -26.511113) (xy 409.454248 -26.553324) (xy 409.430982 -26.571448) (xy 409.419828 -26.580308)
			(xy 409.402643 -26.603018) (xy 409.392397 -26.62959) (xy 409.389884 -26.657958) (xy 409.3953 -26.685917)
			(xy 409.408224 -26.711294) (xy 409.427652 -26.732118) (xy 409.439618 -26.73985) (xy 409.463359 -26.754748)
			(xy 409.506593 -26.790416) (xy 409.544144 -26.832025) (xy 409.575203 -26.87868) (xy 409.599102 -26.929377)
			(xy 409.615326 -26.983025) (xy 409.623527 -27.03847) (xy 409.624022 -27.066494) (xy 409.623536 -27.093745)
			(xy 409.61578 -27.147693) (xy 409.600425 -27.199988) (xy 409.577783 -27.249565) (xy 409.548317 -27.295415)
			(xy 409.512626 -27.336606) (xy 409.505424 -27.342846) (xy 416.823652 -27.342846) (xy 416.823652 -26.479246)
			(xy 416.824142 -26.449278) (xy 416.831965 -26.389856) (xy 416.847478 -26.331963) (xy 416.870414 -26.27659)
			(xy 416.900381 -26.224684) (xy 416.936868 -26.177134) (xy 416.979248 -26.134754) (xy 417.026798 -26.098267)
			(xy 417.078704 -26.0683) (xy 417.134077 -26.045364) (xy 417.19197 -26.029851) (xy 417.251392 -26.022028)
			(xy 417.311328 -26.022028) (xy 417.37075 -26.029851) (xy 417.428643 -26.045364) (xy 417.484016 -26.0683)
			(xy 417.535922 -26.098267) (xy 417.583472 -26.134754) (xy 417.625852 -26.177134) (xy 417.662339 -26.224684)
			(xy 417.692306 -26.27659) (xy 417.715242 -26.331963) (xy 417.722991 -26.360882) (xy 419.389558 -26.360882)
			(xy 419.393629 -26.30526) (xy 419.405755 -26.250823) (xy 419.425678 -26.198732) (xy 419.452974 -26.150097)
			(xy 419.48706 -26.105954) (xy 419.527209 -26.067245) (xy 419.572567 -26.034794) (xy 419.622167 -26.009293)
			(xy 419.674951 -25.991286) (xy 419.729794 -25.981156) (xy 419.785528 -25.979119) (xy 419.840965 -25.985219)
			(xy 419.894922 -25.999325) (xy 419.946251 -26.021137) (xy 419.993857 -26.050191) (xy 420.036725 -26.085866)
			(xy 420.073942 -26.127403) (xy 420.104715 -26.173916) (xy 420.128387 -26.224413) (xy 420.144455 -26.27782)
			(xy 420.150623 -26.319734) (xy 425.141896 -26.319734) (xy 425.145967 -26.264112) (xy 425.158093 -26.209675)
			(xy 425.178016 -26.157584) (xy 425.205312 -26.108949) (xy 425.239398 -26.064806) (xy 425.279547 -26.026097)
			(xy 425.324905 -25.993646) (xy 425.374505 -25.968145) (xy 425.427289 -25.950138) (xy 425.482132 -25.940008)
			(xy 425.537866 -25.937971) (xy 425.593303 -25.944071) (xy 425.64726 -25.958177) (xy 425.698589 -25.979989)
			(xy 425.746195 -26.009043) (xy 425.77586 -26.03373) (xy 431.567842 -26.03373) (xy 431.571913 -25.978108)
			(xy 431.584039 -25.923671) (xy 431.603962 -25.87158) (xy 431.631258 -25.822945) (xy 431.665344 -25.778802)
			(xy 431.705493 -25.740093) (xy 431.750851 -25.707642) (xy 431.800451 -25.682141) (xy 431.853235 -25.664134)
			(xy 431.908078 -25.654004) (xy 431.963812 -25.651967) (xy 432.019249 -25.658067) (xy 432.073206 -25.672173)
			(xy 432.124535 -25.693985) (xy 432.172141 -25.723039) (xy 432.215009 -25.758714) (xy 432.252226 -25.800251)
			(xy 432.282999 -25.846764) (xy 432.306671 -25.897261) (xy 432.322739 -25.950668) (xy 432.330859 -26.005844)
			(xy 432.331368 -26.03373) (xy 432.330859 -26.061616) (xy 432.322739 -26.116792) (xy 432.306671 -26.170199)
			(xy 432.282999 -26.220696) (xy 432.252765 -26.266394) (xy 434.820568 -26.266394) (xy 434.821054 -26.239143)
			(xy 434.82881 -26.185195) (xy 434.844165 -26.1329) (xy 434.866807 -26.083323) (xy 434.896273 -26.037473)
			(xy 434.931964 -25.996282) (xy 434.973155 -25.960591) (xy 435.019005 -25.931125) (xy 435.068582 -25.908483)
			(xy 435.120877 -25.893128) (xy 435.174825 -25.885372) (xy 435.229327 -25.885372) (xy 435.283275 -25.893128)
			(xy 435.33557 -25.908483) (xy 435.385147 -25.931125) (xy 435.430997 -25.960591) (xy 435.472188 -25.996282)
			(xy 435.507879 -26.037473) (xy 435.537345 -26.083323) (xy 435.559987 -26.1329) (xy 435.575342 -26.185195)
			(xy 435.583098 -26.239143) (xy 435.583584 -26.266394) (xy 435.583038 -26.295882) (xy 435.573943 -26.354153)
			(xy 435.555984 -26.410329) (xy 435.52959 -26.463069) (xy 435.49539 -26.511117) (xy 435.454199 -26.553326)
			(xy 435.43093 -26.571448) (xy 435.419784 -26.580314) (xy 435.402609 -26.603026) (xy 435.392368 -26.629594)
			(xy 435.389857 -26.657958) (xy 435.39527 -26.685912) (xy 435.408187 -26.711288) (xy 435.427605 -26.732114)
			(xy 435.439566 -26.73985) (xy 435.463295 -26.754767) (xy 435.506532 -26.790429) (xy 435.544085 -26.832034)
			(xy 435.575147 -26.878686) (xy 435.599048 -26.929381) (xy 435.615274 -26.983027) (xy 435.623475 -27.038471)
			(xy 435.62397 -27.066494) (xy 435.623484 -27.093745) (xy 435.615728 -27.147693) (xy 435.600373 -27.199988)
			(xy 435.577731 -27.249565) (xy 435.548265 -27.295415) (xy 435.512574 -27.336606) (xy 435.505372 -27.342846)
			(xy 442.8236 -27.342846) (xy 442.8236 -26.479246) (xy 442.82409 -26.449278) (xy 442.831913 -26.389856)
			(xy 442.847426 -26.331963) (xy 442.870362 -26.27659) (xy 442.900329 -26.224684) (xy 442.936816 -26.177134)
			(xy 442.979196 -26.134754) (xy 443.026746 -26.098267) (xy 443.078652 -26.0683) (xy 443.134025 -26.045364)
			(xy 443.191918 -26.029851) (xy 443.25134 -26.022028) (xy 443.311276 -26.022028) (xy 443.370698 -26.029851)
			(xy 443.428591 -26.045364) (xy 443.483964 -26.0683) (xy 443.53587 -26.098267) (xy 443.58342 -26.134754)
			(xy 443.6258 -26.177134) (xy 443.662287 -26.224684) (xy 443.692254 -26.27659) (xy 443.71519 -26.331963)
			(xy 443.722939 -26.360882) (xy 445.389506 -26.360882) (xy 445.393577 -26.30526) (xy 445.405703 -26.250823)
			(xy 445.425626 -26.198732) (xy 445.452922 -26.150097) (xy 445.487008 -26.105954) (xy 445.527157 -26.067245)
			(xy 445.572515 -26.034794) (xy 445.622115 -26.009293) (xy 445.674899 -25.991286) (xy 445.729742 -25.981156)
			(xy 445.785476 -25.979119) (xy 445.840913 -25.985219) (xy 445.89487 -25.999325) (xy 445.946199 -26.021137)
			(xy 445.993805 -26.050191) (xy 446.036673 -26.085866) (xy 446.07389 -26.127403) (xy 446.104663 -26.173916)
			(xy 446.128335 -26.224413) (xy 446.144403 -26.27782) (xy 446.150571 -26.319734) (xy 451.141844 -26.319734)
			(xy 451.145915 -26.264112) (xy 451.158041 -26.209675) (xy 451.177964 -26.157584) (xy 451.20526 -26.108949)
			(xy 451.239346 -26.064806) (xy 451.279495 -26.026097) (xy 451.324853 -25.993646) (xy 451.374453 -25.968145)
			(xy 451.427237 -25.950138) (xy 451.48208 -25.940008) (xy 451.537814 -25.937971) (xy 451.593251 -25.944071)
			(xy 451.647208 -25.958177) (xy 451.698537 -25.979989) (xy 451.746143 -26.009043) (xy 451.789011 -26.044718)
			(xy 451.826228 -26.086255) (xy 451.857001 -26.132768) (xy 451.880673 -26.183265) (xy 451.896741 -26.236672)
			(xy 451.904861 -26.291848) (xy 451.90537 -26.319734) (xy 451.904861 -26.34762) (xy 451.896741 -26.402796)
			(xy 451.880673 -26.456203) (xy 451.857001 -26.5067) (xy 451.826228 -26.553213) (xy 451.789011 -26.59475)
			(xy 451.746143 -26.630425) (xy 451.698537 -26.659479) (xy 451.647208 -26.681291) (xy 451.593251 -26.695397)
			(xy 451.537814 -26.701497) (xy 451.48208 -26.69946) (xy 451.427237 -26.68933) (xy 451.374453 -26.671323)
			(xy 451.324853 -26.645822) (xy 451.279495 -26.613371) (xy 451.239346 -26.574662) (xy 451.20526 -26.530519)
			(xy 451.177964 -26.481884) (xy 451.158041 -26.429793) (xy 451.145915 -26.375356) (xy 451.141844 -26.319734)
			(xy 446.150571 -26.319734) (xy 446.152523 -26.332996) (xy 446.153032 -26.360882) (xy 446.152523 -26.388768)
			(xy 446.144403 -26.443944) (xy 446.128335 -26.497351) (xy 446.104663 -26.547848) (xy 446.07389 -26.594361)
			(xy 446.036673 -26.635898) (xy 445.993805 -26.671573) (xy 445.946199 -26.700627) (xy 445.89487 -26.722439)
			(xy 445.840913 -26.736545) (xy 445.785476 -26.742645) (xy 445.729742 -26.740608) (xy 445.674899 -26.730478)
			(xy 445.622115 -26.712471) (xy 445.572515 -26.68697) (xy 445.527157 -26.654519) (xy 445.487008 -26.61581)
			(xy 445.452922 -26.571667) (xy 445.425626 -26.523032) (xy 445.405703 -26.470941) (xy 445.393577 -26.416504)
			(xy 445.389506 -26.360882) (xy 443.722939 -26.360882) (xy 443.730703 -26.389856) (xy 443.738526 -26.449278)
			(xy 443.739016 -26.479246) (xy 443.739016 -26.971244) (xy 447.150996 -26.971244) (xy 447.155067 -26.915622)
			(xy 447.167193 -26.861185) (xy 447.187116 -26.809094) (xy 447.214412 -26.760459) (xy 447.248498 -26.716316)
			(xy 447.288647 -26.677607) (xy 447.334005 -26.645156) (xy 447.383605 -26.619655) (xy 447.436389 -26.601648)
			(xy 447.491232 -26.591518) (xy 447.546966 -26.589481) (xy 447.602403 -26.595581) (xy 447.65636 -26.609687)
			(xy 447.707689 -26.631499) (xy 447.755295 -26.660553) (xy 447.798163 -26.696228) (xy 447.83538 -26.737765)
			(xy 447.866153 -26.784278) (xy 447.889825 -26.834775) (xy 447.905893 -26.888182) (xy 447.914013 -26.943358)
			(xy 447.914522 -26.971244) (xy 447.914013 -26.99913) (xy 447.905893 -27.054306) (xy 447.889825 -27.107713)
			(xy 447.866153 -27.15821) (xy 447.83538 -27.204723) (xy 447.798163 -27.24626) (xy 447.755295 -27.281935)
			(xy 447.707689 -27.310989) (xy 447.65636 -27.332801) (xy 447.602403 -27.346907) (xy 447.546966 -27.353007)
			(xy 447.491232 -27.35097) (xy 447.436389 -27.34084) (xy 447.383605 -27.322833) (xy 447.334005 -27.297332)
			(xy 447.288647 -27.264881) (xy 447.248498 -27.226172) (xy 447.214412 -27.182029) (xy 447.187116 -27.133394)
			(xy 447.167193 -27.081303) (xy 447.155067 -27.026866) (xy 447.150996 -26.971244) (xy 443.739016 -26.971244)
			(xy 443.739016 -27.342846) (xy 443.738526 -27.372814) (xy 443.730703 -27.432236) (xy 443.71519 -27.490129)
			(xy 443.692254 -27.545502) (xy 443.662287 -27.597408) (xy 443.6258 -27.644958) (xy 443.58342 -27.687338)
			(xy 443.53587 -27.723825) (xy 443.483964 -27.753792) (xy 443.428591 -27.776728) (xy 443.370698 -27.792241)
			(xy 443.311276 -27.800064) (xy 443.25134 -27.800064) (xy 443.191918 -27.792241) (xy 443.134025 -27.776728)
			(xy 443.078652 -27.753792) (xy 443.026746 -27.723825) (xy 442.979196 -27.687338) (xy 442.936816 -27.644958)
			(xy 442.900329 -27.597408) (xy 442.870362 -27.545502) (xy 442.847426 -27.490129) (xy 442.831913 -27.432236)
			(xy 442.82409 -27.372814) (xy 442.8236 -27.342846) (xy 435.505372 -27.342846) (xy 435.471383 -27.372297)
			(xy 435.425533 -27.401763) (xy 435.375956 -27.424405) (xy 435.323661 -27.43976) (xy 435.269713 -27.447516)
			(xy 435.215211 -27.447516) (xy 435.161263 -27.43976) (xy 435.108968 -27.424405) (xy 435.059391 -27.401763)
			(xy 435.013541 -27.372297) (xy 434.97235 -27.336606) (xy 434.936659 -27.295415) (xy 434.907193 -27.249565)
			(xy 434.884551 -27.199988) (xy 434.869196 -27.147693) (xy 434.86144 -27.093745) (xy 434.860954 -27.066494)
			(xy 434.861515 -27.037007) (xy 434.870611 -26.978738) (xy 434.888568 -26.922563) (xy 434.91496 -26.869823)
			(xy 434.949156 -26.821775) (xy 434.990342 -26.779564) (xy 435.013608 -26.76144) (xy 435.024673 -26.752476)
			(xy 435.041858 -26.729791) (xy 435.052113 -26.703243) (xy 435.054638 -26.674895) (xy 435.049239 -26.646953)
			(xy 435.036334 -26.621587) (xy 435.016927 -26.60077) (xy 435.004972 -26.593038) (xy 434.981224 -26.578151)
			(xy 434.93799 -26.542482) (xy 434.90044 -26.50087) (xy 434.869382 -26.454213) (xy 434.845484 -26.403514)
			(xy 434.829261 -26.349865) (xy 434.821062 -26.294419) (xy 434.820568 -26.266394) (xy 432.252765 -26.266394)
			(xy 432.252226 -26.267209) (xy 432.215009 -26.308746) (xy 432.172141 -26.344421) (xy 432.124535 -26.373475)
			(xy 432.073206 -26.395287) (xy 432.019249 -26.409393) (xy 431.963812 -26.415493) (xy 431.908078 -26.413456)
			(xy 431.853235 -26.403326) (xy 431.800451 -26.385319) (xy 431.750851 -26.359818) (xy 431.705493 -26.327367)
			(xy 431.665344 -26.288658) (xy 431.631258 -26.244515) (xy 431.603962 -26.19588) (xy 431.584039 -26.143789)
			(xy 431.571913 -26.089352) (xy 431.567842 -26.03373) (xy 425.77586 -26.03373) (xy 425.789063 -26.044718)
			(xy 425.82628 -26.086255) (xy 425.857053 -26.132768) (xy 425.880725 -26.183265) (xy 425.896793 -26.236672)
			(xy 425.904913 -26.291848) (xy 425.905422 -26.319734) (xy 425.904913 -26.34762) (xy 425.896793 -26.402796)
			(xy 425.880725 -26.456203) (xy 425.857053 -26.5067) (xy 425.82628 -26.553213) (xy 425.789063 -26.59475)
			(xy 425.746195 -26.630425) (xy 425.698589 -26.659479) (xy 425.64726 -26.681291) (xy 425.593303 -26.695397)
			(xy 425.537866 -26.701497) (xy 425.482132 -26.69946) (xy 425.427289 -26.68933) (xy 425.374505 -26.671323)
			(xy 425.324905 -26.645822) (xy 425.279547 -26.613371) (xy 425.239398 -26.574662) (xy 425.205312 -26.530519)
			(xy 425.178016 -26.481884) (xy 425.158093 -26.429793) (xy 425.145967 -26.375356) (xy 425.141896 -26.319734)
			(xy 420.150623 -26.319734) (xy 420.152575 -26.332996) (xy 420.153084 -26.360882) (xy 420.152575 -26.388768)
			(xy 420.144455 -26.443944) (xy 420.128387 -26.497351) (xy 420.104715 -26.547848) (xy 420.073942 -26.594361)
			(xy 420.036725 -26.635898) (xy 419.993857 -26.671573) (xy 419.946251 -26.700627) (xy 419.894922 -26.722439)
			(xy 419.840965 -26.736545) (xy 419.785528 -26.742645) (xy 419.729794 -26.740608) (xy 419.674951 -26.730478)
			(xy 419.622167 -26.712471) (xy 419.572567 -26.68697) (xy 419.527209 -26.654519) (xy 419.48706 -26.61581)
			(xy 419.452974 -26.571667) (xy 419.425678 -26.523032) (xy 419.405755 -26.470941) (xy 419.393629 -26.416504)
			(xy 419.389558 -26.360882) (xy 417.722991 -26.360882) (xy 417.730755 -26.389856) (xy 417.738578 -26.449278)
			(xy 417.739068 -26.479246) (xy 417.739068 -26.971244) (xy 421.151048 -26.971244) (xy 421.155119 -26.915622)
			(xy 421.167245 -26.861185) (xy 421.187168 -26.809094) (xy 421.214464 -26.760459) (xy 421.24855 -26.716316)
			(xy 421.288699 -26.677607) (xy 421.334057 -26.645156) (xy 421.383657 -26.619655) (xy 421.436441 -26.601648)
			(xy 421.491284 -26.591518) (xy 421.547018 -26.589481) (xy 421.602455 -26.595581) (xy 421.656412 -26.609687)
			(xy 421.707741 -26.631499) (xy 421.755347 -26.660553) (xy 421.798215 -26.696228) (xy 421.835432 -26.737765)
			(xy 421.866205 -26.784278) (xy 421.889877 -26.834775) (xy 421.905945 -26.888182) (xy 421.914065 -26.943358)
			(xy 421.914574 -26.971244) (xy 421.914065 -26.99913) (xy 421.905945 -27.054306) (xy 421.889877 -27.107713)
			(xy 421.866205 -27.15821) (xy 421.835432 -27.204723) (xy 421.798215 -27.24626) (xy 421.755347 -27.281935)
			(xy 421.707741 -27.310989) (xy 421.656412 -27.332801) (xy 421.602455 -27.346907) (xy 421.547018 -27.353007)
			(xy 421.491284 -27.35097) (xy 421.436441 -27.34084) (xy 421.383657 -27.322833) (xy 421.334057 -27.297332)
			(xy 421.288699 -27.264881) (xy 421.24855 -27.226172) (xy 421.214464 -27.182029) (xy 421.187168 -27.133394)
			(xy 421.167245 -27.081303) (xy 421.155119 -27.026866) (xy 421.151048 -26.971244) (xy 417.739068 -26.971244)
			(xy 417.739068 -27.342846) (xy 417.738578 -27.372814) (xy 417.730755 -27.432236) (xy 417.715242 -27.490129)
			(xy 417.692306 -27.545502) (xy 417.662339 -27.597408) (xy 417.625852 -27.644958) (xy 417.583472 -27.687338)
			(xy 417.535922 -27.723825) (xy 417.484016 -27.753792) (xy 417.428643 -27.776728) (xy 417.37075 -27.792241)
			(xy 417.311328 -27.800064) (xy 417.251392 -27.800064) (xy 417.19197 -27.792241) (xy 417.134077 -27.776728)
			(xy 417.078704 -27.753792) (xy 417.026798 -27.723825) (xy 416.979248 -27.687338) (xy 416.936868 -27.644958)
			(xy 416.900381 -27.597408) (xy 416.870414 -27.545502) (xy 416.847478 -27.490129) (xy 416.831965 -27.432236)
			(xy 416.824142 -27.372814) (xy 416.823652 -27.342846) (xy 409.505424 -27.342846) (xy 409.471435 -27.372297)
			(xy 409.425585 -27.401763) (xy 409.376008 -27.424405) (xy 409.323713 -27.43976) (xy 409.269765 -27.447516)
			(xy 409.215263 -27.447516) (xy 409.161315 -27.43976) (xy 409.10902 -27.424405) (xy 409.059443 -27.401763)
			(xy 409.013593 -27.372297) (xy 408.972402 -27.336606) (xy 408.936711 -27.295415) (xy 408.907245 -27.249565)
			(xy 408.884603 -27.199988) (xy 408.869248 -27.147693) (xy 408.861492 -27.093745) (xy 408.861006 -27.066494)
			(xy 408.861547 -27.037006) (xy 408.870644 -26.978735) (xy 408.888604 -26.922559) (xy 408.914999 -26.869819)
			(xy 408.9492 -26.821771) (xy 408.990391 -26.779562) (xy 409.01366 -26.76144) (xy 409.024718 -26.75247)
			(xy 409.041894 -26.729784) (xy 409.052142 -26.703238) (xy 409.054665 -26.674896) (xy 409.049269 -26.646957)
			(xy 409.036371 -26.621593) (xy 409.016975 -26.600773) (xy 409.005024 -26.593038) (xy 408.981288 -26.578133)
			(xy 408.938051 -26.542468) (xy 408.900499 -26.500861) (xy 408.869438 -26.454207) (xy 408.845538 -26.40351)
			(xy 408.829314 -26.349862) (xy 408.821114 -26.294418) (xy 408.82062 -26.266394) (xy 406.252817 -26.266394)
			(xy 406.252278 -26.267209) (xy 406.215061 -26.308746) (xy 406.172193 -26.344421) (xy 406.124587 -26.373475)
			(xy 406.073258 -26.395287) (xy 406.019301 -26.409393) (xy 405.963864 -26.415493) (xy 405.90813 -26.413456)
			(xy 405.853287 -26.403326) (xy 405.800503 -26.385319) (xy 405.750903 -26.359818) (xy 405.705545 -26.327367)
			(xy 405.665396 -26.288658) (xy 405.63131 -26.244515) (xy 405.604014 -26.19588) (xy 405.584091 -26.143789)
			(xy 405.571965 -26.089352) (xy 405.567894 -26.03373) (xy 399.775912 -26.03373) (xy 399.789115 -26.044718)
			(xy 399.826332 -26.086255) (xy 399.857105 -26.132768) (xy 399.880777 -26.183265) (xy 399.896845 -26.236672)
			(xy 399.904965 -26.291848) (xy 399.905474 -26.319734) (xy 399.904965 -26.34762) (xy 399.896845 -26.402796)
			(xy 399.880777 -26.456203) (xy 399.857105 -26.5067) (xy 399.826332 -26.553213) (xy 399.789115 -26.59475)
			(xy 399.746247 -26.630425) (xy 399.698641 -26.659479) (xy 399.647312 -26.681291) (xy 399.593355 -26.695397)
			(xy 399.537918 -26.701497) (xy 399.482184 -26.69946) (xy 399.427341 -26.68933) (xy 399.374557 -26.671323)
			(xy 399.324957 -26.645822) (xy 399.279599 -26.613371) (xy 399.23945 -26.574662) (xy 399.205364 -26.530519)
			(xy 399.178068 -26.481884) (xy 399.158145 -26.429793) (xy 399.146019 -26.375356) (xy 399.141948 -26.319734)
			(xy 394.150675 -26.319734) (xy 394.152627 -26.332996) (xy 394.153136 -26.360882) (xy 394.152627 -26.388768)
			(xy 394.144507 -26.443944) (xy 394.128439 -26.497351) (xy 394.104767 -26.547848) (xy 394.073994 -26.594361)
			(xy 394.036777 -26.635898) (xy 393.993909 -26.671573) (xy 393.946303 -26.700627) (xy 393.894974 -26.722439)
			(xy 393.841017 -26.736545) (xy 393.78558 -26.742645) (xy 393.729846 -26.740608) (xy 393.675003 -26.730478)
			(xy 393.622219 -26.712471) (xy 393.572619 -26.68697) (xy 393.527261 -26.654519) (xy 393.487112 -26.61581)
			(xy 393.453026 -26.571667) (xy 393.42573 -26.523032) (xy 393.405807 -26.470941) (xy 393.393681 -26.416504)
			(xy 393.38961 -26.360882) (xy 391.723043 -26.360882) (xy 391.730807 -26.389856) (xy 391.73863 -26.449278)
			(xy 391.73912 -26.479246) (xy 391.73912 -26.971244) (xy 395.1511 -26.971244) (xy 395.155171 -26.915622)
			(xy 395.167297 -26.861185) (xy 395.18722 -26.809094) (xy 395.214516 -26.760459) (xy 395.248602 -26.716316)
			(xy 395.288751 -26.677607) (xy 395.334109 -26.645156) (xy 395.383709 -26.619655) (xy 395.436493 -26.601648)
			(xy 395.491336 -26.591518) (xy 395.54707 -26.589481) (xy 395.602507 -26.595581) (xy 395.656464 -26.609687)
			(xy 395.707793 -26.631499) (xy 395.755399 -26.660553) (xy 395.798267 -26.696228) (xy 395.835484 -26.737765)
			(xy 395.866257 -26.784278) (xy 395.889929 -26.834775) (xy 395.905997 -26.888182) (xy 395.914117 -26.943358)
			(xy 395.914626 -26.971244) (xy 395.914117 -26.99913) (xy 395.905997 -27.054306) (xy 395.889929 -27.107713)
			(xy 395.866257 -27.15821) (xy 395.835484 -27.204723) (xy 395.798267 -27.24626) (xy 395.755399 -27.281935)
			(xy 395.707793 -27.310989) (xy 395.656464 -27.332801) (xy 395.602507 -27.346907) (xy 395.54707 -27.353007)
			(xy 395.491336 -27.35097) (xy 395.436493 -27.34084) (xy 395.383709 -27.322833) (xy 395.334109 -27.297332)
			(xy 395.288751 -27.264881) (xy 395.248602 -27.226172) (xy 395.214516 -27.182029) (xy 395.18722 -27.133394)
			(xy 395.167297 -27.081303) (xy 395.155171 -27.026866) (xy 395.1511 -26.971244) (xy 391.73912 -26.971244)
			(xy 391.73912 -27.342846) (xy 391.73863 -27.372814) (xy 391.730807 -27.432236) (xy 391.715294 -27.490129)
			(xy 391.692358 -27.545502) (xy 391.662391 -27.597408) (xy 391.625904 -27.644958) (xy 391.583524 -27.687338)
			(xy 391.535974 -27.723825) (xy 391.484068 -27.753792) (xy 391.428695 -27.776728) (xy 391.370802 -27.792241)
			(xy 391.31138 -27.800064) (xy 391.251444 -27.800064) (xy 391.192022 -27.792241) (xy 391.134129 -27.776728)
			(xy 391.078756 -27.753792) (xy 391.02685 -27.723825) (xy 390.9793 -27.687338) (xy 390.93692 -27.644958)
			(xy 390.900433 -27.597408) (xy 390.870466 -27.545502) (xy 390.84753 -27.490129) (xy 390.832017 -27.432236)
			(xy 390.824194 -27.372814) (xy 390.823704 -27.342846) (xy 383.505476 -27.342846) (xy 383.471487 -27.372297)
			(xy 383.425637 -27.401763) (xy 383.37606 -27.424405) (xy 383.323765 -27.43976) (xy 383.269817 -27.447516)
			(xy 383.215315 -27.447516) (xy 383.161367 -27.43976) (xy 383.109072 -27.424405) (xy 383.059495 -27.401763)
			(xy 383.013645 -27.372297) (xy 382.972454 -27.336606) (xy 382.936763 -27.295415) (xy 382.907297 -27.249565)
			(xy 382.884655 -27.199988) (xy 382.8693 -27.147693) (xy 382.861544 -27.093745) (xy 382.861058 -27.066494)
			(xy 382.861618 -27.037007) (xy 382.870713 -26.978737) (xy 382.888671 -26.922563) (xy 382.915063 -26.869823)
			(xy 382.949259 -26.821775) (xy 382.990445 -26.779564) (xy 383.013712 -26.76144) (xy 383.024776 -26.752476)
			(xy 383.041961 -26.729791) (xy 383.052215 -26.703243) (xy 383.05474 -26.674895) (xy 383.049341 -26.646953)
			(xy 383.036437 -26.621587) (xy 383.017031 -26.60077) (xy 383.005076 -26.593038) (xy 382.981329 -26.57815)
			(xy 382.938095 -26.542481) (xy 382.900544 -26.50087) (xy 382.869486 -26.454213) (xy 382.845588 -26.403514)
			(xy 382.829365 -26.349864) (xy 382.821166 -26.294418) (xy 382.820672 -26.266394) (xy 380.252869 -26.266394)
			(xy 380.25233 -26.267209) (xy 380.215113 -26.308746) (xy 380.172245 -26.344421) (xy 380.124639 -26.373475)
			(xy 380.07331 -26.395287) (xy 380.019353 -26.409393) (xy 379.963916 -26.415493) (xy 379.908182 -26.413456)
			(xy 379.853339 -26.403326) (xy 379.800555 -26.385319) (xy 379.750955 -26.359818) (xy 379.705597 -26.327367)
			(xy 379.665448 -26.288658) (xy 379.631362 -26.244515) (xy 379.604066 -26.19588) (xy 379.584143 -26.143789)
			(xy 379.572017 -26.089352) (xy 379.567946 -26.03373) (xy 373.775964 -26.03373) (xy 373.789167 -26.044718)
			(xy 373.826384 -26.086255) (xy 373.857157 -26.132768) (xy 373.880829 -26.183265) (xy 373.896897 -26.236672)
			(xy 373.905017 -26.291848) (xy 373.905526 -26.319734) (xy 373.905017 -26.34762) (xy 373.896897 -26.402796)
			(xy 373.880829 -26.456203) (xy 373.857157 -26.5067) (xy 373.826384 -26.553213) (xy 373.789167 -26.59475)
			(xy 373.746299 -26.630425) (xy 373.698693 -26.659479) (xy 373.647364 -26.681291) (xy 373.593407 -26.695397)
			(xy 373.53797 -26.701497) (xy 373.482236 -26.69946) (xy 373.427393 -26.68933) (xy 373.374609 -26.671323)
			(xy 373.325009 -26.645822) (xy 373.279651 -26.613371) (xy 373.239502 -26.574662) (xy 373.205416 -26.530519)
			(xy 373.17812 -26.481884) (xy 373.158197 -26.429793) (xy 373.146071 -26.375356) (xy 373.142 -26.319734)
			(xy 368.150727 -26.319734) (xy 368.152679 -26.332996) (xy 368.153188 -26.360882) (xy 368.152679 -26.388768)
			(xy 368.144559 -26.443944) (xy 368.128491 -26.497351) (xy 368.104819 -26.547848) (xy 368.074046 -26.594361)
			(xy 368.036829 -26.635898) (xy 367.993961 -26.671573) (xy 367.946355 -26.700627) (xy 367.895026 -26.722439)
			(xy 367.841069 -26.736545) (xy 367.785632 -26.742645) (xy 367.729898 -26.740608) (xy 367.675055 -26.730478)
			(xy 367.622271 -26.712471) (xy 367.572671 -26.68697) (xy 367.527313 -26.654519) (xy 367.487164 -26.61581)
			(xy 367.453078 -26.571667) (xy 367.425782 -26.523032) (xy 367.405859 -26.470941) (xy 367.393733 -26.416504)
			(xy 367.389662 -26.360882) (xy 365.723095 -26.360882) (xy 365.730859 -26.389856) (xy 365.738682 -26.449278)
			(xy 365.739172 -26.479246) (xy 365.739172 -26.971244) (xy 369.151152 -26.971244) (xy 369.155223 -26.915622)
			(xy 369.167349 -26.861185) (xy 369.187272 -26.809094) (xy 369.214568 -26.760459) (xy 369.248654 -26.716316)
			(xy 369.288803 -26.677607) (xy 369.334161 -26.645156) (xy 369.383761 -26.619655) (xy 369.436545 -26.601648)
			(xy 369.491388 -26.591518) (xy 369.547122 -26.589481) (xy 369.602559 -26.595581) (xy 369.656516 -26.609687)
			(xy 369.707845 -26.631499) (xy 369.755451 -26.660553) (xy 369.798319 -26.696228) (xy 369.835536 -26.737765)
			(xy 369.866309 -26.784278) (xy 369.889981 -26.834775) (xy 369.906049 -26.888182) (xy 369.914169 -26.943358)
			(xy 369.914678 -26.971244) (xy 369.914169 -26.99913) (xy 369.906049 -27.054306) (xy 369.889981 -27.107713)
			(xy 369.866309 -27.15821) (xy 369.835536 -27.204723) (xy 369.798319 -27.24626) (xy 369.755451 -27.281935)
			(xy 369.707845 -27.310989) (xy 369.656516 -27.332801) (xy 369.602559 -27.346907) (xy 369.547122 -27.353007)
			(xy 369.491388 -27.35097) (xy 369.436545 -27.34084) (xy 369.383761 -27.322833) (xy 369.334161 -27.297332)
			(xy 369.288803 -27.264881) (xy 369.248654 -27.226172) (xy 369.214568 -27.182029) (xy 369.187272 -27.133394)
			(xy 369.167349 -27.081303) (xy 369.155223 -27.026866) (xy 369.151152 -26.971244) (xy 365.739172 -26.971244)
			(xy 365.739172 -27.342846) (xy 365.738682 -27.372814) (xy 365.730859 -27.432236) (xy 365.715346 -27.490129)
			(xy 365.69241 -27.545502) (xy 365.662443 -27.597408) (xy 365.625956 -27.644958) (xy 365.583576 -27.687338)
			(xy 365.536026 -27.723825) (xy 365.48412 -27.753792) (xy 365.428747 -27.776728) (xy 365.370854 -27.792241)
			(xy 365.311432 -27.800064) (xy 365.251496 -27.800064) (xy 365.192074 -27.792241) (xy 365.134181 -27.776728)
			(xy 365.078808 -27.753792) (xy 365.026902 -27.723825) (xy 364.979352 -27.687338) (xy 364.936972 -27.644958)
			(xy 364.900485 -27.597408) (xy 364.870518 -27.545502) (xy 364.847582 -27.490129) (xy 364.832069 -27.432236)
			(xy 364.824246 -27.372814) (xy 364.823756 -27.342846) (xy 357.505528 -27.342846) (xy 357.471539 -27.372297)
			(xy 357.425689 -27.401763) (xy 357.376112 -27.424405) (xy 357.323817 -27.43976) (xy 357.269869 -27.447516)
			(xy 357.215367 -27.447516) (xy 357.161419 -27.43976) (xy 357.109124 -27.424405) (xy 357.059547 -27.401763)
			(xy 357.013697 -27.372297) (xy 356.972506 -27.336606) (xy 356.936815 -27.295415) (xy 356.907349 -27.249565)
			(xy 356.884707 -27.199988) (xy 356.869352 -27.147693) (xy 356.861596 -27.093745) (xy 356.86111 -27.066494)
			(xy 356.861649 -27.037006) (xy 356.870746 -26.978734) (xy 356.888707 -26.922559) (xy 356.915102 -26.869818)
			(xy 356.949303 -26.821771) (xy 356.990495 -26.779562) (xy 357.013764 -26.76144) (xy 357.024821 -26.75247)
			(xy 357.041996 -26.729784) (xy 357.052244 -26.703238) (xy 357.054767 -26.674896) (xy 357.049371 -26.646957)
			(xy 357.036474 -26.621593) (xy 357.017078 -26.600773) (xy 357.005128 -26.593038) (xy 356.981392 -26.578131)
			(xy 356.938156 -26.542467) (xy 356.900603 -26.50086) (xy 356.869542 -26.454207) (xy 356.845643 -26.40351)
			(xy 356.829418 -26.349862) (xy 356.821218 -26.294418) (xy 356.820724 -26.266394) (xy 354.252921 -26.266394)
			(xy 354.252382 -26.267209) (xy 354.215165 -26.308746) (xy 354.172297 -26.344421) (xy 354.124691 -26.373475)
			(xy 354.073362 -26.395287) (xy 354.019405 -26.409393) (xy 353.963968 -26.415493) (xy 353.908234 -26.413456)
			(xy 353.853391 -26.403326) (xy 353.800607 -26.385319) (xy 353.751007 -26.359818) (xy 353.705649 -26.327367)
			(xy 353.6655 -26.288658) (xy 353.631414 -26.244515) (xy 353.604118 -26.19588) (xy 353.584195 -26.143789)
			(xy 353.572069 -26.089352) (xy 353.567998 -26.03373) (xy 335.67571 -26.03373) (xy 335.688913 -26.044718)
			(xy 335.72613 -26.086255) (xy 335.756903 -26.132768) (xy 335.780575 -26.183265) (xy 335.796643 -26.236672)
			(xy 335.804763 -26.291848) (xy 335.805272 -26.319734) (xy 335.804763 -26.34762) (xy 335.796643 -26.402796)
			(xy 335.780575 -26.456203) (xy 335.756903 -26.5067) (xy 335.72613 -26.553213) (xy 335.688913 -26.59475)
			(xy 335.646045 -26.630425) (xy 335.598439 -26.659479) (xy 335.54711 -26.681291) (xy 335.493153 -26.695397)
			(xy 335.437716 -26.701497) (xy 335.381982 -26.69946) (xy 335.327139 -26.68933) (xy 335.274355 -26.671323)
			(xy 335.224755 -26.645822) (xy 335.179397 -26.613371) (xy 335.139248 -26.574662) (xy 335.105162 -26.530519)
			(xy 335.077866 -26.481884) (xy 335.057943 -26.429793) (xy 335.045817 -26.375356) (xy 335.041746 -26.319734)
			(xy 330.050473 -26.319734) (xy 330.052425 -26.332996) (xy 330.052934 -26.360882) (xy 330.052425 -26.388768)
			(xy 330.044305 -26.443944) (xy 330.028237 -26.497351) (xy 330.004565 -26.547848) (xy 329.973792 -26.594361)
			(xy 329.936575 -26.635898) (xy 329.893707 -26.671573) (xy 329.846101 -26.700627) (xy 329.794772 -26.722439)
			(xy 329.740815 -26.736545) (xy 329.685378 -26.742645) (xy 329.629644 -26.740608) (xy 329.574801 -26.730478)
			(xy 329.522017 -26.712471) (xy 329.472417 -26.68697) (xy 329.427059 -26.654519) (xy 329.38691 -26.61581)
			(xy 329.352824 -26.571667) (xy 329.325528 -26.523032) (xy 329.305605 -26.470941) (xy 329.293479 -26.416504)
			(xy 329.289408 -26.360882) (xy 327.623104 -26.360882) (xy 327.630854 -26.389806) (xy 327.638682 -26.449262)
			(xy 327.639172 -26.479246) (xy 327.639172 -26.971244) (xy 331.050898 -26.971244) (xy 331.054969 -26.915622)
			(xy 331.067095 -26.861185) (xy 331.087018 -26.809094) (xy 331.114314 -26.760459) (xy 331.1484 -26.716316)
			(xy 331.188549 -26.677607) (xy 331.233907 -26.645156) (xy 331.283507 -26.619655) (xy 331.336291 -26.601648)
			(xy 331.391134 -26.591518) (xy 331.446868 -26.589481) (xy 331.502305 -26.595581) (xy 331.556262 -26.609687)
			(xy 331.607591 -26.631499) (xy 331.655197 -26.660553) (xy 331.698065 -26.696228) (xy 331.735282 -26.737765)
			(xy 331.766055 -26.784278) (xy 331.789727 -26.834775) (xy 331.805795 -26.888182) (xy 331.813915 -26.943358)
			(xy 331.814424 -26.971244) (xy 331.813915 -26.99913) (xy 331.805795 -27.054306) (xy 331.789727 -27.107713)
			(xy 331.766055 -27.15821) (xy 331.735282 -27.204723) (xy 331.698065 -27.24626) (xy 331.655197 -27.281935)
			(xy 331.607591 -27.310989) (xy 331.556262 -27.332801) (xy 331.502305 -27.346907) (xy 331.446868 -27.353007)
			(xy 331.391134 -27.35097) (xy 331.336291 -27.34084) (xy 331.283507 -27.322833) (xy 331.233907 -27.297332)
			(xy 331.188549 -27.264881) (xy 331.1484 -27.226172) (xy 331.114314 -27.182029) (xy 331.087018 -27.133394)
			(xy 331.067095 -27.081303) (xy 331.054969 -27.026866) (xy 331.050898 -26.971244) (xy 327.639172 -26.971244)
			(xy 327.639172 -27.342846) (xy 327.638682 -27.37283) (xy 327.630854 -27.432286) (xy 327.615333 -27.490211)
			(xy 327.592384 -27.545615) (xy 327.5624 -27.597549) (xy 327.525894 -27.645125) (xy 327.483489 -27.68753)
			(xy 327.435913 -27.724036) (xy 327.383979 -27.75402) (xy 327.328575 -27.776969) (xy 327.27065 -27.79249)
			(xy 327.211194 -27.800318) (xy 327.151226 -27.800318) (xy 327.09177 -27.79249) (xy 327.033845 -27.776969)
			(xy 326.978441 -27.75402) (xy 326.926507 -27.724036) (xy 326.878931 -27.68753) (xy 326.836526 -27.645125)
			(xy 326.80002 -27.597549) (xy 326.770036 -27.545615) (xy 326.747087 -27.490211) (xy 326.731566 -27.432286)
			(xy 326.723738 -27.37283) (xy 326.723248 -27.342846) (xy 319.405274 -27.342846) (xy 319.371285 -27.372297)
			(xy 319.325435 -27.401763) (xy 319.275858 -27.424405) (xy 319.223563 -27.43976) (xy 319.169615 -27.447516)
			(xy 319.115113 -27.447516) (xy 319.061165 -27.43976) (xy 319.00887 -27.424405) (xy 318.959293 -27.401763)
			(xy 318.913443 -27.372297) (xy 318.872252 -27.336606) (xy 318.836561 -27.295415) (xy 318.807095 -27.249565)
			(xy 318.784453 -27.199988) (xy 318.769098 -27.147693) (xy 318.761342 -27.093745) (xy 318.760856 -27.066494)
			(xy 318.761417 -27.037007) (xy 318.770512 -26.978738) (xy 318.78847 -26.922563) (xy 318.814861 -26.869823)
			(xy 318.849058 -26.821775) (xy 318.890244 -26.779564) (xy 318.91351 -26.76144) (xy 318.924575 -26.752476)
			(xy 318.94176 -26.729791) (xy 318.952014 -26.703243) (xy 318.954539 -26.674895) (xy 318.94914 -26.646953)
			(xy 318.936235 -26.621587) (xy 318.916829 -26.60077) (xy 318.904874 -26.593038) (xy 318.881126 -26.578151)
			(xy 318.837892 -26.542481) (xy 318.800342 -26.50087) (xy 318.769284 -26.454213) (xy 318.745386 -26.403514)
			(xy 318.729163 -26.349864) (xy 318.720964 -26.294418) (xy 318.72047 -26.266394) (xy 316.152667 -26.266394)
			(xy 316.152128 -26.267209) (xy 316.114911 -26.308746) (xy 316.072043 -26.344421) (xy 316.024437 -26.373475)
			(xy 315.973108 -26.395287) (xy 315.919151 -26.409393) (xy 315.863714 -26.415493) (xy 315.80798 -26.413456)
			(xy 315.753137 -26.403326) (xy 315.700353 -26.385319) (xy 315.650753 -26.359818) (xy 315.605395 -26.327367)
			(xy 315.565246 -26.288658) (xy 315.53116 -26.244515) (xy 315.503864 -26.19588) (xy 315.483941 -26.143789)
			(xy 315.471815 -26.089352) (xy 315.467744 -26.03373) (xy 309.675762 -26.03373) (xy 309.688965 -26.044718)
			(xy 309.726182 -26.086255) (xy 309.756955 -26.132768) (xy 309.780627 -26.183265) (xy 309.796695 -26.236672)
			(xy 309.804815 -26.291848) (xy 309.805324 -26.319734) (xy 309.804815 -26.34762) (xy 309.796695 -26.402796)
			(xy 309.780627 -26.456203) (xy 309.756955 -26.5067) (xy 309.726182 -26.553213) (xy 309.688965 -26.59475)
			(xy 309.646097 -26.630425) (xy 309.598491 -26.659479) (xy 309.547162 -26.681291) (xy 309.493205 -26.695397)
			(xy 309.437768 -26.701497) (xy 309.382034 -26.69946) (xy 309.327191 -26.68933) (xy 309.274407 -26.671323)
			(xy 309.224807 -26.645822) (xy 309.179449 -26.613371) (xy 309.1393 -26.574662) (xy 309.105214 -26.530519)
			(xy 309.077918 -26.481884) (xy 309.057995 -26.429793) (xy 309.045869 -26.375356) (xy 309.041798 -26.319734)
			(xy 304.050525 -26.319734) (xy 304.052477 -26.332996) (xy 304.052986 -26.360882) (xy 304.052477 -26.388768)
			(xy 304.044357 -26.443944) (xy 304.028289 -26.497351) (xy 304.004617 -26.547848) (xy 303.973844 -26.594361)
			(xy 303.936627 -26.635898) (xy 303.893759 -26.671573) (xy 303.846153 -26.700627) (xy 303.794824 -26.722439)
			(xy 303.740867 -26.736545) (xy 303.68543 -26.742645) (xy 303.629696 -26.740608) (xy 303.574853 -26.730478)
			(xy 303.522069 -26.712471) (xy 303.472469 -26.68697) (xy 303.427111 -26.654519) (xy 303.386962 -26.61581)
			(xy 303.352876 -26.571667) (xy 303.32558 -26.523032) (xy 303.305657 -26.470941) (xy 303.293531 -26.416504)
			(xy 303.28946 -26.360882) (xy 301.623156 -26.360882) (xy 301.630906 -26.389806) (xy 301.638734 -26.449262)
			(xy 301.639224 -26.479246) (xy 301.639224 -26.971244) (xy 305.05095 -26.971244) (xy 305.055021 -26.915622)
			(xy 305.067147 -26.861185) (xy 305.08707 -26.809094) (xy 305.114366 -26.760459) (xy 305.148452 -26.716316)
			(xy 305.188601 -26.677607) (xy 305.233959 -26.645156) (xy 305.283559 -26.619655) (xy 305.336343 -26.601648)
			(xy 305.391186 -26.591518) (xy 305.44692 -26.589481) (xy 305.502357 -26.595581) (xy 305.556314 -26.609687)
			(xy 305.607643 -26.631499) (xy 305.655249 -26.660553) (xy 305.698117 -26.696228) (xy 305.735334 -26.737765)
			(xy 305.766107 -26.784278) (xy 305.789779 -26.834775) (xy 305.805847 -26.888182) (xy 305.813967 -26.943358)
			(xy 305.814476 -26.971244) (xy 305.813967 -26.99913) (xy 305.805847 -27.054306) (xy 305.789779 -27.107713)
			(xy 305.766107 -27.15821) (xy 305.735334 -27.204723) (xy 305.698117 -27.24626) (xy 305.655249 -27.281935)
			(xy 305.607643 -27.310989) (xy 305.556314 -27.332801) (xy 305.502357 -27.346907) (xy 305.44692 -27.353007)
			(xy 305.391186 -27.35097) (xy 305.336343 -27.34084) (xy 305.283559 -27.322833) (xy 305.233959 -27.297332)
			(xy 305.188601 -27.264881) (xy 305.148452 -27.226172) (xy 305.114366 -27.182029) (xy 305.08707 -27.133394)
			(xy 305.067147 -27.081303) (xy 305.055021 -27.026866) (xy 305.05095 -26.971244) (xy 301.639224 -26.971244)
			(xy 301.639224 -27.342846) (xy 301.638734 -27.37283) (xy 301.630906 -27.432286) (xy 301.615385 -27.490211)
			(xy 301.592436 -27.545615) (xy 301.562452 -27.597549) (xy 301.525946 -27.645125) (xy 301.483541 -27.68753)
			(xy 301.435965 -27.724036) (xy 301.384031 -27.75402) (xy 301.328627 -27.776969) (xy 301.270702 -27.79249)
			(xy 301.211246 -27.800318) (xy 301.151278 -27.800318) (xy 301.091822 -27.79249) (xy 301.033897 -27.776969)
			(xy 300.978493 -27.75402) (xy 300.926559 -27.724036) (xy 300.878983 -27.68753) (xy 300.836578 -27.645125)
			(xy 300.800072 -27.597549) (xy 300.770088 -27.545615) (xy 300.747139 -27.490211) (xy 300.731618 -27.432286)
			(xy 300.72379 -27.37283) (xy 300.7233 -27.342846) (xy 293.405326 -27.342846) (xy 293.371337 -27.372297)
			(xy 293.325487 -27.401763) (xy 293.27591 -27.424405) (xy 293.223615 -27.43976) (xy 293.169667 -27.447516)
			(xy 293.115165 -27.447516) (xy 293.061217 -27.43976) (xy 293.008922 -27.424405) (xy 292.959345 -27.401763)
			(xy 292.913495 -27.372297) (xy 292.872304 -27.336606) (xy 292.836613 -27.295415) (xy 292.807147 -27.249565)
			(xy 292.784505 -27.199988) (xy 292.76915 -27.147693) (xy 292.761394 -27.093745) (xy 292.760908 -27.066494)
			(xy 292.761448 -27.037006) (xy 292.770545 -26.978735) (xy 292.788505 -26.922559) (xy 292.814901 -26.869818)
			(xy 292.849102 -26.821771) (xy 292.890293 -26.779562) (xy 292.913562 -26.76144) (xy 292.924619 -26.75247)
			(xy 292.941795 -26.729784) (xy 292.952043 -26.703238) (xy 292.954566 -26.674896) (xy 292.94917 -26.646957)
			(xy 292.936273 -26.621593) (xy 292.916876 -26.600773) (xy 292.904926 -26.593038) (xy 292.88119 -26.578132)
			(xy 292.837953 -26.542468) (xy 292.800401 -26.500861) (xy 292.76934 -26.454207) (xy 292.74544 -26.40351)
			(xy 292.729216 -26.349862) (xy 292.721016 -26.294418) (xy 292.720522 -26.266394) (xy 290.152719 -26.266394)
			(xy 290.15218 -26.267209) (xy 290.114963 -26.308746) (xy 290.072095 -26.344421) (xy 290.024489 -26.373475)
			(xy 289.97316 -26.395287) (xy 289.919203 -26.409393) (xy 289.863766 -26.415493) (xy 289.808032 -26.413456)
			(xy 289.753189 -26.403326) (xy 289.700405 -26.385319) (xy 289.650805 -26.359818) (xy 289.605447 -26.327367)
			(xy 289.565298 -26.288658) (xy 289.531212 -26.244515) (xy 289.503916 -26.19588) (xy 289.483993 -26.143789)
			(xy 289.471867 -26.089352) (xy 289.467796 -26.03373) (xy 283.675814 -26.03373) (xy 283.689017 -26.044718)
			(xy 283.726234 -26.086255) (xy 283.757007 -26.132768) (xy 283.780679 -26.183265) (xy 283.796747 -26.236672)
			(xy 283.804867 -26.291848) (xy 283.805376 -26.319734) (xy 283.804867 -26.34762) (xy 283.796747 -26.402796)
			(xy 283.780679 -26.456203) (xy 283.757007 -26.5067) (xy 283.726234 -26.553213) (xy 283.689017 -26.59475)
			(xy 283.646149 -26.630425) (xy 283.598543 -26.659479) (xy 283.547214 -26.681291) (xy 283.493257 -26.695397)
			(xy 283.43782 -26.701497) (xy 283.382086 -26.69946) (xy 283.327243 -26.68933) (xy 283.274459 -26.671323)
			(xy 283.224859 -26.645822) (xy 283.179501 -26.613371) (xy 283.139352 -26.574662) (xy 283.105266 -26.530519)
			(xy 283.07797 -26.481884) (xy 283.058047 -26.429793) (xy 283.045921 -26.375356) (xy 283.04185 -26.319734)
			(xy 278.050577 -26.319734) (xy 278.052529 -26.332996) (xy 278.053038 -26.360882) (xy 278.052529 -26.388768)
			(xy 278.044409 -26.443944) (xy 278.028341 -26.497351) (xy 278.004669 -26.547848) (xy 277.973896 -26.594361)
			(xy 277.936679 -26.635898) (xy 277.893811 -26.671573) (xy 277.846205 -26.700627) (xy 277.794876 -26.722439)
			(xy 277.740919 -26.736545) (xy 277.685482 -26.742645) (xy 277.629748 -26.740608) (xy 277.574905 -26.730478)
			(xy 277.522121 -26.712471) (xy 277.472521 -26.68697) (xy 277.427163 -26.654519) (xy 277.387014 -26.61581)
			(xy 277.352928 -26.571667) (xy 277.325632 -26.523032) (xy 277.305709 -26.470941) (xy 277.293583 -26.416504)
			(xy 277.289512 -26.360882) (xy 275.623208 -26.360882) (xy 275.630958 -26.389806) (xy 275.638786 -26.449262)
			(xy 275.639276 -26.479246) (xy 275.639276 -26.971244) (xy 279.051002 -26.971244) (xy 279.055073 -26.915622)
			(xy 279.067199 -26.861185) (xy 279.087122 -26.809094) (xy 279.114418 -26.760459) (xy 279.148504 -26.716316)
			(xy 279.188653 -26.677607) (xy 279.234011 -26.645156) (xy 279.283611 -26.619655) (xy 279.336395 -26.601648)
			(xy 279.391238 -26.591518) (xy 279.446972 -26.589481) (xy 279.502409 -26.595581) (xy 279.556366 -26.609687)
			(xy 279.607695 -26.631499) (xy 279.655301 -26.660553) (xy 279.698169 -26.696228) (xy 279.735386 -26.737765)
			(xy 279.766159 -26.784278) (xy 279.789831 -26.834775) (xy 279.805899 -26.888182) (xy 279.814019 -26.943358)
			(xy 279.814528 -26.971244) (xy 279.814019 -26.99913) (xy 279.805899 -27.054306) (xy 279.789831 -27.107713)
			(xy 279.766159 -27.15821) (xy 279.735386 -27.204723) (xy 279.698169 -27.24626) (xy 279.655301 -27.281935)
			(xy 279.607695 -27.310989) (xy 279.556366 -27.332801) (xy 279.502409 -27.346907) (xy 279.446972 -27.353007)
			(xy 279.391238 -27.35097) (xy 279.336395 -27.34084) (xy 279.283611 -27.322833) (xy 279.234011 -27.297332)
			(xy 279.188653 -27.264881) (xy 279.148504 -27.226172) (xy 279.114418 -27.182029) (xy 279.087122 -27.133394)
			(xy 279.067199 -27.081303) (xy 279.055073 -27.026866) (xy 279.051002 -26.971244) (xy 275.639276 -26.971244)
			(xy 275.639276 -27.342846) (xy 275.638786 -27.37283) (xy 275.630958 -27.432286) (xy 275.615437 -27.490211)
			(xy 275.592488 -27.545615) (xy 275.562504 -27.597549) (xy 275.525998 -27.645125) (xy 275.483593 -27.68753)
			(xy 275.436017 -27.724036) (xy 275.384083 -27.75402) (xy 275.328679 -27.776969) (xy 275.270754 -27.79249)
			(xy 275.211298 -27.800318) (xy 275.15133 -27.800318) (xy 275.091874 -27.79249) (xy 275.033949 -27.776969)
			(xy 274.978545 -27.75402) (xy 274.926611 -27.724036) (xy 274.879035 -27.68753) (xy 274.83663 -27.645125)
			(xy 274.800124 -27.597549) (xy 274.77014 -27.545615) (xy 274.747191 -27.490211) (xy 274.73167 -27.432286)
			(xy 274.723842 -27.37283) (xy 274.723352 -27.342846) (xy 267.405378 -27.342846) (xy 267.371389 -27.372297)
			(xy 267.325539 -27.401763) (xy 267.275962 -27.424405) (xy 267.223667 -27.43976) (xy 267.169719 -27.447516)
			(xy 267.115217 -27.447516) (xy 267.061269 -27.43976) (xy 267.008974 -27.424405) (xy 266.959397 -27.401763)
			(xy 266.913547 -27.372297) (xy 266.872356 -27.336606) (xy 266.836665 -27.295415) (xy 266.807199 -27.249565)
			(xy 266.784557 -27.199988) (xy 266.769202 -27.147693) (xy 266.761446 -27.093745) (xy 266.76096 -27.066494)
			(xy 266.761519 -27.037007) (xy 266.770615 -26.978737) (xy 266.788572 -26.922563) (xy 266.814964 -26.869823)
			(xy 266.849161 -26.821775) (xy 266.890347 -26.779564) (xy 266.913614 -26.76144) (xy 266.924678 -26.752476)
			(xy 266.941862 -26.72979) (xy 266.952116 -26.703242) (xy 266.954641 -26.674895) (xy 266.949242 -26.646953)
			(xy 266.936338 -26.621587) (xy 266.916933 -26.60077) (xy 266.904978 -26.593038) (xy 266.881231 -26.578149)
			(xy 266.837997 -26.54248) (xy 266.800447 -26.500869) (xy 266.769388 -26.454213) (xy 266.74549 -26.403514)
			(xy 266.729267 -26.349864) (xy 266.721068 -26.294418) (xy 266.720574 -26.266394) (xy 264.152771 -26.266394)
			(xy 264.152232 -26.267209) (xy 264.115015 -26.308746) (xy 264.072147 -26.344421) (xy 264.024541 -26.373475)
			(xy 263.973212 -26.395287) (xy 263.919255 -26.409393) (xy 263.863818 -26.415493) (xy 263.808084 -26.413456)
			(xy 263.753241 -26.403326) (xy 263.700457 -26.385319) (xy 263.650857 -26.359818) (xy 263.605499 -26.327367)
			(xy 263.56535 -26.288658) (xy 263.531264 -26.244515) (xy 263.503968 -26.19588) (xy 263.484045 -26.143789)
			(xy 263.471919 -26.089352) (xy 263.467848 -26.03373) (xy 257.675866 -26.03373) (xy 257.689069 -26.044718)
			(xy 257.726286 -26.086255) (xy 257.757059 -26.132768) (xy 257.780731 -26.183265) (xy 257.796799 -26.236672)
			(xy 257.804919 -26.291848) (xy 257.805428 -26.319734) (xy 257.804919 -26.34762) (xy 257.796799 -26.402796)
			(xy 257.780731 -26.456203) (xy 257.757059 -26.5067) (xy 257.726286 -26.553213) (xy 257.689069 -26.59475)
			(xy 257.646201 -26.630425) (xy 257.598595 -26.659479) (xy 257.547266 -26.681291) (xy 257.493309 -26.695397)
			(xy 257.437872 -26.701497) (xy 257.382138 -26.69946) (xy 257.327295 -26.68933) (xy 257.274511 -26.671323)
			(xy 257.224911 -26.645822) (xy 257.179553 -26.613371) (xy 257.139404 -26.574662) (xy 257.105318 -26.530519)
			(xy 257.078022 -26.481884) (xy 257.058099 -26.429793) (xy 257.045973 -26.375356) (xy 257.041902 -26.319734)
			(xy 252.050629 -26.319734) (xy 252.052581 -26.332996) (xy 252.05309 -26.360882) (xy 252.052581 -26.388768)
			(xy 252.044461 -26.443944) (xy 252.028393 -26.497351) (xy 252.004721 -26.547848) (xy 251.973948 -26.594361)
			(xy 251.936731 -26.635898) (xy 251.893863 -26.671573) (xy 251.846257 -26.700627) (xy 251.794928 -26.722439)
			(xy 251.740971 -26.736545) (xy 251.685534 -26.742645) (xy 251.6298 -26.740608) (xy 251.574957 -26.730478)
			(xy 251.522173 -26.712471) (xy 251.472573 -26.68697) (xy 251.427215 -26.654519) (xy 251.387066 -26.61581)
			(xy 251.35298 -26.571667) (xy 251.325684 -26.523032) (xy 251.305761 -26.470941) (xy 251.293635 -26.416504)
			(xy 251.289564 -26.360882) (xy 249.62326 -26.360882) (xy 249.63101 -26.389806) (xy 249.638838 -26.449262)
			(xy 249.639328 -26.479246) (xy 249.639328 -26.971244) (xy 253.051054 -26.971244) (xy 253.055125 -26.915622)
			(xy 253.067251 -26.861185) (xy 253.087174 -26.809094) (xy 253.11447 -26.760459) (xy 253.148556 -26.716316)
			(xy 253.188705 -26.677607) (xy 253.234063 -26.645156) (xy 253.283663 -26.619655) (xy 253.336447 -26.601648)
			(xy 253.39129 -26.591518) (xy 253.447024 -26.589481) (xy 253.502461 -26.595581) (xy 253.556418 -26.609687)
			(xy 253.607747 -26.631499) (xy 253.655353 -26.660553) (xy 253.698221 -26.696228) (xy 253.735438 -26.737765)
			(xy 253.766211 -26.784278) (xy 253.789883 -26.834775) (xy 253.805951 -26.888182) (xy 253.814071 -26.943358)
			(xy 253.81458 -26.971244) (xy 253.814071 -26.99913) (xy 253.805951 -27.054306) (xy 253.789883 -27.107713)
			(xy 253.766211 -27.15821) (xy 253.735438 -27.204723) (xy 253.698221 -27.24626) (xy 253.655353 -27.281935)
			(xy 253.607747 -27.310989) (xy 253.556418 -27.332801) (xy 253.502461 -27.346907) (xy 253.447024 -27.353007)
			(xy 253.39129 -27.35097) (xy 253.336447 -27.34084) (xy 253.283663 -27.322833) (xy 253.234063 -27.297332)
			(xy 253.188705 -27.264881) (xy 253.148556 -27.226172) (xy 253.11447 -27.182029) (xy 253.087174 -27.133394)
			(xy 253.067251 -27.081303) (xy 253.055125 -27.026866) (xy 253.051054 -26.971244) (xy 249.639328 -26.971244)
			(xy 249.639328 -27.342846) (xy 249.638838 -27.37283) (xy 249.63101 -27.432286) (xy 249.615489 -27.490211)
			(xy 249.59254 -27.545615) (xy 249.562556 -27.597549) (xy 249.52605 -27.645125) (xy 249.483645 -27.68753)
			(xy 249.436069 -27.724036) (xy 249.384135 -27.75402) (xy 249.328731 -27.776969) (xy 249.270806 -27.79249)
			(xy 249.21135 -27.800318) (xy 249.151382 -27.800318) (xy 249.091926 -27.79249) (xy 249.034001 -27.776969)
			(xy 248.978597 -27.75402) (xy 248.926663 -27.724036) (xy 248.879087 -27.68753) (xy 248.836682 -27.645125)
			(xy 248.800176 -27.597549) (xy 248.770192 -27.545615) (xy 248.747243 -27.490211) (xy 248.731722 -27.432286)
			(xy 248.723894 -27.37283) (xy 248.723404 -27.342846) (xy 241.40543 -27.342846) (xy 241.371441 -27.372297)
			(xy 241.325591 -27.401763) (xy 241.276014 -27.424405) (xy 241.223719 -27.43976) (xy 241.169771 -27.447516)
			(xy 241.115269 -27.447516) (xy 241.061321 -27.43976) (xy 241.009026 -27.424405) (xy 240.959449 -27.401763)
			(xy 240.913599 -27.372297) (xy 240.872408 -27.336606) (xy 240.836717 -27.295415) (xy 240.807251 -27.249565)
			(xy 240.784609 -27.199988) (xy 240.769254 -27.147693) (xy 240.761498 -27.093745) (xy 240.761012 -27.066494)
			(xy 240.76155 -27.037006) (xy 240.770647 -26.978734) (xy 240.788608 -26.922559) (xy 240.815004 -26.869818)
			(xy 240.849205 -26.821771) (xy 240.890397 -26.779562) (xy 240.913666 -26.76144) (xy 240.924723 -26.75247)
			(xy 240.941898 -26.729783) (xy 240.952145 -26.703238) (xy 240.954668 -26.674896) (xy 240.949272 -26.646957)
			(xy 240.936376 -26.621593) (xy 240.91698 -26.600773) (xy 240.90503 -26.593038) (xy 240.881295 -26.578131)
			(xy 240.838058 -26.542467) (xy 240.800505 -26.50086) (xy 240.769445 -26.454206) (xy 240.745545 -26.40351)
			(xy 240.72932 -26.349862) (xy 240.72112 -26.294418) (xy 240.720626 -26.266394) (xy 238.152823 -26.266394)
			(xy 238.152284 -26.267209) (xy 238.115067 -26.308746) (xy 238.072199 -26.344421) (xy 238.024593 -26.373475)
			(xy 237.973264 -26.395287) (xy 237.919307 -26.409393) (xy 237.86387 -26.415493) (xy 237.808136 -26.413456)
			(xy 237.753293 -26.403326) (xy 237.700509 -26.385319) (xy 237.650909 -26.359818) (xy 237.605551 -26.327367)
			(xy 237.565402 -26.288658) (xy 237.531316 -26.244515) (xy 237.50402 -26.19588) (xy 237.484097 -26.143789)
			(xy 237.471971 -26.089352) (xy 237.4679 -26.03373) (xy 219.575866 -26.03373) (xy 219.589069 -26.044718)
			(xy 219.626286 -26.086255) (xy 219.657059 -26.132768) (xy 219.680731 -26.183265) (xy 219.696799 -26.236672)
			(xy 219.704919 -26.291848) (xy 219.705428 -26.319734) (xy 219.704919 -26.34762) (xy 219.696799 -26.402796)
			(xy 219.680731 -26.456203) (xy 219.657059 -26.5067) (xy 219.626286 -26.553213) (xy 219.589069 -26.59475)
			(xy 219.546201 -26.630425) (xy 219.498595 -26.659479) (xy 219.447266 -26.681291) (xy 219.393309 -26.695397)
			(xy 219.337872 -26.701497) (xy 219.282138 -26.69946) (xy 219.227295 -26.68933) (xy 219.174511 -26.671323)
			(xy 219.124911 -26.645822) (xy 219.079553 -26.613371) (xy 219.039404 -26.574662) (xy 219.005318 -26.530519)
			(xy 218.978022 -26.481884) (xy 218.958099 -26.429793) (xy 218.945973 -26.375356) (xy 218.941902 -26.319734)
			(xy 213.950629 -26.319734) (xy 213.952581 -26.332996) (xy 213.95309 -26.360882) (xy 213.952581 -26.388768)
			(xy 213.944461 -26.443944) (xy 213.928393 -26.497351) (xy 213.904721 -26.547848) (xy 213.873948 -26.594361)
			(xy 213.836731 -26.635898) (xy 213.793863 -26.671573) (xy 213.746257 -26.700627) (xy 213.694928 -26.722439)
			(xy 213.640971 -26.736545) (xy 213.585534 -26.742645) (xy 213.5298 -26.740608) (xy 213.474957 -26.730478)
			(xy 213.422173 -26.712471) (xy 213.372573 -26.68697) (xy 213.327215 -26.654519) (xy 213.287066 -26.61581)
			(xy 213.25298 -26.571667) (xy 213.225684 -26.523032) (xy 213.205761 -26.470941) (xy 213.193635 -26.416504)
			(xy 213.189564 -26.360882) (xy 211.52326 -26.360882) (xy 211.53101 -26.389806) (xy 211.538838 -26.449262)
			(xy 211.539328 -26.479246) (xy 211.539328 -26.971244) (xy 214.951054 -26.971244) (xy 214.955125 -26.915622)
			(xy 214.967251 -26.861185) (xy 214.987174 -26.809094) (xy 215.01447 -26.760459) (xy 215.048556 -26.716316)
			(xy 215.088705 -26.677607) (xy 215.134063 -26.645156) (xy 215.183663 -26.619655) (xy 215.236447 -26.601648)
			(xy 215.29129 -26.591518) (xy 215.347024 -26.589481) (xy 215.402461 -26.595581) (xy 215.456418 -26.609687)
			(xy 215.507747 -26.631499) (xy 215.555353 -26.660553) (xy 215.598221 -26.696228) (xy 215.635438 -26.737765)
			(xy 215.666211 -26.784278) (xy 215.689883 -26.834775) (xy 215.705951 -26.888182) (xy 215.714071 -26.943358)
			(xy 215.71458 -26.971244) (xy 215.714071 -26.99913) (xy 215.705951 -27.054306) (xy 215.689883 -27.107713)
			(xy 215.666211 -27.15821) (xy 215.635438 -27.204723) (xy 215.598221 -27.24626) (xy 215.555353 -27.281935)
			(xy 215.507747 -27.310989) (xy 215.456418 -27.332801) (xy 215.402461 -27.346907) (xy 215.347024 -27.353007)
			(xy 215.29129 -27.35097) (xy 215.236447 -27.34084) (xy 215.183663 -27.322833) (xy 215.134063 -27.297332)
			(xy 215.088705 -27.264881) (xy 215.048556 -27.226172) (xy 215.01447 -27.182029) (xy 214.987174 -27.133394)
			(xy 214.967251 -27.081303) (xy 214.955125 -27.026866) (xy 214.951054 -26.971244) (xy 211.539328 -26.971244)
			(xy 211.539328 -27.342846) (xy 211.538838 -27.37283) (xy 211.53101 -27.432286) (xy 211.515489 -27.490211)
			(xy 211.49254 -27.545615) (xy 211.462556 -27.597549) (xy 211.42605 -27.645125) (xy 211.383645 -27.68753)
			(xy 211.336069 -27.724036) (xy 211.284135 -27.75402) (xy 211.228731 -27.776969) (xy 211.170806 -27.79249)
			(xy 211.11135 -27.800318) (xy 211.051382 -27.800318) (xy 210.991926 -27.79249) (xy 210.934001 -27.776969)
			(xy 210.878597 -27.75402) (xy 210.826663 -27.724036) (xy 210.779087 -27.68753) (xy 210.736682 -27.645125)
			(xy 210.700176 -27.597549) (xy 210.670192 -27.545615) (xy 210.647243 -27.490211) (xy 210.631722 -27.432286)
			(xy 210.623894 -27.37283) (xy 210.623404 -27.342846) (xy 203.30543 -27.342846) (xy 203.271441 -27.372297)
			(xy 203.225591 -27.401763) (xy 203.176014 -27.424405) (xy 203.123719 -27.43976) (xy 203.069771 -27.447516)
			(xy 203.015269 -27.447516) (xy 202.961321 -27.43976) (xy 202.909026 -27.424405) (xy 202.859449 -27.401763)
			(xy 202.813599 -27.372297) (xy 202.772408 -27.336606) (xy 202.736717 -27.295415) (xy 202.707251 -27.249565)
			(xy 202.684609 -27.199988) (xy 202.669254 -27.147693) (xy 202.661498 -27.093745) (xy 202.661012 -27.066494)
			(xy 202.66155 -27.037006) (xy 202.670647 -26.978734) (xy 202.688608 -26.922559) (xy 202.715004 -26.869818)
			(xy 202.749205 -26.821771) (xy 202.790397 -26.779562) (xy 202.813666 -26.76144) (xy 202.824723 -26.75247)
			(xy 202.841898 -26.729783) (xy 202.852145 -26.703238) (xy 202.854668 -26.674896) (xy 202.849272 -26.646957)
			(xy 202.836376 -26.621593) (xy 202.81698 -26.600773) (xy 202.80503 -26.593038) (xy 202.781295 -26.578131)
			(xy 202.738058 -26.542467) (xy 202.700505 -26.50086) (xy 202.669445 -26.454206) (xy 202.645545 -26.40351)
			(xy 202.62932 -26.349862) (xy 202.62112 -26.294418) (xy 202.620626 -26.266394) (xy 200.052823 -26.266394)
			(xy 200.052284 -26.267209) (xy 200.015067 -26.308746) (xy 199.972199 -26.344421) (xy 199.924593 -26.373475)
			(xy 199.873264 -26.395287) (xy 199.819307 -26.409393) (xy 199.76387 -26.415493) (xy 199.708136 -26.413456)
			(xy 199.653293 -26.403326) (xy 199.600509 -26.385319) (xy 199.550909 -26.359818) (xy 199.505551 -26.327367)
			(xy 199.465402 -26.288658) (xy 199.431316 -26.244515) (xy 199.40402 -26.19588) (xy 199.384097 -26.143789)
			(xy 199.371971 -26.089352) (xy 199.3679 -26.03373) (xy 193.575918 -26.03373) (xy 193.589121 -26.044718)
			(xy 193.626338 -26.086255) (xy 193.657111 -26.132768) (xy 193.680783 -26.183265) (xy 193.696851 -26.236672)
			(xy 193.704971 -26.291848) (xy 193.70548 -26.319734) (xy 193.704971 -26.34762) (xy 193.696851 -26.402796)
			(xy 193.680783 -26.456203) (xy 193.657111 -26.5067) (xy 193.626338 -26.553213) (xy 193.589121 -26.59475)
			(xy 193.546253 -26.630425) (xy 193.498647 -26.659479) (xy 193.447318 -26.681291) (xy 193.393361 -26.695397)
			(xy 193.337924 -26.701497) (xy 193.28219 -26.69946) (xy 193.227347 -26.68933) (xy 193.174563 -26.671323)
			(xy 193.124963 -26.645822) (xy 193.079605 -26.613371) (xy 193.039456 -26.574662) (xy 193.00537 -26.530519)
			(xy 192.978074 -26.481884) (xy 192.958151 -26.429793) (xy 192.946025 -26.375356) (xy 192.941954 -26.319734)
			(xy 187.950681 -26.319734) (xy 187.952633 -26.332996) (xy 187.953142 -26.360882) (xy 187.952633 -26.388768)
			(xy 187.944513 -26.443944) (xy 187.928445 -26.497351) (xy 187.904773 -26.547848) (xy 187.874 -26.594361)
			(xy 187.836783 -26.635898) (xy 187.793915 -26.671573) (xy 187.746309 -26.700627) (xy 187.69498 -26.722439)
			(xy 187.641023 -26.736545) (xy 187.585586 -26.742645) (xy 187.529852 -26.740608) (xy 187.475009 -26.730478)
			(xy 187.422225 -26.712471) (xy 187.372625 -26.68697) (xy 187.327267 -26.654519) (xy 187.287118 -26.61581)
			(xy 187.253032 -26.571667) (xy 187.225736 -26.523032) (xy 187.205813 -26.470941) (xy 187.193687 -26.416504)
			(xy 187.189616 -26.360882) (xy 185.523312 -26.360882) (xy 185.531062 -26.389806) (xy 185.53889 -26.449262)
			(xy 185.53938 -26.479246) (xy 185.53938 -26.971244) (xy 188.951106 -26.971244) (xy 188.955177 -26.915622)
			(xy 188.967303 -26.861185) (xy 188.987226 -26.809094) (xy 189.014522 -26.760459) (xy 189.048608 -26.716316)
			(xy 189.088757 -26.677607) (xy 189.134115 -26.645156) (xy 189.183715 -26.619655) (xy 189.236499 -26.601648)
			(xy 189.291342 -26.591518) (xy 189.347076 -26.589481) (xy 189.402513 -26.595581) (xy 189.45647 -26.609687)
			(xy 189.507799 -26.631499) (xy 189.555405 -26.660553) (xy 189.598273 -26.696228) (xy 189.63549 -26.737765)
			(xy 189.666263 -26.784278) (xy 189.689935 -26.834775) (xy 189.706003 -26.888182) (xy 189.714123 -26.943358)
			(xy 189.714632 -26.971244) (xy 189.714123 -26.99913) (xy 189.706003 -27.054306) (xy 189.689935 -27.107713)
			(xy 189.666263 -27.15821) (xy 189.63549 -27.204723) (xy 189.598273 -27.24626) (xy 189.555405 -27.281935)
			(xy 189.507799 -27.310989) (xy 189.45647 -27.332801) (xy 189.402513 -27.346907) (xy 189.347076 -27.353007)
			(xy 189.291342 -27.35097) (xy 189.236499 -27.34084) (xy 189.183715 -27.322833) (xy 189.134115 -27.297332)
			(xy 189.088757 -27.264881) (xy 189.048608 -27.226172) (xy 189.014522 -27.182029) (xy 188.987226 -27.133394)
			(xy 188.967303 -27.081303) (xy 188.955177 -27.026866) (xy 188.951106 -26.971244) (xy 185.53938 -26.971244)
			(xy 185.53938 -27.342846) (xy 185.53889 -27.37283) (xy 185.531062 -27.432286) (xy 185.515541 -27.490211)
			(xy 185.492592 -27.545615) (xy 185.462608 -27.597549) (xy 185.426102 -27.645125) (xy 185.383697 -27.68753)
			(xy 185.336121 -27.724036) (xy 185.284187 -27.75402) (xy 185.228783 -27.776969) (xy 185.170858 -27.79249)
			(xy 185.111402 -27.800318) (xy 185.051434 -27.800318) (xy 184.991978 -27.79249) (xy 184.934053 -27.776969)
			(xy 184.878649 -27.75402) (xy 184.826715 -27.724036) (xy 184.779139 -27.68753) (xy 184.736734 -27.645125)
			(xy 184.700228 -27.597549) (xy 184.670244 -27.545615) (xy 184.647295 -27.490211) (xy 184.631774 -27.432286)
			(xy 184.623946 -27.37283) (xy 184.623456 -27.342846) (xy 177.305482 -27.342846) (xy 177.271493 -27.372297)
			(xy 177.225643 -27.401763) (xy 177.176066 -27.424405) (xy 177.123771 -27.43976) (xy 177.069823 -27.447516)
			(xy 177.015321 -27.447516) (xy 176.961373 -27.43976) (xy 176.909078 -27.424405) (xy 176.859501 -27.401763)
			(xy 176.813651 -27.372297) (xy 176.77246 -27.336606) (xy 176.736769 -27.295415) (xy 176.707303 -27.249565)
			(xy 176.684661 -27.199988) (xy 176.669306 -27.147693) (xy 176.66155 -27.093745) (xy 176.661064 -27.066494)
			(xy 176.661622 -27.037007) (xy 176.670717 -26.978737) (xy 176.688675 -26.922563) (xy 176.715067 -26.869822)
			(xy 176.749265 -26.821774) (xy 176.790451 -26.779564) (xy 176.813718 -26.76144) (xy 176.824782 -26.752475)
			(xy 176.841965 -26.72979) (xy 176.852218 -26.703242) (xy 176.854743 -26.674895) (xy 176.849344 -26.646953)
			(xy 176.836441 -26.621588) (xy 176.817036 -26.600771) (xy 176.805082 -26.593038) (xy 176.781336 -26.578148)
			(xy 176.738102 -26.542479) (xy 176.700551 -26.500869) (xy 176.669493 -26.454212) (xy 176.645595 -26.403514)
			(xy 176.629371 -26.349864) (xy 176.621172 -26.294418) (xy 176.620678 -26.266394) (xy 174.052875 -26.266394)
			(xy 174.052336 -26.267209) (xy 174.015119 -26.308746) (xy 173.972251 -26.344421) (xy 173.924645 -26.373475)
			(xy 173.873316 -26.395287) (xy 173.819359 -26.409393) (xy 173.763922 -26.415493) (xy 173.708188 -26.413456)
			(xy 173.653345 -26.403326) (xy 173.600561 -26.385319) (xy 173.550961 -26.359818) (xy 173.505603 -26.327367)
			(xy 173.465454 -26.288658) (xy 173.431368 -26.244515) (xy 173.404072 -26.19588) (xy 173.384149 -26.143789)
			(xy 173.372023 -26.089352) (xy 173.367952 -26.03373) (xy 167.57597 -26.03373) (xy 167.589173 -26.044718)
			(xy 167.62639 -26.086255) (xy 167.657163 -26.132768) (xy 167.680835 -26.183265) (xy 167.696903 -26.236672)
			(xy 167.705023 -26.291848) (xy 167.705532 -26.319734) (xy 167.705023 -26.34762) (xy 167.696903 -26.402796)
			(xy 167.680835 -26.456203) (xy 167.657163 -26.5067) (xy 167.62639 -26.553213) (xy 167.589173 -26.59475)
			(xy 167.546305 -26.630425) (xy 167.498699 -26.659479) (xy 167.44737 -26.681291) (xy 167.393413 -26.695397)
			(xy 167.337976 -26.701497) (xy 167.282242 -26.69946) (xy 167.227399 -26.68933) (xy 167.174615 -26.671323)
			(xy 167.125015 -26.645822) (xy 167.079657 -26.613371) (xy 167.039508 -26.574662) (xy 167.005422 -26.530519)
			(xy 166.978126 -26.481884) (xy 166.958203 -26.429793) (xy 166.946077 -26.375356) (xy 166.942006 -26.319734)
			(xy 161.950733 -26.319734) (xy 161.952685 -26.332996) (xy 161.953194 -26.360882) (xy 161.952685 -26.388768)
			(xy 161.944565 -26.443944) (xy 161.928497 -26.497351) (xy 161.904825 -26.547848) (xy 161.874052 -26.594361)
			(xy 161.836835 -26.635898) (xy 161.793967 -26.671573) (xy 161.746361 -26.700627) (xy 161.695032 -26.722439)
			(xy 161.641075 -26.736545) (xy 161.585638 -26.742645) (xy 161.529904 -26.740608) (xy 161.475061 -26.730478)
			(xy 161.422277 -26.712471) (xy 161.372677 -26.68697) (xy 161.327319 -26.654519) (xy 161.28717 -26.61581)
			(xy 161.253084 -26.571667) (xy 161.225788 -26.523032) (xy 161.205865 -26.470941) (xy 161.193739 -26.416504)
			(xy 161.189668 -26.360882) (xy 159.523364 -26.360882) (xy 159.531114 -26.389806) (xy 159.538942 -26.449262)
			(xy 159.539432 -26.479246) (xy 159.539432 -26.971244) (xy 162.951158 -26.971244) (xy 162.955229 -26.915622)
			(xy 162.967355 -26.861185) (xy 162.987278 -26.809094) (xy 163.014574 -26.760459) (xy 163.04866 -26.716316)
			(xy 163.088809 -26.677607) (xy 163.134167 -26.645156) (xy 163.183767 -26.619655) (xy 163.236551 -26.601648)
			(xy 163.291394 -26.591518) (xy 163.347128 -26.589481) (xy 163.402565 -26.595581) (xy 163.456522 -26.609687)
			(xy 163.507851 -26.631499) (xy 163.555457 -26.660553) (xy 163.598325 -26.696228) (xy 163.635542 -26.737765)
			(xy 163.666315 -26.784278) (xy 163.689987 -26.834775) (xy 163.706055 -26.888182) (xy 163.714175 -26.943358)
			(xy 163.714684 -26.971244) (xy 163.714175 -26.99913) (xy 163.706055 -27.054306) (xy 163.689987 -27.107713)
			(xy 163.666315 -27.15821) (xy 163.635542 -27.204723) (xy 163.598325 -27.24626) (xy 163.555457 -27.281935)
			(xy 163.507851 -27.310989) (xy 163.456522 -27.332801) (xy 163.402565 -27.346907) (xy 163.347128 -27.353007)
			(xy 163.291394 -27.35097) (xy 163.236551 -27.34084) (xy 163.183767 -27.322833) (xy 163.134167 -27.297332)
			(xy 163.088809 -27.264881) (xy 163.04866 -27.226172) (xy 163.014574 -27.182029) (xy 162.987278 -27.133394)
			(xy 162.967355 -27.081303) (xy 162.955229 -27.026866) (xy 162.951158 -26.971244) (xy 159.539432 -26.971244)
			(xy 159.539432 -27.342846) (xy 159.538942 -27.37283) (xy 159.531114 -27.432286) (xy 159.515593 -27.490211)
			(xy 159.492644 -27.545615) (xy 159.46266 -27.597549) (xy 159.426154 -27.645125) (xy 159.383749 -27.68753)
			(xy 159.336173 -27.724036) (xy 159.284239 -27.75402) (xy 159.228835 -27.776969) (xy 159.17091 -27.79249)
			(xy 159.111454 -27.800318) (xy 159.051486 -27.800318) (xy 158.99203 -27.79249) (xy 158.934105 -27.776969)
			(xy 158.878701 -27.75402) (xy 158.826767 -27.724036) (xy 158.779191 -27.68753) (xy 158.736786 -27.645125)
			(xy 158.70028 -27.597549) (xy 158.670296 -27.545615) (xy 158.647347 -27.490211) (xy 158.631826 -27.432286)
			(xy 158.623998 -27.37283) (xy 158.623508 -27.342846) (xy 151.305534 -27.342846) (xy 151.271545 -27.372297)
			(xy 151.225695 -27.401763) (xy 151.176118 -27.424405) (xy 151.123823 -27.43976) (xy 151.069875 -27.447516)
			(xy 151.015373 -27.447516) (xy 150.961425 -27.43976) (xy 150.90913 -27.424405) (xy 150.859553 -27.401763)
			(xy 150.813703 -27.372297) (xy 150.772512 -27.336606) (xy 150.736821 -27.295415) (xy 150.707355 -27.249565)
			(xy 150.684713 -27.199988) (xy 150.669358 -27.147693) (xy 150.661602 -27.093745) (xy 150.661116 -27.066494)
			(xy 150.661653 -27.037006) (xy 150.67075 -26.978734) (xy 150.688711 -26.922558) (xy 150.715107 -26.869818)
			(xy 150.749308 -26.82177) (xy 150.7905 -26.779562) (xy 150.81377 -26.76144) (xy 150.824826 -26.752469)
			(xy 150.842 -26.729783) (xy 150.852247 -26.703238) (xy 150.85477 -26.674896) (xy 150.849375 -26.646958)
			(xy 150.836478 -26.621594) (xy 150.817084 -26.600774) (xy 150.805134 -26.593038) (xy 150.7814 -26.578129)
			(xy 150.738163 -26.542466) (xy 150.70061 -26.500859) (xy 150.669549 -26.454206) (xy 150.645649 -26.40351)
			(xy 150.629424 -26.349862) (xy 150.621224 -26.294418) (xy 150.62073 -26.266394) (xy 148.052927 -26.266394)
			(xy 148.052388 -26.267209) (xy 148.015171 -26.308746) (xy 147.972303 -26.344421) (xy 147.924697 -26.373475)
			(xy 147.873368 -26.395287) (xy 147.819411 -26.409393) (xy 147.763974 -26.415493) (xy 147.70824 -26.413456)
			(xy 147.653397 -26.403326) (xy 147.600613 -26.385319) (xy 147.551013 -26.359818) (xy 147.505655 -26.327367)
			(xy 147.465506 -26.288658) (xy 147.43142 -26.244515) (xy 147.404124 -26.19588) (xy 147.384201 -26.143789)
			(xy 147.372075 -26.089352) (xy 147.368004 -26.03373) (xy 141.576022 -26.03373) (xy 141.589225 -26.044718)
			(xy 141.626442 -26.086255) (xy 141.657215 -26.132768) (xy 141.680887 -26.183265) (xy 141.696955 -26.236672)
			(xy 141.705075 -26.291848) (xy 141.705584 -26.319734) (xy 141.705075 -26.34762) (xy 141.696955 -26.402796)
			(xy 141.680887 -26.456203) (xy 141.657215 -26.5067) (xy 141.626442 -26.553213) (xy 141.589225 -26.59475)
			(xy 141.546357 -26.630425) (xy 141.498751 -26.659479) (xy 141.447422 -26.681291) (xy 141.393465 -26.695397)
			(xy 141.338028 -26.701497) (xy 141.282294 -26.69946) (xy 141.227451 -26.68933) (xy 141.174667 -26.671323)
			(xy 141.125067 -26.645822) (xy 141.079709 -26.613371) (xy 141.03956 -26.574662) (xy 141.005474 -26.530519)
			(xy 140.978178 -26.481884) (xy 140.958255 -26.429793) (xy 140.946129 -26.375356) (xy 140.942058 -26.319734)
			(xy 135.950785 -26.319734) (xy 135.952737 -26.332996) (xy 135.953246 -26.360882) (xy 135.952737 -26.388768)
			(xy 135.944617 -26.443944) (xy 135.928549 -26.497351) (xy 135.904877 -26.547848) (xy 135.874104 -26.594361)
			(xy 135.836887 -26.635898) (xy 135.794019 -26.671573) (xy 135.746413 -26.700627) (xy 135.695084 -26.722439)
			(xy 135.641127 -26.736545) (xy 135.58569 -26.742645) (xy 135.529956 -26.740608) (xy 135.475113 -26.730478)
			(xy 135.422329 -26.712471) (xy 135.372729 -26.68697) (xy 135.327371 -26.654519) (xy 135.287222 -26.61581)
			(xy 135.253136 -26.571667) (xy 135.22584 -26.523032) (xy 135.205917 -26.470941) (xy 135.193791 -26.416504)
			(xy 135.18972 -26.360882) (xy 133.523416 -26.360882) (xy 133.531166 -26.389806) (xy 133.538994 -26.449262)
			(xy 133.539484 -26.479246) (xy 133.539484 -26.971244) (xy 136.95121 -26.971244) (xy 136.955281 -26.915622)
			(xy 136.967407 -26.861185) (xy 136.98733 -26.809094) (xy 137.014626 -26.760459) (xy 137.048712 -26.716316)
			(xy 137.088861 -26.677607) (xy 137.134219 -26.645156) (xy 137.183819 -26.619655) (xy 137.236603 -26.601648)
			(xy 137.291446 -26.591518) (xy 137.34718 -26.589481) (xy 137.402617 -26.595581) (xy 137.456574 -26.609687)
			(xy 137.507903 -26.631499) (xy 137.555509 -26.660553) (xy 137.598377 -26.696228) (xy 137.635594 -26.737765)
			(xy 137.666367 -26.784278) (xy 137.690039 -26.834775) (xy 137.706107 -26.888182) (xy 137.714227 -26.943358)
			(xy 137.714736 -26.971244) (xy 137.714227 -26.99913) (xy 137.706107 -27.054306) (xy 137.690039 -27.107713)
			(xy 137.666367 -27.15821) (xy 137.635594 -27.204723) (xy 137.598377 -27.24626) (xy 137.555509 -27.281935)
			(xy 137.507903 -27.310989) (xy 137.456574 -27.332801) (xy 137.402617 -27.346907) (xy 137.34718 -27.353007)
			(xy 137.291446 -27.35097) (xy 137.236603 -27.34084) (xy 137.183819 -27.322833) (xy 137.134219 -27.297332)
			(xy 137.088861 -27.264881) (xy 137.048712 -27.226172) (xy 137.014626 -27.182029) (xy 136.98733 -27.133394)
			(xy 136.967407 -27.081303) (xy 136.955281 -27.026866) (xy 136.95121 -26.971244) (xy 133.539484 -26.971244)
			(xy 133.539484 -27.342846) (xy 133.538994 -27.37283) (xy 133.531166 -27.432286) (xy 133.515645 -27.490211)
			(xy 133.492696 -27.545615) (xy 133.462712 -27.597549) (xy 133.426206 -27.645125) (xy 133.383801 -27.68753)
			(xy 133.336225 -27.724036) (xy 133.284291 -27.75402) (xy 133.228887 -27.776969) (xy 133.170962 -27.79249)
			(xy 133.111506 -27.800318) (xy 133.051538 -27.800318) (xy 132.992082 -27.79249) (xy 132.934157 -27.776969)
			(xy 132.878753 -27.75402) (xy 132.826819 -27.724036) (xy 132.779243 -27.68753) (xy 132.736838 -27.645125)
			(xy 132.700332 -27.597549) (xy 132.670348 -27.545615) (xy 132.647399 -27.490211) (xy 132.631878 -27.432286)
			(xy 132.62405 -27.37283) (xy 132.62356 -27.342846) (xy 125.305586 -27.342846) (xy 125.271597 -27.372297)
			(xy 125.225747 -27.401763) (xy 125.17617 -27.424405) (xy 125.123875 -27.43976) (xy 125.069927 -27.447516)
			(xy 125.015425 -27.447516) (xy 124.961477 -27.43976) (xy 124.909182 -27.424405) (xy 124.859605 -27.401763)
			(xy 124.813755 -27.372297) (xy 124.772564 -27.336606) (xy 124.736873 -27.295415) (xy 124.707407 -27.249565)
			(xy 124.684765 -27.199988) (xy 124.66941 -27.147693) (xy 124.661654 -27.093745) (xy 124.661168 -27.066494)
			(xy 124.661724 -27.037007) (xy 124.67082 -26.978737) (xy 124.688778 -26.922562) (xy 124.71517 -26.869822)
			(xy 124.749368 -26.821774) (xy 124.790555 -26.779564) (xy 124.813822 -26.76144) (xy 124.824885 -26.752475)
			(xy 124.842068 -26.729789) (xy 124.85232 -26.703242) (xy 124.854845 -26.674895) (xy 124.849447 -26.646954)
			(xy 124.836544 -26.621588) (xy 124.81714 -26.600771) (xy 124.805186 -26.593038) (xy 124.781441 -26.578146)
			(xy 124.738206 -26.542478) (xy 124.700656 -26.500868) (xy 124.669597 -26.454212) (xy 124.645699 -26.403513)
			(xy 124.629475 -26.349864) (xy 124.621276 -26.294418) (xy 124.620782 -26.266394) (xy 122.052979 -26.266394)
			(xy 122.05244 -26.267209) (xy 122.015223 -26.308746) (xy 121.972355 -26.344421) (xy 121.924749 -26.373475)
			(xy 121.87342 -26.395287) (xy 121.819463 -26.409393) (xy 121.764026 -26.415493) (xy 121.708292 -26.413456)
			(xy 121.653449 -26.403326) (xy 121.600665 -26.385319) (xy 121.551065 -26.359818) (xy 121.505707 -26.327367)
			(xy 121.465558 -26.288658) (xy 121.431472 -26.244515) (xy 121.404176 -26.19588) (xy 121.384253 -26.143789)
			(xy 121.372127 -26.089352) (xy 121.368056 -26.03373) (xy 103.475768 -26.03373) (xy 103.488971 -26.044718)
			(xy 103.526188 -26.086255) (xy 103.556961 -26.132768) (xy 103.580633 -26.183265) (xy 103.596701 -26.236672)
			(xy 103.604821 -26.291848) (xy 103.60533 -26.319734) (xy 103.604821 -26.34762) (xy 103.596701 -26.402796)
			(xy 103.580633 -26.456203) (xy 103.556961 -26.5067) (xy 103.526188 -26.553213) (xy 103.488971 -26.59475)
			(xy 103.446103 -26.630425) (xy 103.398497 -26.659479) (xy 103.347168 -26.681291) (xy 103.293211 -26.695397)
			(xy 103.237774 -26.701497) (xy 103.18204 -26.69946) (xy 103.127197 -26.68933) (xy 103.074413 -26.671323)
			(xy 103.024813 -26.645822) (xy 102.979455 -26.613371) (xy 102.939306 -26.574662) (xy 102.90522 -26.530519)
			(xy 102.877924 -26.481884) (xy 102.858001 -26.429793) (xy 102.845875 -26.375356) (xy 102.841804 -26.319734)
			(xy 97.850531 -26.319734) (xy 97.852483 -26.332996) (xy 97.852992 -26.360882) (xy 97.852483 -26.388768)
			(xy 97.844363 -26.443944) (xy 97.828295 -26.497351) (xy 97.804623 -26.547848) (xy 97.77385 -26.594361)
			(xy 97.736633 -26.635898) (xy 97.693765 -26.671573) (xy 97.646159 -26.700627) (xy 97.59483 -26.722439)
			(xy 97.540873 -26.736545) (xy 97.485436 -26.742645) (xy 97.429702 -26.740608) (xy 97.374859 -26.730478)
			(xy 97.322075 -26.712471) (xy 97.272475 -26.68697) (xy 97.227117 -26.654519) (xy 97.186968 -26.61581)
			(xy 97.152882 -26.571667) (xy 97.125586 -26.523032) (xy 97.105663 -26.470941) (xy 97.093537 -26.416504)
			(xy 97.089466 -26.360882) (xy 95.422899 -26.360882) (xy 95.430663 -26.389856) (xy 95.438486 -26.449278)
			(xy 95.438976 -26.479246) (xy 95.438976 -26.971244) (xy 98.850956 -26.971244) (xy 98.855027 -26.915622)
			(xy 98.867153 -26.861185) (xy 98.887076 -26.809094) (xy 98.914372 -26.760459) (xy 98.948458 -26.716316)
			(xy 98.988607 -26.677607) (xy 99.033965 -26.645156) (xy 99.083565 -26.619655) (xy 99.136349 -26.601648)
			(xy 99.191192 -26.591518) (xy 99.246926 -26.589481) (xy 99.302363 -26.595581) (xy 99.35632 -26.609687)
			(xy 99.407649 -26.631499) (xy 99.455255 -26.660553) (xy 99.498123 -26.696228) (xy 99.53534 -26.737765)
			(xy 99.566113 -26.784278) (xy 99.589785 -26.834775) (xy 99.605853 -26.888182) (xy 99.613973 -26.943358)
			(xy 99.614482 -26.971244) (xy 99.613973 -26.99913) (xy 99.605853 -27.054306) (xy 99.589785 -27.107713)
			(xy 99.566113 -27.15821) (xy 99.53534 -27.204723) (xy 99.498123 -27.24626) (xy 99.455255 -27.281935)
			(xy 99.407649 -27.310989) (xy 99.35632 -27.332801) (xy 99.302363 -27.346907) (xy 99.246926 -27.353007)
			(xy 99.191192 -27.35097) (xy 99.136349 -27.34084) (xy 99.083565 -27.322833) (xy 99.033965 -27.297332)
			(xy 98.988607 -27.264881) (xy 98.948458 -27.226172) (xy 98.914372 -27.182029) (xy 98.887076 -27.133394)
			(xy 98.867153 -27.081303) (xy 98.855027 -27.026866) (xy 98.850956 -26.971244) (xy 95.438976 -26.971244)
			(xy 95.438976 -27.342846) (xy 95.438486 -27.372814) (xy 95.430663 -27.432236) (xy 95.41515 -27.490129)
			(xy 95.392214 -27.545502) (xy 95.362247 -27.597408) (xy 95.32576 -27.644958) (xy 95.28338 -27.687338)
			(xy 95.23583 -27.723825) (xy 95.183924 -27.753792) (xy 95.128551 -27.776728) (xy 95.070658 -27.792241)
			(xy 95.011236 -27.800064) (xy 94.9513 -27.800064) (xy 94.891878 -27.792241) (xy 94.833985 -27.776728)
			(xy 94.778612 -27.753792) (xy 94.726706 -27.723825) (xy 94.679156 -27.687338) (xy 94.636776 -27.644958)
			(xy 94.600289 -27.597408) (xy 94.570322 -27.545502) (xy 94.547386 -27.490129) (xy 94.531873 -27.432236)
			(xy 94.52405 -27.372814) (xy 94.52356 -27.342846) (xy 87.205332 -27.342846) (xy 87.171343 -27.372297)
			(xy 87.125493 -27.401763) (xy 87.075916 -27.424405) (xy 87.023621 -27.43976) (xy 86.969673 -27.447516)
			(xy 86.915171 -27.447516) (xy 86.861223 -27.43976) (xy 86.808928 -27.424405) (xy 86.759351 -27.401763)
			(xy 86.713501 -27.372297) (xy 86.67231 -27.336606) (xy 86.636619 -27.295415) (xy 86.607153 -27.249565)
			(xy 86.584511 -27.199988) (xy 86.569156 -27.147693) (xy 86.5614 -27.093745) (xy 86.560914 -27.066494)
			(xy 86.561452 -27.037006) (xy 86.570549 -26.978734) (xy 86.588509 -26.922558) (xy 86.614905 -26.869818)
			(xy 86.649107 -26.82177) (xy 86.690299 -26.779562) (xy 86.713568 -26.76144) (xy 86.724624 -26.75247)
			(xy 86.741799 -26.729783) (xy 86.752046 -26.703238) (xy 86.754569 -26.674896) (xy 86.749173 -26.646958)
			(xy 86.736277 -26.621594) (xy 86.716882 -26.600773) (xy 86.704932 -26.593038) (xy 86.681197 -26.57813)
			(xy 86.637961 -26.542466) (xy 86.600408 -26.50086) (xy 86.569347 -26.454206) (xy 86.545447 -26.40351)
			(xy 86.529222 -26.349862) (xy 86.521022 -26.294418) (xy 86.520528 -26.266394) (xy 83.952725 -26.266394)
			(xy 83.952186 -26.267209) (xy 83.914969 -26.308746) (xy 83.872101 -26.344421) (xy 83.824495 -26.373475)
			(xy 83.773166 -26.395287) (xy 83.719209 -26.409393) (xy 83.663772 -26.415493) (xy 83.608038 -26.413456)
			(xy 83.553195 -26.403326) (xy 83.500411 -26.385319) (xy 83.450811 -26.359818) (xy 83.405453 -26.327367)
			(xy 83.365304 -26.288658) (xy 83.331218 -26.244515) (xy 83.303922 -26.19588) (xy 83.283999 -26.143789)
			(xy 83.271873 -26.089352) (xy 83.267802 -26.03373) (xy 77.47582 -26.03373) (xy 77.489023 -26.044718)
			(xy 77.52624 -26.086255) (xy 77.557013 -26.132768) (xy 77.580685 -26.183265) (xy 77.596753 -26.236672)
			(xy 77.604873 -26.291848) (xy 77.605382 -26.319734) (xy 77.604873 -26.34762) (xy 77.596753 -26.402796)
			(xy 77.580685 -26.456203) (xy 77.557013 -26.5067) (xy 77.52624 -26.553213) (xy 77.489023 -26.59475)
			(xy 77.446155 -26.630425) (xy 77.398549 -26.659479) (xy 77.34722 -26.681291) (xy 77.293263 -26.695397)
			(xy 77.237826 -26.701497) (xy 77.182092 -26.69946) (xy 77.127249 -26.68933) (xy 77.074465 -26.671323)
			(xy 77.024865 -26.645822) (xy 76.979507 -26.613371) (xy 76.939358 -26.574662) (xy 76.905272 -26.530519)
			(xy 76.877976 -26.481884) (xy 76.858053 -26.429793) (xy 76.845927 -26.375356) (xy 76.841856 -26.319734)
			(xy 71.850583 -26.319734) (xy 71.852535 -26.332996) (xy 71.853044 -26.360882) (xy 71.852535 -26.388768)
			(xy 71.844415 -26.443944) (xy 71.828347 -26.497351) (xy 71.804675 -26.547848) (xy 71.773902 -26.594361)
			(xy 71.736685 -26.635898) (xy 71.693817 -26.671573) (xy 71.646211 -26.700627) (xy 71.594882 -26.722439)
			(xy 71.540925 -26.736545) (xy 71.485488 -26.742645) (xy 71.429754 -26.740608) (xy 71.374911 -26.730478)
			(xy 71.322127 -26.712471) (xy 71.272527 -26.68697) (xy 71.227169 -26.654519) (xy 71.18702 -26.61581)
			(xy 71.152934 -26.571667) (xy 71.125638 -26.523032) (xy 71.105715 -26.470941) (xy 71.093589 -26.416504)
			(xy 71.089518 -26.360882) (xy 69.422951 -26.360882) (xy 69.430715 -26.389856) (xy 69.438538 -26.449278)
			(xy 69.439028 -26.479246) (xy 69.439028 -26.971244) (xy 72.851008 -26.971244) (xy 72.855079 -26.915622)
			(xy 72.867205 -26.861185) (xy 72.887128 -26.809094) (xy 72.914424 -26.760459) (xy 72.94851 -26.716316)
			(xy 72.988659 -26.677607) (xy 73.034017 -26.645156) (xy 73.083617 -26.619655) (xy 73.136401 -26.601648)
			(xy 73.191244 -26.591518) (xy 73.246978 -26.589481) (xy 73.302415 -26.595581) (xy 73.356372 -26.609687)
			(xy 73.407701 -26.631499) (xy 73.455307 -26.660553) (xy 73.498175 -26.696228) (xy 73.535392 -26.737765)
			(xy 73.566165 -26.784278) (xy 73.589837 -26.834775) (xy 73.605905 -26.888182) (xy 73.614025 -26.943358)
			(xy 73.614534 -26.971244) (xy 73.614025 -26.99913) (xy 73.605905 -27.054306) (xy 73.589837 -27.107713)
			(xy 73.566165 -27.15821) (xy 73.535392 -27.204723) (xy 73.498175 -27.24626) (xy 73.455307 -27.281935)
			(xy 73.407701 -27.310989) (xy 73.356372 -27.332801) (xy 73.302415 -27.346907) (xy 73.246978 -27.353007)
			(xy 73.191244 -27.35097) (xy 73.136401 -27.34084) (xy 73.083617 -27.322833) (xy 73.034017 -27.297332)
			(xy 72.988659 -27.264881) (xy 72.94851 -27.226172) (xy 72.914424 -27.182029) (xy 72.887128 -27.133394)
			(xy 72.867205 -27.081303) (xy 72.855079 -27.026866) (xy 72.851008 -26.971244) (xy 69.439028 -26.971244)
			(xy 69.439028 -27.342846) (xy 69.438538 -27.372814) (xy 69.430715 -27.432236) (xy 69.415202 -27.490129)
			(xy 69.392266 -27.545502) (xy 69.362299 -27.597408) (xy 69.325812 -27.644958) (xy 69.283432 -27.687338)
			(xy 69.235882 -27.723825) (xy 69.183976 -27.753792) (xy 69.128603 -27.776728) (xy 69.07071 -27.792241)
			(xy 69.011288 -27.800064) (xy 68.951352 -27.800064) (xy 68.89193 -27.792241) (xy 68.834037 -27.776728)
			(xy 68.778664 -27.753792) (xy 68.726758 -27.723825) (xy 68.679208 -27.687338) (xy 68.636828 -27.644958)
			(xy 68.600341 -27.597408) (xy 68.570374 -27.545502) (xy 68.547438 -27.490129) (xy 68.531925 -27.432236)
			(xy 68.524102 -27.372814) (xy 68.523612 -27.342846) (xy 61.205384 -27.342846) (xy 61.171395 -27.372297)
			(xy 61.125545 -27.401763) (xy 61.075968 -27.424405) (xy 61.023673 -27.43976) (xy 60.969725 -27.447516)
			(xy 60.915223 -27.447516) (xy 60.861275 -27.43976) (xy 60.80898 -27.424405) (xy 60.759403 -27.401763)
			(xy 60.713553 -27.372297) (xy 60.672362 -27.336606) (xy 60.636671 -27.295415) (xy 60.607205 -27.249565)
			(xy 60.584563 -27.199988) (xy 60.569208 -27.147693) (xy 60.561452 -27.093745) (xy 60.560966 -27.066494)
			(xy 60.561523 -27.037007) (xy 60.570618 -26.978737) (xy 60.588577 -26.922562) (xy 60.614969 -26.869822)
			(xy 60.649166 -26.821774) (xy 60.690353 -26.779564) (xy 60.71362 -26.76144) (xy 60.724683 -26.752475)
			(xy 60.741866 -26.729789) (xy 60.752119 -26.703242) (xy 60.754644 -26.674895) (xy 60.749245 -26.646954)
			(xy 60.736342 -26.621588) (xy 60.716938 -26.600771) (xy 60.704984 -26.593038) (xy 60.681238 -26.578147)
			(xy 60.638004 -26.542478) (xy 60.600453 -26.500868) (xy 60.569395 -26.454212) (xy 60.545497 -26.403513)
			(xy 60.529273 -26.349864) (xy 60.521074 -26.294418) (xy 60.52058 -26.266394) (xy 57.952777 -26.266394)
			(xy 57.952238 -26.267209) (xy 57.915021 -26.308746) (xy 57.872153 -26.344421) (xy 57.824547 -26.373475)
			(xy 57.773218 -26.395287) (xy 57.719261 -26.409393) (xy 57.663824 -26.415493) (xy 57.60809 -26.413456)
			(xy 57.553247 -26.403326) (xy 57.500463 -26.385319) (xy 57.450863 -26.359818) (xy 57.405505 -26.327367)
			(xy 57.365356 -26.288658) (xy 57.33127 -26.244515) (xy 57.303974 -26.19588) (xy 57.284051 -26.143789)
			(xy 57.271925 -26.089352) (xy 57.267854 -26.03373) (xy 51.475872 -26.03373) (xy 51.489075 -26.044718)
			(xy 51.526292 -26.086255) (xy 51.557065 -26.132768) (xy 51.580737 -26.183265) (xy 51.596805 -26.236672)
			(xy 51.604925 -26.291848) (xy 51.605434 -26.319734) (xy 51.604925 -26.34762) (xy 51.596805 -26.402796)
			(xy 51.580737 -26.456203) (xy 51.557065 -26.5067) (xy 51.526292 -26.553213) (xy 51.489075 -26.59475)
			(xy 51.446207 -26.630425) (xy 51.398601 -26.659479) (xy 51.347272 -26.681291) (xy 51.293315 -26.695397)
			(xy 51.237878 -26.701497) (xy 51.182144 -26.69946) (xy 51.127301 -26.68933) (xy 51.074517 -26.671323)
			(xy 51.024917 -26.645822) (xy 50.979559 -26.613371) (xy 50.93941 -26.574662) (xy 50.905324 -26.530519)
			(xy 50.878028 -26.481884) (xy 50.858105 -26.429793) (xy 50.845979 -26.375356) (xy 50.841908 -26.319734)
			(xy 45.850635 -26.319734) (xy 45.852587 -26.332996) (xy 45.853096 -26.360882) (xy 45.852587 -26.388768)
			(xy 45.844467 -26.443944) (xy 45.828399 -26.497351) (xy 45.804727 -26.547848) (xy 45.773954 -26.594361)
			(xy 45.736737 -26.635898) (xy 45.693869 -26.671573) (xy 45.646263 -26.700627) (xy 45.594934 -26.722439)
			(xy 45.540977 -26.736545) (xy 45.48554 -26.742645) (xy 45.429806 -26.740608) (xy 45.374963 -26.730478)
			(xy 45.322179 -26.712471) (xy 45.272579 -26.68697) (xy 45.227221 -26.654519) (xy 45.187072 -26.61581)
			(xy 45.152986 -26.571667) (xy 45.12569 -26.523032) (xy 45.105767 -26.470941) (xy 45.093641 -26.416504)
			(xy 45.08957 -26.360882) (xy 43.423003 -26.360882) (xy 43.430767 -26.389856) (xy 43.43859 -26.449278)
			(xy 43.43908 -26.479246) (xy 43.43908 -26.971244) (xy 46.85106 -26.971244) (xy 46.855131 -26.915622)
			(xy 46.867257 -26.861185) (xy 46.88718 -26.809094) (xy 46.914476 -26.760459) (xy 46.948562 -26.716316)
			(xy 46.988711 -26.677607) (xy 47.034069 -26.645156) (xy 47.083669 -26.619655) (xy 47.136453 -26.601648)
			(xy 47.191296 -26.591518) (xy 47.24703 -26.589481) (xy 47.302467 -26.595581) (xy 47.356424 -26.609687)
			(xy 47.407753 -26.631499) (xy 47.455359 -26.660553) (xy 47.498227 -26.696228) (xy 47.535444 -26.737765)
			(xy 47.566217 -26.784278) (xy 47.589889 -26.834775) (xy 47.605957 -26.888182) (xy 47.614077 -26.943358)
			(xy 47.614586 -26.971244) (xy 47.614077 -26.99913) (xy 47.605957 -27.054306) (xy 47.589889 -27.107713)
			(xy 47.566217 -27.15821) (xy 47.535444 -27.204723) (xy 47.498227 -27.24626) (xy 47.455359 -27.281935)
			(xy 47.407753 -27.310989) (xy 47.356424 -27.332801) (xy 47.302467 -27.346907) (xy 47.24703 -27.353007)
			(xy 47.191296 -27.35097) (xy 47.136453 -27.34084) (xy 47.083669 -27.322833) (xy 47.034069 -27.297332)
			(xy 46.988711 -27.264881) (xy 46.948562 -27.226172) (xy 46.914476 -27.182029) (xy 46.88718 -27.133394)
			(xy 46.867257 -27.081303) (xy 46.855131 -27.026866) (xy 46.85106 -26.971244) (xy 43.43908 -26.971244)
			(xy 43.43908 -27.342846) (xy 43.43859 -27.372814) (xy 43.430767 -27.432236) (xy 43.415254 -27.490129)
			(xy 43.392318 -27.545502) (xy 43.362351 -27.597408) (xy 43.325864 -27.644958) (xy 43.283484 -27.687338)
			(xy 43.235934 -27.723825) (xy 43.184028 -27.753792) (xy 43.128655 -27.776728) (xy 43.070762 -27.792241)
			(xy 43.01134 -27.800064) (xy 42.951404 -27.800064) (xy 42.891982 -27.792241) (xy 42.834089 -27.776728)
			(xy 42.778716 -27.753792) (xy 42.72681 -27.723825) (xy 42.67926 -27.687338) (xy 42.63688 -27.644958)
			(xy 42.600393 -27.597408) (xy 42.570426 -27.545502) (xy 42.54749 -27.490129) (xy 42.531977 -27.432236)
			(xy 42.524154 -27.372814) (xy 42.523664 -27.342846) (xy 35.205436 -27.342846) (xy 35.171447 -27.372297)
			(xy 35.125597 -27.401763) (xy 35.07602 -27.424405) (xy 35.023725 -27.43976) (xy 34.969777 -27.447516)
			(xy 34.915275 -27.447516) (xy 34.861327 -27.43976) (xy 34.809032 -27.424405) (xy 34.759455 -27.401763)
			(xy 34.713605 -27.372297) (xy 34.672414 -27.336606) (xy 34.636723 -27.295415) (xy 34.607257 -27.249565)
			(xy 34.584615 -27.199988) (xy 34.56926 -27.147693) (xy 34.561504 -27.093745) (xy 34.561018 -27.066494)
			(xy 34.561554 -27.037005) (xy 34.570651 -26.978734) (xy 34.588612 -26.922558) (xy 34.615008 -26.869818)
			(xy 34.64921 -26.82177) (xy 34.690402 -26.779562) (xy 34.713672 -26.76144) (xy 34.724728 -26.752469)
			(xy 34.741902 -26.729782) (xy 34.752148 -26.703237) (xy 34.754672 -26.674896) (xy 34.749276 -26.646958)
			(xy 34.73638 -26.621594) (xy 34.716985 -26.600774) (xy 34.705036 -26.593038) (xy 34.681302 -26.578128)
			(xy 34.638065 -26.542465) (xy 34.600512 -26.500859) (xy 34.569451 -26.454206) (xy 34.545551 -26.40351)
			(xy 34.529326 -26.349862) (xy 34.521126 -26.294418) (xy 34.520632 -26.266394) (xy 31.952829 -26.266394)
			(xy 31.95229 -26.267209) (xy 31.915073 -26.308746) (xy 31.872205 -26.344421) (xy 31.824599 -26.373475)
			(xy 31.77327 -26.395287) (xy 31.719313 -26.409393) (xy 31.663876 -26.415493) (xy 31.608142 -26.413456)
			(xy 31.553299 -26.403326) (xy 31.500515 -26.385319) (xy 31.450915 -26.359818) (xy 31.405557 -26.327367)
			(xy 31.365408 -26.288658) (xy 31.331322 -26.244515) (xy 31.304026 -26.19588) (xy 31.284103 -26.143789)
			(xy 31.271977 -26.089352) (xy 31.267906 -26.03373) (xy 19.666949 -26.03373) (xy 19.693921 -26.050191)
			(xy 19.736789 -26.085866) (xy 19.774006 -26.127403) (xy 19.804779 -26.173916) (xy 19.828451 -26.224413)
			(xy 19.844519 -26.27782) (xy 19.852639 -26.332996) (xy 19.853148 -26.360882) (xy 19.852639 -26.388768)
			(xy 19.844519 -26.443944) (xy 19.828451 -26.497351) (xy 19.804779 -26.547848) (xy 19.774006 -26.594361)
			(xy 19.736789 -26.635898) (xy 19.693921 -26.671573) (xy 19.646315 -26.700627) (xy 19.594986 -26.722439)
			(xy 19.541029 -26.736545) (xy 19.485592 -26.742645) (xy 19.429858 -26.740608) (xy 19.375015 -26.730478)
			(xy 19.322231 -26.712471) (xy 19.272631 -26.68697) (xy 19.227273 -26.654519) (xy 19.187124 -26.61581)
			(xy 19.153038 -26.571667) (xy 19.125742 -26.523032) (xy 19.105819 -26.470941) (xy 19.093693 -26.416504)
			(xy 19.089622 -26.360882) (xy 17.423055 -26.360882) (xy 17.430819 -26.389856) (xy 17.438642 -26.449278)
			(xy 17.439132 -26.479246) (xy 17.439132 -27.342846) (xy 17.438642 -27.372814) (xy 17.430819 -27.432236)
			(xy 17.415306 -27.490129) (xy 17.39237 -27.545502) (xy 17.362403 -27.597408) (xy 17.325916 -27.644958)
			(xy 17.283536 -27.687338) (xy 17.235986 -27.723825) (xy 17.18408 -27.753792) (xy 17.128707 -27.776728)
			(xy 17.070814 -27.792241) (xy 17.011392 -27.800064) (xy 16.951456 -27.800064) (xy 16.892034 -27.792241)
			(xy 16.834141 -27.776728) (xy 16.778768 -27.753792) (xy 16.726862 -27.723825) (xy 16.679312 -27.687338)
			(xy 16.636932 -27.644958) (xy 16.600445 -27.597408) (xy 16.570478 -27.545502) (xy 16.547542 -27.490129)
			(xy 16.532029 -27.432236) (xy 16.524206 -27.372814) (xy 16.523716 -27.342846) (xy 9.205488 -27.342846)
			(xy 9.171499 -27.372297) (xy 9.125649 -27.401763) (xy 9.076072 -27.424405) (xy 9.023777 -27.43976)
			(xy 8.969829 -27.447516) (xy 8.915327 -27.447516) (xy 8.861379 -27.43976) (xy 8.809084 -27.424405)
			(xy 8.759507 -27.401763) (xy 8.713657 -27.372297) (xy 8.672466 -27.336606) (xy 8.636775 -27.295415)
			(xy 8.607309 -27.249565) (xy 8.584667 -27.199988) (xy 8.569312 -27.147693) (xy 8.561556 -27.093745)
			(xy 8.56107 -27.066494) (xy 8.561625 -27.037006) (xy 8.570721 -26.978737) (xy 8.588679 -26.922562)
			(xy 8.615072 -26.869822) (xy 8.64927 -26.821774) (xy 8.690457 -26.779564) (xy 8.713724 -26.76144)
			(xy 8.724787 -26.752474) (xy 8.741969 -26.729789) (xy 8.752221 -26.703241) (xy 8.754746 -26.674895)
			(xy 8.749348 -26.646954) (xy 8.736445 -26.621589) (xy 8.717042 -26.600771) (xy 8.705088 -26.593038)
			(xy 8.681343 -26.578146) (xy 8.638109 -26.542477) (xy 8.600558 -26.500868) (xy 8.569499 -26.454211)
			(xy 8.545601 -26.403513) (xy 8.529377 -26.349864) (xy 8.521178 -26.294418) (xy 8.520684 -26.266394)
			(xy 6.002411 -26.266394) (xy 6.001872 -26.267209) (xy 5.964655 -26.308746) (xy 5.921787 -26.344421)
			(xy 5.874181 -26.373475) (xy 5.822852 -26.395287) (xy 5.768895 -26.409393) (xy 5.713458 -26.415493)
			(xy 5.657724 -26.413456) (xy 5.602881 -26.403326) (xy 5.550097 -26.385319) (xy 5.500497 -26.359818)
			(xy 5.455139 -26.327367) (xy 5.41499 -26.288658) (xy 5.380904 -26.244515) (xy 5.353608 -26.19588)
			(xy 5.333685 -26.143789) (xy 5.321559 -26.089352) (xy 5.317488 -26.03373) (xy 5.018509 -26.03373)
			(xy 5.004503 -26.080283) (xy 4.980831 -26.13078) (xy 4.950058 -26.177293) (xy 4.912841 -26.21883)
			(xy 4.869973 -26.254505) (xy 4.822367 -26.283559) (xy 4.771038 -26.305371) (xy 4.717081 -26.319477)
			(xy 4.661644 -26.325577) (xy 4.60591 -26.32354) (xy 4.551067 -26.31341) (xy 4.498283 -26.295403)
			(xy 4.448683 -26.269902) (xy 4.403325 -26.237451) (xy 4.363176 -26.198742) (xy 4.32909 -26.154599)
			(xy 4.301794 -26.105964) (xy 4.281871 -26.053873) (xy 4.269745 -25.999436) (xy 4.265674 -25.943814)
			(xy 2.402435 -25.943814) (xy 2.404879 -25.951938) (xy 2.412999 -26.007114) (xy 2.413508 -26.035)
			(xy 2.412999 -26.062886) (xy 2.404879 -26.118062) (xy 2.388811 -26.171469) (xy 2.365139 -26.221966)
			(xy 2.334366 -26.268479) (xy 2.297149 -26.310016) (xy 2.254281 -26.345691) (xy 2.206675 -26.374745)
			(xy 2.155346 -26.396557) (xy 2.101389 -26.410663) (xy 2.045952 -26.416763) (xy 1.990218 -26.414726)
			(xy 1.935375 -26.404596) (xy 1.882591 -26.386589) (xy 1.832991 -26.361088) (xy 1.787633 -26.328637)
			(xy 1.747484 -26.289928) (xy 1.713398 -26.245785) (xy 1.686102 -26.19715) (xy 1.666179 -26.145059)
			(xy 1.654053 -26.090622) (xy 1.649982 -26.035) (xy 1.306576 -26.035) (xy 1.306576 -29.330142) (xy 2.191256 -29.330142)
			(xy 2.195327 -29.27452) (xy 2.207453 -29.220083) (xy 2.227376 -29.167992) (xy 2.254672 -29.119357)
			(xy 2.288758 -29.075214) (xy 2.328907 -29.036505) (xy 2.374265 -29.004054) (xy 2.423865 -28.978553)
			(xy 2.476649 -28.960546) (xy 2.531492 -28.950416) (xy 2.587226 -28.948379) (xy 2.642663 -28.954479)
			(xy 2.69662 -28.968585) (xy 2.747949 -28.990397) (xy 2.795555 -29.019451) (xy 2.838423 -29.055126)
			(xy 2.87564 -29.096663) (xy 2.906413 -29.143176) (xy 2.930085 -29.193673) (xy 2.946153 -29.24708)
			(xy 2.954273 -29.302256) (xy 2.954782 -29.330142) (xy 2.954281 -29.357574) (xy 3.464304 -29.357574)
			(xy 3.468375 -29.301952) (xy 3.480501 -29.247515) (xy 3.500424 -29.195424) (xy 3.52772 -29.146789)
			(xy 3.561806 -29.102646) (xy 3.601955 -29.063937) (xy 3.647313 -29.031486) (xy 3.696913 -29.005985)
			(xy 3.749697 -28.987978) (xy 3.80454 -28.977848) (xy 3.860274 -28.975811) (xy 3.915711 -28.981911)
			(xy 3.969668 -28.996017) (xy 4.020997 -29.017829) (xy 4.068603 -29.046883) (xy 4.111471 -29.082558)
			(xy 4.147142 -29.12237) (xy 8.607044 -29.12237) (xy 8.607044 -28.25877) (xy 8.607534 -28.228802)
			(xy 8.615357 -28.16938) (xy 8.63087 -28.111487) (xy 8.653806 -28.056114) (xy 8.683773 -28.004208)
			(xy 8.72026 -27.956658) (xy 8.76264 -27.914278) (xy 8.81019 -27.877791) (xy 8.862096 -27.847824)
			(xy 8.917469 -27.824888) (xy 8.975362 -27.809375) (xy 9.034784 -27.801552) (xy 9.09472 -27.801552)
			(xy 9.154142 -27.809375) (xy 9.212035 -27.824888) (xy 9.267408 -27.847824) (xy 9.319314 -27.877791)
			(xy 9.366864 -27.914278) (xy 9.409244 -27.956658) (xy 9.445731 -28.004208) (xy 9.475698 -28.056114)
			(xy 9.498634 -28.111487) (xy 9.514147 -28.16938) (xy 9.52197 -28.228802) (xy 9.52246 -28.25877) (xy 9.52246 -29.12237)
			(xy 9.52197 -29.152338) (xy 9.514147 -29.21176) (xy 9.498634 -29.269653) (xy 9.475698 -29.325026)
			(xy 9.445731 -29.376932) (xy 9.409244 -29.424482) (xy 9.366864 -29.466862) (xy 9.319314 -29.503349)
			(xy 9.267408 -29.533316) (xy 9.212035 -29.556252) (xy 9.154142 -29.571765) (xy 9.09472 -29.579588)
			(xy 9.034784 -29.579588) (xy 8.975362 -29.571765) (xy 8.917469 -29.556252) (xy 8.862096 -29.533316)
			(xy 8.81019 -29.503349) (xy 8.76264 -29.466862) (xy 8.72026 -29.424482) (xy 8.683773 -29.376932)
			(xy 8.653806 -29.325026) (xy 8.63087 -29.269653) (xy 8.615357 -29.21176) (xy 8.607534 -29.152338)
			(xy 8.607044 -29.12237) (xy 4.147142 -29.12237) (xy 4.148688 -29.124095) (xy 4.179461 -29.170608)
			(xy 4.203133 -29.221105) (xy 4.219201 -29.274512) (xy 4.227321 -29.329688) (xy 4.22783 -29.357574)
			(xy 4.227321 -29.38546) (xy 4.219201 -29.440636) (xy 4.203133 -29.494043) (xy 4.179461 -29.54454)
			(xy 4.148688 -29.591053) (xy 4.111471 -29.63259) (xy 4.068603 -29.668265) (xy 4.020997 -29.697319)
			(xy 3.969668 -29.719131) (xy 3.915711 -29.733237) (xy 3.860274 -29.739337) (xy 3.80454 -29.7373)
			(xy 3.749697 -29.72717) (xy 3.696913 -29.709163) (xy 3.647313 -29.683662) (xy 3.601955 -29.651211)
			(xy 3.561806 -29.612502) (xy 3.52772 -29.568359) (xy 3.500424 -29.519724) (xy 3.480501 -29.467633)
			(xy 3.468375 -29.413196) (xy 3.464304 -29.357574) (xy 2.954281 -29.357574) (xy 2.954273 -29.358028)
			(xy 2.946153 -29.413204) (xy 2.930085 -29.466611) (xy 2.906413 -29.517108) (xy 2.87564 -29.563621)
			(xy 2.838423 -29.605158) (xy 2.795555 -29.640833) (xy 2.747949 -29.669887) (xy 2.69662 -29.691699)
			(xy 2.642663 -29.705805) (xy 2.587226 -29.711905) (xy 2.531492 -29.709868) (xy 2.476649 -29.699738)
			(xy 2.423865 -29.681731) (xy 2.374265 -29.65623) (xy 2.328907 -29.623779) (xy 2.288758 -29.58507)
			(xy 2.254672 -29.540927) (xy 2.227376 -29.492292) (xy 2.207453 -29.440201) (xy 2.195327 -29.385764)
			(xy 2.191256 -29.330142) (xy 1.306576 -29.330142) (xy 1.306576 -30.922468) (xy 6.752844 -30.922468)
			(xy 6.752844 -30.058868) (xy 6.753334 -30.0289) (xy 6.761157 -29.969478) (xy 6.77667 -29.911585)
			(xy 6.799606 -29.856212) (xy 6.829573 -29.804306) (xy 6.86606 -29.756756) (xy 6.90844 -29.714376)
			(xy 6.95599 -29.677889) (xy 7.007896 -29.647922) (xy 7.063269 -29.624986) (xy 7.121162 -29.609473)
			(xy 7.180584 -29.60165) (xy 7.24052 -29.60165) (xy 7.299942 -29.609473) (xy 7.357835 -29.624986)
			(xy 7.413208 -29.647922) (xy 7.465114 -29.677889) (xy 7.512664 -29.714376) (xy 7.555044 -29.756756)
			(xy 7.591531 -29.804306) (xy 7.621498 -29.856212) (xy 7.644434 -29.911585) (xy 7.659947 -29.969478)
			(xy 7.66777 -30.0289) (xy 7.66826 -30.058868) (xy 7.66826 -30.922468) (xy 7.66777 -30.952436) (xy 7.659947 -31.011858)
			(xy 7.644434 -31.069751) (xy 7.621498 -31.125124) (xy 7.591531 -31.17703) (xy 7.555044 -31.22458)
			(xy 7.512664 -31.26696) (xy 7.465114 -31.303447) (xy 7.413208 -31.333414) (xy 7.357835 -31.35635)
			(xy 7.299942 -31.371863) (xy 7.24052 -31.379686) (xy 7.180584 -31.379686) (xy 7.121162 -31.371863)
			(xy 7.063269 -31.35635) (xy 7.007896 -31.333414) (xy 6.95599 -31.303447) (xy 6.90844 -31.26696) (xy 6.86606 -31.22458)
			(xy 6.829573 -31.17703) (xy 6.799606 -31.125124) (xy 6.77667 -31.069751) (xy 6.761157 -31.011858)
			(xy 6.753334 -30.952436) (xy 6.752844 -30.922468) (xy 1.306576 -30.922468) (xy 1.306576 -32.722312)
			(xy 8.607044 -32.722312) (xy 8.607044 -31.858712) (xy 8.607534 -31.828744) (xy 8.615357 -31.769322)
			(xy 8.63087 -31.711429) (xy 8.653806 -31.656056) (xy 8.683773 -31.60415) (xy 8.72026 -31.5566) (xy 8.76264 -31.51422)
			(xy 8.81019 -31.477733) (xy 8.862096 -31.447766) (xy 8.917469 -31.42483) (xy 8.975362 -31.409317)
			(xy 9.034784 -31.401494) (xy 9.09472 -31.401494) (xy 9.154142 -31.409317) (xy 9.212035 -31.42483)
			(xy 9.267408 -31.447766) (xy 9.319314 -31.477733) (xy 9.366864 -31.51422) (xy 9.409244 -31.5566)
			(xy 9.445731 -31.60415) (xy 9.475698 -31.656056) (xy 9.498634 -31.711429) (xy 9.514147 -31.769322)
			(xy 9.52197 -31.828744) (xy 9.52246 -31.858712) (xy 9.52246 -32.722312) (xy 9.52197 -32.75228) (xy 9.514147 -32.811702)
			(xy 9.498634 -32.869595) (xy 9.475698 -32.924968) (xy 9.445731 -32.976874) (xy 9.409244 -33.024424)
			(xy 9.366864 -33.066804) (xy 9.319314 -33.103291) (xy 9.267408 -33.133258) (xy 9.212035 -33.156194)
			(xy 9.154142 -33.171707) (xy 9.09472 -33.17953) (xy 9.034784 -33.17953) (xy 8.975362 -33.171707)
			(xy 8.917469 -33.156194) (xy 8.862096 -33.133258) (xy 8.81019 -33.103291) (xy 8.76264 -33.066804)
			(xy 8.72026 -33.024424) (xy 8.683773 -32.976874) (xy 8.653806 -32.924968) (xy 8.63087 -32.869595)
			(xy 8.615357 -32.811702) (xy 8.607534 -32.75228) (xy 8.607044 -32.722312) (xy 1.306576 -32.722312)
			(xy 1.306576 -33.710626) (xy 2.52425 -33.710626) (xy 2.528321 -33.655004) (xy 2.540447 -33.600567)
			(xy 2.56037 -33.548476) (xy 2.587666 -33.499841) (xy 2.621752 -33.455698) (xy 2.661901 -33.416989)
			(xy 2.707259 -33.384538) (xy 2.756859 -33.359037) (xy 2.809643 -33.34103) (xy 2.864486 -33.3309)
			(xy 2.92022 -33.328863) (xy 2.975657 -33.334963) (xy 3.029614 -33.349069) (xy 3.080943 -33.370881)
			(xy 3.128549 -33.399935) (xy 3.171417 -33.43561) (xy 3.208634 -33.477147) (xy 3.239407 -33.52366)
			(xy 3.263079 -33.574157) (xy 3.279147 -33.627564) (xy 3.287267 -33.68274) (xy 3.287776 -33.710626)
			(xy 3.287267 -33.738512) (xy 3.279596 -33.790636) (xy 3.426966 -33.790636) (xy 3.431037 -33.735014)
			(xy 3.443163 -33.680577) (xy 3.463086 -33.628486) (xy 3.490382 -33.579851) (xy 3.524468 -33.535708)
			(xy 3.564617 -33.496999) (xy 3.609975 -33.464548) (xy 3.659575 -33.439047) (xy 3.712359 -33.42104)
			(xy 3.767202 -33.41091) (xy 3.822936 -33.408873) (xy 3.878373 -33.414973) (xy 3.93233 -33.429079)
			(xy 3.983659 -33.450891) (xy 4.031265 -33.479945) (xy 4.074133 -33.51562) (xy 4.11135 -33.557157)
			(xy 4.142123 -33.60367) (xy 4.165795 -33.654167) (xy 4.181863 -33.707574) (xy 4.189983 -33.76275)
			(xy 4.190334 -33.782) (xy 4.661152 -33.782) (xy 4.665223 -33.726378) (xy 4.677349 -33.671941) (xy 4.697272 -33.61985)
			(xy 4.724568 -33.571215) (xy 4.758654 -33.527072) (xy 4.798803 -33.488363) (xy 4.844161 -33.455912)
			(xy 4.893761 -33.430411) (xy 4.946545 -33.412404) (xy 5.001388 -33.402274) (xy 5.057122 -33.400237)
			(xy 5.112559 -33.406337) (xy 5.166516 -33.420443) (xy 5.217845 -33.442255) (xy 5.265451 -33.471309)
			(xy 5.308319 -33.506984) (xy 5.345536 -33.548521) (xy 5.376309 -33.595034) (xy 5.399981 -33.645531)
			(xy 5.416049 -33.698938) (xy 5.424169 -33.754114) (xy 5.424678 -33.782) (xy 5.424169 -33.809886)
			(xy 5.416049 -33.865062) (xy 5.399981 -33.918469) (xy 5.376309 -33.968966) (xy 5.345536 -34.015479)
			(xy 5.308319 -34.057016) (xy 5.265451 -34.092691) (xy 5.217845 -34.121745) (xy 5.166516 -34.143557)
			(xy 5.112559 -34.157663) (xy 5.057122 -34.163763) (xy 5.001388 -34.161726) (xy 4.946545 -34.151596)
			(xy 4.893761 -34.133589) (xy 4.844161 -34.108088) (xy 4.798803 -34.075637) (xy 4.758654 -34.036928)
			(xy 4.724568 -33.992785) (xy 4.697272 -33.94415) (xy 4.677349 -33.892059) (xy 4.665223 -33.837622)
			(xy 4.661152 -33.782) (xy 4.190334 -33.782) (xy 4.190492 -33.790636) (xy 4.189983 -33.818522) (xy 4.181863 -33.873698)
			(xy 4.165795 -33.927105) (xy 4.142123 -33.977602) (xy 4.11135 -34.024115) (xy 4.074133 -34.065652)
			(xy 4.031265 -34.101327) (xy 3.983659 -34.130381) (xy 3.93233 -34.152193) (xy 3.878373 -34.166299)
			(xy 3.822936 -34.172399) (xy 3.767202 -34.170362) (xy 3.712359 -34.160232) (xy 3.659575 -34.142225)
			(xy 3.609975 -34.116724) (xy 3.564617 -34.084273) (xy 3.524468 -34.045564) (xy 3.490382 -34.001421)
			(xy 3.463086 -33.952786) (xy 3.443163 -33.900695) (xy 3.431037 -33.846258) (xy 3.426966 -33.790636)
			(xy 3.279596 -33.790636) (xy 3.279147 -33.793688) (xy 3.263079 -33.847095) (xy 3.239407 -33.897592)
			(xy 3.208634 -33.944105) (xy 3.171417 -33.985642) (xy 3.128549 -34.021317) (xy 3.080943 -34.050371)
			(xy 3.029614 -34.072183) (xy 2.975657 -34.086289) (xy 2.92022 -34.092389) (xy 2.864486 -34.090352)
			(xy 2.809643 -34.080222) (xy 2.756859 -34.062215) (xy 2.707259 -34.036714) (xy 2.661901 -34.004263)
			(xy 2.621752 -33.965554) (xy 2.587666 -33.921411) (xy 2.56037 -33.872776) (xy 2.540447 -33.820685)
			(xy 2.528321 -33.766248) (xy 2.52425 -33.710626) (xy 1.306576 -33.710626) (xy 1.306576 -34.490406)
			(xy 1.92481 -34.490406) (xy 1.928881 -34.434784) (xy 1.941007 -34.380347) (xy 1.96093 -34.328256)
			(xy 1.988226 -34.279621) (xy 2.022312 -34.235478) (xy 2.062461 -34.196769) (xy 2.107819 -34.164318)
			(xy 2.157419 -34.138817) (xy 2.210203 -34.12081) (xy 2.265046 -34.11068) (xy 2.32078 -34.108643)
			(xy 2.376217 -34.114743) (xy 2.430174 -34.128849) (xy 2.481503 -34.150661) (xy 2.529109 -34.179715)
			(xy 2.571977 -34.21539) (xy 2.609194 -34.256927) (xy 2.639967 -34.30344) (xy 2.663639 -34.353937)
			(xy 2.679707 -34.407344) (xy 2.687827 -34.46252) (xy 2.688336 -34.490406) (xy 2.687827 -34.518292)
			(xy 2.687221 -34.52241) (xy 6.752844 -34.52241) (xy 6.752844 -33.65881) (xy 6.753334 -33.628842)
			(xy 6.761157 -33.56942) (xy 6.77667 -33.511527) (xy 6.799606 -33.456154) (xy 6.829573 -33.404248)
			(xy 6.86606 -33.356698) (xy 6.90844 -33.314318) (xy 6.95599 -33.277831) (xy 7.007896 -33.247864)
			(xy 7.063269 -33.224928) (xy 7.121162 -33.209415) (xy 7.180584 -33.201592) (xy 7.24052 -33.201592)
			(xy 7.299942 -33.209415) (xy 7.357835 -33.224928) (xy 7.413208 -33.247864) (xy 7.465114 -33.277831)
			(xy 7.512664 -33.314318) (xy 7.555044 -33.356698) (xy 7.591531 -33.404248) (xy 7.621498 -33.456154)
			(xy 7.644434 -33.511527) (xy 7.659947 -33.56942) (xy 7.66777 -33.628842) (xy 7.66826 -33.65881) (xy 7.66826 -34.52241)
			(xy 7.66777 -34.552378) (xy 7.659947 -34.6118) (xy 7.644434 -34.669693) (xy 7.621498 -34.725066)
			(xy 7.591531 -34.776972) (xy 7.555044 -34.824522) (xy 7.512664 -34.866902) (xy 7.465114 -34.903389)
			(xy 7.413208 -34.933356) (xy 7.357835 -34.956292) (xy 7.299942 -34.971805) (xy 7.24052 -34.979628)
			(xy 7.180584 -34.979628) (xy 7.121162 -34.971805) (xy 7.063269 -34.956292) (xy 7.007896 -34.933356)
			(xy 6.95599 -34.903389) (xy 6.90844 -34.866902) (xy 6.86606 -34.824522) (xy 6.829573 -34.776972)
			(xy 6.799606 -34.725066) (xy 6.77667 -34.669693) (xy 6.761157 -34.6118) (xy 6.753334 -34.552378)
			(xy 6.752844 -34.52241) (xy 2.687221 -34.52241) (xy 2.679707 -34.573468) (xy 2.663639 -34.626875)
			(xy 2.639967 -34.677372) (xy 2.609194 -34.723885) (xy 2.571977 -34.765422) (xy 2.529109 -34.801097)
			(xy 2.481503 -34.830151) (xy 2.430174 -34.851963) (xy 2.376217 -34.866069) (xy 2.32078 -34.872169)
			(xy 2.265046 -34.870132) (xy 2.210203 -34.860002) (xy 2.157419 -34.841995) (xy 2.107819 -34.816494)
			(xy 2.062461 -34.784043) (xy 2.022312 -34.745334) (xy 1.988226 -34.701191) (xy 1.96093 -34.652556)
			(xy 1.941007 -34.600465) (xy 1.928881 -34.546028) (xy 1.92481 -34.490406) (xy 1.306576 -34.490406)
			(xy 1.306576 -35.91941) (xy 2.665728 -35.91941) (xy 2.669799 -35.863788) (xy 2.681925 -35.809351)
			(xy 2.701848 -35.75726) (xy 2.729144 -35.708625) (xy 2.76323 -35.664482) (xy 2.803379 -35.625773)
			(xy 2.848737 -35.593322) (xy 2.898337 -35.567821) (xy 2.951121 -35.549814) (xy 3.005964 -35.539684)
			(xy 3.061698 -35.537647) (xy 3.117135 -35.543747) (xy 3.171092 -35.557853) (xy 3.222421 -35.579665)
			(xy 3.270027 -35.608719) (xy 3.312895 -35.644394) (xy 3.350112 -35.685931) (xy 3.380885 -35.732444)
			(xy 3.404557 -35.782941) (xy 3.420625 -35.836348) (xy 3.427317 -35.881818) (xy 3.668774 -35.881818)
			(xy 3.672845 -35.826196) (xy 3.684971 -35.771759) (xy 3.704894 -35.719668) (xy 3.73219 -35.671033)
			(xy 3.766276 -35.62689) (xy 3.806425 -35.588181) (xy 3.851783 -35.55573) (xy 3.901383 -35.530229)
			(xy 3.954167 -35.512222) (xy 4.00901 -35.502092) (xy 4.064744 -35.500055) (xy 4.120181 -35.506155)
			(xy 4.174138 -35.520261) (xy 4.225467 -35.542073) (xy 4.273073 -35.571127) (xy 4.315941 -35.606802)
			(xy 4.353158 -35.648339) (xy 4.383931 -35.694852) (xy 4.407603 -35.745349) (xy 4.423671 -35.798756)
			(xy 4.431791 -35.853932) (xy 4.4323 -35.881818) (xy 4.43186 -35.905948) (xy 4.661152 -35.905948)
			(xy 4.665223 -35.850326) (xy 4.677349 -35.795889) (xy 4.697272 -35.743798) (xy 4.724568 -35.695163)
			(xy 4.758654 -35.65102) (xy 4.798803 -35.612311) (xy 4.844161 -35.57986) (xy 4.893761 -35.554359)
			(xy 4.946545 -35.536352) (xy 5.001388 -35.526222) (xy 5.057122 -35.524185) (xy 5.112559 -35.530285)
			(xy 5.166516 -35.544391) (xy 5.217845 -35.566203) (xy 5.265451 -35.595257) (xy 5.308319 -35.630932)
			(xy 5.345536 -35.672469) (xy 5.376309 -35.718982) (xy 5.399981 -35.769479) (xy 5.416049 -35.822886)
			(xy 5.424169 -35.878062) (xy 5.424678 -35.905948) (xy 5.424169 -35.933834) (xy 5.416049 -35.98901)
			(xy 5.399981 -36.042417) (xy 5.376309 -36.092914) (xy 5.345536 -36.139427) (xy 5.308319 -36.180964)
			(xy 5.265451 -36.216639) (xy 5.217845 -36.245693) (xy 5.166516 -36.267505) (xy 5.112559 -36.281611)
			(xy 5.057122 -36.287711) (xy 5.001388 -36.285674) (xy 4.946545 -36.275544) (xy 4.893761 -36.257537)
			(xy 4.844161 -36.232036) (xy 4.798803 -36.199585) (xy 4.758654 -36.160876) (xy 4.724568 -36.116733)
			(xy 4.697272 -36.068098) (xy 4.677349 -36.016007) (xy 4.665223 -35.96157) (xy 4.661152 -35.905948)
			(xy 4.43186 -35.905948) (xy 4.431791 -35.909704) (xy 4.423671 -35.96488) (xy 4.407603 -36.018287)
			(xy 4.383931 -36.068784) (xy 4.353158 -36.115297) (xy 4.315941 -36.156834) (xy 4.273073 -36.192509)
			(xy 4.225467 -36.221563) (xy 4.174138 -36.243375) (xy 4.120181 -36.257481) (xy 4.064744 -36.263581)
			(xy 4.00901 -36.261544) (xy 3.954167 -36.251414) (xy 3.901383 -36.233407) (xy 3.851783 -36.207906)
			(xy 3.806425 -36.175455) (xy 3.766276 -36.136746) (xy 3.73219 -36.092603) (xy 3.704894 -36.043968)
			(xy 3.684971 -35.991877) (xy 3.672845 -35.93744) (xy 3.668774 -35.881818) (xy 3.427317 -35.881818)
			(xy 3.428745 -35.891524) (xy 3.429254 -35.91941) (xy 3.428745 -35.947296) (xy 3.420625 -36.002472)
			(xy 3.404557 -36.055879) (xy 3.380885 -36.106376) (xy 3.350112 -36.152889) (xy 3.312895 -36.194426)
			(xy 3.270027 -36.230101) (xy 3.222421 -36.259155) (xy 3.171092 -36.280967) (xy 3.117135 -36.295073)
			(xy 3.061698 -36.301173) (xy 3.005964 -36.299136) (xy 2.951121 -36.289006) (xy 2.898337 -36.270999)
			(xy 2.848737 -36.245498) (xy 2.803379 -36.213047) (xy 2.76323 -36.174338) (xy 2.729144 -36.130195)
			(xy 2.701848 -36.08156) (xy 2.681925 -36.029469) (xy 2.669799 -35.975032) (xy 2.665728 -35.91941)
			(xy 1.306576 -35.91941) (xy 1.306576 -36.60013) (xy 11.998205 -36.60013) (xy 12.00221 -36.512222)
			(xy 12.014193 -36.425042) (xy 12.034053 -36.339313) (xy 12.061628 -36.255745) (xy 12.096687 -36.175031)
			(xy 12.13894 -36.097839) (xy 12.188038 -36.02481) (xy 12.243574 -35.956548) (xy 12.305086 -35.893618)
			(xy 12.372067 -35.836544) (xy 12.44396 -35.785796) (xy 12.520169 -35.741796) (xy 12.600064 -35.704909)
			(xy 12.682983 -35.67544) (xy 12.768238 -35.653633) (xy 12.855122 -35.639669) (xy 12.942916 -35.633663)
			(xy 13.030893 -35.635667) (xy 13.118323 -35.645662) (xy 13.204482 -35.663566) (xy 13.288656 -35.68923)
			(xy 13.370147 -35.722443) (xy 13.448281 -35.762929) (xy 13.522409 -35.810351) (xy 13.591917 -35.864318)
			(xy 13.605216 -35.876738) (xy 18.717258 -35.876738) (xy 18.721329 -35.821116) (xy 18.733455 -35.766679)
			(xy 18.753378 -35.714588) (xy 18.780674 -35.665953) (xy 18.81476 -35.62181) (xy 18.854909 -35.583101)
			(xy 18.900267 -35.55065) (xy 18.949867 -35.525149) (xy 19.002651 -35.507142) (xy 19.057494 -35.497012)
			(xy 19.113228 -35.494975) (xy 19.168665 -35.501075) (xy 19.222622 -35.515181) (xy 19.273951 -35.536993)
			(xy 19.321557 -35.566047) (xy 19.364425 -35.601722) (xy 19.401642 -35.643259) (xy 19.432415 -35.689772)
			(xy 19.456087 -35.740269) (xy 19.472155 -35.793676) (xy 19.480275 -35.848852) (xy 19.480784 -35.876738)
			(xy 19.480275 -35.904624) (xy 19.472155 -35.9598) (xy 19.456087 -36.013207) (xy 19.432415 -36.063704)
			(xy 19.401642 -36.110217) (xy 19.364425 -36.151754) (xy 19.321557 -36.187429) (xy 19.273951 -36.216483)
			(xy 19.222622 -36.238295) (xy 19.168665 -36.252401) (xy 19.113228 -36.258501) (xy 19.057494 -36.256464)
			(xy 19.002651 -36.246334) (xy 18.949867 -36.228327) (xy 18.900267 -36.202826) (xy 18.854909 -36.170375)
			(xy 18.81476 -36.131666) (xy 18.780674 -36.087523) (xy 18.753378 -36.038888) (xy 18.733455 -35.986797)
			(xy 18.721329 -35.93236) (xy 18.717258 -35.876738) (xy 13.605216 -35.876738) (xy 13.656231 -35.924383)
			(xy 13.714815 -35.990047) (xy 13.767186 -36.060766) (xy 13.812909 -36.135954) (xy 13.851606 -36.214989)
			(xy 13.882955 -36.297215) (xy 13.906697 -36.381951) (xy 13.922635 -36.468495) (xy 13.926421 -36.50996)
			(xy 20.613876 -36.50996) (xy 20.617947 -36.454338) (xy 20.630073 -36.399901) (xy 20.649996 -36.34781)
			(xy 20.677292 -36.299175) (xy 20.711378 -36.255032) (xy 20.751527 -36.216323) (xy 20.796885 -36.183872)
			(xy 20.846485 -36.158371) (xy 20.899269 -36.140364) (xy 20.954112 -36.130234) (xy 21.009846 -36.128197)
			(xy 21.065283 -36.134297) (xy 21.11924 -36.148403) (xy 21.170569 -36.170215) (xy 21.218175 -36.199269)
			(xy 21.261043 -36.234944) (xy 21.29826 -36.276481) (xy 21.329033 -36.322994) (xy 21.352705 -36.373491)
			(xy 21.368773 -36.426898) (xy 21.376893 -36.482074) (xy 21.377402 -36.50996) (xy 21.376893 -36.537846)
			(xy 21.368773 -36.593022) (xy 21.352705 -36.646429) (xy 21.329033 -36.696926) (xy 21.29826 -36.743439)
			(xy 21.261043 -36.784976) (xy 21.218175 -36.820651) (xy 21.170569 -36.849705) (xy 21.11924 -36.871517)
			(xy 21.065283 -36.885623) (xy 21.009846 -36.891723) (xy 20.954112 -36.889686) (xy 20.899269 -36.879556)
			(xy 20.846485 -36.861549) (xy 20.796885 -36.836048) (xy 20.751527 -36.803597) (xy 20.711378 -36.764888)
			(xy 20.677292 -36.720745) (xy 20.649996 -36.67211) (xy 20.630073 -36.620019) (xy 20.617947 -36.565582)
			(xy 20.613876 -36.50996) (xy 13.926421 -36.50996) (xy 13.930637 -36.55613) (xy 13.931138 -36.60013)
			(xy 13.930637 -36.64413) (xy 13.922635 -36.731765) (xy 13.906697 -36.818309) (xy 13.882955 -36.903045)
			(xy 13.851606 -36.985271) (xy 13.812909 -37.064306) (xy 13.767186 -37.139494) (xy 13.714815 -37.210213)
			(xy 13.656231 -37.275877) (xy 13.591917 -37.335942) (xy 13.522409 -37.389909) (xy 13.448281 -37.437331)
			(xy 13.375275 -37.47516) (xy 17.75917 -37.47516) (xy 17.763241 -37.419538) (xy 17.775367 -37.365101)
			(xy 17.79529 -37.31301) (xy 17.822586 -37.264375) (xy 17.856672 -37.220232) (xy 17.896821 -37.181523)
			(xy 17.942179 -37.149072) (xy 17.991779 -37.123571) (xy 18.044563 -37.105564) (xy 18.099406 -37.095434)
			(xy 18.15514 -37.093397) (xy 18.210577 -37.099497) (xy 18.264534 -37.113603) (xy 18.315863 -37.135415)
			(xy 18.363469 -37.164469) (xy 18.406337 -37.200144) (xy 18.443554 -37.241681) (xy 18.474327 -37.288194)
			(xy 18.497999 -37.338691) (xy 18.514067 -37.392098) (xy 18.522187 -37.447274) (xy 18.522696 -37.47516)
			(xy 18.522187 -37.503046) (xy 18.514067 -37.558222) (xy 18.497999 -37.611629) (xy 18.474327 -37.662126)
			(xy 18.474174 -37.662358) (xy 19.948396 -37.662358) (xy 19.952467 -37.606736) (xy 19.964593 -37.552299)
			(xy 19.984516 -37.500208) (xy 20.011812 -37.451573) (xy 20.045898 -37.40743) (xy 20.086047 -37.368721)
			(xy 20.131405 -37.33627) (xy 20.181005 -37.310769) (xy 20.233789 -37.292762) (xy 20.288632 -37.282632)
			(xy 20.344366 -37.280595) (xy 20.399803 -37.286695) (xy 20.45376 -37.300801) (xy 20.505089 -37.322613)
			(xy 20.552695 -37.351667) (xy 20.595563 -37.387342) (xy 20.63278 -37.428879) (xy 20.663553 -37.475392)
			(xy 20.687225 -37.525889) (xy 20.703293 -37.579296) (xy 20.711413 -37.634472) (xy 20.711922 -37.662358)
			(xy 20.711413 -37.690244) (xy 20.703293 -37.74542) (xy 20.687225 -37.798827) (xy 20.663553 -37.849324)
			(xy 20.63278 -37.895837) (xy 20.595563 -37.937374) (xy 20.552695 -37.973049) (xy 20.505089 -38.002103)
			(xy 20.45376 -38.023915) (xy 20.399803 -38.038021) (xy 20.344366 -38.044121) (xy 20.288632 -38.042084)
			(xy 20.233789 -38.031954) (xy 20.181005 -38.013947) (xy 20.131405 -37.988446) (xy 20.086047 -37.955995)
			(xy 20.045898 -37.917286) (xy 20.011812 -37.873143) (xy 19.984516 -37.824508) (xy 19.964593 -37.772417)
			(xy 19.952467 -37.71798) (xy 19.948396 -37.662358) (xy 18.474174 -37.662358) (xy 18.443554 -37.708639)
			(xy 18.406337 -37.750176) (xy 18.363469 -37.785851) (xy 18.315863 -37.814905) (xy 18.264534 -37.836717)
			(xy 18.210577 -37.850823) (xy 18.15514 -37.856923) (xy 18.099406 -37.854886) (xy 18.044563 -37.844756)
			(xy 17.991779 -37.826749) (xy 17.942179 -37.801248) (xy 17.896821 -37.768797) (xy 17.856672 -37.730088)
			(xy 17.822586 -37.685945) (xy 17.79529 -37.63731) (xy 17.775367 -37.585219) (xy 17.763241 -37.530782)
			(xy 17.75917 -37.47516) (xy 13.375275 -37.47516) (xy 13.370147 -37.477817) (xy 13.288656 -37.51103)
			(xy 13.204482 -37.536694) (xy 13.118323 -37.554598) (xy 13.030893 -37.564593) (xy 12.942916 -37.566597)
			(xy 12.855122 -37.560591) (xy 12.768238 -37.546627) (xy 12.682983 -37.52482) (xy 12.600064 -37.495351)
			(xy 12.520169 -37.458464) (xy 12.44396 -37.414464) (xy 12.372067 -37.363716) (xy 12.305086 -37.306642)
			(xy 12.243574 -37.243712) (xy 12.188038 -37.17545) (xy 12.13894 -37.102421) (xy 12.096687 -37.025229)
			(xy 12.061628 -36.944515) (xy 12.034053 -36.860947) (xy 12.014193 -36.775218) (xy 12.00221 -36.688038)
			(xy 11.998205 -36.60013) (xy 1.306576 -36.60013) (xy 1.306576 -38.928802) (xy 3.912868 -38.928802)
			(xy 3.916939 -38.87318) (xy 3.929065 -38.818743) (xy 3.948988 -38.766652) (xy 3.976284 -38.718017)
			(xy 4.01037 -38.673874) (xy 4.050519 -38.635165) (xy 4.095877 -38.602714) (xy 4.145477 -38.577213)
			(xy 4.198261 -38.559206) (xy 4.253104 -38.549076) (xy 4.308838 -38.547039) (xy 4.364275 -38.553139)
			(xy 4.418232 -38.567245) (xy 4.469561 -38.589057) (xy 4.517167 -38.618111) (xy 4.560035 -38.653786)
			(xy 4.597252 -38.695323) (xy 4.628025 -38.741836) (xy 4.651697 -38.792333) (xy 4.667765 -38.84574)
			(xy 4.675885 -38.900916) (xy 4.676394 -38.928802) (xy 5.182868 -38.928802) (xy 5.186939 -38.87318)
			(xy 5.199065 -38.818743) (xy 5.218988 -38.766652) (xy 5.246284 -38.718017) (xy 5.28037 -38.673874)
			(xy 5.320519 -38.635165) (xy 5.365877 -38.602714) (xy 5.415477 -38.577213) (xy 5.468261 -38.559206)
			(xy 5.523104 -38.549076) (xy 5.578838 -38.547039) (xy 5.634275 -38.553139) (xy 5.688232 -38.567245)
			(xy 5.739561 -38.589057) (xy 5.787167 -38.618111) (xy 5.830035 -38.653786) (xy 5.867252 -38.695323)
			(xy 5.898025 -38.741836) (xy 5.921697 -38.792333) (xy 5.937765 -38.84574) (xy 5.945885 -38.900916)
			(xy 5.946394 -38.928802) (xy 5.945885 -38.956688) (xy 5.937765 -39.011864) (xy 5.921697 -39.065271)
			(xy 5.898025 -39.115768) (xy 5.867252 -39.162281) (xy 5.830035 -39.203818) (xy 5.787167 -39.239493)
			(xy 5.739561 -39.268547) (xy 5.688232 -39.290359) (xy 5.634275 -39.304465) (xy 5.578838 -39.310565)
			(xy 5.523104 -39.308528) (xy 5.468261 -39.298398) (xy 5.415477 -39.280391) (xy 5.365877 -39.25489)
			(xy 5.320519 -39.222439) (xy 5.28037 -39.18373) (xy 5.246284 -39.139587) (xy 5.218988 -39.090952)
			(xy 5.199065 -39.038861) (xy 5.186939 -38.984424) (xy 5.182868 -38.928802) (xy 4.676394 -38.928802)
			(xy 4.675885 -38.956688) (xy 4.667765 -39.011864) (xy 4.651697 -39.065271) (xy 4.628025 -39.115768)
			(xy 4.597252 -39.162281) (xy 4.560035 -39.203818) (xy 4.517167 -39.239493) (xy 4.469561 -39.268547)
			(xy 4.418232 -39.290359) (xy 4.364275 -39.304465) (xy 4.308838 -39.310565) (xy 4.253104 -39.308528)
			(xy 4.198261 -39.298398) (xy 4.145477 -39.280391) (xy 4.095877 -39.25489) (xy 4.050519 -39.222439)
			(xy 4.01037 -39.18373) (xy 3.976284 -39.139587) (xy 3.948988 -39.090952) (xy 3.929065 -39.038861)
			(xy 3.916939 -38.984424) (xy 3.912868 -38.928802) (xy 1.306576 -38.928802) (xy 1.306576 -41.166542)
			(xy 2.403856 -41.166542) (xy 2.404383 -41.137625) (xy 2.413107 -41.080453) (xy 2.430362 -41.025254)
			(xy 2.455752 -40.973292) (xy 2.488695 -40.925758) (xy 2.528436 -40.883741) (xy 2.550922 -40.865552)
			(xy 2.559745 -40.85796) (xy 2.569919 -40.837048) (xy 2.57048 -40.82542) (xy 2.57048 -40.745664) (xy 2.569954 -40.73403)
			(xy 2.559757 -40.713121) (xy 2.550922 -40.705532) (xy 2.528438 -40.687342) (xy 2.488703 -40.645322)
			(xy 2.455764 -40.597787) (xy 2.430376 -40.545825) (xy 2.41312 -40.490628) (xy 2.404391 -40.433458)
			(xy 2.403856 -40.404542) (xy 2.404342 -40.377291) (xy 2.412098 -40.323343) (xy 2.427453 -40.271048)
			(xy 2.450095 -40.221471) (xy 2.479561 -40.175621) (xy 2.515252 -40.13443) (xy 2.556443 -40.098739)
			(xy 2.602293 -40.069273) (xy 2.65187 -40.046631) (xy 2.704165 -40.031276) (xy 2.758113 -40.02352)
			(xy 2.812615 -40.02352) (xy 2.866563 -40.031276) (xy 2.918858 -40.046631) (xy 2.968435 -40.069273)
			(xy 3.014285 -40.098739) (xy 3.055476 -40.13443) (xy 3.091167 -40.175621) (xy 3.120633 -40.221471)
			(xy 3.143275 -40.271048) (xy 3.15863 -40.323343) (xy 3.166386 -40.377291) (xy 3.166872 -40.404542)
			(xy 3.166323 -40.433458) (xy 3.157602 -40.490628) (xy 3.140351 -40.545827) (xy 3.114965 -40.597789)
			(xy 3.082026 -40.645324) (xy 3.04229 -40.687341) (xy 3.019806 -40.705532) (xy 3.010995 -40.713136)
			(xy 3.000813 -40.734039) (xy 3.000248 -40.745664) (xy 3.000248 -40.82542) (xy 3.000773 -40.837054)
			(xy 3.01097 -40.857964) (xy 3.019806 -40.865552) (xy 3.042287 -40.883746) (xy 3.082022 -40.925765)
			(xy 3.114961 -40.9733) (xy 3.14035 -41.02526) (xy 3.157607 -41.080457) (xy 3.166337 -41.137626) (xy 3.166872 -41.166542)
			(xy 5.443982 -41.166542) (xy 5.4445 -41.137625) (xy 5.453225 -41.080452) (xy 5.470481 -41.025252)
			(xy 5.495872 -40.97329) (xy 5.528818 -40.925756) (xy 5.568561 -40.883741) (xy 5.591048 -40.865552)
			(xy 5.599875 -40.857964) (xy 5.610046 -40.837048) (xy 5.610606 -40.82542) (xy 5.610606 -40.745664)
			(xy 5.610071 -40.734032) (xy 5.599879 -40.713122) (xy 5.591048 -40.705532) (xy 5.568569 -40.687336)
			(xy 5.528836 -40.645316) (xy 5.495898 -40.597781) (xy 5.470509 -40.545821) (xy 5.453251 -40.490625)
			(xy 5.444519 -40.433457) (xy 5.443982 -40.404542) (xy 5.444468 -40.377291) (xy 5.452224 -40.323343)
			(xy 5.467579 -40.271048) (xy 5.490221 -40.221471) (xy 5.519687 -40.175621) (xy 5.555378 -40.13443)
			(xy 5.596569 -40.098739) (xy 5.642419 -40.069273) (xy 5.691996 -40.046631) (xy 5.744291 -40.031276)
			(xy 5.798239 -40.02352) (xy 5.852741 -40.02352) (xy 5.906689 -40.031276) (xy 5.958984 -40.046631)
			(xy 6.008561 -40.069273) (xy 6.054411 -40.098739) (xy 6.095602 -40.13443) (xy 6.131293 -40.175621)
			(xy 6.160759 -40.221471) (xy 6.183401 -40.271048) (xy 6.198756 -40.323343) (xy 6.206512 -40.377291)
			(xy 6.206998 -40.404542) (xy 6.206439 -40.433457) (xy 6.197718 -40.490627) (xy 6.180469 -40.545825)
			(xy 6.155085 -40.597787) (xy 6.122148 -40.645322) (xy 6.082414 -40.687341) (xy 6.059932 -40.705532)
			(xy 6.051109 -40.713123) (xy 6.040937 -40.734036) (xy 6.040374 -40.745664) (xy 6.040374 -40.82542)
			(xy 6.04089 -40.837056) (xy 6.051092 -40.857967) (xy 6.059932 -40.865552) (xy 6.082412 -40.883747)
			(xy 6.122147 -40.925766) (xy 6.155087 -40.9733) (xy 6.180476 -41.025261) (xy 6.197733 -41.080457)
			(xy 6.206463 -41.137626) (xy 6.206998 -41.166542) (xy 6.206512 -41.193793) (xy 6.198756 -41.247741)
			(xy 6.192586 -41.268755) (xy 15.843927 -41.268755) (xy 15.843927 -41.214245) (xy 15.851685 -41.160289)
			(xy 15.867043 -41.107986) (xy 15.889688 -41.058401) (xy 15.919159 -41.012544) (xy 15.954857 -40.971348)
			(xy 15.996054 -40.935652) (xy 16.041912 -40.906182) (xy 16.091497 -40.883538) (xy 16.1438 -40.868182)
			(xy 16.197757 -40.860426) (xy 16.225012 -40.859964) (xy 16.253751 -40.86049) (xy 16.310578 -40.869114)
			(xy 16.365468 -40.886164) (xy 16.41718 -40.911254) (xy 16.464543 -40.943818) (xy 16.48587 -40.963088)
			(xy 16.492728 -40.969692) (xy 16.510762 -40.976804) (xy 16.599662 -40.976804) (xy 16.617696 -40.969692)
			(xy 16.624554 -40.963088) (xy 16.645883 -40.94382) (xy 16.693244 -40.911251) (xy 16.744955 -40.886157)
			(xy 16.799845 -40.869106) (xy 16.856673 -40.860484) (xy 16.885412 -40.859964) (xy 16.912661 -40.860507)
			(xy 16.966603 -40.868264) (xy 17.018892 -40.883619) (xy 17.068464 -40.90626) (xy 17.11431 -40.935724)
			(xy 17.155496 -40.971413) (xy 17.191183 -41.0126) (xy 17.220646 -41.058446) (xy 17.243285 -41.108019)
			(xy 17.258638 -41.160309) (xy 17.266394 -41.214251) (xy 17.266394 -41.268749) (xy 17.258638 -41.322691)
			(xy 17.243285 -41.374981) (xy 17.220646 -41.424554) (xy 17.191183 -41.4704) (xy 17.155496 -41.511587)
			(xy 17.11431 -41.547276) (xy 17.068464 -41.57674) (xy 17.018892 -41.599381) (xy 16.966603 -41.614736)
			(xy 16.912661 -41.622493) (xy 16.885412 -41.62298) (xy 16.856674 -41.622428) (xy 16.799849 -41.613809)
			(xy 16.74496 -41.596764) (xy 16.693248 -41.57168) (xy 16.645883 -41.539123) (xy 16.624554 -41.519856)
			(xy 16.617696 -41.513252) (xy 16.599662 -41.50614) (xy 16.510762 -41.50614) (xy 16.492728 -41.513252)
			(xy 16.48587 -41.519856) (xy 16.464537 -41.53912) (xy 16.417177 -41.571687) (xy 16.365467 -41.596781)
			(xy 16.310577 -41.613834) (xy 16.253751 -41.622458) (xy 16.225012 -41.62298) (xy 16.197757 -41.622574)
			(xy 16.1438 -41.614818) (xy 16.091497 -41.599462) (xy 16.041912 -41.576818) (xy 15.996054 -41.547348)
			(xy 15.954857 -41.511652) (xy 15.919159 -41.470456) (xy 15.889688 -41.424599) (xy 15.867043 -41.375014)
			(xy 15.851685 -41.322711) (xy 15.843927 -41.268755) (xy 6.192586 -41.268755) (xy 6.183401 -41.300036)
			(xy 6.160759 -41.349613) (xy 6.131293 -41.395463) (xy 6.095602 -41.436654) (xy 6.054411 -41.472345)
			(xy 6.008561 -41.501811) (xy 5.958984 -41.524453) (xy 5.906689 -41.539808) (xy 5.852741 -41.547564)
			(xy 5.798239 -41.547564) (xy 5.744291 -41.539808) (xy 5.691996 -41.524453) (xy 5.642419 -41.501811)
			(xy 5.596569 -41.472345) (xy 5.555378 -41.436654) (xy 5.519687 -41.395463) (xy 5.490221 -41.349613)
			(xy 5.467579 -41.300036) (xy 5.452224 -41.247741) (xy 5.444468 -41.193793) (xy 5.443982 -41.166542)
			(xy 3.166872 -41.166542) (xy 3.166386 -41.193793) (xy 3.15863 -41.247741) (xy 3.143275 -41.300036)
			(xy 3.120633 -41.349613) (xy 3.091167 -41.395463) (xy 3.055476 -41.436654) (xy 3.014285 -41.472345)
			(xy 2.968435 -41.501811) (xy 2.918858 -41.524453) (xy 2.866563 -41.539808) (xy 2.812615 -41.547564)
			(xy 2.758113 -41.547564) (xy 2.704165 -41.539808) (xy 2.65187 -41.524453) (xy 2.602293 -41.501811)
			(xy 2.556443 -41.472345) (xy 2.515252 -41.436654) (xy 2.479561 -41.395463) (xy 2.450095 -41.349613)
			(xy 2.427453 -41.300036) (xy 2.412098 -41.247741) (xy 2.404342 -41.193793) (xy 2.403856 -41.166542)
			(xy 1.306576 -41.166542) (xy 1.306576 -42.250614) (xy 2.72872 -42.250614) (xy 2.732791 -42.194992)
			(xy 2.744917 -42.140555) (xy 2.76484 -42.088464) (xy 2.792136 -42.039829) (xy 2.826222 -41.995686)
			(xy 2.866371 -41.956977) (xy 2.911729 -41.924526) (xy 2.961329 -41.899025) (xy 3.014113 -41.881018)
			(xy 3.068956 -41.870888) (xy 3.12469 -41.868851) (xy 3.180127 -41.874951) (xy 3.234084 -41.889057)
			(xy 3.285413 -41.910869) (xy 3.333019 -41.939923) (xy 3.375887 -41.975598) (xy 3.413104 -42.017135)
			(xy 3.443877 -42.063648) (xy 3.467549 -42.114145) (xy 3.483617 -42.167552) (xy 3.491737 -42.222728)
			(xy 3.492246 -42.250614) (xy 3.491737 -42.2785) (xy 3.483617 -42.333676) (xy 3.467549 -42.387083)
			(xy 3.460557 -42.401998) (xy 4.015484 -42.401998) (xy 4.019555 -42.346376) (xy 4.031681 -42.291939)
			(xy 4.051604 -42.239848) (xy 4.0789 -42.191213) (xy 4.112986 -42.14707) (xy 4.153135 -42.108361)
			(xy 4.198493 -42.07591) (xy 4.248093 -42.050409) (xy 4.300877 -42.032402) (xy 4.35572 -42.022272)
			(xy 4.411454 -42.020235) (xy 4.466891 -42.026335) (xy 4.520848 -42.040441) (xy 4.572177 -42.062253)
			(xy 4.619783 -42.091307) (xy 4.662651 -42.126982) (xy 4.699868 -42.168519) (xy 4.730641 -42.215032)
			(xy 4.754313 -42.265529) (xy 4.770381 -42.318936) (xy 4.774531 -42.347134) (xy 5.291072 -42.347134)
			(xy 5.295143 -42.291512) (xy 5.307269 -42.237075) (xy 5.327192 -42.184984) (xy 5.354488 -42.136349)
			(xy 5.388574 -42.092206) (xy 5.428723 -42.053497) (xy 5.474081 -42.021046) (xy 5.523681 -41.995545)
			(xy 5.576465 -41.977538) (xy 5.631308 -41.967408) (xy 5.687042 -41.965371) (xy 5.742479 -41.971471)
			(xy 5.796436 -41.985577) (xy 5.847765 -42.007389) (xy 5.895371 -42.036443) (xy 5.938239 -42.072118)
			(xy 5.975456 -42.113655) (xy 6.006229 -42.160168) (xy 6.029901 -42.210665) (xy 6.045969 -42.264072)
			(xy 6.054089 -42.319248) (xy 6.054598 -42.347134) (xy 6.054089 -42.37502) (xy 6.045969 -42.430196)
			(xy 6.029901 -42.483603) (xy 6.006229 -42.5341) (xy 5.975456 -42.580613) (xy 5.938239 -42.62215)
			(xy 5.895371 -42.657825) (xy 5.847765 -42.686879) (xy 5.796436 -42.708691) (xy 5.742479 -42.722797)
			(xy 5.687042 -42.728897) (xy 5.631308 -42.72686) (xy 5.576465 -42.71673) (xy 5.523681 -42.698723)
			(xy 5.474081 -42.673222) (xy 5.428723 -42.640771) (xy 5.388574 -42.602062) (xy 5.354488 -42.557919)
			(xy 5.327192 -42.509284) (xy 5.307269 -42.457193) (xy 5.295143 -42.402756) (xy 5.291072 -42.347134)
			(xy 4.774531 -42.347134) (xy 4.778501 -42.374112) (xy 4.77901 -42.401998) (xy 4.778501 -42.429884)
			(xy 4.770381 -42.48506) (xy 4.754313 -42.538467) (xy 4.730641 -42.588964) (xy 4.699868 -42.635477)
			(xy 4.662651 -42.677014) (xy 4.619783 -42.712689) (xy 4.572177 -42.741743) (xy 4.520848 -42.763555)
			(xy 4.466891 -42.777661) (xy 4.411454 -42.783761) (xy 4.35572 -42.781724) (xy 4.300877 -42.771594)
			(xy 4.248093 -42.753587) (xy 4.198493 -42.728086) (xy 4.153135 -42.695635) (xy 4.112986 -42.656926)
			(xy 4.0789 -42.612783) (xy 4.051604 -42.564148) (xy 4.031681 -42.512057) (xy 4.019555 -42.45762)
			(xy 4.015484 -42.401998) (xy 3.460557 -42.401998) (xy 3.443877 -42.43758) (xy 3.413104 -42.484093)
			(xy 3.375887 -42.52563) (xy 3.333019 -42.561305) (xy 3.285413 -42.590359) (xy 3.234084 -42.612171)
			(xy 3.180127 -42.626277) (xy 3.12469 -42.632377) (xy 3.068956 -42.63034) (xy 3.014113 -42.62021)
			(xy 2.961329 -42.602203) (xy 2.911729 -42.576702) (xy 2.866371 -42.544251) (xy 2.826222 -42.505542)
			(xy 2.792136 -42.461399) (xy 2.76484 -42.412764) (xy 2.744917 -42.360673) (xy 2.732791 -42.306236)
			(xy 2.72872 -42.250614) (xy 1.306576 -42.250614) (xy 1.306576 -43.305222) (xy 18.307304 -43.305222)
			(xy 18.307782 -43.277852) (xy 18.315597 -43.223674) (xy 18.331083 -43.171171) (xy 18.353922 -43.121424)
			(xy 18.383644 -43.075456) (xy 18.401284 -43.054524) (xy 18.401538 -43.05427) (xy 18.407106 -43.047171)
			(xy 18.413363 -43.030264) (xy 18.41373 -43.02125) (xy 18.41373 -42.954194) (xy 18.413369 -42.945178)
			(xy 18.407123 -42.928261) (xy 18.401538 -42.921174) (xy 18.401284 -42.921174) (xy 18.401284 -42.92092)
			(xy 18.383638 -42.899993) (xy 18.353928 -42.854019) (xy 18.331094 -42.80427) (xy 18.315604 -42.751768)
			(xy 18.307777 -42.697591) (xy 18.307304 -42.670222) (xy 18.30784 -42.641484) (xy 18.316459 -42.584657)
			(xy 18.333507 -42.529766) (xy 18.358595 -42.478054) (xy 18.391158 -42.430691) (xy 18.410428 -42.409364)
			(xy 18.417032 -42.402506) (xy 18.424144 -42.384472) (xy 18.424144 -42.295572) (xy 18.417032 -42.277538)
			(xy 18.410428 -42.27068) (xy 18.391179 -42.249334) (xy 18.358613 -42.201975) (xy 18.333519 -42.150267)
			(xy 18.316468 -42.095379) (xy 18.307843 -42.038554) (xy 18.30784 -41.981078) (xy 18.31646 -41.924253)
			(xy 18.333508 -41.869363) (xy 18.358596 -41.817653) (xy 18.391159 -41.770291) (xy 18.410428 -41.748964)
			(xy 18.417032 -41.742106) (xy 18.424144 -41.724072) (xy 18.424144 -41.635172) (xy 18.417032 -41.617138)
			(xy 18.410428 -41.61028) (xy 18.391166 -41.588945) (xy 18.358599 -41.541585) (xy 18.333505 -41.489876)
			(xy 18.316452 -41.434987) (xy 18.307827 -41.37816) (xy 18.307304 -41.349422) (xy 18.30779 -41.322171)
			(xy 18.315546 -41.268223) (xy 18.330901 -41.215928) (xy 18.353543 -41.166351) (xy 18.383009 -41.120501)
			(xy 18.4187 -41.07931) (xy 18.459891 -41.043619) (xy 18.505741 -41.014153) (xy 18.555318 -40.991511)
			(xy 18.607613 -40.976156) (xy 18.661561 -40.9684) (xy 18.716063 -40.9684) (xy 18.770011 -40.976156)
			(xy 18.822306 -40.991511) (xy 18.871883 -41.014153) (xy 18.917733 -41.043619) (xy 18.958924 -41.07931)
			(xy 18.994615 -41.120501) (xy 19.024081 -41.166351) (xy 19.046723 -41.215928) (xy 19.062078 -41.268223)
			(xy 19.069834 -41.322171) (xy 19.07032 -41.349422) (xy 19.069804 -41.378161) (xy 19.061179 -41.434989)
			(xy 19.044127 -41.489879) (xy 19.019033 -41.541591) (xy 18.986467 -41.588953) (xy 18.967196 -41.61028)
			(xy 18.960592 -41.617138) (xy 18.95348 -41.635172) (xy 18.95348 -41.724072) (xy 18.960592 -41.742106)
			(xy 18.967196 -41.748964) (xy 18.986488 -41.770272) (xy 19.019051 -41.817639) (xy 19.04414 -41.869353)
			(xy 19.061187 -41.924247) (xy 19.069807 -41.981076) (xy 19.069805 -42.038556) (xy 19.06118 -42.095385)
			(xy 19.044128 -42.150276) (xy 19.019034 -42.201989) (xy 18.986468 -42.249353) (xy 18.967196 -42.27068)
			(xy 18.960592 -42.277538) (xy 18.95348 -42.295572) (xy 18.95348 -42.384472) (xy 18.960592 -42.402506)
			(xy 18.967196 -42.409364) (xy 18.986466 -42.430692) (xy 19.019035 -42.478053) (xy 19.044128 -42.529764)
			(xy 19.061179 -42.584655) (xy 19.0698 -42.641483) (xy 19.07032 -42.670222) (xy 19.069886 -42.697594)
			(xy 19.062064 -42.751775) (xy 19.046568 -42.804279) (xy 19.02601 -42.849038) (xy 20.892006 -42.849038)
			(xy 20.896077 -42.793416) (xy 20.908203 -42.738979) (xy 20.928126 -42.686888) (xy 20.955422 -42.638253)
			(xy 20.989508 -42.59411) (xy 21.029657 -42.555401) (xy 21.075015 -42.52295) (xy 21.124615 -42.497449)
			(xy 21.177399 -42.479442) (xy 21.232242 -42.469312) (xy 21.287976 -42.467275) (xy 21.343413 -42.473375)
			(xy 21.39737 -42.487481) (xy 21.448699 -42.509293) (xy 21.496305 -42.538347) (xy 21.539173 -42.574022)
			(xy 21.57639 -42.615559) (xy 21.607163 -42.662072) (xy 21.630835 -42.712569) (xy 21.646903 -42.765976)
			(xy 21.655023 -42.821152) (xy 21.655532 -42.849038) (xy 21.655023 -42.876924) (xy 21.646903 -42.9321)
			(xy 21.630835 -42.985507) (xy 21.607163 -43.036004) (xy 21.57639 -43.082517) (xy 21.539173 -43.124054)
			(xy 21.496305 -43.159729) (xy 21.448699 -43.188783) (xy 21.39737 -43.210595) (xy 21.343413 -43.224701)
			(xy 21.287976 -43.230801) (xy 21.232242 -43.228764) (xy 21.177399 -43.218634) (xy 21.124615 -43.200627)
			(xy 21.075015 -43.175126) (xy 21.029657 -43.142675) (xy 20.989508 -43.103966) (xy 20.955422 -43.059823)
			(xy 20.928126 -43.011188) (xy 20.908203 -42.959097) (xy 20.896077 -42.90466) (xy 20.892006 -42.849038)
			(xy 19.02601 -42.849038) (xy 19.023719 -42.854026) (xy 18.993986 -42.89999) (xy 18.97634 -42.92092)
			(xy 18.976086 -42.921174) (xy 18.970503 -42.928263) (xy 18.964254 -42.945178) (xy 18.963894 -42.954194)
			(xy 18.963894 -43.02125) (xy 18.964277 -43.030264) (xy 18.970507 -43.047181) (xy 18.976086 -43.05427)
			(xy 18.97634 -43.05427) (xy 18.97634 -43.054524) (xy 18.993964 -43.075468) (xy 19.023676 -43.121438)
			(xy 19.046515 -43.171183) (xy 19.06201 -43.223681) (xy 19.069843 -43.277854) (xy 19.07032 -43.305222)
			(xy 19.069834 -43.332473) (xy 19.062078 -43.386421) (xy 19.046723 -43.438716) (xy 19.024081 -43.488293)
			(xy 18.994615 -43.534143) (xy 18.958924 -43.575334) (xy 18.917733 -43.611025) (xy 18.871883 -43.640491)
			(xy 18.822306 -43.663133) (xy 18.770011 -43.678488) (xy 18.716063 -43.686244) (xy 18.661561 -43.686244)
			(xy 18.607613 -43.678488) (xy 18.555318 -43.663133) (xy 18.505741 -43.640491) (xy 18.459891 -43.611025)
			(xy 18.4187 -43.575334) (xy 18.383009 -43.534143) (xy 18.353543 -43.488293) (xy 18.330901 -43.438716)
			(xy 18.315546 -43.386421) (xy 18.30779 -43.332473) (xy 18.307304 -43.305222) (xy 1.306576 -43.305222)
			(xy 1.306576 -43.73626) (xy 20.213064 -43.73626) (xy 20.217135 -43.680638) (xy 20.229261 -43.626201)
			(xy 20.249184 -43.57411) (xy 20.27648 -43.525475) (xy 20.310566 -43.481332) (xy 20.350715 -43.442623)
			(xy 20.396073 -43.410172) (xy 20.445673 -43.384671) (xy 20.498457 -43.366664) (xy 20.5533 -43.356534)
			(xy 20.609034 -43.354497) (xy 20.664471 -43.360597) (xy 20.718428 -43.374703) (xy 20.769757 -43.396515)
			(xy 20.817363 -43.425569) (xy 20.860231 -43.461244) (xy 20.897448 -43.502781) (xy 20.928221 -43.549294)
			(xy 20.951893 -43.599791) (xy 20.967961 -43.653198) (xy 20.976081 -43.708374) (xy 20.97659 -43.73626)
			(xy 20.976081 -43.764146) (xy 20.967961 -43.819322) (xy 20.956652 -43.85691) (xy 24.719786 -43.85691)
			(xy 24.723857 -43.801288) (xy 24.735983 -43.746851) (xy 24.755906 -43.69476) (xy 24.783202 -43.646125)
			(xy 24.817288 -43.601982) (xy 24.857437 -43.563273) (xy 24.902795 -43.530822) (xy 24.952395 -43.505321)
			(xy 25.005179 -43.487314) (xy 25.060022 -43.477184) (xy 25.115756 -43.475147) (xy 25.171193 -43.481247)
			(xy 25.22515 -43.495353) (xy 25.276479 -43.517165) (xy 25.324085 -43.546219) (xy 25.366953 -43.581894)
			(xy 25.40417 -43.623431) (xy 25.434943 -43.669944) (xy 25.458615 -43.720441) (xy 25.474683 -43.773848)
			(xy 25.482803 -43.829024) (xy 25.483312 -43.85691) (xy 25.482803 -43.884796) (xy 25.474683 -43.939972)
			(xy 25.458615 -43.993379) (xy 25.434943 -44.043876) (xy 25.40417 -44.090389) (xy 25.366953 -44.131926)
			(xy 25.324085 -44.167601) (xy 25.276479 -44.196655) (xy 25.22515 -44.218467) (xy 25.171193 -44.232573)
			(xy 25.115756 -44.238673) (xy 25.060022 -44.236636) (xy 25.005179 -44.226506) (xy 24.952395 -44.208499)
			(xy 24.902795 -44.182998) (xy 24.857437 -44.150547) (xy 24.817288 -44.111838) (xy 24.783202 -44.067695)
			(xy 24.755906 -44.01906) (xy 24.735983 -43.966969) (xy 24.723857 -43.912532) (xy 24.719786 -43.85691)
			(xy 20.956652 -43.85691) (xy 20.951893 -43.872729) (xy 20.928221 -43.923226) (xy 20.897448 -43.969739)
			(xy 20.860231 -44.011276) (xy 20.817363 -44.046951) (xy 20.769757 -44.076005) (xy 20.718428 -44.097817)
			(xy 20.664471 -44.111923) (xy 20.609034 -44.118023) (xy 20.5533 -44.115986) (xy 20.498457 -44.105856)
			(xy 20.445673 -44.087849) (xy 20.396073 -44.062348) (xy 20.350715 -44.029897) (xy 20.310566 -43.991188)
			(xy 20.27648 -43.947045) (xy 20.249184 -43.89841) (xy 20.229261 -43.846319) (xy 20.217135 -43.791882)
			(xy 20.213064 -43.73626) (xy 1.306576 -43.73626) (xy 1.306576 -44.689522) (xy 3.862068 -44.689522)
			(xy 3.866139 -44.6339) (xy 3.878265 -44.579463) (xy 3.898188 -44.527372) (xy 3.925484 -44.478737)
			(xy 3.95957 -44.434594) (xy 3.999719 -44.395885) (xy 4.045077 -44.363434) (xy 4.094677 -44.337933)
			(xy 4.147461 -44.319926) (xy 4.202304 -44.309796) (xy 4.258038 -44.307759) (xy 4.313475 -44.313859)
			(xy 4.367432 -44.327965) (xy 4.418761 -44.349777) (xy 4.466367 -44.378831) (xy 4.509235 -44.414506)
			(xy 4.546452 -44.456043) (xy 4.577225 -44.502556) (xy 4.600897 -44.553053) (xy 4.616965 -44.60646)
			(xy 4.625085 -44.661636) (xy 4.625594 -44.689522) (xy 4.625085 -44.717408) (xy 4.616965 -44.772584)
			(xy 4.600897 -44.825991) (xy 4.577225 -44.876488) (xy 4.546452 -44.923001) (xy 4.509235 -44.964538)
			(xy 4.466367 -45.000213) (xy 4.418761 -45.029267) (xy 4.367432 -45.051079) (xy 4.313475 -45.065185)
			(xy 4.258038 -45.071285) (xy 4.202304 -45.069248) (xy 4.147461 -45.059118) (xy 4.094677 -45.041111)
			(xy 4.045077 -45.01561) (xy 3.999719 -44.983159) (xy 3.95957 -44.94445) (xy 3.925484 -44.900307)
			(xy 3.898188 -44.851672) (xy 3.878265 -44.799581) (xy 3.866139 -44.745144) (xy 3.862068 -44.689522)
			(xy 1.306576 -44.689522) (xy 1.306576 -45.071792) (xy 6.365492 -45.071792) (xy 6.369563 -45.01617)
			(xy 6.381689 -44.961733) (xy 6.401612 -44.909642) (xy 6.428908 -44.861007) (xy 6.462994 -44.816864)
			(xy 6.503143 -44.778155) (xy 6.548501 -44.745704) (xy 6.598101 -44.720203) (xy 6.650885 -44.702196)
			(xy 6.705728 -44.692066) (xy 6.761462 -44.690029) (xy 6.816899 -44.696129) (xy 6.870856 -44.710235)
			(xy 6.922185 -44.732047) (xy 6.969791 -44.761101) (xy 7.012659 -44.796776) (xy 7.049876 -44.838313)
			(xy 7.080649 -44.884826) (xy 7.104321 -44.935323) (xy 7.120389 -44.98873) (xy 7.128509 -45.043906)
			(xy 7.129018 -45.071792) (xy 7.128509 -45.099678) (xy 7.126333 -45.114464) (xy 20.06549 -45.114464)
			(xy 20.069561 -45.058842) (xy 20.081687 -45.004405) (xy 20.10161 -44.952314) (xy 20.128906 -44.903679)
			(xy 20.162992 -44.859536) (xy 20.203141 -44.820827) (xy 20.248499 -44.788376) (xy 20.298099 -44.762875)
			(xy 20.350883 -44.744868) (xy 20.405726 -44.734738) (xy 20.46146 -44.732701) (xy 20.516897 -44.738801)
			(xy 20.570854 -44.752907) (xy 20.622183 -44.774719) (xy 20.669789 -44.803773) (xy 20.712657 -44.839448)
			(xy 20.742639 -44.87291) (xy 26.933142 -44.87291) (xy 26.937213 -44.817288) (xy 26.949339 -44.762851)
			(xy 26.969262 -44.71076) (xy 26.996558 -44.662125) (xy 27.030644 -44.617982) (xy 27.070793 -44.579273)
			(xy 27.116151 -44.546822) (xy 27.165751 -44.521321) (xy 27.218535 -44.503314) (xy 27.273378 -44.493184)
			(xy 27.329112 -44.491147) (xy 27.384549 -44.497247) (xy 27.438506 -44.511353) (xy 27.489835 -44.533165)
			(xy 27.537441 -44.562219) (xy 27.580309 -44.597894) (xy 27.617526 -44.639431) (xy 27.648299 -44.685944)
			(xy 27.671971 -44.736441) (xy 27.688039 -44.789848) (xy 27.696159 -44.845024) (xy 27.696668 -44.87291)
			(xy 27.696159 -44.900796) (xy 27.688039 -44.955972) (xy 27.671971 -45.009379) (xy 27.648299 -45.059876)
			(xy 27.617526 -45.106389) (xy 27.580309 -45.147926) (xy 27.537441 -45.183601) (xy 27.489835 -45.212655)
			(xy 27.438506 -45.234467) (xy 27.384549 -45.248573) (xy 27.329112 -45.254673) (xy 27.273378 -45.252636)
			(xy 27.218535 -45.242506) (xy 27.165751 -45.224499) (xy 27.116151 -45.198998) (xy 27.070793 -45.166547)
			(xy 27.030644 -45.127838) (xy 26.996558 -45.083695) (xy 26.969262 -45.03506) (xy 26.949339 -44.982969)
			(xy 26.937213 -44.928532) (xy 26.933142 -44.87291) (xy 20.742639 -44.87291) (xy 20.749874 -44.880985)
			(xy 20.780647 -44.927498) (xy 20.804319 -44.977995) (xy 20.820387 -45.031402) (xy 20.828507 -45.086578)
			(xy 20.829016 -45.114464) (xy 20.828507 -45.14235) (xy 20.820387 -45.197526) (xy 20.804319 -45.250933)
			(xy 20.780647 -45.30143) (xy 20.749874 -45.347943) (xy 20.744232 -45.35424) (xy 24.703784 -45.35424)
			(xy 24.707855 -45.298618) (xy 24.719981 -45.244181) (xy 24.739904 -45.19209) (xy 24.7672 -45.143455)
			(xy 24.801286 -45.099312) (xy 24.841435 -45.060603) (xy 24.886793 -45.028152) (xy 24.936393 -45.002651)
			(xy 24.989177 -44.984644) (xy 25.04402 -44.974514) (xy 25.099754 -44.972477) (xy 25.155191 -44.978577)
			(xy 25.209148 -44.992683) (xy 25.260477 -45.014495) (xy 25.308083 -45.043549) (xy 25.350951 -45.079224)
			(xy 25.388168 -45.120761) (xy 25.418941 -45.167274) (xy 25.442613 -45.217771) (xy 25.458681 -45.271178)
			(xy 25.466801 -45.326354) (xy 25.46731 -45.35424) (xy 25.466801 -45.382126) (xy 25.458681 -45.437302)
			(xy 25.442613 -45.490709) (xy 25.418941 -45.541206) (xy 25.388168 -45.587719) (xy 25.350951 -45.629256)
			(xy 25.308083 -45.664931) (xy 25.260477 -45.693985) (xy 25.209148 -45.715797) (xy 25.155191 -45.729903)
			(xy 25.099754 -45.736003) (xy 25.04402 -45.733966) (xy 24.989177 -45.723836) (xy 24.936393 -45.705829)
			(xy 24.886793 -45.680328) (xy 24.841435 -45.647877) (xy 24.801286 -45.609168) (xy 24.7672 -45.565025)
			(xy 24.739904 -45.51639) (xy 24.719981 -45.464299) (xy 24.707855 -45.409862) (xy 24.703784 -45.35424)
			(xy 20.744232 -45.35424) (xy 20.712657 -45.38948) (xy 20.669789 -45.425155) (xy 20.622183 -45.454209)
			(xy 20.570854 -45.476021) (xy 20.516897 -45.490127) (xy 20.46146 -45.496227) (xy 20.405726 -45.49419)
			(xy 20.350883 -45.48406) (xy 20.298099 -45.466053) (xy 20.248499 -45.440552) (xy 20.203141 -45.408101)
			(xy 20.162992 -45.369392) (xy 20.128906 -45.325249) (xy 20.10161 -45.276614) (xy 20.081687 -45.224523)
			(xy 20.069561 -45.170086) (xy 20.06549 -45.114464) (xy 7.126333 -45.114464) (xy 7.120389 -45.154854)
			(xy 7.104321 -45.208261) (xy 7.080649 -45.258758) (xy 7.049876 -45.305271) (xy 7.012659 -45.346808)
			(xy 6.969791 -45.382483) (xy 6.922185 -45.411537) (xy 6.870856 -45.433349) (xy 6.816899 -45.447455)
			(xy 6.761462 -45.453555) (xy 6.705728 -45.451518) (xy 6.650885 -45.441388) (xy 6.598101 -45.423381)
			(xy 6.548501 -45.39788) (xy 6.503143 -45.365429) (xy 6.462994 -45.32672) (xy 6.428908 -45.282577)
			(xy 6.401612 -45.233942) (xy 6.381689 -45.181851) (xy 6.369563 -45.127414) (xy 6.365492 -45.071792)
			(xy 1.306576 -45.071792) (xy 1.306576 -45.851318) (xy 7.87476 -45.851318) (xy 7.878831 -45.795696)
			(xy 7.890957 -45.741259) (xy 7.91088 -45.689168) (xy 7.938176 -45.640533) (xy 7.972262 -45.59639)
			(xy 8.012411 -45.557681) (xy 8.057769 -45.52523) (xy 8.107369 -45.499729) (xy 8.160153 -45.481722)
			(xy 8.214996 -45.471592) (xy 8.27073 -45.469555) (xy 8.326167 -45.475655) (xy 8.380124 -45.489761)
			(xy 8.431453 -45.511573) (xy 8.479059 -45.540627) (xy 8.521927 -45.576302) (xy 8.559144 -45.617839)
			(xy 8.589917 -45.664352) (xy 8.613589 -45.714849) (xy 8.629657 -45.768256) (xy 8.637777 -45.823432)
			(xy 8.638286 -45.851318) (xy 8.637777 -45.879204) (xy 8.630854 -45.926248) (xy 11.930886 -45.926248)
			(xy 11.934957 -45.870626) (xy 11.947083 -45.816189) (xy 11.967006 -45.764098) (xy 11.994302 -45.715463)
			(xy 12.028388 -45.67132) (xy 12.068537 -45.632611) (xy 12.113895 -45.60016) (xy 12.163495 -45.574659)
			(xy 12.216279 -45.556652) (xy 12.271122 -45.546522) (xy 12.326856 -45.544485) (xy 12.382293 -45.550585)
			(xy 12.43625 -45.564691) (xy 12.487579 -45.586503) (xy 12.535185 -45.615557) (xy 12.578053 -45.651232)
			(xy 12.61527 -45.692769) (xy 12.646043 -45.739282) (xy 12.669715 -45.789779) (xy 12.685783 -45.843186)
			(xy 12.693903 -45.898362) (xy 12.694412 -45.926248) (xy 12.693903 -45.954134) (xy 12.685783 -46.00931)
			(xy 12.669715 -46.062717) (xy 12.66058 -46.082204) (xy 18.052542 -46.082204) (xy 18.052959 -46.054949)
			(xy 18.060717 -46.000994) (xy 18.076075 -45.948692) (xy 18.098721 -45.899109) (xy 18.128193 -45.853253)
			(xy 18.163892 -45.812059) (xy 18.20509 -45.776365) (xy 18.250949 -45.746899) (xy 18.300535 -45.724259)
			(xy 18.352839 -45.708907) (xy 18.406795 -45.701156) (xy 18.43405 -45.700696) (xy 18.460954 -45.70112)
			(xy 18.514226 -45.708699) (xy 18.565905 -45.723685) (xy 18.614967 -45.745781) (xy 18.660438 -45.774549)
			(xy 18.701419 -45.80942) (xy 18.737095 -45.8497) (xy 18.752312 -45.871892) (xy 18.759424 -45.882814)
			(xy 18.782284 -45.894752) (xy 18.894552 -45.89272) (xy 18.916904 -45.879766) (xy 18.923762 -45.86859)
			(xy 18.938655 -45.844969) (xy 18.974339 -45.802018) (xy 19.015902 -45.764726) (xy 19.062457 -45.733891)
			(xy 19.113009 -45.710171) (xy 19.166479 -45.694072) (xy 19.221724 -45.685939) (xy 19.249644 -45.685456)
			(xy 19.276638 -45.685892) (xy 19.330087 -45.693504) (xy 19.381931 -45.70857) (xy 19.431135 -45.730789)
			(xy 19.476718 -45.759719) (xy 19.497548 -45.776896) (xy 19.505676 -45.784008) (xy 19.52625 -45.790104)
			(xy 19.611594 -45.779182) (xy 19.62214 -45.777415) (xy 19.640422 -45.766355) (xy 19.6469 -45.757846)
			(xy 19.66226 -45.73662) (xy 19.697846 -45.698167) (xy 19.738362 -45.664948) (xy 19.783044 -45.637589)
			(xy 19.831051 -45.616605) (xy 19.881479 -45.602391) (xy 19.933378 -45.595214) (xy 19.959574 -45.594778)
			(xy 19.986827 -45.595268) (xy 20.040779 -45.603021) (xy 20.093078 -45.618374) (xy 20.142659 -45.641015)
			(xy 20.188514 -45.670481) (xy 20.229708 -45.706173) (xy 20.265404 -45.747365) (xy 20.294873 -45.793218)
			(xy 20.317516 -45.842798) (xy 20.332873 -45.895096) (xy 20.340631 -45.949047) (xy 20.340631 -46.003553)
			(xy 20.332873 -46.057504) (xy 20.317516 -46.109802) (xy 20.294873 -46.159382) (xy 20.265404 -46.205235)
			(xy 20.229708 -46.246427) (xy 20.188514 -46.282119) (xy 20.142659 -46.311585) (xy 20.093078 -46.334226)
			(xy 20.040779 -46.349579) (xy 19.986827 -46.357332) (xy 19.959574 -46.357794) (xy 19.932581 -46.357336)
			(xy 19.879133 -46.349728) (xy 19.82729 -46.334666) (xy 19.778085 -46.312452) (xy 19.732501 -46.283528)
			(xy 19.71167 -46.266354) (xy 19.703542 -46.259242) (xy 19.682968 -46.253146) (xy 19.597624 -46.264068)
			(xy 19.587085 -46.265862) (xy 19.568801 -46.276903) (xy 19.562318 -46.285404) (xy 19.544699 -46.3097)
			(xy 19.503108 -46.352962) (xy 19.479514 -46.37151) (xy 19.47164 -46.377352) (xy 19.461226 -46.394878)
			(xy 19.448018 -46.485302) (xy 19.452844 -46.504606) (xy 19.458686 -46.51248) (xy 19.458686 -46.512734)
			(xy 19.47619 -46.537477) (xy 19.503992 -46.59133) (xy 19.522928 -46.648903) (xy 19.530131 -46.693836)
			(xy 24.676354 -46.693836) (xy 24.67684 -46.666585) (xy 24.684596 -46.612637) (xy 24.699951 -46.560342)
			(xy 24.722593 -46.510765) (xy 24.752059 -46.464915) (xy 24.78775 -46.423724) (xy 24.828941 -46.388033)
			(xy 24.874791 -46.358567) (xy 24.924368 -46.335925) (xy 24.976663 -46.32057) (xy 25.030611 -46.312814)
			(xy 25.085113 -46.312814) (xy 25.139061 -46.32057) (xy 25.191356 -46.335925) (xy 25.240933 -46.358567)
			(xy 25.286783 -46.388033) (xy 25.327974 -46.423724) (xy 25.363665 -46.464915) (xy 25.393131 -46.510765)
			(xy 25.415773 -46.560342) (xy 25.431128 -46.612637) (xy 25.438884 -46.666585) (xy 25.43937 -46.693836)
			(xy 25.438901 -46.720264) (xy 25.431591 -46.772611) (xy 25.417117 -46.823446) (xy 25.395755 -46.871793)
			(xy 25.38222 -46.894496) (xy 25.381966 -46.89475) (xy 25.37663 -46.904768) (xy 25.374372 -46.927318)
			(xy 25.377648 -46.938184) (xy 25.40381 -47.01286) (xy 25.408168 -47.023389) (xy 25.424274 -47.039472)
			(xy 25.434798 -47.043848) (xy 25.435052 -47.043848) (xy 25.459562 -47.052914) (xy 25.506014 -47.076857)
			(xy 25.548766 -47.106914) (xy 25.587018 -47.142522) (xy 25.620054 -47.183015) (xy 25.647258 -47.227636)
			(xy 25.668119 -47.275552) (xy 25.682249 -47.325865) (xy 25.689383 -47.377636) (xy 25.689814 -47.403766)
			(xy 25.689328 -47.431017) (xy 25.687805 -47.441612) (xy 26.961844 -47.441612) (xy 26.965915 -47.38599)
			(xy 26.978041 -47.331553) (xy 26.997964 -47.279462) (xy 27.02526 -47.230827) (xy 27.059346 -47.186684)
			(xy 27.099495 -47.147975) (xy 27.144853 -47.115524) (xy 27.194453 -47.090023) (xy 27.247237 -47.072016)
			(xy 27.30208 -47.061886) (xy 27.357814 -47.059849) (xy 27.413251 -47.065949) (xy 27.467208 -47.080055)
			(xy 27.518537 -47.101867) (xy 27.566143 -47.130921) (xy 27.609011 -47.166596) (xy 27.646228 -47.208133)
			(xy 27.677001 -47.254646) (xy 27.700673 -47.305143) (xy 27.716741 -47.35855) (xy 27.724861 -47.413726)
			(xy 27.72537 -47.441612) (xy 27.724861 -47.469498) (xy 27.716741 -47.524674) (xy 27.700673 -47.578081)
			(xy 27.677001 -47.628578) (xy 27.646228 -47.675091) (xy 27.609011 -47.716628) (xy 27.566143 -47.752303)
			(xy 27.518537 -47.781357) (xy 27.467208 -47.803169) (xy 27.413251 -47.817275) (xy 27.357814 -47.823375)
			(xy 27.30208 -47.821338) (xy 27.247237 -47.811208) (xy 27.194453 -47.793201) (xy 27.144853 -47.7677)
			(xy 27.099495 -47.735249) (xy 27.059346 -47.69654) (xy 27.02526 -47.652397) (xy 26.997964 -47.603762)
			(xy 26.978041 -47.551671) (xy 26.965915 -47.497234) (xy 26.961844 -47.441612) (xy 25.687805 -47.441612)
			(xy 25.681572 -47.484965) (xy 25.666217 -47.53726) (xy 25.643575 -47.586837) (xy 25.614109 -47.632687)
			(xy 25.578418 -47.673878) (xy 25.537227 -47.709569) (xy 25.491377 -47.739035) (xy 25.4418 -47.761677)
			(xy 25.389505 -47.777032) (xy 25.335557 -47.784788) (xy 25.281055 -47.784788) (xy 25.227107 -47.777032)
			(xy 25.174812 -47.761677) (xy 25.125235 -47.739035) (xy 25.079385 -47.709569) (xy 25.038194 -47.673878)
			(xy 25.002503 -47.632687) (xy 24.973037 -47.586837) (xy 24.950395 -47.53726) (xy 24.93504 -47.484965)
			(xy 24.927284 -47.431017) (xy 24.926798 -47.403766) (xy 24.927272 -47.377338) (xy 24.934581 -47.324991)
			(xy 24.949054 -47.274156) (xy 24.970413 -47.225809) (xy 24.983948 -47.203106) (xy 24.984202 -47.202852)
			(xy 24.989537 -47.192833) (xy 24.991798 -47.170283) (xy 24.98852 -47.159418) (xy 24.962358 -47.084742)
			(xy 24.958014 -47.074206) (xy 24.941898 -47.058126) (xy 24.93137 -47.053754) (xy 24.931116 -47.053754)
			(xy 24.9066 -47.044704) (xy 24.860148 -47.020757) (xy 24.817398 -46.990698) (xy 24.779147 -46.955088)
			(xy 24.746112 -46.914592) (xy 24.718909 -46.869969) (xy 24.698048 -46.822053) (xy 24.683919 -46.771738)
			(xy 24.676785 -46.719966) (xy 24.676354 -46.693836) (xy 19.530131 -46.693836) (xy 19.532521 -46.708745)
			(xy 19.533108 -46.739048) (xy 19.532667 -46.7663) (xy 19.524904 -46.82025) (xy 19.509543 -46.872545)
			(xy 19.486896 -46.922123) (xy 19.457425 -46.967973) (xy 19.421729 -47.009163) (xy 19.380534 -47.044853)
			(xy 19.334681 -47.074319) (xy 19.2851 -47.096959) (xy 19.232803 -47.112314) (xy 19.178852 -47.12007)
			(xy 19.1516 -47.120556) (xy 19.125567 -47.120101) (xy 19.073984 -47.113015) (xy 19.023843 -47.098987)
			(xy 18.976072 -47.078278) (xy 18.931557 -47.051271) (xy 18.911062 -47.035212) (xy 18.903294 -47.029488)
			(xy 18.884892 -47.023736) (xy 18.875248 -47.024036) (xy 18.795492 -47.030386) (xy 18.777712 -47.039022)
			(xy 18.771362 -47.046388) (xy 18.753173 -47.066026) (xy 18.712267 -47.100549) (xy 18.66694 -47.129019)
			(xy 18.61808 -47.150878) (xy 18.566645 -47.165697) (xy 18.513645 -47.173186) (xy 18.486882 -47.173642)
			(xy 18.459632 -47.173139) (xy 18.405687 -47.165381) (xy 18.353394 -47.150025) (xy 18.303819 -47.127385)
			(xy 18.25797 -47.09792) (xy 18.216781 -47.06223) (xy 18.18109 -47.021042) (xy 18.151623 -46.975195)
			(xy 18.12898 -46.925621) (xy 18.113622 -46.873329) (xy 18.105862 -46.819384) (xy 18.105374 -46.792134)
			(xy 18.105905 -46.76336) (xy 18.114556 -46.706467) (xy 18.131651 -46.651517) (xy 18.156803 -46.599756)
			(xy 18.189441 -46.55236) (xy 18.208752 -46.531022) (xy 18.216118 -46.523148) (xy 18.22323 -46.503336)
			(xy 18.215864 -46.40707) (xy 18.205958 -46.388274) (xy 18.197576 -46.38167) (xy 18.175382 -46.363456)
			(xy 18.136175 -46.321517) (xy 18.103692 -46.274179) (xy 18.078665 -46.222509) (xy 18.06166 -46.167674)
			(xy 18.05306 -46.11091) (xy 18.052542 -46.082204) (xy 12.66058 -46.082204) (xy 12.646043 -46.113214)
			(xy 12.61527 -46.159727) (xy 12.578053 -46.201264) (xy 12.535185 -46.236939) (xy 12.487579 -46.265993)
			(xy 12.43625 -46.287805) (xy 12.382293 -46.301911) (xy 12.326856 -46.308011) (xy 12.271122 -46.305974)
			(xy 12.216279 -46.295844) (xy 12.163495 -46.277837) (xy 12.113895 -46.252336) (xy 12.068537 -46.219885)
			(xy 12.028388 -46.181176) (xy 11.994302 -46.137033) (xy 11.967006 -46.088398) (xy 11.947083 -46.036307)
			(xy 11.934957 -45.98187) (xy 11.930886 -45.926248) (xy 8.630854 -45.926248) (xy 8.629657 -45.93438)
			(xy 8.613589 -45.987787) (xy 8.589917 -46.038284) (xy 8.559144 -46.084797) (xy 8.521927 -46.126334)
			(xy 8.479059 -46.162009) (xy 8.431453 -46.191063) (xy 8.380124 -46.212875) (xy 8.326167 -46.226981)
			(xy 8.27073 -46.233081) (xy 8.214996 -46.231044) (xy 8.160153 -46.220914) (xy 8.107369 -46.202907)
			(xy 8.057769 -46.177406) (xy 8.012411 -46.144955) (xy 7.972262 -46.106246) (xy 7.938176 -46.062103)
			(xy 7.91088 -46.013468) (xy 7.890957 -45.961377) (xy 7.878831 -45.90694) (xy 7.87476 -45.851318)
			(xy 1.306576 -45.851318) (xy 1.306576 -48.30699) (xy 24.553924 -48.30699) (xy 24.557995 -48.251368)
			(xy 24.570121 -48.196931) (xy 24.590044 -48.14484) (xy 24.61734 -48.096205) (xy 24.651426 -48.052062)
			(xy 24.691575 -48.013353) (xy 24.736933 -47.980902) (xy 24.786533 -47.955401) (xy 24.839317 -47.937394)
			(xy 24.89416 -47.927264) (xy 24.949894 -47.925227) (xy 25.005331 -47.931327) (xy 25.059288 -47.945433)
			(xy 25.110617 -47.967245) (xy 25.158223 -47.996299) (xy 25.201091 -48.031974) (xy 25.238308 -48.073511)
			(xy 25.269081 -48.120024) (xy 25.292753 -48.170521) (xy 25.308821 -48.223928) (xy 25.316941 -48.279104)
			(xy 25.31745 -48.30699) (xy 25.316941 -48.334876) (xy 25.308821 -48.390052) (xy 25.292753 -48.443459)
			(xy 25.269081 -48.493956) (xy 25.238308 -48.540469) (xy 25.201091 -48.582006) (xy 25.158223 -48.617681)
			(xy 25.110617 -48.646735) (xy 25.059288 -48.668547) (xy 25.005331 -48.682653) (xy 24.949894 -48.688753)
			(xy 24.89416 -48.686716) (xy 24.839317 -48.676586) (xy 24.786533 -48.658579) (xy 24.736933 -48.633078)
			(xy 24.691575 -48.600627) (xy 24.651426 -48.561918) (xy 24.61734 -48.517775) (xy 24.590044 -48.46914)
			(xy 24.570121 -48.417049) (xy 24.557995 -48.362612) (xy 24.553924 -48.30699) (xy 1.306576 -48.30699)
			(xy 1.306576 -48.753014) (xy 21.168358 -48.753014) (xy 21.172429 -48.697392) (xy 21.184555 -48.642955)
			(xy 21.204478 -48.590864) (xy 21.231774 -48.542229) (xy 21.26586 -48.498086) (xy 21.306009 -48.459377)
			(xy 21.351367 -48.426926) (xy 21.400967 -48.401425) (xy 21.453751 -48.383418) (xy 21.508594 -48.373288)
			(xy 21.564328 -48.371251) (xy 21.619765 -48.377351) (xy 21.673722 -48.391457) (xy 21.725051 -48.413269)
			(xy 21.772657 -48.442323) (xy 21.815525 -48.477998) (xy 21.852742 -48.519535) (xy 21.883515 -48.566048)
			(xy 21.907187 -48.616545) (xy 21.923255 -48.669952) (xy 21.931375 -48.725128) (xy 21.931884 -48.753014)
			(xy 21.931375 -48.7809) (xy 21.923255 -48.836076) (xy 21.907187 -48.889483) (xy 21.905791 -48.89246)
			(xy 23.214074 -48.89246) (xy 23.218145 -48.836838) (xy 23.230271 -48.782401) (xy 23.250194 -48.73031)
			(xy 23.27749 -48.681675) (xy 23.311576 -48.637532) (xy 23.351725 -48.598823) (xy 23.397083 -48.566372)
			(xy 23.446683 -48.540871) (xy 23.499467 -48.522864) (xy 23.55431 -48.512734) (xy 23.610044 -48.510697)
			(xy 23.665481 -48.516797) (xy 23.719438 -48.530903) (xy 23.770767 -48.552715) (xy 23.818373 -48.581769)
			(xy 23.861241 -48.617444) (xy 23.898458 -48.658981) (xy 23.929231 -48.705494) (xy 23.952903 -48.755991)
			(xy 23.968971 -48.809398) (xy 23.977091 -48.864574) (xy 23.9776 -48.89246) (xy 23.977091 -48.920346)
			(xy 23.974653 -48.93691) (xy 26.933142 -48.93691) (xy 26.937213 -48.881288) (xy 26.949339 -48.826851)
			(xy 26.969262 -48.77476) (xy 26.996558 -48.726125) (xy 27.030644 -48.681982) (xy 27.070793 -48.643273)
			(xy 27.116151 -48.610822) (xy 27.165751 -48.585321) (xy 27.218535 -48.567314) (xy 27.273378 -48.557184)
			(xy 27.329112 -48.555147) (xy 27.384549 -48.561247) (xy 27.438506 -48.575353) (xy 27.489835 -48.597165)
			(xy 27.537441 -48.626219) (xy 27.580309 -48.661894) (xy 27.617526 -48.703431) (xy 27.648299 -48.749944)
			(xy 27.671971 -48.800441) (xy 27.688039 -48.853848) (xy 27.696159 -48.909024) (xy 27.696668 -48.93691)
			(xy 27.696159 -48.964796) (xy 27.688039 -49.019972) (xy 27.671971 -49.073379) (xy 27.648299 -49.123876)
			(xy 27.617526 -49.170389) (xy 27.580309 -49.211926) (xy 27.537441 -49.247601) (xy 27.489835 -49.276655)
			(xy 27.438506 -49.298467) (xy 27.384549 -49.312573) (xy 27.329112 -49.318673) (xy 27.273378 -49.316636)
			(xy 27.218535 -49.306506) (xy 27.165751 -49.288499) (xy 27.116151 -49.262998) (xy 27.070793 -49.230547)
			(xy 27.030644 -49.191838) (xy 26.996558 -49.147695) (xy 26.969262 -49.09906) (xy 26.949339 -49.046969)
			(xy 26.937213 -48.992532) (xy 26.933142 -48.93691) (xy 23.974653 -48.93691) (xy 23.968971 -48.975522)
			(xy 23.952903 -49.028929) (xy 23.929231 -49.079426) (xy 23.898458 -49.125939) (xy 23.861241 -49.167476)
			(xy 23.818373 -49.203151) (xy 23.770767 -49.232205) (xy 23.719438 -49.254017) (xy 23.665481 -49.268123)
			(xy 23.610044 -49.274223) (xy 23.55431 -49.272186) (xy 23.499467 -49.262056) (xy 23.446683 -49.244049)
			(xy 23.397083 -49.218548) (xy 23.351725 -49.186097) (xy 23.311576 -49.147388) (xy 23.27749 -49.103245)
			(xy 23.250194 -49.05461) (xy 23.230271 -49.002519) (xy 23.218145 -48.948082) (xy 23.214074 -48.89246)
			(xy 21.905791 -48.89246) (xy 21.883515 -48.93998) (xy 21.852742 -48.986493) (xy 21.815525 -49.02803)
			(xy 21.772657 -49.063705) (xy 21.725051 -49.092759) (xy 21.673722 -49.114571) (xy 21.619765 -49.128677)
			(xy 21.564328 -49.134777) (xy 21.508594 -49.13274) (xy 21.453751 -49.12261) (xy 21.400967 -49.104603)
			(xy 21.351367 -49.079102) (xy 21.306009 -49.046651) (xy 21.26586 -49.007942) (xy 21.231774 -48.963799)
			(xy 21.204478 -48.915164) (xy 21.184555 -48.863073) (xy 21.172429 -48.808636) (xy 21.168358 -48.753014)
			(xy 1.306576 -48.753014) (xy 1.306576 -49.601951) (xy 6.113002 -49.601951) (xy 6.113002 -49.547449)
			(xy 6.120758 -49.493502) (xy 6.136113 -49.441208) (xy 6.158754 -49.391632) (xy 6.18822 -49.345782)
			(xy 6.223911 -49.304592) (xy 6.2651 -49.268901) (xy 6.31095 -49.239435) (xy 6.360526 -49.216794)
			(xy 6.41282 -49.201439) (xy 6.466767 -49.193682) (xy 6.494018 -49.193196) (xy 6.521389 -49.193652)
			(xy 6.575568 -49.201473) (xy 6.628071 -49.216964) (xy 6.677818 -49.239808) (xy 6.723784 -49.269534)
			(xy 6.744716 -49.287176) (xy 6.74497 -49.28743) (xy 6.752059 -49.293013) (xy 6.768974 -49.299261)
			(xy 6.77799 -49.299622) (xy 6.845046 -49.299622) (xy 6.85406 -49.299235) (xy 6.870977 -49.293008)
			(xy 6.878066 -49.28743) (xy 6.878066 -49.287176) (xy 6.87832 -49.287176) (xy 6.899253 -49.269535)
			(xy 6.945221 -49.239811) (xy 6.994967 -49.216965) (xy 7.047469 -49.201469) (xy 7.101647 -49.19364)
			(xy 7.156389 -49.19364) (xy 7.210567 -49.201469) (xy 7.263069 -49.216965) (xy 7.312815 -49.239811)
			(xy 7.358783 -49.269535) (xy 7.379716 -49.287176) (xy 7.37997 -49.28743) (xy 7.387059 -49.293013)
			(xy 7.403974 -49.299261) (xy 7.41299 -49.299622) (xy 7.480046 -49.299622) (xy 7.48906 -49.299235)
			(xy 7.505977 -49.293008) (xy 7.513066 -49.28743) (xy 7.513066 -49.287176) (xy 7.51332 -49.287176)
			(xy 7.534253 -49.269535) (xy 7.580221 -49.239811) (xy 7.629967 -49.216965) (xy 7.682469 -49.201469)
			(xy 7.736647 -49.19364) (xy 7.791389 -49.19364) (xy 7.845567 -49.201469) (xy 7.898069 -49.216965)
			(xy 7.947815 -49.239811) (xy 7.993783 -49.269535) (xy 8.014716 -49.287176) (xy 8.01497 -49.28743)
			(xy 8.022059 -49.293013) (xy 8.038974 -49.299261) (xy 8.04799 -49.299622) (xy 8.115046 -49.299622)
			(xy 8.12406 -49.299235) (xy 8.140977 -49.293008) (xy 8.148066 -49.28743) (xy 8.148066 -49.287176)
			(xy 8.14832 -49.287176) (xy 8.169268 -49.269557) (xy 8.215237 -49.239843) (xy 8.26498 -49.217004)
			(xy 8.317477 -49.201508) (xy 8.37165 -49.193673) (xy 8.399018 -49.193196) (xy 8.426271 -49.193651)
			(xy 8.480223 -49.201408) (xy 8.532522 -49.216764) (xy 8.582102 -49.239407) (xy 8.627956 -49.268875)
			(xy 8.66915 -49.304569) (xy 8.704844 -49.345762) (xy 8.734312 -49.391616) (xy 8.756955 -49.441197)
			(xy 8.772312 -49.493495) (xy 8.780069 -49.547447) (xy 8.780069 -49.601953) (xy 8.772312 -49.655905)
			(xy 8.756955 -49.708203) (xy 8.734312 -49.757784) (xy 8.704844 -49.803638) (xy 8.66915 -49.844831)
			(xy 8.627956 -49.880525) (xy 8.582102 -49.909993) (xy 8.532522 -49.932636) (xy 8.480223 -49.947992)
			(xy 8.446017 -49.95291) (xy 26.933142 -49.95291) (xy 26.937213 -49.897288) (xy 26.949339 -49.842851)
			(xy 26.969262 -49.79076) (xy 26.996558 -49.742125) (xy 27.030644 -49.697982) (xy 27.070793 -49.659273)
			(xy 27.116151 -49.626822) (xy 27.165751 -49.601321) (xy 27.218535 -49.583314) (xy 27.273378 -49.573184)
			(xy 27.329112 -49.571147) (xy 27.384549 -49.577247) (xy 27.438506 -49.591353) (xy 27.489835 -49.613165)
			(xy 27.537441 -49.642219) (xy 27.580309 -49.677894) (xy 27.617526 -49.719431) (xy 27.648299 -49.765944)
			(xy 27.671971 -49.816441) (xy 27.688039 -49.869848) (xy 27.696159 -49.925024) (xy 27.696668 -49.95291)
			(xy 27.696159 -49.980796) (xy 27.688039 -50.035972) (xy 27.671971 -50.089379) (xy 27.648299 -50.139876)
			(xy 27.617526 -50.186389) (xy 27.580309 -50.227926) (xy 27.537441 -50.263601) (xy 27.489835 -50.292655)
			(xy 27.438506 -50.314467) (xy 27.384549 -50.328573) (xy 27.329112 -50.334673) (xy 27.273378 -50.332636)
			(xy 27.218535 -50.322506) (xy 27.165751 -50.304499) (xy 27.116151 -50.278998) (xy 27.070793 -50.246547)
			(xy 27.030644 -50.207838) (xy 26.996558 -50.163695) (xy 26.969262 -50.11506) (xy 26.949339 -50.062969)
			(xy 26.937213 -50.008532) (xy 26.933142 -49.95291) (xy 8.446017 -49.95291) (xy 8.426271 -49.955749)
			(xy 8.399018 -49.956212) (xy 8.371648 -49.955732) (xy 8.31747 -49.947917) (xy 8.264967 -49.932431)
			(xy 8.21522 -49.909593) (xy 8.169252 -49.879872) (xy 8.14832 -49.862232) (xy 8.148066 -49.861978)
			(xy 8.140966 -49.85641) (xy 8.12406 -49.850153) (xy 8.115046 -49.849786) (xy 8.04799 -49.849786)
			(xy 8.038973 -49.850141) (xy 8.022056 -49.856391) (xy 8.01497 -49.861978) (xy 8.014716 -49.862232)
			(xy 7.993783 -49.879873) (xy 7.947815 -49.909597) (xy 7.898069 -49.932443) (xy 7.845567 -49.947939)
			(xy 7.791389 -49.955768) (xy 7.736647 -49.955768) (xy 7.682469 -49.947939) (xy 7.629967 -49.932443)
			(xy 7.580221 -49.909597) (xy 7.534253 -49.879873) (xy 7.51332 -49.862232) (xy 7.513066 -49.861978)
			(xy 7.505966 -49.85641) (xy 7.48906 -49.850153) (xy 7.480046 -49.849786) (xy 7.41299 -49.849786)
			(xy 7.403973 -49.850141) (xy 7.387056 -49.856391) (xy 7.37997 -49.861978) (xy 7.37997 -49.862232)
			(xy 7.379716 -49.862232) (xy 7.358783 -49.879873) (xy 7.312815 -49.909597) (xy 7.263069 -49.932443)
			(xy 7.210567 -49.947939) (xy 7.156389 -49.955768) (xy 7.101647 -49.955768) (xy 7.047469 -49.947939)
			(xy 6.994967 -49.932443) (xy 6.945221 -49.909597) (xy 6.899253 -49.879873) (xy 6.87832 -49.862232)
			(xy 6.878066 -49.861978) (xy 6.870966 -49.85641) (xy 6.85406 -49.850153) (xy 6.845046 -49.849786)
			(xy 6.77799 -49.849786) (xy 6.768973 -49.850141) (xy 6.752056 -49.856391) (xy 6.74497 -49.861978)
			(xy 6.74497 -49.862232) (xy 6.744716 -49.862232) (xy 6.723793 -49.879882) (xy 6.677817 -49.909591)
			(xy 6.628067 -49.932424) (xy 6.575565 -49.947913) (xy 6.521388 -49.955739) (xy 6.494018 -49.956212)
			(xy 6.466767 -49.955718) (xy 6.41282 -49.947961) (xy 6.360526 -49.932606) (xy 6.31095 -49.909965)
			(xy 6.2651 -49.880499) (xy 6.223911 -49.844808) (xy 6.18822 -49.803618) (xy 6.158754 -49.757768)
			(xy 6.136113 -49.708192) (xy 6.120758 -49.655898) (xy 6.113002 -49.601951) (xy 1.306576 -49.601951)
			(xy 1.306576 -51.243992) (xy 7.133082 -51.243992) (xy 7.133523 -51.216621) (xy 7.141344 -51.16244)
			(xy 7.156838 -51.109936) (xy 7.179686 -51.060189) (xy 7.209417 -51.014224) (xy 7.227062 -50.993294)
			(xy 7.227316 -50.99304) (xy 7.232894 -50.985947) (xy 7.239145 -50.969035) (xy 7.239508 -50.96002)
			(xy 7.239508 -50.892964) (xy 7.239167 -50.883946) (xy 7.232908 -50.867029) (xy 7.227316 -50.859944)
			(xy 7.227062 -50.859944) (xy 7.227062 -50.85969) (xy 7.209398 -50.838778) (xy 7.179691 -50.792799)
			(xy 7.156861 -50.743046) (xy 7.141375 -50.690541) (xy 7.133553 -50.636362) (xy 7.133082 -50.608992)
			(xy 7.13357 -50.581741) (xy 7.141328 -50.527794) (xy 7.156683 -50.4755) (xy 7.179325 -50.425923)
			(xy 7.208791 -50.380073) (xy 7.244482 -50.338883) (xy 7.285672 -50.303192) (xy 7.331521 -50.273726)
			(xy 7.381098 -50.251084) (xy 7.433392 -50.235728) (xy 7.487339 -50.22797) (xy 7.51459 -50.227484)
			(xy 7.543508 -50.227978) (xy 7.600682 -50.236707) (xy 7.655883 -50.253968) (xy 7.707845 -50.279364)
			(xy 7.755378 -50.312314) (xy 7.797392 -50.352061) (xy 7.81558 -50.37455) (xy 7.823197 -50.383347)
			(xy 7.844091 -50.393534) (xy 7.855712 -50.394108) (xy 7.935468 -50.394108) (xy 7.947095 -50.393533)
			(xy 7.968005 -50.383369) (xy 7.9756 -50.37455) (xy 7.993778 -50.352056) (xy 8.035802 -50.312324)
			(xy 8.08334 -50.279388) (xy 8.135304 -50.254001) (xy 8.190503 -50.236747) (xy 8.247673 -50.228019)
			(xy 8.27659 -50.227484) (xy 8.303842 -50.227965) (xy 8.357792 -50.23572) (xy 8.410089 -50.251074)
			(xy 8.459669 -50.273715) (xy 8.505522 -50.303181) (xy 8.546714 -50.338873) (xy 8.582408 -50.380064)
			(xy 8.611876 -50.425915) (xy 8.634519 -50.475494) (xy 8.649876 -50.52779) (xy 8.657634 -50.58174)
			(xy 8.658098 -50.608992) (xy 8.657626 -50.635306) (xy 8.650392 -50.687434) (xy 8.636074 -50.738077)
			(xy 8.614942 -50.786276) (xy 8.587397 -50.831119) (xy 8.553959 -50.871759) (xy 8.534908 -50.889916)
			(xy 8.527499 -50.897431) (xy 8.518978 -50.916716) (xy 8.518398 -50.927254) (xy 8.518398 -51.00193)
			(xy 8.518952 -51.012477) (xy 8.522033 -51.019456) (xy 24.749504 -51.019456) (xy 24.753575 -50.963834)
			(xy 24.765701 -50.909397) (xy 24.785624 -50.857306) (xy 24.81292 -50.808671) (xy 24.847006 -50.764528)
			(xy 24.887155 -50.725819) (xy 24.932513 -50.693368) (xy 24.982113 -50.667867) (xy 25.034897 -50.64986)
			(xy 25.08974 -50.63973) (xy 25.145474 -50.637693) (xy 25.200911 -50.643793) (xy 25.254868 -50.657899)
			(xy 25.306197 -50.679711) (xy 25.353803 -50.708765) (xy 25.396671 -50.74444) (xy 25.433888 -50.785977)
			(xy 25.464661 -50.83249) (xy 25.488333 -50.882987) (xy 25.504401 -50.936394) (xy 25.512521 -50.99157)
			(xy 25.51303 -51.019456) (xy 25.512521 -51.047342) (xy 25.504401 -51.102518) (xy 25.488333 -51.155925)
			(xy 25.464661 -51.206422) (xy 25.433888 -51.252935) (xy 25.396671 -51.294472) (xy 25.353803 -51.330147)
			(xy 25.306197 -51.359201) (xy 25.254868 -51.381013) (xy 25.200911 -51.395119) (xy 25.145474 -51.401219)
			(xy 25.08974 -51.399182) (xy 25.034897 -51.389052) (xy 24.982113 -51.371045) (xy 24.932513 -51.345544)
			(xy 24.887155 -51.313093) (xy 24.847006 -51.274384) (xy 24.81292 -51.230241) (xy 24.785624 -51.181606)
			(xy 24.765701 -51.129515) (xy 24.753575 -51.075078) (xy 24.749504 -51.019456) (xy 8.522033 -51.019456)
			(xy 8.52747 -51.031772) (xy 8.534908 -51.039268) (xy 8.553991 -51.057396) (xy 8.587445 -51.098032)
			(xy 8.615001 -51.142878) (xy 8.636134 -51.191084) (xy 8.650446 -51.241736) (xy 8.657663 -51.293874)
			(xy 8.658098 -51.320192) (xy 8.657637 -51.347445) (xy 8.649881 -51.401397) (xy 8.634526 -51.453695)
			(xy 8.611883 -51.503276) (xy 8.582415 -51.54913) (xy 8.546721 -51.590323) (xy 8.505528 -51.626016)
			(xy 8.459674 -51.655484) (xy 8.410093 -51.678126) (xy 8.357795 -51.693481) (xy 8.303843 -51.701237)
			(xy 8.27659 -51.7017) (xy 8.248925 -51.701196) (xy 8.194175 -51.693195) (xy 8.141153 -51.677377)
			(xy 8.090969 -51.654073) (xy 8.044674 -51.62377) (xy 8.003236 -51.587104) (xy 7.967523 -51.544841)
			(xy 7.952486 -51.521614) (xy 7.945866 -51.511924) (xy 7.925992 -51.499488) (xy 7.914386 -51.497738)
			(xy 7.834376 -51.489864) (xy 7.822737 -51.489221) (xy 7.800899 -51.497308) (xy 7.792466 -51.505358)
			(xy 7.792212 -51.505612) (xy 7.77411 -51.524172) (xy 7.733782 -51.556752) (xy 7.689412 -51.583567)
			(xy 7.641818 -51.604124) (xy 7.591878 -51.618042) (xy 7.540512 -51.625065) (xy 7.51459 -51.6255)
			(xy 7.487338 -51.625031) (xy 7.433389 -51.617273) (xy 7.381094 -51.601917) (xy 7.331516 -51.579274)
			(xy 7.285665 -51.549806) (xy 7.244475 -51.514112) (xy 7.208784 -51.47292) (xy 7.179318 -51.427068)
			(xy 7.156677 -51.377489) (xy 7.141323 -51.325193) (xy 7.133567 -51.271244) (xy 7.133082 -51.243992)
			(xy 1.306576 -51.243992) (xy 1.306576 -52.035456) (xy 26.94127 -52.035456) (xy 26.945341 -51.979834)
			(xy 26.957467 -51.925397) (xy 26.97739 -51.873306) (xy 27.004686 -51.824671) (xy 27.038772 -51.780528)
			(xy 27.078921 -51.741819) (xy 27.124279 -51.709368) (xy 27.173879 -51.683867) (xy 27.226663 -51.66586)
			(xy 27.281506 -51.65573) (xy 27.33724 -51.653693) (xy 27.392677 -51.659793) (xy 27.446634 -51.673899)
			(xy 27.497963 -51.695711) (xy 27.545569 -51.724765) (xy 27.588437 -51.76044) (xy 27.625654 -51.801977)
			(xy 27.656427 -51.84849) (xy 27.680099 -51.898987) (xy 27.696167 -51.952394) (xy 27.704287 -52.00757)
			(xy 27.704796 -52.035456) (xy 27.704287 -52.063342) (xy 27.696167 -52.118518) (xy 27.680099 -52.171925)
			(xy 27.656427 -52.222422) (xy 27.625654 -52.268935) (xy 27.588437 -52.310472) (xy 27.545569 -52.346147)
			(xy 27.497963 -52.375201) (xy 27.446634 -52.397013) (xy 27.392677 -52.411119) (xy 27.33724 -52.417219)
			(xy 27.281506 -52.415182) (xy 27.226663 -52.405052) (xy 27.173879 -52.387045) (xy 27.124279 -52.361544)
			(xy 27.078921 -52.329093) (xy 27.038772 -52.290384) (xy 27.004686 -52.246241) (xy 26.97739 -52.197606)
			(xy 26.957467 -52.145515) (xy 26.945341 -52.091078) (xy 26.94127 -52.035456) (xy 1.306576 -52.035456)
			(xy 1.306576 -52.555973) (xy 6.583889 -52.555973) (xy 6.583889 -52.501467) (xy 6.591646 -52.447517)
			(xy 6.607002 -52.395219) (xy 6.629645 -52.345639) (xy 6.659113 -52.299786) (xy 6.694807 -52.258594)
			(xy 6.735999 -52.222901) (xy 6.781853 -52.193433) (xy 6.831433 -52.170791) (xy 6.88373 -52.155435)
			(xy 6.937681 -52.147679) (xy 6.964934 -52.147216) (xy 6.992305 -52.147658) (xy 7.046485 -52.155481)
			(xy 7.098989 -52.170976) (xy 7.148735 -52.193823) (xy 7.194701 -52.223552) (xy 7.215632 -52.241196)
			(xy 7.215886 -52.24145) (xy 7.222968 -52.247043) (xy 7.239888 -52.253285) (xy 7.248906 -52.253642)
			(xy 7.315962 -52.253642) (xy 7.324979 -52.253279) (xy 7.341896 -52.247037) (xy 7.348982 -52.24145)
			(xy 7.348982 -52.241196) (xy 7.349236 -52.241196) (xy 7.370181 -52.223573) (xy 7.41615 -52.193859)
			(xy 7.465894 -52.17102) (xy 7.518392 -52.155525) (xy 7.572566 -52.147692) (xy 7.599934 -52.147216)
			(xy 7.627185 -52.147694) (xy 7.681133 -52.155451) (xy 7.733428 -52.170807) (xy 7.783005 -52.193448)
			(xy 7.828856 -52.222915) (xy 7.870046 -52.258607) (xy 7.905737 -52.299798) (xy 7.935204 -52.345648)
			(xy 7.957845 -52.395226) (xy 7.9732 -52.447521) (xy 7.980956 -52.501469) (xy 7.980956 -52.555971)
			(xy 7.9732 -52.609919) (xy 7.957845 -52.662214) (xy 7.935204 -52.711792) (xy 7.905737 -52.757642)
			(xy 7.870046 -52.798833) (xy 7.828856 -52.834525) (xy 7.783005 -52.863992) (xy 7.733428 -52.886633)
			(xy 7.681133 -52.901989) (xy 7.627185 -52.909746) (xy 7.599934 -52.910232) (xy 7.572564 -52.909763)
			(xy 7.518384 -52.901948) (xy 7.46588 -52.886461) (xy 7.416133 -52.863619) (xy 7.370167 -52.833894)
			(xy 7.349236 -52.816252) (xy 7.348982 -52.815998) (xy 7.341905 -52.810398) (xy 7.324981 -52.804159)
			(xy 7.315962 -52.803806) (xy 7.248906 -52.803806) (xy 7.239889 -52.804165) (xy 7.222972 -52.810411)
			(xy 7.215886 -52.815998) (xy 7.215886 -52.816252) (xy 7.215632 -52.816252) (xy 7.194693 -52.833882)
			(xy 7.148723 -52.863597) (xy 7.098977 -52.886435) (xy 7.046478 -52.901928) (xy 6.992303 -52.909758)
			(xy 6.964934 -52.910232) (xy 6.937681 -52.909761) (xy 6.88373 -52.902005) (xy 6.831433 -52.886649)
			(xy 6.781853 -52.864007) (xy 6.735999 -52.834539) (xy 6.694807 -52.798846) (xy 6.659113 -52.757654)
			(xy 6.629645 -52.711801) (xy 6.607002 -52.662221) (xy 6.591646 -52.609923) (xy 6.583889 -52.555973)
			(xy 1.306576 -52.555973) (xy 1.306576 -53.496543) (xy 6.133541 -53.496543) (xy 6.133541 -53.442037)
			(xy 6.141298 -53.388085) (xy 6.156655 -53.335787) (xy 6.179298 -53.286206) (xy 6.208766 -53.240352)
			(xy 6.24446 -53.199159) (xy 6.285654 -53.163465) (xy 6.331508 -53.133997) (xy 6.381088 -53.111354)
			(xy 6.433387 -53.095998) (xy 6.487339 -53.088241) (xy 6.514592 -53.087778) (xy 6.541963 -53.08823)
			(xy 6.596143 -53.096048) (xy 6.648647 -53.111539) (xy 6.698394 -53.134385) (xy 6.74436 -53.164114)
			(xy 6.76529 -53.181758) (xy 6.765544 -53.182012) (xy 6.772641 -53.187583) (xy 6.78955 -53.193839)
			(xy 6.798564 -53.194204) (xy 6.86562 -53.194204) (xy 6.874638 -53.193856) (xy 6.891555 -53.187602)
			(xy 6.89864 -53.182012) (xy 6.89864 -53.181758) (xy 6.898894 -53.181758) (xy 6.919812 -53.164101)
			(xy 6.965789 -53.134393) (xy 7.01554 -53.111561) (xy 7.068044 -53.096074) (xy 7.122222 -53.08825)
			(xy 7.149592 -53.087778) (xy 7.176843 -53.088272) (xy 7.23079 -53.096029) (xy 7.283084 -53.111384)
			(xy 7.33266 -53.134025) (xy 7.37851 -53.163491) (xy 7.419699 -53.199182) (xy 7.45539 -53.240372)
			(xy 7.484856 -53.286222) (xy 7.507497 -53.335798) (xy 7.522852 -53.388092) (xy 7.530608 -53.442039)
			(xy 7.530608 -53.496541) (xy 7.522852 -53.550488) (xy 7.507497 -53.602782) (xy 7.484856 -53.652358)
			(xy 7.45539 -53.698208) (xy 7.419699 -53.739398) (xy 7.37851 -53.775089) (xy 7.33266 -53.804555)
			(xy 7.283084 -53.827196) (xy 7.23079 -53.842551) (xy 7.176843 -53.850308) (xy 7.149592 -53.850794)
			(xy 7.122222 -53.850334) (xy 7.068042 -53.842515) (xy 7.015539 -53.827025) (xy 6.965792 -53.804181)
			(xy 6.919826 -53.774456) (xy 6.898894 -53.756814) (xy 6.89864 -53.75656) (xy 6.89155 -53.750979)
			(xy 6.874636 -53.74473) (xy 6.86562 -53.744368) (xy 6.798564 -53.744368) (xy 6.789546 -53.744715)
			(xy 6.77263 -53.75097) (xy 6.765544 -53.75656) (xy 6.765544 -53.756814) (xy 6.76529 -53.756814) (xy 6.744374 -53.774473)
			(xy 6.698397 -53.804182) (xy 6.648645 -53.827014) (xy 6.596141 -53.8425) (xy 6.541962 -53.850323)
			(xy 6.514592 -53.850794) (xy 6.487339 -53.850339) (xy 6.433387 -53.842582) (xy 6.381088 -53.827226)
			(xy 6.331508 -53.804583) (xy 6.285654 -53.775115) (xy 6.24446 -53.739421) (xy 6.208766 -53.698228)
			(xy 6.179298 -53.652374) (xy 6.156655 -53.602793) (xy 6.141298 -53.550495) (xy 6.133541 -53.496543)
			(xy 1.306576 -53.496543) (xy 1.306576 -54.989041) (xy 3.901168 -54.989041) (xy 3.901168 -54.934539)
			(xy 3.908924 -54.880592) (xy 3.924279 -54.828297) (xy 3.94692 -54.77872) (xy 3.976386 -54.73287)
			(xy 4.012077 -54.69168) (xy 4.053267 -54.655988) (xy 4.099117 -54.626522) (xy 4.148693 -54.603881)
			(xy 4.200988 -54.588525) (xy 4.254935 -54.580768) (xy 4.282186 -54.580282) (xy 4.310277 -54.580788)
			(xy 4.365854 -54.589013) (xy 4.419622 -54.605302) (xy 4.47042 -54.629303) (xy 4.517147 -54.660496)
			(xy 4.558792 -54.698207) (xy 4.594455 -54.741618) (xy 4.609338 -54.765448) (xy 4.614672 -54.774338)
			(xy 4.63169 -54.78653) (xy 4.724908 -54.80685) (xy 4.745482 -54.802532) (xy 4.754118 -54.79669) (xy 4.778175 -54.780679)
			(xy 4.830109 -54.755339) (xy 4.885269 -54.738117) (xy 4.942395 -54.729405) (xy 4.971288 -54.728872)
			(xy 4.998541 -54.729337) (xy 5.012973 -54.731412) (xy 13.520674 -54.731412) (xy 13.521129 -54.704041)
			(xy 13.528947 -54.649861) (xy 13.544437 -54.597357) (xy 13.567282 -54.54761) (xy 13.597011 -54.501645)
			(xy 13.614654 -54.480714) (xy 13.614908 -54.48046) (xy 13.620476 -54.473361) (xy 13.626734 -54.456454)
			(xy 13.6271 -54.44744) (xy 13.6271 -54.380384) (xy 13.626751 -54.371366) (xy 13.620498 -54.35445)
			(xy 13.614908 -54.347364) (xy 13.614654 -54.347364) (xy 13.614654 -54.34711) (xy 13.597024 -54.326168)
			(xy 13.567297 -54.280203) (xy 13.544449 -54.230458) (xy 13.528951 -54.177957) (xy 13.52112 -54.123779)
			(xy 13.521119 -54.069039) (xy 13.528947 -54.014861) (xy 13.544443 -53.962359) (xy 13.567288 -53.912613)
			(xy 13.597013 -53.866646) (xy 13.614654 -53.845714) (xy 13.614908 -53.84546) (xy 13.620476 -53.838361)
			(xy 13.626734 -53.821454) (xy 13.6271 -53.81244) (xy 13.6271 -53.745384) (xy 13.626751 -53.736366)
			(xy 13.620498 -53.71945) (xy 13.614908 -53.712364) (xy 13.614654 -53.712364) (xy 13.614654 -53.71211)
			(xy 13.597024 -53.691168) (xy 13.567297 -53.645203) (xy 13.544449 -53.595458) (xy 13.528951 -53.542957)
			(xy 13.52112 -53.488779) (xy 13.521119 -53.434039) (xy 13.528947 -53.379861) (xy 13.544443 -53.327359)
			(xy 13.567288 -53.277613) (xy 13.597013 -53.231646) (xy 13.614654 -53.210714) (xy 13.614908 -53.21046)
			(xy 13.620476 -53.203361) (xy 13.626734 -53.186454) (xy 13.6271 -53.17744) (xy 13.6271 -53.110384)
			(xy 13.626751 -53.101366) (xy 13.620498 -53.08445) (xy 13.614908 -53.077364) (xy 13.614654 -53.077364)
			(xy 13.614654 -53.07711) (xy 13.597015 -53.056178) (xy 13.567301 -53.010206) (xy 13.544464 -52.960459)
			(xy 13.528973 -52.907958) (xy 13.521147 -52.853781) (xy 13.520674 -52.826412) (xy 13.52116 -52.799161)
			(xy 13.528916 -52.745213) (xy 13.544271 -52.692918) (xy 13.566913 -52.643341) (xy 13.596379 -52.597491)
			(xy 13.63207 -52.5563) (xy 13.673261 -52.520609) (xy 13.719111 -52.491143) (xy 13.768688 -52.468501)
			(xy 13.820983 -52.453146) (xy 13.874931 -52.44539) (xy 13.929433 -52.44539) (xy 13.983381 -52.453146)
			(xy 14.035676 -52.468501) (xy 14.085253 -52.491143) (xy 14.131103 -52.520609) (xy 14.172294 -52.5563)
			(xy 14.207985 -52.597491) (xy 14.237451 -52.643341) (xy 14.260093 -52.692918) (xy 14.275448 -52.745213)
			(xy 14.283204 -52.799161) (xy 14.28369 -52.826412) (xy 14.283233 -52.853783) (xy 14.275414 -52.907962)
			(xy 14.259922 -52.960466) (xy 14.237079 -53.010212) (xy 14.207352 -53.056179) (xy 14.18971 -53.07711)
			(xy 14.189456 -53.077364) (xy 14.183873 -53.084453) (xy 14.177625 -53.101368) (xy 14.177264 -53.110384)
			(xy 14.177264 -53.17744) (xy 14.17761 -53.186458) (xy 14.183866 -53.203374) (xy 14.189456 -53.21046)
			(xy 14.18971 -53.21046) (xy 14.18971 -53.210714) (xy 14.207361 -53.231638) (xy 14.237082 -53.277608)
			(xy 14.259925 -53.327356) (xy 14.275419 -53.379859) (xy 14.283245 -53.434038) (xy 14.283244 -53.48878)
			(xy 14.275415 -53.542958) (xy 14.259918 -53.595461) (xy 14.237074 -53.645208) (xy 14.20735 -53.691177)
			(xy 14.18971 -53.71211) (xy 14.189456 -53.712364) (xy 14.183873 -53.719453) (xy 14.177625 -53.736368)
			(xy 14.177264 -53.745384) (xy 14.177264 -53.81244) (xy 14.17761 -53.821458) (xy 14.183866 -53.838374)
			(xy 14.189456 -53.84546) (xy 14.18971 -53.84546) (xy 14.18971 -53.845714) (xy 14.207361 -53.866638)
			(xy 14.237082 -53.912608) (xy 14.259925 -53.962356) (xy 14.275419 -54.014859) (xy 14.283245 -54.069038)
			(xy 14.283244 -54.12378) (xy 14.275415 -54.177958) (xy 14.259918 -54.230461) (xy 14.237074 -54.280208)
			(xy 14.20735 -54.326177) (xy 14.18971 -54.34711) (xy 14.189456 -54.347364) (xy 14.183873 -54.354453)
			(xy 14.177625 -54.371368) (xy 14.177264 -54.380384) (xy 14.177264 -54.44744) (xy 14.17761 -54.456458)
			(xy 14.183866 -54.473374) (xy 14.189456 -54.48046) (xy 14.18971 -54.48046) (xy 14.18971 -54.480714)
			(xy 14.207324 -54.501666) (xy 14.237039 -54.547634) (xy 14.25988 -54.597376) (xy 14.275377 -54.649872)
			(xy 14.283212 -54.704044) (xy 14.28369 -54.731412) (xy 14.283204 -54.758663) (xy 14.27854 -54.791102)
			(xy 16.176498 -54.791102) (xy 16.176966 -54.763732) (xy 16.184783 -54.709553) (xy 16.200272 -54.65705)
			(xy 16.223113 -54.607303) (xy 16.252837 -54.561336) (xy 16.270478 -54.540404) (xy 16.270732 -54.54015)
			(xy 16.276307 -54.533056) (xy 16.28256 -54.516145) (xy 16.282924 -54.50713) (xy 16.282924 -54.440074)
			(xy 16.282574 -54.431056) (xy 16.276321 -54.41414) (xy 16.270732 -54.407054) (xy 16.270478 -54.407054)
			(xy 16.270478 -54.4068) (xy 16.252841 -54.385865) (xy 16.22312 -54.339896) (xy 16.200278 -54.29015)
			(xy 16.184783 -54.237649) (xy 16.176956 -54.183471) (xy 16.176955 -54.128732) (xy 16.184783 -54.074554)
			(xy 16.200277 -54.022053) (xy 16.223119 -53.972307) (xy 16.252839 -53.926338) (xy 16.270478 -53.905404)
			(xy 16.270732 -53.90515) (xy 16.276307 -53.898056) (xy 16.28256 -53.881145) (xy 16.282924 -53.87213)
			(xy 16.282924 -53.805074) (xy 16.282574 -53.796056) (xy 16.276321 -53.77914) (xy 16.270732 -53.772054)
			(xy 16.270478 -53.772054) (xy 16.270478 -53.7718) (xy 16.252841 -53.750865) (xy 16.22312 -53.704896)
			(xy 16.200278 -53.65515) (xy 16.184783 -53.602649) (xy 16.176956 -53.548471) (xy 16.176955 -53.493732)
			(xy 16.184783 -53.439554) (xy 16.200277 -53.387053) (xy 16.223119 -53.337307) (xy 16.252839 -53.291338)
			(xy 16.270478 -53.270404) (xy 16.270732 -53.27015) (xy 16.276307 -53.263056) (xy 16.28256 -53.246145)
			(xy 16.282924 -53.23713) (xy 16.282924 -53.170074) (xy 16.282574 -53.161056) (xy 16.276321 -53.14414)
			(xy 16.270732 -53.137054) (xy 16.270478 -53.137054) (xy 16.270478 -53.1368) (xy 16.252822 -53.115882)
			(xy 16.223113 -53.069905) (xy 16.200281 -53.020154) (xy 16.184794 -52.96765) (xy 16.17697 -52.913472)
			(xy 16.176498 -52.886102) (xy 16.176984 -52.858851) (xy 16.18474 -52.804903) (xy 16.200095 -52.752608)
			(xy 16.222737 -52.703031) (xy 16.252203 -52.657181) (xy 16.287894 -52.61599) (xy 16.329085 -52.580299)
			(xy 16.374935 -52.550833) (xy 16.424512 -52.528191) (xy 16.476807 -52.512836) (xy 16.530755 -52.50508)
			(xy 16.585257 -52.50508) (xy 16.639205 -52.512836) (xy 16.6915 -52.528191) (xy 16.7306 -52.546048)
			(xy 21.679696 -52.546048) (xy 21.679696 -52.491552) (xy 21.687451 -52.43761) (xy 21.702804 -52.385321)
			(xy 21.725441 -52.335749) (xy 21.754902 -52.289902) (xy 21.790588 -52.248715) (xy 21.831772 -52.213025)
			(xy 21.877615 -52.183559) (xy 21.927185 -52.160917) (xy 21.979473 -52.145559) (xy 22.033414 -52.137799)
			(xy 22.060662 -52.13731) (xy 22.088032 -52.137796) (xy 22.14221 -52.145609) (xy 22.194713 -52.161093)
			(xy 22.24446 -52.18393) (xy 22.290428 -52.213651) (xy 22.31136 -52.23129) (xy 22.311614 -52.231544)
			(xy 22.318689 -52.237148) (xy 22.335615 -52.243383) (xy 22.344634 -52.243736) (xy 22.41169 -52.243736)
			(xy 22.420705 -52.243366) (xy 22.437622 -52.237127) (xy 22.44471 -52.231544) (xy 22.44471 -52.23129)
			(xy 22.444964 -52.23129) (xy 22.465897 -52.213649) (xy 22.511865 -52.183925) (xy 22.561611 -52.161079)
			(xy 22.614113 -52.145583) (xy 22.668291 -52.137754) (xy 22.723033 -52.137754) (xy 22.777211 -52.145583)
			(xy 22.829713 -52.161079) (xy 22.879459 -52.183925) (xy 22.925427 -52.213649) (xy 22.94636 -52.23129)
			(xy 22.946614 -52.231544) (xy 22.953689 -52.237148) (xy 22.970615 -52.243383) (xy 22.979634 -52.243736)
			(xy 23.04669 -52.243736) (xy 23.055705 -52.243366) (xy 23.072622 -52.237127) (xy 23.07971 -52.231544)
			(xy 23.07971 -52.23129) (xy 23.079964 -52.23129) (xy 23.100898 -52.213653) (xy 23.14687 -52.183941)
			(xy 23.196617 -52.161105) (xy 23.249118 -52.145613) (xy 23.303293 -52.137784) (xy 23.330662 -52.13731)
			(xy 23.357918 -52.137734) (xy 23.411876 -52.145487) (xy 23.464181 -52.160841) (xy 23.513768 -52.183482)
			(xy 23.559628 -52.212951) (xy 23.600827 -52.248646) (xy 23.636527 -52.289842) (xy 23.666 -52.335699)
			(xy 23.688646 -52.385284) (xy 23.704005 -52.437587) (xy 23.711763 -52.491544) (xy 23.711763 -52.546056)
			(xy 23.705819 -52.587398) (xy 24.755346 -52.587398) (xy 24.759417 -52.531776) (xy 24.771543 -52.477339)
			(xy 24.791466 -52.425248) (xy 24.818762 -52.376613) (xy 24.852848 -52.33247) (xy 24.892997 -52.293761)
			(xy 24.938355 -52.26131) (xy 24.987955 -52.235809) (xy 25.040739 -52.217802) (xy 25.095582 -52.207672)
			(xy 25.151316 -52.205635) (xy 25.206753 -52.211735) (xy 25.26071 -52.225841) (xy 25.312039 -52.247653)
			(xy 25.359645 -52.276707) (xy 25.402513 -52.312382) (xy 25.43973 -52.353919) (xy 25.470503 -52.400432)
			(xy 25.494175 -52.450929) (xy 25.510243 -52.504336) (xy 25.517839 -52.555949) (xy 32.583902 -52.555949)
			(xy 32.583902 -52.501451) (xy 32.591658 -52.447509) (xy 32.607011 -52.395219) (xy 32.629649 -52.345646)
			(xy 32.659112 -52.299799) (xy 32.694799 -52.258612) (xy 32.735985 -52.222923) (xy 32.78183 -52.193458)
			(xy 32.831402 -52.170817) (xy 32.883691 -52.155462) (xy 32.937633 -52.147703) (xy 32.964882 -52.147216)
			(xy 32.992252 -52.147689) (xy 33.046431 -52.155504) (xy 33.098934 -52.170992) (xy 33.148681 -52.193832)
			(xy 33.194648 -52.223555) (xy 33.21558 -52.241196) (xy 33.215834 -52.24145) (xy 33.222931 -52.247021)
			(xy 33.23984 -52.253276) (xy 33.248854 -52.253642) (xy 33.31591 -52.253642) (xy 33.324929 -52.253302)
			(xy 33.341846 -52.247044) (xy 33.34893 -52.24145) (xy 33.34893 -52.241196) (xy 33.349184 -52.241196)
			(xy 33.370111 -52.22355) (xy 33.416085 -52.19384) (xy 33.465834 -52.171005) (xy 33.518336 -52.155515)
			(xy 33.572512 -52.147689) (xy 33.599882 -52.147216) (xy 33.627137 -52.14763) (xy 33.681094 -52.155385)
			(xy 33.733397 -52.170741) (xy 33.782983 -52.193383) (xy 33.828841 -52.222853) (xy 33.870038 -52.258549)
			(xy 33.905736 -52.299745) (xy 33.935208 -52.345601) (xy 33.957853 -52.395186) (xy 33.973211 -52.447489)
			(xy 33.980969 -52.501445) (xy 33.980969 -52.555955) (xy 33.973211 -52.609911) (xy 33.957853 -52.662214)
			(xy 33.935208 -52.711799) (xy 33.905736 -52.757655) (xy 33.870038 -52.798851) (xy 33.828841 -52.834547)
			(xy 33.782983 -52.864017) (xy 33.733397 -52.886659) (xy 33.681094 -52.902015) (xy 33.627137 -52.90977)
			(xy 33.599882 -52.910232) (xy 33.572511 -52.909793) (xy 33.51833 -52.901971) (xy 33.465826 -52.886477)
			(xy 33.416079 -52.863629) (xy 33.370114 -52.833897) (xy 33.349184 -52.816252) (xy 33.34893 -52.815998)
			(xy 33.341839 -52.810418) (xy 33.324926 -52.804167) (xy 33.31591 -52.803806) (xy 33.248854 -52.803806)
			(xy 33.23984 -52.804188) (xy 33.222922 -52.810418) (xy 33.215834 -52.815998) (xy 33.215834 -52.816252)
			(xy 33.21558 -52.816252) (xy 33.194622 -52.83386) (xy 33.148657 -52.863578) (xy 33.098916 -52.886421)
			(xy 33.046421 -52.901919) (xy 32.99225 -52.909754) (xy 32.964882 -52.910232) (xy 32.937633 -52.909697)
			(xy 32.883691 -52.901938) (xy 32.831402 -52.886583) (xy 32.78183 -52.863942) (xy 32.735985 -52.834477)
			(xy 32.694799 -52.798788) (xy 32.659112 -52.757601) (xy 32.629649 -52.711754) (xy 32.607011 -52.662181)
			(xy 32.591658 -52.609891) (xy 32.583902 -52.555949) (xy 25.517839 -52.555949) (xy 25.518363 -52.559512)
			(xy 25.518872 -52.587398) (xy 25.518363 -52.615284) (xy 25.510243 -52.67046) (xy 25.494175 -52.723867)
			(xy 25.470503 -52.774364) (xy 25.43973 -52.820877) (xy 25.402513 -52.862414) (xy 25.359645 -52.898089)
			(xy 25.312039 -52.927143) (xy 25.26071 -52.948955) (xy 25.206753 -52.963061) (xy 25.151316 -52.969161)
			(xy 25.095582 -52.967124) (xy 25.040739 -52.956994) (xy 24.987955 -52.938987) (xy 24.938355 -52.913486)
			(xy 24.892997 -52.881035) (xy 24.852848 -52.842326) (xy 24.818762 -52.798183) (xy 24.791466 -52.749548)
			(xy 24.771543 -52.697457) (xy 24.759417 -52.64302) (xy 24.755346 -52.587398) (xy 23.705819 -52.587398)
			(xy 23.704005 -52.600013) (xy 23.688646 -52.652316) (xy 23.666 -52.701901) (xy 23.636527 -52.747758)
			(xy 23.600827 -52.788954) (xy 23.559628 -52.824649) (xy 23.513768 -52.854118) (xy 23.464181 -52.876759)
			(xy 23.411876 -52.892113) (xy 23.357918 -52.899866) (xy 23.330662 -52.900326) (xy 23.303292 -52.899842)
			(xy 23.249113 -52.892031) (xy 23.19661 -52.876547) (xy 23.146862 -52.853709) (xy 23.100895 -52.823987)
			(xy 23.079964 -52.806346) (xy 23.07971 -52.806092) (xy 23.072625 -52.800503) (xy 23.055707 -52.794258)
			(xy 23.04669 -52.7939) (xy 22.979634 -52.7939) (xy 22.970619 -52.794273) (xy 22.953702 -52.800509)
			(xy 22.946614 -52.806092) (xy 22.94636 -52.806346) (xy 22.925427 -52.823987) (xy 22.879459 -52.853711)
			(xy 22.829713 -52.876557) (xy 22.777211 -52.892053) (xy 22.723033 -52.899882) (xy 22.668291 -52.899882)
			(xy 22.614113 -52.892053) (xy 22.561611 -52.876557) (xy 22.511865 -52.853711) (xy 22.465897 -52.823987)
			(xy 22.444964 -52.806346) (xy 22.44471 -52.806092) (xy 22.437625 -52.800503) (xy 22.420707 -52.794258)
			(xy 22.41169 -52.7939) (xy 22.344634 -52.7939) (xy 22.335619 -52.794273) (xy 22.318702 -52.800509)
			(xy 22.311614 -52.806092) (xy 22.311614 -52.806346) (xy 22.31136 -52.806346) (xy 22.290409 -52.823962)
			(xy 22.244442 -52.853679) (xy 22.1947 -52.87652) (xy 22.142203 -52.892017) (xy 22.08803 -52.89985)
			(xy 22.060662 -52.900326) (xy 22.033414 -52.899801) (xy 21.979473 -52.892041) (xy 21.927185 -52.876683)
			(xy 21.877615 -52.854041) (xy 21.831772 -52.824575) (xy 21.790588 -52.788885) (xy 21.754902 -52.747698)
			(xy 21.725441 -52.701851) (xy 21.702804 -52.652279) (xy 21.687451 -52.59999) (xy 21.679696 -52.546048)
			(xy 16.7306 -52.546048) (xy 16.741077 -52.550833) (xy 16.786927 -52.580299) (xy 16.828118 -52.61599)
			(xy 16.863809 -52.657181) (xy 16.893275 -52.703031) (xy 16.915917 -52.752608) (xy 16.931272 -52.804903)
			(xy 16.939028 -52.858851) (xy 16.939514 -52.886102) (xy 16.939046 -52.913472) (xy 16.931228 -52.967651)
			(xy 16.915739 -53.020154) (xy 16.892898 -53.069901) (xy 16.863175 -53.115868) (xy 16.845534 -53.1368)
			(xy 16.84528 -53.137054) (xy 16.839704 -53.144148) (xy 16.833452 -53.161059) (xy 16.833088 -53.170074)
			(xy 16.833088 -53.23713) (xy 16.833434 -53.246148) (xy 16.839689 -53.263065) (xy 16.84528 -53.27015)
			(xy 16.845534 -53.27015) (xy 16.845534 -53.270404) (xy 16.863178 -53.291334) (xy 16.892906 -53.337302)
			(xy 16.915754 -53.387048) (xy 16.931251 -53.439551) (xy 16.939081 -53.49373) (xy 16.93908 -53.548473)
			(xy 16.931251 -53.602652) (xy 16.915753 -53.655155) (xy 16.892905 -53.704901) (xy 16.863176 -53.750868)
			(xy 16.846604 -53.77053) (xy 17.210786 -53.77053) (xy 17.211293 -53.741612) (xy 17.22002 -53.684439)
			(xy 17.237278 -53.629239) (xy 17.262671 -53.577276) (xy 17.295619 -53.529743) (xy 17.335364 -53.487728)
			(xy 17.357852 -53.46954) (xy 17.36664 -53.461915) (xy 17.376832 -53.441027) (xy 17.37741 -53.429408)
			(xy 17.37741 -53.349652) (xy 17.376881 -53.338019) (xy 17.366685 -53.31711) (xy 17.357852 -53.30952)
			(xy 17.335368 -53.29133) (xy 17.295635 -53.249308) (xy 17.262698 -53.201773) (xy 17.23731 -53.149812)
			(xy 17.220053 -53.094615) (xy 17.211322 -53.037446) (xy 17.210786 -53.00853) (xy 17.211283 -52.981278)
			(xy 17.219036 -52.927329) (xy 17.234388 -52.875032) (xy 17.257026 -52.825452) (xy 17.286491 -52.779599)
			(xy 17.322181 -52.738406) (xy 17.36337 -52.702712) (xy 17.409221 -52.673244) (xy 17.458798 -52.6506)
			(xy 17.511094 -52.635244) (xy 17.565042 -52.627486) (xy 17.592294 -52.627022) (xy 17.618608 -52.627486)
			(xy 17.670737 -52.634721) (xy 17.72138 -52.64904) (xy 17.769579 -52.670173) (xy 17.814423 -52.69772)
			(xy 17.855062 -52.73116) (xy 17.873218 -52.750212) (xy 17.880729 -52.757625) (xy 17.900017 -52.766143)
			(xy 17.910556 -52.766722) (xy 17.985232 -52.766722) (xy 17.995778 -52.766163) (xy 18.015073 -52.757648)
			(xy 18.02257 -52.750212) (xy 18.04075 -52.73118) (xy 18.081374 -52.697721) (xy 18.126209 -52.670158)
			(xy 18.174405 -52.649015) (xy 18.225049 -52.634693) (xy 18.277179 -52.627463) (xy 18.303494 -52.627022)
			(xy 18.330748 -52.627461) (xy 18.384701 -52.635218) (xy 18.437002 -52.650575) (xy 18.486584 -52.673219)
			(xy 18.532438 -52.702689) (xy 18.573632 -52.738385) (xy 18.609326 -52.779581) (xy 18.638793 -52.825437)
			(xy 18.661434 -52.875021) (xy 18.676787 -52.927322) (xy 18.684541 -52.981276) (xy 18.685002 -53.00853)
			(xy 18.684512 -53.036196) (xy 18.682281 -53.051456) (xy 26.94127 -53.051456) (xy 26.945341 -52.995834)
			(xy 26.957467 -52.941397) (xy 26.97739 -52.889306) (xy 27.004686 -52.840671) (xy 27.038772 -52.796528)
			(xy 27.078921 -52.757819) (xy 27.124279 -52.725368) (xy 27.173879 -52.699867) (xy 27.226663 -52.68186)
			(xy 27.281506 -52.67173) (xy 27.33724 -52.669693) (xy 27.392677 -52.675793) (xy 27.446634 -52.689899)
			(xy 27.497963 -52.711711) (xy 27.545569 -52.740765) (xy 27.588437 -52.77644) (xy 27.625654 -52.817977)
			(xy 27.656427 -52.86449) (xy 27.680099 -52.914987) (xy 27.696167 -52.968394) (xy 27.704287 -53.02357)
			(xy 27.704796 -53.051456) (xy 27.704287 -53.079342) (xy 27.696167 -53.134518) (xy 27.680099 -53.187925)
			(xy 27.656427 -53.238422) (xy 27.625654 -53.284935) (xy 27.588437 -53.326472) (xy 27.545569 -53.362147)
			(xy 27.497963 -53.391201) (xy 27.446634 -53.413013) (xy 27.392677 -53.427119) (xy 27.33724 -53.433219)
			(xy 27.281506 -53.431182) (xy 27.226663 -53.421052) (xy 27.173879 -53.403045) (xy 27.124279 -53.377544)
			(xy 27.078921 -53.345093) (xy 27.038772 -53.306384) (xy 27.004686 -53.262241) (xy 26.97739 -53.213606)
			(xy 26.957467 -53.161515) (xy 26.945341 -53.107078) (xy 26.94127 -53.051456) (xy 18.682281 -53.051456)
			(xy 18.676509 -53.090946) (xy 18.660688 -53.143968) (xy 18.637381 -53.194152) (xy 18.607077 -53.240448)
			(xy 18.570409 -53.281885) (xy 18.528144 -53.317597) (xy 18.504916 -53.332634) (xy 18.495219 -53.339246)
			(xy 18.482787 -53.359126) (xy 18.48104 -53.370734) (xy 18.473166 -53.450744) (xy 18.47251 -53.462383)
			(xy 18.480606 -53.484222) (xy 18.48866 -53.492654) (xy 18.488914 -53.492908) (xy 18.507484 -53.511)
			(xy 18.540063 -53.55133) (xy 18.566877 -53.595702) (xy 18.587432 -53.643298) (xy 18.601348 -53.69324)
			(xy 18.608368 -53.744608) (xy 18.608802 -53.77053) (xy 18.60835 -53.797782) (xy 18.600589 -53.851732)
			(xy 18.58523 -53.904027) (xy 18.562585 -53.953605) (xy 18.533115 -53.999456) (xy 18.49742 -54.040646)
			(xy 18.456227 -54.076337) (xy 18.410373 -54.105802) (xy 18.360793 -54.128443) (xy 18.308496 -54.143797)
			(xy 18.254546 -54.151553) (xy 18.227294 -54.152038) (xy 18.199923 -54.151591) (xy 18.145742 -54.143771)
			(xy 18.093239 -54.128278) (xy 18.043492 -54.105432) (xy 17.997526 -54.075702) (xy 17.976596 -54.058058)
			(xy 17.976342 -54.057804) (xy 17.969247 -54.052229) (xy 17.952337 -54.045975) (xy 17.943322 -54.045612)
			(xy 17.876266 -54.045612) (xy 17.867247 -54.04595) (xy 17.85033 -54.052211) (xy 17.843246 -54.057804)
			(xy 17.843246 -54.058058) (xy 17.842992 -54.058058) (xy 17.822068 -54.075708) (xy 17.776094 -54.105419)
			(xy 17.726344 -54.128254) (xy 17.673842 -54.143742) (xy 17.619664 -54.151567) (xy 17.592294 -54.152038)
			(xy 17.565044 -54.151528) (xy 17.511099 -54.143771) (xy 17.458806 -54.128417) (xy 17.409231 -54.105777)
			(xy 17.363382 -54.076313) (xy 17.322193 -54.040624) (xy 17.286501 -53.999437) (xy 17.257034 -53.95359)
			(xy 17.234391 -53.904016) (xy 17.219034 -53.851725) (xy 17.211274 -53.79778) (xy 17.210786 -53.77053)
			(xy 16.846604 -53.77053) (xy 16.845534 -53.7718) (xy 16.84528 -53.772054) (xy 16.839704 -53.779148)
			(xy 16.833452 -53.796059) (xy 16.833088 -53.805074) (xy 16.833088 -53.87213) (xy 16.833434 -53.881148)
			(xy 16.839689 -53.898065) (xy 16.84528 -53.90515) (xy 16.845534 -53.90515) (xy 16.845534 -53.905404)
			(xy 16.863178 -53.926334) (xy 16.892906 -53.972302) (xy 16.915754 -54.022048) (xy 16.931251 -54.074551)
			(xy 16.939081 -54.12873) (xy 16.93908 -54.183473) (xy 16.931251 -54.237652) (xy 16.915753 -54.290155)
			(xy 16.90196 -54.320186) (xy 19.130518 -54.320186) (xy 19.130971 -54.292815) (xy 19.138792 -54.238635)
			(xy 19.154283 -54.186132) (xy 19.177128 -54.136385) (xy 19.206855 -54.090419) (xy 19.224498 -54.069488)
			(xy 19.224752 -54.069234) (xy 19.230337 -54.062146) (xy 19.236583 -54.04523) (xy 19.236944 -54.036214)
			(xy 19.236944 -53.969158) (xy 19.236572 -53.960142) (xy 19.230336 -53.943225) (xy 19.224752 -53.936138)
			(xy 19.224498 -53.936138) (xy 19.224498 -53.935884) (xy 19.206885 -53.914931) (xy 19.177169 -53.868964)
			(xy 19.154328 -53.819222) (xy 19.138831 -53.766726) (xy 19.130996 -53.712554) (xy 19.130518 -53.685186)
			(xy 19.131004 -53.657935) (xy 19.13876 -53.603987) (xy 19.154115 -53.551692) (xy 19.176757 -53.502115)
			(xy 19.206223 -53.456265) (xy 19.241914 -53.415074) (xy 19.283105 -53.379383) (xy 19.328955 -53.349917)
			(xy 19.378532 -53.327275) (xy 19.430827 -53.31192) (xy 19.484775 -53.304164) (xy 19.539277 -53.304164)
			(xy 19.593225 -53.31192) (xy 19.64552 -53.327275) (xy 19.695097 -53.349917) (xy 19.740947 -53.379383)
			(xy 19.782138 -53.415074) (xy 19.817829 -53.456265) (xy 19.843722 -53.496556) (xy 32.133441 -53.496556)
			(xy 32.133441 -53.442044) (xy 32.141199 -53.388088) (xy 32.156558 -53.335785) (xy 32.179204 -53.2862)
			(xy 32.208677 -53.240343) (xy 32.244376 -53.199148) (xy 32.285575 -53.163453) (xy 32.331435 -53.133985)
			(xy 32.381022 -53.111344) (xy 32.433327 -53.095991) (xy 32.487284 -53.088238) (xy 32.51454 -53.087778)
			(xy 32.54191 -53.08826) (xy 32.596089 -53.096071) (xy 32.648593 -53.111555) (xy 32.69834 -53.134394)
			(xy 32.744307 -53.164117) (xy 32.765238 -53.181758) (xy 32.765492 -53.182012) (xy 32.772576 -53.187603)
			(xy 32.789495 -53.193847) (xy 32.798512 -53.194204) (xy 32.865568 -53.194204) (xy 32.874583 -53.193831)
			(xy 32.8915 -53.187594) (xy 32.898588 -53.182012) (xy 32.898588 -53.181758) (xy 32.898842 -53.181758)
			(xy 32.919779 -53.164126) (xy 32.965751 -53.134414) (xy 33.015498 -53.111578) (xy 33.067997 -53.096085)
			(xy 33.122171 -53.088253) (xy 33.14954 -53.087778) (xy 33.176788 -53.088295) (xy 33.23073 -53.096056)
			(xy 33.283018 -53.111414) (xy 33.332588 -53.134056) (xy 33.378432 -53.163523) (xy 33.419616 -53.199213)
			(xy 33.455301 -53.2404) (xy 33.484763 -53.286247) (xy 33.5074 -53.33582) (xy 33.522753 -53.388109)
			(xy 33.530508 -53.442052) (xy 33.530508 -53.496548) (xy 33.522753 -53.550491) (xy 33.5074 -53.60278)
			(xy 33.484763 -53.652353) (xy 33.455301 -53.6982) (xy 33.419616 -53.739387) (xy 33.378432 -53.775077)
			(xy 33.332588 -53.804544) (xy 33.283018 -53.827186) (xy 33.23073 -53.842544) (xy 33.176788 -53.850305)
			(xy 33.14954 -53.850794) (xy 33.122171 -53.850306) (xy 33.067992 -53.842494) (xy 33.015489 -53.82701)
			(xy 32.965742 -53.804173) (xy 32.919774 -53.774453) (xy 32.898842 -53.756814) (xy 32.898588 -53.75656)
			(xy 32.891513 -53.750957) (xy 32.874587 -53.744721) (xy 32.865568 -53.744368) (xy 32.798512 -53.744368)
			(xy 32.789497 -53.744738) (xy 32.77258 -53.750977) (xy 32.765492 -53.75656) (xy 32.765492 -53.756814)
			(xy 32.765238 -53.756814) (xy 32.744304 -53.774451) (xy 32.698332 -53.804163) (xy 32.648585 -53.826999)
			(xy 32.596084 -53.84249) (xy 32.541909 -53.850319) (xy 32.51454 -53.850794) (xy 32.487284 -53.850362)
			(xy 32.433327 -53.842609) (xy 32.381022 -53.827256) (xy 32.331435 -53.804615) (xy 32.285575 -53.775147)
			(xy 32.244376 -53.739452) (xy 32.208677 -53.698257) (xy 32.179204 -53.6524) (xy 32.156558 -53.602815)
			(xy 32.141199 -53.550512) (xy 32.133441 -53.496556) (xy 19.843722 -53.496556) (xy 19.847295 -53.502115)
			(xy 19.869937 -53.551692) (xy 19.885292 -53.603987) (xy 19.893048 -53.657935) (xy 19.893534 -53.685186)
			(xy 19.893076 -53.712557) (xy 19.885259 -53.766737) (xy 19.869769 -53.819241) (xy 19.846925 -53.868987)
			(xy 19.817197 -53.914953) (xy 19.799554 -53.935884) (xy 19.7993 -53.936138) (xy 19.793733 -53.943238)
			(xy 19.787475 -53.960145) (xy 19.787108 -53.969158) (xy 19.787108 -54.036214) (xy 19.787457 -54.045232)
			(xy 19.79371 -54.062149) (xy 19.7993 -54.069234) (xy 19.799554 -54.069234) (xy 19.799554 -54.069488)
			(xy 19.817194 -54.09042) (xy 19.846907 -54.136392) (xy 19.869744 -54.186139) (xy 19.885234 -54.23864)
			(xy 19.893061 -54.292817) (xy 19.893534 -54.320186) (xy 19.893048 -54.347437) (xy 19.885292 -54.401385)
			(xy 19.869937 -54.45368) (xy 19.847295 -54.503257) (xy 19.817829 -54.549107) (xy 19.782138 -54.590298)
			(xy 19.740947 -54.625989) (xy 19.695097 -54.655455) (xy 19.64552 -54.678097) (xy 19.593225 -54.693452)
			(xy 19.539277 -54.701208) (xy 19.484775 -54.701208) (xy 19.430827 -54.693452) (xy 19.378532 -54.678097)
			(xy 19.328955 -54.655455) (xy 19.283105 -54.625989) (xy 19.241914 -54.590298) (xy 19.206223 -54.549107)
			(xy 19.176757 -54.503257) (xy 19.154115 -54.45368) (xy 19.13876 -54.401385) (xy 19.131004 -54.347437)
			(xy 19.130518 -54.320186) (xy 16.90196 -54.320186) (xy 16.892905 -54.339901) (xy 16.863176 -54.385868)
			(xy 16.845534 -54.4068) (xy 16.84528 -54.407054) (xy 16.839704 -54.414148) (xy 16.833452 -54.431059)
			(xy 16.833088 -54.440074) (xy 16.833088 -54.50713) (xy 16.833434 -54.516148) (xy 16.839689 -54.533065)
			(xy 16.84528 -54.54015) (xy 16.845534 -54.54015) (xy 16.845534 -54.540404) (xy 16.863194 -54.561319)
			(xy 16.892901 -54.607297) (xy 16.915733 -54.657049) (xy 16.931219 -54.709553) (xy 16.939042 -54.763732)
			(xy 16.939159 -54.770528) (xy 20.07108 -54.770528) (xy 20.071543 -54.743157) (xy 20.079359 -54.688977)
			(xy 20.094847 -54.636474) (xy 20.11769 -54.586727) (xy 20.147417 -54.540761) (xy 20.16506 -54.51983)
			(xy 20.165314 -54.519576) (xy 20.170918 -54.512502) (xy 20.177154 -54.495575) (xy 20.177506 -54.486556)
			(xy 20.177506 -54.4195) (xy 20.177148 -54.410483) (xy 20.170901 -54.393566) (xy 20.165314 -54.38648)
			(xy 20.16506 -54.38648) (xy 20.16506 -54.386226) (xy 20.147413 -54.3653) (xy 20.117704 -54.319325)
			(xy 20.09487 -54.269576) (xy 20.07938 -54.217074) (xy 20.071553 -54.162898) (xy 20.07108 -54.135528)
			(xy 20.071566 -54.108277) (xy 20.079322 -54.054329) (xy 20.094677 -54.002034) (xy 20.117319 -53.952457)
			(xy 20.146785 -53.906607) (xy 20.182476 -53.865416) (xy 20.223667 -53.829725) (xy 20.269517 -53.800259)
			(xy 20.319094 -53.777617) (xy 20.371389 -53.762262) (xy 20.425337 -53.754506) (xy 20.479839 -53.754506)
			(xy 20.533787 -53.762262) (xy 20.586082 -53.777617) (xy 20.635659 -53.800259) (xy 20.681509 -53.829725)
			(xy 20.7227 -53.865416) (xy 20.758391 -53.906607) (xy 20.787857 -53.952457) (xy 20.792932 -53.96357)
			(xy 24.77211 -53.96357) (xy 24.776181 -53.907948) (xy 24.788307 -53.853511) (xy 24.80823 -53.80142)
			(xy 24.835526 -53.752785) (xy 24.869612 -53.708642) (xy 24.909761 -53.669933) (xy 24.955119 -53.637482)
			(xy 25.004719 -53.611981) (xy 25.057503 -53.593974) (xy 25.112346 -53.583844) (xy 25.16808 -53.581807)
			(xy 25.223517 -53.587907) (xy 25.277474 -53.602013) (xy 25.328803 -53.623825) (xy 25.376409 -53.652879)
			(xy 25.419277 -53.688554) (xy 25.456494 -53.730091) (xy 25.487267 -53.776604) (xy 25.510939 -53.827101)
			(xy 25.527007 -53.880508) (xy 25.535127 -53.935684) (xy 25.535636 -53.96357) (xy 25.535127 -53.991456)
			(xy 25.527007 -54.046632) (xy 25.510939 -54.100039) (xy 25.487267 -54.150536) (xy 25.456494 -54.197049)
			(xy 25.419277 -54.238586) (xy 25.376409 -54.274261) (xy 25.328803 -54.303315) (xy 25.277474 -54.325127)
			(xy 25.223517 -54.339233) (xy 25.16808 -54.345333) (xy 25.112346 -54.343296) (xy 25.057503 -54.333166)
			(xy 25.004719 -54.315159) (xy 24.955119 -54.289658) (xy 24.909761 -54.257207) (xy 24.869612 -54.218498)
			(xy 24.835526 -54.174355) (xy 24.80823 -54.12572) (xy 24.788307 -54.073629) (xy 24.776181 -54.019192)
			(xy 24.77211 -53.96357) (xy 20.792932 -53.96357) (xy 20.810499 -54.002034) (xy 20.825854 -54.054329)
			(xy 20.83361 -54.108277) (xy 20.834096 -54.135528) (xy 20.833647 -54.162899) (xy 20.825825 -54.217079)
			(xy 20.810332 -54.269582) (xy 20.787487 -54.319329) (xy 20.757759 -54.365295) (xy 20.740116 -54.386226)
			(xy 20.739862 -54.38648) (xy 20.734273 -54.393565) (xy 20.728029 -54.410483) (xy 20.72767 -54.4195)
			(xy 20.72767 -54.486556) (xy 20.728055 -54.49557) (xy 20.734284 -54.512487) (xy 20.739862 -54.519576)
			(xy 20.740116 -54.519576) (xy 20.740116 -54.51983) (xy 20.757738 -54.540776) (xy 20.787452 -54.586745)
			(xy 20.810291 -54.636489) (xy 20.825786 -54.688987) (xy 20.833619 -54.74316) (xy 20.834096 -54.770528)
			(xy 20.83361 -54.797779) (xy 20.825854 -54.851727) (xy 20.810499 -54.904022) (xy 20.787857 -54.953599)
			(xy 20.765071 -54.989055) (xy 29.901045 -54.989055) (xy 29.901045 -54.934545) (xy 29.908803 -54.880589)
			(xy 29.924161 -54.828287) (xy 29.946807 -54.778704) (xy 29.976279 -54.732848) (xy 30.011977 -54.691653)
			(xy 30.053175 -54.655958) (xy 30.099034 -54.62649) (xy 30.148619 -54.603849) (xy 30.200923 -54.588496)
			(xy 30.254879 -54.580743) (xy 30.282134 -54.580282) (xy 30.310226 -54.58075) (xy 30.365805 -54.588982)
			(xy 30.419575 -54.605278) (xy 30.470372 -54.629285) (xy 30.517098 -54.660484) (xy 30.558743 -54.698199)
			(xy 30.594404 -54.741616) (xy 30.609286 -54.765448) (xy 30.61462 -54.774338) (xy 30.631638 -54.78653)
			(xy 30.724856 -54.80685) (xy 30.74543 -54.802532) (xy 30.754066 -54.79669) (xy 30.778137 -54.780701)
			(xy 30.830066 -54.755356) (xy 30.885222 -54.738127) (xy 30.942344 -54.729409) (xy 30.971236 -54.728872)
			(xy 30.998487 -54.729344) (xy 31.052434 -54.737105) (xy 31.104728 -54.752464) (xy 31.154304 -54.775108)
			(xy 31.200153 -54.804576) (xy 31.241343 -54.840269) (xy 31.277034 -54.881459) (xy 31.3065 -54.92731)
			(xy 31.329142 -54.976887) (xy 31.344498 -55.029181) (xy 31.352257 -55.083129) (xy 31.352744 -55.11038)
			(xy 31.35228 -55.13775) (xy 31.344464 -55.19193) (xy 31.328975 -55.244434) (xy 31.306132 -55.294181)
			(xy 31.276406 -55.340147) (xy 31.258764 -55.361078) (xy 31.25851 -55.361332) (xy 31.252947 -55.368435)
			(xy 31.246686 -55.385339) (xy 31.246318 -55.394352) (xy 31.246318 -55.461408) (xy 31.246667 -55.470426)
			(xy 31.25292 -55.487343) (xy 31.25851 -55.494428) (xy 31.258764 -55.494428) (xy 31.258764 -55.494682)
			(xy 31.276385 -55.51563) (xy 31.306112 -55.561595) (xy 31.328959 -55.611339) (xy 31.344457 -55.663839)
			(xy 31.352288 -55.718015) (xy 31.35229 -55.772755) (xy 31.344463 -55.826932) (xy 31.328969 -55.879433)
			(xy 31.306126 -55.929178) (xy 31.276404 -55.975145) (xy 31.258764 -55.996078) (xy 31.25851 -55.996332)
			(xy 31.252947 -56.003435) (xy 31.246686 -56.020339) (xy 31.246318 -56.029352) (xy 31.246318 -56.096408)
			(xy 31.246667 -56.105426) (xy 31.25292 -56.122343) (xy 31.25851 -56.129428) (xy 31.258764 -56.129428)
			(xy 31.258764 -56.129682) (xy 31.276403 -56.150615) (xy 31.306116 -56.196587) (xy 31.328952 -56.246334)
			(xy 31.344443 -56.298835) (xy 31.352271 -56.353011) (xy 31.352744 -56.38038) (xy 31.352258 -56.407631)
			(xy 31.344502 -56.461579) (xy 31.329147 -56.513874) (xy 31.306505 -56.563451) (xy 31.277039 -56.609301)
			(xy 31.241348 -56.650492) (xy 31.200157 -56.686183) (xy 31.154307 -56.715649) (xy 31.10473 -56.738291)
			(xy 31.052435 -56.753646) (xy 30.998487 -56.761402) (xy 30.943985 -56.761402) (xy 30.890037 -56.753646)
			(xy 30.837742 -56.738291) (xy 30.788165 -56.715649) (xy 30.742315 -56.686183) (xy 30.701124 -56.650492)
			(xy 30.665433 -56.609301) (xy 30.635967 -56.563451) (xy 30.613325 -56.513874) (xy 30.59797 -56.461579)
			(xy 30.590214 -56.407631) (xy 30.589728 -56.38038) (xy 30.590176 -56.353009) (xy 30.597997 -56.298829)
			(xy 30.61349 -56.246325) (xy 30.636336 -56.196579) (xy 30.666065 -56.150613) (xy 30.683708 -56.129682)
			(xy 30.683962 -56.129428) (xy 30.68955 -56.122343) (xy 30.695794 -56.105425) (xy 30.696154 -56.096408)
			(xy 30.696154 -56.029352) (xy 30.695782 -56.020336) (xy 30.689546 -56.003419) (xy 30.683962 -55.996332)
			(xy 30.683708 -55.996332) (xy 30.683708 -55.996078) (xy 30.666049 -55.975161) (xy 30.636326 -55.92919)
			(xy 30.613483 -55.879441) (xy 30.597989 -55.826937) (xy 30.590163 -55.772756) (xy 30.590165 -55.718014)
			(xy 30.597995 -55.663834) (xy 30.613494 -55.611331) (xy 30.63634 -55.561584) (xy 30.666067 -55.515615)
			(xy 30.683708 -55.494682) (xy 30.683962 -55.494428) (xy 30.68955 -55.487343) (xy 30.695794 -55.470425)
			(xy 30.696154 -55.461408) (xy 30.696154 -55.394352) (xy 30.695782 -55.385336) (xy 30.689546 -55.368419)
			(xy 30.683962 -55.361332) (xy 30.683708 -55.360824) (xy 30.672765 -55.348089) (xy 30.652923 -55.320998)
			(xy 30.644084 -55.306722) (xy 30.63875 -55.297832) (xy 30.621732 -55.28564) (xy 30.528514 -55.26532)
			(xy 30.50794 -55.269638) (xy 30.499304 -55.27548) (xy 30.475239 -55.291478) (xy 30.423308 -55.316822)
			(xy 30.368151 -55.334048) (xy 30.311026 -55.342763) (xy 30.282134 -55.343298) (xy 30.254879 -55.342857)
			(xy 30.200923 -55.335104) (xy 30.148619 -55.319751) (xy 30.099034 -55.29711) (xy 30.053175 -55.267642)
			(xy 30.011977 -55.231947) (xy 29.976279 -55.190752) (xy 29.946807 -55.144896) (xy 29.924161 -55.095313)
			(xy 29.908803 -55.043011) (xy 29.901045 -54.989055) (xy 20.765071 -54.989055) (xy 20.758391 -54.999449)
			(xy 20.7227 -55.04064) (xy 20.681509 -55.076331) (xy 20.635659 -55.105797) (xy 20.586082 -55.128439)
			(xy 20.533787 -55.143794) (xy 20.479839 -55.15155) (xy 20.425337 -55.15155) (xy 20.371389 -55.143794)
			(xy 20.319094 -55.128439) (xy 20.269517 -55.105797) (xy 20.223667 -55.076331) (xy 20.182476 -55.04064)
			(xy 20.146785 -54.999449) (xy 20.117319 -54.953599) (xy 20.094677 -54.904022) (xy 20.079322 -54.851727)
			(xy 20.071566 -54.797779) (xy 20.07108 -54.770528) (xy 16.939159 -54.770528) (xy 16.939514 -54.791102)
			(xy 16.939028 -54.818353) (xy 16.931272 -54.872301) (xy 16.915917 -54.924596) (xy 16.893275 -54.974173)
			(xy 16.863809 -55.020023) (xy 16.828118 -55.061214) (xy 16.786927 -55.096905) (xy 16.741077 -55.126371)
			(xy 16.6915 -55.149013) (xy 16.639205 -55.164368) (xy 16.585257 -55.172124) (xy 16.530755 -55.172124)
			(xy 16.476807 -55.164368) (xy 16.424512 -55.149013) (xy 16.374935 -55.126371) (xy 16.329085 -55.096905)
			(xy 16.287894 -55.061214) (xy 16.252203 -55.020023) (xy 16.222737 -54.974173) (xy 16.200095 -54.924596)
			(xy 16.18474 -54.872301) (xy 16.176984 -54.818353) (xy 16.176498 -54.791102) (xy 14.27854 -54.791102)
			(xy 14.275448 -54.812611) (xy 14.260093 -54.864906) (xy 14.237451 -54.914483) (xy 14.207985 -54.960333)
			(xy 14.172294 -55.001524) (xy 14.131103 -55.037215) (xy 14.085253 -55.066681) (xy 14.035676 -55.089323)
			(xy 13.983381 -55.104678) (xy 13.929433 -55.112434) (xy 13.874931 -55.112434) (xy 13.820983 -55.104678)
			(xy 13.768688 -55.089323) (xy 13.719111 -55.066681) (xy 13.673261 -55.037215) (xy 13.63207 -55.001524)
			(xy 13.596379 -54.960333) (xy 13.566913 -54.914483) (xy 13.544271 -54.864906) (xy 13.528916 -54.812611)
			(xy 13.52116 -54.758663) (xy 13.520674 -54.731412) (xy 5.012973 -54.731412) (xy 5.052492 -54.737094)
			(xy 5.104789 -54.75245) (xy 5.15437 -54.775092) (xy 5.200223 -54.80456) (xy 5.241415 -54.840253)
			(xy 5.277109 -54.881446) (xy 5.306577 -54.927299) (xy 5.32922 -54.976879) (xy 5.344576 -55.029176)
			(xy 5.352333 -55.083127) (xy 5.352796 -55.11038) (xy 5.352319 -55.13775) (xy 5.344504 -55.191929)
			(xy 5.329018 -55.244432) (xy 5.306178 -55.294179) (xy 5.276456 -55.340146) (xy 5.258816 -55.361078)
			(xy 5.258562 -55.361332) (xy 5.252994 -55.368431) (xy 5.246737 -55.385338) (xy 5.24637 -55.394352)
			(xy 5.24637 -55.461408) (xy 5.24673 -55.470424) (xy 5.252976 -55.487341) (xy 5.258562 -55.494428)
			(xy 5.258816 -55.494428) (xy 5.258816 -55.494682) (xy 5.276457 -55.515615) (xy 5.306181 -55.561583)
			(xy 5.329026 -55.611329) (xy 5.344522 -55.663831) (xy 5.352351 -55.718009) (xy 5.352351 -55.722266)
			(xy 25.834084 -55.722266) (xy 25.838155 -55.666644) (xy 25.850281 -55.612207) (xy 25.870204 -55.560116)
			(xy 25.8975 -55.511481) (xy 25.931586 -55.467338) (xy 25.971735 -55.428629) (xy 26.017093 -55.396178)
			(xy 26.066693 -55.370677) (xy 26.119477 -55.35267) (xy 26.17432 -55.34254) (xy 26.230054 -55.340503)
			(xy 26.285491 -55.346603) (xy 26.339448 -55.360709) (xy 26.390777 -55.382521) (xy 26.438383 -55.411575)
			(xy 26.449534 -55.420855) (xy 28.224645 -55.420855) (xy 28.224645 -55.366345) (xy 28.232403 -55.312389)
			(xy 28.247761 -55.260087) (xy 28.270407 -55.210504) (xy 28.299879 -55.164648) (xy 28.335577 -55.123453)
			(xy 28.376775 -55.087758) (xy 28.422634 -55.05829) (xy 28.472219 -55.035649) (xy 28.524523 -55.020296)
			(xy 28.578479 -55.012543) (xy 28.605734 -55.012082) (xy 28.632048 -55.012533) (xy 28.684177 -55.019772)
			(xy 28.73482 -55.034094) (xy 28.783019 -55.05523) (xy 28.827862 -55.082779) (xy 28.868502 -55.11622)
			(xy 28.886658 -55.135272) (xy 28.894197 -55.142653) (xy 28.913464 -55.15119) (xy 28.923996 -55.151782)
			(xy 28.998672 -55.151782) (xy 29.009222 -55.151257) (xy 29.028518 -55.142719) (xy 29.03601 -55.135272)
			(xy 29.054162 -55.116213) (xy 29.094793 -55.082757) (xy 29.139634 -55.0552) (xy 29.187836 -55.034062)
			(xy 29.238484 -55.019745) (xy 29.290618 -55.012521) (xy 29.316934 -55.012082) (xy 29.344183 -55.012591)
			(xy 29.398125 -55.020351) (xy 29.450415 -55.035708) (xy 29.499986 -55.058351) (xy 29.545831 -55.087817)
			(xy 29.587016 -55.123508) (xy 29.622703 -55.164696) (xy 29.652165 -55.210544) (xy 29.674803 -55.260117)
			(xy 29.690156 -55.312408) (xy 29.697912 -55.366351) (xy 29.697912 -55.420849) (xy 29.690156 -55.474792)
			(xy 29.674803 -55.527083) (xy 29.652165 -55.576656) (xy 29.622703 -55.622504) (xy 29.587016 -55.663692)
			(xy 29.545831 -55.699383) (xy 29.499986 -55.728849) (xy 29.450415 -55.751492) (xy 29.398125 -55.766849)
			(xy 29.344183 -55.774609) (xy 29.316934 -55.775098) (xy 29.290619 -55.774675) (xy 29.238488 -55.767431)
			(xy 29.187844 -55.753104) (xy 29.139646 -55.731963) (xy 29.094803 -55.704409) (xy 29.054165 -55.670963)
			(xy 29.03601 -55.651908) (xy 29.028485 -55.64451) (xy 29.009208 -55.635983) (xy 28.998672 -55.635398)
			(xy 28.923996 -55.635398) (xy 28.913445 -55.635912) (xy 28.894149 -55.644458) (xy 28.886658 -55.651908)
			(xy 28.868517 -55.670978) (xy 28.827884 -55.704434) (xy 28.783041 -55.731991) (xy 28.734837 -55.753127)
			(xy 28.684187 -55.767441) (xy 28.632051 -55.774662) (xy 28.605734 -55.775098) (xy 28.578479 -55.774657)
			(xy 28.524523 -55.766904) (xy 28.472219 -55.751551) (xy 28.422634 -55.72891) (xy 28.376775 -55.699442)
			(xy 28.335577 -55.663747) (xy 28.299879 -55.622552) (xy 28.270407 -55.576696) (xy 28.247761 -55.527113)
			(xy 28.232403 -55.474811) (xy 28.224645 -55.420855) (xy 26.449534 -55.420855) (xy 26.481251 -55.44725)
			(xy 26.518468 -55.488787) (xy 26.549241 -55.5353) (xy 26.572913 -55.585797) (xy 26.588981 -55.639204)
			(xy 26.597101 -55.69438) (xy 26.59761 -55.722266) (xy 26.597101 -55.750152) (xy 26.588981 -55.805328)
			(xy 26.572913 -55.858735) (xy 26.549241 -55.909232) (xy 26.518468 -55.955745) (xy 26.481251 -55.997282)
			(xy 26.438383 -56.032957) (xy 26.390777 -56.062011) (xy 26.339448 -56.083823) (xy 26.285491 -56.097929)
			(xy 26.230054 -56.104029) (xy 26.17432 -56.101992) (xy 26.119477 -56.091862) (xy 26.066693 -56.073855)
			(xy 26.017093 -56.048354) (xy 25.971735 -56.015903) (xy 25.931586 -55.977194) (xy 25.8975 -55.933051)
			(xy 25.870204 -55.884416) (xy 25.850281 -55.832325) (xy 25.838155 -55.777888) (xy 25.834084 -55.722266)
			(xy 5.352351 -55.722266) (xy 5.352351 -55.772751) (xy 5.344522 -55.826929) (xy 5.329026 -55.879431)
			(xy 5.306181 -55.929177) (xy 5.276457 -55.975145) (xy 5.258816 -55.996078) (xy 5.258562 -55.996332)
			(xy 5.252994 -56.003431) (xy 5.246737 -56.020338) (xy 5.24637 -56.029352) (xy 5.24637 -56.096408)
			(xy 5.24673 -56.105424) (xy 5.252976 -56.122341) (xy 5.258562 -56.129428) (xy 5.258816 -56.129428)
			(xy 5.258816 -56.129682) (xy 5.276463 -56.150608) (xy 5.306173 -56.196583) (xy 5.329007 -56.246332)
			(xy 5.344496 -56.298834) (xy 5.352323 -56.35301) (xy 5.352796 -56.38038) (xy 5.35231 -56.407631)
			(xy 5.344554 -56.461579) (xy 5.329199 -56.513874) (xy 5.306557 -56.563451) (xy 5.277091 -56.609301)
			(xy 5.2414 -56.650492) (xy 5.200209 -56.686183) (xy 5.154359 -56.715649) (xy 5.104782 -56.738291)
			(xy 5.052487 -56.753646) (xy 4.998539 -56.761402) (xy 4.944037 -56.761402) (xy 4.890089 -56.753646)
			(xy 4.837794 -56.738291) (xy 4.788217 -56.715649) (xy 4.742367 -56.686183) (xy 4.701176 -56.650492)
			(xy 4.665485 -56.609301) (xy 4.636019 -56.563451) (xy 4.613377 -56.513874) (xy 4.598022 -56.461579)
			(xy 4.590266 -56.407631) (xy 4.58978 -56.38038) (xy 4.590215 -56.353008) (xy 4.598037 -56.298827)
			(xy 4.613533 -56.246323) (xy 4.636382 -56.196577) (xy 4.666114 -56.150612) (xy 4.68376 -56.129682)
			(xy 4.684014 -56.129428) (xy 4.689597 -56.122339) (xy 4.695845 -56.105424) (xy 4.696206 -56.096408)
			(xy 4.696206 -56.029352) (xy 4.695823 -56.020338) (xy 4.689593 -56.003421) (xy 4.684014 -55.996332)
			(xy 4.68376 -55.996332) (xy 4.68376 -55.996078) (xy 4.666119 -55.975145) (xy 4.636394 -55.929178)
			(xy 4.613549 -55.879431) (xy 4.598052 -55.826929) (xy 4.590224 -55.772751) (xy 4.590224 -55.718009)
			(xy 4.598052 -55.663831) (xy 4.613549 -55.611329) (xy 4.636394 -55.561582) (xy 4.666119 -55.515615)
			(xy 4.68376 -55.494682) (xy 4.684014 -55.494428) (xy 4.689597 -55.487339) (xy 4.695845 -55.470424)
			(xy 4.696206 -55.461408) (xy 4.696206 -55.394352) (xy 4.695823 -55.385338) (xy 4.689593 -55.368421)
			(xy 4.684014 -55.361332) (xy 4.68376 -55.360824) (xy 4.672814 -55.348091) (xy 4.652974 -55.320999)
			(xy 4.644136 -55.306722) (xy 4.638802 -55.297832) (xy 4.621784 -55.28564) (xy 4.528566 -55.26532)
			(xy 4.507992 -55.269638) (xy 4.499356 -55.27548) (xy 4.475304 -55.291499) (xy 4.423368 -55.316838)
			(xy 4.368207 -55.334058) (xy 4.31108 -55.342767) (xy 4.282186 -55.343298) (xy 4.254935 -55.342812)
			(xy 4.200988 -55.335055) (xy 4.148693 -55.319699) (xy 4.099117 -55.297058) (xy 4.053267 -55.267592)
			(xy 4.012077 -55.2319) (xy 3.976386 -55.19071) (xy 3.94692 -55.14486) (xy 3.924279 -55.095283) (xy 3.908924 -55.042988)
			(xy 3.901168 -54.989041) (xy 1.306576 -54.989041) (xy 1.306576 -55.420841) (xy 2.224768 -55.420841)
			(xy 2.224768 -55.366339) (xy 2.232524 -55.312392) (xy 2.247879 -55.260097) (xy 2.27052 -55.21052)
			(xy 2.299986 -55.16467) (xy 2.335677 -55.12348) (xy 2.376867 -55.087788) (xy 2.422717 -55.058322)
			(xy 2.472293 -55.035681) (xy 2.524588 -55.020325) (xy 2.578535 -55.012568) (xy 2.605786 -55.012082)
			(xy 2.632099 -55.012565) (xy 2.684227 -55.019797) (xy 2.734869 -55.034114) (xy 2.783068 -55.055243)
			(xy 2.827912 -55.082786) (xy 2.868553 -55.116222) (xy 2.88671 -55.135272) (xy 2.89423 -55.142676)
			(xy 2.913511 -55.1512) (xy 2.924048 -55.151782) (xy 2.998724 -55.151782) (xy 3.009271 -55.151231)
			(xy 3.028567 -55.142712) (xy 3.036062 -55.135272) (xy 3.054189 -55.116188) (xy 3.094825 -55.082735)
			(xy 3.139672 -55.05518) (xy 3.187878 -55.034047) (xy 3.23853 -55.019735) (xy 3.290668 -55.012517)
			(xy 3.316986 -55.012082) (xy 3.344239 -55.012545) (xy 3.39819 -55.020302) (xy 3.450489 -55.035657)
			(xy 3.500069 -55.0583) (xy 3.545923 -55.087767) (xy 3.587116 -55.123461) (xy 3.62281 -55.164654)
			(xy 3.652279 -55.210507) (xy 3.674921 -55.260088) (xy 3.690278 -55.312386) (xy 3.698035 -55.366337)
			(xy 3.698035 -55.420843) (xy 3.690278 -55.474794) (xy 3.674921 -55.527092) (xy 3.652279 -55.576673)
			(xy 3.62281 -55.622526) (xy 3.587116 -55.663719) (xy 3.545923 -55.699413) (xy 3.500069 -55.72888)
			(xy 3.450489 -55.751523) (xy 3.39819 -55.766878) (xy 3.344239 -55.774635) (xy 3.316986 -55.775098)
			(xy 3.290672 -55.774641) (xy 3.238543 -55.767404) (xy 3.1879 -55.753083) (xy 3.139701 -55.731948)
			(xy 3.094858 -55.704401) (xy 3.054218 -55.67096) (xy 3.036062 -55.651908) (xy 3.028555 -55.644489)
			(xy 3.009264 -55.635974) (xy 2.998724 -55.635398) (xy 2.924048 -55.635398) (xy 2.9135 -55.63594)
			(xy 2.894204 -55.644466) (xy 2.88671 -55.651908) (xy 2.868544 -55.670953) (xy 2.827916 -55.704411)
			(xy 2.783078 -55.731971) (xy 2.73488 -55.753111) (xy 2.684234 -55.767431) (xy 2.632102 -55.774658)
			(xy 2.605786 -55.775098) (xy 2.578535 -55.774612) (xy 2.524588 -55.766855) (xy 2.472293 -55.751499)
			(xy 2.422717 -55.728858) (xy 2.376867 -55.699392) (xy 2.335677 -55.6637) (xy 2.299986 -55.62251)
			(xy 2.27052 -55.57666) (xy 2.247879 -55.527083) (xy 2.232524 -55.474788) (xy 2.224768 -55.420841)
			(xy 1.306576 -55.420841) (xy 1.306576 -57.002934) (xy 21.563584 -57.002934) (xy 21.564105 -56.974843)
			(xy 21.572327 -56.919267) (xy 21.588614 -56.865499) (xy 21.612612 -56.814702) (xy 21.643803 -56.767974)
			(xy 21.681511 -56.726329) (xy 21.724921 -56.690665) (xy 21.74875 -56.675782) (xy 21.75764 -56.670448)
			(xy 21.769832 -56.65343) (xy 21.790152 -56.560212) (xy 21.785834 -56.539638) (xy 21.779992 -56.531002)
			(xy 21.76399 -56.50694) (xy 21.738648 -56.455008) (xy 21.721423 -56.399849) (xy 21.712708 -56.342725)
			(xy 21.712174 -56.313832) (xy 21.712685 -56.286581) (xy 21.720437 -56.232632) (xy 21.735788 -56.180337)
			(xy 21.758426 -56.130758) (xy 21.787889 -56.084905) (xy 21.823577 -56.043713) (xy 21.864765 -56.008019)
			(xy 21.910614 -55.97855) (xy 21.96019 -55.955906) (xy 22.012484 -55.940548) (xy 22.066431 -55.932789)
			(xy 22.093682 -55.932324) (xy 22.121052 -55.932795) (xy 22.175231 -55.940611) (xy 22.227735 -55.956098)
			(xy 22.277481 -55.978939) (xy 22.323448 -56.008663) (xy 22.34438 -56.026304) (xy 22.344634 -56.026558)
			(xy 22.35173 -56.03213) (xy 22.36864 -56.038384) (xy 22.377654 -56.03875) (xy 22.44471 -56.03875)
			(xy 22.453729 -56.038408) (xy 22.470646 -56.032151) (xy 22.47773 -56.026558) (xy 22.47773 -56.026304)
			(xy 22.477984 -56.026304) (xy 22.498917 -56.008663) (xy 22.544885 -55.978939) (xy 22.594631 -55.956093)
			(xy 22.647133 -55.940597) (xy 22.701311 -55.932768) (xy 22.756053 -55.932768) (xy 22.810231 -55.940597)
			(xy 22.862733 -55.956093) (xy 22.912479 -55.978939) (xy 22.958447 -56.008663) (xy 22.97938 -56.026304)
			(xy 22.979634 -56.026558) (xy 22.98673 -56.03213) (xy 23.00364 -56.038384) (xy 23.012654 -56.03875)
			(xy 23.07971 -56.03875) (xy 23.088729 -56.038408) (xy 23.105646 -56.032151) (xy 23.11273 -56.026558)
			(xy 23.11273 -56.026304) (xy 23.112984 -56.026304) (xy 23.133912 -56.00866) (xy 23.179886 -55.978948)
			(xy 23.229634 -55.956113) (xy 23.282136 -55.940624) (xy 23.336313 -55.932797) (xy 23.363682 -55.932324)
			(xy 23.390938 -55.932722) (xy 23.444895 -55.940477) (xy 23.4972 -55.955833) (xy 23.546787 -55.978476)
			(xy 23.592646 -56.007946) (xy 23.633844 -56.043643) (xy 23.669543 -56.08484) (xy 23.699015 -56.130698)
			(xy 23.721661 -56.180283) (xy 23.737019 -56.232587) (xy 23.744777 -56.286544) (xy 23.744777 -56.297068)
			(xy 24.086564 -56.297068) (xy 24.090635 -56.241446) (xy 24.102761 -56.187009) (xy 24.122684 -56.134918)
			(xy 24.14998 -56.086283) (xy 24.184066 -56.04214) (xy 24.224215 -56.003431) (xy 24.269573 -55.97098)
			(xy 24.319173 -55.945479) (xy 24.371957 -55.927472) (xy 24.4268 -55.917342) (xy 24.482534 -55.915305)
			(xy 24.537971 -55.921405) (xy 24.591928 -55.935511) (xy 24.643257 -55.957323) (xy 24.690863 -55.986377)
			(xy 24.733731 -56.022052) (xy 24.770948 -56.063589) (xy 24.801721 -56.110102) (xy 24.825393 -56.160599)
			(xy 24.841461 -56.214006) (xy 24.849581 -56.269182) (xy 24.85009 -56.297068) (xy 24.849581 -56.324954)
			(xy 24.841461 -56.38013) (xy 24.825393 -56.433537) (xy 24.801721 -56.484034) (xy 24.770948 -56.530547)
			(xy 24.733731 -56.572084) (xy 24.690863 -56.607759) (xy 24.643257 -56.636813) (xy 24.591928 -56.658625)
			(xy 24.537971 -56.672731) (xy 24.482534 -56.678831) (xy 24.4268 -56.676794) (xy 24.371957 -56.666664)
			(xy 24.319173 -56.648657) (xy 24.269573 -56.623156) (xy 24.224215 -56.590705) (xy 24.184066 -56.551996)
			(xy 24.14998 -56.507853) (xy 24.122684 -56.459218) (xy 24.102761 -56.407127) (xy 24.090635 -56.35269)
			(xy 24.086564 -56.297068) (xy 23.744777 -56.297068) (xy 23.744777 -56.341056) (xy 23.737019 -56.395013)
			(xy 23.721661 -56.447317) (xy 23.699015 -56.496902) (xy 23.669543 -56.54276) (xy 23.633844 -56.583957)
			(xy 23.592646 -56.619654) (xy 23.546787 -56.649124) (xy 23.4972 -56.671767) (xy 23.444895 -56.687123)
			(xy 23.390938 -56.694878) (xy 23.363682 -56.69534) (xy 23.336311 -56.694899) (xy 23.28213 -56.687077)
			(xy 23.229626 -56.671583) (xy 23.179879 -56.648736) (xy 23.133914 -56.619005) (xy 23.112984 -56.60136)
			(xy 23.11273 -56.601106) (xy 23.105639 -56.595527) (xy 23.088726 -56.589275) (xy 23.07971 -56.588914)
			(xy 23.012654 -56.588914) (xy 23.003639 -56.589294) (xy 22.986722 -56.595525) (xy 22.979634 -56.601106)
			(xy 22.979634 -56.60136) (xy 22.97938 -56.60136) (xy 22.958447 -56.619001) (xy 22.912479 -56.648725)
			(xy 22.862733 -56.671571) (xy 22.810231 -56.687067) (xy 22.756053 -56.694896) (xy 22.701311 -56.694896)
			(xy 22.647133 -56.687067) (xy 22.594631 -56.671571) (xy 22.544885 -56.648725) (xy 22.498917 -56.619001)
			(xy 22.477984 -56.60136) (xy 22.47773 -56.601106) (xy 22.470639 -56.595527) (xy 22.453726 -56.589275)
			(xy 22.44471 -56.588914) (xy 22.377654 -56.588914) (xy 22.368639 -56.589294) (xy 22.351722 -56.595525)
			(xy 22.344634 -56.601106) (xy 22.344126 -56.60136) (xy 22.331394 -56.612307) (xy 22.304301 -56.632146)
			(xy 22.290024 -56.640984) (xy 22.281134 -56.646318) (xy 22.268942 -56.663336) (xy 22.248622 -56.756554)
			(xy 22.25294 -56.777128) (xy 22.258782 -56.785764) (xy 22.274767 -56.809837) (xy 22.300113 -56.861765)
			(xy 22.317343 -56.91692) (xy 22.326063 -56.974042) (xy 22.3266 -57.002934) (xy 22.326114 -57.030185)
			(xy 22.318358 -57.084133) (xy 22.303003 -57.136428) (xy 22.280361 -57.186005) (xy 22.250895 -57.231855)
			(xy 22.215204 -57.273046) (xy 22.174013 -57.308737) (xy 22.128163 -57.338203) (xy 22.078586 -57.360845)
			(xy 22.026291 -57.3762) (xy 21.972343 -57.383956) (xy 21.917841 -57.383956) (xy 21.863893 -57.3762)
			(xy 21.811598 -57.360845) (xy 21.762021 -57.338203) (xy 21.716171 -57.308737) (xy 21.67498 -57.273046)
			(xy 21.639289 -57.231855) (xy 21.609823 -57.186005) (xy 21.587181 -57.136428) (xy 21.571826 -57.084133)
			(xy 21.56407 -57.030185) (xy 21.563584 -57.002934) (xy 1.306576 -57.002934) (xy 1.306576 -57.48528)
			(xy 4.606034 -57.48528) (xy 4.610105 -57.429658) (xy 4.622231 -57.375221) (xy 4.642154 -57.32313)
			(xy 4.66945 -57.274495) (xy 4.703536 -57.230352) (xy 4.743685 -57.191643) (xy 4.789043 -57.159192)
			(xy 4.838643 -57.133691) (xy 4.891427 -57.115684) (xy 4.94627 -57.105554) (xy 5.002004 -57.103517)
			(xy 5.057441 -57.109617) (xy 5.111398 -57.123723) (xy 5.162727 -57.145535) (xy 5.210333 -57.174589)
			(xy 5.253201 -57.210264) (xy 5.290418 -57.251801) (xy 5.321191 -57.298314) (xy 5.344863 -57.348811)
			(xy 5.360931 -57.402218) (xy 5.369051 -57.457394) (xy 5.36956 -57.48528) (xy 30.605982 -57.48528)
			(xy 30.610053 -57.429658) (xy 30.622179 -57.375221) (xy 30.642102 -57.32313) (xy 30.669398 -57.274495)
			(xy 30.703484 -57.230352) (xy 30.743633 -57.191643) (xy 30.788991 -57.159192) (xy 30.838591 -57.133691)
			(xy 30.891375 -57.115684) (xy 30.946218 -57.105554) (xy 31.001952 -57.103517) (xy 31.057389 -57.109617)
			(xy 31.111346 -57.123723) (xy 31.162675 -57.145535) (xy 31.210281 -57.174589) (xy 31.253149 -57.210264)
			(xy 31.290366 -57.251801) (xy 31.321139 -57.298314) (xy 31.344811 -57.348811) (xy 31.360879 -57.402218)
			(xy 31.368999 -57.457394) (xy 31.369508 -57.48528) (xy 31.368999 -57.513166) (xy 31.360879 -57.568342)
			(xy 31.344811 -57.621749) (xy 31.321139 -57.672246) (xy 31.290366 -57.718759) (xy 31.253149 -57.760296)
			(xy 31.210281 -57.795971) (xy 31.162675 -57.825025) (xy 31.111346 -57.846837) (xy 31.057389 -57.860943)
			(xy 31.001952 -57.867043) (xy 30.946218 -57.865006) (xy 30.891375 -57.854876) (xy 30.838591 -57.836869)
			(xy 30.788991 -57.811368) (xy 30.743633 -57.778917) (xy 30.703484 -57.740208) (xy 30.669398 -57.696065)
			(xy 30.642102 -57.64743) (xy 30.622179 -57.595339) (xy 30.610053 -57.540902) (xy 30.605982 -57.48528)
			(xy 5.36956 -57.48528) (xy 5.369051 -57.513166) (xy 5.360931 -57.568342) (xy 5.344863 -57.621749)
			(xy 5.321191 -57.672246) (xy 5.290418 -57.718759) (xy 5.253201 -57.760296) (xy 5.210333 -57.795971)
			(xy 5.162727 -57.825025) (xy 5.111398 -57.846837) (xy 5.057441 -57.860943) (xy 5.002004 -57.867043)
			(xy 4.94627 -57.865006) (xy 4.891427 -57.854876) (xy 4.838643 -57.836869) (xy 4.789043 -57.811368)
			(xy 4.743685 -57.778917) (xy 4.703536 -57.740208) (xy 4.66945 -57.696065) (xy 4.642154 -57.64743)
			(xy 4.622231 -57.595339) (xy 4.610105 -57.540902) (xy 4.606034 -57.48528) (xy 1.306576 -57.48528)
			(xy 1.306576 -58.076084) (xy 5.358128 -58.076084) (xy 5.362199 -58.020462) (xy 5.374325 -57.966025)
			(xy 5.394248 -57.913934) (xy 5.421544 -57.865299) (xy 5.45563 -57.821156) (xy 5.495779 -57.782447)
			(xy 5.541137 -57.749996) (xy 5.590737 -57.724495) (xy 5.643521 -57.706488) (xy 5.698364 -57.696358)
			(xy 5.754098 -57.694321) (xy 5.809535 -57.700421) (xy 5.863492 -57.714527) (xy 5.914821 -57.736339)
			(xy 5.962427 -57.765393) (xy 6.005295 -57.801068) (xy 6.042512 -57.842605) (xy 6.058848 -57.867296)
			(xy 7.643112 -57.867296) (xy 7.647183 -57.811674) (xy 7.659309 -57.757237) (xy 7.679232 -57.705146)
			(xy 7.706528 -57.656511) (xy 7.740614 -57.612368) (xy 7.780763 -57.573659) (xy 7.826121 -57.541208)
			(xy 7.875721 -57.515707) (xy 7.928505 -57.4977) (xy 7.983348 -57.48757) (xy 8.039082 -57.485533)
			(xy 8.094519 -57.491633) (xy 8.148476 -57.505739) (xy 8.199805 -57.527551) (xy 8.247411 -57.556605)
			(xy 8.290279 -57.59228) (xy 8.327496 -57.633817) (xy 8.358269 -57.68033) (xy 8.381941 -57.730827)
			(xy 8.398009 -57.784234) (xy 8.406129 -57.83941) (xy 8.406638 -57.867296) (xy 8.406129 -57.895182)
			(xy 8.398009 -57.950358) (xy 8.381941 -58.003765) (xy 8.358269 -58.054262) (xy 8.327496 -58.100775)
			(xy 8.290279 -58.142312) (xy 8.247411 -58.177987) (xy 8.199805 -58.207041) (xy 8.148476 -58.228853)
			(xy 8.094519 -58.242959) (xy 8.039082 -58.249059) (xy 7.983348 -58.247022) (xy 7.928505 -58.236892)
			(xy 7.875721 -58.218885) (xy 7.826121 -58.193384) (xy 7.780763 -58.160933) (xy 7.740614 -58.122224)
			(xy 7.706528 -58.078081) (xy 7.679232 -58.029446) (xy 7.659309 -57.977355) (xy 7.647183 -57.922918)
			(xy 7.643112 -57.867296) (xy 6.058848 -57.867296) (xy 6.073285 -57.889118) (xy 6.096957 -57.939615)
			(xy 6.113025 -57.993022) (xy 6.121145 -58.048198) (xy 6.121654 -58.076084) (xy 6.121145 -58.10397)
			(xy 6.113025 -58.159146) (xy 6.096957 -58.212553) (xy 6.073285 -58.26305) (xy 6.042512 -58.309563)
			(xy 6.005295 -58.3511) (xy 5.962427 -58.386775) (xy 5.914821 -58.415829) (xy 5.863492 -58.437641)
			(xy 5.809535 -58.451747) (xy 5.754098 -58.457847) (xy 5.698364 -58.45581) (xy 5.643521 -58.44568)
			(xy 5.590737 -58.427673) (xy 5.541137 -58.402172) (xy 5.495779 -58.369721) (xy 5.45563 -58.331012)
			(xy 5.421544 -58.286869) (xy 5.394248 -58.238234) (xy 5.374325 -58.186143) (xy 5.362199 -58.131706)
			(xy 5.358128 -58.076084) (xy 1.306576 -58.076084) (xy 1.306576 -58.561224) (xy 6.562342 -58.561224)
			(xy 6.566413 -58.505602) (xy 6.578539 -58.451165) (xy 6.598462 -58.399074) (xy 6.625758 -58.350439)
			(xy 6.659844 -58.306296) (xy 6.699993 -58.267587) (xy 6.745351 -58.235136) (xy 6.794951 -58.209635)
			(xy 6.847735 -58.191628) (xy 6.902578 -58.181498) (xy 6.958312 -58.179461) (xy 7.013749 -58.185561)
			(xy 7.067706 -58.199667) (xy 7.119035 -58.221479) (xy 7.166641 -58.250533) (xy 7.209509 -58.286208)
			(xy 7.246726 -58.327745) (xy 7.277499 -58.374258) (xy 7.301171 -58.424755) (xy 7.308681 -58.449718)
			(xy 8.808972 -58.449718) (xy 8.813043 -58.394096) (xy 8.825169 -58.339659) (xy 8.845092 -58.287568)
			(xy 8.872388 -58.238933) (xy 8.906474 -58.19479) (xy 8.946623 -58.156081) (xy 8.991981 -58.12363)
			(xy 9.041581 -58.098129) (xy 9.094365 -58.080122) (xy 9.149208 -58.069992) (xy 9.204942 -58.067955)
			(xy 9.260379 -58.074055) (xy 9.314336 -58.088161) (xy 9.365665 -58.109973) (xy 9.413271 -58.139027)
			(xy 9.456139 -58.174702) (xy 9.493356 -58.216239) (xy 9.524129 -58.262752) (xy 9.547801 -58.313249)
			(xy 9.563869 -58.366656) (xy 9.571989 -58.421832) (xy 9.572498 -58.449718) (xy 9.571989 -58.477604)
			(xy 9.563869 -58.53278) (xy 9.547801 -58.586187) (xy 9.524129 -58.636684) (xy 9.495912 -58.679334)
			(xy 21.995384 -58.679334) (xy 21.995813 -58.653019) (xy 22.003056 -58.600889) (xy 22.017383 -58.550246)
			(xy 22.038523 -58.502047) (xy 22.066076 -58.457204) (xy 22.09952 -58.416566) (xy 22.118574 -58.39841)
			(xy 22.125969 -58.390883) (xy 22.134498 -58.371607) (xy 22.135084 -58.361072) (xy 22.135084 -58.286396)
			(xy 22.134575 -58.275844) (xy 22.126026 -58.256549) (xy 22.118574 -58.249058) (xy 22.0995 -58.230921)
			(xy 22.066046 -58.190287) (xy 22.03849 -58.145442) (xy 22.017355 -58.097238) (xy 22.003041 -58.046588)
			(xy 21.99582 -57.994451) (xy 21.995384 -57.968134) (xy 21.99587 -57.940883) (xy 22.003626 -57.886935)
			(xy 22.018981 -57.83464) (xy 22.041623 -57.785063) (xy 22.071089 -57.739213) (xy 22.10678 -57.698022)
			(xy 22.147971 -57.662331) (xy 22.193821 -57.632865) (xy 22.243398 -57.610223) (xy 22.295693 -57.594868)
			(xy 22.349641 -57.587112) (xy 22.404143 -57.587112) (xy 22.458091 -57.594868) (xy 22.510386 -57.610223)
			(xy 22.559963 -57.632865) (xy 22.605813 -57.662331) (xy 22.647004 -57.698022) (xy 22.682695 -57.739213)
			(xy 22.712161 -57.785063) (xy 22.734803 -57.83464) (xy 22.750158 -57.886935) (xy 22.757914 -57.940883)
			(xy 22.7584 -57.968134) (xy 22.757955 -57.994449) (xy 22.750716 -58.046578) (xy 22.743448 -58.072274)
			(xy 25.993596 -58.072274) (xy 25.997667 -58.016652) (xy 26.009793 -57.962215) (xy 26.029716 -57.910124)
			(xy 26.057012 -57.861489) (xy 26.091098 -57.817346) (xy 26.131247 -57.778637) (xy 26.176605 -57.746186)
			(xy 26.226205 -57.720685) (xy 26.278989 -57.702678) (xy 26.333832 -57.692548) (xy 26.389566 -57.690511)
			(xy 26.445003 -57.696611) (xy 26.49896 -57.710717) (xy 26.550289 -57.732529) (xy 26.597895 -57.761583)
			(xy 26.640763 -57.797258) (xy 26.67798 -57.838795) (xy 26.708753 -57.885308) (xy 26.732425 -57.935805)
			(xy 26.748493 -57.989212) (xy 26.756613 -58.044388) (xy 26.757122 -58.072274) (xy 26.757052 -58.076084)
			(xy 31.358076 -58.076084) (xy 31.362147 -58.020462) (xy 31.374273 -57.966025) (xy 31.394196 -57.913934)
			(xy 31.421492 -57.865299) (xy 31.455578 -57.821156) (xy 31.495727 -57.782447) (xy 31.541085 -57.749996)
			(xy 31.590685 -57.724495) (xy 31.643469 -57.706488) (xy 31.698312 -57.696358) (xy 31.754046 -57.694321)
			(xy 31.809483 -57.700421) (xy 31.86344 -57.714527) (xy 31.914769 -57.736339) (xy 31.962375 -57.765393)
			(xy 32.005243 -57.801068) (xy 32.04246 -57.842605) (xy 32.058796 -57.867296) (xy 33.64306 -57.867296)
			(xy 33.647131 -57.811674) (xy 33.659257 -57.757237) (xy 33.67918 -57.705146) (xy 33.706476 -57.656511)
			(xy 33.740562 -57.612368) (xy 33.780711 -57.573659) (xy 33.826069 -57.541208) (xy 33.875669 -57.515707)
			(xy 33.928453 -57.4977) (xy 33.983296 -57.48757) (xy 34.03903 -57.485533) (xy 34.094467 -57.491633)
			(xy 34.148424 -57.505739) (xy 34.199753 -57.527551) (xy 34.247359 -57.556605) (xy 34.290227 -57.59228)
			(xy 34.327444 -57.633817) (xy 34.358217 -57.68033) (xy 34.381889 -57.730827) (xy 34.397957 -57.784234)
			(xy 34.406077 -57.83941) (xy 34.406586 -57.867296) (xy 34.406077 -57.895182) (xy 34.397957 -57.950358)
			(xy 34.381889 -58.003765) (xy 34.358217 -58.054262) (xy 34.327444 -58.100775) (xy 34.290227 -58.142312)
			(xy 34.247359 -58.177987) (xy 34.199753 -58.207041) (xy 34.148424 -58.228853) (xy 34.094467 -58.242959)
			(xy 34.03903 -58.249059) (xy 33.983296 -58.247022) (xy 33.928453 -58.236892) (xy 33.875669 -58.218885)
			(xy 33.826069 -58.193384) (xy 33.780711 -58.160933) (xy 33.740562 -58.122224) (xy 33.706476 -58.078081)
			(xy 33.67918 -58.029446) (xy 33.659257 -57.977355) (xy 33.647131 -57.922918) (xy 33.64306 -57.867296)
			(xy 32.058796 -57.867296) (xy 32.073233 -57.889118) (xy 32.096905 -57.939615) (xy 32.112973 -57.993022)
			(xy 32.121093 -58.048198) (xy 32.121602 -58.076084) (xy 32.121093 -58.10397) (xy 32.112973 -58.159146)
			(xy 32.096905 -58.212553) (xy 32.073233 -58.26305) (xy 32.04246 -58.309563) (xy 32.005243 -58.3511)
			(xy 31.962375 -58.386775) (xy 31.914769 -58.415829) (xy 31.86344 -58.437641) (xy 31.809483 -58.451747)
			(xy 31.754046 -58.457847) (xy 31.698312 -58.45581) (xy 31.643469 -58.44568) (xy 31.590685 -58.427673)
			(xy 31.541085 -58.402172) (xy 31.495727 -58.369721) (xy 31.455578 -58.331012) (xy 31.421492 -58.286869)
			(xy 31.394196 -58.238234) (xy 31.374273 -58.186143) (xy 31.362147 -58.131706) (xy 31.358076 -58.076084)
			(xy 26.757052 -58.076084) (xy 26.756613 -58.10016) (xy 26.748493 -58.155336) (xy 26.732425 -58.208743)
			(xy 26.708753 -58.25924) (xy 26.67798 -58.305753) (xy 26.640763 -58.34729) (xy 26.597895 -58.382965)
			(xy 26.550289 -58.412019) (xy 26.49896 -58.433831) (xy 26.445003 -58.447937) (xy 26.389566 -58.454037)
			(xy 26.333832 -58.452) (xy 26.278989 -58.44187) (xy 26.226205 -58.423863) (xy 26.176605 -58.398362)
			(xy 26.131247 -58.365911) (xy 26.091098 -58.327202) (xy 26.057012 -58.283059) (xy 26.029716 -58.234424)
			(xy 26.009793 -58.182333) (xy 25.997667 -58.127896) (xy 25.993596 -58.072274) (xy 22.743448 -58.072274)
			(xy 22.736392 -58.097221) (xy 22.715256 -58.14542) (xy 22.687705 -58.190263) (xy 22.654263 -58.230902)
			(xy 22.63521 -58.249058) (xy 22.627826 -58.256595) (xy 22.619291 -58.275863) (xy 22.6187 -58.286396)
			(xy 22.6187 -58.361072) (xy 22.619231 -58.371621) (xy 22.627765 -58.390917) (xy 22.63521 -58.39841)
			(xy 22.654265 -58.416566) (xy 22.687722 -58.457196) (xy 22.715281 -58.502036) (xy 22.736419 -58.550237)
			(xy 22.739525 -58.561224) (xy 32.56229 -58.561224) (xy 32.566361 -58.505602) (xy 32.578487 -58.451165)
			(xy 32.59841 -58.399074) (xy 32.625706 -58.350439) (xy 32.659792 -58.306296) (xy 32.699941 -58.267587)
			(xy 32.745299 -58.235136) (xy 32.794899 -58.209635) (xy 32.847683 -58.191628) (xy 32.902526 -58.181498)
			(xy 32.95826 -58.179461) (xy 33.013697 -58.185561) (xy 33.067654 -58.199667) (xy 33.118983 -58.221479)
			(xy 33.166589 -58.250533) (xy 33.209457 -58.286208) (xy 33.246674 -58.327745) (xy 33.277447 -58.374258)
			(xy 33.301119 -58.424755) (xy 33.317187 -58.478162) (xy 33.325307 -58.533338) (xy 33.325816 -58.561224)
			(xy 33.325307 -58.58911) (xy 33.317187 -58.644286) (xy 33.301119 -58.697693) (xy 33.277447 -58.74819)
			(xy 33.246674 -58.794703) (xy 33.209457 -58.83624) (xy 33.166589 -58.871915) (xy 33.118983 -58.900969)
			(xy 33.067654 -58.922781) (xy 33.013697 -58.936887) (xy 32.95826 -58.942987) (xy 32.902526 -58.94095)
			(xy 32.847683 -58.93082) (xy 32.794899 -58.912813) (xy 32.745299 -58.887312) (xy 32.699941 -58.854861)
			(xy 32.659792 -58.816152) (xy 32.625706 -58.772009) (xy 32.59841 -58.723374) (xy 32.578487 -58.671283)
			(xy 32.566361 -58.616846) (xy 32.56229 -58.561224) (xy 22.739525 -58.561224) (xy 22.750737 -58.600884)
			(xy 22.757961 -58.653018) (xy 22.7584 -58.679334) (xy 22.757914 -58.706585) (xy 22.750158 -58.760533)
			(xy 22.734803 -58.812828) (xy 22.712161 -58.862405) (xy 22.682695 -58.908255) (xy 22.647004 -58.949446)
			(xy 22.605813 -58.985137) (xy 22.559963 -59.014603) (xy 22.510386 -59.037245) (xy 22.458091 -59.0526)
			(xy 22.404143 -59.060356) (xy 22.349641 -59.060356) (xy 22.295693 -59.0526) (xy 22.243398 -59.037245)
			(xy 22.193821 -59.014603) (xy 22.147971 -58.985137) (xy 22.10678 -58.949446) (xy 22.071089 -58.908255)
			(xy 22.041623 -58.862405) (xy 22.018981 -58.812828) (xy 22.003626 -58.760533) (xy 21.99587 -58.706585)
			(xy 21.995384 -58.679334) (xy 9.495912 -58.679334) (xy 9.493356 -58.683197) (xy 9.456139 -58.724734)
			(xy 9.413271 -58.760409) (xy 9.365665 -58.789463) (xy 9.314336 -58.811275) (xy 9.260379 -58.825381)
			(xy 9.204942 -58.831481) (xy 9.149208 -58.829444) (xy 9.094365 -58.819314) (xy 9.041581 -58.801307)
			(xy 8.991981 -58.775806) (xy 8.946623 -58.743355) (xy 8.906474 -58.704646) (xy 8.872388 -58.660503)
			(xy 8.845092 -58.611868) (xy 8.825169 -58.559777) (xy 8.813043 -58.50534) (xy 8.808972 -58.449718)
			(xy 7.308681 -58.449718) (xy 7.317239 -58.478162) (xy 7.325359 -58.533338) (xy 7.325868 -58.561224)
			(xy 7.325359 -58.58911) (xy 7.317239 -58.644286) (xy 7.301171 -58.697693) (xy 7.277499 -58.74819)
			(xy 7.246726 -58.794703) (xy 7.209509 -58.83624) (xy 7.166641 -58.871915) (xy 7.119035 -58.900969)
			(xy 7.067706 -58.922781) (xy 7.013749 -58.936887) (xy 6.958312 -58.942987) (xy 6.902578 -58.94095)
			(xy 6.847735 -58.93082) (xy 6.794951 -58.912813) (xy 6.745351 -58.887312) (xy 6.699993 -58.854861)
			(xy 6.659844 -58.816152) (xy 6.625758 -58.772009) (xy 6.598462 -58.723374) (xy 6.578539 -58.671283)
			(xy 6.566413 -58.616846) (xy 6.562342 -58.561224) (xy 1.306576 -58.561224) (xy 1.306576 -59.174634)
			(xy 5.093206 -59.174634) (xy 5.097277 -59.119012) (xy 5.109403 -59.064575) (xy 5.129326 -59.012484)
			(xy 5.156622 -58.963849) (xy 5.190708 -58.919706) (xy 5.230857 -58.880997) (xy 5.276215 -58.848546)
			(xy 5.325815 -58.823045) (xy 5.378599 -58.805038) (xy 5.433442 -58.794908) (xy 5.489176 -58.792871)
			(xy 5.544613 -58.798971) (xy 5.59857 -58.813077) (xy 5.649899 -58.834889) (xy 5.697505 -58.863943)
			(xy 5.740373 -58.899618) (xy 5.77759 -58.941155) (xy 5.808363 -58.987668) (xy 5.832035 -59.038165)
			(xy 5.848103 -59.091572) (xy 5.856223 -59.146748) (xy 5.856732 -59.174634) (xy 31.093154 -59.174634)
			(xy 31.097225 -59.119012) (xy 31.109351 -59.064575) (xy 31.129274 -59.012484) (xy 31.15657 -58.963849)
			(xy 31.190656 -58.919706) (xy 31.230805 -58.880997) (xy 31.276163 -58.848546) (xy 31.325763 -58.823045)
			(xy 31.378547 -58.805038) (xy 31.43339 -58.794908) (xy 31.489124 -58.792871) (xy 31.544561 -58.798971)
			(xy 31.598518 -58.813077) (xy 31.649847 -58.834889) (xy 31.697453 -58.863943) (xy 31.740321 -58.899618)
			(xy 31.777538 -58.941155) (xy 31.808311 -58.987668) (xy 31.831983 -59.038165) (xy 31.848051 -59.091572)
			(xy 31.856171 -59.146748) (xy 31.85668 -59.174634) (xy 31.856171 -59.20252) (xy 31.848051 -59.257696)
			(xy 31.831983 -59.311103) (xy 31.808311 -59.3616) (xy 31.777538 -59.408113) (xy 31.740321 -59.44965)
			(xy 31.697453 -59.485325) (xy 31.649847 -59.514379) (xy 31.598518 -59.536191) (xy 31.544561 -59.550297)
			(xy 31.489124 -59.556397) (xy 31.43339 -59.55436) (xy 31.378547 -59.54423) (xy 31.325763 -59.526223)
			(xy 31.276163 -59.500722) (xy 31.230805 -59.468271) (xy 31.190656 -59.429562) (xy 31.15657 -59.385419)
			(xy 31.129274 -59.336784) (xy 31.109351 -59.284693) (xy 31.097225 -59.230256) (xy 31.093154 -59.174634)
			(xy 5.856732 -59.174634) (xy 5.856223 -59.20252) (xy 5.848103 -59.257696) (xy 5.832035 -59.311103)
			(xy 5.808363 -59.3616) (xy 5.77759 -59.408113) (xy 5.740373 -59.44965) (xy 5.697505 -59.485325) (xy 5.649899 -59.514379)
			(xy 5.59857 -59.536191) (xy 5.544613 -59.550297) (xy 5.489176 -59.556397) (xy 5.433442 -59.55436)
			(xy 5.378599 -59.54423) (xy 5.325815 -59.526223) (xy 5.276215 -59.500722) (xy 5.230857 -59.468271)
			(xy 5.190708 -59.429562) (xy 5.156622 -59.385419) (xy 5.129326 -59.336784) (xy 5.109403 -59.284693)
			(xy 5.097277 -59.230256) (xy 5.093206 -59.174634) (xy 1.306576 -59.174634) (xy 1.306576 -60.019261)
			(xy 22.135824 -60.019261) (xy 22.135824 -59.964759) (xy 22.14358 -59.910811) (xy 22.158935 -59.858516)
			(xy 22.181576 -59.808938) (xy 22.211043 -59.763088) (xy 22.246734 -59.721897) (xy 22.287924 -59.686205)
			(xy 22.333775 -59.656738) (xy 22.383352 -59.634097) (xy 22.435647 -59.618741) (xy 22.489595 -59.610984)
			(xy 22.516846 -59.610498) (xy 22.544215 -59.610996) (xy 22.598393 -59.618806) (xy 22.650895 -59.634288)
			(xy 22.700643 -59.657123) (xy 22.746611 -59.68684) (xy 22.767544 -59.704478) (xy 22.767798 -59.704732)
			(xy 22.774878 -59.710327) (xy 22.7918 -59.716568) (xy 22.800818 -59.716924) (xy 22.867874 -59.716924)
			(xy 22.876889 -59.716549) (xy 22.893806 -59.710313) (xy 22.900894 -59.704732) (xy 22.900894 -59.704478)
			(xy 22.901148 -59.704478) (xy 22.922081 -59.686837) (xy 22.968049 -59.657113) (xy 23.017795 -59.634267)
			(xy 23.070297 -59.618771) (xy 23.124475 -59.610942) (xy 23.179217 -59.610942) (xy 23.233395 -59.618771)
			(xy 23.285897 -59.634267) (xy 23.335643 -59.657113) (xy 23.381611 -59.686837) (xy 23.402544 -59.704478)
			(xy 23.402798 -59.704732) (xy 23.409878 -59.710327) (xy 23.4268 -59.716568) (xy 23.435818 -59.716924)
			(xy 23.502874 -59.716924) (xy 23.511889 -59.716549) (xy 23.528806 -59.710313) (xy 23.535894 -59.704732)
			(xy 23.535894 -59.704478) (xy 23.536148 -59.704478) (xy 23.557086 -59.686846) (xy 23.603058 -59.657134)
			(xy 23.652804 -59.634297) (xy 23.705303 -59.618804) (xy 23.759477 -59.610974) (xy 23.786846 -59.610498)
			(xy 23.814099 -59.610969) (xy 23.86805 -59.618725) (xy 23.920347 -59.634081) (xy 23.969927 -59.656723)
			(xy 24.015781 -59.686191) (xy 24.056973 -59.721884) (xy 24.092667 -59.763076) (xy 24.122135 -59.808929)
			(xy 24.144778 -59.858509) (xy 24.160134 -59.910807) (xy 24.167891 -59.964757) (xy 24.167891 -60.019263)
			(xy 24.160134 -60.073213) (xy 24.144778 -60.125511) (xy 24.122135 -60.175091) (xy 24.092667 -60.220944)
			(xy 24.056973 -60.262136) (xy 24.015781 -60.297829) (xy 23.969927 -60.327297) (xy 23.920347 -60.349939)
			(xy 23.86805 -60.365295) (xy 23.814099 -60.373051) (xy 23.786846 -60.373514) (xy 23.759477 -60.373018)
			(xy 23.705299 -60.365207) (xy 23.652797 -60.349724) (xy 23.603049 -60.32689) (xy 23.557081 -60.297172)
			(xy 23.536148 -60.279534) (xy 23.535894 -60.27928) (xy 23.528815 -60.273683) (xy 23.511892 -60.267443)
			(xy 23.502874 -60.267088) (xy 23.435818 -60.267088) (xy 23.426802 -60.267456) (xy 23.409885 -60.273696)
			(xy 23.402798 -60.27928) (xy 23.402544 -60.279534) (xy 23.381611 -60.297175) (xy 23.335643 -60.326899)
			(xy 23.285897 -60.349745) (xy 23.233395 -60.365241) (xy 23.179217 -60.37307) (xy 23.124475 -60.37307)
			(xy 23.070297 -60.365241) (xy 23.017795 -60.349745) (xy 22.968049 -60.326899) (xy 22.922081 -60.297175)
			(xy 22.901148 -60.279534) (xy 22.900894 -60.27928) (xy 22.893815 -60.273683) (xy 22.876892 -60.267443)
			(xy 22.867874 -60.267088) (xy 22.800818 -60.267088) (xy 22.791802 -60.267456) (xy 22.774885 -60.273696)
			(xy 22.767798 -60.27928) (xy 22.767798 -60.279534) (xy 22.767544 -60.279534) (xy 22.746611 -60.297171)
			(xy 22.700638 -60.326882) (xy 22.65089 -60.349718) (xy 22.59839 -60.36521) (xy 22.544215 -60.373039)
			(xy 22.516846 -60.373514) (xy 22.489595 -60.373036) (xy 22.435647 -60.365279) (xy 22.383352 -60.349923)
			(xy 22.333775 -60.327282) (xy 22.287924 -60.297815) (xy 22.246734 -60.262123) (xy 22.211043 -60.220932)
			(xy 22.181576 -60.175082) (xy 22.158935 -60.125504) (xy 22.14358 -60.073209) (xy 22.135824 -60.019261)
			(xy 1.306576 -60.019261) (xy 1.306576 -60.781946) (xy 5.674358 -60.781946) (xy 5.678429 -60.726324)
			(xy 5.690555 -60.671887) (xy 5.710478 -60.619796) (xy 5.737774 -60.571161) (xy 5.77186 -60.527018)
			(xy 5.812009 -60.488309) (xy 5.857367 -60.455858) (xy 5.906967 -60.430357) (xy 5.959751 -60.41235)
			(xy 6.014594 -60.40222) (xy 6.070328 -60.400183) (xy 6.125765 -60.406283) (xy 6.179722 -60.420389)
			(xy 6.231051 -60.442201) (xy 6.278657 -60.471255) (xy 6.321525 -60.50693) (xy 6.358742 -60.548467)
			(xy 6.389515 -60.59498) (xy 6.407505 -60.633356) (xy 7.797036 -60.633356) (xy 7.801107 -60.577734)
			(xy 7.813233 -60.523297) (xy 7.833156 -60.471206) (xy 7.860452 -60.422571) (xy 7.894538 -60.378428)
			(xy 7.934687 -60.339719) (xy 7.980045 -60.307268) (xy 8.029645 -60.281767) (xy 8.082429 -60.26376)
			(xy 8.137272 -60.25363) (xy 8.193006 -60.251593) (xy 8.248443 -60.257693) (xy 8.3024 -60.271799)
			(xy 8.353729 -60.293611) (xy 8.401335 -60.322665) (xy 8.444203 -60.35834) (xy 8.48142 -60.399877)
			(xy 8.512193 -60.44639) (xy 8.535865 -60.496887) (xy 8.551933 -60.550294) (xy 8.560053 -60.60547)
			(xy 8.560562 -60.633356) (xy 33.796984 -60.633356) (xy 33.801055 -60.577734) (xy 33.813181 -60.523297)
			(xy 33.833104 -60.471206) (xy 33.8604 -60.422571) (xy 33.894486 -60.378428) (xy 33.934635 -60.339719)
			(xy 33.979993 -60.307268) (xy 34.029593 -60.281767) (xy 34.082377 -60.26376) (xy 34.13722 -60.25363)
			(xy 34.192954 -60.251593) (xy 34.248391 -60.257693) (xy 34.302348 -60.271799) (xy 34.353677 -60.293611)
			(xy 34.401283 -60.322665) (xy 34.444151 -60.35834) (xy 34.481368 -60.399877) (xy 34.512141 -60.44639)
			(xy 34.535813 -60.496887) (xy 34.551881 -60.550294) (xy 34.560001 -60.60547) (xy 34.56051 -60.633356)
			(xy 34.560001 -60.661242) (xy 34.551881 -60.716418) (xy 34.535813 -60.769825) (xy 34.512141 -60.820322)
			(xy 34.481368 -60.866835) (xy 34.444151 -60.908372) (xy 34.401283 -60.944047) (xy 34.353677 -60.973101)
			(xy 34.302348 -60.994913) (xy 34.248391 -61.009019) (xy 34.192954 -61.015119) (xy 34.13722 -61.013082)
			(xy 34.082377 -61.002952) (xy 34.029593 -60.984945) (xy 33.979993 -60.959444) (xy 33.934635 -60.926993)
			(xy 33.894486 -60.888284) (xy 33.8604 -60.844141) (xy 33.833104 -60.795506) (xy 33.813181 -60.743415)
			(xy 33.801055 -60.688978) (xy 33.796984 -60.633356) (xy 8.560562 -60.633356) (xy 8.560053 -60.661242)
			(xy 8.551933 -60.716418) (xy 8.535865 -60.769825) (xy 8.512193 -60.820322) (xy 8.48142 -60.866835)
			(xy 8.444203 -60.908372) (xy 8.401335 -60.944047) (xy 8.353729 -60.973101) (xy 8.3024 -60.994913)
			(xy 8.248443 -61.009019) (xy 8.193006 -61.015119) (xy 8.137272 -61.013082) (xy 8.082429 -61.002952)
			(xy 8.029645 -60.984945) (xy 7.980045 -60.959444) (xy 7.934687 -60.926993) (xy 7.894538 -60.888284)
			(xy 7.860452 -60.844141) (xy 7.833156 -60.795506) (xy 7.813233 -60.743415) (xy 7.801107 -60.688978)
			(xy 7.797036 -60.633356) (xy 6.407505 -60.633356) (xy 6.413187 -60.645477) (xy 6.429255 -60.698884)
			(xy 6.437375 -60.75406) (xy 6.437884 -60.781946) (xy 6.437375 -60.809832) (xy 6.429255 -60.865008)
			(xy 6.413187 -60.918415) (xy 6.389515 -60.968912) (xy 6.358742 -61.015425) (xy 6.321525 -61.056962)
			(xy 6.278657 -61.092637) (xy 6.231051 -61.121691) (xy 6.179722 -61.143503) (xy 6.125765 -61.157609)
			(xy 6.070328 -61.163709) (xy 6.014594 -61.161672) (xy 5.959751 -61.151542) (xy 5.906967 -61.133535)
			(xy 5.857367 -61.108034) (xy 5.812009 -61.075583) (xy 5.77186 -61.036874) (xy 5.737774 -60.992731)
			(xy 5.710478 -60.944096) (xy 5.690555 -60.892005) (xy 5.678429 -60.837568) (xy 5.674358 -60.781946)
			(xy 1.306576 -60.781946) (xy 1.306576 -61.487812) (xy 32.30448 -61.487812) (xy 32.308551 -61.43219)
			(xy 32.320677 -61.377753) (xy 32.3406 -61.325662) (xy 32.367896 -61.277027) (xy 32.401982 -61.232884)
			(xy 32.442131 -61.194175) (xy 32.487489 -61.161724) (xy 32.537089 -61.136223) (xy 32.589873 -61.118216)
			(xy 32.644716 -61.108086) (xy 32.70045 -61.106049) (xy 32.755887 -61.112149) (xy 32.809844 -61.126255)
			(xy 32.861173 -61.148067) (xy 32.908779 -61.177121) (xy 32.951647 -61.212796) (xy 32.988864 -61.254333)
			(xy 33.019637 -61.300846) (xy 33.043309 -61.351343) (xy 33.059377 -61.40475) (xy 33.067497 -61.459926)
			(xy 33.068006 -61.487812) (xy 33.067497 -61.515698) (xy 33.059377 -61.570874) (xy 33.043309 -61.624281)
			(xy 33.019637 -61.674778) (xy 32.988864 -61.721291) (xy 32.951647 -61.762828) (xy 32.908779 -61.798503)
			(xy 32.861173 -61.827557) (xy 32.809844 -61.849369) (xy 32.755887 -61.863475) (xy 32.70045 -61.869575)
			(xy 32.644716 -61.867538) (xy 32.589873 -61.857408) (xy 32.537089 -61.839401) (xy 32.487489 -61.8139)
			(xy 32.442131 -61.781449) (xy 32.401982 -61.74274) (xy 32.367896 -61.698597) (xy 32.3406 -61.649962)
			(xy 32.320677 -61.597871) (xy 32.308551 -61.543434) (xy 32.30448 -61.487812) (xy 1.306576 -61.487812)
			(xy 1.306576 -62.121034) (xy 4.242306 -62.121034) (xy 4.246377 -62.065412) (xy 4.258503 -62.010975)
			(xy 4.278426 -61.958884) (xy 4.305722 -61.910249) (xy 4.339808 -61.866106) (xy 4.379957 -61.827397)
			(xy 4.425315 -61.794946) (xy 4.474915 -61.769445) (xy 4.527699 -61.751438) (xy 4.582542 -61.741308)
			(xy 4.638276 -61.739271) (xy 4.693713 -61.745371) (xy 4.74767 -61.759477) (xy 4.798999 -61.781289)
			(xy 4.846605 -61.810343) (xy 4.889473 -61.846018) (xy 4.92669 -61.887555) (xy 4.957463 -61.934068)
			(xy 4.981135 -61.984565) (xy 4.997203 -62.037972) (xy 5.005323 -62.093148) (xy 5.005832 -62.121034)
			(xy 5.005323 -62.14892) (xy 4.997203 -62.204096) (xy 4.981135 -62.257503) (xy 4.957463 -62.308) (xy 4.92669 -62.354513)
			(xy 4.889473 -62.39605) (xy 4.846605 -62.431725) (xy 4.798999 -62.460779) (xy 4.74767 -62.482591)
			(xy 4.693713 -62.496697) (xy 4.638276 -62.502797) (xy 4.582542 -62.50076) (xy 4.527699 -62.49063)
			(xy 4.474915 -62.472623) (xy 4.425315 -62.447122) (xy 4.379957 -62.414671) (xy 4.339808 -62.375962)
			(xy 4.305722 -62.331819) (xy 4.278426 -62.283184) (xy 4.258503 -62.231093) (xy 4.246377 -62.176656)
			(xy 4.242306 -62.121034) (xy 1.306576 -62.121034) (xy 1.306576 -62.733236) (xy 7.66615 -62.733236)
			(xy 7.666153 -62.678729) (xy 7.673912 -62.624777) (xy 7.689272 -62.572478) (xy 7.711917 -62.522898)
			(xy 7.741389 -62.477045) (xy 7.777086 -62.435854) (xy 7.818282 -62.400161) (xy 7.864138 -62.370696)
			(xy 7.913721 -62.348056) (xy 7.966021 -62.332703) (xy 8.019974 -62.324949) (xy 8.047228 -62.324488)
			(xy 8.070783 -62.324863) (xy 8.117527 -62.330723) (xy 8.140446 -62.336172) (xy 8.154202 -62.33921)
			(xy 8.182352 -62.338354) (xy 8.209199 -62.329848) (xy 8.232706 -62.314337) (xy 8.251087 -62.292999)
			(xy 8.262946 -62.267454) (xy 8.267383 -62.239643) (xy 8.264061 -62.211677) (xy 8.259064 -62.198504)
			(xy 8.249754 -62.175114) (xy 8.236628 -62.126514) (xy 8.230005 -62.076609) (xy 8.2296 -62.051438)
			(xy 8.230067 -62.024185) (xy 8.237825 -61.970235) (xy 8.253181 -61.917937) (xy 8.275824 -61.868357)
			(xy 8.305292 -61.822505) (xy 8.340985 -61.781312) (xy 8.382178 -61.745619) (xy 8.428031 -61.716152)
			(xy 8.477611 -61.69351) (xy 8.529909 -61.678154) (xy 8.583859 -61.670397) (xy 8.638365 -61.670397)
			(xy 8.692315 -61.678155) (xy 8.744613 -61.693511) (xy 8.794193 -61.716154) (xy 8.840045 -61.745622)
			(xy 8.881238 -61.781315) (xy 8.916931 -61.822508) (xy 8.946398 -61.868361) (xy 8.96904 -61.917941)
			(xy 8.984396 -61.970239) (xy 8.992153 -62.024189) (xy 8.992153 -62.078695) (xy 8.986065 -62.121034)
			(xy 30.242254 -62.121034) (xy 30.246325 -62.065412) (xy 30.258451 -62.010975) (xy 30.278374 -61.958884)
			(xy 30.30567 -61.910249) (xy 30.339756 -61.866106) (xy 30.379905 -61.827397) (xy 30.425263 -61.794946)
			(xy 30.474863 -61.769445) (xy 30.527647 -61.751438) (xy 30.58249 -61.741308) (xy 30.638224 -61.739271)
			(xy 30.693661 -61.745371) (xy 30.747618 -61.759477) (xy 30.798947 -61.781289) (xy 30.846553 -61.810343)
			(xy 30.889421 -61.846018) (xy 30.926638 -61.887555) (xy 30.957411 -61.934068) (xy 30.981083 -61.984565)
			(xy 30.997151 -62.037972) (xy 31.005271 -62.093148) (xy 31.00578 -62.121034) (xy 31.005271 -62.14892)
			(xy 30.997151 -62.204096) (xy 30.981083 -62.257503) (xy 30.957411 -62.308) (xy 30.926638 -62.354513)
			(xy 30.889421 -62.39605) (xy 30.846553 -62.431725) (xy 30.798947 -62.460779) (xy 30.747618 -62.482591)
			(xy 30.693661 -62.496697) (xy 30.638224 -62.502797) (xy 30.58249 -62.50076) (xy 30.527647 -62.49063)
			(xy 30.474863 -62.472623) (xy 30.425263 -62.447122) (xy 30.379905 -62.414671) (xy 30.339756 -62.375962)
			(xy 30.30567 -62.331819) (xy 30.278374 -62.283184) (xy 30.258451 -62.231093) (xy 30.246325 -62.176656)
			(xy 30.242254 -62.121034) (xy 8.986065 -62.121034) (xy 8.984395 -62.132645) (xy 8.969039 -62.184943)
			(xy 8.946396 -62.234523) (xy 8.916928 -62.280375) (xy 8.881235 -62.321568) (xy 8.840042 -62.357261)
			(xy 8.794189 -62.386728) (xy 8.744609 -62.40937) (xy 8.692311 -62.424726) (xy 8.638361 -62.432483)
			(xy 8.611108 -62.432946) (xy 8.587554 -62.432564) (xy 8.540809 -62.426708) (xy 8.51789 -62.421262)
			(xy 8.504134 -62.418214) (xy 8.475978 -62.419062) (xy 8.449124 -62.427564) (xy 8.425611 -62.443076)
			(xy 8.407227 -62.464418) (xy 8.395369 -62.489969) (xy 8.390937 -62.517786) (xy 8.394269 -62.545757)
			(xy 8.399272 -62.55893) (xy 8.408595 -62.582315) (xy 8.421715 -62.630918) (xy 8.428333 -62.680824)
			(xy 8.428736 -62.705996) (xy 8.428249 -62.73325) (xy 8.420492 -62.787202) (xy 8.405136 -62.839502)
			(xy 8.382493 -62.889083) (xy 8.353024 -62.934938) (xy 8.317329 -62.976131) (xy 8.276135 -63.011826)
			(xy 8.230281 -63.041294) (xy 8.180699 -63.063937) (xy 8.1284 -63.079293) (xy 8.074447 -63.087049)
			(xy 8.01994 -63.087048) (xy 7.965987 -63.07929) (xy 7.913688 -63.063932) (xy 7.864108 -63.041288)
			(xy 7.818254 -63.011818) (xy 7.777061 -62.976122) (xy 7.741368 -62.934927) (xy 7.711901 -62.889071)
			(xy 7.689259 -62.839489) (xy 7.673905 -62.787189) (xy 7.66615 -62.733236) (xy 1.306576 -62.733236)
			(xy 1.306576 -63.273432) (xy 3.576826 -63.273432) (xy 3.580897 -63.21781) (xy 3.593023 -63.163373)
			(xy 3.612946 -63.111282) (xy 3.640242 -63.062647) (xy 3.674328 -63.018504) (xy 3.714477 -62.979795)
			(xy 3.759835 -62.947344) (xy 3.809435 -62.921843) (xy 3.862219 -62.903836) (xy 3.917062 -62.893706)
			(xy 3.972796 -62.891669) (xy 4.028233 -62.897769) (xy 4.08219 -62.911875) (xy 4.133519 -62.933687)
			(xy 4.181125 -62.962741) (xy 4.223993 -62.998416) (xy 4.26121 -63.039953) (xy 4.291983 -63.086466)
			(xy 4.315655 -63.136963) (xy 4.331723 -63.19037) (xy 4.335134 -63.213549) (xy 22.120888 -63.213549)
			(xy 22.120888 -63.159051) (xy 22.128643 -63.105109) (xy 22.143996 -63.052818) (xy 22.166634 -63.003245)
			(xy 22.196095 -62.957398) (xy 22.231782 -62.91621) (xy 22.272966 -62.880519) (xy 22.31881 -62.851053)
			(xy 22.368381 -62.82841) (xy 22.420669 -62.813052) (xy 22.474611 -62.805291) (xy 22.50186 -62.804802)
			(xy 22.529229 -62.805291) (xy 22.583408 -62.813103) (xy 22.63591 -62.828587) (xy 22.685658 -62.851424)
			(xy 22.731626 -62.881143) (xy 22.752558 -62.898782) (xy 22.752812 -62.899036) (xy 22.759888 -62.904638)
			(xy 22.776813 -62.910874) (xy 22.785832 -62.911228) (xy 22.852888 -62.911228) (xy 22.861904 -62.910859)
			(xy 22.87882 -62.904619) (xy 22.885908 -62.899036) (xy 22.885908 -62.898782) (xy 22.886162 -62.898782)
			(xy 22.907095 -62.881141) (xy 22.953063 -62.851417) (xy 23.002809 -62.828571) (xy 23.055311 -62.813075)
			(xy 23.109489 -62.805246) (xy 23.164231 -62.805246) (xy 23.218409 -62.813075) (xy 23.270911 -62.828571)
			(xy 23.320657 -62.851417) (xy 23.366625 -62.881141) (xy 23.387558 -62.898782) (xy 23.387812 -62.899036)
			(xy 23.394888 -62.904638) (xy 23.411813 -62.910874) (xy 23.420832 -62.911228) (xy 23.487888 -62.911228)
			(xy 23.496904 -62.910859) (xy 23.51382 -62.904619) (xy 23.520908 -62.899036) (xy 23.520908 -62.898782)
			(xy 23.521162 -62.898782) (xy 23.542095 -62.881144) (xy 23.588068 -62.851433) (xy 23.637815 -62.828597)
			(xy 23.690316 -62.813106) (xy 23.744491 -62.805277) (xy 23.77186 -62.804802) (xy 23.799115 -62.805242)
			(xy 23.853072 -62.812995) (xy 23.905376 -62.828348) (xy 23.954963 -62.850989) (xy 24.000822 -62.880456)
			(xy 24.042021 -62.916151) (xy 24.07772 -62.957346) (xy 24.107192 -63.003202) (xy 24.129838 -63.052786)
			(xy 24.13966 -63.086234) (xy 27.387548 -63.086234) (xy 27.391619 -63.030612) (xy 27.403745 -62.976175)
			(xy 27.423668 -62.924084) (xy 27.450964 -62.875449) (xy 27.48505 -62.831306) (xy 27.525199 -62.792597)
			(xy 27.570557 -62.760146) (xy 27.620157 -62.734645) (xy 27.672941 -62.716638) (xy 27.727784 -62.706508)
			(xy 27.783518 -62.704471) (xy 27.797377 -62.705996) (xy 33.665158 -62.705996) (xy 33.669229 -62.650374)
			(xy 33.681355 -62.595937) (xy 33.701278 -62.543846) (xy 33.728574 -62.495211) (xy 33.76266 -62.451068)
			(xy 33.802809 -62.412359) (xy 33.848167 -62.379908) (xy 33.897767 -62.354407) (xy 33.950551 -62.3364)
			(xy 34.005394 -62.32627) (xy 34.061128 -62.324233) (xy 34.116565 -62.330333) (xy 34.170522 -62.344439)
			(xy 34.221851 -62.366251) (xy 34.269457 -62.395305) (xy 34.312325 -62.43098) (xy 34.349542 -62.472517)
			(xy 34.380315 -62.51903) (xy 34.403987 -62.569527) (xy 34.420055 -62.622934) (xy 34.428175 -62.67811)
			(xy 34.428684 -62.705996) (xy 34.428175 -62.733882) (xy 34.420055 -62.789058) (xy 34.403987 -62.842465)
			(xy 34.380315 -62.892962) (xy 34.349542 -62.939475) (xy 34.312325 -62.981012) (xy 34.269457 -63.016687)
			(xy 34.221851 -63.045741) (xy 34.170522 -63.067553) (xy 34.116565 -63.081659) (xy 34.061128 -63.087759)
			(xy 34.005394 -63.085722) (xy 33.950551 -63.075592) (xy 33.897767 -63.057585) (xy 33.848167 -63.032084)
			(xy 33.802809 -62.999633) (xy 33.76266 -62.960924) (xy 33.728574 -62.916781) (xy 33.701278 -62.868146)
			(xy 33.681355 -62.816055) (xy 33.669229 -62.761618) (xy 33.665158 -62.705996) (xy 27.797377 -62.705996)
			(xy 27.838955 -62.710571) (xy 27.892912 -62.724677) (xy 27.944241 -62.746489) (xy 27.991847 -62.775543)
			(xy 28.034715 -62.811218) (xy 28.071932 -62.852755) (xy 28.102705 -62.899268) (xy 28.126377 -62.949765)
			(xy 28.142445 -63.003172) (xy 28.150565 -63.058348) (xy 28.151074 -63.086234) (xy 28.150565 -63.11412)
			(xy 28.142445 -63.169296) (xy 28.126377 -63.222703) (xy 28.102705 -63.2732) (xy 28.102552 -63.273432)
			(xy 29.576774 -63.273432) (xy 29.580845 -63.21781) (xy 29.592971 -63.163373) (xy 29.612894 -63.111282)
			(xy 29.64019 -63.062647) (xy 29.674276 -63.018504) (xy 29.714425 -62.979795) (xy 29.759783 -62.947344)
			(xy 29.809383 -62.921843) (xy 29.862167 -62.903836) (xy 29.91701 -62.893706) (xy 29.972744 -62.891669)
			(xy 30.028181 -62.897769) (xy 30.082138 -62.911875) (xy 30.133467 -62.933687) (xy 30.181073 -62.962741)
			(xy 30.223941 -62.998416) (xy 30.261158 -63.039953) (xy 30.291931 -63.086466) (xy 30.315603 -63.136963)
			(xy 30.331671 -63.19037) (xy 30.339791 -63.245546) (xy 30.3403 -63.273432) (xy 30.339791 -63.301318)
			(xy 30.331671 -63.356494) (xy 30.315603 -63.409901) (xy 30.291931 -63.460398) (xy 30.261158 -63.506911)
			(xy 30.223941 -63.548448) (xy 30.181073 -63.584123) (xy 30.133467 -63.613177) (xy 30.082138 -63.634989)
			(xy 30.028181 -63.649095) (xy 29.972744 -63.655195) (xy 29.91701 -63.653158) (xy 29.862167 -63.643028)
			(xy 29.809383 -63.625021) (xy 29.759783 -63.59952) (xy 29.714425 -63.567069) (xy 29.674276 -63.52836)
			(xy 29.64019 -63.484217) (xy 29.612894 -63.435582) (xy 29.592971 -63.383491) (xy 29.580845 -63.329054)
			(xy 29.576774 -63.273432) (xy 28.102552 -63.273432) (xy 28.071932 -63.319713) (xy 28.034715 -63.36125)
			(xy 27.991847 -63.396925) (xy 27.944241 -63.425979) (xy 27.892912 -63.447791) (xy 27.838955 -63.461897)
			(xy 27.783518 -63.467997) (xy 27.727784 -63.46596) (xy 27.672941 -63.45583) (xy 27.620157 -63.437823)
			(xy 27.570557 -63.412322) (xy 27.525199 -63.379871) (xy 27.48505 -63.341162) (xy 27.450964 -63.297019)
			(xy 27.423668 -63.248384) (xy 27.403745 -63.196293) (xy 27.391619 -63.141856) (xy 27.387548 -63.086234)
			(xy 24.13966 -63.086234) (xy 24.145197 -63.105089) (xy 24.152955 -63.159045) (xy 24.152955 -63.213555)
			(xy 24.145197 -63.267511) (xy 24.129838 -63.319814) (xy 24.107192 -63.369398) (xy 24.07772 -63.415254)
			(xy 24.042021 -63.456449) (xy 24.000822 -63.492144) (xy 23.954963 -63.521611) (xy 23.905376 -63.544252)
			(xy 23.853072 -63.559605) (xy 23.799115 -63.567358) (xy 23.77186 -63.567818) (xy 23.74449 -63.567337)
			(xy 23.690311 -63.559526) (xy 23.637807 -63.544041) (xy 23.58806 -63.521202) (xy 23.542093 -63.491479)
			(xy 23.521162 -63.473838) (xy 23.520908 -63.473584) (xy 23.513825 -63.467993) (xy 23.496905 -63.461749)
			(xy 23.487888 -63.461392) (xy 23.420832 -63.461392) (xy 23.411817 -63.461766) (xy 23.3949 -63.468002)
			(xy 23.387812 -63.473584) (xy 23.387558 -63.473838) (xy 23.366625 -63.491479) (xy 23.320657 -63.521203)
			(xy 23.270911 -63.544049) (xy 23.218409 -63.559545) (xy 23.164231 -63.567374) (xy 23.109489 -63.567374)
			(xy 23.055311 -63.559545) (xy 23.002809 -63.544049) (xy 22.953063 -63.521203) (xy 22.907095 -63.491479)
			(xy 22.886162 -63.473838) (xy 22.885908 -63.473584) (xy 22.878825 -63.467993) (xy 22.861905 -63.461749)
			(xy 22.852888 -63.461392) (xy 22.785832 -63.461392) (xy 22.776817 -63.461766) (xy 22.7599 -63.468002)
			(xy 22.752812 -63.473584) (xy 22.752812 -63.473838) (xy 22.752558 -63.473838) (xy 22.73162 -63.49147)
			(xy 22.685648 -63.521181) (xy 22.635902 -63.544018) (xy 22.583403 -63.559511) (xy 22.529229 -63.567343)
			(xy 22.50186 -63.567818) (xy 22.474611 -63.567309) (xy 22.420669 -63.559548) (xy 22.368381 -63.54419)
			(xy 22.31881 -63.521547) (xy 22.272966 -63.492081) (xy 22.231782 -63.45639) (xy 22.196095 -63.415202)
			(xy 22.166634 -63.369355) (xy 22.143996 -63.319782) (xy 22.128643 -63.267491) (xy 22.120888 -63.213549)
			(xy 4.335134 -63.213549) (xy 4.339843 -63.245546) (xy 4.340352 -63.273432) (xy 4.339843 -63.301318)
			(xy 4.331723 -63.356494) (xy 4.315655 -63.409901) (xy 4.291983 -63.460398) (xy 4.26121 -63.506911)
			(xy 4.223993 -63.548448) (xy 4.181125 -63.584123) (xy 4.133519 -63.613177) (xy 4.08219 -63.634989)
			(xy 4.028233 -63.649095) (xy 3.972796 -63.655195) (xy 3.917062 -63.653158) (xy 3.862219 -63.643028)
			(xy 3.809435 -63.625021) (xy 3.759835 -63.59952) (xy 3.714477 -63.567069) (xy 3.674328 -63.52836)
			(xy 3.640242 -63.484217) (xy 3.612946 -63.435582) (xy 3.593023 -63.383491) (xy 3.580897 -63.329054)
			(xy 3.576826 -63.273432) (xy 1.306576 -63.273432) (xy 1.306576 -64.737234) (xy 1.896362 -64.737234)
			(xy 1.900433 -64.681612) (xy 1.912559 -64.627175) (xy 1.932482 -64.575084) (xy 1.959778 -64.526449)
			(xy 1.993864 -64.482306) (xy 2.034013 -64.443597) (xy 2.079371 -64.411146) (xy 2.128971 -64.385645)
			(xy 2.181755 -64.367638) (xy 2.236598 -64.357508) (xy 2.292332 -64.355471) (xy 2.347769 -64.361571)
			(xy 2.401726 -64.375677) (xy 2.453055 -64.397489) (xy 2.500661 -64.426543) (xy 2.543529 -64.462218)
			(xy 2.580746 -64.503755) (xy 2.611519 -64.550268) (xy 2.635191 -64.600765) (xy 2.651259 -64.654172)
			(xy 2.659379 -64.709348) (xy 2.659888 -64.737234) (xy 2.659379 -64.76512) (xy 2.651259 -64.820296)
			(xy 2.635191 -64.873703) (xy 2.611519 -64.9242) (xy 2.580746 -64.970713) (xy 2.543529 -65.01225)
			(xy 2.500661 -65.047925) (xy 2.453055 -65.076979) (xy 2.401726 -65.098791) (xy 2.347769 -65.112897)
			(xy 2.292332 -65.118997) (xy 2.236598 -65.11696) (xy 2.181755 -65.10683) (xy 2.128971 -65.088823)
			(xy 2.079371 -65.063322) (xy 2.034013 -65.030871) (xy 1.993864 -64.992162) (xy 1.959778 -64.948019)
			(xy 1.932482 -64.899384) (xy 1.912559 -64.847293) (xy 1.900433 -64.792856) (xy 1.896362 -64.737234)
			(xy 1.306576 -64.737234) (xy 1.306576 -65.124076) (xy 6.107428 -65.124076) (xy 6.111499 -65.068454)
			(xy 6.123625 -65.014017) (xy 6.143548 -64.961926) (xy 6.170844 -64.913291) (xy 6.20493 -64.869148)
			(xy 6.245079 -64.830439) (xy 6.290437 -64.797988) (xy 6.340037 -64.772487) (xy 6.392821 -64.75448)
			(xy 6.447664 -64.74435) (xy 6.503398 -64.742313) (xy 6.558835 -64.748413) (xy 6.612792 -64.762519)
			(xy 6.664121 -64.784331) (xy 6.711727 -64.813385) (xy 6.754595 -64.84906) (xy 6.791812 -64.890597)
			(xy 6.822585 -64.93711) (xy 6.846257 -64.987607) (xy 6.862325 -65.041014) (xy 6.870445 -65.09619)
			(xy 6.870532 -65.100962) (xy 20.132546 -65.100962) (xy 20.136617 -65.04534) (xy 20.148743 -64.990903)
			(xy 20.168666 -64.938812) (xy 20.195962 -64.890177) (xy 20.230048 -64.846034) (xy 20.270197 -64.807325)
			(xy 20.315555 -64.774874) (xy 20.365155 -64.749373) (xy 20.417939 -64.731366) (xy 20.472782 -64.721236)
			(xy 20.528516 -64.719199) (xy 20.583953 -64.725299) (xy 20.63791 -64.739405) (xy 20.689239 -64.761217)
			(xy 20.736845 -64.790271) (xy 20.779713 -64.825946) (xy 20.81693 -64.867483) (xy 20.847703 -64.913996)
			(xy 20.871375 -64.964493) (xy 20.887443 -65.0179) (xy 20.895563 -65.073076) (xy 20.896072 -65.100962)
			(xy 20.89565 -65.124076) (xy 32.107376 -65.124076) (xy 32.111447 -65.068454) (xy 32.123573 -65.014017)
			(xy 32.143496 -64.961926) (xy 32.170792 -64.913291) (xy 32.204878 -64.869148) (xy 32.245027 -64.830439)
			(xy 32.290385 -64.797988) (xy 32.339985 -64.772487) (xy 32.392769 -64.75448) (xy 32.447612 -64.74435)
			(xy 32.503346 -64.742313) (xy 32.558783 -64.748413) (xy 32.61274 -64.762519) (xy 32.664069 -64.784331)
			(xy 32.711675 -64.813385) (xy 32.754543 -64.84906) (xy 32.79176 -64.890597) (xy 32.822533 -64.93711)
			(xy 32.846205 -64.987607) (xy 32.862273 -65.041014) (xy 32.870393 -65.09619) (xy 32.870902 -65.124076)
			(xy 32.870393 -65.151962) (xy 32.862273 -65.207138) (xy 32.846205 -65.260545) (xy 32.822533 -65.311042)
			(xy 32.79176 -65.357555) (xy 32.754543 -65.399092) (xy 32.711675 -65.434767) (xy 32.664069 -65.463821)
			(xy 32.61274 -65.485633) (xy 32.558783 -65.499739) (xy 32.503346 -65.505839) (xy 32.447612 -65.503802)
			(xy 32.392769 -65.493672) (xy 32.339985 -65.475665) (xy 32.290385 -65.450164) (xy 32.245027 -65.417713)
			(xy 32.204878 -65.379004) (xy 32.170792 -65.334861) (xy 32.143496 -65.286226) (xy 32.123573 -65.234135)
			(xy 32.111447 -65.179698) (xy 32.107376 -65.124076) (xy 20.89565 -65.124076) (xy 20.895563 -65.128848)
			(xy 20.887443 -65.184024) (xy 20.871375 -65.237431) (xy 20.847703 -65.287928) (xy 20.81693 -65.334441)
			(xy 20.779713 -65.375978) (xy 20.736845 -65.411653) (xy 20.689239 -65.440707) (xy 20.63791 -65.462519)
			(xy 20.583953 -65.476625) (xy 20.528516 -65.482725) (xy 20.472782 -65.480688) (xy 20.417939 -65.470558)
			(xy 20.365155 -65.452551) (xy 20.315555 -65.42705) (xy 20.270197 -65.394599) (xy 20.230048 -65.35589)
			(xy 20.195962 -65.311747) (xy 20.168666 -65.263112) (xy 20.148743 -65.211021) (xy 20.136617 -65.156584)
			(xy 20.132546 -65.100962) (xy 6.870532 -65.100962) (xy 6.870954 -65.124076) (xy 6.870445 -65.151962)
			(xy 6.862325 -65.207138) (xy 6.846257 -65.260545) (xy 6.822585 -65.311042) (xy 6.791812 -65.357555)
			(xy 6.754595 -65.399092) (xy 6.711727 -65.434767) (xy 6.664121 -65.463821) (xy 6.612792 -65.485633)
			(xy 6.558835 -65.499739) (xy 6.503398 -65.505839) (xy 6.447664 -65.503802) (xy 6.392821 -65.493672)
			(xy 6.340037 -65.475665) (xy 6.290437 -65.450164) (xy 6.245079 -65.417713) (xy 6.20493 -65.379004)
			(xy 6.170844 -65.334861) (xy 6.143548 -65.286226) (xy 6.123625 -65.234135) (xy 6.111499 -65.179698)
			(xy 6.107428 -65.124076) (xy 1.306576 -65.124076) (xy 1.306576 -65.882774) (xy 3.101592 -65.882774)
			(xy 3.105663 -65.827152) (xy 3.117789 -65.772715) (xy 3.137712 -65.720624) (xy 3.165008 -65.671989)
			(xy 3.199094 -65.627846) (xy 3.239243 -65.589137) (xy 3.284601 -65.556686) (xy 3.334201 -65.531185)
			(xy 3.386985 -65.513178) (xy 3.441828 -65.503048) (xy 3.497562 -65.501011) (xy 3.552999 -65.507111)
			(xy 3.606956 -65.521217) (xy 3.658285 -65.543029) (xy 3.705891 -65.572083) (xy 3.748759 -65.607758)
			(xy 3.785976 -65.649295) (xy 3.816749 -65.695808) (xy 3.840421 -65.746305) (xy 3.843193 -65.75552)
			(xy 14.34668 -65.75552) (xy 14.350751 -65.699898) (xy 14.362877 -65.645461) (xy 14.3828 -65.59337)
			(xy 14.410096 -65.544735) (xy 14.444182 -65.500592) (xy 14.484331 -65.461883) (xy 14.529689 -65.429432)
			(xy 14.579289 -65.403931) (xy 14.632073 -65.385924) (xy 14.686916 -65.375794) (xy 14.74265 -65.373757)
			(xy 14.798087 -65.379857) (xy 14.852044 -65.393963) (xy 14.903373 -65.415775) (xy 14.950979 -65.444829)
			(xy 14.993847 -65.480504) (xy 15.031064 -65.522041) (xy 15.061837 -65.568554) (xy 15.085509 -65.619051)
			(xy 15.101577 -65.672458) (xy 15.109697 -65.727634) (xy 15.110206 -65.75552) (xy 15.109697 -65.783406)
			(xy 15.101577 -65.838582) (xy 15.085509 -65.891989) (xy 15.061837 -65.942486) (xy 15.031064 -65.988999)
			(xy 14.993847 -66.030536) (xy 14.950979 -66.066211) (xy 14.903373 -66.095265) (xy 14.852044 -66.117077)
			(xy 14.798087 -66.131183) (xy 14.74265 -66.137283) (xy 14.686916 -66.135246) (xy 14.632073 -66.125116)
			(xy 14.579289 -66.107109) (xy 14.529689 -66.081608) (xy 14.484331 -66.049157) (xy 14.444182 -66.010448)
			(xy 14.410096 -65.966305) (xy 14.3828 -65.91767) (xy 14.362877 -65.865579) (xy 14.350751 -65.811142)
			(xy 14.34668 -65.75552) (xy 3.843193 -65.75552) (xy 3.856489 -65.799712) (xy 3.864609 -65.854888)
			(xy 3.865118 -65.882774) (xy 3.864609 -65.91066) (xy 3.856489 -65.965836) (xy 3.840421 -66.019243)
			(xy 3.816749 -66.06974) (xy 3.785976 -66.116253) (xy 3.748759 -66.15779) (xy 3.705891 -66.193465)
			(xy 3.658285 -66.222519) (xy 3.606956 -66.244331) (xy 3.552999 -66.258437) (xy 3.497562 -66.264537)
			(xy 3.441828 -66.2625) (xy 3.386985 -66.25237) (xy 3.334201 -66.234363) (xy 3.284601 -66.208862)
			(xy 3.239243 -66.176411) (xy 3.199094 -66.137702) (xy 3.165008 -66.093559) (xy 3.137712 -66.044924)
			(xy 3.117789 -65.992833) (xy 3.105663 -65.938396) (xy 3.101592 -65.882774) (xy 1.306576 -65.882774)
			(xy 1.306576 -66.567812) (xy 6.304532 -66.567812) (xy 6.308603 -66.51219) (xy 6.320729 -66.457753)
			(xy 6.340652 -66.405662) (xy 6.367948 -66.357027) (xy 6.402034 -66.312884) (xy 6.442183 -66.274175)
			(xy 6.487541 -66.241724) (xy 6.537141 -66.216223) (xy 6.589925 -66.198216) (xy 6.644768 -66.188086)
			(xy 6.700502 -66.186049) (xy 6.755939 -66.192149) (xy 6.809896 -66.206255) (xy 6.861225 -66.228067)
			(xy 6.908831 -66.257121) (xy 6.951699 -66.292796) (xy 6.988916 -66.334333) (xy 7.019689 -66.380846)
			(xy 7.043361 -66.431343) (xy 7.059429 -66.48475) (xy 7.067549 -66.539926) (xy 7.068058 -66.567812)
			(xy 7.067549 -66.595698) (xy 7.059429 -66.650874) (xy 7.043361 -66.704281) (xy 7.019689 -66.754778)
			(xy 6.988916 -66.801291) (xy 6.951699 -66.842828) (xy 6.908831 -66.878503) (xy 6.861225 -66.907557)
			(xy 6.809896 -66.929369) (xy 6.755939 -66.943475) (xy 6.700502 -66.949575) (xy 6.644768 -66.947538)
			(xy 6.589925 -66.937408) (xy 6.537141 -66.919401) (xy 6.487541 -66.8939) (xy 6.442183 -66.861449)
			(xy 6.402034 -66.82274) (xy 6.367948 -66.778597) (xy 6.340652 -66.729962) (xy 6.320729 -66.677871)
			(xy 6.308603 -66.623434) (xy 6.304532 -66.567812) (xy 1.306576 -66.567812) (xy 1.306576 -67.201034)
			(xy 4.242306 -67.201034) (xy 4.246377 -67.145412) (xy 4.258503 -67.090975) (xy 4.278426 -67.038884)
			(xy 4.305722 -66.990249) (xy 4.339808 -66.946106) (xy 4.379957 -66.907397) (xy 4.425315 -66.874946)
			(xy 4.474915 -66.849445) (xy 4.527699 -66.831438) (xy 4.582542 -66.821308) (xy 4.638276 -66.819271)
			(xy 4.693713 -66.825371) (xy 4.74767 -66.839477) (xy 4.798999 -66.861289) (xy 4.846605 -66.890343)
			(xy 4.889473 -66.926018) (xy 4.92669 -66.967555) (xy 4.957463 -67.014068) (xy 4.981135 -67.064565)
			(xy 4.997203 -67.117972) (xy 4.998822 -67.128971) (xy 14.366728 -67.128971) (xy 14.366728 -67.074469)
			(xy 14.374484 -67.020521) (xy 14.389839 -66.968227) (xy 14.41248 -66.91865) (xy 14.441946 -66.872799)
			(xy 14.477638 -66.831609) (xy 14.518828 -66.795918) (xy 14.564678 -66.766451) (xy 14.614255 -66.74381)
			(xy 14.666549 -66.728455) (xy 14.720497 -66.720698) (xy 14.747748 -66.720212) (xy 14.775117 -66.720706)
			(xy 14.829295 -66.728516) (xy 14.881798 -66.743999) (xy 14.931546 -66.766834) (xy 14.977514 -66.796553)
			(xy 14.998446 -66.814192) (xy 14.9987 -66.814446) (xy 15.005778 -66.820044) (xy 15.022702 -66.826283)
			(xy 15.03172 -66.826638) (xy 15.098776 -66.826638) (xy 15.107791 -66.826261) (xy 15.124707 -66.820026)
			(xy 15.131796 -66.814446) (xy 15.131796 -66.814192) (xy 15.13205 -66.814192) (xy 15.152989 -66.796562)
			(xy 15.19896 -66.766849) (xy 15.248706 -66.744011) (xy 15.301205 -66.728518) (xy 15.355379 -66.720687)
			(xy 15.382748 -66.720212) (xy 15.410001 -66.720675) (xy 15.463952 -66.728432) (xy 15.51625 -66.743788)
			(xy 15.565831 -66.76643) (xy 15.611684 -66.795898) (xy 15.652877 -66.831592) (xy 15.688571 -66.872784)
			(xy 15.718039 -66.918638) (xy 15.740682 -66.968218) (xy 15.756038 -67.020516) (xy 15.763795 -67.074467)
			(xy 15.763795 -67.128973) (xy 15.756038 -67.182924) (xy 15.740682 -67.235222) (xy 15.718039 -67.284802)
			(xy 15.688571 -67.330656) (xy 15.652877 -67.371848) (xy 15.611684 -67.407542) (xy 15.565831 -67.43701)
			(xy 15.51625 -67.459652) (xy 15.463952 -67.475008) (xy 15.410001 -67.482765) (xy 15.382748 -67.483228)
			(xy 15.355378 -67.482751) (xy 15.301199 -67.474939) (xy 15.248695 -67.459453) (xy 15.198948 -67.436613)
			(xy 15.152981 -67.406889) (xy 15.13205 -67.389248) (xy 15.131796 -67.388994) (xy 15.124715 -67.383399)
			(xy 15.107794 -67.377158) (xy 15.098776 -67.376802) (xy 15.03172 -67.376802) (xy 15.022704 -67.377168)
			(xy 15.005787 -67.383409) (xy 14.9987 -67.388994) (xy 14.9987 -67.389248) (xy 14.998446 -67.389248)
			(xy 14.977501 -67.406871) (xy 14.931532 -67.436587) (xy 14.881788 -67.459427) (xy 14.82929 -67.474922)
			(xy 14.775116 -67.482753) (xy 14.747748 -67.483228) (xy 14.720497 -67.482742) (xy 14.666549 -67.474985)
			(xy 14.614255 -67.45963) (xy 14.564678 -67.436989) (xy 14.518828 -67.407522) (xy 14.477638 -67.371831)
			(xy 14.441946 -67.330641) (xy 14.41248 -67.28479) (xy 14.389839 -67.235213) (xy 14.374484 -67.182919)
			(xy 14.366728 -67.128971) (xy 4.998822 -67.128971) (xy 5.005323 -67.173148) (xy 5.005832 -67.201034)
			(xy 5.005323 -67.22892) (xy 4.997203 -67.284096) (xy 4.981135 -67.337503) (xy 4.957463 -67.388) (xy 4.92669 -67.434513)
			(xy 4.889473 -67.47605) (xy 4.846605 -67.511725) (xy 4.798999 -67.540779) (xy 4.74767 -67.562591)
			(xy 4.693713 -67.576697) (xy 4.638276 -67.582797) (xy 4.582542 -67.58076) (xy 4.527699 -67.57063)
			(xy 4.474915 -67.552623) (xy 4.425315 -67.527122) (xy 4.379957 -67.494671) (xy 4.339808 -67.455962)
			(xy 4.305722 -67.411819) (xy 4.278426 -67.363184) (xy 4.258503 -67.311093) (xy 4.246377 -67.256656)
			(xy 4.242306 -67.201034) (xy 1.306576 -67.201034) (xy 1.306576 -67.785996) (xy 7.66521 -67.785996)
			(xy 7.669281 -67.730374) (xy 7.681407 -67.675937) (xy 7.70133 -67.623846) (xy 7.728626 -67.575211)
			(xy 7.762712 -67.531068) (xy 7.802861 -67.492359) (xy 7.848219 -67.459908) (xy 7.897819 -67.434407)
			(xy 7.950603 -67.4164) (xy 8.005446 -67.40627) (xy 8.06118 -67.404233) (xy 8.116617 -67.410333) (xy 8.170574 -67.424439)
			(xy 8.221903 -67.446251) (xy 8.269509 -67.475305) (xy 8.284829 -67.488054) (xy 18.779234 -67.488054)
			(xy 18.783305 -67.432432) (xy 18.795431 -67.377995) (xy 18.815354 -67.325904) (xy 18.84265 -67.277269)
			(xy 18.876736 -67.233126) (xy 18.916885 -67.194417) (xy 18.962243 -67.161966) (xy 19.011843 -67.136465)
			(xy 19.064627 -67.118458) (xy 19.11947 -67.108328) (xy 19.175204 -67.106291) (xy 19.230641 -67.112391)
			(xy 19.284598 -67.126497) (xy 19.335927 -67.148309) (xy 19.383533 -67.177363) (xy 19.426401 -67.213038)
			(xy 19.463618 -67.254575) (xy 19.494391 -67.301088) (xy 19.518063 -67.351585) (xy 19.534131 -67.404992)
			(xy 19.542251 -67.460168) (xy 19.54276 -67.488054) (xy 19.542251 -67.51594) (xy 19.539066 -67.537584)
			(xy 20.071332 -67.537584) (xy 20.075403 -67.481962) (xy 20.087529 -67.427525) (xy 20.107452 -67.375434)
			(xy 20.134748 -67.326799) (xy 20.168834 -67.282656) (xy 20.208983 -67.243947) (xy 20.254341 -67.211496)
			(xy 20.303941 -67.185995) (xy 20.356725 -67.167988) (xy 20.411568 -67.157858) (xy 20.467302 -67.155821)
			(xy 20.522739 -67.161921) (xy 20.576696 -67.176027) (xy 20.628025 -67.197839) (xy 20.675631 -67.226893)
			(xy 20.718499 -67.262568) (xy 20.755716 -67.304105) (xy 20.786489 -67.350618) (xy 20.810161 -67.401115)
			(xy 20.826229 -67.454522) (xy 20.834349 -67.509698) (xy 20.834858 -67.537584) (xy 20.834349 -67.56547)
			(xy 20.830304 -67.592956) (xy 21.345396 -67.592956) (xy 21.349467 -67.537334) (xy 21.361593 -67.482897)
			(xy 21.381516 -67.430806) (xy 21.408812 -67.382171) (xy 21.442898 -67.338028) (xy 21.483047 -67.299319)
			(xy 21.528405 -67.266868) (xy 21.578005 -67.241367) (xy 21.630789 -67.22336) (xy 21.685632 -67.21323)
			(xy 21.741366 -67.211193) (xy 21.796803 -67.217293) (xy 21.85076 -67.231399) (xy 21.902089 -67.253211)
			(xy 21.949695 -67.282265) (xy 21.992563 -67.31794) (xy 22.02978 -67.359477) (xy 22.060553 -67.40599)
			(xy 22.084225 -67.456487) (xy 22.100293 -67.509894) (xy 22.10841 -67.565052) (xy 24.446693 -67.565052)
			(xy 24.446693 -67.510548) (xy 24.454451 -67.456599) (xy 24.469807 -67.404304) (xy 24.49245 -67.354726)
			(xy 24.521919 -67.308875) (xy 24.557613 -67.267686) (xy 24.598806 -67.231996) (xy 24.644659 -67.202532)
			(xy 24.694239 -67.179894) (xy 24.746536 -67.164542) (xy 24.800486 -67.156791) (xy 24.827738 -67.15633)
			(xy 24.855107 -67.156825) (xy 24.909285 -67.164635) (xy 24.961788 -67.180117) (xy 25.011536 -67.202952)
			(xy 25.057504 -67.232671) (xy 25.078436 -67.25031) (xy 25.07869 -67.250564) (xy 25.08577 -67.25616)
			(xy 25.102692 -67.262399) (xy 25.11171 -67.262756) (xy 25.178766 -67.262756) (xy 25.187782 -67.262392)
			(xy 25.2047 -67.25615) (xy 25.211786 -67.250564) (xy 25.211786 -67.25031) (xy 25.21204 -67.25031)
			(xy 25.232985 -67.232687) (xy 25.278954 -67.202973) (xy 25.328698 -67.180133) (xy 25.381196 -67.164638)
			(xy 25.43537 -67.156806) (xy 25.462738 -67.15633) (xy 25.48999 -67.156742) (xy 25.543939 -67.164504)
			(xy 25.596235 -67.179864) (xy 25.645812 -67.20251) (xy 25.691662 -67.23198) (xy 25.732852 -67.267675)
			(xy 25.768543 -67.308868) (xy 25.798009 -67.354721) (xy 25.820649 -67.404301) (xy 25.836004 -67.456598)
			(xy 25.84376 -67.510548) (xy 25.84376 -67.565052) (xy 25.836004 -67.619002) (xy 25.820649 -67.671299)
			(xy 25.798009 -67.720879) (xy 25.768543 -67.766732) (xy 25.732852 -67.807925) (xy 25.691662 -67.84362)
			(xy 25.645812 -67.87309) (xy 25.596235 -67.895736) (xy 25.543939 -67.911096) (xy 25.48999 -67.918858)
			(xy 25.462738 -67.919346) (xy 25.435368 -67.918871) (xy 25.381189 -67.911057) (xy 25.328685 -67.895571)
			(xy 25.278938 -67.872731) (xy 25.232971 -67.843007) (xy 25.21204 -67.825366) (xy 25.211786 -67.825112)
			(xy 25.204707 -67.819515) (xy 25.187784 -67.813274) (xy 25.178766 -67.81292) (xy 25.11171 -67.81292)
			(xy 25.102693 -67.813277) (xy 25.085776 -67.819524) (xy 25.07869 -67.825112) (xy 25.07869 -67.825366)
			(xy 25.078436 -67.825366) (xy 25.057497 -67.842996) (xy 25.011527 -67.872711) (xy 24.961781 -67.895549)
			(xy 24.909282 -67.911042) (xy 24.855107 -67.918871) (xy 24.827738 -67.919346) (xy 24.800486 -67.918809)
			(xy 24.746536 -67.911058) (xy 24.694239 -67.895706) (xy 24.644659 -67.873068) (xy 24.598806 -67.843604)
			(xy 24.557613 -67.807914) (xy 24.521919 -67.766725) (xy 24.49245 -67.720874) (xy 24.469807 -67.671296)
			(xy 24.454451 -67.619001) (xy 24.446693 -67.565052) (xy 22.10841 -67.565052) (xy 22.108413 -67.56507)
			(xy 22.108922 -67.592956) (xy 22.108413 -67.620842) (xy 22.100293 -67.676018) (xy 22.084225 -67.729425)
			(xy 22.060553 -67.779922) (xy 22.02978 -67.826435) (xy 21.992563 -67.867972) (xy 21.949695 -67.903647)
			(xy 21.902089 -67.932701) (xy 21.85076 -67.954513) (xy 21.796803 -67.968619) (xy 21.741366 -67.974719)
			(xy 21.685632 -67.972682) (xy 21.630789 -67.962552) (xy 21.578005 -67.944545) (xy 21.528405 -67.919044)
			(xy 21.483047 -67.886593) (xy 21.442898 -67.847884) (xy 21.408812 -67.803741) (xy 21.381516 -67.755106)
			(xy 21.361593 -67.703015) (xy 21.349467 -67.648578) (xy 21.345396 -67.592956) (xy 20.830304 -67.592956)
			(xy 20.826229 -67.620646) (xy 20.810161 -67.674053) (xy 20.786489 -67.72455) (xy 20.755716 -67.771063)
			(xy 20.718499 -67.8126) (xy 20.675631 -67.848275) (xy 20.628025 -67.877329) (xy 20.576696 -67.899141)
			(xy 20.522739 -67.913247) (xy 20.467302 -67.919347) (xy 20.411568 -67.91731) (xy 20.356725 -67.90718)
			(xy 20.303941 -67.889173) (xy 20.254341 -67.863672) (xy 20.208983 -67.831221) (xy 20.168834 -67.792512)
			(xy 20.134748 -67.748369) (xy 20.107452 -67.699734) (xy 20.087529 -67.647643) (xy 20.075403 -67.593206)
			(xy 20.071332 -67.537584) (xy 19.539066 -67.537584) (xy 19.534131 -67.571116) (xy 19.518063 -67.624523)
			(xy 19.494391 -67.67502) (xy 19.463618 -67.721533) (xy 19.426401 -67.76307) (xy 19.383533 -67.798745)
			(xy 19.335927 -67.827799) (xy 19.284598 -67.849611) (xy 19.230641 -67.863717) (xy 19.175204 -67.869817)
			(xy 19.11947 -67.86778) (xy 19.064627 -67.85765) (xy 19.011843 -67.839643) (xy 18.962243 -67.814142)
			(xy 18.916885 -67.781691) (xy 18.876736 -67.742982) (xy 18.84265 -67.698839) (xy 18.815354 -67.650204)
			(xy 18.795431 -67.598113) (xy 18.783305 -67.543676) (xy 18.779234 -67.488054) (xy 8.284829 -67.488054)
			(xy 8.312377 -67.51098) (xy 8.349594 -67.552517) (xy 8.380367 -67.59903) (xy 8.404039 -67.649527)
			(xy 8.420107 -67.702934) (xy 8.428227 -67.75811) (xy 8.428736 -67.785996) (xy 8.428227 -67.813882)
			(xy 8.420107 -67.869058) (xy 8.404039 -67.922465) (xy 8.380367 -67.972962) (xy 8.349594 -68.019475)
			(xy 8.312377 -68.061012) (xy 8.269509 -68.096687) (xy 8.221903 -68.125741) (xy 8.170574 -68.147553)
			(xy 8.116617 -68.161659) (xy 8.06118 -68.167759) (xy 8.005446 -68.165722) (xy 7.950603 -68.155592)
			(xy 7.897819 -68.137585) (xy 7.848219 -68.112084) (xy 7.802861 -68.079633) (xy 7.762712 -68.040924)
			(xy 7.728626 -67.996781) (xy 7.70133 -67.948146) (xy 7.681407 -67.896055) (xy 7.669281 -67.841618)
			(xy 7.66521 -67.785996) (xy 1.306576 -67.785996) (xy 1.306576 -68.353432) (xy 3.576826 -68.353432)
			(xy 3.580897 -68.29781) (xy 3.593023 -68.243373) (xy 3.612946 -68.191282) (xy 3.640242 -68.142647)
			(xy 3.674328 -68.098504) (xy 3.714477 -68.059795) (xy 3.759835 -68.027344) (xy 3.809435 -68.001843)
			(xy 3.862219 -67.983836) (xy 3.917062 -67.973706) (xy 3.972796 -67.971669) (xy 4.028233 -67.977769)
			(xy 4.08219 -67.991875) (xy 4.133519 -68.013687) (xy 4.181125 -68.042741) (xy 4.223993 -68.078416)
			(xy 4.26121 -68.119953) (xy 4.291983 -68.166466) (xy 4.315655 -68.216963) (xy 4.331723 -68.27037)
			(xy 4.339843 -68.325546) (xy 4.340352 -68.353432) (xy 4.339843 -68.381318) (xy 4.331723 -68.436494)
			(xy 4.315655 -68.489901) (xy 4.291983 -68.540398) (xy 4.261413 -68.586604) (xy 16.625316 -68.586604)
			(xy 16.625781 -68.559234) (xy 16.633598 -68.505054) (xy 16.649087 -68.452551) (xy 16.67193 -68.402804)
			(xy 16.701655 -68.356838) (xy 16.719296 -68.335906) (xy 16.71955 -68.335652) (xy 16.725127 -68.328559)
			(xy 16.731378 -68.311647) (xy 16.731742 -68.302632) (xy 16.731742 -68.235576) (xy 16.731409 -68.226556)
			(xy 16.725146 -68.209639) (xy 16.71955 -68.202556) (xy 16.719296 -68.202556) (xy 16.719296 -68.202302)
			(xy 16.701644 -68.181381) (xy 16.671934 -68.135405) (xy 16.649101 -68.085655) (xy 16.633613 -68.033152)
			(xy 16.625788 -67.978974) (xy 16.625316 -67.951604) (xy 16.625759 -67.92435) (xy 16.633516 -67.870397)
			(xy 16.648873 -67.818098) (xy 16.671517 -67.768516) (xy 16.700987 -67.722662) (xy 16.736682 -67.681468)
			(xy 16.777878 -67.645775) (xy 16.823733 -67.616307) (xy 16.873316 -67.593666) (xy 16.925617 -67.578312)
			(xy 16.97957 -67.570558) (xy 17.006824 -67.570096) (xy 17.033138 -67.570549) (xy 17.085268 -67.577787)
			(xy 17.13591 -67.592109) (xy 17.184109 -67.613244) (xy 17.228953 -67.640793) (xy 17.269592 -67.674233)
			(xy 17.287748 -67.693286) (xy 17.295252 -67.700709) (xy 17.314545 -67.709221) (xy 17.325086 -67.709796)
			(xy 17.399762 -67.709796) (xy 17.410311 -67.709261) (xy 17.429607 -67.70073) (xy 17.4371 -67.693286)
			(xy 17.45526 -67.674235) (xy 17.495889 -67.640778) (xy 17.540728 -67.613219) (xy 17.588928 -67.592079)
			(xy 17.639575 -67.577761) (xy 17.691708 -67.570535) (xy 17.718024 -67.570096) (xy 17.745395 -67.570549)
			(xy 17.799574 -67.57837) (xy 17.852078 -67.593862) (xy 17.901824 -67.616707) (xy 17.947791 -67.646434)
			(xy 17.968722 -67.664076) (xy 17.968976 -67.66433) (xy 17.976063 -67.669916) (xy 17.99298 -67.676162)
			(xy 18.001996 -67.676522) (xy 18.069052 -67.676522) (xy 18.078066 -67.676137) (xy 18.094983 -67.669908)
			(xy 18.102072 -67.66433) (xy 18.102072 -67.664076) (xy 18.102326 -67.664076) (xy 18.123272 -67.646454)
			(xy 18.169241 -67.616741) (xy 18.218985 -67.593902) (xy 18.271483 -67.578407) (xy 18.325656 -67.570573)
			(xy 18.353024 -67.570096) (xy 18.380276 -67.570555) (xy 18.434225 -67.578315) (xy 18.48652 -67.593674)
			(xy 18.536098 -67.616318) (xy 18.581948 -67.645787) (xy 18.623138 -67.681481) (xy 18.65883 -67.722674)
			(xy 18.688295 -67.768527) (xy 18.710936 -67.818106) (xy 18.726291 -67.870402) (xy 18.734047 -67.924352)
			(xy 18.734532 -67.951604) (xy 18.734085 -67.978975) (xy 18.726265 -68.033156) (xy 18.710772 -68.08566)
			(xy 18.687926 -68.135406) (xy 18.658196 -68.181372) (xy 18.640552 -68.202302) (xy 18.640298 -68.202556)
			(xy 18.634723 -68.209651) (xy 18.62847 -68.226561) (xy 18.628106 -68.235576) (xy 18.628106 -68.302632)
			(xy 18.628447 -68.311651) (xy 18.634705 -68.328567) (xy 18.640298 -68.335652) (xy 18.640552 -68.335652)
			(xy 18.640552 -68.335906) (xy 18.6582 -68.356831) (xy 18.687912 -68.402805) (xy 18.710747 -68.452554)
			(xy 18.726236 -68.505057) (xy 18.73406 -68.559234) (xy 18.734532 -68.586604) (xy 18.734026 -68.613854)
			(xy 18.72627 -68.6678) (xy 18.710915 -68.720093) (xy 18.694275 -68.75653) (xy 22.17039 -68.75653)
			(xy 22.170876 -68.729161) (xy 22.178689 -68.674982) (xy 22.194174 -68.62248) (xy 22.217011 -68.572732)
			(xy 22.246731 -68.526765) (xy 22.26437 -68.505832) (xy 22.264624 -68.505578) (xy 22.270229 -68.498504)
			(xy 22.276464 -68.481577) (xy 22.276816 -68.472558) (xy 22.276816 -68.405502) (xy 22.276454 -68.396486)
			(xy 22.27021 -68.379569) (xy 22.264624 -68.372482) (xy 22.26437 -68.372482) (xy 22.26437 -68.372228)
			(xy 22.246726 -68.3513) (xy 22.217016 -68.305326) (xy 22.194181 -68.255577) (xy 22.178691 -68.203076)
			(xy 22.170864 -68.148899) (xy 22.17039 -68.12153) (xy 22.170883 -68.094278) (xy 22.178636 -68.040328)
			(xy 22.193988 -67.988031) (xy 22.216627 -67.938451) (xy 22.246092 -67.892598) (xy 22.281782 -67.851405)
			(xy 22.322972 -67.815711) (xy 22.368823 -67.786242) (xy 22.418401 -67.763599) (xy 22.470697 -67.748243)
			(xy 22.524646 -67.740485) (xy 22.551898 -67.740022) (xy 22.579268 -67.740484) (xy 22.633448 -67.748302)
			(xy 22.685951 -67.763792) (xy 22.735698 -67.786634) (xy 22.781665 -67.81636) (xy 22.802596 -67.834002)
			(xy 22.80285 -67.834256) (xy 22.809942 -67.839834) (xy 22.826855 -67.846085) (xy 22.83587 -67.846448)
			(xy 22.902926 -67.846448) (xy 22.911946 -67.846115) (xy 22.928863 -67.839852) (xy 22.935946 -67.834256)
			(xy 22.935946 -67.834002) (xy 22.9362 -67.834002) (xy 22.957121 -67.81635) (xy 23.003097 -67.78664)
			(xy 23.052847 -67.763806) (xy 23.10535 -67.748318) (xy 23.159528 -67.740494) (xy 23.186898 -67.740022)
			(xy 23.213212 -67.740484) (xy 23.265341 -67.747719) (xy 23.315984 -67.762038) (xy 23.364184 -67.783172)
			(xy 23.409027 -67.810719) (xy 23.449666 -67.84416) (xy 23.467822 -67.863212) (xy 23.475332 -67.870627)
			(xy 23.494621 -67.879144) (xy 23.50516 -67.879722) (xy 23.579836 -67.879722) (xy 23.590382 -67.879165)
			(xy 23.609678 -67.870649) (xy 23.617174 -67.863212) (xy 23.635352 -67.844178) (xy 23.675976 -67.810719)
			(xy 23.720812 -67.783157) (xy 23.769008 -67.762014) (xy 23.819652 -67.747693) (xy 23.871783 -67.740463)
			(xy 23.898098 -67.740022) (xy 23.925352 -67.740457) (xy 23.979306 -67.748215) (xy 24.031606 -67.763572)
			(xy 24.081188 -67.786217) (xy 24.127043 -67.815687) (xy 24.168236 -67.851384) (xy 24.20393 -67.89258)
			(xy 24.233397 -67.938437) (xy 24.256038 -67.98802) (xy 24.271391 -68.040322) (xy 24.279145 -68.094276)
			(xy 24.279606 -68.12153) (xy 24.279156 -68.148901) (xy 24.271334 -68.203081) (xy 24.255841 -68.255584)
			(xy 24.232996 -68.30533) (xy 24.203268 -68.351297) (xy 24.185626 -68.372228) (xy 24.185372 -68.372482)
			(xy 24.179784 -68.379567) (xy 24.173539 -68.396485) (xy 24.17318 -68.405502) (xy 24.17318 -68.472558)
			(xy 24.173561 -68.481572) (xy 24.179792 -68.498489) (xy 24.185372 -68.505578) (xy 24.185626 -68.505578)
			(xy 24.185626 -68.505832) (xy 24.203251 -68.526776) (xy 24.232964 -68.572746) (xy 24.255802 -68.62249)
			(xy 24.271297 -68.674988) (xy 24.279129 -68.729162) (xy 24.279606 -68.75653) (xy 24.27915 -68.783782)
			(xy 24.271389 -68.837731) (xy 24.25603 -68.890026) (xy 24.233386 -68.939604) (xy 24.203916 -68.985454)
			(xy 24.168221 -69.026644) (xy 24.127029 -69.062335) (xy 24.081176 -69.091801) (xy 24.031596 -69.114442)
			(xy 23.9793 -69.129796) (xy 23.92535 -69.137552) (xy 23.898098 -69.138038) (xy 23.871783 -69.137592)
			(xy 23.819653 -69.130355) (xy 23.769009 -69.116033) (xy 23.72081 -69.094897) (xy 23.675967 -69.067346)
			(xy 23.635329 -69.033902) (xy 23.617174 -69.014848) (xy 23.609657 -69.00744) (xy 23.590374 -68.998918)
			(xy 23.579836 -68.998338) (xy 23.50516 -68.998338) (xy 23.494611 -68.998875) (xy 23.475315 -69.007403)
			(xy 23.467822 -69.014848) (xy 23.449658 -69.033895) (xy 23.409029 -69.067351) (xy 23.36419 -69.09491)
			(xy 23.315991 -69.11605) (xy 23.265346 -69.130369) (xy 23.213213 -69.137597) (xy 23.186898 -69.138038)
			(xy 23.159527 -69.137588) (xy 23.105347 -69.129769) (xy 23.052843 -69.114277) (xy 23.003096 -69.091431)
			(xy 22.957131 -69.061702) (xy 22.9362 -69.044058) (xy 22.935946 -69.043804) (xy 22.92885 -69.038231)
			(xy 22.911941 -69.031976) (xy 22.902926 -69.031612) (xy 22.83587 -69.031612) (xy 22.826851 -69.031952)
			(xy 22.809934 -69.038211) (xy 22.80285 -69.043804) (xy 22.80285 -69.044058) (xy 22.802596 -69.044058)
			(xy 22.781671 -69.061706) (xy 22.735697 -69.091418) (xy 22.685948 -69.114253) (xy 22.633445 -69.129742)
			(xy 22.579268 -69.137566) (xy 22.551898 -69.138038) (xy 22.524648 -69.137524) (xy 22.470703 -69.129768)
			(xy 22.418411 -69.114414) (xy 22.368835 -69.091775) (xy 22.322986 -69.062311) (xy 22.281797 -69.026623)
			(xy 22.246105 -68.985436) (xy 22.216638 -68.939589) (xy 22.193995 -68.890016) (xy 22.178638 -68.837724)
			(xy 22.170878 -68.78378) (xy 22.17039 -68.75653) (xy 18.694275 -68.75653) (xy 18.688275 -68.769669)
			(xy 18.658811 -68.815518) (xy 18.623122 -68.856707) (xy 18.581934 -68.892399) (xy 18.536086 -68.921866)
			(xy 18.486512 -68.944508) (xy 18.43422 -68.959865) (xy 18.380274 -68.967625) (xy 18.353024 -68.968112)
			(xy 18.325654 -68.967629) (xy 18.271476 -68.959815) (xy 18.218973 -68.944329) (xy 18.169226 -68.921492)
			(xy 18.123258 -68.891771) (xy 18.102326 -68.874132) (xy 18.102072 -68.873878) (xy 18.094971 -68.868313)
			(xy 18.078065 -68.862054) (xy 18.069052 -68.861686) (xy 18.001996 -68.861686) (xy 17.992979 -68.862044)
			(xy 17.976063 -68.868291) (xy 17.968976 -68.873878) (xy 17.968976 -68.874132) (xy 17.968722 -68.874132)
			(xy 17.947797 -68.891779) (xy 17.901821 -68.921489) (xy 17.852072 -68.944323) (xy 17.79957 -68.959812)
			(xy 17.745394 -68.967639) (xy 17.718024 -68.968112) (xy 17.691711 -68.967625) (xy 17.639583 -68.960393)
			(xy 17.588941 -68.946078) (xy 17.540742 -68.924949) (xy 17.495898 -68.897407) (xy 17.455257 -68.863972)
			(xy 17.4371 -68.844922) (xy 17.429577 -68.837522) (xy 17.410298 -68.828996) (xy 17.399762 -68.828412)
			(xy 17.325086 -68.828412) (xy 17.314533 -68.828916) (xy 17.295238 -68.837468) (xy 17.287748 -68.844922)
			(xy 17.269615 -68.864) (xy 17.22898 -68.897454) (xy 17.184135 -68.92501) (xy 17.13593 -68.946144)
			(xy 17.085278 -68.960457) (xy 17.033141 -68.967676) (xy 17.006824 -68.968112) (xy 16.979572 -68.967622)
			(xy 16.925622 -68.959869) (xy 16.873325 -68.944516) (xy 16.823745 -68.921877) (xy 16.777892 -68.892411)
			(xy 16.736699 -68.85672) (xy 16.701005 -68.81553) (xy 16.671537 -68.769679) (xy 16.648894 -68.720101)
			(xy 16.633537 -68.667805) (xy 16.62578 -68.613856) (xy 16.625316 -68.586604) (xy 4.261413 -68.586604)
			(xy 4.26121 -68.586911) (xy 4.223993 -68.628448) (xy 4.181125 -68.664123) (xy 4.133519 -68.693177)
			(xy 4.08219 -68.714989) (xy 4.028233 -68.729095) (xy 3.972796 -68.735195) (xy 3.917062 -68.733158)
			(xy 3.862219 -68.723028) (xy 3.809435 -68.705021) (xy 3.759835 -68.67952) (xy 3.714477 -68.647069)
			(xy 3.674328 -68.60836) (xy 3.640242 -68.564217) (xy 3.612946 -68.515582) (xy 3.593023 -68.463491)
			(xy 3.580897 -68.409054) (xy 3.576826 -68.353432) (xy 1.306576 -68.353432) (xy 1.306576 -68.882768)
			(xy 1.306974 -68.892757) (xy 1.3146 -68.911219) (xy 1.328733 -68.925335) (xy 1.337818 -68.929504)
			(xy 1.434338 -68.962778) (xy 1.441218 -68.964505) (xy 1.455398 -68.964505) (xy 1.462278 -68.962778)
			(xy 1.469898 -68.960492) (xy 1.474978 -68.95719) (xy 1.48209 -68.951348) (xy 1.487932 -68.945506)
			(xy 1.48971 -68.94322) (xy 1.507941 -68.921396) (xy 1.549764 -68.882869) (xy 1.596837 -68.850968)
			(xy 1.64812 -68.826401) (xy 1.702479 -68.809709) (xy 1.758712 -68.801261) (xy 1.787144 -68.800726)
			(xy 1.814395 -68.801212) (xy 1.868343 -68.808968) (xy 1.920638 -68.824323) (xy 1.970215 -68.846965)
			(xy 2.016065 -68.876431) (xy 2.057256 -68.912122) (xy 2.092947 -68.953313) (xy 2.122413 -68.999163)
			(xy 2.145055 -69.04874) (xy 2.16041 -69.101035) (xy 2.168166 -69.154983) (xy 2.168166 -69.209485)
			(xy 2.16041 -69.263433) (xy 2.145055 -69.315728) (xy 2.122413 -69.365305) (xy 2.092947 -69.411155)
			(xy 2.057256 -69.452346) (xy 2.016065 -69.488037) (xy 1.970215 -69.517503) (xy 1.920638 -69.540145)
			(xy 1.868343 -69.5555) (xy 1.814395 -69.563256) (xy 1.787144 -69.563742) (xy 1.775714 -69.563742)
			(xy 1.748568 -69.562444) (xy 1.695028 -69.553131) (xy 1.669034 -69.5452) (xy 1.66497 -69.54393) (xy 1.664208 -69.543676)
			(xy 1.650975 -69.538987) (xy 1.625167 -69.527929) (xy 1.612646 -69.521578) (xy 1.591446 -69.510226)
			(xy 1.551831 -69.482964) (xy 1.533652 -69.467222) (xy 1.532636 -69.466714) (xy 1.529588 -69.463666)
			(xy 1.522476 -69.45757) (xy 1.519428 -69.454522) (xy 1.519174 -69.454268) (xy 1.50876 -69.443346)
			(xy 1.48717 -69.418708) (xy 1.483868 -69.414644) (xy 1.479239 -69.410268) (xy 1.468316 -69.403721)
			(xy 1.462278 -69.40169) (xy 1.455156 -69.39983) (xy 1.440444 -69.39983) (xy 1.433322 -69.40169) (xy 1.368298 -69.424296)
			(xy 1.36525 -69.421756) (xy 1.33604 -69.435472) (xy 1.32969 -69.438774) (xy 1.321559 -69.444629)
			(xy 1.310179 -69.461098) (xy 1.307592 -69.470778) (xy 1.306576 -69.48043) (xy 1.306576 -70.204076)
			(xy 6.107428 -70.204076) (xy 6.111499 -70.148454) (xy 6.123625 -70.094017) (xy 6.143548 -70.041926)
			(xy 6.170844 -69.993291) (xy 6.20493 -69.949148) (xy 6.245079 -69.910439) (xy 6.290437 -69.877988)
			(xy 6.340037 -69.852487) (xy 6.392821 -69.83448) (xy 6.447664 -69.82435) (xy 6.503398 -69.822313)
			(xy 6.558835 -69.828413) (xy 6.612792 -69.842519) (xy 6.664121 -69.864331) (xy 6.711727 -69.893385)
			(xy 6.754595 -69.92906) (xy 6.791812 -69.970597) (xy 6.822585 -70.01711) (xy 6.846257 -70.067607)
			(xy 6.862325 -70.121014) (xy 6.870445 -70.17619) (xy 6.870954 -70.204076) (xy 6.870445 -70.231962)
			(xy 6.862325 -70.287138) (xy 6.846257 -70.340545) (xy 6.822585 -70.391042) (xy 6.791812 -70.437555)
			(xy 6.754595 -70.479092) (xy 6.711727 -70.514767) (xy 6.664121 -70.543821) (xy 6.612792 -70.565633)
			(xy 6.558835 -70.579739) (xy 6.503398 -70.585839) (xy 6.447664 -70.583802) (xy 6.392821 -70.573672)
			(xy 6.340037 -70.555665) (xy 6.290437 -70.530164) (xy 6.245079 -70.497713) (xy 6.20493 -70.459004)
			(xy 6.170844 -70.414861) (xy 6.143548 -70.366226) (xy 6.123625 -70.314135) (xy 6.111499 -70.259698)
			(xy 6.107428 -70.204076) (xy 1.306576 -70.204076) (xy 1.306576 -71.288402) (xy 1.735072 -71.288402)
			(xy 1.739143 -71.23278) (xy 1.751269 -71.178343) (xy 1.771192 -71.126252) (xy 1.798488 -71.077617)
			(xy 1.832574 -71.033474) (xy 1.872723 -70.994765) (xy 1.918081 -70.962314) (xy 1.967681 -70.936813)
			(xy 2.020465 -70.918806) (xy 2.075308 -70.908676) (xy 2.131042 -70.906639) (xy 2.186479 -70.912739)
			(xy 2.240436 -70.926845) (xy 2.291765 -70.948657) (xy 2.339371 -70.977711) (xy 2.382239 -71.013386)
			(xy 2.419456 -71.054923) (xy 2.450229 -71.101436) (xy 2.473901 -71.151933) (xy 2.489969 -71.20534)
			(xy 2.498089 -71.260516) (xy 2.498598 -71.288402) (xy 2.498089 -71.316288) (xy 2.489969 -71.371464)
			(xy 2.473901 -71.424871) (xy 2.450229 -71.475368) (xy 2.419456 -71.521881) (xy 2.382239 -71.563418)
			(xy 2.339371 -71.599093) (xy 2.291765 -71.628147) (xy 2.240436 -71.649959) (xy 2.186479 -71.664065)
			(xy 2.131042 -71.670165) (xy 2.075308 -71.668128) (xy 2.020465 -71.657998) (xy 1.967681 -71.639991)
			(xy 1.918081 -71.61449) (xy 1.872723 -71.582039) (xy 1.832574 -71.54333) (xy 1.798488 -71.499187)
			(xy 1.771192 -71.450552) (xy 1.751269 -71.398461) (xy 1.739143 -71.344024) (xy 1.735072 -71.288402)
			(xy 1.306576 -71.288402) (xy 1.306576 -71.673974) (xy 3.37896 -71.673974) (xy 3.383031 -71.618352)
			(xy 3.395157 -71.563915) (xy 3.41508 -71.511824) (xy 3.442376 -71.463189) (xy 3.476462 -71.419046)
			(xy 3.516611 -71.380337) (xy 3.561969 -71.347886) (xy 3.611569 -71.322385) (xy 3.664353 -71.304378)
			(xy 3.719196 -71.294248) (xy 3.77493 -71.292211) (xy 3.830367 -71.298311) (xy 3.884324 -71.312417)
			(xy 3.935653 -71.334229) (xy 3.983259 -71.363283) (xy 4.026127 -71.398958) (xy 4.033123 -71.406766)
			(xy 7.013446 -71.406766) (xy 7.017517 -71.351144) (xy 7.029643 -71.296707) (xy 7.049566 -71.244616)
			(xy 7.076862 -71.195981) (xy 7.110948 -71.151838) (xy 7.151097 -71.113129) (xy 7.196455 -71.080678)
			(xy 7.246055 -71.055177) (xy 7.298839 -71.03717) (xy 7.353682 -71.02704) (xy 7.409416 -71.025003)
			(xy 7.464853 -71.031103) (xy 7.51881 -71.045209) (xy 7.570139 -71.067021) (xy 7.617745 -71.096075)
			(xy 7.643747 -71.117714) (xy 9.0457 -71.117714) (xy 9.049771 -71.062092) (xy 9.061897 -71.007655)
			(xy 9.08182 -70.955564) (xy 9.109116 -70.906929) (xy 9.143202 -70.862786) (xy 9.183351 -70.824077)
			(xy 9.228709 -70.791626) (xy 9.278309 -70.766125) (xy 9.331093 -70.748118) (xy 9.385936 -70.737988)
			(xy 9.44167 -70.735951) (xy 9.497107 -70.742051) (xy 9.551064 -70.756157) (xy 9.602393 -70.777969)
			(xy 9.649999 -70.807023) (xy 9.692867 -70.842698) (xy 9.730084 -70.884235) (xy 9.760857 -70.930748)
			(xy 9.784529 -70.981245) (xy 9.800597 -71.034652) (xy 9.808717 -71.089828) (xy 9.809226 -71.117714)
			(xy 9.808717 -71.1456) (xy 9.800597 -71.200776) (xy 9.784529 -71.254183) (xy 9.760857 -71.30468)
			(xy 9.730084 -71.351193) (xy 9.692867 -71.39273) (xy 9.649999 -71.428405) (xy 9.602393 -71.457459)
			(xy 9.551064 -71.479271) (xy 9.497107 -71.493377) (xy 9.44167 -71.499477) (xy 9.385936 -71.49744)
			(xy 9.331093 -71.48731) (xy 9.278309 -71.469303) (xy 9.228709 -71.443802) (xy 9.183351 -71.411351)
			(xy 9.143202 -71.372642) (xy 9.109116 -71.328499) (xy 9.08182 -71.279864) (xy 9.061897 -71.227773)
			(xy 9.049771 -71.173336) (xy 9.0457 -71.117714) (xy 7.643747 -71.117714) (xy 7.660613 -71.13175)
			(xy 7.69783 -71.173287) (xy 7.728603 -71.2198) (xy 7.752275 -71.270297) (xy 7.768343 -71.323704)
			(xy 7.776463 -71.37888) (xy 7.776972 -71.406766) (xy 7.776463 -71.434652) (xy 7.768343 -71.489828)
			(xy 7.752275 -71.543235) (xy 7.746355 -71.555864) (xy 19.194524 -71.555864) (xy 19.198595 -71.500242)
			(xy 19.210721 -71.445805) (xy 19.230644 -71.393714) (xy 19.25794 -71.345079) (xy 19.292026 -71.300936)
			(xy 19.332175 -71.262227) (xy 19.377533 -71.229776) (xy 19.427133 -71.204275) (xy 19.479917 -71.186268)
			(xy 19.53476 -71.176138) (xy 19.590494 -71.174101) (xy 19.645931 -71.180201) (xy 19.699888 -71.194307)
			(xy 19.751217 -71.216119) (xy 19.798823 -71.245173) (xy 19.841691 -71.280848) (xy 19.878908 -71.322385)
			(xy 19.909681 -71.368898) (xy 19.933353 -71.419395) (xy 19.949421 -71.472802) (xy 19.957541 -71.527978)
			(xy 19.95805 -71.555864) (xy 19.957541 -71.58375) (xy 19.951702 -71.623428) (xy 20.703538 -71.623428)
			(xy 20.707609 -71.567806) (xy 20.719735 -71.513369) (xy 20.739658 -71.461278) (xy 20.766954 -71.412643)
			(xy 20.80104 -71.3685) (xy 20.841189 -71.329791) (xy 20.886547 -71.29734) (xy 20.936147 -71.271839)
			(xy 20.988931 -71.253832) (xy 21.043774 -71.243702) (xy 21.099508 -71.241665) (xy 21.154945 -71.247765)
			(xy 21.208902 -71.261871) (xy 21.260231 -71.283683) (xy 21.307837 -71.312737) (xy 21.350705 -71.348412)
			(xy 21.387922 -71.389949) (xy 21.418695 -71.436462) (xy 21.442367 -71.486959) (xy 21.458435 -71.540366)
			(xy 21.466555 -71.595542) (xy 21.467064 -71.623428) (xy 21.466555 -71.651314) (xy 21.458435 -71.70649)
			(xy 21.442367 -71.759897) (xy 21.418695 -71.810394) (xy 21.387922 -71.856907) (xy 21.350705 -71.898444)
			(xy 21.307837 -71.934119) (xy 21.260231 -71.963173) (xy 21.208902 -71.984985) (xy 21.154945 -71.999091)
			(xy 21.099508 -72.005191) (xy 21.043774 -72.003154) (xy 20.988931 -71.993024) (xy 20.936147 -71.975017)
			(xy 20.886547 -71.949516) (xy 20.841189 -71.917065) (xy 20.80104 -71.878356) (xy 20.766954 -71.834213)
			(xy 20.739658 -71.785578) (xy 20.719735 -71.733487) (xy 20.707609 -71.67905) (xy 20.703538 -71.623428)
			(xy 19.951702 -71.623428) (xy 19.949421 -71.638926) (xy 19.933353 -71.692333) (xy 19.909681 -71.74283)
			(xy 19.878908 -71.789343) (xy 19.841691 -71.83088) (xy 19.798823 -71.866555) (xy 19.751217 -71.895609)
			(xy 19.699888 -71.917421) (xy 19.645931 -71.931527) (xy 19.590494 -71.937627) (xy 19.53476 -71.93559)
			(xy 19.479917 -71.92546) (xy 19.427133 -71.907453) (xy 19.377533 -71.881952) (xy 19.332175 -71.849501)
			(xy 19.292026 -71.810792) (xy 19.25794 -71.766649) (xy 19.230644 -71.718014) (xy 19.210721 -71.665923)
			(xy 19.198595 -71.611486) (xy 19.194524 -71.555864) (xy 7.746355 -71.555864) (xy 7.728603 -71.593732)
			(xy 7.69783 -71.640245) (xy 7.660613 -71.681782) (xy 7.617745 -71.717457) (xy 7.570139 -71.746511)
			(xy 7.51881 -71.768323) (xy 7.464853 -71.782429) (xy 7.409416 -71.788529) (xy 7.353682 -71.786492)
			(xy 7.298839 -71.776362) (xy 7.246055 -71.758355) (xy 7.196455 -71.732854) (xy 7.151097 -71.700403)
			(xy 7.110948 -71.661694) (xy 7.076862 -71.617551) (xy 7.049566 -71.568916) (xy 7.029643 -71.516825)
			(xy 7.017517 -71.462388) (xy 7.013446 -71.406766) (xy 4.033123 -71.406766) (xy 4.063344 -71.440495)
			(xy 4.094117 -71.487008) (xy 4.117789 -71.537505) (xy 4.133857 -71.590912) (xy 4.141977 -71.646088)
			(xy 4.142486 -71.673974) (xy 4.141977 -71.70186) (xy 4.133857 -71.757036) (xy 4.117789 -71.810443)
			(xy 4.094117 -71.86094) (xy 4.063344 -71.907453) (xy 4.026127 -71.94899) (xy 3.983259 -71.984665)
			(xy 3.935653 -72.013719) (xy 3.884324 -72.035531) (xy 3.830367 -72.049637) (xy 3.77493 -72.055737)
			(xy 3.719196 -72.0537) (xy 3.664353 -72.04357) (xy 3.611569 -72.025563) (xy 3.561969 -72.000062)
			(xy 3.516611 -71.967611) (xy 3.476462 -71.928902) (xy 3.442376 -71.884759) (xy 3.41508 -71.836124)
			(xy 3.395157 -71.784033) (xy 3.383031 -71.729596) (xy 3.37896 -71.673974) (xy 1.306576 -71.673974)
			(xy 1.306576 -73.289668) (xy 3.554728 -73.289668) (xy 3.558799 -73.234046) (xy 3.570925 -73.179609)
			(xy 3.590848 -73.127518) (xy 3.618144 -73.078883) (xy 3.65223 -73.03474) (xy 3.692379 -72.996031)
			(xy 3.737737 -72.96358) (xy 3.787337 -72.938079) (xy 3.840121 -72.920072) (xy 3.894964 -72.909942)
			(xy 3.950698 -72.907905) (xy 4.006135 -72.914005) (xy 4.060092 -72.928111) (xy 4.111421 -72.949923)
			(xy 4.159027 -72.978977) (xy 4.201895 -73.014652) (xy 4.239112 -73.056189) (xy 4.269885 -73.102702)
			(xy 4.293557 -73.153199) (xy 4.309625 -73.206606) (xy 4.317745 -73.261782) (xy 4.318254 -73.289668)
			(xy 4.317745 -73.317554) (xy 4.309625 -73.37273) (xy 4.293557 -73.426137) (xy 4.269885 -73.476634)
			(xy 4.239112 -73.523147) (xy 4.201895 -73.564684) (xy 4.159027 -73.600359) (xy 4.111421 -73.629413)
			(xy 4.060092 -73.651225) (xy 4.006135 -73.665331) (xy 3.950698 -73.671431) (xy 3.894964 -73.669394)
			(xy 3.840121 -73.659264) (xy 3.787337 -73.641257) (xy 3.737737 -73.615756) (xy 3.692379 -73.583305)
			(xy 3.65223 -73.544596) (xy 3.618144 -73.500453) (xy 3.590848 -73.451818) (xy 3.570925 -73.399727)
			(xy 3.558799 -73.34529) (xy 3.554728 -73.289668) (xy 1.306576 -73.289668) (xy 1.306576 -74.106024)
			(xy 8.468612 -74.106024) (xy 8.472683 -74.050402) (xy 8.484809 -73.995965) (xy 8.504732 -73.943874)
			(xy 8.532028 -73.895239) (xy 8.566114 -73.851096) (xy 8.606263 -73.812387) (xy 8.651621 -73.779936)
			(xy 8.701221 -73.754435) (xy 8.754005 -73.736428) (xy 8.808848 -73.726298) (xy 8.864582 -73.724261)
			(xy 8.920019 -73.730361) (xy 8.973976 -73.744467) (xy 9.025305 -73.766279) (xy 9.072911 -73.795333)
			(xy 9.115779 -73.831008) (xy 9.152996 -73.872545) (xy 9.183769 -73.919058) (xy 9.207441 -73.969555)
			(xy 9.223509 -74.022962) (xy 9.231629 -74.078138) (xy 9.232138 -74.106024) (xy 9.231629 -74.13391)
			(xy 9.223509 -74.189086) (xy 9.207441 -74.242493) (xy 9.183769 -74.29299) (xy 9.152996 -74.339503)
			(xy 9.115779 -74.38104) (xy 9.072911 -74.416715) (xy 9.025305 -74.445769) (xy 8.973976 -74.467581)
			(xy 8.920019 -74.481687) (xy 8.864582 -74.487787) (xy 8.808848 -74.48575) (xy 8.754005 -74.47562)
			(xy 8.701221 -74.457613) (xy 8.651621 -74.432112) (xy 8.606263 -74.399661) (xy 8.566114 -74.360952)
			(xy 8.532028 -74.316809) (xy 8.504732 -74.268174) (xy 8.484809 -74.216083) (xy 8.472683 -74.161646)
			(xy 8.468612 -74.106024) (xy 1.306576 -74.106024) (xy 1.306576 -75.087226) (xy 6.381748 -75.087226)
			(xy 6.385819 -75.031604) (xy 6.397945 -74.977167) (xy 6.417868 -74.925076) (xy 6.445164 -74.876441)
			(xy 6.47925 -74.832298) (xy 6.519399 -74.793589) (xy 6.564757 -74.761138) (xy 6.614357 -74.735637)
			(xy 6.667141 -74.71763) (xy 6.721984 -74.7075) (xy 6.777718 -74.705463) (xy 6.833155 -74.711563)
			(xy 6.887112 -74.725669) (xy 6.938441 -74.747481) (xy 6.986047 -74.776535) (xy 7.028915 -74.81221)
			(xy 7.066132 -74.853747) (xy 7.096905 -74.90026) (xy 7.120577 -74.950757) (xy 7.136645 -75.004164)
			(xy 7.144765 -75.05934) (xy 7.145274 -75.087226) (xy 7.144765 -75.115112) (xy 7.136645 -75.170288)
			(xy 7.120577 -75.223695) (xy 7.096905 -75.274192) (xy 7.066132 -75.320705) (xy 7.028915 -75.362242)
			(xy 6.986047 -75.397917) (xy 6.938441 -75.426971) (xy 6.887112 -75.448783) (xy 6.833155 -75.462889)
			(xy 6.777718 -75.468989) (xy 6.721984 -75.466952) (xy 6.667141 -75.456822) (xy 6.614357 -75.438815)
			(xy 6.564757 -75.413314) (xy 6.519399 -75.380863) (xy 6.47925 -75.342154) (xy 6.445164 -75.298011)
			(xy 6.417868 -75.249376) (xy 6.397945 -75.197285) (xy 6.385819 -75.142848) (xy 6.381748 -75.087226)
			(xy 1.306576 -75.087226) (xy 1.306576 -81.38922) (xy 1.307338 -81.397348) (xy 1.307338 -81.397856)
			(xy 1.308943 -81.405372) (xy 1.315928 -81.419052) (xy 1.321054 -81.42478) (xy 5.090414 -85.19414)
			(xy 5.097264 -85.201536) (xy 5.104997 -85.220136) (xy 5.1054 -85.230208) (xy 5.1054 -91.315794) (xy 31.655256 -91.315794)
			(xy 31.659327 -91.260172) (xy 31.671453 -91.205735) (xy 31.691376 -91.153644) (xy 31.718672 -91.105009)
			(xy 31.752758 -91.060866) (xy 31.792907 -91.022157) (xy 31.838265 -90.989706) (xy 31.887865 -90.964205)
			(xy 31.940649 -90.946198) (xy 31.995492 -90.936068) (xy 32.051226 -90.934031) (xy 32.106663 -90.940131)
			(xy 32.16062 -90.954237) (xy 32.211949 -90.976049) (xy 32.259555 -91.005103) (xy 32.302423 -91.040778)
			(xy 32.33964 -91.082315) (xy 32.370413 -91.128828) (xy 32.394085 -91.179325) (xy 32.410153 -91.232732)
			(xy 32.418273 -91.287908) (xy 32.418782 -91.315794) (xy 32.418273 -91.34368) (xy 32.410153 -91.398856)
			(xy 32.394085 -91.452263) (xy 32.370413 -91.50276) (xy 32.33964 -91.549273) (xy 32.302423 -91.59081)
			(xy 32.259555 -91.626485) (xy 32.211949 -91.655539) (xy 32.16062 -91.677351) (xy 32.106663 -91.691457)
			(xy 32.051226 -91.697557) (xy 31.995492 -91.69552) (xy 31.940649 -91.68539) (xy 31.887865 -91.667383)
			(xy 31.838265 -91.641882) (xy 31.792907 -91.609431) (xy 31.752758 -91.570722) (xy 31.718672 -91.526579)
			(xy 31.691376 -91.477944) (xy 31.671453 -91.425853) (xy 31.659327 -91.371416) (xy 31.655256 -91.315794)
			(xy 5.1054 -91.315794) (xy 5.1054 -95.12554) (xy 24.574752 -95.12554) (xy 24.578823 -95.069918) (xy 24.590949 -95.015481)
			(xy 24.610872 -94.96339) (xy 24.638168 -94.914755) (xy 24.672254 -94.870612) (xy 24.712403 -94.831903)
			(xy 24.757761 -94.799452) (xy 24.807361 -94.773951) (xy 24.860145 -94.755944) (xy 24.914988 -94.745814)
			(xy 24.970722 -94.743777) (xy 25.026159 -94.749877) (xy 25.080116 -94.763983) (xy 25.131445 -94.785795)
			(xy 25.179051 -94.814849) (xy 25.221919 -94.850524) (xy 25.259136 -94.892061) (xy 25.289909 -94.938574)
			(xy 25.313581 -94.989071) (xy 25.329649 -95.042478) (xy 25.337769 -95.097654) (xy 25.338278 -95.12554)
			(xy 25.337769 -95.153426) (xy 25.329649 -95.208602) (xy 25.313581 -95.262009) (xy 25.289909 -95.312506)
			(xy 25.259136 -95.359019) (xy 25.221919 -95.400556) (xy 25.179051 -95.436231) (xy 25.131445 -95.465285)
			(xy 25.080116 -95.487097) (xy 25.026159 -95.501203) (xy 24.970722 -95.507303) (xy 24.914988 -95.505266)
			(xy 24.860145 -95.495136) (xy 24.807361 -95.477129) (xy 24.757761 -95.451628) (xy 24.712403 -95.419177)
			(xy 24.672254 -95.380468) (xy 24.638168 -95.336325) (xy 24.610872 -95.28769) (xy 24.590949 -95.235599)
			(xy 24.578823 -95.181162) (xy 24.574752 -95.12554) (xy 5.1054 -95.12554) (xy 5.1054 -95.986092) (xy 25.048462 -95.986092)
			(xy 25.052533 -95.93047) (xy 25.064659 -95.876033) (xy 25.084582 -95.823942) (xy 25.111878 -95.775307)
			(xy 25.145964 -95.731164) (xy 25.186113 -95.692455) (xy 25.231471 -95.660004) (xy 25.281071 -95.634503)
			(xy 25.333855 -95.616496) (xy 25.388698 -95.606366) (xy 25.444432 -95.604329) (xy 25.499869 -95.610429)
			(xy 25.553826 -95.624535) (xy 25.605155 -95.646347) (xy 25.652761 -95.675401) (xy 25.695629 -95.711076)
			(xy 25.732846 -95.752613) (xy 25.763619 -95.799126) (xy 25.787291 -95.849623) (xy 25.803359 -95.90303)
			(xy 25.811479 -95.958206) (xy 25.811988 -95.986092) (xy 25.811479 -96.013978) (xy 25.803359 -96.069154)
			(xy 25.787291 -96.122561) (xy 25.763619 -96.173058) (xy 25.732846 -96.219571) (xy 25.695629 -96.261108)
			(xy 25.652761 -96.296783) (xy 25.605155 -96.325837) (xy 25.553826 -96.347649) (xy 25.499869 -96.361755)
			(xy 25.444432 -96.367855) (xy 25.388698 -96.365818) (xy 25.333855 -96.355688) (xy 25.281071 -96.337681)
			(xy 25.231471 -96.31218) (xy 25.186113 -96.279729) (xy 25.145964 -96.24102) (xy 25.111878 -96.196877)
			(xy 25.084582 -96.148242) (xy 25.064659 -96.096151) (xy 25.052533 -96.041714) (xy 25.048462 -95.986092)
			(xy 5.1054 -95.986092) (xy 5.1054 -97.021904) (xy 25.034746 -97.021904) (xy 25.038817 -96.966282)
			(xy 25.050943 -96.911845) (xy 25.070866 -96.859754) (xy 25.098162 -96.811119) (xy 25.132248 -96.766976)
			(xy 25.172397 -96.728267) (xy 25.217755 -96.695816) (xy 25.267355 -96.670315) (xy 25.320139 -96.652308)
			(xy 25.374982 -96.642178) (xy 25.430716 -96.640141) (xy 25.486153 -96.646241) (xy 25.54011 -96.660347)
			(xy 25.591439 -96.682159) (xy 25.639045 -96.711213) (xy 25.681913 -96.746888) (xy 25.71913 -96.788425)
			(xy 25.749903 -96.834938) (xy 25.773575 -96.885435) (xy 25.789643 -96.938842) (xy 25.797763 -96.994018)
			(xy 25.798272 -97.021904) (xy 25.797763 -97.04979) (xy 25.789643 -97.104966) (xy 25.773575 -97.158373)
			(xy 25.749903 -97.20887) (xy 25.71913 -97.255383) (xy 25.681913 -97.29692) (xy 25.639045 -97.332595)
			(xy 25.591439 -97.361649) (xy 25.54011 -97.383461) (xy 25.486153 -97.397567) (xy 25.430716 -97.403667)
			(xy 25.374982 -97.40163) (xy 25.320139 -97.3915) (xy 25.267355 -97.373493) (xy 25.217755 -97.347992)
			(xy 25.172397 -97.315541) (xy 25.132248 -97.276832) (xy 25.098162 -97.232689) (xy 25.070866 -97.184054)
			(xy 25.050943 -97.131963) (xy 25.038817 -97.077526) (xy 25.034746 -97.021904) (xy 5.1054 -97.021904)
			(xy 5.1054 -112.501426) (xy 11.973304 -112.501426) (xy 11.977375 -112.445804) (xy 11.989501 -112.391367)
			(xy 12.009424 -112.339276) (xy 12.03672 -112.290641) (xy 12.070806 -112.246498) (xy 12.110955 -112.207789)
			(xy 12.156313 -112.175338) (xy 12.205913 -112.149837) (xy 12.258697 -112.13183) (xy 12.31354 -112.1217)
			(xy 12.369274 -112.119663) (xy 12.424711 -112.125763) (xy 12.478668 -112.139869) (xy 12.529997 -112.161681)
			(xy 12.577603 -112.190735) (xy 12.620471 -112.22641) (xy 12.657688 -112.267947) (xy 12.688461 -112.31446)
			(xy 12.712133 -112.364957) (xy 12.728201 -112.418364) (xy 12.736321 -112.47354) (xy 12.73683 -112.501426)
			(xy 12.736321 -112.529312) (xy 12.728201 -112.584488) (xy 12.712133 -112.637895) (xy 12.688461 -112.688392)
			(xy 12.657688 -112.734905) (xy 12.620471 -112.776442) (xy 12.577603 -112.812117) (xy 12.529997 -112.841171)
			(xy 12.478668 -112.862983) (xy 12.424711 -112.877089) (xy 12.369274 -112.883189) (xy 12.31354 -112.881152)
			(xy 12.258697 -112.871022) (xy 12.205913 -112.853015) (xy 12.156313 -112.827514) (xy 12.110955 -112.795063)
			(xy 12.070806 -112.756354) (xy 12.03672 -112.712211) (xy 12.009424 -112.663576) (xy 11.989501 -112.611485)
			(xy 11.977375 -112.557048) (xy 11.973304 -112.501426) (xy 5.1054 -112.501426) (xy 5.1054 -113.302034)
			(xy 14.31366 -113.302034) (xy 14.317731 -113.246412) (xy 14.329857 -113.191975) (xy 14.34978 -113.139884)
			(xy 14.377076 -113.091249) (xy 14.411162 -113.047106) (xy 14.451311 -113.008397) (xy 14.496669 -112.975946)
			(xy 14.546269 -112.950445) (xy 14.599053 -112.932438) (xy 14.653896 -112.922308) (xy 14.70963 -112.920271)
			(xy 14.765067 -112.926371) (xy 14.819024 -112.940477) (xy 14.870353 -112.962289) (xy 14.917959 -112.991343)
			(xy 14.960827 -113.027018) (xy 14.998044 -113.068555) (xy 15.028817 -113.115068) (xy 15.052489 -113.165565)
			(xy 15.057783 -113.183162) (xy 16.31518 -113.183162) (xy 16.319251 -113.12754) (xy 16.331377 -113.073103)
			(xy 16.3513 -113.021012) (xy 16.378596 -112.972377) (xy 16.412682 -112.928234) (xy 16.452831 -112.889525)
			(xy 16.498189 -112.857074) (xy 16.547789 -112.831573) (xy 16.600573 -112.813566) (xy 16.655416 -112.803436)
			(xy 16.71115 -112.801399) (xy 16.766587 -112.807499) (xy 16.820544 -112.821605) (xy 16.871873 -112.843417)
			(xy 16.919479 -112.872471) (xy 16.962347 -112.908146) (xy 16.999564 -112.949683) (xy 17.030337 -112.996196)
			(xy 17.054009 -113.046693) (xy 17.070077 -113.1001) (xy 17.078197 -113.155276) (xy 17.078706 -113.183162)
			(xy 17.078197 -113.211048) (xy 17.070077 -113.266224) (xy 17.054009 -113.319631) (xy 17.030337 -113.370128)
			(xy 16.999564 -113.416641) (xy 16.962347 -113.458178) (xy 16.919479 -113.493853) (xy 16.871873 -113.522907)
			(xy 16.820544 -113.544719) (xy 16.766587 -113.558825) (xy 16.71115 -113.564925) (xy 16.655416 -113.562888)
			(xy 16.600573 -113.552758) (xy 16.547789 -113.534751) (xy 16.498189 -113.50925) (xy 16.452831 -113.476799)
			(xy 16.412682 -113.43809) (xy 16.378596 -113.393947) (xy 16.3513 -113.345312) (xy 16.331377 -113.293221)
			(xy 16.319251 -113.238784) (xy 16.31518 -113.183162) (xy 15.057783 -113.183162) (xy 15.068557 -113.218972)
			(xy 15.076677 -113.274148) (xy 15.077186 -113.302034) (xy 15.076677 -113.32992) (xy 15.068557 -113.385096)
			(xy 15.052489 -113.438503) (xy 15.028817 -113.489) (xy 14.998044 -113.535513) (xy 14.960827 -113.57705)
			(xy 14.917959 -113.612725) (xy 14.870353 -113.641779) (xy 14.819024 -113.663591) (xy 14.765067 -113.677697)
			(xy 14.70963 -113.683797) (xy 14.653896 -113.68176) (xy 14.599053 -113.67163) (xy 14.546269 -113.653623)
			(xy 14.496669 -113.628122) (xy 14.451311 -113.595671) (xy 14.411162 -113.556962) (xy 14.377076 -113.512819)
			(xy 14.34978 -113.464184) (xy 14.329857 -113.412093) (xy 14.317731 -113.357656) (xy 14.31366 -113.302034)
			(xy 5.1054 -113.302034) (xy 5.1054 -114.660426) (xy 11.961366 -114.660426) (xy 11.965437 -114.604804)
			(xy 11.977563 -114.550367) (xy 11.997486 -114.498276) (xy 12.024782 -114.449641) (xy 12.058868 -114.405498)
			(xy 12.099017 -114.366789) (xy 12.144375 -114.334338) (xy 12.193975 -114.308837) (xy 12.246759 -114.29083)
			(xy 12.301602 -114.2807) (xy 12.357336 -114.278663) (xy 12.412773 -114.284763) (xy 12.46673 -114.298869)
			(xy 12.518059 -114.320681) (xy 12.565665 -114.349735) (xy 12.608533 -114.38541) (xy 12.64575 -114.426947)
			(xy 12.676523 -114.47346) (xy 12.700195 -114.523957) (xy 12.716263 -114.577364) (xy 12.724383 -114.63254)
			(xy 12.724892 -114.660426) (xy 12.724383 -114.688312) (xy 12.716263 -114.743488) (xy 12.700195 -114.796895)
			(xy 12.676523 -114.847392) (xy 12.64575 -114.893905) (xy 12.608533 -114.935442) (xy 12.565665 -114.971117)
			(xy 12.518059 -115.000171) (xy 12.46673 -115.021983) (xy 12.412773 -115.036089) (xy 12.357336 -115.042189)
			(xy 12.301602 -115.040152) (xy 12.246759 -115.030022) (xy 12.193975 -115.012015) (xy 12.144375 -114.986514)
			(xy 12.099017 -114.954063) (xy 12.058868 -114.915354) (xy 12.024782 -114.871211) (xy 11.997486 -114.822576)
			(xy 11.977563 -114.770485) (xy 11.965437 -114.716048) (xy 11.961366 -114.660426) (xy 5.1054 -114.660426)
			(xy 5.1054 -117.434106) (xy 13.37691 -117.434106) (xy 13.377377 -117.406736) (xy 13.385194 -117.352557)
			(xy 13.400683 -117.300053) (xy 13.423525 -117.250307) (xy 13.453249 -117.20434) (xy 13.47089 -117.183408)
			(xy 13.471144 -117.183154) (xy 13.476719 -117.17606) (xy 13.482972 -117.159149) (xy 13.483336 -117.150134)
			(xy 13.483336 -117.083078) (xy 13.482982 -117.074061) (xy 13.476732 -117.057144) (xy 13.471144 -117.050058)
			(xy 13.47089 -117.050058) (xy 13.47089 -117.049804) (xy 13.453257 -117.028866) (xy 13.423535 -116.982898)
			(xy 13.400691 -116.933152) (xy 13.385196 -116.880652) (xy 13.377368 -116.826474) (xy 13.377367 -116.771735)
			(xy 13.385194 -116.717557) (xy 13.400688 -116.665056) (xy 13.42353 -116.61531) (xy 13.453251 -116.569341)
			(xy 13.47089 -116.548408) (xy 13.471144 -116.548154) (xy 13.476719 -116.54106) (xy 13.482972 -116.524149)
			(xy 13.483336 -116.515134) (xy 13.483336 -116.448078) (xy 13.482982 -116.439061) (xy 13.476732 -116.422144)
			(xy 13.471144 -116.415058) (xy 13.47089 -116.415058) (xy 13.47089 -116.414804) (xy 13.453238 -116.393883)
			(xy 13.423528 -116.347907) (xy 13.400695 -116.298156) (xy 13.385207 -116.245653) (xy 13.377382 -116.191476)
			(xy 13.37691 -116.164106) (xy 13.377361 -116.136852) (xy 13.385118 -116.0829) (xy 13.400474 -116.030601)
			(xy 13.423117 -115.98102) (xy 13.452586 -115.935166) (xy 13.488281 -115.893972) (xy 13.529475 -115.858279)
			(xy 13.57533 -115.828811) (xy 13.624912 -115.80617) (xy 13.677212 -115.790815) (xy 13.731164 -115.78306)
			(xy 13.758418 -115.782598) (xy 13.785789 -115.783054) (xy 13.839968 -115.790874) (xy 13.892471 -115.806366)
			(xy 13.942218 -115.82921) (xy 13.988184 -115.858936) (xy 14.009116 -115.876578) (xy 14.00937 -115.876832)
			(xy 14.016458 -115.882416) (xy 14.033374 -115.888663) (xy 14.04239 -115.889024) (xy 14.109446 -115.889024)
			(xy 14.11846 -115.888636) (xy 14.135377 -115.882409) (xy 14.142466 -115.876832) (xy 14.142466 -115.876578)
			(xy 14.14272 -115.876578) (xy 14.163669 -115.85896) (xy 14.209637 -115.829245) (xy 14.259381 -115.806406)
			(xy 14.311877 -115.79091) (xy 14.36605 -115.783075) (xy 14.393418 -115.782598) (xy 14.42067 -115.783061)
			(xy 14.474619 -115.79082) (xy 14.526914 -115.806178) (xy 14.576492 -115.828822) (xy 14.622343 -115.85829)
			(xy 14.663533 -115.893984) (xy 14.699224 -115.935177) (xy 14.72869 -115.981029) (xy 14.75133 -116.030608)
			(xy 14.766685 -116.082905) (xy 14.774441 -116.136854) (xy 14.774926 -116.164106) (xy 14.774481 -116.191477)
			(xy 14.766661 -116.245658) (xy 14.751168 -116.298162) (xy 14.728321 -116.347909) (xy 14.69859 -116.393874)
			(xy 14.680946 -116.414804) (xy 14.680692 -116.415058) (xy 14.675116 -116.422152) (xy 14.668863 -116.439063)
			(xy 14.6685 -116.448078) (xy 14.6685 -116.515134) (xy 14.668841 -116.524152) (xy 14.6751 -116.541069)
			(xy 14.680692 -116.548154) (xy 14.680946 -116.548154) (xy 14.680946 -116.548408) (xy 14.698594 -116.569335)
			(xy 14.72832 -116.615303) (xy 14.751167 -116.66505) (xy 14.766664 -116.717554) (xy 14.774493 -116.771733)
			(xy 14.774492 -116.826476) (xy 14.766662 -116.880655) (xy 14.751164 -116.933158) (xy 14.728316 -116.982904)
			(xy 14.698588 -117.028872) (xy 14.680946 -117.049804) (xy 14.680692 -117.050058) (xy 14.675116 -117.057152)
			(xy 14.668863 -117.074063) (xy 14.6685 -117.083078) (xy 14.6685 -117.150134) (xy 14.668841 -117.159152)
			(xy 14.6751 -117.176069) (xy 14.680692 -117.183154) (xy 14.680946 -117.183154) (xy 14.680946 -117.183408)
			(xy 14.698594 -117.204333) (xy 14.728306 -117.250307) (xy 14.751141 -117.300056) (xy 14.76663 -117.352559)
			(xy 14.774454 -117.406736) (xy 14.774926 -117.434106) (xy 14.774786 -117.442234) (xy 15.659098 -117.442234)
			(xy 15.663169 -117.386612) (xy 15.675295 -117.332175) (xy 15.695218 -117.280084) (xy 15.722514 -117.231449)
			(xy 15.7566 -117.187306) (xy 15.796749 -117.148597) (xy 15.842107 -117.116146) (xy 15.891707 -117.090645)
			(xy 15.944491 -117.072638) (xy 15.999334 -117.062508) (xy 16.055068 -117.060471) (xy 16.110505 -117.066571)
			(xy 16.164462 -117.080677) (xy 16.215791 -117.102489) (xy 16.263397 -117.131543) (xy 16.306265 -117.167218)
			(xy 16.343482 -117.208755) (xy 16.374255 -117.255268) (xy 16.397927 -117.305765) (xy 16.413995 -117.359172)
			(xy 16.422115 -117.414348) (xy 16.422624 -117.442234) (xy 16.422115 -117.47012) (xy 16.413995 -117.525296)
			(xy 16.397927 -117.578703) (xy 16.374255 -117.6292) (xy 16.343482 -117.675713) (xy 16.306265 -117.71725)
			(xy 16.263397 -117.752925) (xy 16.215791 -117.781979) (xy 16.164462 -117.803791) (xy 16.110505 -117.817897)
			(xy 16.055068 -117.823997) (xy 15.999334 -117.82196) (xy 15.944491 -117.81183) (xy 15.891707 -117.793823)
			(xy 15.842107 -117.768322) (xy 15.796749 -117.735871) (xy 15.7566 -117.697162) (xy 15.722514 -117.653019)
			(xy 15.695218 -117.604384) (xy 15.675295 -117.552293) (xy 15.663169 -117.497856) (xy 15.659098 -117.442234)
			(xy 14.774786 -117.442234) (xy 14.774469 -117.460662) (xy 14.767101 -117.513262) (xy 14.752509 -117.564331)
			(xy 14.74216 -117.588792) (xy 14.737815 -117.600161) (xy 14.739162 -117.624433) (xy 14.7447 -117.635274)
			(xy 14.786102 -117.706394) (xy 14.792839 -117.716462) (xy 14.813244 -117.729453) (xy 14.825218 -117.731286)
			(xy 14.853196 -117.734495) (xy 14.90786 -117.748027) (xy 14.959939 -117.769449) (xy 15.008302 -117.798296)
			(xy 15.051898 -117.833941) (xy 15.089779 -117.875609) (xy 15.121122 -117.922394) (xy 15.145244 -117.973279)
			(xy 15.161622 -118.027158) (xy 15.167063 -118.063772) (xy 16.806162 -118.063772) (xy 16.810233 -118.00815)
			(xy 16.822359 -117.953713) (xy 16.842282 -117.901622) (xy 16.869578 -117.852987) (xy 16.903664 -117.808844)
			(xy 16.943813 -117.770135) (xy 16.989171 -117.737684) (xy 17.038771 -117.712183) (xy 17.091555 -117.694176)
			(xy 17.146398 -117.684046) (xy 17.202132 -117.682009) (xy 17.257569 -117.688109) (xy 17.311526 -117.702215)
			(xy 17.362855 -117.724027) (xy 17.410461 -117.753081) (xy 17.453329 -117.788756) (xy 17.490546 -117.830293)
			(xy 17.521319 -117.876806) (xy 17.544991 -117.927303) (xy 17.561059 -117.98071) (xy 17.567078 -118.021608)
			(xy 17.685512 -118.021608) (xy 17.68598 -117.994238) (xy 17.693797 -117.940059) (xy 17.709285 -117.887555)
			(xy 17.732127 -117.837809) (xy 17.761851 -117.791842) (xy 17.779492 -117.77091) (xy 17.779746 -117.770656)
			(xy 17.785321 -117.763562) (xy 17.791573 -117.746651) (xy 17.791938 -117.737636) (xy 17.791938 -117.67058)
			(xy 17.791582 -117.661563) (xy 17.785333 -117.644647) (xy 17.779746 -117.63756) (xy 17.779492 -117.63756)
			(xy 17.779492 -117.637306) (xy 17.761861 -117.616366) (xy 17.732138 -117.570399) (xy 17.709294 -117.520653)
			(xy 17.693799 -117.468153) (xy 17.68597 -117.413976) (xy 17.68597 -117.359236) (xy 17.693796 -117.305059)
			(xy 17.70929 -117.252558) (xy 17.732132 -117.202812) (xy 17.761853 -117.156843) (xy 17.779492 -117.13591)
			(xy 17.779746 -117.135656) (xy 17.785321 -117.128562) (xy 17.791573 -117.111651) (xy 17.791938 -117.102636)
			(xy 17.791938 -117.03558) (xy 17.791582 -117.026563) (xy 17.785333 -117.009647) (xy 17.779746 -117.00256)
			(xy 17.779492 -117.00256) (xy 17.779492 -117.002306) (xy 17.761841 -116.981384) (xy 17.732131 -116.935408)
			(xy 17.709298 -116.885658) (xy 17.693809 -116.833155) (xy 17.685984 -116.778978) (xy 17.685512 -116.751608)
			(xy 17.685963 -116.724354) (xy 17.693719 -116.670402) (xy 17.709075 -116.618103) (xy 17.731718 -116.568521)
			(xy 17.761187 -116.522667) (xy 17.796882 -116.481474) (xy 17.838077 -116.44578) (xy 17.883932 -116.416313)
			(xy 17.933514 -116.393671) (xy 17.985814 -116.378317) (xy 18.039766 -116.370562) (xy 18.06702 -116.3701)
			(xy 18.094391 -116.370554) (xy 18.14857 -116.378375) (xy 18.201073 -116.393867) (xy 18.25082 -116.416711)
			(xy 18.296787 -116.446438) (xy 18.317718 -116.46408) (xy 18.317972 -116.464334) (xy 18.32506 -116.469919)
			(xy 18.341976 -116.476165) (xy 18.350992 -116.476526) (xy 18.418048 -116.476526) (xy 18.427062 -116.476139)
			(xy 18.443979 -116.469912) (xy 18.451068 -116.464334) (xy 18.451068 -116.46408) (xy 18.451322 -116.46408)
			(xy 18.47227 -116.446461) (xy 18.518239 -116.416747) (xy 18.567982 -116.393907) (xy 18.620479 -116.378411)
			(xy 18.674652 -116.370577) (xy 18.70202 -116.3701) (xy 18.729272 -116.370559) (xy 18.783221 -116.378319)
			(xy 18.835517 -116.393677) (xy 18.885095 -116.416321) (xy 18.930945 -116.44579) (xy 18.972136 -116.481484)
			(xy 19.007827 -116.522677) (xy 19.037293 -116.56853) (xy 19.059933 -116.618109) (xy 19.075287 -116.670406)
			(xy 19.083043 -116.724356) (xy 19.083528 -116.751608) (xy 19.083084 -116.778979) (xy 19.075264 -116.83316)
			(xy 19.05977 -116.885664) (xy 19.036923 -116.935411) (xy 19.007192 -116.981376) (xy 18.989548 -117.002306)
			(xy 18.989294 -117.00256) (xy 18.983717 -117.009653) (xy 18.977465 -117.026565) (xy 18.977102 -117.03558)
			(xy 18.977102 -117.102636) (xy 18.977442 -117.111655) (xy 18.983701 -117.128571) (xy 18.989294 -117.135656)
			(xy 18.989548 -117.135656) (xy 18.989548 -117.13591) (xy 19.007198 -117.156836) (xy 19.036924 -117.202804)
			(xy 19.05977 -117.252551) (xy 19.075267 -117.305055) (xy 19.083095 -117.359235) (xy 19.083095 -117.413977)
			(xy 19.075265 -117.468157) (xy 19.059766 -117.52066) (xy 19.036918 -117.570406) (xy 19.00719 -117.616374)
			(xy 18.989548 -117.637306) (xy 18.989294 -117.63756) (xy 18.983717 -117.644653) (xy 18.977465 -117.661565)
			(xy 18.977102 -117.67058) (xy 18.977102 -117.737636) (xy 18.977442 -117.746655) (xy 18.983701 -117.763571)
			(xy 18.989294 -117.770656) (xy 18.989548 -117.770656) (xy 18.989548 -117.77091) (xy 19.007197 -117.791834)
			(xy 19.036909 -117.837808) (xy 19.059744 -117.887558) (xy 19.075233 -117.94006) (xy 19.083057 -117.994238)
			(xy 19.083528 -118.021608) (xy 19.08303 -118.048859) (xy 19.075273 -118.102805) (xy 19.059918 -118.155098)
			(xy 19.037277 -118.204674) (xy 19.007812 -118.250523) (xy 18.972122 -118.291713) (xy 18.930933 -118.327404)
			(xy 18.885085 -118.356871) (xy 18.835509 -118.379513) (xy 18.783217 -118.39487) (xy 18.729271 -118.402629)
			(xy 18.70202 -118.403116) (xy 18.674649 -118.402659) (xy 18.620469 -118.394842) (xy 18.567965 -118.379352)
			(xy 18.518218 -118.356508) (xy 18.472252 -118.326779) (xy 18.451322 -118.309136) (xy 18.451068 -118.308882)
			(xy 18.443968 -118.303316) (xy 18.427061 -118.297057) (xy 18.418048 -118.29669) (xy 18.350992 -118.29669)
			(xy 18.341975 -118.297045) (xy 18.325058 -118.303294) (xy 18.317972 -118.308882) (xy 18.317972 -118.309136)
			(xy 18.317718 -118.309136) (xy 18.296795 -118.326786) (xy 18.250819 -118.356495) (xy 18.201069 -118.379328)
			(xy 18.148567 -118.394817) (xy 18.09439 -118.402643) (xy 18.06702 -118.403116) (xy 18.039768 -118.402626)
			(xy 17.985818 -118.394872) (xy 17.933522 -118.379519) (xy 17.883942 -118.356879) (xy 17.838089 -118.327414)
			(xy 17.796897 -118.291723) (xy 17.761203 -118.250533) (xy 17.731734 -118.204683) (xy 17.709091 -118.155105)
			(xy 17.693734 -118.102809) (xy 17.685976 -118.04886) (xy 17.685512 -118.021608) (xy 17.567078 -118.021608)
			(xy 17.569179 -118.035886) (xy 17.569688 -118.063772) (xy 17.569179 -118.091658) (xy 17.561059 -118.146834)
			(xy 17.544991 -118.200241) (xy 17.521319 -118.250738) (xy 17.490546 -118.297251) (xy 17.453329 -118.338788)
			(xy 17.410461 -118.374463) (xy 17.362855 -118.403517) (xy 17.311526 -118.425329) (xy 17.257569 -118.439435)
			(xy 17.202132 -118.445535) (xy 17.146398 -118.443498) (xy 17.091555 -118.433368) (xy 17.038771 -118.415361)
			(xy 16.989171 -118.38986) (xy 16.943813 -118.357409) (xy 16.903664 -118.3187) (xy 16.869578 -118.274557)
			(xy 16.842282 -118.225922) (xy 16.822359 -118.173831) (xy 16.810233 -118.119394) (xy 16.806162 -118.063772)
			(xy 15.167063 -118.063772) (xy 15.1699 -118.082859) (xy 15.170404 -118.111016) (xy 15.169918 -118.138267)
			(xy 15.162162 -118.192215) (xy 15.146807 -118.24451) (xy 15.124165 -118.294087) (xy 15.094699 -118.339937)
			(xy 15.059008 -118.381128) (xy 15.017817 -118.416819) (xy 14.971967 -118.446285) (xy 14.92239 -118.468927)
			(xy 14.870095 -118.484282) (xy 14.816147 -118.492038) (xy 14.761645 -118.492038) (xy 14.707697 -118.484282)
			(xy 14.655402 -118.468927) (xy 14.605825 -118.446285) (xy 14.559975 -118.416819) (xy 14.518784 -118.381128)
			(xy 14.483093 -118.339937) (xy 14.453627 -118.294087) (xy 14.430985 -118.24451) (xy 14.41563 -118.192215)
			(xy 14.407874 -118.138267) (xy 14.407388 -118.111016) (xy 14.407851 -118.08446) (xy 14.415217 -118.031861)
			(xy 14.429807 -117.980792) (xy 14.440154 -117.95633) (xy 14.444483 -117.944956) (xy 14.443146 -117.920689)
			(xy 14.437614 -117.909848) (xy 14.396212 -117.838728) (xy 14.389488 -117.828651) (xy 14.369072 -117.815667)
			(xy 14.357096 -117.813836) (xy 14.32762 -117.810473) (xy 14.270151 -117.79575) (xy 14.215655 -117.772305)
			(xy 14.165446 -117.740706) (xy 14.14272 -117.721634) (xy 14.142466 -117.72138) (xy 14.135366 -117.715813)
			(xy 14.11846 -117.709555) (xy 14.109446 -117.709188) (xy 14.04239 -117.709188) (xy 14.033373 -117.709543)
			(xy 14.016456 -117.715792) (xy 14.00937 -117.72138) (xy 14.00937 -117.721634) (xy 14.009116 -117.721634)
			(xy 13.988193 -117.739284) (xy 13.942217 -117.768993) (xy 13.892467 -117.791827) (xy 13.839965 -117.807315)
			(xy 13.785788 -117.815141) (xy 13.758418 -117.815614) (xy 13.731166 -117.815128) (xy 13.677216 -117.807374)
			(xy 13.624919 -117.79202) (xy 13.575339 -117.76938) (xy 13.529486 -117.739915) (xy 13.488294 -117.704223)
			(xy 13.4526 -117.663033) (xy 13.423131 -117.617182) (xy 13.400488 -117.567604) (xy 13.385132 -117.515307)
			(xy 13.377374 -117.461358) (xy 13.37691 -117.434106) (xy 5.1054 -117.434106) (xy 5.1054 -118.089426)
			(xy 10.195304 -118.089426) (xy 10.199375 -118.033804) (xy 10.211501 -117.979367) (xy 10.231424 -117.927276)
			(xy 10.25872 -117.878641) (xy 10.292806 -117.834498) (xy 10.332955 -117.795789) (xy 10.378313 -117.763338)
			(xy 10.427913 -117.737837) (xy 10.480697 -117.71983) (xy 10.53554 -117.7097) (xy 10.591274 -117.707663)
			(xy 10.646711 -117.713763) (xy 10.700668 -117.727869) (xy 10.751997 -117.749681) (xy 10.799603 -117.778735)
			(xy 10.842471 -117.81441) (xy 10.879688 -117.855947) (xy 10.910461 -117.90246) (xy 10.934133 -117.952957)
			(xy 10.936982 -117.962426) (xy 12.227304 -117.962426) (xy 12.231375 -117.906804) (xy 12.243501 -117.852367)
			(xy 12.263424 -117.800276) (xy 12.29072 -117.751641) (xy 12.324806 -117.707498) (xy 12.364955 -117.668789)
			(xy 12.410313 -117.636338) (xy 12.459913 -117.610837) (xy 12.512697 -117.59283) (xy 12.56754 -117.5827)
			(xy 12.623274 -117.580663) (xy 12.678711 -117.586763) (xy 12.732668 -117.600869) (xy 12.783997 -117.622681)
			(xy 12.831603 -117.651735) (xy 12.874471 -117.68741) (xy 12.911688 -117.728947) (xy 12.942461 -117.77546)
			(xy 12.966133 -117.825957) (xy 12.982201 -117.879364) (xy 12.990321 -117.93454) (xy 12.99083 -117.962426)
			(xy 12.990321 -117.990312) (xy 12.982201 -118.045488) (xy 12.966133 -118.098895) (xy 12.942461 -118.149392)
			(xy 12.911688 -118.195905) (xy 12.874471 -118.237442) (xy 12.831603 -118.273117) (xy 12.783997 -118.302171)
			(xy 12.732668 -118.323983) (xy 12.678711 -118.338089) (xy 12.623274 -118.344189) (xy 12.56754 -118.342152)
			(xy 12.512697 -118.332022) (xy 12.459913 -118.314015) (xy 12.410313 -118.288514) (xy 12.364955 -118.256063)
			(xy 12.324806 -118.217354) (xy 12.29072 -118.173211) (xy 12.263424 -118.124576) (xy 12.243501 -118.072485)
			(xy 12.231375 -118.018048) (xy 12.227304 -117.962426) (xy 10.936982 -117.962426) (xy 10.950201 -118.006364)
			(xy 10.958321 -118.06154) (xy 10.95883 -118.089426) (xy 10.958321 -118.117312) (xy 10.950201 -118.172488)
			(xy 10.934133 -118.225895) (xy 10.910461 -118.276392) (xy 10.879688 -118.322905) (xy 10.842471 -118.364442)
			(xy 10.799603 -118.400117) (xy 10.751997 -118.429171) (xy 10.700668 -118.450983) (xy 10.646711 -118.465089)
			(xy 10.591274 -118.471189) (xy 10.53554 -118.469152) (xy 10.480697 -118.459022) (xy 10.427913 -118.441015)
			(xy 10.378313 -118.415514) (xy 10.332955 -118.383063) (xy 10.292806 -118.344354) (xy 10.25872 -118.300211)
			(xy 10.231424 -118.251576) (xy 10.211501 -118.199485) (xy 10.199375 -118.145048) (xy 10.195304 -118.089426)
			(xy 5.1054 -118.089426) (xy 5.1054 -120.248426) (xy 10.195304 -120.248426) (xy 10.199375 -120.192804)
			(xy 10.211501 -120.138367) (xy 10.231424 -120.086276) (xy 10.25872 -120.037641) (xy 10.292806 -119.993498)
			(xy 10.332955 -119.954789) (xy 10.378313 -119.922338) (xy 10.427913 -119.896837) (xy 10.480697 -119.87883)
			(xy 10.53554 -119.8687) (xy 10.591274 -119.866663) (xy 10.646711 -119.872763) (xy 10.700668 -119.886869)
			(xy 10.751997 -119.908681) (xy 10.799603 -119.937735) (xy 10.842471 -119.97341) (xy 10.879688 -120.014947)
			(xy 10.910461 -120.06146) (xy 10.934133 -120.111957) (xy 10.935912 -120.11787) (xy 11.211304 -120.11787)
			(xy 11.215375 -120.062248) (xy 11.227501 -120.007811) (xy 11.247424 -119.95572) (xy 11.27472 -119.907085)
			(xy 11.308806 -119.862942) (xy 11.348955 -119.824233) (xy 11.394313 -119.791782) (xy 11.443913 -119.766281)
			(xy 11.496697 -119.748274) (xy 11.55154 -119.738144) (xy 11.607274 -119.736107) (xy 11.662711 -119.742207)
			(xy 11.716668 -119.756313) (xy 11.767997 -119.778125) (xy 11.815603 -119.807179) (xy 11.858471 -119.842854)
			(xy 11.895688 -119.884391) (xy 11.926461 -119.930904) (xy 11.950133 -119.981401) (xy 11.966201 -120.034808)
			(xy 11.974321 -120.089984) (xy 11.97483 -120.11787) (xy 12.227304 -120.11787) (xy 12.231375 -120.062248)
			(xy 12.243501 -120.007811) (xy 12.263424 -119.95572) (xy 12.29072 -119.907085) (xy 12.324806 -119.862942)
			(xy 12.364955 -119.824233) (xy 12.410313 -119.791782) (xy 12.459913 -119.766281) (xy 12.512697 -119.748274)
			(xy 12.56754 -119.738144) (xy 12.623274 -119.736107) (xy 12.678711 -119.742207) (xy 12.732668 -119.756313)
			(xy 12.783997 -119.778125) (xy 12.831603 -119.807179) (xy 12.874471 -119.842854) (xy 12.911688 -119.884391)
			(xy 12.942461 -119.930904) (xy 12.966133 -119.981401) (xy 12.982201 -120.034808) (xy 12.990321 -120.089984)
			(xy 12.99083 -120.11787) (xy 12.990321 -120.145756) (xy 12.989192 -120.15343) (xy 15.422878 -120.15343)
			(xy 15.426949 -120.097808) (xy 15.439075 -120.043371) (xy 15.458998 -119.99128) (xy 15.486294 -119.942645)
			(xy 15.52038 -119.898502) (xy 15.560529 -119.859793) (xy 15.605887 -119.827342) (xy 15.655487 -119.801841)
			(xy 15.708271 -119.783834) (xy 15.763114 -119.773704) (xy 15.818848 -119.771667) (xy 15.874285 -119.777767)
			(xy 15.928242 -119.791873) (xy 15.979571 -119.813685) (xy 16.027177 -119.842739) (xy 16.070045 -119.878414)
			(xy 16.107262 -119.919951) (xy 16.138035 -119.966464) (xy 16.161707 -120.016961) (xy 16.177775 -120.070368)
			(xy 16.185895 -120.125544) (xy 16.186404 -120.15343) (xy 16.185895 -120.181316) (xy 16.177775 -120.236492)
			(xy 16.161707 -120.289899) (xy 16.138035 -120.340396) (xy 16.107262 -120.386909) (xy 16.070045 -120.428446)
			(xy 16.027177 -120.464121) (xy 15.979571 -120.493175) (xy 15.928242 -120.514987) (xy 15.874285 -120.529093)
			(xy 15.818848 -120.535193) (xy 15.763114 -120.533156) (xy 15.708271 -120.523026) (xy 15.655487 -120.505019)
			(xy 15.605887 -120.479518) (xy 15.560529 -120.447067) (xy 15.52038 -120.408358) (xy 15.486294 -120.364215)
			(xy 15.458998 -120.31558) (xy 15.439075 -120.263489) (xy 15.426949 -120.209052) (xy 15.422878 -120.15343)
			(xy 12.989192 -120.15343) (xy 12.982201 -120.200932) (xy 12.966133 -120.254339) (xy 12.942461 -120.304836)
			(xy 12.911688 -120.351349) (xy 12.874471 -120.392886) (xy 12.831603 -120.428561) (xy 12.783997 -120.457615)
			(xy 12.732668 -120.479427) (xy 12.678711 -120.493533) (xy 12.623274 -120.499633) (xy 12.56754 -120.497596)
			(xy 12.512697 -120.487466) (xy 12.459913 -120.469459) (xy 12.410313 -120.443958) (xy 12.364955 -120.411507)
			(xy 12.324806 -120.372798) (xy 12.29072 -120.328655) (xy 12.263424 -120.28002) (xy 12.243501 -120.227929)
			(xy 12.231375 -120.173492) (xy 12.227304 -120.11787) (xy 11.97483 -120.11787) (xy 11.974321 -120.145756)
			(xy 11.966201 -120.200932) (xy 11.950133 -120.254339) (xy 11.926461 -120.304836) (xy 11.895688 -120.351349)
			(xy 11.858471 -120.392886) (xy 11.815603 -120.428561) (xy 11.767997 -120.457615) (xy 11.716668 -120.479427)
			(xy 11.662711 -120.493533) (xy 11.607274 -120.499633) (xy 11.55154 -120.497596) (xy 11.496697 -120.487466)
			(xy 11.443913 -120.469459) (xy 11.394313 -120.443958) (xy 11.348955 -120.411507) (xy 11.308806 -120.372798)
			(xy 11.27472 -120.328655) (xy 11.247424 -120.28002) (xy 11.227501 -120.227929) (xy 11.215375 -120.173492)
			(xy 11.211304 -120.11787) (xy 10.935912 -120.11787) (xy 10.950201 -120.165364) (xy 10.958321 -120.22054)
			(xy 10.95883 -120.248426) (xy 10.958321 -120.276312) (xy 10.950201 -120.331488) (xy 10.934133 -120.384895)
			(xy 10.910461 -120.435392) (xy 10.879688 -120.481905) (xy 10.842471 -120.523442) (xy 10.799603 -120.559117)
			(xy 10.751997 -120.588171) (xy 10.700668 -120.609983) (xy 10.646711 -120.624089) (xy 10.591274 -120.630189)
			(xy 10.53554 -120.628152) (xy 10.480697 -120.618022) (xy 10.427913 -120.600015) (xy 10.378313 -120.574514)
			(xy 10.332955 -120.542063) (xy 10.292806 -120.503354) (xy 10.25872 -120.459211) (xy 10.231424 -120.410576)
			(xy 10.211501 -120.358485) (xy 10.199375 -120.304048) (xy 10.195304 -120.248426) (xy 5.1054 -120.248426)
			(xy 5.1054 -121.57075) (xy 13.619988 -121.57075) (xy 13.620426 -121.544435) (xy 13.627667 -121.492305)
			(xy 13.641992 -121.441662) (xy 13.66313 -121.393464) (xy 13.690682 -121.348621) (xy 13.724125 -121.307982)
			(xy 13.743178 -121.289826) (xy 13.750567 -121.282294) (xy 13.759099 -121.263022) (xy 13.759688 -121.252488)
			(xy 13.759688 -121.177812) (xy 13.759169 -121.167261) (xy 13.750627 -121.147966) (xy 13.743178 -121.140474)
			(xy 13.724113 -121.122328) (xy 13.690657 -121.081696) (xy 13.6631 -121.036854) (xy 13.641963 -120.988651)
			(xy 13.627648 -120.938002) (xy 13.620425 -120.885867) (xy 13.619988 -120.85955) (xy 13.620474 -120.832299)
			(xy 13.62823 -120.778351) (xy 13.643585 -120.726056) (xy 13.666227 -120.676479) (xy 13.695693 -120.630629)
			(xy 13.731384 -120.589438) (xy 13.772575 -120.553747) (xy 13.818425 -120.524281) (xy 13.868002 -120.501639)
			(xy 13.920297 -120.486284) (xy 13.974245 -120.478528) (xy 14.028747 -120.478528) (xy 14.082695 -120.486284)
			(xy 14.13499 -120.501639) (xy 14.184567 -120.524281) (xy 14.230417 -120.553747) (xy 14.271608 -120.589438)
			(xy 14.307299 -120.630629) (xy 14.336765 -120.676479) (xy 14.359407 -120.726056) (xy 14.374762 -120.778351)
			(xy 14.382518 -120.832299) (xy 14.383004 -120.85955) (xy 14.382569 -120.885865) (xy 14.375327 -120.937995)
			(xy 14.361002 -120.988638) (xy 14.339863 -121.036837) (xy 14.312311 -121.08168) (xy 14.278868 -121.122318)
			(xy 14.259814 -121.140474) (xy 14.252424 -121.148005) (xy 14.243892 -121.167278) (xy 14.243304 -121.177812)
			(xy 14.243304 -121.252488) (xy 14.243825 -121.263039) (xy 14.252366 -121.282334) (xy 14.259814 -121.289826)
			(xy 14.278878 -121.307973) (xy 14.312334 -121.348605) (xy 14.339891 -121.393447) (xy 14.361028 -121.44165)
			(xy 14.375344 -121.492298) (xy 14.382567 -121.544433) (xy 14.383004 -121.57075) (xy 14.382518 -121.598001)
			(xy 14.374762 -121.651949) (xy 14.359407 -121.704244) (xy 14.336765 -121.753821) (xy 14.307299 -121.799671)
			(xy 14.271608 -121.840862) (xy 14.230417 -121.876553) (xy 14.184567 -121.906019) (xy 14.13499 -121.928661)
			(xy 14.082695 -121.944016) (xy 14.028747 -121.951772) (xy 13.974245 -121.951772) (xy 13.920297 -121.944016)
			(xy 13.868002 -121.928661) (xy 13.818425 -121.906019) (xy 13.772575 -121.876553) (xy 13.731384 -121.840862)
			(xy 13.695693 -121.799671) (xy 13.666227 -121.753821) (xy 13.643585 -121.704244) (xy 13.62823 -121.651949)
			(xy 13.620474 -121.598001) (xy 13.619988 -121.57075) (xy 5.1054 -121.57075) (xy 5.1054 -122.292618)
			(xy 9.780268 -122.292618) (xy 9.784339 -122.236996) (xy 9.796465 -122.182559) (xy 9.816388 -122.130468)
			(xy 9.843684 -122.081833) (xy 9.87777 -122.03769) (xy 9.917919 -121.998981) (xy 9.963277 -121.96653)
			(xy 10.012877 -121.941029) (xy 10.065661 -121.923022) (xy 10.120504 -121.912892) (xy 10.176238 -121.910855)
			(xy 10.231675 -121.916955) (xy 10.285632 -121.931061) (xy 10.336961 -121.952873) (xy 10.384567 -121.981927)
			(xy 10.427435 -122.017602) (xy 10.464652 -122.059139) (xy 10.495425 -122.105652) (xy 10.519097 -122.156149)
			(xy 10.535165 -122.209556) (xy 10.543285 -122.264732) (xy 10.543794 -122.292618) (xy 10.543285 -122.320504)
			(xy 10.535165 -122.37568) (xy 10.519097 -122.429087) (xy 10.49996 -122.46991) (xy 10.936984 -122.46991)
			(xy 10.941055 -122.414288) (xy 10.953181 -122.359851) (xy 10.973104 -122.30776) (xy 11.0004 -122.259125)
			(xy 11.034486 -122.214982) (xy 11.074635 -122.176273) (xy 11.119993 -122.143822) (xy 11.169593 -122.118321)
			(xy 11.222377 -122.100314) (xy 11.27722 -122.090184) (xy 11.332954 -122.088147) (xy 11.388391 -122.094247)
			(xy 11.442348 -122.108353) (xy 11.493677 -122.130165) (xy 11.541283 -122.159219) (xy 11.584151 -122.194894)
			(xy 11.621368 -122.236431) (xy 11.652141 -122.282944) (xy 11.675813 -122.333441) (xy 11.691881 -122.386848)
			(xy 11.700001 -122.442024) (xy 11.70051 -122.46991) (xy 11.700001 -122.497796) (xy 11.691881 -122.552972)
			(xy 11.675813 -122.606379) (xy 11.652141 -122.656876) (xy 11.621368 -122.703389) (xy 11.584151 -122.744926)
			(xy 11.541283 -122.780601) (xy 11.493677 -122.809655) (xy 11.442348 -122.831467) (xy 11.388391 -122.845573)
			(xy 11.332954 -122.851673) (xy 11.27722 -122.849636) (xy 11.222377 -122.839506) (xy 11.169593 -122.821499)
			(xy 11.119993 -122.795998) (xy 11.074635 -122.763547) (xy 11.034486 -122.724838) (xy 11.0004 -122.680695)
			(xy 10.973104 -122.63206) (xy 10.953181 -122.579969) (xy 10.941055 -122.525532) (xy 10.936984 -122.46991)
			(xy 10.49996 -122.46991) (xy 10.495425 -122.479584) (xy 10.464652 -122.526097) (xy 10.427435 -122.567634)
			(xy 10.384567 -122.603309) (xy 10.336961 -122.632363) (xy 10.285632 -122.654175) (xy 10.231675 -122.668281)
			(xy 10.176238 -122.674381) (xy 10.120504 -122.672344) (xy 10.065661 -122.662214) (xy 10.012877 -122.644207)
			(xy 9.963277 -122.618706) (xy 9.917919 -122.586255) (xy 9.87777 -122.547546) (xy 9.843684 -122.503403)
			(xy 9.816388 -122.454768) (xy 9.796465 -122.402677) (xy 9.784339 -122.34824) (xy 9.780268 -122.292618)
			(xy 5.1054 -122.292618) (xy 5.1054 -123.249761) (xy 11.91004 -123.249761) (xy 11.91004 -123.195259)
			(xy 11.917796 -123.141311) (xy 11.933151 -123.089017) (xy 11.955792 -123.03944) (xy 11.985258 -122.99359)
			(xy 12.02095 -122.9524) (xy 12.06214 -122.916708) (xy 12.10799 -122.887242) (xy 12.157567 -122.864601)
			(xy 12.209861 -122.849246) (xy 12.263809 -122.84149) (xy 12.29106 -122.841004) (xy 12.318091 -122.841459)
			(xy 12.371611 -122.849105) (xy 12.423513 -122.864236) (xy 12.472757 -122.886548) (xy 12.518354 -122.915593)
			(xy 12.559391 -122.950789) (xy 12.577572 -122.970798) (xy 12.577826 -122.971052) (xy 12.585282 -122.978685)
			(xy 12.604757 -122.987361) (xy 12.615418 -122.987816) (xy 12.703048 -122.988324) (xy 12.722606 -122.979688)
			(xy 12.729972 -122.971306) (xy 12.748153 -122.951603) (xy 12.78905 -122.916937) (xy 12.834401 -122.888346)
			(xy 12.883312 -122.866393) (xy 12.934818 -122.851514) (xy 12.9879 -122.844) (xy 13.014706 -122.843544)
			(xy 13.042077 -122.843996) (xy 13.096257 -122.851815) (xy 13.148761 -122.867307) (xy 13.198507 -122.890152)
			(xy 13.244473 -122.919881) (xy 13.265404 -122.937524) (xy 13.265658 -122.937778) (xy 13.272746 -122.943362)
			(xy 13.289662 -122.949608) (xy 13.298678 -122.94997) (xy 13.365734 -122.94997) (xy 13.374753 -122.949636)
			(xy 13.39167 -122.943373) (xy 13.398754 -122.937778) (xy 13.398754 -122.937524) (xy 13.399008 -122.937524)
			(xy 13.419941 -122.919883) (xy 13.465909 -122.890159) (xy 13.515655 -122.867313) (xy 13.568157 -122.851817)
			(xy 13.622335 -122.843988) (xy 13.677077 -122.843988) (xy 13.731255 -122.851817) (xy 13.783757 -122.867313)
			(xy 13.833503 -122.890159) (xy 13.879471 -122.919883) (xy 13.900404 -122.937524) (xy 13.900658 -122.937778)
			(xy 13.907746 -122.943362) (xy 13.924662 -122.949608) (xy 13.933678 -122.94997) (xy 14.000734 -122.94997)
			(xy 14.009753 -122.949636) (xy 14.02667 -122.943373) (xy 14.033754 -122.937778) (xy 14.034262 -122.937524)
			(xy 14.046999 -122.926583) (xy 14.074088 -122.90674) (xy 14.088364 -122.8979) (xy 14.097254 -122.892566)
			(xy 14.109446 -122.875548) (xy 14.129766 -122.78233) (xy 14.125448 -122.761756) (xy 14.119606 -122.75312)
			(xy 14.103613 -122.729052) (xy 14.078269 -122.677122) (xy 14.061041 -122.621965) (xy 14.052324 -122.564842)
			(xy 14.051788 -122.53595) (xy 14.052274 -122.508699) (xy 14.06003 -122.454751) (xy 14.075385 -122.402456)
			(xy 14.098027 -122.352879) (xy 14.127493 -122.307029) (xy 14.163184 -122.265838) (xy 14.204375 -122.230147)
			(xy 14.250225 -122.200681) (xy 14.299802 -122.178039) (xy 14.352097 -122.162684) (xy 14.406045 -122.154928)
			(xy 14.460547 -122.154928) (xy 14.514495 -122.162684) (xy 14.56679 -122.178039) (xy 14.616367 -122.200681)
			(xy 14.662217 -122.230147) (xy 14.703408 -122.265838) (xy 14.739099 -122.307029) (xy 14.768565 -122.352879)
			(xy 14.791207 -122.402456) (xy 14.806562 -122.454751) (xy 14.814318 -122.508699) (xy 14.814804 -122.53595)
			(xy 14.814277 -122.56404) (xy 14.806056 -122.619616) (xy 14.789771 -122.673385) (xy 14.765774 -122.724183)
			(xy 14.734584 -122.77091) (xy 14.696876 -122.812556) (xy 14.653467 -122.848219) (xy 14.629638 -122.863102)
			(xy 14.620748 -122.868436) (xy 14.608556 -122.885454) (xy 14.588236 -122.978672) (xy 14.592554 -122.999246)
			(xy 14.598396 -123.007882) (xy 14.61439 -123.03195) (xy 14.639734 -123.08388) (xy 14.656962 -123.139036)
			(xy 14.665678 -123.19616) (xy 14.666214 -123.225052) (xy 14.6657 -123.252303) (xy 14.65795 -123.306252)
			(xy 14.6426 -123.358549) (xy 14.619964 -123.408128) (xy 14.590501 -123.453981) (xy 14.554813 -123.495174)
			(xy 14.513625 -123.530869) (xy 14.467776 -123.560338) (xy 14.418199 -123.582981) (xy 14.365905 -123.598338)
			(xy 14.311957 -123.606096) (xy 14.284706 -123.60656) (xy 14.257335 -123.6061) (xy 14.203156 -123.598282)
			(xy 14.150652 -123.582792) (xy 14.100905 -123.559949) (xy 14.054939 -123.530222) (xy 14.034008 -123.51258)
			(xy 14.033754 -123.512326) (xy 14.026662 -123.506747) (xy 14.009749 -123.500498) (xy 14.000734 -123.500134)
			(xy 13.933678 -123.500134) (xy 13.924659 -123.500473) (xy 13.907742 -123.506732) (xy 13.900658 -123.512326)
			(xy 13.900404 -123.51258) (xy 13.879471 -123.530221) (xy 13.833503 -123.559945) (xy 13.783757 -123.582791)
			(xy 13.731255 -123.598287) (xy 13.677077 -123.606116) (xy 13.622335 -123.606116) (xy 13.568157 -123.598287)
			(xy 13.515655 -123.582791) (xy 13.465909 -123.559945) (xy 13.419941 -123.530221) (xy 13.399008 -123.51258)
			(xy 13.398754 -123.512326) (xy 13.391662 -123.506747) (xy 13.374749 -123.500498) (xy 13.365734 -123.500134)
			(xy 13.298678 -123.500134) (xy 13.289659 -123.500473) (xy 13.272742 -123.506732) (xy 13.265658 -123.512326)
			(xy 13.265658 -123.51258) (xy 13.265404 -123.51258) (xy 13.244479 -123.530228) (xy 13.198504 -123.559939)
			(xy 13.148755 -123.582773) (xy 13.096253 -123.598262) (xy 13.042076 -123.606088) (xy 13.014706 -123.60656)
			(xy 12.987675 -123.606107) (xy 12.934156 -123.598457) (xy 12.882255 -123.583325) (xy 12.833012 -123.561012)
			(xy 12.787414 -123.531968) (xy 12.746376 -123.496774) (xy 12.728194 -123.476766) (xy 12.72794 -123.476512)
			(xy 12.720488 -123.468874) (xy 12.70101 -123.460199) (xy 12.690348 -123.459748) (xy 12.602718 -123.45924)
			(xy 12.58316 -123.467876) (xy 12.575794 -123.476258) (xy 12.557643 -123.495991) (xy 12.516739 -123.530651)
			(xy 12.471381 -123.559237) (xy 12.422464 -123.581184) (xy 12.370954 -123.596059) (xy 12.317867 -123.603567)
			(xy 12.29106 -123.60402) (xy 12.263809 -123.60353) (xy 12.209861 -123.595774) (xy 12.157567 -123.580419)
			(xy 12.10799 -123.557778) (xy 12.06214 -123.528312) (xy 12.02095 -123.49262) (xy 11.985258 -123.45143)
			(xy 11.955792 -123.40558) (xy 11.933151 -123.356003) (xy 11.917796 -123.303709) (xy 11.91004 -123.249761)
			(xy 5.1054 -123.249761) (xy 5.1054 -124.963428) (xy 8.673082 -124.963428) (xy 8.677153 -124.907806)
			(xy 8.689279 -124.853369) (xy 8.709202 -124.801278) (xy 8.736498 -124.752643) (xy 8.770584 -124.7085)
			(xy 8.810733 -124.669791) (xy 8.856091 -124.63734) (xy 8.905691 -124.611839) (xy 8.958475 -124.593832)
			(xy 9.013318 -124.583702) (xy 9.069052 -124.581665) (xy 9.124489 -124.587765) (xy 9.178446 -124.601871)
			(xy 9.229775 -124.623683) (xy 9.277381 -124.652737) (xy 9.320249 -124.688412) (xy 9.357466 -124.729949)
			(xy 9.388239 -124.776462) (xy 9.411911 -124.826959) (xy 9.427979 -124.880366) (xy 9.436099 -124.935542)
			(xy 9.436608 -124.963428) (xy 9.436099 -124.991314) (xy 9.435493 -124.995432) (xy 10.780774 -124.995432)
			(xy 10.784845 -124.93981) (xy 10.796971 -124.885373) (xy 10.816894 -124.833282) (xy 10.84419 -124.784647)
			(xy 10.878276 -124.740504) (xy 10.918425 -124.701795) (xy 10.963783 -124.669344) (xy 11.013383 -124.643843)
			(xy 11.066167 -124.625836) (xy 11.12101 -124.615706) (xy 11.176744 -124.613669) (xy 11.232181 -124.619769)
			(xy 11.286138 -124.633875) (xy 11.337467 -124.655687) (xy 11.385073 -124.684741) (xy 11.427941 -124.720416)
			(xy 11.465158 -124.761953) (xy 11.495931 -124.808466) (xy 11.519603 -124.858963) (xy 11.535671 -124.91237)
			(xy 11.543791 -124.967546) (xy 11.5443 -124.995432) (xy 11.543791 -125.023318) (xy 11.535671 -125.078494)
			(xy 11.519603 -125.131901) (xy 11.495931 -125.182398) (xy 11.465158 -125.228911) (xy 11.427941 -125.270448)
			(xy 11.385073 -125.306123) (xy 11.337467 -125.335177) (xy 11.286138 -125.356989) (xy 11.232181 -125.371095)
			(xy 11.176744 -125.377195) (xy 11.12101 -125.375158) (xy 11.066167 -125.365028) (xy 11.013383 -125.347021)
			(xy 10.963783 -125.32152) (xy 10.918425 -125.289069) (xy 10.878276 -125.25036) (xy 10.84419 -125.206217)
			(xy 10.816894 -125.157582) (xy 10.796971 -125.105491) (xy 10.784845 -125.051054) (xy 10.780774 -124.995432)
			(xy 9.435493 -124.995432) (xy 9.427979 -125.04649) (xy 9.411911 -125.099897) (xy 9.388239 -125.150394)
			(xy 9.357466 -125.196907) (xy 9.320249 -125.238444) (xy 9.277381 -125.274119) (xy 9.229775 -125.303173)
			(xy 9.178446 -125.324985) (xy 9.124489 -125.339091) (xy 9.069052 -125.345191) (xy 9.013318 -125.343154)
			(xy 8.958475 -125.333024) (xy 8.905691 -125.315017) (xy 8.856091 -125.289516) (xy 8.810733 -125.257065)
			(xy 8.770584 -125.218356) (xy 8.736498 -125.174213) (xy 8.709202 -125.125578) (xy 8.689279 -125.073487)
			(xy 8.677153 -125.01905) (xy 8.673082 -124.963428) (xy 5.1054 -124.963428) (xy 5.1054 -125.403356)
			(xy 15.544292 -125.403356) (xy 15.544793 -125.375987) (xy 15.552603 -125.32181) (xy 15.568084 -125.269307)
			(xy 15.590918 -125.219559) (xy 15.620634 -125.173591) (xy 15.638272 -125.152658) (xy 15.638526 -125.152404)
			(xy 15.64412 -125.145323) (xy 15.650361 -125.128402) (xy 15.650718 -125.119384) (xy 15.650718 -125.052328)
			(xy 15.650344 -125.043313) (xy 15.644108 -125.026396) (xy 15.638526 -125.019308) (xy 15.638272 -125.019308)
			(xy 15.638272 -125.019054) (xy 15.62064 -124.998116) (xy 15.590928 -124.952144) (xy 15.568091 -124.902398)
			(xy 15.552599 -124.849899) (xy 15.544768 -124.795725) (xy 15.544292 -124.768356) (xy 15.544778 -124.741105)
			(xy 15.552534 -124.687157) (xy 15.567889 -124.634862) (xy 15.590531 -124.585285) (xy 15.619997 -124.539435)
			(xy 15.655688 -124.498244) (xy 15.696879 -124.462553) (xy 15.742729 -124.433087) (xy 15.792306 -124.410445)
			(xy 15.844601 -124.39509) (xy 15.898549 -124.387334) (xy 15.953051 -124.387334) (xy 16.006999 -124.39509)
			(xy 16.059294 -124.410445) (xy 16.108871 -124.433087) (xy 16.154721 -124.462553) (xy 16.195912 -124.498244)
			(xy 16.231603 -124.539435) (xy 16.261069 -124.585285) (xy 16.283711 -124.634862) (xy 16.299066 -124.687157)
			(xy 16.306822 -124.741105) (xy 16.307308 -124.768356) (xy 16.306814 -124.795725) (xy 16.299003 -124.849903)
			(xy 16.28352 -124.902406) (xy 16.260685 -124.952153) (xy 16.230966 -124.998121) (xy 16.213328 -125.019054)
			(xy 16.213074 -125.019308) (xy 16.207475 -125.026386) (xy 16.201237 -125.043309) (xy 16.200882 -125.052328)
			(xy 16.200882 -125.119384) (xy 16.201251 -125.1284) (xy 16.207491 -125.145316) (xy 16.213074 -125.152404)
			(xy 16.213328 -125.152404) (xy 16.213328 -125.152658) (xy 16.230965 -125.173591) (xy 16.260676 -125.219564)
			(xy 16.283512 -125.269312) (xy 16.299004 -125.321812) (xy 16.306833 -125.375987) (xy 16.307308 -125.403356)
			(xy 16.306822 -125.430607) (xy 16.299066 -125.484555) (xy 16.283711 -125.53685) (xy 16.261069 -125.586427)
			(xy 16.231603 -125.632277) (xy 16.195912 -125.673468) (xy 16.154721 -125.709159) (xy 16.108871 -125.738625)
			(xy 16.059294 -125.761267) (xy 16.006999 -125.776622) (xy 15.953051 -125.784378) (xy 15.898549 -125.784378)
			(xy 15.844601 -125.776622) (xy 15.792306 -125.761267) (xy 15.742729 -125.738625) (xy 15.696879 -125.709159)
			(xy 15.655688 -125.673468) (xy 15.619997 -125.632277) (xy 15.590531 -125.586427) (xy 15.567889 -125.53685)
			(xy 15.552534 -125.484555) (xy 15.544778 -125.430607) (xy 15.544292 -125.403356) (xy 5.1054 -125.403356)
			(xy 5.1054 -125.979428) (xy 8.673082 -125.979428) (xy 8.677153 -125.923806) (xy 8.689279 -125.869369)
			(xy 8.709202 -125.817278) (xy 8.736498 -125.768643) (xy 8.770584 -125.7245) (xy 8.810733 -125.685791)
			(xy 8.856091 -125.65334) (xy 8.905691 -125.627839) (xy 8.958475 -125.609832) (xy 9.013318 -125.599702)
			(xy 9.069052 -125.597665) (xy 9.124489 -125.603765) (xy 9.178446 -125.617871) (xy 9.229775 -125.639683)
			(xy 9.277381 -125.668737) (xy 9.320249 -125.704412) (xy 9.357466 -125.745949) (xy 9.388239 -125.792462)
			(xy 9.411911 -125.842959) (xy 9.427979 -125.896366) (xy 9.436099 -125.951542) (xy 9.436608 -125.979428)
			(xy 9.436557 -125.982222) (xy 11.113006 -125.982222) (xy 11.117077 -125.9266) (xy 11.129203 -125.872163)
			(xy 11.149126 -125.820072) (xy 11.176422 -125.771437) (xy 11.210508 -125.727294) (xy 11.250657 -125.688585)
			(xy 11.296015 -125.656134) (xy 11.345615 -125.630633) (xy 11.398399 -125.612626) (xy 11.453242 -125.602496)
			(xy 11.508976 -125.600459) (xy 11.564413 -125.606559) (xy 11.61837 -125.620665) (xy 11.669699 -125.642477)
			(xy 11.717305 -125.671531) (xy 11.760173 -125.707206) (xy 11.79739 -125.748743) (xy 11.828163 -125.795256)
			(xy 11.851835 -125.845753) (xy 11.854225 -125.853698) (xy 16.484854 -125.853698) (xy 16.485306 -125.826327)
			(xy 16.493125 -125.772147) (xy 16.508617 -125.719643) (xy 16.531462 -125.669896) (xy 16.561191 -125.623931)
			(xy 16.578834 -125.603) (xy 16.579088 -125.602746) (xy 16.58466 -125.595649) (xy 16.590916 -125.57874)
			(xy 16.59128 -125.569726) (xy 16.59128 -125.50267) (xy 16.590942 -125.493651) (xy 16.584682 -125.476734)
			(xy 16.579088 -125.46965) (xy 16.578834 -125.46965) (xy 16.578834 -125.469396) (xy 16.561185 -125.448472)
			(xy 16.531473 -125.402497) (xy 16.508639 -125.352748) (xy 16.49315 -125.300245) (xy 16.485326 -125.246068)
			(xy 16.484854 -125.218698) (xy 16.48534 -125.191447) (xy 16.493096 -125.137499) (xy 16.508451 -125.085204)
			(xy 16.531093 -125.035627) (xy 16.560559 -124.989777) (xy 16.59625 -124.948586) (xy 16.637441 -124.912895)
			(xy 16.683291 -124.883429) (xy 16.732868 -124.860787) (xy 16.785163 -124.845432) (xy 16.839111 -124.837676)
			(xy 16.893613 -124.837676) (xy 16.947561 -124.845432) (xy 16.999856 -124.860787) (xy 17.049433 -124.883429)
			(xy 17.095283 -124.912895) (xy 17.136474 -124.948586) (xy 17.172165 -124.989777) (xy 17.201631 -125.035627)
			(xy 17.224273 -125.085204) (xy 17.239628 -125.137499) (xy 17.247384 -125.191447) (xy 17.24787 -125.218698)
			(xy 17.24741 -125.246069) (xy 17.239592 -125.300248) (xy 17.224102 -125.352752) (xy 17.201258 -125.402498)
			(xy 17.171532 -125.448465) (xy 17.15389 -125.469396) (xy 17.153636 -125.46965) (xy 17.148057 -125.476741)
			(xy 17.141807 -125.493655) (xy 17.141444 -125.50267) (xy 17.141444 -125.569726) (xy 17.141779 -125.578745)
			(xy 17.148041 -125.595663) (xy 17.153636 -125.602746) (xy 17.15389 -125.602746) (xy 17.15389 -125.603)
			(xy 17.171541 -125.623923) (xy 17.201251 -125.669898) (xy 17.224085 -125.719648) (xy 17.239573 -125.772151)
			(xy 17.247398 -125.826328) (xy 17.24787 -125.853698) (xy 17.247384 -125.880949) (xy 17.239628 -125.934897)
			(xy 17.224273 -125.987192) (xy 17.201631 -126.036769) (xy 17.172165 -126.082619) (xy 17.136474 -126.12381)
			(xy 17.095283 -126.159501) (xy 17.049433 -126.188967) (xy 16.999856 -126.211609) (xy 16.947561 -126.226964)
			(xy 16.893613 -126.23472) (xy 16.839111 -126.23472) (xy 16.785163 -126.226964) (xy 16.732868 -126.211609)
			(xy 16.683291 -126.188967) (xy 16.637441 -126.159501) (xy 16.59625 -126.12381) (xy 16.560559 -126.082619)
			(xy 16.531093 -126.036769) (xy 16.508451 -125.987192) (xy 16.493096 -125.934897) (xy 16.48534 -125.880949)
			(xy 16.484854 -125.853698) (xy 11.854225 -125.853698) (xy 11.867903 -125.89916) (xy 11.876023 -125.954336)
			(xy 11.876532 -125.982222) (xy 11.876023 -126.010108) (xy 11.867903 -126.065284) (xy 11.851835 -126.118691)
			(xy 11.828163 -126.169188) (xy 11.79739 -126.215701) (xy 11.760173 -126.257238) (xy 11.717305 -126.292913)
			(xy 11.669699 -126.321967) (xy 11.61837 -126.343779) (xy 11.564413 -126.357885) (xy 11.508976 -126.363985)
			(xy 11.453242 -126.361948) (xy 11.398399 -126.351818) (xy 11.345615 -126.333811) (xy 11.296015 -126.30831)
			(xy 11.250657 -126.275859) (xy 11.210508 -126.23715) (xy 11.176422 -126.193007) (xy 11.149126 -126.144372)
			(xy 11.129203 -126.092281) (xy 11.117077 -126.037844) (xy 11.113006 -125.982222) (xy 9.436557 -125.982222)
			(xy 9.436099 -126.007314) (xy 9.427979 -126.06249) (xy 9.411911 -126.115897) (xy 9.388239 -126.166394)
			(xy 9.357466 -126.212907) (xy 9.320249 -126.254444) (xy 9.277381 -126.290119) (xy 9.229775 -126.319173)
			(xy 9.178446 -126.340985) (xy 9.124489 -126.355091) (xy 9.069052 -126.361191) (xy 9.013318 -126.359154)
			(xy 8.958475 -126.349024) (xy 8.905691 -126.331017) (xy 8.856091 -126.305516) (xy 8.810733 -126.273065)
			(xy 8.770584 -126.234356) (xy 8.736498 -126.190213) (xy 8.709202 -126.141578) (xy 8.689279 -126.089487)
			(xy 8.677153 -126.03505) (xy 8.673082 -125.979428) (xy 5.1054 -125.979428) (xy 5.1054 -126.530354)
			(xy 17.769586 -126.530354) (xy 17.770111 -126.501437) (xy 17.778834 -126.444265) (xy 17.796088 -126.389065)
			(xy 17.821479 -126.337102) (xy 17.854423 -126.289568) (xy 17.894166 -126.247553) (xy 17.916652 -126.229364)
			(xy 17.925474 -126.221772) (xy 17.935648 -126.200859) (xy 17.93621 -126.189232) (xy 17.93621 -126.109476)
			(xy 17.935667 -126.097845) (xy 17.92548 -126.076936) (xy 17.916652 -126.069344) (xy 17.89418 -126.05114)
			(xy 17.854446 -126.009122) (xy 17.821507 -125.961589) (xy 17.796117 -125.90963) (xy 17.778858 -125.854436)
			(xy 17.770124 -125.797269) (xy 17.769586 -125.768354) (xy 17.770035 -125.741102) (xy 17.777798 -125.687153)
			(xy 17.793158 -125.634858) (xy 17.815804 -125.585281) (xy 17.845275 -125.539431) (xy 17.88097 -125.498242)
			(xy 17.922163 -125.462551) (xy 17.968016 -125.433085) (xy 18.017596 -125.410444) (xy 18.069892 -125.395089)
			(xy 18.123842 -125.387332) (xy 18.151094 -125.386846) (xy 18.178465 -125.387304) (xy 18.232645 -125.395122)
			(xy 18.285148 -125.410613) (xy 18.334895 -125.433456) (xy 18.380861 -125.463183) (xy 18.401792 -125.480826)
			(xy 18.402046 -125.48108) (xy 18.409137 -125.486659) (xy 18.426051 -125.492908) (xy 18.435066 -125.493272)
			(xy 18.502122 -125.493272) (xy 18.511141 -125.492932) (xy 18.528058 -125.486673) (xy 18.535142 -125.48108)
			(xy 18.535142 -125.480826) (xy 18.535396 -125.480826) (xy 18.556322 -125.463179) (xy 18.602296 -125.433468)
			(xy 18.652045 -125.410633) (xy 18.704547 -125.395144) (xy 18.758724 -125.387318) (xy 18.786094 -125.386846)
			(xy 18.813343 -125.387383) (xy 18.867287 -125.395138) (xy 18.919577 -125.41049) (xy 18.969152 -125.433127)
			(xy 19.015 -125.462588) (xy 19.056189 -125.498274) (xy 19.091881 -125.539458) (xy 19.121348 -125.585303)
			(xy 19.143992 -125.634874) (xy 19.159351 -125.687163) (xy 19.167113 -125.741105) (xy 19.167602 -125.768354)
			(xy 19.16705 -125.79727) (xy 19.158328 -125.854439) (xy 19.141076 -125.909637) (xy 19.115691 -125.961599)
			(xy 19.082754 -126.009134) (xy 19.043019 -126.051153) (xy 19.020536 -126.069344) (xy 19.011708 -126.076931)
			(xy 19.001538 -126.097847) (xy 19.000978 -126.109476) (xy 19.000978 -126.189232) (xy 19.001521 -126.200863)
			(xy 19.011708 -126.221772) (xy 19.020536 -126.229364) (xy 19.04301 -126.247566) (xy 19.082744 -126.289585)
			(xy 19.115683 -126.337118) (xy 19.141073 -126.389077) (xy 19.158332 -126.444272) (xy 19.167065 -126.501439)
			(xy 19.167602 -126.530354) (xy 19.167102 -126.557606) (xy 19.159351 -126.611556) (xy 19.147251 -126.652782)
			(xy 19.438874 -126.652782) (xy 19.439311 -126.625411) (xy 19.447133 -126.571229) (xy 19.462628 -126.518725)
			(xy 19.485477 -126.468979) (xy 19.515209 -126.423014) (xy 19.532854 -126.402084) (xy 19.533108 -126.40183)
			(xy 19.538689 -126.39474) (xy 19.544939 -126.377826) (xy 19.5453 -126.36881) (xy 19.5453 -126.301754)
			(xy 19.544917 -126.29274) (xy 19.538687 -126.275823) (xy 19.533108 -126.268734) (xy 19.532854 -126.268734)
			(xy 19.532854 -126.26848) (xy 19.515195 -126.247562) (xy 19.485468 -126.201592) (xy 19.462622 -126.151844)
			(xy 19.447126 -126.099339) (xy 19.439299 -126.045158) (xy 19.439301 -125.990415) (xy 19.447132 -125.936234)
			(xy 19.462632 -125.883731) (xy 19.485481 -125.833984) (xy 19.515211 -125.788016) (xy 19.532854 -125.767084)
			(xy 19.533108 -125.76683) (xy 19.538689 -125.75974) (xy 19.544939 -125.742826) (xy 19.5453 -125.73381)
			(xy 19.5453 -125.666754) (xy 19.544917 -125.65774) (xy 19.538687 -125.640823) (xy 19.533108 -125.633734)
			(xy 19.532854 -125.633734) (xy 19.532854 -125.63348) (xy 19.515195 -125.612562) (xy 19.485468 -125.566592)
			(xy 19.462622 -125.516844) (xy 19.447126 -125.464339) (xy 19.439299 -125.410158) (xy 19.439301 -125.355415)
			(xy 19.447132 -125.301234) (xy 19.462632 -125.248731) (xy 19.485481 -125.198984) (xy 19.515211 -125.153016)
			(xy 19.532854 -125.132084) (xy 19.533108 -125.13183) (xy 19.538689 -125.12474) (xy 19.544939 -125.107826)
			(xy 19.5453 -125.09881) (xy 19.5453 -125.031754) (xy 19.544917 -125.02274) (xy 19.538687 -125.005823)
			(xy 19.533108 -124.998734) (xy 19.532854 -124.998734) (xy 19.532854 -124.99848) (xy 19.515247 -124.977522)
			(xy 19.485529 -124.931557) (xy 19.462686 -124.881816) (xy 19.447187 -124.829321) (xy 19.439352 -124.77515)
			(xy 19.438874 -124.747782) (xy 19.43936 -124.720531) (xy 19.447116 -124.666583) (xy 19.462471 -124.614288)
			(xy 19.485113 -124.564711) (xy 19.514579 -124.518861) (xy 19.55027 -124.47767) (xy 19.591461 -124.441979)
			(xy 19.637311 -124.412513) (xy 19.686888 -124.389871) (xy 19.739183 -124.374516) (xy 19.793131 -124.36676)
			(xy 19.847633 -124.36676) (xy 19.901581 -124.374516) (xy 19.953876 -124.389871) (xy 20.003453 -124.412513)
			(xy 20.049303 -124.441979) (xy 20.090494 -124.47767) (xy 20.126185 -124.518861) (xy 20.155651 -124.564711)
			(xy 20.178293 -124.614288) (xy 20.193648 -124.666583) (xy 20.201404 -124.720531) (xy 20.20189 -124.747782)
			(xy 20.201416 -124.775152) (xy 20.1936 -124.829331) (xy 20.178113 -124.881834) (xy 20.155273 -124.931581)
			(xy 20.12555 -124.977548) (xy 20.10791 -124.99848) (xy 20.107656 -124.998734) (xy 20.102086 -125.005831)
			(xy 20.09583 -125.02274) (xy 20.095464 -125.031754) (xy 20.095464 -125.09881) (xy 20.095824 -125.107826)
			(xy 20.10207 -125.124743) (xy 20.107656 -125.13183) (xy 20.10791 -125.13183) (xy 20.10791 -125.132084)
			(xy 20.125532 -125.153032) (xy 20.155254 -125.198998) (xy 20.178098 -125.248742) (xy 20.193594 -125.301241)
			(xy 20.201424 -125.355417) (xy 20.201426 -125.410156) (xy 20.1936 -125.464332) (xy 20.178108 -125.516833)
			(xy 20.155267 -125.566578) (xy 20.125548 -125.612547) (xy 20.10791 -125.63348) (xy 20.107656 -125.633734)
			(xy 20.102086 -125.640831) (xy 20.09583 -125.65774) (xy 20.095464 -125.666754) (xy 20.095464 -125.73381)
			(xy 20.095824 -125.742826) (xy 20.10207 -125.759743) (xy 20.107656 -125.76683) (xy 20.10791 -125.76683)
			(xy 20.10791 -125.767084) (xy 20.125532 -125.788032) (xy 20.155254 -125.833998) (xy 20.178098 -125.883742)
			(xy 20.193594 -125.936241) (xy 20.201424 -125.990417) (xy 20.201426 -126.045156) (xy 20.1936 -126.099332)
			(xy 20.178108 -126.151833) (xy 20.155267 -126.201578) (xy 20.125548 -126.247547) (xy 20.10791 -126.26848)
			(xy 20.107656 -126.268734) (xy 20.102086 -126.275831) (xy 20.09583 -126.29274) (xy 20.095464 -126.301754)
			(xy 20.095464 -126.36881) (xy 20.095824 -126.377826) (xy 20.10207 -126.394743) (xy 20.107656 -126.40183)
			(xy 20.10791 -126.40183) (xy 20.10791 -126.402084) (xy 20.125557 -126.42301) (xy 20.155267 -126.468985)
			(xy 20.178101 -126.518734) (xy 20.193591 -126.571236) (xy 20.201417 -126.625412) (xy 20.20189 -126.652782)
			(xy 20.201404 -126.680033) (xy 20.193648 -126.733981) (xy 20.178293 -126.786276) (xy 20.155651 -126.835853)
			(xy 20.126185 -126.881703) (xy 20.090494 -126.922894) (xy 20.049303 -126.958585) (xy 20.003453 -126.988051)
			(xy 19.953876 -127.010693) (xy 19.901581 -127.026048) (xy 19.847633 -127.033804) (xy 19.793131 -127.033804)
			(xy 19.739183 -127.026048) (xy 19.686888 -127.010693) (xy 19.637311 -126.988051) (xy 19.591461 -126.958585)
			(xy 19.55027 -126.922894) (xy 19.514579 -126.881703) (xy 19.485113 -126.835853) (xy 19.462471 -126.786276)
			(xy 19.447116 -126.733981) (xy 19.43936 -126.680033) (xy 19.438874 -126.652782) (xy 19.147251 -126.652782)
			(xy 19.144001 -126.663853) (xy 19.121363 -126.713434) (xy 19.091899 -126.759287) (xy 19.056209 -126.800481)
			(xy 19.01502 -126.836175) (xy 18.969169 -126.865644) (xy 18.919591 -126.888287) (xy 18.867295 -126.903643)
			(xy 18.813346 -126.911399) (xy 18.786094 -126.911862) (xy 18.758723 -126.911409) (xy 18.704543 -126.903589)
			(xy 18.65204 -126.888098) (xy 18.602293 -126.865253) (xy 18.556327 -126.835525) (xy 18.535396 -126.817882)
			(xy 18.535142 -126.817628) (xy 18.528054 -126.812044) (xy 18.511138 -126.805798) (xy 18.502122 -126.805436)
			(xy 18.435066 -126.805436) (xy 18.426047 -126.805769) (xy 18.409129 -126.812032) (xy 18.402046 -126.817628)
			(xy 18.402046 -126.817882) (xy 18.401792 -126.817882) (xy 18.380871 -126.835536) (xy 18.334896 -126.865246)
			(xy 18.285145 -126.888079) (xy 18.232642 -126.903567) (xy 18.178464 -126.911391) (xy 18.151094 -126.911862)
			(xy 18.123839 -126.91145) (xy 18.069884 -126.903691) (xy 18.017582 -126.888332) (xy 17.967999 -126.865685)
			(xy 17.922144 -126.836213) (xy 17.88095 -126.800513) (xy 17.845256 -126.759315) (xy 17.81579 -126.713455)
			(xy 17.79315 -126.663869) (xy 17.777798 -126.611565) (xy 17.770046 -126.557609) (xy 17.769586 -126.530354)
			(xy 5.1054 -126.530354) (xy 5.1054 -127.051308) (xy 10.744198 -127.051308) (xy 10.748269 -126.995686)
			(xy 10.760395 -126.941249) (xy 10.780318 -126.889158) (xy 10.807614 -126.840523) (xy 10.8417 -126.79638)
			(xy 10.881849 -126.757671) (xy 10.927207 -126.72522) (xy 10.976807 -126.699719) (xy 11.029591 -126.681712)
			(xy 11.084434 -126.671582) (xy 11.140168 -126.669545) (xy 11.195605 -126.675645) (xy 11.249562 -126.689751)
			(xy 11.300891 -126.711563) (xy 11.348497 -126.740617) (xy 11.391365 -126.776292) (xy 11.428582 -126.817829)
			(xy 11.459355 -126.864342) (xy 11.483027 -126.914839) (xy 11.499095 -126.968246) (xy 11.507215 -127.023422)
			(xy 11.507724 -127.051308) (xy 11.507215 -127.079194) (xy 11.499095 -127.13437) (xy 11.483027 -127.187777)
			(xy 11.459355 -127.238274) (xy 11.428582 -127.284787) (xy 11.391365 -127.326324) (xy 11.348497 -127.361999)
			(xy 11.300891 -127.391053) (xy 11.249562 -127.412865) (xy 11.195605 -127.426971) (xy 11.140168 -127.433071)
			(xy 11.084434 -127.431034) (xy 11.029591 -127.420904) (xy 10.976807 -127.402897) (xy 10.927207 -127.377396)
			(xy 10.881849 -127.344945) (xy 10.8417 -127.306236) (xy 10.807614 -127.262093) (xy 10.780318 -127.213458)
			(xy 10.760395 -127.161367) (xy 10.748269 -127.10693) (xy 10.744198 -127.051308) (xy 5.1054 -127.051308)
			(xy 5.1054 -128.252803) (xy 9.728405 -128.252803) (xy 9.728405 -128.198297) (xy 9.736162 -128.144346)
			(xy 9.751519 -128.092048) (xy 9.774161 -128.042467) (xy 9.80363 -127.996614) (xy 9.839324 -127.955421)
			(xy 9.880517 -127.919727) (xy 9.926371 -127.89026) (xy 9.975951 -127.867617) (xy 10.02825 -127.852262)
			(xy 10.082201 -127.844505) (xy 10.109454 -127.844042) (xy 10.136824 -127.844525) (xy 10.191003 -127.852337)
			(xy 10.243506 -127.867822) (xy 10.293253 -127.89066) (xy 10.33922 -127.920382) (xy 10.360152 -127.938022)
			(xy 10.360406 -127.938276) (xy 10.36748 -127.94388) (xy 10.384407 -127.950114) (xy 10.393426 -127.950468)
			(xy 10.460482 -127.950468) (xy 10.469499 -127.950109) (xy 10.486416 -127.943863) (xy 10.493502 -127.938276)
			(xy 10.493502 -127.938022) (xy 10.493756 -127.938022) (xy 10.514689 -127.920381) (xy 10.560657 -127.890657)
			(xy 10.610403 -127.867811) (xy 10.662905 -127.852315) (xy 10.717083 -127.844486) (xy 10.771825 -127.844486)
			(xy 10.826003 -127.852315) (xy 10.878505 -127.867811) (xy 10.928251 -127.890657) (xy 10.974219 -127.920381)
			(xy 10.995152 -127.938022) (xy 10.995406 -127.938276) (xy 11.00248 -127.94388) (xy 11.019407 -127.950114)
			(xy 11.028426 -127.950468) (xy 11.095482 -127.950468) (xy 11.104499 -127.950109) (xy 11.121416 -127.943863)
			(xy 11.128502 -127.938276) (xy 11.128502 -127.938022) (xy 11.128756 -127.938022) (xy 11.149697 -127.920393)
			(xy 11.195667 -127.890679) (xy 11.245412 -127.867841) (xy 11.297911 -127.852348) (xy 11.352085 -127.844517)
			(xy 11.379454 -127.844042) (xy 11.406705 -127.844528) (xy 11.460652 -127.852285) (xy 11.512947 -127.867641)
			(xy 11.562523 -127.890282) (xy 11.608373 -127.919748) (xy 11.649563 -127.95544) (xy 11.685254 -127.99663)
			(xy 11.71472 -128.04248) (xy 11.737361 -128.092057) (xy 11.752716 -128.144352) (xy 11.760472 -128.198299)
			(xy 11.760472 -128.252801) (xy 11.752716 -128.306748) (xy 11.737361 -128.359043) (xy 11.71472 -128.40862)
			(xy 11.685254 -128.45447) (xy 11.649563 -128.49566) (xy 11.608373 -128.531352) (xy 11.562523 -128.560818)
			(xy 11.512947 -128.583459) (xy 11.460652 -128.598815) (xy 11.406705 -128.606572) (xy 11.379454 -128.607058)
			(xy 11.352084 -128.606571) (xy 11.297906 -128.598759) (xy 11.245403 -128.583276) (xy 11.195655 -128.560439)
			(xy 11.149688 -128.530718) (xy 11.128756 -128.513078) (xy 11.128502 -128.512824) (xy 11.121425 -128.507223)
			(xy 11.104501 -128.500987) (xy 11.095482 -128.500632) (xy 11.028426 -128.500632) (xy 11.01941 -128.500995)
			(xy 11.002492 -128.507238) (xy 10.995406 -128.512824) (xy 10.995152 -128.513078) (xy 10.974219 -128.530719)
			(xy 10.928251 -128.560443) (xy 10.878505 -128.583289) (xy 10.826003 -128.598785) (xy 10.771825 -128.606614)
			(xy 10.717083 -128.606614) (xy 10.662905 -128.598785) (xy 10.610403 -128.583289) (xy 10.560657 -128.560443)
			(xy 10.514689 -128.530719) (xy 10.493756 -128.513078) (xy 10.493502 -128.512824) (xy 10.486425 -128.507223)
			(xy 10.469501 -128.500987) (xy 10.460482 -128.500632) (xy 10.393426 -128.500632) (xy 10.38441 -128.500995)
			(xy 10.367492 -128.507238) (xy 10.360406 -128.512824) (xy 10.360406 -128.513078) (xy 10.360152 -128.513078)
			(xy 10.339208 -128.530703) (xy 10.293239 -128.560418) (xy 10.243495 -128.583257) (xy 10.190996 -128.598751)
			(xy 10.136822 -128.606582) (xy 10.109454 -128.607058) (xy 10.082201 -128.606595) (xy 10.02825 -128.598838)
			(xy 9.975951 -128.583483) (xy 9.926371 -128.56084) (xy 9.880517 -128.531373) (xy 9.839324 -128.495679)
			(xy 9.80363 -128.454486) (xy 9.774161 -128.408633) (xy 9.751519 -128.359052) (xy 9.736162 -128.306754)
			(xy 9.728405 -128.252803) (xy 5.1054 -128.252803) (xy 5.1054 -131.447101) (xy 9.713452 -131.447101)
			(xy 9.713452 -131.392599) (xy 9.721208 -131.338652) (xy 9.736563 -131.286358) (xy 9.759204 -131.236782)
			(xy 9.78867 -131.190932) (xy 9.824361 -131.149742) (xy 9.86555 -131.114051) (xy 9.9114 -131.084585)
			(xy 9.960976 -131.061944) (xy 10.01327 -131.046589) (xy 10.067217 -131.038832) (xy 10.094468 -131.038346)
			(xy 10.121838 -131.03882) (xy 10.176017 -131.046634) (xy 10.228521 -131.062121) (xy 10.278268 -131.084961)
			(xy 10.324235 -131.114685) (xy 10.345166 -131.132326) (xy 10.34542 -131.13258) (xy 10.35249 -131.13819)
			(xy 10.36942 -131.144421) (xy 10.37844 -131.144772) (xy 10.445496 -131.144772) (xy 10.454513 -131.144419)
			(xy 10.471431 -131.13817) (xy 10.478516 -131.13258) (xy 10.478516 -131.132326) (xy 10.47877 -131.132326)
			(xy 10.499703 -131.114685) (xy 10.545671 -131.084961) (xy 10.595417 -131.062115) (xy 10.647919 -131.046619)
			(xy 10.702097 -131.03879) (xy 10.756839 -131.03879) (xy 10.811017 -131.046619) (xy 10.863519 -131.062115)
			(xy 10.913265 -131.084961) (xy 10.959233 -131.114685) (xy 10.980166 -131.132326) (xy 10.98042 -131.13258)
			(xy 10.98749 -131.13819) (xy 11.00442 -131.144421) (xy 11.01344 -131.144772) (xy 11.080496 -131.144772)
			(xy 11.089513 -131.144419) (xy 11.106431 -131.13817) (xy 11.113516 -131.13258) (xy 11.113516 -131.132326)
			(xy 11.11377 -131.132326) (xy 11.134706 -131.114692) (xy 11.180677 -131.084978) (xy 11.230424 -131.062141)
			(xy 11.282924 -131.046649) (xy 11.337099 -131.03882) (xy 11.364468 -131.038346) (xy 11.391721 -131.038801)
			(xy 11.445673 -131.046558) (xy 11.497972 -131.061914) (xy 11.547552 -131.084557) (xy 11.593406 -131.114025)
			(xy 11.6346 -131.149719) (xy 11.670294 -131.190912) (xy 11.699762 -131.236766) (xy 11.722405 -131.286347)
			(xy 11.737762 -131.338645) (xy 11.745519 -131.392597) (xy 11.745519 -131.447103) (xy 11.737762 -131.501055)
			(xy 11.722405 -131.553353) (xy 11.699762 -131.602934) (xy 11.670294 -131.648788) (xy 11.6346 -131.689981)
			(xy 11.593406 -131.725675) (xy 11.547552 -131.755143) (xy 11.497972 -131.777786) (xy 11.445673 -131.793142)
			(xy 11.391721 -131.800899) (xy 11.364468 -131.801362) (xy 11.337097 -131.800924) (xy 11.282916 -131.793101)
			(xy 11.230412 -131.777606) (xy 11.180666 -131.754757) (xy 11.1347 -131.725026) (xy 11.11377 -131.707382)
			(xy 11.113516 -131.707128) (xy 11.106435 -131.701534) (xy 11.089514 -131.695294) (xy 11.080496 -131.694936)
			(xy 11.01344 -131.694936) (xy 11.004424 -131.695304) (xy 10.987507 -131.701543) (xy 10.98042 -131.707128)
			(xy 10.980166 -131.707382) (xy 10.959233 -131.725023) (xy 10.913265 -131.754747) (xy 10.863519 -131.777593)
			(xy 10.811017 -131.793089) (xy 10.756839 -131.800918) (xy 10.702097 -131.800918) (xy 10.647919 -131.793089)
			(xy 10.595417 -131.777593) (xy 10.545671 -131.754747) (xy 10.499703 -131.725023) (xy 10.47877 -131.707382)
			(xy 10.478516 -131.707128) (xy 10.471435 -131.701534) (xy 10.454514 -131.695294) (xy 10.445496 -131.694936)
			(xy 10.37844 -131.694936) (xy 10.369424 -131.695304) (xy 10.352507 -131.701543) (xy 10.34542 -131.707128)
			(xy 10.34542 -131.707382) (xy 10.345166 -131.707382) (xy 10.324218 -131.725001) (xy 10.27825 -131.754716)
			(xy 10.228506 -131.777556) (xy 10.176009 -131.793052) (xy 10.121836 -131.800885) (xy 10.094468 -131.801362)
			(xy 10.067217 -131.800868) (xy 10.01327 -131.793111) (xy 9.960976 -131.777756) (xy 9.9114 -131.755115)
			(xy 9.86555 -131.725649) (xy 9.824361 -131.689958) (xy 9.78867 -131.648768) (xy 9.759204 -131.602918)
			(xy 9.736563 -131.553342) (xy 9.721208 -131.501048) (xy 9.713452 -131.447101) (xy 5.1054 -131.447101)
			(xy 5.1054 -133.443726) (xy 11.122914 -133.443726) (xy 11.123394 -133.417412) (xy 11.130626 -133.365284)
			(xy 11.144942 -133.314642) (xy 11.166072 -133.266442) (xy 11.193616 -133.221599) (xy 11.227053 -133.180959)
			(xy 11.246104 -133.162802) (xy 11.253507 -133.155282) (xy 11.26203 -133.136001) (xy 11.262614 -133.125464)
			(xy 11.262614 -133.050788) (xy 11.262101 -133.040237) (xy 11.253554 -133.020942) (xy 11.246104 -133.01345)
			(xy 11.227032 -132.995311) (xy 11.193576 -132.954678) (xy 11.166019 -132.909834) (xy 11.144884 -132.86163)
			(xy 11.13057 -132.81098) (xy 11.12335 -132.758843) (xy 11.122914 -132.732526) (xy 11.1234 -132.705275)
			(xy 11.131156 -132.651327) (xy 11.146511 -132.599032) (xy 11.169153 -132.549455) (xy 11.198619 -132.503605)
			(xy 11.23431 -132.462414) (xy 11.275501 -132.426723) (xy 11.321351 -132.397257) (xy 11.370928 -132.374615)
			(xy 11.423223 -132.35926) (xy 11.477171 -132.351504) (xy 11.531673 -132.351504) (xy 11.585621 -132.35926)
			(xy 11.637916 -132.374615) (xy 11.687493 -132.397257) (xy 11.733343 -132.426723) (xy 11.774534 -132.462414)
			(xy 11.810225 -132.503605) (xy 11.839691 -132.549455) (xy 11.862333 -132.599032) (xy 11.877688 -132.651327)
			(xy 11.885444 -132.705275) (xy 11.88593 -132.732526) (xy 11.88547 -132.75884) (xy 11.878233 -132.810969)
			(xy 11.863911 -132.861611) (xy 11.842777 -132.90981) (xy 11.81523 -132.954653) (xy 11.781791 -132.995293)
			(xy 11.76274 -133.01345) (xy 11.75532 -133.020957) (xy 11.746805 -133.040248) (xy 11.74623 -133.050788)
			(xy 11.74623 -133.125464) (xy 11.746756 -133.136014) (xy 11.755293 -133.15531) (xy 11.76274 -133.162802)
			(xy 11.781797 -133.180956) (xy 11.815253 -133.221587) (xy 11.84281 -133.266428) (xy 11.863948 -133.314629)
			(xy 11.878266 -133.365276) (xy 11.885491 -133.41741) (xy 11.88593 -133.443726) (xy 11.885444 -133.470977)
			(xy 11.877688 -133.524925) (xy 11.862333 -133.57722) (xy 11.839691 -133.626797) (xy 11.810225 -133.672647)
			(xy 11.774534 -133.713838) (xy 11.733343 -133.749529) (xy 11.687493 -133.778995) (xy 11.637916 -133.801637)
			(xy 11.585621 -133.816992) (xy 11.531673 -133.824748) (xy 11.477171 -133.824748) (xy 11.423223 -133.816992)
			(xy 11.370928 -133.801637) (xy 11.321351 -133.778995) (xy 11.275501 -133.749529) (xy 11.23431 -133.713838)
			(xy 11.198619 -133.672647) (xy 11.169153 -133.626797) (xy 11.146511 -133.57722) (xy 11.131156 -133.524925)
			(xy 11.1234 -133.470977) (xy 11.122914 -133.443726) (xy 5.1054 -133.443726) (xy 5.1054 -134.042404)
			(xy 6.176008 -134.042404) (xy 6.180079 -133.986782) (xy 6.192205 -133.932345) (xy 6.212128 -133.880254)
			(xy 6.239424 -133.831619) (xy 6.27351 -133.787476) (xy 6.313659 -133.748767) (xy 6.359017 -133.716316)
			(xy 6.408617 -133.690815) (xy 6.461401 -133.672808) (xy 6.516244 -133.662678) (xy 6.571978 -133.660641)
			(xy 6.627415 -133.666741) (xy 6.681372 -133.680847) (xy 6.732701 -133.702659) (xy 6.780307 -133.731713)
			(xy 6.823175 -133.767388) (xy 6.860392 -133.808925) (xy 6.891165 -133.855438) (xy 6.914837 -133.905935)
			(xy 6.930905 -133.959342) (xy 6.939025 -134.014518) (xy 6.939534 -134.042404) (xy 6.939025 -134.07029)
			(xy 6.930905 -134.125466) (xy 6.914837 -134.178873) (xy 6.891165 -134.22937) (xy 6.860392 -134.275883)
			(xy 6.823175 -134.31742) (xy 6.780307 -134.353095) (xy 6.732701 -134.382149) (xy 6.681372 -134.403961)
			(xy 6.627415 -134.418067) (xy 6.571978 -134.424167) (xy 6.516244 -134.42213) (xy 6.461401 -134.412)
			(xy 6.408617 -134.393993) (xy 6.359017 -134.368492) (xy 6.313659 -134.336041) (xy 6.27351 -134.297332)
			(xy 6.239424 -134.253189) (xy 6.212128 -134.204554) (xy 6.192205 -134.152463) (xy 6.180079 -134.098026)
			(xy 6.176008 -134.042404) (xy 5.1054 -134.042404) (xy 5.1054 -135.142043) (xy 9.361887 -135.142043)
			(xy 9.361887 -135.087537) (xy 9.369644 -135.033586) (xy 9.385 -134.981289) (xy 9.407643 -134.931709)
			(xy 9.437111 -134.885856) (xy 9.472805 -134.844663) (xy 9.513997 -134.80897) (xy 9.55985 -134.779502)
			(xy 9.609431 -134.75686) (xy 9.661728 -134.741504) (xy 9.715679 -134.733747) (xy 9.742932 -134.733284)
			(xy 9.771849 -134.733819) (xy 9.82902 -134.74254) (xy 9.88422 -134.759793) (xy 9.936183 -134.785181)
			(xy 9.983717 -134.818123) (xy 10.025733 -134.857864) (xy 10.043922 -134.88035) (xy 10.051733 -134.889318)
			(xy 10.073184 -134.899517) (xy 10.08507 -134.899908) (xy 10.178542 -134.897876) (xy 10.199878 -134.8867)
			(xy 10.206736 -134.876794) (xy 10.22216 -134.855904) (xy 10.257734 -134.818076) (xy 10.298108 -134.785422)
			(xy 10.342538 -134.758545) (xy 10.390203 -134.737942) (xy 10.440221 -134.723993) (xy 10.491669 -134.716955)
			(xy 10.517632 -134.71652) (xy 10.545003 -134.716962) (xy 10.599183 -134.724785) (xy 10.651687 -134.74028)
			(xy 10.701433 -134.763127) (xy 10.747399 -134.792856) (xy 10.76833 -134.8105) (xy 10.768584 -134.810754)
			(xy 10.775666 -134.816346) (xy 10.792587 -134.822588) (xy 10.801604 -134.822946) (xy 10.86866 -134.822946)
			(xy 10.877676 -134.822582) (xy 10.894594 -134.81634) (xy 10.90168 -134.810754) (xy 10.90168 -134.8105)
			(xy 10.901934 -134.8105) (xy 10.922867 -134.792859) (xy 10.968835 -134.763135) (xy 11.018581 -134.740289)
			(xy 11.071083 -134.724793) (xy 11.125261 -134.716964) (xy 11.180003 -134.716964) (xy 11.234181 -134.724793)
			(xy 11.286683 -134.740289) (xy 11.336429 -134.763135) (xy 11.382397 -134.792859) (xy 11.40333 -134.8105)
			(xy 11.403584 -134.810754) (xy 11.410666 -134.816346) (xy 11.427587 -134.822588) (xy 11.436604 -134.822946)
			(xy 11.50366 -134.822946) (xy 11.512676 -134.822582) (xy 11.529594 -134.81634) (xy 11.53668 -134.810754)
			(xy 11.537188 -134.8105) (xy 11.549922 -134.799555) (xy 11.577013 -134.779714) (xy 11.59129 -134.770876)
			(xy 11.60018 -134.765542) (xy 11.612372 -134.748524) (xy 11.632692 -134.655306) (xy 11.628374 -134.634732)
			(xy 11.622532 -134.626096) (xy 11.606532 -134.602032) (xy 11.581188 -134.550101) (xy 11.563962 -134.494943)
			(xy 11.555248 -134.437819) (xy 11.554714 -134.408926) (xy 11.5552 -134.381675) (xy 11.562956 -134.327727)
			(xy 11.578311 -134.275432) (xy 11.600953 -134.225855) (xy 11.630419 -134.180005) (xy 11.66611 -134.138814)
			(xy 11.707301 -134.103123) (xy 11.753151 -134.073657) (xy 11.802728 -134.051015) (xy 11.855023 -134.03566)
			(xy 11.908971 -134.027904) (xy 11.963473 -134.027904) (xy 12.017421 -134.03566) (xy 12.069716 -134.051015)
			(xy 12.119293 -134.073657) (xy 12.165143 -134.103123) (xy 12.206334 -134.138814) (xy 12.242025 -134.180005)
			(xy 12.271491 -134.225855) (xy 12.294133 -134.275432) (xy 12.309488 -134.327727) (xy 12.317244 -134.381675)
			(xy 12.31773 -134.408926) (xy 12.31725 -134.437018) (xy 12.309019 -134.492596) (xy 12.292725 -134.546365)
			(xy 12.26872 -134.597162) (xy 12.237523 -134.643889) (xy 12.19981 -134.685533) (xy 12.156395 -134.721196)
			(xy 12.132564 -134.736078) (xy 12.123674 -134.741412) (xy 12.111482 -134.75843) (xy 12.091162 -134.851648)
			(xy 12.09548 -134.872222) (xy 12.101322 -134.880858) (xy 12.117309 -134.90493) (xy 12.142654 -134.956859)
			(xy 12.159883 -135.012014) (xy 12.168603 -135.069136) (xy 12.16914 -135.098028) (xy 12.168648 -135.125278)
			(xy 12.160889 -135.179224) (xy 12.145532 -135.231517) (xy 12.12289 -135.281092) (xy 12.093423 -135.326941)
			(xy 12.057733 -135.36813) (xy 12.016544 -135.403821) (xy 11.970696 -135.433288) (xy 11.921121 -135.45593)
			(xy 11.868828 -135.471288) (xy 11.814882 -135.479048) (xy 11.787632 -135.479536) (xy 11.760262 -135.479067)
			(xy 11.706082 -135.471252) (xy 11.653578 -135.455765) (xy 11.603831 -135.432923) (xy 11.557865 -135.403198)
			(xy 11.536934 -135.385556) (xy 11.53668 -135.385302) (xy 11.529603 -135.379701) (xy 11.512679 -135.373463)
			(xy 11.50366 -135.37311) (xy 11.436604 -135.37311) (xy 11.427587 -135.373467) (xy 11.41067 -135.379714)
			(xy 11.403584 -135.385302) (xy 11.403584 -135.385556) (xy 11.40333 -135.385556) (xy 11.382397 -135.403197)
			(xy 11.336429 -135.432921) (xy 11.286683 -135.455767) (xy 11.234181 -135.471263) (xy 11.180003 -135.479092)
			(xy 11.125261 -135.479092) (xy 11.071083 -135.471263) (xy 11.018581 -135.455767) (xy 10.968835 -135.432921)
			(xy 10.922867 -135.403197) (xy 10.901934 -135.385556) (xy 10.90168 -135.385302) (xy 10.894603 -135.379701)
			(xy 10.877679 -135.373463) (xy 10.86866 -135.37311) (xy 10.801604 -135.37311) (xy 10.792587 -135.373467)
			(xy 10.77567 -135.379714) (xy 10.768584 -135.385302) (xy 10.768584 -135.385556) (xy 10.76833 -135.385556)
			(xy 10.747392 -135.403188) (xy 10.701421 -135.432902) (xy 10.651676 -135.45574) (xy 10.599176 -135.471233)
			(xy 10.545001 -135.479062) (xy 10.517632 -135.479536) (xy 10.488715 -135.479019) (xy 10.431542 -135.470293)
			(xy 10.376342 -135.453037) (xy 10.32438 -135.427645) (xy 10.276847 -135.3947) (xy 10.234831 -135.354957)
			(xy 10.216642 -135.33247) (xy 10.208844 -135.323489) (xy 10.187383 -135.313296) (xy 10.175494 -135.312912)
			(xy 10.082022 -135.314944) (xy 10.060686 -135.32612) (xy 10.053828 -135.336026) (xy 10.038432 -135.356938)
			(xy 10.002853 -135.394764) (xy 9.962473 -135.427415) (xy 9.918038 -135.454289) (xy 9.87037 -135.474889)
			(xy 9.820348 -135.488834) (xy 9.768897 -135.495867) (xy 9.742932 -135.4963) (xy 9.715679 -135.495833)
			(xy 9.661728 -135.488076) (xy 9.609431 -135.47272) (xy 9.55985 -135.450078) (xy 9.513997 -135.42061)
			(xy 9.472805 -135.384917) (xy 9.437111 -135.343724) (xy 9.407643 -135.297871) (xy 9.385 -135.248291)
			(xy 9.369644 -135.195994) (xy 9.361887 -135.142043) (xy 5.1054 -135.142043) (xy 5.1054 -135.689594)
			(xy 7.28294 -135.689594) (xy 7.287011 -135.633972) (xy 7.299137 -135.579535) (xy 7.31906 -135.527444)
			(xy 7.346356 -135.478809) (xy 7.380442 -135.434666) (xy 7.420591 -135.395957) (xy 7.465949 -135.363506)
			(xy 7.515549 -135.338005) (xy 7.568333 -135.319998) (xy 7.623176 -135.309868) (xy 7.67891 -135.307831)
			(xy 7.734347 -135.313931) (xy 7.788304 -135.328037) (xy 7.839633 -135.349849) (xy 7.887239 -135.378903)
			(xy 7.930107 -135.414578) (xy 7.967324 -135.456115) (xy 7.998097 -135.502628) (xy 8.021769 -135.553125)
			(xy 8.037837 -135.606532) (xy 8.045957 -135.661708) (xy 8.046466 -135.689594) (xy 8.045957 -135.71748)
			(xy 8.037837 -135.772656) (xy 8.021769 -135.826063) (xy 8.002632 -135.866886) (xy 8.43991 -135.866886)
			(xy 8.443981 -135.811264) (xy 8.456107 -135.756827) (xy 8.47603 -135.704736) (xy 8.503326 -135.656101)
			(xy 8.537412 -135.611958) (xy 8.577561 -135.573249) (xy 8.622919 -135.540798) (xy 8.672519 -135.515297)
			(xy 8.725303 -135.49729) (xy 8.780146 -135.48716) (xy 8.83588 -135.485123) (xy 8.891317 -135.491223)
			(xy 8.945274 -135.505329) (xy 8.996603 -135.527141) (xy 9.044209 -135.556195) (xy 9.087077 -135.59187)
			(xy 9.124294 -135.633407) (xy 9.155067 -135.67992) (xy 9.178739 -135.730417) (xy 9.194807 -135.783824)
			(xy 9.202927 -135.839) (xy 9.203436 -135.866886) (xy 9.202927 -135.894772) (xy 9.194807 -135.949948)
			(xy 9.178739 -136.003355) (xy 9.155067 -136.053852) (xy 9.124294 -136.100365) (xy 9.087077 -136.141902)
			(xy 9.044209 -136.177577) (xy 8.996603 -136.206631) (xy 8.945274 -136.228443) (xy 8.891317 -136.242549)
			(xy 8.83588 -136.248649) (xy 8.780146 -136.246612) (xy 8.725303 -136.236482) (xy 8.672519 -136.218475)
			(xy 8.622919 -136.192974) (xy 8.577561 -136.160523) (xy 8.537412 -136.121814) (xy 8.503326 -136.077671)
			(xy 8.47603 -136.029036) (xy 8.456107 -135.976945) (xy 8.443981 -135.922508) (xy 8.43991 -135.866886)
			(xy 8.002632 -135.866886) (xy 7.998097 -135.87656) (xy 7.967324 -135.923073) (xy 7.930107 -135.96461)
			(xy 7.887239 -136.000285) (xy 7.839633 -136.029339) (xy 7.788304 -136.051151) (xy 7.734347 -136.065257)
			(xy 7.67891 -136.071357) (xy 7.623176 -136.06932) (xy 7.568333 -136.05919) (xy 7.515549 -136.041183)
			(xy 7.465949 -136.015682) (xy 7.420591 -135.983231) (xy 7.380442 -135.944522) (xy 7.346356 -135.900379)
			(xy 7.31906 -135.851744) (xy 7.299137 -135.799653) (xy 7.287011 -135.745216) (xy 7.28294 -135.689594)
			(xy 5.1054 -135.689594) (xy 5.1054 -137.44829) (xy 8.345168 -137.44829) (xy 8.349239 -137.392668)
			(xy 8.361365 -137.338231) (xy 8.381288 -137.28614) (xy 8.408584 -137.237505) (xy 8.44267 -137.193362)
			(xy 8.482819 -137.154653) (xy 8.528177 -137.122202) (xy 8.577777 -137.096701) (xy 8.630561 -137.078694)
			(xy 8.685404 -137.068564) (xy 8.741138 -137.066527) (xy 8.796575 -137.072627) (xy 8.850532 -137.086733)
			(xy 8.901861 -137.108545) (xy 8.949467 -137.137599) (xy 8.992335 -137.173274) (xy 9.029552 -137.214811)
			(xy 9.060325 -137.261324) (xy 9.06736 -137.276332) (xy 13.047218 -137.276332) (xy 13.047698 -137.248962)
			(xy 13.055512 -137.194784) (xy 13.070998 -137.14228) (xy 13.093836 -137.092533) (xy 13.123558 -137.046566)
			(xy 13.141198 -137.025634) (xy 13.141452 -137.02538) (xy 13.147059 -137.018308) (xy 13.153292 -137.00138)
			(xy 13.153644 -136.99236) (xy 13.153644 -136.925304) (xy 13.153297 -136.916286) (xy 13.147044 -136.899368)
			(xy 13.141452 -136.892284) (xy 13.141198 -136.892284) (xy 13.141198 -136.89203) (xy 13.123559 -136.871098)
			(xy 13.093847 -136.825125) (xy 13.071011 -136.775377) (xy 13.05552 -136.722877) (xy 13.047692 -136.668701)
			(xy 13.047218 -136.641332) (xy 13.047704 -136.614081) (xy 13.05546 -136.560133) (xy 13.070815 -136.507838)
			(xy 13.093457 -136.458261) (xy 13.122923 -136.412411) (xy 13.158614 -136.37122) (xy 13.199805 -136.335529)
			(xy 13.245655 -136.306063) (xy 13.295232 -136.283421) (xy 13.347527 -136.268066) (xy 13.401475 -136.26031)
			(xy 13.455977 -136.26031) (xy 13.509925 -136.268066) (xy 13.56222 -136.283421) (xy 13.611797 -136.306063)
			(xy 13.657647 -136.335529) (xy 13.698838 -136.37122) (xy 13.734529 -136.412411) (xy 13.763995 -136.458261)
			(xy 13.786637 -136.507838) (xy 13.801992 -136.560133) (xy 13.809748 -136.614081) (xy 13.810234 -136.641332)
			(xy 13.809803 -136.668704) (xy 13.801979 -136.722885) (xy 13.786483 -136.775389) (xy 13.763633 -136.825135)
			(xy 13.7339 -136.8711) (xy 13.716254 -136.89203) (xy 13.716 -136.892284) (xy 13.710414 -136.899371)
			(xy 13.704167 -136.916287) (xy 13.703808 -136.925304) (xy 13.703808 -136.99236) (xy 13.704183 -137.001375)
			(xy 13.710418 -137.018292) (xy 13.716 -137.02538) (xy 13.716254 -137.02538) (xy 13.716254 -137.025634)
			(xy 13.733868 -137.046586) (xy 13.763586 -137.092553) (xy 13.786427 -137.142295) (xy 13.801924 -137.194792)
			(xy 13.809757 -137.248964) (xy 13.810234 -137.276332) (xy 13.809748 -137.303583) (xy 13.801992 -137.357531)
			(xy 13.786637 -137.409826) (xy 13.763995 -137.459403) (xy 13.734529 -137.505253) (xy 13.698838 -137.546444)
			(xy 13.657647 -137.582135) (xy 13.611797 -137.611601) (xy 13.56222 -137.634243) (xy 13.509925 -137.649598)
			(xy 13.455977 -137.657354) (xy 13.401475 -137.657354) (xy 13.347527 -137.649598) (xy 13.295232 -137.634243)
			(xy 13.245655 -137.611601) (xy 13.199805 -137.582135) (xy 13.158614 -137.546444) (xy 13.122923 -137.505253)
			(xy 13.093457 -137.459403) (xy 13.070815 -137.409826) (xy 13.05546 -137.357531) (xy 13.047704 -137.303583)
			(xy 13.047218 -137.276332) (xy 9.06736 -137.276332) (xy 9.083997 -137.311821) (xy 9.100065 -137.365228)
			(xy 9.108185 -137.420404) (xy 9.108694 -137.44829) (xy 9.108185 -137.476176) (xy 9.100065 -137.531352)
			(xy 9.083997 -137.584759) (xy 9.060325 -137.635256) (xy 9.029552 -137.681769) (xy 8.992335 -137.723306)
			(xy 8.988288 -137.726674) (xy 13.98778 -137.726674) (xy 13.988211 -137.699302) (xy 13.996035 -137.645121)
			(xy 14.011531 -137.592617) (xy 14.034381 -137.54287) (xy 14.064114 -137.496906) (xy 14.08176 -137.475976)
			(xy 14.082014 -137.475722) (xy 14.087599 -137.468634) (xy 14.093846 -137.451718) (xy 14.094206 -137.442702)
			(xy 14.094206 -137.375646) (xy 14.093826 -137.366631) (xy 14.087594 -137.349714) (xy 14.082014 -137.342626)
			(xy 14.08176 -137.342626) (xy 14.08176 -137.342372) (xy 14.064135 -137.321429) (xy 14.034422 -137.275459)
			(xy 14.011584 -137.225714) (xy 13.996089 -137.173216) (xy 13.988256 -137.119042) (xy 13.98778 -137.091674)
			(xy 13.988266 -137.064423) (xy 13.996022 -137.010475) (xy 14.011377 -136.95818) (xy 14.034019 -136.908603)
			(xy 14.063485 -136.862753) (xy 14.099176 -136.821562) (xy 14.140367 -136.785871) (xy 14.186217 -136.756405)
			(xy 14.235794 -136.733763) (xy 14.288089 -136.718408) (xy 14.342037 -136.710652) (xy 14.396539 -136.710652)
			(xy 14.450487 -136.718408) (xy 14.502782 -136.733763) (xy 14.552359 -136.756405) (xy 14.598209 -136.785871)
			(xy 14.6394 -136.821562) (xy 14.675091 -136.862753) (xy 14.704557 -136.908603) (xy 14.727199 -136.95818)
			(xy 14.742554 -137.010475) (xy 14.75031 -137.064423) (xy 14.750796 -137.091674) (xy 14.750316 -137.119044)
			(xy 14.742501 -137.173222) (xy 14.727016 -137.225725) (xy 14.704177 -137.275472) (xy 14.674456 -137.32144)
			(xy 14.656816 -137.342372) (xy 14.656562 -137.342626) (xy 14.650996 -137.349726) (xy 14.644738 -137.366633)
			(xy 14.64437 -137.375646) (xy 14.64437 -137.442702) (xy 14.644733 -137.451718) (xy 14.650977 -137.468635)
			(xy 14.656562 -137.475722) (xy 14.656816 -137.475722) (xy 14.656816 -137.475976) (xy 14.67446 -137.496904)
			(xy 14.70417 -137.542878) (xy 14.727005 -137.592627) (xy 14.742495 -137.645128) (xy 14.750322 -137.699305)
			(xy 14.750796 -137.726674) (xy 14.75031 -137.753925) (xy 14.742554 -137.807873) (xy 14.727199 -137.860168)
			(xy 14.704557 -137.909745) (xy 14.675091 -137.955595) (xy 14.6394 -137.996786) (xy 14.598209 -138.032477)
			(xy 14.552359 -138.061943) (xy 14.502782 -138.084585) (xy 14.450487 -138.09994) (xy 14.396539 -138.107696)
			(xy 14.342037 -138.107696) (xy 14.288089 -138.09994) (xy 14.235794 -138.084585) (xy 14.186217 -138.061943)
			(xy 14.140367 -138.032477) (xy 14.099176 -137.996786) (xy 14.063485 -137.955595) (xy 14.034019 -137.909745)
			(xy 14.011377 -137.860168) (xy 13.996022 -137.807873) (xy 13.988266 -137.753925) (xy 13.98778 -137.726674)
			(xy 8.988288 -137.726674) (xy 8.949467 -137.758981) (xy 8.901861 -137.788035) (xy 8.850532 -137.809847)
			(xy 8.796575 -137.823953) (xy 8.741138 -137.830053) (xy 8.685404 -137.828016) (xy 8.630561 -137.817886)
			(xy 8.577777 -137.799879) (xy 8.528177 -137.774378) (xy 8.482819 -137.741927) (xy 8.44267 -137.703218)
			(xy 8.408584 -137.659075) (xy 8.381288 -137.61044) (xy 8.361365 -137.558349) (xy 8.349239 -137.503912)
			(xy 8.345168 -137.44829) (xy 5.1054 -137.44829) (xy 5.1054 -138.360404) (xy 6.176008 -138.360404)
			(xy 6.180079 -138.304782) (xy 6.192205 -138.250345) (xy 6.212128 -138.198254) (xy 6.239424 -138.149619)
			(xy 6.27351 -138.105476) (xy 6.313659 -138.066767) (xy 6.359017 -138.034316) (xy 6.408617 -138.008815)
			(xy 6.461401 -137.990808) (xy 6.516244 -137.980678) (xy 6.571978 -137.978641) (xy 6.627415 -137.984741)
			(xy 6.681372 -137.998847) (xy 6.732701 -138.020659) (xy 6.780307 -138.049713) (xy 6.823175 -138.085388)
			(xy 6.860392 -138.126925) (xy 6.891165 -138.173438) (xy 6.914837 -138.223935) (xy 6.930905 -138.277342)
			(xy 6.939025 -138.332518) (xy 6.939534 -138.360404) (xy 6.939025 -138.38829) (xy 6.936812 -138.40333)
			(xy 15.196312 -138.40333) (xy 15.196842 -138.375665) (xy 15.204838 -138.320917) (xy 15.220651 -138.267895)
			(xy 15.243951 -138.217711) (xy 15.274249 -138.171415) (xy 15.310912 -138.129977) (xy 15.353172 -138.094264)
			(xy 15.376398 -138.079226) (xy 15.386055 -138.072565) (xy 15.398512 -138.052722) (xy 15.400274 -138.041126)
			(xy 15.408148 -137.961116) (xy 15.408763 -137.949478) (xy 15.400695 -137.927642) (xy 15.392654 -137.919206)
			(xy 15.3924 -137.918952) (xy 15.373813 -137.900876) (xy 15.341235 -137.860543) (xy 15.314423 -137.816168)
			(xy 15.293871 -137.768568) (xy 15.279959 -137.718623) (xy 15.272943 -137.667253) (xy 15.272512 -137.64133)
			(xy 15.272983 -137.614077) (xy 15.280737 -137.560125) (xy 15.29609 -137.507826) (xy 15.31873 -137.458245)
			(xy 15.348197 -137.412391) (xy 15.38389 -137.371197) (xy 15.425083 -137.335503) (xy 15.470936 -137.306035)
			(xy 15.520517 -137.283393) (xy 15.572816 -137.268039) (xy 15.626767 -137.260284) (xy 15.65402 -137.259822)
			(xy 15.681391 -137.260271) (xy 15.735571 -137.268092) (xy 15.788074 -137.283585) (xy 15.837821 -137.306431)
			(xy 15.883787 -137.336159) (xy 15.904718 -137.353802) (xy 15.904972 -137.354056) (xy 15.912058 -137.359644)
			(xy 15.928975 -137.365888) (xy 15.937992 -137.366248) (xy 16.005048 -137.366248) (xy 16.014064 -137.365877)
			(xy 16.030981 -137.359641) (xy 16.038068 -137.354056) (xy 16.038068 -137.353802) (xy 16.038322 -137.353802)
			(xy 16.059273 -137.336186) (xy 16.105241 -137.306471) (xy 16.154983 -137.28363) (xy 16.20748 -137.268134)
			(xy 16.261652 -137.260299) (xy 16.28902 -137.259822) (xy 16.316275 -137.260236) (xy 16.370229 -137.267997)
			(xy 16.42253 -137.283357) (xy 16.472112 -137.306004) (xy 16.517966 -137.335477) (xy 16.55916 -137.371176)
			(xy 16.594853 -137.412374) (xy 16.62432 -137.458232) (xy 16.646961 -137.507817) (xy 16.662314 -137.56012)
			(xy 16.670067 -137.614075) (xy 16.670528 -137.64133) (xy 16.669987 -137.670246) (xy 16.661266 -137.727418)
			(xy 16.644015 -137.782617) (xy 16.618627 -137.83458) (xy 16.585686 -137.882114) (xy 16.545947 -137.92413)
			(xy 16.523462 -137.94232) (xy 16.514649 -137.949922) (xy 16.50447 -137.970827) (xy 16.503904 -137.982452)
			(xy 16.503904 -138.062208) (xy 16.504451 -138.073839) (xy 16.514634 -138.094749) (xy 16.523462 -138.10234)
			(xy 16.545957 -138.120518) (xy 16.585693 -138.162539) (xy 16.618632 -138.210077) (xy 16.644019 -138.262041)
			(xy 16.661272 -138.317241) (xy 16.669996 -138.374413) (xy 16.670528 -138.40333) (xy 16.67005 -138.430581)
			(xy 16.66229 -138.484528) (xy 16.646932 -138.536822) (xy 16.624289 -138.586398) (xy 16.594821 -138.632247)
			(xy 16.559129 -138.673436) (xy 16.517939 -138.709127) (xy 16.472089 -138.738594) (xy 16.422512 -138.761236)
			(xy 16.370218 -138.776592) (xy 16.316271 -138.784351) (xy 16.28902 -138.784838) (xy 16.262706 -138.784377)
			(xy 16.210576 -138.777144) (xy 16.159932 -138.762825) (xy 16.111733 -138.741691) (xy 16.06689 -138.714143)
			(xy 16.026251 -138.680701) (xy 16.008096 -138.661648) (xy 16.000571 -138.65425) (xy 15.981294 -138.645722)
			(xy 15.970758 -138.645138) (xy 15.896082 -138.645138) (xy 15.885534 -138.645687) (xy 15.866238 -138.654207)
			(xy 15.858744 -138.661648) (xy 15.840618 -138.680733) (xy 15.799981 -138.714185) (xy 15.755134 -138.741739)
			(xy 15.706928 -138.762872) (xy 15.656276 -138.777184) (xy 15.604138 -138.784403) (xy 15.57782 -138.784838)
			(xy 15.550571 -138.784303) (xy 15.496626 -138.77655) (xy 15.444334 -138.761199) (xy 15.394759 -138.738563)
			(xy 15.34891 -138.709101) (xy 15.307721 -138.673415) (xy 15.272029 -138.63223) (xy 15.242561 -138.586385)
			(xy 15.219918 -138.536813) (xy 15.20456 -138.484523) (xy 15.1968 -138.430579) (xy 15.196312 -138.40333)
			(xy 6.936812 -138.40333) (xy 6.930905 -138.443466) (xy 6.914837 -138.496873) (xy 6.891165 -138.54737)
			(xy 6.860392 -138.593883) (xy 6.823175 -138.63542) (xy 6.780307 -138.671095) (xy 6.732701 -138.700149)
			(xy 6.681372 -138.721961) (xy 6.627415 -138.736067) (xy 6.571978 -138.742167) (xy 6.516244 -138.74013)
			(xy 6.461401 -138.73) (xy 6.408617 -138.711993) (xy 6.359017 -138.686492) (xy 6.313659 -138.654041)
			(xy 6.27351 -138.615332) (xy 6.239424 -138.571189) (xy 6.212128 -138.522554) (xy 6.192205 -138.470463)
			(xy 6.180079 -138.416026) (xy 6.176008 -138.360404) (xy 5.1054 -138.360404) (xy 5.1054 -138.824462)
			(xy 8.361932 -138.824462) (xy 8.366003 -138.76884) (xy 8.378129 -138.714403) (xy 8.398052 -138.662312)
			(xy 8.425348 -138.613677) (xy 8.459434 -138.569534) (xy 8.499583 -138.530825) (xy 8.544941 -138.498374)
			(xy 8.594541 -138.472873) (xy 8.647325 -138.454866) (xy 8.702168 -138.444736) (xy 8.757902 -138.442699)
			(xy 8.813339 -138.448799) (xy 8.867296 -138.462905) (xy 8.918625 -138.484717) (xy 8.966231 -138.513771)
			(xy 9.009099 -138.549446) (xy 9.046316 -138.590983) (xy 9.077089 -138.637496) (xy 9.100761 -138.687993)
			(xy 9.116829 -138.7414) (xy 9.124949 -138.796576) (xy 9.125458 -138.824462) (xy 9.124949 -138.852348)
			(xy 9.116829 -138.907524) (xy 9.100761 -138.960931) (xy 9.077089 -139.011428) (xy 9.046316 -139.057941)
			(xy 9.009099 -139.099478) (xy 8.966231 -139.135153) (xy 8.918625 -139.164207) (xy 8.867296 -139.186019)
			(xy 8.813339 -139.200125) (xy 8.757902 -139.206225) (xy 8.702168 -139.204188) (xy 8.647325 -139.194058)
			(xy 8.594541 -139.176051) (xy 8.544941 -139.15055) (xy 8.499583 -139.118099) (xy 8.459434 -139.07939)
			(xy 8.425348 -139.035247) (xy 8.398052 -138.986612) (xy 8.378129 -138.934521) (xy 8.366003 -138.880084)
			(xy 8.361932 -138.824462) (xy 5.1054 -138.824462) (xy 5.1054 -139.376404) (xy 6.176008 -139.376404)
			(xy 6.180079 -139.320782) (xy 6.192205 -139.266345) (xy 6.212128 -139.214254) (xy 6.239424 -139.165619)
			(xy 6.27351 -139.121476) (xy 6.313659 -139.082767) (xy 6.359017 -139.050316) (xy 6.408617 -139.024815)
			(xy 6.461401 -139.006808) (xy 6.516244 -138.996678) (xy 6.571978 -138.994641) (xy 6.627415 -139.000741)
			(xy 6.681372 -139.014847) (xy 6.732701 -139.036659) (xy 6.780307 -139.065713) (xy 6.823175 -139.101388)
			(xy 6.860392 -139.142925) (xy 6.891165 -139.189438) (xy 6.914837 -139.239935) (xy 6.927773 -139.282932)
			(xy 16.938244 -139.282932) (xy 16.938754 -139.25414) (xy 16.947436 -139.197214) (xy 16.964578 -139.14224)
			(xy 16.989789 -139.090467) (xy 17.022498 -139.043074) (xy 17.061959 -139.001136) (xy 17.084294 -138.982958)
			(xy 17.092898 -138.975378) (xy 17.102912 -138.954782) (xy 17.103598 -138.943334) (xy 17.104106 -138.851894)
			(xy 17.093946 -138.830812) (xy 17.084802 -138.8237) (xy 17.062892 -138.805501) (xy 17.024216 -138.763691)
			(xy 16.992191 -138.716591) (xy 16.967531 -138.665251) (xy 16.950784 -138.610813) (xy 16.942323 -138.55449)
			(xy 16.9418 -138.526012) (xy 16.9418 -138.525758) (xy 16.9423 -138.498389) (xy 16.95011 -138.444211)
			(xy 16.965591 -138.391709) (xy 16.988425 -138.341961) (xy 17.018142 -138.295993) (xy 17.03578 -138.27506)
			(xy 17.036034 -138.274806) (xy 17.041628 -138.267725) (xy 17.047869 -138.250804) (xy 17.048226 -138.241786)
			(xy 17.048226 -138.17473) (xy 17.047849 -138.165715) (xy 17.041615 -138.148798) (xy 17.036034 -138.14171)
			(xy 17.03578 -138.14171) (xy 17.03578 -138.141456) (xy 17.018137 -138.120525) (xy 16.988412 -138.074557)
			(xy 16.965567 -138.02481) (xy 16.950071 -137.972308) (xy 16.942242 -137.918129) (xy 16.942242 -137.863388)
			(xy 16.950071 -137.809209) (xy 16.965568 -137.756707) (xy 16.988414 -137.70696) (xy 17.018139 -137.660993)
			(xy 17.03578 -137.64006) (xy 17.036034 -137.639806) (xy 17.041628 -137.632725) (xy 17.047869 -137.615804)
			(xy 17.048226 -137.606786) (xy 17.048226 -137.53973) (xy 17.047849 -137.530715) (xy 17.041615 -137.513798)
			(xy 17.036034 -137.50671) (xy 17.03578 -137.50671) (xy 17.03578 -137.506456) (xy 17.018137 -137.485525)
			(xy 16.988412 -137.439557) (xy 16.965567 -137.38981) (xy 16.950071 -137.337308) (xy 16.942242 -137.283129)
			(xy 16.942242 -137.228388) (xy 16.950071 -137.174209) (xy 16.965568 -137.121707) (xy 16.988414 -137.07196)
			(xy 17.018139 -137.025993) (xy 17.03578 -137.00506) (xy 17.036034 -137.004806) (xy 17.041628 -136.997725)
			(xy 17.047869 -136.980804) (xy 17.048226 -136.971786) (xy 17.048226 -136.90473) (xy 17.047849 -136.895715)
			(xy 17.041615 -136.878798) (xy 17.036034 -136.87171) (xy 17.03578 -136.87171) (xy 17.03578 -136.871456)
			(xy 17.018151 -136.850516) (xy 16.988438 -136.804545) (xy 16.9656 -136.7548) (xy 16.950107 -136.702301)
			(xy 16.942276 -136.648127) (xy 16.9418 -136.620758) (xy 16.942286 -136.593507) (xy 16.950042 -136.539559)
			(xy 16.965397 -136.487264) (xy 16.988039 -136.437687) (xy 17.017505 -136.391837) (xy 17.053196 -136.350646)
			(xy 17.094387 -136.314955) (xy 17.140237 -136.285489) (xy 17.189814 -136.262847) (xy 17.242109 -136.247492)
			(xy 17.296057 -136.239736) (xy 17.350559 -136.239736) (xy 17.404507 -136.247492) (xy 17.456802 -136.262847)
			(xy 17.506379 -136.285489) (xy 17.552229 -136.314955) (xy 17.59342 -136.350646) (xy 17.629111 -136.391837)
			(xy 17.658577 -136.437687) (xy 17.681219 -136.487264) (xy 17.696574 -136.539559) (xy 17.70433 -136.593507)
			(xy 17.704816 -136.620758) (xy 17.704346 -136.648128) (xy 17.696532 -136.702308) (xy 17.681045 -136.754812)
			(xy 17.658204 -136.804559) (xy 17.628478 -136.850525) (xy 17.610836 -136.871456) (xy 17.610582 -136.87171)
			(xy 17.604983 -136.878788) (xy 17.598744 -136.895711) (xy 17.59839 -136.90473) (xy 17.59839 -136.971786)
			(xy 17.598756 -136.980802) (xy 17.604998 -136.997719) (xy 17.610582 -137.004806) (xy 17.610836 -137.004806)
			(xy 17.610836 -137.00506) (xy 17.628475 -137.025994) (xy 17.658199 -137.071962) (xy 17.681045 -137.121708)
			(xy 17.696541 -137.17421) (xy 17.70437 -137.228388) (xy 17.70437 -137.283129) (xy 17.696541 -137.337307)
			(xy 17.681046 -137.389809) (xy 17.658201 -137.439555) (xy 17.628476 -137.485523) (xy 17.610836 -137.506456)
			(xy 17.610582 -137.50671) (xy 17.604983 -137.513788) (xy 17.598744 -137.530711) (xy 17.59839 -137.53973)
			(xy 17.59839 -137.606786) (xy 17.598756 -137.615802) (xy 17.604998 -137.632719) (xy 17.610582 -137.639806)
			(xy 17.610836 -137.639806) (xy 17.610836 -137.64006) (xy 17.628475 -137.660994) (xy 17.658199 -137.706962)
			(xy 17.681045 -137.756708) (xy 17.696541 -137.80921) (xy 17.70437 -137.863388) (xy 17.70437 -137.918129)
			(xy 17.696541 -137.972307) (xy 17.681046 -138.024809) (xy 17.658201 -138.074555) (xy 17.628476 -138.120523)
			(xy 17.610836 -138.141456) (xy 17.610582 -138.14171) (xy 17.604983 -138.148788) (xy 17.598744 -138.165711)
			(xy 17.59839 -138.17473) (xy 17.59839 -138.241786) (xy 17.598756 -138.250802) (xy 17.604998 -138.267719)
			(xy 17.610582 -138.274806) (xy 17.610836 -138.274806) (xy 17.610836 -138.27506) (xy 17.628475 -138.295992)
			(xy 17.658186 -138.341965) (xy 17.681021 -138.391713) (xy 17.696512 -138.444213) (xy 17.704341 -138.498389)
			(xy 17.704816 -138.525758) (xy 17.704314 -138.554551) (xy 17.695632 -138.611478) (xy 17.67849 -138.666453)
			(xy 17.653277 -138.718225) (xy 17.620567 -138.765619) (xy 17.581102 -138.807555) (xy 17.558766 -138.825732)
			(xy 17.550177 -138.833327) (xy 17.540152 -138.853911) (xy 17.539462 -138.865356) (xy 17.538954 -138.956796)
			(xy 17.549114 -138.977878) (xy 17.558258 -138.98499) (xy 17.57045 -138.995404) (xy 17.570704 -138.995658)
			(xy 17.57778 -139.001259) (xy 17.594705 -139.007496) (xy 17.603724 -139.00785) (xy 17.67078 -139.00785)
			(xy 17.679797 -139.007494) (xy 17.696715 -139.001247) (xy 17.7038 -138.995658) (xy 17.7038 -138.995404)
			(xy 17.704054 -138.995404) (xy 17.724987 -138.977763) (xy 17.770955 -138.948039) (xy 17.820701 -138.925193)
			(xy 17.873203 -138.909697) (xy 17.927381 -138.901868) (xy 17.982123 -138.901868) (xy 18.036301 -138.909697)
			(xy 18.088803 -138.925193) (xy 18.138549 -138.948039) (xy 18.184517 -138.977763) (xy 18.20545 -138.995404)
			(xy 18.205704 -138.995658) (xy 18.21278 -139.001259) (xy 18.229705 -139.007496) (xy 18.238724 -139.00785)
			(xy 18.30578 -139.00785) (xy 18.314797 -139.007494) (xy 18.331715 -139.001247) (xy 18.3388 -138.995658)
			(xy 18.3388 -138.995404) (xy 18.339054 -138.995404) (xy 18.359987 -138.977763) (xy 18.405955 -138.948039)
			(xy 18.455701 -138.925193) (xy 18.508203 -138.909697) (xy 18.562381 -138.901868) (xy 18.617123 -138.901868)
			(xy 18.671301 -138.909697) (xy 18.723803 -138.925193) (xy 18.773549 -138.948039) (xy 18.819517 -138.977763)
			(xy 18.84045 -138.995404) (xy 18.840704 -138.995658) (xy 18.84778 -139.001259) (xy 18.864705 -139.007496)
			(xy 18.873724 -139.00785) (xy 18.94078 -139.00785) (xy 18.949797 -139.007494) (xy 18.966715 -139.001247)
			(xy 18.9738 -138.995658) (xy 18.9738 -138.995404) (xy 18.974054 -138.995404) (xy 18.994993 -138.977774)
			(xy 19.040964 -138.94806) (xy 19.09071 -138.925223) (xy 19.143209 -138.90973) (xy 19.197383 -138.901899)
			(xy 19.224752 -138.901424) (xy 19.252003 -138.901906) (xy 19.305951 -138.909663) (xy 19.358246 -138.925018)
			(xy 19.407823 -138.947659) (xy 19.453674 -138.977126) (xy 19.494864 -139.012818) (xy 19.530555 -139.054008)
			(xy 19.560021 -139.099859) (xy 19.582663 -139.149436) (xy 19.598018 -139.201731) (xy 19.605774 -139.255679)
			(xy 19.605774 -139.310181) (xy 19.598018 -139.364129) (xy 19.582663 -139.416424) (xy 19.560021 -139.466001)
			(xy 19.530555 -139.511852) (xy 19.494864 -139.553042) (xy 19.453674 -139.588734) (xy 19.407823 -139.618201)
			(xy 19.358246 -139.640842) (xy 19.305951 -139.656197) (xy 19.252003 -139.663954) (xy 19.224752 -139.66444)
			(xy 19.197382 -139.663958) (xy 19.143203 -139.656146) (xy 19.0907 -139.640662) (xy 19.040952 -139.617823)
			(xy 18.994986 -139.588101) (xy 18.974054 -139.57046) (xy 18.9738 -139.570206) (xy 18.966717 -139.564614)
			(xy 18.949798 -139.55837) (xy 18.94078 -139.558014) (xy 18.873724 -139.558014) (xy 18.864708 -139.558379)
			(xy 18.847791 -139.564621) (xy 18.840704 -139.570206) (xy 18.84045 -139.57046) (xy 18.819517 -139.588101)
			(xy 18.773549 -139.617825) (xy 18.723803 -139.640671) (xy 18.671301 -139.656167) (xy 18.617123 -139.663996)
			(xy 18.562381 -139.663996) (xy 18.508203 -139.656167) (xy 18.455701 -139.640671) (xy 18.405955 -139.617825)
			(xy 18.359987 -139.588101) (xy 18.339054 -139.57046) (xy 18.3388 -139.570206) (xy 18.331717 -139.564614)
			(xy 18.314798 -139.55837) (xy 18.30578 -139.558014) (xy 18.238724 -139.558014) (xy 18.229708 -139.558379)
			(xy 18.212791 -139.564621) (xy 18.205704 -139.570206) (xy 18.205704 -139.57046) (xy 18.20545 -139.57046)
			(xy 18.184517 -139.588101) (xy 18.138549 -139.617825) (xy 18.088803 -139.640671) (xy 18.036301 -139.656167)
			(xy 17.982123 -139.663996) (xy 17.927381 -139.663996) (xy 17.873203 -139.656167) (xy 17.820701 -139.640671)
			(xy 17.770955 -139.617825) (xy 17.724987 -139.588101) (xy 17.704054 -139.57046) (xy 17.7038 -139.570206)
			(xy 17.696717 -139.564614) (xy 17.679798 -139.55837) (xy 17.67078 -139.558014) (xy 17.603724 -139.558014)
			(xy 17.594708 -139.558379) (xy 17.577791 -139.564621) (xy 17.570704 -139.570206) (xy 17.570704 -139.57046)
			(xy 17.57045 -139.57046) (xy 17.549505 -139.588083) (xy 17.503536 -139.617799) (xy 17.453792 -139.640638)
			(xy 17.401294 -139.656133) (xy 17.34712 -139.663964) (xy 17.319752 -139.66444) (xy 17.292501 -139.663967)
			(xy 17.238555 -139.656205) (xy 17.186262 -139.640845) (xy 17.136686 -139.618201) (xy 17.090838 -139.588732)
			(xy 17.049649 -139.55304) (xy 17.013958 -139.51185) (xy 16.984492 -139.466) (xy 16.961849 -139.416423)
			(xy 16.946492 -139.36413) (xy 16.938732 -139.310183) (xy 16.938244 -139.282932) (xy 6.927773 -139.282932)
			(xy 6.930905 -139.293342) (xy 6.939025 -139.348518) (xy 6.939534 -139.376404) (xy 6.939025 -139.40429)
			(xy 6.930905 -139.459466) (xy 6.914837 -139.512873) (xy 6.891165 -139.56337) (xy 6.860392 -139.609883)
			(xy 6.823175 -139.65142) (xy 6.780307 -139.687095) (xy 6.732701 -139.716149) (xy 6.681372 -139.737961)
			(xy 6.627415 -139.752067) (xy 6.571978 -139.758167) (xy 6.516244 -139.75613) (xy 6.461401 -139.746)
			(xy 6.408617 -139.727993) (xy 6.359017 -139.702492) (xy 6.313659 -139.670041) (xy 6.27351 -139.631332)
			(xy 6.239424 -139.587189) (xy 6.212128 -139.538554) (xy 6.192205 -139.486463) (xy 6.180079 -139.432026)
			(xy 6.176008 -139.376404) (xy 5.1054 -139.376404) (xy 5.1054 -140.392404) (xy 8.367774 -140.392404)
			(xy 8.371845 -140.336782) (xy 8.383971 -140.282345) (xy 8.403894 -140.230254) (xy 8.43119 -140.181619)
			(xy 8.465276 -140.137476) (xy 8.505425 -140.098767) (xy 8.550783 -140.066316) (xy 8.600383 -140.040815)
			(xy 8.653167 -140.022808) (xy 8.70801 -140.012678) (xy 8.763744 -140.010641) (xy 8.819181 -140.016741)
			(xy 8.873138 -140.030847) (xy 8.924467 -140.052659) (xy 8.972073 -140.081713) (xy 9.014941 -140.117388)
			(xy 9.052158 -140.158925) (xy 9.082931 -140.205438) (xy 9.106603 -140.255935) (xy 9.122671 -140.309342)
			(xy 9.130791 -140.364518) (xy 9.1313 -140.392404) (xy 9.130791 -140.42029) (xy 9.122671 -140.475466)
			(xy 9.106603 -140.528873) (xy 9.082931 -140.57937) (xy 9.052158 -140.625883) (xy 9.014941 -140.66742)
			(xy 8.972073 -140.703095) (xy 8.924467 -140.732149) (xy 8.873138 -140.753961) (xy 8.819181 -140.768067)
			(xy 8.763744 -140.774167) (xy 8.70801 -140.77213) (xy 8.653167 -140.762) (xy 8.600383 -140.743993)
			(xy 8.550783 -140.718492) (xy 8.505425 -140.686041) (xy 8.465276 -140.647332) (xy 8.43119 -140.603189)
			(xy 8.403894 -140.554554) (xy 8.383971 -140.502463) (xy 8.371845 -140.448026) (xy 8.367774 -140.392404)
			(xy 5.1054 -140.392404) (xy 5.1054 -141.046533) (xy 10.755071 -141.046533) (xy 10.755071 -140.992027)
			(xy 10.762828 -140.938075) (xy 10.778185 -140.885777) (xy 10.800828 -140.836196) (xy 10.830296 -140.790342)
			(xy 10.86599 -140.749149) (xy 10.907184 -140.713455) (xy 10.953038 -140.683987) (xy 11.002618 -140.661344)
			(xy 11.054917 -140.645988) (xy 11.108869 -140.638231) (xy 11.136122 -140.637768) (xy 11.162436 -140.638231)
			(xy 11.214564 -140.645468) (xy 11.265207 -140.659789) (xy 11.313405 -140.680922) (xy 11.358249 -140.708469)
			(xy 11.398889 -140.741907) (xy 11.417046 -140.760958) (xy 11.424554 -140.768376) (xy 11.443844 -140.776892)
			(xy 11.454384 -140.777468) (xy 11.52906 -140.777468) (xy 11.53961 -140.77694) (xy 11.558906 -140.768405)
			(xy 11.566398 -140.760958) (xy 11.584553 -140.741902) (xy 11.625184 -140.708447) (xy 11.670025 -140.680889)
			(xy 11.718225 -140.659751) (xy 11.768872 -140.645433) (xy 11.821006 -140.638207) (xy 11.847322 -140.637768)
			(xy 11.874573 -140.638262) (xy 11.92852 -140.646019) (xy 11.980814 -140.661374) (xy 12.03039 -140.684015)
			(xy 12.07624 -140.713481) (xy 12.117429 -140.749172) (xy 12.15312 -140.790362) (xy 12.182586 -140.836212)
			(xy 12.205227 -140.885788) (xy 12.220582 -140.938082) (xy 12.228338 -140.992029) (xy 12.228338 -141.046531)
			(xy 12.220582 -141.100478) (xy 12.205227 -141.152772) (xy 12.182586 -141.202348) (xy 12.15312 -141.248198)
			(xy 12.117429 -141.289388) (xy 12.07624 -141.325079) (xy 12.03039 -141.354545) (xy 11.980814 -141.377186)
			(xy 11.92852 -141.392541) (xy 11.874573 -141.400298) (xy 11.847322 -141.400784) (xy 11.821008 -141.400307)
			(xy 11.76888 -141.393075) (xy 11.718237 -141.378758) (xy 11.670038 -141.357627) (xy 11.625194 -141.330083)
			(xy 11.584555 -141.296645) (xy 11.566398 -141.277594) (xy 11.55888 -141.270189) (xy 11.539597 -141.261667)
			(xy 11.52906 -141.261084) (xy 11.454384 -141.261084) (xy 11.443832 -141.261596) (xy 11.424538 -141.270144)
			(xy 11.417046 -141.277594) (xy 11.398909 -141.296668) (xy 11.358275 -141.330123) (xy 11.313431 -141.35768)
			(xy 11.265227 -141.378815) (xy 11.214576 -141.393129) (xy 11.162439 -141.400348) (xy 11.136122 -141.400784)
			(xy 11.108869 -141.400329) (xy 11.054917 -141.392572) (xy 11.002618 -141.377216) (xy 10.953038 -141.354573)
			(xy 10.907184 -141.325105) (xy 10.86599 -141.289411) (xy 10.830296 -141.248218) (xy 10.800828 -141.202364)
			(xy 10.778185 -141.152783) (xy 10.762828 -141.100485) (xy 10.755071 -141.046533) (xy 5.1054 -141.046533)
			(xy 5.1054 -143.078533) (xy 10.755071 -143.078533) (xy 10.755071 -143.024027) (xy 10.762828 -142.970075)
			(xy 10.778185 -142.917777) (xy 10.800828 -142.868196) (xy 10.830296 -142.822342) (xy 10.86599 -142.781149)
			(xy 10.907184 -142.745455) (xy 10.953038 -142.715987) (xy 11.002618 -142.693344) (xy 11.054917 -142.677988)
			(xy 11.108869 -142.670231) (xy 11.136122 -142.669768) (xy 11.162436 -142.670231) (xy 11.214564 -142.677468)
			(xy 11.265207 -142.691789) (xy 11.313405 -142.712922) (xy 11.358249 -142.740469) (xy 11.398889 -142.773907)
			(xy 11.417046 -142.792958) (xy 11.424554 -142.800376) (xy 11.443844 -142.808892) (xy 11.454384 -142.809468)
			(xy 11.52906 -142.809468) (xy 11.53961 -142.80894) (xy 11.558906 -142.800405) (xy 11.566398 -142.792958)
			(xy 11.584553 -142.773902) (xy 11.625184 -142.740447) (xy 11.670025 -142.712889) (xy 11.718225 -142.691751)
			(xy 11.768872 -142.677433) (xy 11.821006 -142.670207) (xy 11.847322 -142.669768) (xy 11.874573 -142.670262)
			(xy 11.92852 -142.678019) (xy 11.980814 -142.693374) (xy 12.03039 -142.716015) (xy 12.07624 -142.745481)
			(xy 12.117429 -142.781172) (xy 12.15312 -142.822362) (xy 12.182586 -142.868212) (xy 12.205227 -142.917788)
			(xy 12.220582 -142.970082) (xy 12.228338 -143.024029) (xy 12.228338 -143.078531) (xy 12.220582 -143.132478)
			(xy 12.205227 -143.184772) (xy 12.182586 -143.234348) (xy 12.15312 -143.280198) (xy 12.117429 -143.321388)
			(xy 12.07624 -143.357079) (xy 12.03039 -143.386545) (xy 11.980814 -143.409186) (xy 11.92852 -143.424541)
			(xy 11.874573 -143.432298) (xy 11.847322 -143.432784) (xy 11.821008 -143.432307) (xy 11.76888 -143.425075)
			(xy 11.718237 -143.410758) (xy 11.670038 -143.389627) (xy 11.625194 -143.362083) (xy 11.584555 -143.328645)
			(xy 11.566398 -143.309594) (xy 11.55888 -143.302189) (xy 11.539597 -143.293667) (xy 11.52906 -143.293084)
			(xy 11.454384 -143.293084) (xy 11.443832 -143.293596) (xy 11.424538 -143.302144) (xy 11.417046 -143.309594)
			(xy 11.398909 -143.328668) (xy 11.358275 -143.362123) (xy 11.313431 -143.38968) (xy 11.265227 -143.410815)
			(xy 11.214576 -143.425129) (xy 11.162439 -143.432348) (xy 11.136122 -143.432784) (xy 11.108869 -143.432329)
			(xy 11.054917 -143.424572) (xy 11.002618 -143.409216) (xy 10.953038 -143.386573) (xy 10.907184 -143.357105)
			(xy 10.86599 -143.321411) (xy 10.830296 -143.280218) (xy 10.800828 -143.234364) (xy 10.778185 -143.184783)
			(xy 10.762828 -143.132485) (xy 10.755071 -143.078533) (xy 5.1054 -143.078533) (xy 5.1054 -143.915638)
			(xy 19.464274 -143.915638) (xy 19.464775 -143.888065) (xy 19.472722 -143.833494) (xy 19.48844 -143.780635)
			(xy 19.511604 -143.730589) (xy 19.541729 -143.684399) (xy 19.57819 -143.643025) (xy 19.598894 -143.624808)
			(xy 19.606965 -143.617249) (xy 19.616322 -143.597241) (xy 19.616928 -143.5862) (xy 19.616928 -143.508476)
			(xy 19.616341 -143.497428) (xy 19.606991 -143.477406) (xy 19.598894 -143.469868) (xy 19.578163 -143.451679)
			(xy 19.541694 -143.410305) (xy 19.511565 -143.364111) (xy 19.488403 -143.314058) (xy 19.472691 -143.261192)
			(xy 19.464756 -143.206614) (xy 19.464274 -143.179038) (xy 19.464767 -143.150298) (xy 19.473398 -143.09347)
			(xy 19.490456 -143.038579) (xy 19.515554 -142.986868) (xy 19.548125 -142.939506) (xy 19.567398 -142.91818)
			(xy 19.574002 -142.911322) (xy 19.581114 -142.893288) (xy 19.581114 -142.804388) (xy 19.574002 -142.786354)
			(xy 19.567398 -142.779496) (xy 19.548166 -142.758136) (xy 19.515602 -142.710778) (xy 19.49051 -142.659072)
			(xy 19.473458 -142.604187) (xy 19.464833 -142.547364) (xy 19.464829 -142.489891) (xy 19.473446 -142.433068)
			(xy 19.490489 -142.37818) (xy 19.515574 -142.32647) (xy 19.548131 -142.279107) (xy 19.567398 -142.25778)
			(xy 19.574002 -142.250922) (xy 19.581114 -142.232888) (xy 19.581114 -142.143988) (xy 19.574002 -142.125954)
			(xy 19.567398 -142.119096) (xy 19.548166 -142.097736) (xy 19.515602 -142.050378) (xy 19.49051 -141.998672)
			(xy 19.473458 -141.943787) (xy 19.464833 -141.886964) (xy 19.464829 -141.829491) (xy 19.473446 -141.772668)
			(xy 19.490489 -141.71778) (xy 19.515574 -141.66607) (xy 19.548131 -141.618707) (xy 19.567398 -141.59738)
			(xy 19.574002 -141.590522) (xy 19.581114 -141.572488) (xy 19.581114 -141.483588) (xy 19.574002 -141.465554)
			(xy 19.567398 -141.458696) (xy 19.548166 -141.437336) (xy 19.515602 -141.389978) (xy 19.49051 -141.338272)
			(xy 19.473458 -141.283387) (xy 19.464833 -141.226564) (xy 19.464829 -141.169091) (xy 19.473446 -141.112268)
			(xy 19.490489 -141.05738) (xy 19.515574 -141.00567) (xy 19.548131 -140.958307) (xy 19.567398 -140.93698)
			(xy 19.574002 -140.930122) (xy 19.581114 -140.912088) (xy 19.581114 -140.823188) (xy 19.574002 -140.805154)
			(xy 19.567398 -140.798296) (xy 19.548156 -140.776944) (xy 19.515583 -140.72959) (xy 19.490484 -140.677885)
			(xy 19.473427 -140.622999) (xy 19.464798 -140.566175) (xy 19.464274 -140.537438) (xy 19.46476 -140.510187)
			(xy 19.472516 -140.456239) (xy 19.487871 -140.403944) (xy 19.510513 -140.354367) (xy 19.539979 -140.308517)
			(xy 19.57567 -140.267326) (xy 19.616861 -140.231635) (xy 19.662711 -140.202169) (xy 19.712288 -140.179527)
			(xy 19.764583 -140.164172) (xy 19.818531 -140.156416) (xy 19.873033 -140.156416) (xy 19.926981 -140.164172)
			(xy 19.979276 -140.179527) (xy 20.028853 -140.202169) (xy 20.074703 -140.231635) (xy 20.115894 -140.267326)
			(xy 20.151585 -140.308517) (xy 20.181051 -140.354367) (xy 20.203693 -140.403944) (xy 20.219048 -140.456239)
			(xy 20.226804 -140.510187) (xy 20.22729 -140.537438) (xy 20.226792 -140.566178) (xy 20.218164 -140.623007)
			(xy 20.201108 -140.677898) (xy 20.17601 -140.729609) (xy 20.143439 -140.77697) (xy 20.124166 -140.798296)
			(xy 20.117562 -140.805154) (xy 20.11045 -140.823188) (xy 20.11045 -140.912088) (xy 20.117562 -140.930122)
			(xy 20.124166 -140.93698) (xy 20.143475 -140.958274) (xy 20.17604 -141.005642) (xy 20.20113 -141.057359)
			(xy 20.218178 -141.112255) (xy 20.226797 -141.169087) (xy 20.226793 -141.226569) (xy 20.218165 -141.283399)
			(xy 20.20111 -141.338293) (xy 20.176012 -141.390006) (xy 20.14344 -141.437369) (xy 20.124166 -141.458696)
			(xy 20.117562 -141.465554) (xy 20.11045 -141.483588) (xy 20.11045 -141.572488) (xy 20.117562 -141.590522)
			(xy 20.124166 -141.59738) (xy 20.143475 -141.618674) (xy 20.17604 -141.666042) (xy 20.20113 -141.717759)
			(xy 20.218178 -141.772655) (xy 20.226797 -141.829487) (xy 20.226793 -141.886969) (xy 20.218165 -141.943799)
			(xy 20.20111 -141.998693) (xy 20.176012 -142.050406) (xy 20.14344 -142.097769) (xy 20.124166 -142.119096)
			(xy 20.117562 -142.125954) (xy 20.11045 -142.143988) (xy 20.11045 -142.232888) (xy 20.117562 -142.250922)
			(xy 20.124166 -142.25778) (xy 20.143475 -142.279074) (xy 20.17604 -142.326442) (xy 20.20113 -142.378159)
			(xy 20.218178 -142.433055) (xy 20.226797 -142.489887) (xy 20.226793 -142.547369) (xy 20.218165 -142.604199)
			(xy 20.20111 -142.659093) (xy 20.176012 -142.710806) (xy 20.14344 -142.758169) (xy 20.124166 -142.779496)
			(xy 20.117562 -142.786354) (xy 20.11045 -142.804388) (xy 20.11045 -142.893288) (xy 20.117562 -142.911322)
			(xy 20.124166 -142.91818) (xy 20.143455 -142.939491) (xy 20.176019 -142.986857) (xy 20.201108 -143.038573)
			(xy 20.218154 -143.093467) (xy 20.226772 -143.150298) (xy 20.22729 -143.179038) (xy 20.226785 -143.206611)
			(xy 20.218841 -143.261182) (xy 20.203124 -143.314042) (xy 20.179961 -143.364088) (xy 20.149836 -143.410279)
			(xy 20.113374 -143.451651) (xy 20.09267 -143.469868) (xy 20.084604 -143.477431) (xy 20.075246 -143.497437)
			(xy 20.074636 -143.508476) (xy 20.074636 -143.5862) (xy 20.075248 -143.597244) (xy 20.084581 -143.617266)
			(xy 20.09267 -143.624808) (xy 20.113382 -143.643018) (xy 20.149854 -143.684386) (xy 20.179987 -143.730576)
			(xy 20.203152 -143.780625) (xy 20.218868 -143.833488) (xy 20.226806 -143.888063) (xy 20.22729 -143.915638)
			(xy 20.226804 -143.942889) (xy 20.219048 -143.996837) (xy 20.203693 -144.049132) (xy 20.181051 -144.098709)
			(xy 20.151585 -144.144559) (xy 20.115894 -144.18575) (xy 20.074703 -144.221441) (xy 20.028853 -144.250907)
			(xy 19.979276 -144.273549) (xy 19.926981 -144.288904) (xy 19.873033 -144.29666) (xy 19.818531 -144.29666)
			(xy 19.764583 -144.288904) (xy 19.712288 -144.273549) (xy 19.662711 -144.250907) (xy 19.616861 -144.221441)
			(xy 19.57567 -144.18575) (xy 19.539979 -144.144559) (xy 19.510513 -144.098709) (xy 19.487871 -144.049132)
			(xy 19.472516 -143.996837) (xy 19.46476 -143.942889) (xy 19.464274 -143.915638) (xy 5.1054 -143.915638)
			(xy 5.1054 -145.110533) (xy 10.755071 -145.110533) (xy 10.755071 -145.056027) (xy 10.762828 -145.002075)
			(xy 10.778185 -144.949777) (xy 10.800828 -144.900196) (xy 10.830296 -144.854342) (xy 10.86599 -144.813149)
			(xy 10.907184 -144.777455) (xy 10.953038 -144.747987) (xy 11.002618 -144.725344) (xy 11.054917 -144.709988)
			(xy 11.108869 -144.702231) (xy 11.136122 -144.701768) (xy 11.162436 -144.702231) (xy 11.214564 -144.709468)
			(xy 11.265207 -144.723789) (xy 11.313405 -144.744922) (xy 11.358249 -144.772469) (xy 11.398889 -144.805907)
			(xy 11.417046 -144.824958) (xy 11.424554 -144.832376) (xy 11.443844 -144.840892) (xy 11.454384 -144.841468)
			(xy 11.52906 -144.841468) (xy 11.53961 -144.84094) (xy 11.558906 -144.832405) (xy 11.566398 -144.824958)
			(xy 11.584553 -144.805902) (xy 11.625184 -144.772447) (xy 11.670025 -144.744889) (xy 11.718225 -144.723751)
			(xy 11.768872 -144.709433) (xy 11.821006 -144.702207) (xy 11.847322 -144.701768) (xy 11.874573 -144.702262)
			(xy 11.92852 -144.710019) (xy 11.980814 -144.725374) (xy 12.03039 -144.748015) (xy 12.07624 -144.777481)
			(xy 12.117429 -144.813172) (xy 12.15312 -144.854362) (xy 12.182586 -144.900212) (xy 12.205227 -144.949788)
			(xy 12.206535 -144.954244) (xy 17.939004 -144.954244) (xy 17.939496 -144.926992) (xy 17.947248 -144.873041)
			(xy 17.962599 -144.820743) (xy 17.985237 -144.771162) (xy 18.014701 -144.725308) (xy 18.050392 -144.684115)
			(xy 18.091583 -144.648421) (xy 18.137434 -144.618952) (xy 18.187013 -144.59631) (xy 18.23931 -144.580954)
			(xy 18.29326 -144.573199) (xy 18.320512 -144.572736) (xy 18.349288 -144.573223) (xy 18.406184 -144.581882)
			(xy 18.461135 -144.598986) (xy 18.512895 -144.624148) (xy 18.560289 -144.656798) (xy 18.581624 -144.676114)
			(xy 18.589498 -144.68348) (xy 18.60931 -144.690592) (xy 18.705576 -144.683226) (xy 18.724372 -144.67332)
			(xy 18.730976 -144.664938) (xy 18.749179 -144.642735) (xy 18.791119 -144.603525) (xy 18.838459 -144.571041)
			(xy 18.890131 -144.546016) (xy 18.944969 -144.529014) (xy 19.001735 -144.520419) (xy 19.030442 -144.519904)
			(xy 19.057695 -144.520339) (xy 19.111645 -144.528101) (xy 19.163941 -144.543462) (xy 19.21352 -144.566109)
			(xy 19.25937 -144.595581) (xy 19.30056 -144.631278) (xy 19.336251 -144.672473) (xy 19.365717 -144.718328)
			(xy 19.388357 -144.767909) (xy 19.40371 -144.820208) (xy 19.411465 -144.874159) (xy 19.41195 -144.901412)
			(xy 19.411476 -144.928314) (xy 19.403904 -144.981583) (xy 19.388925 -145.03326) (xy 19.366836 -145.082321)
			(xy 19.338076 -145.127793) (xy 19.303214 -145.168775) (xy 19.262942 -145.204455) (xy 19.240754 -145.219674)
			(xy 19.229832 -145.226786) (xy 19.217894 -145.249646) (xy 19.219926 -145.361914) (xy 19.23288 -145.384266)
			(xy 19.244056 -145.391124) (xy 19.267647 -145.406062) (xy 19.310602 -145.441736) (xy 19.347897 -145.483291)
			(xy 19.378737 -145.529838) (xy 19.402462 -145.580383) (xy 19.418566 -145.633847) (xy 19.426704 -145.689088)
			(xy 19.42719 -145.717006) (xy 19.426721 -145.743999) (xy 19.419116 -145.797446) (xy 19.404057 -145.849289)
			(xy 19.381845 -145.898494) (xy 19.352923 -145.944079) (xy 19.33575 -145.96491) (xy 19.328638 -145.973038)
			(xy 19.322542 -145.993612) (xy 19.333464 -146.078956) (xy 19.335269 -146.089493) (xy 19.346303 -146.107777)
			(xy 19.3548 -146.114262) (xy 19.376018 -146.129632) (xy 19.414469 -146.165218) (xy 19.447687 -146.205732)
			(xy 19.475047 -146.250413) (xy 19.496032 -146.298418) (xy 19.510249 -146.348843) (xy 19.517429 -146.40074)
			(xy 19.517868 -146.426936) (xy 19.517382 -146.454187) (xy 19.509626 -146.508135) (xy 19.494271 -146.56043)
			(xy 19.471629 -146.610007) (xy 19.442163 -146.655857) (xy 19.406472 -146.697048) (xy 19.365281 -146.732739)
			(xy 19.319431 -146.762205) (xy 19.269854 -146.784847) (xy 19.217559 -146.800202) (xy 19.163611 -146.807958)
			(xy 19.109109 -146.807958) (xy 19.055161 -146.800202) (xy 19.002866 -146.784847) (xy 18.953289 -146.762205)
			(xy 18.907439 -146.732739) (xy 18.866248 -146.697048) (xy 18.830557 -146.655857) (xy 18.801091 -146.610007)
			(xy 18.778449 -146.56043) (xy 18.763094 -146.508135) (xy 18.755338 -146.454187) (xy 18.754852 -146.426936)
			(xy 18.755335 -146.399943) (xy 18.762936 -146.346496) (xy 18.777991 -146.294653) (xy 18.8002 -146.245448)
			(xy 18.82912 -146.199863) (xy 18.846292 -146.179032) (xy 18.853404 -146.170904) (xy 18.8595 -146.15033)
			(xy 18.848578 -146.064986) (xy 18.846822 -146.054437) (xy 18.835755 -146.036156) (xy 18.827242 -146.02968)
			(xy 18.802936 -146.012074) (xy 18.75968 -145.970474) (xy 18.741136 -145.946876) (xy 18.735294 -145.939002)
			(xy 18.717768 -145.928588) (xy 18.627344 -145.91538) (xy 18.60804 -145.920206) (xy 18.600166 -145.926048)
			(xy 18.599912 -145.926048) (xy 18.575181 -145.943571) (xy 18.521324 -145.97137) (xy 18.463748 -145.990301)
			(xy 18.403902 -145.999887) (xy 18.373598 -146.00047) (xy 18.346343 -146.000046) (xy 18.292389 -145.992288)
			(xy 18.240088 -145.97693) (xy 18.190505 -145.954284) (xy 18.144651 -145.924813) (xy 18.103457 -145.889115)
			(xy 18.067763 -145.847917) (xy 18.038296 -145.802059) (xy 18.015656 -145.752474) (xy 18.000303 -145.700172)
			(xy 17.992551 -145.646217) (xy 17.99209 -145.618962) (xy 17.992513 -145.592928) (xy 17.999606 -145.541344)
			(xy 18.01364 -145.491201) (xy 18.034357 -145.443431) (xy 18.061371 -145.398917) (xy 18.077434 -145.378424)
			(xy 18.08318 -145.37067) (xy 18.088917 -145.352257) (xy 18.08861 -145.34261) (xy 18.08226 -145.262854)
			(xy 18.073624 -145.245074) (xy 18.066258 -145.238724) (xy 18.046611 -145.220544) (xy 18.012087 -145.179638)
			(xy 17.983617 -145.134309) (xy 17.961759 -145.085447) (xy 17.946943 -145.03401) (xy 17.939458 -144.981008)
			(xy 17.939004 -144.954244) (xy 12.206535 -144.954244) (xy 12.220582 -145.002082) (xy 12.228338 -145.056029)
			(xy 12.228338 -145.110531) (xy 12.220582 -145.164478) (xy 12.205227 -145.216772) (xy 12.182586 -145.266348)
			(xy 12.15312 -145.312198) (xy 12.117429 -145.353388) (xy 12.07624 -145.389079) (xy 12.03039 -145.418545)
			(xy 11.980814 -145.441186) (xy 11.92852 -145.456541) (xy 11.874573 -145.464298) (xy 11.847322 -145.464784)
			(xy 11.821008 -145.464307) (xy 11.76888 -145.457075) (xy 11.718237 -145.442758) (xy 11.670038 -145.421627)
			(xy 11.625194 -145.394083) (xy 11.584555 -145.360645) (xy 11.566398 -145.341594) (xy 11.55888 -145.334189)
			(xy 11.539597 -145.325667) (xy 11.52906 -145.325084) (xy 11.454384 -145.325084) (xy 11.443832 -145.325596)
			(xy 11.424538 -145.334144) (xy 11.417046 -145.341594) (xy 11.398909 -145.360668) (xy 11.358275 -145.394123)
			(xy 11.313431 -145.42168) (xy 11.265227 -145.442815) (xy 11.214576 -145.457129) (xy 11.162439 -145.464348)
			(xy 11.136122 -145.464784) (xy 11.108869 -145.464329) (xy 11.054917 -145.456572) (xy 11.002618 -145.441216)
			(xy 10.953038 -145.418573) (xy 10.907184 -145.389105) (xy 10.86599 -145.353411) (xy 10.830296 -145.312218)
			(xy 10.800828 -145.266364) (xy 10.778185 -145.216783) (xy 10.762828 -145.164485) (xy 10.755071 -145.110533)
			(xy 5.1054 -145.110533) (xy 5.1054 -146.91487) (xy 19.616164 -146.91487) (xy 19.620235 -146.859248)
			(xy 19.632361 -146.804811) (xy 19.652284 -146.75272) (xy 19.67958 -146.704085) (xy 19.713666 -146.659942)
			(xy 19.753815 -146.621233) (xy 19.799173 -146.588782) (xy 19.848773 -146.563281) (xy 19.901557 -146.545274)
			(xy 19.9564 -146.535144) (xy 20.012134 -146.533107) (xy 20.067571 -146.539207) (xy 20.121528 -146.553313)
			(xy 20.172857 -146.575125) (xy 20.220463 -146.604179) (xy 20.263331 -146.639854) (xy 20.300548 -146.681391)
			(xy 20.331321 -146.727904) (xy 20.354993 -146.778401) (xy 20.371061 -146.831808) (xy 20.379181 -146.886984)
			(xy 20.37969 -146.91487) (xy 20.379181 -146.942756) (xy 20.371061 -146.997932) (xy 20.354993 -147.051339)
			(xy 20.349787 -147.062444) (xy 20.994368 -147.062444) (xy 20.998439 -147.006822) (xy 21.010565 -146.952385)
			(xy 21.030488 -146.900294) (xy 21.057784 -146.851659) (xy 21.09187 -146.807516) (xy 21.132019 -146.768807)
			(xy 21.177377 -146.736356) (xy 21.226977 -146.710855) (xy 21.279761 -146.692848) (xy 21.334604 -146.682718)
			(xy 21.390338 -146.680681) (xy 21.445775 -146.686781) (xy 21.499732 -146.700887) (xy 21.551061 -146.722699)
			(xy 21.598667 -146.751753) (xy 21.641535 -146.787428) (xy 21.678752 -146.828965) (xy 21.709525 -146.875478)
			(xy 21.733197 -146.925975) (xy 21.749265 -146.979382) (xy 21.757385 -147.034558) (xy 21.757894 -147.062444)
			(xy 21.757385 -147.09033) (xy 21.749265 -147.145506) (xy 21.733197 -147.198913) (xy 21.709525 -147.24941)
			(xy 21.678752 -147.295923) (xy 21.641535 -147.33746) (xy 21.598667 -147.373135) (xy 21.551061 -147.402189)
			(xy 21.499732 -147.424001) (xy 21.445775 -147.438107) (xy 21.390338 -147.444207) (xy 21.334604 -147.44217)
			(xy 21.279761 -147.43204) (xy 21.226977 -147.414033) (xy 21.177377 -147.388532) (xy 21.132019 -147.356081)
			(xy 21.09187 -147.317372) (xy 21.057784 -147.273229) (xy 21.030488 -147.224594) (xy 21.010565 -147.172503)
			(xy 20.998439 -147.118066) (xy 20.994368 -147.062444) (xy 20.349787 -147.062444) (xy 20.331321 -147.101836)
			(xy 20.300548 -147.148349) (xy 20.263331 -147.189886) (xy 20.220463 -147.225561) (xy 20.172857 -147.254615)
			(xy 20.121528 -147.276427) (xy 20.067571 -147.290533) (xy 20.012134 -147.296633) (xy 19.9564 -147.294596)
			(xy 19.901557 -147.284466) (xy 19.848773 -147.266459) (xy 19.799173 -147.240958) (xy 19.753815 -147.208507)
			(xy 19.713666 -147.169798) (xy 19.67958 -147.125655) (xy 19.652284 -147.07702) (xy 19.632361 -147.024929)
			(xy 19.620235 -146.970492) (xy 19.616164 -146.91487) (xy 5.1054 -146.91487) (xy 5.1054 -147.657652)
			(xy 11.150566 -147.657652) (xy 11.150566 -147.603148) (xy 11.158323 -147.549198) (xy 11.173678 -147.496902)
			(xy 11.19632 -147.447323) (xy 11.225787 -147.401471) (xy 11.26148 -147.36028) (xy 11.302671 -147.324587)
			(xy 11.348523 -147.29512) (xy 11.398102 -147.272478) (xy 11.450398 -147.257123) (xy 11.504348 -147.249366)
			(xy 11.5316 -147.24888) (xy 11.557914 -147.249354) (xy 11.610042 -147.256588) (xy 11.660684 -147.270907)
			(xy 11.708883 -147.292038) (xy 11.753727 -147.319582) (xy 11.794367 -147.353019) (xy 11.812524 -147.37207)
			(xy 11.820039 -147.37948) (xy 11.839324 -147.388001) (xy 11.849862 -147.38858) (xy 11.924538 -147.38858)
			(xy 11.935086 -147.388037) (xy 11.954382 -147.379512) (xy 11.961876 -147.37207) (xy 11.981696 -147.351282)
			(xy 12.026468 -147.315307) (xy 12.076126 -147.286447) (xy 12.129548 -147.265354) (xy 12.185527 -147.252505)
			(xy 12.2428 -147.24819) (xy 12.300073 -147.252505) (xy 12.356052 -147.265354) (xy 12.409474 -147.286447)
			(xy 12.459132 -147.315307) (xy 12.503904 -147.351282) (xy 12.523724 -147.37207) (xy 12.531239 -147.37948)
			(xy 12.550524 -147.388001) (xy 12.561062 -147.38858) (xy 12.635738 -147.38858) (xy 12.646286 -147.388037)
			(xy 12.665582 -147.379512) (xy 12.673076 -147.37207) (xy 12.691244 -147.353027) (xy 12.731872 -147.31957)
			(xy 12.77671 -147.29201) (xy 12.824908 -147.27087) (xy 12.875553 -147.256549) (xy 12.927685 -147.249321)
			(xy 12.954 -147.24888) (xy 12.98125 -147.24939) (xy 13.035196 -147.257147) (xy 13.087489 -147.272501)
			(xy 13.137065 -147.295142) (xy 13.182914 -147.324607) (xy 13.224103 -147.360297) (xy 13.259793 -147.401486)
			(xy 13.289258 -147.447335) (xy 13.311899 -147.496911) (xy 13.327253 -147.549204) (xy 13.33501 -147.60315)
			(xy 13.33501 -147.65765) (xy 13.327253 -147.711596) (xy 13.311899 -147.763889) (xy 13.289258 -147.813465)
			(xy 13.259793 -147.859314) (xy 13.224103 -147.900503) (xy 13.182914 -147.936193) (xy 13.137065 -147.965658)
			(xy 13.087489 -147.988299) (xy 13.035196 -148.003653) (xy 12.98125 -148.01141) (xy 12.954 -148.011896)
			(xy 12.927686 -148.01143) (xy 12.875557 -148.004195) (xy 12.824915 -147.989876) (xy 12.776716 -147.968743)
			(xy 12.731872 -147.941197) (xy 12.691233 -147.907758) (xy 12.673076 -147.888706) (xy 12.665564 -147.881293)
			(xy 12.646277 -147.872775) (xy 12.635738 -147.872196) (xy 12.561062 -147.872196) (xy 12.550515 -147.872746)
			(xy 12.531219 -147.881267) (xy 12.523724 -147.888706) (xy 12.503904 -147.909494) (xy 12.459132 -147.945469)
			(xy 12.409474 -147.974329) (xy 12.356052 -147.995422) (xy 12.300073 -148.008271) (xy 12.2428 -148.012586)
			(xy 12.185527 -148.008271) (xy 12.129548 -147.995422) (xy 12.076126 -147.974329) (xy 12.026468 -147.945469)
			(xy 11.981696 -147.909494) (xy 11.961876 -147.888706) (xy 11.954364 -147.881293) (xy 11.935077 -147.872775)
			(xy 11.924538 -147.872196) (xy 11.849862 -147.872196) (xy 11.839315 -147.872746) (xy 11.820019 -147.881267)
			(xy 11.812524 -147.888706) (xy 11.794351 -147.907744) (xy 11.753725 -147.941203) (xy 11.708888 -147.968764)
			(xy 11.660691 -147.989905) (xy 11.610047 -148.004226) (xy 11.557915 -148.011455) (xy 11.5316 -148.011896)
			(xy 11.504348 -148.011434) (xy 11.450398 -148.003677) (xy 11.398102 -147.988322) (xy 11.348523 -147.96568)
			(xy 11.302671 -147.936213) (xy 11.26148 -147.90052) (xy 11.225787 -147.859329) (xy 11.19632 -147.813477)
			(xy 11.173678 -147.763898) (xy 11.158323 -147.711602) (xy 11.150566 -147.657652) (xy 5.1054 -147.657652)
			(xy 5.1054 -148.017738) (xy 15.977614 -148.017738) (xy 15.981685 -147.962116) (xy 15.993811 -147.907679)
			(xy 16.013734 -147.855588) (xy 16.04103 -147.806953) (xy 16.075116 -147.76281) (xy 16.115265 -147.724101)
			(xy 16.160623 -147.69165) (xy 16.210223 -147.666149) (xy 16.263007 -147.648142) (xy 16.31785 -147.638012)
			(xy 16.373584 -147.635975) (xy 16.429021 -147.642075) (xy 16.482978 -147.656181) (xy 16.534307 -147.677993)
			(xy 16.581913 -147.707047) (xy 16.623176 -147.741386) (xy 21.662134 -147.741386) (xy 21.666205 -147.685764)
			(xy 21.678331 -147.631327) (xy 21.698254 -147.579236) (xy 21.72555 -147.530601) (xy 21.759636 -147.486458)
			(xy 21.799785 -147.447749) (xy 21.845143 -147.415298) (xy 21.894743 -147.389797) (xy 21.947527 -147.37179)
			(xy 22.00237 -147.36166) (xy 22.058104 -147.359623) (xy 22.113541 -147.365723) (xy 22.167498 -147.379829)
			(xy 22.218827 -147.401641) (xy 22.266433 -147.430695) (xy 22.309301 -147.46637) (xy 22.346518 -147.507907)
			(xy 22.377291 -147.55442) (xy 22.400963 -147.604917) (xy 22.417031 -147.658324) (xy 22.425151 -147.7135)
			(xy 22.42566 -147.741386) (xy 22.425151 -147.769272) (xy 22.417031 -147.824448) (xy 22.400963 -147.877855)
			(xy 22.377291 -147.928352) (xy 22.346518 -147.974865) (xy 22.309301 -148.016402) (xy 22.266433 -148.052077)
			(xy 22.218827 -148.081131) (xy 22.167498 -148.102943) (xy 22.113541 -148.117049) (xy 22.058104 -148.123149)
			(xy 22.00237 -148.121112) (xy 21.947527 -148.110982) (xy 21.894743 -148.092975) (xy 21.845143 -148.067474)
			(xy 21.799785 -148.035023) (xy 21.759636 -147.996314) (xy 21.72555 -147.952171) (xy 21.698254 -147.903536)
			(xy 21.678331 -147.851445) (xy 21.666205 -147.797008) (xy 21.662134 -147.741386) (xy 16.623176 -147.741386)
			(xy 16.624781 -147.742722) (xy 16.661998 -147.784259) (xy 16.692771 -147.830772) (xy 16.716443 -147.881269)
			(xy 16.732511 -147.934676) (xy 16.740631 -147.989852) (xy 16.74114 -148.017738) (xy 16.740631 -148.045624)
			(xy 16.732511 -148.1008) (xy 16.716443 -148.154207) (xy 16.692771 -148.204704) (xy 16.661998 -148.251217)
			(xy 16.624781 -148.292754) (xy 16.581913 -148.328429) (xy 16.534307 -148.357483) (xy 16.482978 -148.379295)
			(xy 16.429021 -148.393401) (xy 16.373584 -148.399501) (xy 16.31785 -148.397464) (xy 16.263007 -148.387334)
			(xy 16.210223 -148.369327) (xy 16.160623 -148.343826) (xy 16.115265 -148.311375) (xy 16.075116 -148.272666)
			(xy 16.04103 -148.228523) (xy 16.013734 -148.179888) (xy 15.993811 -148.127797) (xy 15.981685 -148.07336)
			(xy 15.977614 -148.017738) (xy 5.1054 -148.017738) (xy 5.1054 -150.19585) (xy 11.150588 -150.19585)
			(xy 11.150588 -150.14135) (xy 11.158345 -150.087403) (xy 11.173699 -150.03511) (xy 11.19634 -149.985534)
			(xy 11.225805 -149.939685) (xy 11.261496 -149.898496) (xy 11.302685 -149.862805) (xy 11.348534 -149.83334)
			(xy 11.39811 -149.810699) (xy 11.450403 -149.795345) (xy 11.50435 -149.787588) (xy 11.5316 -149.787102)
			(xy 11.557914 -149.787569) (xy 11.610043 -149.794804) (xy 11.660685 -149.809123) (xy 11.708884 -149.830255)
			(xy 11.753728 -149.857802) (xy 11.794367 -149.89124) (xy 11.812524 -149.910292) (xy 11.820036 -149.917705)
			(xy 11.839323 -149.926223) (xy 11.849862 -149.926802) (xy 11.924538 -149.926802) (xy 11.935085 -149.926252)
			(xy 11.954381 -149.917732) (xy 11.961876 -149.910292) (xy 11.981696 -149.889504) (xy 12.026468 -149.853529)
			(xy 12.076126 -149.824669) (xy 12.129548 -149.803576) (xy 12.185527 -149.790727) (xy 12.2428 -149.786412)
			(xy 12.300073 -149.790727) (xy 12.356052 -149.803576) (xy 12.409474 -149.824669) (xy 12.459132 -149.853529)
			(xy 12.503904 -149.889504) (xy 12.523724 -149.910292) (xy 12.531236 -149.917705) (xy 12.550523 -149.926223)
			(xy 12.561062 -149.926802) (xy 12.635738 -149.926802) (xy 12.646285 -149.926252) (xy 12.665581 -149.917732)
			(xy 12.673076 -149.910292) (xy 12.691249 -149.891254) (xy 12.731875 -149.857795) (xy 12.776712 -149.830234)
			(xy 12.824909 -149.809093) (xy 12.875553 -149.794772) (xy 12.927685 -149.787543) (xy 12.954 -149.787102)
			(xy 12.981252 -149.787568) (xy 13.035201 -149.795325) (xy 13.087497 -149.81068) (xy 13.137076 -149.833322)
			(xy 13.182927 -149.862789) (xy 13.224119 -149.898481) (xy 13.259811 -149.939673) (xy 13.289278 -149.985524)
			(xy 13.31192 -150.035103) (xy 13.320244 -150.063454) (xy 15.838168 -150.063454) (xy 15.842239 -150.007832)
			(xy 15.854365 -149.953395) (xy 15.874288 -149.901304) (xy 15.901584 -149.852669) (xy 15.93567 -149.808526)
			(xy 15.975819 -149.769817) (xy 16.021177 -149.737366) (xy 16.070777 -149.711865) (xy 16.123561 -149.693858)
			(xy 16.178404 -149.683728) (xy 16.234138 -149.681691) (xy 16.289575 -149.687791) (xy 16.343532 -149.701897)
			(xy 16.394861 -149.723709) (xy 16.442467 -149.752763) (xy 16.485335 -149.788438) (xy 16.522552 -149.829975)
			(xy 16.553325 -149.876488) (xy 16.576997 -149.926985) (xy 16.593065 -149.980392) (xy 16.601185 -150.035568)
			(xy 16.601694 -150.063454) (xy 16.601185 -150.09134) (xy 16.593065 -150.146516) (xy 16.576997 -150.199923)
			(xy 16.553325 -150.25042) (xy 16.522552 -150.296933) (xy 16.485335 -150.33847) (xy 16.442467 -150.374145)
			(xy 16.394861 -150.403199) (xy 16.343532 -150.425011) (xy 16.289575 -150.439117) (xy 16.234138 -150.445217)
			(xy 16.178404 -150.44318) (xy 16.123561 -150.43305) (xy 16.070777 -150.415043) (xy 16.021177 -150.389542)
			(xy 15.975819 -150.357091) (xy 15.93567 -150.318382) (xy 15.901584 -150.274239) (xy 15.874288 -150.225604)
			(xy 15.854365 -150.173513) (xy 15.842239 -150.119076) (xy 15.838168 -150.063454) (xy 13.320244 -150.063454)
			(xy 13.327275 -150.087399) (xy 13.335032 -150.141348) (xy 13.335032 -150.195852) (xy 13.327275 -150.249801)
			(xy 13.31192 -150.302097) (xy 13.289278 -150.351676) (xy 13.259811 -150.397527) (xy 13.224119 -150.438719)
			(xy 13.182927 -150.474411) (xy 13.137076 -150.503878) (xy 13.087497 -150.52652) (xy 13.035201 -150.541875)
			(xy 12.981252 -150.549632) (xy 12.954 -150.550118) (xy 12.927686 -150.549645) (xy 12.875558 -150.54241)
			(xy 12.824916 -150.528092) (xy 12.776717 -150.506961) (xy 12.731873 -150.479416) (xy 12.691233 -150.445979)
			(xy 12.673076 -150.426928) (xy 12.665562 -150.419518) (xy 12.646276 -150.410997) (xy 12.635738 -150.410418)
			(xy 12.561062 -150.410418) (xy 12.550514 -150.410962) (xy 12.531218 -150.419486) (xy 12.523724 -150.426928)
			(xy 12.503904 -150.447716) (xy 12.459132 -150.483691) (xy 12.409474 -150.512551) (xy 12.356052 -150.533644)
			(xy 12.300073 -150.546493) (xy 12.2428 -150.550808) (xy 12.185527 -150.546493) (xy 12.129548 -150.533644)
			(xy 12.076126 -150.512551) (xy 12.026468 -150.483691) (xy 11.981696 -150.447716) (xy 11.961876 -150.426928)
			(xy 11.954362 -150.419518) (xy 11.935076 -150.410997) (xy 11.924538 -150.410418) (xy 11.849862 -150.410418)
			(xy 11.839314 -150.410962) (xy 11.820018 -150.419486) (xy 11.812524 -150.426928) (xy 11.794355 -150.44597)
			(xy 11.753728 -150.479428) (xy 11.70889 -150.506988) (xy 11.660692 -150.528128) (xy 11.610047 -150.542449)
			(xy 11.557915 -150.549677) (xy 11.5316 -150.550118) (xy 11.50435 -150.549612) (xy 11.450403 -150.541855)
			(xy 11.39811 -150.526501) (xy 11.348534 -150.50386) (xy 11.302685 -150.474395) (xy 11.261496 -150.438704)
			(xy 11.225805 -150.397515) (xy 11.19634 -150.351666) (xy 11.173699 -150.30209) (xy 11.158345 -150.249797)
			(xy 11.150588 -150.19585) (xy 5.1054 -150.19585) (xy 5.1054 -151.67102) (xy 15.793718 -151.67102)
			(xy 15.797789 -151.615398) (xy 15.809915 -151.560961) (xy 15.829838 -151.50887) (xy 15.857134 -151.460235)
			(xy 15.89122 -151.416092) (xy 15.931369 -151.377383) (xy 15.976727 -151.344932) (xy 16.026327 -151.319431)
			(xy 16.079111 -151.301424) (xy 16.133954 -151.291294) (xy 16.189688 -151.289257) (xy 16.245125 -151.295357)
			(xy 16.299082 -151.309463) (xy 16.350411 -151.331275) (xy 16.398017 -151.360329) (xy 16.440885 -151.396004)
			(xy 16.478102 -151.437541) (xy 16.508875 -151.484054) (xy 16.532547 -151.534551) (xy 16.548615 -151.587958)
			(xy 16.556735 -151.643134) (xy 16.557244 -151.67102) (xy 16.556771 -151.696928) (xy 16.809718 -151.696928)
			(xy 16.813789 -151.641306) (xy 16.825915 -151.586869) (xy 16.845838 -151.534778) (xy 16.873134 -151.486143)
			(xy 16.90722 -151.442) (xy 16.947369 -151.403291) (xy 16.992727 -151.37084) (xy 17.042327 -151.345339)
			(xy 17.095111 -151.327332) (xy 17.149954 -151.317202) (xy 17.205688 -151.315165) (xy 17.261125 -151.321265)
			(xy 17.315082 -151.335371) (xy 17.366411 -151.357183) (xy 17.414017 -151.386237) (xy 17.438493 -151.406606)
			(xy 18.036792 -151.406606) (xy 18.040863 -151.350984) (xy 18.052989 -151.296547) (xy 18.072912 -151.244456)
			(xy 18.100208 -151.195821) (xy 18.134294 -151.151678) (xy 18.174443 -151.112969) (xy 18.219801 -151.080518)
			(xy 18.269401 -151.055017) (xy 18.322185 -151.03701) (xy 18.377028 -151.02688) (xy 18.432762 -151.024843)
			(xy 18.488199 -151.030943) (xy 18.542156 -151.045049) (xy 18.593485 -151.066861) (xy 18.641091 -151.095915)
			(xy 18.683959 -151.13159) (xy 18.721176 -151.173127) (xy 18.751949 -151.21964) (xy 18.775621 -151.270137)
			(xy 18.791689 -151.323544) (xy 18.799809 -151.37872) (xy 18.800318 -151.406606) (xy 18.799809 -151.434492)
			(xy 18.791689 -151.489668) (xy 18.775621 -151.543075) (xy 18.757079 -151.582628) (xy 19.362418 -151.582628)
			(xy 19.366489 -151.527006) (xy 19.378615 -151.472569) (xy 19.398538 -151.420478) (xy 19.425834 -151.371843)
			(xy 19.45992 -151.3277) (xy 19.500069 -151.288991) (xy 19.545427 -151.25654) (xy 19.595027 -151.231039)
			(xy 19.647811 -151.213032) (xy 19.702654 -151.202902) (xy 19.758388 -151.200865) (xy 19.813825 -151.206965)
			(xy 19.867782 -151.221071) (xy 19.919111 -151.242883) (xy 19.966717 -151.271937) (xy 20.009585 -151.307612)
			(xy 20.046802 -151.349149) (xy 20.077575 -151.395662) (xy 20.101247 -151.446159) (xy 20.117315 -151.499566)
			(xy 20.125435 -151.554742) (xy 20.125698 -151.569166) (xy 20.873718 -151.569166) (xy 20.877789 -151.513544)
			(xy 20.889915 -151.459107) (xy 20.909838 -151.407016) (xy 20.937134 -151.358381) (xy 20.97122 -151.314238)
			(xy 21.011369 -151.275529) (xy 21.056727 -151.243078) (xy 21.106327 -151.217577) (xy 21.159111 -151.19957)
			(xy 21.213954 -151.18944) (xy 21.269688 -151.187403) (xy 21.325125 -151.193503) (xy 21.379082 -151.207609)
			(xy 21.430411 -151.229421) (xy 21.478017 -151.258475) (xy 21.520885 -151.29415) (xy 21.558102 -151.335687)
			(xy 21.588875 -151.3822) (xy 21.612547 -151.432697) (xy 21.628615 -151.486104) (xy 21.636735 -151.54128)
			(xy 21.637244 -151.569166) (xy 21.636735 -151.597052) (xy 21.628615 -151.652228) (xy 21.612547 -151.705635)
			(xy 21.588875 -151.756132) (xy 21.558102 -151.802645) (xy 21.520885 -151.844182) (xy 21.478017 -151.879857)
			(xy 21.430411 -151.908911) (xy 21.379082 -151.930723) (xy 21.325125 -151.944829) (xy 21.269688 -151.950929)
			(xy 21.213954 -151.948892) (xy 21.159111 -151.938762) (xy 21.106327 -151.920755) (xy 21.056727 -151.895254)
			(xy 21.011369 -151.862803) (xy 20.97122 -151.824094) (xy 20.937134 -151.779951) (xy 20.909838 -151.731316)
			(xy 20.889915 -151.679225) (xy 20.877789 -151.624788) (xy 20.873718 -151.569166) (xy 20.125698 -151.569166)
			(xy 20.125944 -151.582628) (xy 20.125435 -151.610514) (xy 20.117315 -151.66569) (xy 20.101247 -151.719097)
			(xy 20.077575 -151.769594) (xy 20.046802 -151.816107) (xy 20.009585 -151.857644) (xy 19.966717 -151.893319)
			(xy 19.919111 -151.922373) (xy 19.867782 -151.944185) (xy 19.813825 -151.958291) (xy 19.758388 -151.964391)
			(xy 19.702654 -151.962354) (xy 19.647811 -151.952224) (xy 19.595027 -151.934217) (xy 19.545427 -151.908716)
			(xy 19.500069 -151.876265) (xy 19.45992 -151.837556) (xy 19.425834 -151.793413) (xy 19.398538 -151.744778)
			(xy 19.378615 -151.692687) (xy 19.366489 -151.63825) (xy 19.362418 -151.582628) (xy 18.757079 -151.582628)
			(xy 18.751949 -151.593572) (xy 18.721176 -151.640085) (xy 18.683959 -151.681622) (xy 18.641091 -151.717297)
			(xy 18.593485 -151.746351) (xy 18.542156 -151.768163) (xy 18.488199 -151.782269) (xy 18.432762 -151.788369)
			(xy 18.377028 -151.786332) (xy 18.322185 -151.776202) (xy 18.269401 -151.758195) (xy 18.219801 -151.732694)
			(xy 18.174443 -151.700243) (xy 18.134294 -151.661534) (xy 18.100208 -151.617391) (xy 18.072912 -151.568756)
			(xy 18.052989 -151.516665) (xy 18.040863 -151.462228) (xy 18.036792 -151.406606) (xy 17.438493 -151.406606)
			(xy 17.456885 -151.421912) (xy 17.494102 -151.463449) (xy 17.524875 -151.509962) (xy 17.548547 -151.560459)
			(xy 17.564615 -151.613866) (xy 17.572735 -151.669042) (xy 17.573244 -151.696928) (xy 17.572735 -151.724814)
			(xy 17.564615 -151.77999) (xy 17.548547 -151.833397) (xy 17.524875 -151.883894) (xy 17.494102 -151.930407)
			(xy 17.456885 -151.971944) (xy 17.414017 -152.007619) (xy 17.366411 -152.036673) (xy 17.315082 -152.058485)
			(xy 17.261125 -152.072591) (xy 17.205688 -152.078691) (xy 17.149954 -152.076654) (xy 17.095111 -152.066524)
			(xy 17.042327 -152.048517) (xy 16.992727 -152.023016) (xy 16.947369 -151.990565) (xy 16.90722 -151.951856)
			(xy 16.873134 -151.907713) (xy 16.845838 -151.859078) (xy 16.825915 -151.806987) (xy 16.813789 -151.75255)
			(xy 16.809718 -151.696928) (xy 16.556771 -151.696928) (xy 16.556735 -151.698906) (xy 16.548615 -151.754082)
			(xy 16.532547 -151.807489) (xy 16.508875 -151.857986) (xy 16.478102 -151.904499) (xy 16.440885 -151.946036)
			(xy 16.398017 -151.981711) (xy 16.350411 -152.010765) (xy 16.299082 -152.032577) (xy 16.245125 -152.046683)
			(xy 16.189688 -152.052783) (xy 16.133954 -152.050746) (xy 16.079111 -152.040616) (xy 16.026327 -152.022609)
			(xy 15.976727 -151.997108) (xy 15.931369 -151.964657) (xy 15.89122 -151.925948) (xy 15.857134 -151.881805)
			(xy 15.829838 -151.83317) (xy 15.809915 -151.781079) (xy 15.797789 -151.726642) (xy 15.793718 -151.67102)
			(xy 5.1054 -151.67102) (xy 5.1054 -153.782522) (xy 14.777718 -153.782522) (xy 14.781789 -153.7269)
			(xy 14.793915 -153.672463) (xy 14.813838 -153.620372) (xy 14.841134 -153.571737) (xy 14.87522 -153.527594)
			(xy 14.915369 -153.488885) (xy 14.960727 -153.456434) (xy 15.010327 -153.430933) (xy 15.063111 -153.412926)
			(xy 15.117954 -153.402796) (xy 15.173688 -153.400759) (xy 15.229125 -153.406859) (xy 15.283082 -153.420965)
			(xy 15.334411 -153.442777) (xy 15.382017 -153.471831) (xy 15.424885 -153.507506) (xy 15.462102 -153.549043)
			(xy 15.492875 -153.595556) (xy 15.516547 -153.646053) (xy 15.532615 -153.69946) (xy 15.540735 -153.754636)
			(xy 15.541244 -153.782522) (xy 15.793718 -153.782522) (xy 15.797789 -153.7269) (xy 15.809915 -153.672463)
			(xy 15.829838 -153.620372) (xy 15.857134 -153.571737) (xy 15.89122 -153.527594) (xy 15.931369 -153.488885)
			(xy 15.976727 -153.456434) (xy 16.026327 -153.430933) (xy 16.079111 -153.412926) (xy 16.133954 -153.402796)
			(xy 16.189688 -153.400759) (xy 16.245125 -153.406859) (xy 16.299082 -153.420965) (xy 16.350411 -153.442777)
			(xy 16.398017 -153.471831) (xy 16.440885 -153.507506) (xy 16.478102 -153.549043) (xy 16.508875 -153.595556)
			(xy 16.532547 -153.646053) (xy 16.548615 -153.69946) (xy 16.556735 -153.754636) (xy 16.557244 -153.782522)
			(xy 16.556735 -153.810408) (xy 16.553587 -153.831798) (xy 16.809718 -153.831798) (xy 16.813789 -153.776176)
			(xy 16.825915 -153.721739) (xy 16.845838 -153.669648) (xy 16.873134 -153.621013) (xy 16.90722 -153.57687)
			(xy 16.947369 -153.538161) (xy 16.992727 -153.50571) (xy 17.042327 -153.480209) (xy 17.095111 -153.462202)
			(xy 17.149954 -153.452072) (xy 17.205688 -153.450035) (xy 17.261125 -153.456135) (xy 17.315082 -153.470241)
			(xy 17.366411 -153.492053) (xy 17.414017 -153.521107) (xy 17.456885 -153.556782) (xy 17.494102 -153.598319)
			(xy 17.524875 -153.644832) (xy 17.548547 -153.695329) (xy 17.564615 -153.748736) (xy 17.569587 -153.782522)
			(xy 19.857718 -153.782522) (xy 19.861789 -153.7269) (xy 19.873915 -153.672463) (xy 19.893838 -153.620372)
			(xy 19.921134 -153.571737) (xy 19.95522 -153.527594) (xy 19.995369 -153.488885) (xy 20.040727 -153.456434)
			(xy 20.090327 -153.430933) (xy 20.143111 -153.412926) (xy 20.197954 -153.402796) (xy 20.253688 -153.400759)
			(xy 20.309125 -153.406859) (xy 20.363082 -153.420965) (xy 20.414411 -153.442777) (xy 20.462017 -153.471831)
			(xy 20.504885 -153.507506) (xy 20.542102 -153.549043) (xy 20.572875 -153.595556) (xy 20.596547 -153.646053)
			(xy 20.612615 -153.69946) (xy 20.620735 -153.754636) (xy 20.621244 -153.782522) (xy 21.889718 -153.782522)
			(xy 21.893789 -153.7269) (xy 21.905915 -153.672463) (xy 21.925838 -153.620372) (xy 21.953134 -153.571737)
			(xy 21.98722 -153.527594) (xy 22.027369 -153.488885) (xy 22.072727 -153.456434) (xy 22.122327 -153.430933)
			(xy 22.175111 -153.412926) (xy 22.229954 -153.402796) (xy 22.285688 -153.400759) (xy 22.341125 -153.406859)
			(xy 22.395082 -153.420965) (xy 22.446411 -153.442777) (xy 22.494017 -153.471831) (xy 22.536885 -153.507506)
			(xy 22.574102 -153.549043) (xy 22.604875 -153.595556) (xy 22.628547 -153.646053) (xy 22.644615 -153.69946)
			(xy 22.652735 -153.754636) (xy 22.653244 -153.782522) (xy 22.652735 -153.810408) (xy 22.644615 -153.865584)
			(xy 22.628547 -153.918991) (xy 22.604875 -153.969488) (xy 22.574102 -154.016001) (xy 22.536885 -154.057538)
			(xy 22.494017 -154.093213) (xy 22.446411 -154.122267) (xy 22.395082 -154.144079) (xy 22.341125 -154.158185)
			(xy 22.285688 -154.164285) (xy 22.229954 -154.162248) (xy 22.175111 -154.152118) (xy 22.122327 -154.134111)
			(xy 22.072727 -154.10861) (xy 22.027369 -154.076159) (xy 21.98722 -154.03745) (xy 21.953134 -153.993307)
			(xy 21.925838 -153.944672) (xy 21.905915 -153.892581) (xy 21.893789 -153.838144) (xy 21.889718 -153.782522)
			(xy 20.621244 -153.782522) (xy 20.620735 -153.810408) (xy 20.612615 -153.865584) (xy 20.596547 -153.918991)
			(xy 20.572875 -153.969488) (xy 20.542102 -154.016001) (xy 20.504885 -154.057538) (xy 20.462017 -154.093213)
			(xy 20.414411 -154.122267) (xy 20.363082 -154.144079) (xy 20.309125 -154.158185) (xy 20.253688 -154.164285)
			(xy 20.197954 -154.162248) (xy 20.143111 -154.152118) (xy 20.090327 -154.134111) (xy 20.040727 -154.10861)
			(xy 19.995369 -154.076159) (xy 19.95522 -154.03745) (xy 19.921134 -153.993307) (xy 19.893838 -153.944672)
			(xy 19.873915 -153.892581) (xy 19.861789 -153.838144) (xy 19.857718 -153.782522) (xy 17.569587 -153.782522)
			(xy 17.572735 -153.803912) (xy 17.573244 -153.831798) (xy 17.572735 -153.859684) (xy 17.564615 -153.91486)
			(xy 17.548547 -153.968267) (xy 17.524875 -154.018764) (xy 17.494102 -154.065277) (xy 17.456885 -154.106814)
			(xy 17.414017 -154.142489) (xy 17.366411 -154.171543) (xy 17.315082 -154.193355) (xy 17.261125 -154.207461)
			(xy 17.205688 -154.213561) (xy 17.149954 -154.211524) (xy 17.095111 -154.201394) (xy 17.042327 -154.183387)
			(xy 16.992727 -154.157886) (xy 16.947369 -154.125435) (xy 16.90722 -154.086726) (xy 16.873134 -154.042583)
			(xy 16.845838 -153.993948) (xy 16.825915 -153.941857) (xy 16.813789 -153.88742) (xy 16.809718 -153.831798)
			(xy 16.553587 -153.831798) (xy 16.548615 -153.865584) (xy 16.532547 -153.918991) (xy 16.508875 -153.969488)
			(xy 16.478102 -154.016001) (xy 16.440885 -154.057538) (xy 16.398017 -154.093213) (xy 16.350411 -154.122267)
			(xy 16.299082 -154.144079) (xy 16.245125 -154.158185) (xy 16.189688 -154.164285) (xy 16.133954 -154.162248)
			(xy 16.079111 -154.152118) (xy 16.026327 -154.134111) (xy 15.976727 -154.10861) (xy 15.931369 -154.076159)
			(xy 15.89122 -154.03745) (xy 15.857134 -153.993307) (xy 15.829838 -153.944672) (xy 15.809915 -153.892581)
			(xy 15.797789 -153.838144) (xy 15.793718 -153.782522) (xy 15.541244 -153.782522) (xy 15.540735 -153.810408)
			(xy 15.532615 -153.865584) (xy 15.516547 -153.918991) (xy 15.492875 -153.969488) (xy 15.462102 -154.016001)
			(xy 15.424885 -154.057538) (xy 15.382017 -154.093213) (xy 15.334411 -154.122267) (xy 15.283082 -154.144079)
			(xy 15.229125 -154.158185) (xy 15.173688 -154.164285) (xy 15.117954 -154.162248) (xy 15.063111 -154.152118)
			(xy 15.010327 -154.134111) (xy 14.960727 -154.10861) (xy 14.915369 -154.076159) (xy 14.87522 -154.03745)
			(xy 14.841134 -153.993307) (xy 14.813838 -153.944672) (xy 14.793915 -153.892581) (xy 14.781789 -153.838144)
			(xy 14.777718 -153.782522) (xy 5.1054 -153.782522) (xy 5.1054 -155.212034) (xy 7.269224 -155.212034)
			(xy 7.273295 -155.156412) (xy 7.285421 -155.101975) (xy 7.305344 -155.049884) (xy 7.33264 -155.001249)
			(xy 7.366726 -154.957106) (xy 7.406875 -154.918397) (xy 7.452233 -154.885946) (xy 7.501833 -154.860445)
			(xy 7.554617 -154.842438) (xy 7.60946 -154.832308) (xy 7.665194 -154.830271) (xy 7.720631 -154.836371)
			(xy 7.774588 -154.850477) (xy 7.825917 -154.872289) (xy 7.873523 -154.901343) (xy 7.916391 -154.937018)
			(xy 7.953608 -154.978555) (xy 7.984381 -155.025068) (xy 8.008053 -155.075565) (xy 8.009144 -155.079192)
			(xy 9.86993 -155.079192) (xy 9.874001 -155.02357) (xy 9.886127 -154.969133) (xy 9.90605 -154.917042)
			(xy 9.933346 -154.868407) (xy 9.967432 -154.824264) (xy 10.007581 -154.785555) (xy 10.052939 -154.753104)
			(xy 10.102539 -154.727603) (xy 10.155323 -154.709596) (xy 10.210166 -154.699466) (xy 10.2659 -154.697429)
			(xy 10.321337 -154.703529) (xy 10.375294 -154.717635) (xy 10.426623 -154.739447) (xy 10.474229 -154.768501)
			(xy 10.517097 -154.804176) (xy 10.554314 -154.845713) (xy 10.585087 -154.892226) (xy 10.608759 -154.942723)
			(xy 10.624827 -154.99613) (xy 10.632947 -155.051306) (xy 10.633456 -155.079192) (xy 10.633391 -155.082748)
			(xy 11.19378 -155.082748) (xy 11.194219 -155.056433) (xy 11.201461 -155.004304) (xy 11.215786 -154.953661)
			(xy 11.236924 -154.905462) (xy 11.264474 -154.860619) (xy 11.297917 -154.81998) (xy 11.31697 -154.801824)
			(xy 11.324359 -154.794291) (xy 11.332892 -154.77502) (xy 11.33348 -154.764486) (xy 11.33348 -154.68981)
			(xy 11.332965 -154.679259) (xy 11.32442 -154.659963) (xy 11.31697 -154.652472) (xy 11.297902 -154.634329)
			(xy 11.264447 -154.593696) (xy 11.236891 -154.548853) (xy 11.215755 -154.50065) (xy 11.20144 -154.45)
			(xy 11.194217 -154.397865) (xy 11.19378 -154.371548) (xy 11.1943 -154.344297) (xy 11.20205 -154.290349)
			(xy 11.217399 -154.238053) (xy 11.240035 -154.188473) (xy 11.269497 -154.142621) (xy 11.305185 -154.101428)
			(xy 11.346372 -154.065733) (xy 11.392221 -154.036264) (xy 11.441796 -154.01362) (xy 11.49409 -153.998263)
			(xy 11.548037 -153.990504) (xy 11.575288 -153.99004) (xy 11.601602 -153.990503) (xy 11.653731 -153.997737)
			(xy 11.704375 -154.012056) (xy 11.752574 -154.033189) (xy 11.797417 -154.060737) (xy 11.838056 -154.094177)
			(xy 11.856212 -154.11323) (xy 11.863737 -154.120629) (xy 11.883014 -154.129157) (xy 11.89355 -154.12974)
			(xy 11.968226 -154.12974) (xy 11.978771 -154.129173) (xy 11.998066 -154.120663) (xy 12.005564 -154.11323)
			(xy 12.025384 -154.092442) (xy 12.070156 -154.056467) (xy 12.119814 -154.027607) (xy 12.173236 -154.006514)
			(xy 12.229215 -153.993665) (xy 12.286488 -153.98935) (xy 12.343761 -153.993665) (xy 12.39974 -154.006514)
			(xy 12.453162 -154.027607) (xy 12.50282 -154.056467) (xy 12.547592 -154.092442) (xy 12.567412 -154.11323)
			(xy 12.574937 -154.120629) (xy 12.594214 -154.129157) (xy 12.60475 -154.12974) (xy 12.679426 -154.12974)
			(xy 12.689971 -154.129173) (xy 12.709266 -154.120663) (xy 12.716764 -154.11323) (xy 12.736584 -154.092442)
			(xy 12.781356 -154.056467) (xy 12.831014 -154.027607) (xy 12.884436 -154.006514) (xy 12.940415 -153.993665)
			(xy 12.997688 -153.98935) (xy 13.054961 -153.993665) (xy 13.11094 -154.006514) (xy 13.164362 -154.027607)
			(xy 13.21402 -154.056467) (xy 13.258792 -154.092442) (xy 13.278612 -154.11323) (xy 13.286137 -154.120629)
			(xy 13.305414 -154.129157) (xy 13.31595 -154.12974) (xy 13.390626 -154.12974) (xy 13.401171 -154.129173)
			(xy 13.420466 -154.120663) (xy 13.427964 -154.11323) (xy 13.446101 -154.094156) (xy 13.486734 -154.060699)
			(xy 13.531578 -154.033142) (xy 13.579783 -154.012007) (xy 13.630434 -153.997694) (xy 13.682571 -153.990475)
			(xy 13.708888 -153.99004) (xy 13.736143 -153.990467) (xy 13.790097 -153.998223) (xy 13.842399 -154.01358)
			(xy 13.891982 -154.036225) (xy 13.937838 -154.065696) (xy 13.979032 -154.101394) (xy 14.014726 -154.142591)
			(xy 14.044193 -154.188449) (xy 14.066832 -154.238035) (xy 14.082184 -154.290338) (xy 14.089936 -154.344293)
			(xy 14.090396 -154.371548) (xy 14.089962 -154.397863) (xy 14.08272 -154.449993) (xy 14.068395 -154.500637)
			(xy 14.047256 -154.548835) (xy 14.019704 -154.593678) (xy 13.98626 -154.634316) (xy 13.967206 -154.652472)
			(xy 13.959816 -154.660003) (xy 13.951285 -154.679276) (xy 13.950696 -154.68981) (xy 13.950696 -154.764486)
			(xy 13.951221 -154.775036) (xy 13.959759 -154.794331) (xy 13.967206 -154.801824) (xy 13.986267 -154.819974)
			(xy 14.019724 -154.860605) (xy 14.047282 -154.905446) (xy 14.068419 -154.953648) (xy 14.082735 -155.004297)
			(xy 14.089958 -155.056432) (xy 14.090396 -155.082748) (xy 14.089967 -155.110001) (xy 14.082203 -155.163951)
			(xy 14.066842 -155.216248) (xy 14.044194 -155.265826) (xy 14.014722 -155.311677) (xy 13.979024 -155.352867)
			(xy 13.937829 -155.388558) (xy 13.891973 -155.418023) (xy 13.842392 -155.440663) (xy 13.790093 -155.456016)
			(xy 13.736141 -155.463771) (xy 13.708888 -155.464256) (xy 13.682573 -155.463811) (xy 13.630443 -155.456573)
			(xy 13.579799 -155.442251) (xy 13.5316 -155.421114) (xy 13.486757 -155.393564) (xy 13.446119 -155.36012)
			(xy 13.427964 -155.341066) (xy 13.420449 -155.333656) (xy 13.401164 -155.325134) (xy 13.390626 -155.324556)
			(xy 13.31595 -155.324556) (xy 13.305404 -155.325112) (xy 13.286109 -155.33363) (xy 13.278612 -155.341066)
			(xy 13.258792 -155.361854) (xy 13.21402 -155.397829) (xy 13.164362 -155.426689) (xy 13.11094 -155.447782)
			(xy 13.054961 -155.460631) (xy 12.997688 -155.464946) (xy 12.940415 -155.460631) (xy 12.884436 -155.447782)
			(xy 12.831014 -155.426689) (xy 12.781356 -155.397829) (xy 12.736584 -155.361854) (xy 12.716764 -155.341066)
			(xy 12.709249 -155.333656) (xy 12.689964 -155.325134) (xy 12.679426 -155.324556) (xy 12.60475 -155.324556)
			(xy 12.594204 -155.325112) (xy 12.574909 -155.33363) (xy 12.567412 -155.341066) (xy 12.547592 -155.361854)
			(xy 12.50282 -155.397829) (xy 12.453162 -155.426689) (xy 12.39974 -155.447782) (xy 12.343761 -155.460631)
			(xy 12.286488 -155.464946) (xy 12.229215 -155.460631) (xy 12.173236 -155.447782) (xy 12.119814 -155.426689)
			(xy 12.070156 -155.397829) (xy 12.025384 -155.361854) (xy 12.005564 -155.341066) (xy 11.998049 -155.333656)
			(xy 11.978764 -155.325134) (xy 11.968226 -155.324556) (xy 11.89355 -155.324556) (xy 11.883004 -155.325112)
			(xy 11.863709 -155.33363) (xy 11.856212 -155.341066) (xy 11.838057 -155.360121) (xy 11.797425 -155.393576)
			(xy 11.752585 -155.421133) (xy 11.704384 -155.442271) (xy 11.653737 -155.456589) (xy 11.601604 -155.463816)
			(xy 11.575288 -155.464256) (xy 11.548037 -155.463774) (xy 11.494089 -155.456017) (xy 11.441794 -155.440662)
			(xy 11.392216 -155.41802) (xy 11.346366 -155.388554) (xy 11.305176 -155.352862) (xy 11.269484 -155.311671)
			(xy 11.240018 -155.26582) (xy 11.217377 -155.216243) (xy 11.202022 -155.163947) (xy 11.194266 -155.109999)
			(xy 11.19378 -155.082748) (xy 10.633391 -155.082748) (xy 10.632947 -155.107078) (xy 10.624827 -155.162254)
			(xy 10.608759 -155.215661) (xy 10.585087 -155.266158) (xy 10.554314 -155.312671) (xy 10.517097 -155.354208)
			(xy 10.474229 -155.389883) (xy 10.426623 -155.418937) (xy 10.375294 -155.440749) (xy 10.321337 -155.454855)
			(xy 10.2659 -155.460955) (xy 10.210166 -155.458918) (xy 10.155323 -155.448788) (xy 10.102539 -155.430781)
			(xy 10.052939 -155.40528) (xy 10.007581 -155.372829) (xy 9.967432 -155.33412) (xy 9.933346 -155.289977)
			(xy 9.90605 -155.241342) (xy 9.886127 -155.189251) (xy 9.874001 -155.134814) (xy 9.86993 -155.079192)
			(xy 8.009144 -155.079192) (xy 8.024121 -155.128972) (xy 8.032241 -155.184148) (xy 8.03275 -155.212034)
			(xy 8.032241 -155.23992) (xy 8.024121 -155.295096) (xy 8.008053 -155.348503) (xy 7.984381 -155.399)
			(xy 7.953608 -155.445513) (xy 7.916391 -155.48705) (xy 7.873523 -155.522725) (xy 7.825917 -155.551779)
			(xy 7.774588 -155.573591) (xy 7.720631 -155.587697) (xy 7.665194 -155.593797) (xy 7.60946 -155.59176)
			(xy 7.554617 -155.58163) (xy 7.501833 -155.563623) (xy 7.452233 -155.538122) (xy 7.406875 -155.505671)
			(xy 7.366726 -155.466962) (xy 7.33264 -155.422819) (xy 7.305344 -155.374184) (xy 7.285421 -155.322093)
			(xy 7.273295 -155.267656) (xy 7.269224 -155.212034) (xy 5.1054 -155.212034) (xy 5.1054 -156.69387)
			(xy 8.887458 -156.69387) (xy 8.891529 -156.638248) (xy 8.903655 -156.583811) (xy 8.923578 -156.53172)
			(xy 8.950874 -156.483085) (xy 8.98496 -156.438942) (xy 9.025109 -156.400233) (xy 9.070467 -156.367782)
			(xy 9.120067 -156.342281) (xy 9.172851 -156.324274) (xy 9.227694 -156.314144) (xy 9.283428 -156.312107)
			(xy 9.338865 -156.318207) (xy 9.392822 -156.332313) (xy 9.444151 -156.354125) (xy 9.491757 -156.383179)
			(xy 9.534625 -156.418854) (xy 9.571842 -156.460391) (xy 9.602615 -156.506904) (xy 9.626287 -156.557401)
			(xy 9.642355 -156.610808) (xy 9.650475 -156.665984) (xy 9.650984 -156.69387) (xy 9.650475 -156.721756)
			(xy 9.642355 -156.776932) (xy 9.626287 -156.830339) (xy 9.602615 -156.880836) (xy 9.571842 -156.927349)
			(xy 9.534625 -156.968886) (xy 9.491757 -157.004561) (xy 9.444151 -157.033615) (xy 9.392822 -157.055427)
			(xy 9.338865 -157.069533) (xy 9.283428 -157.075633) (xy 9.227694 -157.073596) (xy 9.172851 -157.063466)
			(xy 9.120067 -157.045459) (xy 9.070467 -157.019958) (xy 9.025109 -156.987507) (xy 8.98496 -156.948798)
			(xy 8.950874 -156.904655) (xy 8.923578 -156.85602) (xy 8.903655 -156.803929) (xy 8.891529 -156.749492)
			(xy 8.887458 -156.69387) (xy 5.1054 -156.69387) (xy 5.1054 -157.812994) (xy 6.650226 -157.812994)
			(xy 6.654297 -157.757372) (xy 6.666423 -157.702935) (xy 6.686346 -157.650844) (xy 6.713642 -157.602209)
			(xy 6.747728 -157.558066) (xy 6.787877 -157.519357) (xy 6.833235 -157.486906) (xy 6.882835 -157.461405)
			(xy 6.935619 -157.443398) (xy 6.990462 -157.433268) (xy 7.046196 -157.431231) (xy 7.101633 -157.437331)
			(xy 7.15559 -157.451437) (xy 7.206919 -157.473249) (xy 7.254525 -157.502303) (xy 7.297393 -157.537978)
			(xy 7.33461 -157.579515) (xy 7.365383 -157.626028) (xy 7.375633 -157.647894) (xy 11.013948 -157.647894)
			(xy 11.014459 -157.62125) (xy 11.022984 -157.568649) (xy 11.039844 -157.518099) (xy 11.064602 -157.470913)
			(xy 11.096615 -157.428313) (xy 11.135053 -157.391407) (xy 11.156696 -157.37586) (xy 11.167989 -157.367504)
			(xy 11.185848 -157.34583) (xy 11.197132 -157.320114) (xy 11.20099 -157.292297) (xy 11.19713 -157.26448)
			(xy 11.185844 -157.238764) (xy 11.167984 -157.217092) (xy 11.156696 -157.208728) (xy 11.135107 -157.193114)
			(xy 11.096689 -157.156206) (xy 11.064685 -157.113615) (xy 11.039924 -157.066445) (xy 11.023047 -157.015914)
			(xy 11.014491 -156.963331) (xy 11.013948 -156.936694) (xy 11.014458 -156.910707) (xy 11.022588 -156.859372)
			(xy 11.038649 -156.809942) (xy 11.062245 -156.763632) (xy 11.092795 -156.721584) (xy 11.129546 -156.684833)
			(xy 11.171594 -156.654283) (xy 11.217904 -156.630687) (xy 11.267334 -156.614626) (xy 11.318669 -156.606496)
			(xy 11.370643 -156.606496) (xy 11.421978 -156.614626) (xy 11.471408 -156.630687) (xy 11.517718 -156.654283)
			(xy 11.559766 -156.684833) (xy 11.596517 -156.721584) (xy 11.627067 -156.763632) (xy 11.650663 -156.809942)
			(xy 11.666724 -156.859372) (xy 11.674854 -156.910707) (xy 11.675364 -156.936694) (xy 11.674839 -156.963337)
			(xy 11.666316 -157.015937) (xy 11.649459 -157.066487) (xy 11.624703 -157.113673) (xy 11.592693 -157.156273)
			(xy 11.554258 -157.193181) (xy 11.532616 -157.208728) (xy 11.521334 -157.217098) (xy 11.503473 -157.238768)
			(xy 11.492187 -157.264482) (xy 11.488327 -157.292297) (xy 11.492185 -157.320112) (xy 11.50347 -157.345826)
			(xy 11.521328 -157.367497) (xy 11.532616 -157.37586) (xy 11.554202 -157.391478) (xy 11.59262 -157.428386)
			(xy 11.624623 -157.470975) (xy 11.649384 -157.518145) (xy 11.666262 -157.568675) (xy 11.674821 -157.621257)
			(xy 11.675364 -157.647894) (xy 11.91387 -157.647894) (xy 11.914371 -157.62125) (xy 11.922897 -157.568648)
			(xy 11.939758 -157.518097) (xy 11.964518 -157.47091) (xy 11.996533 -157.428311) (xy 12.034973 -157.391406)
			(xy 12.056618 -157.37586) (xy 12.067909 -157.367503) (xy 12.085764 -157.345828) (xy 12.097046 -157.320112)
			(xy 12.100903 -157.292297) (xy 12.097044 -157.264481) (xy 12.08576 -157.238766) (xy 12.067904 -157.217092)
			(xy 12.056618 -157.208728) (xy 12.035012 -157.193137) (xy 11.996598 -157.156222) (xy 11.964599 -157.113625)
			(xy 11.939842 -157.066451) (xy 11.922968 -157.015917) (xy 11.914412 -156.963332) (xy 11.91387 -156.936694)
			(xy 11.91438 -156.910707) (xy 11.92251 -156.859372) (xy 11.938571 -156.809942) (xy 11.962167 -156.763632)
			(xy 11.992717 -156.721584) (xy 12.029468 -156.684833) (xy 12.071516 -156.654283) (xy 12.117826 -156.630687)
			(xy 12.167256 -156.614626) (xy 12.218591 -156.606496) (xy 12.270565 -156.606496) (xy 12.3219 -156.614626)
			(xy 12.37133 -156.630687) (xy 12.41764 -156.654283) (xy 12.459688 -156.684833) (xy 12.496439 -156.721584)
			(xy 12.526989 -156.763632) (xy 12.550585 -156.809942) (xy 12.566646 -156.859372) (xy 12.574776 -156.910707)
			(xy 12.575286 -156.936694) (xy 12.574752 -156.963337) (xy 12.56623 -157.015936) (xy 12.549373 -157.066485)
			(xy 12.52462 -157.113671) (xy 12.492611 -157.156271) (xy 12.454179 -157.19318) (xy 12.432538 -157.208728)
			(xy 12.421262 -157.217102) (xy 12.403416 -157.238776) (xy 12.392139 -157.264487) (xy 12.388282 -157.292297)
			(xy 12.392137 -157.320106) (xy 12.403412 -157.345818) (xy 12.421257 -157.367493) (xy 12.432538 -157.37586)
			(xy 12.454129 -157.391471) (xy 12.492545 -157.428381) (xy 12.524548 -157.470973) (xy 12.549308 -157.518144)
			(xy 12.566185 -157.568674) (xy 12.574743 -157.621257) (xy 12.575286 -157.647894) (xy 12.813792 -157.647894)
			(xy 12.814327 -157.621251) (xy 12.82285 -157.568653) (xy 12.839707 -157.518105) (xy 12.864461 -157.470918)
			(xy 12.896468 -157.428318) (xy 12.9349 -157.391409) (xy 12.95654 -157.37586) (xy 12.967829 -157.367502)
			(xy 12.98568 -157.345826) (xy 12.996959 -157.320111) (xy 13.000815 -157.292297) (xy 12.996957 -157.264483)
			(xy 12.985677 -157.238768) (xy 12.967824 -157.217094) (xy 12.95654 -157.208728) (xy 12.934939 -157.193131)
			(xy 12.896524 -157.156217) (xy 12.864523 -157.113623) (xy 12.839765 -157.066449) (xy 12.82289 -157.015916)
			(xy 12.814334 -156.963332) (xy 12.813792 -156.936694) (xy 12.814302 -156.910707) (xy 12.822432 -156.859372)
			(xy 12.838493 -156.809942) (xy 12.862089 -156.763632) (xy 12.892639 -156.721584) (xy 12.92939 -156.684833)
			(xy 12.971438 -156.654283) (xy 13.017748 -156.630687) (xy 13.067178 -156.614626) (xy 13.118513 -156.606496)
			(xy 13.170487 -156.606496) (xy 13.221822 -156.614626) (xy 13.271252 -156.630687) (xy 13.317562 -156.654283)
			(xy 13.35961 -156.684833) (xy 13.396361 -156.721584) (xy 13.426911 -156.763632) (xy 13.450507 -156.809942)
			(xy 13.466568 -156.859372) (xy 13.474698 -156.910707) (xy 13.475208 -156.936694) (xy 13.474664 -156.963336)
			(xy 13.466143 -157.015935) (xy 13.449288 -157.066482) (xy 13.424536 -157.113669) (xy 13.39253 -157.156269)
			(xy 13.3541 -157.193179) (xy 13.33246 -157.208728) (xy 13.321182 -157.217101) (xy 13.303332 -157.238773)
			(xy 13.292052 -157.264485) (xy 13.288195 -157.292297) (xy 13.29205 -157.320108) (xy 13.303328 -157.345821)
			(xy 13.321177 -157.367494) (xy 13.33246 -157.37586) (xy 13.354056 -157.391465) (xy 13.392471 -157.428377)
			(xy 13.424472 -157.47097) (xy 13.449231 -157.518142) (xy 13.466107 -157.568673) (xy 13.474665 -157.621257)
			(xy 13.475208 -157.647894) (xy 13.713968 -157.647894) (xy 13.71447 -157.62125) (xy 13.722996 -157.568648)
			(xy 13.739857 -157.518098) (xy 13.764617 -157.470911) (xy 13.796632 -157.428312) (xy 13.835071 -157.391406)
			(xy 13.856716 -157.37586) (xy 13.868008 -157.367503) (xy 13.885863 -157.345828) (xy 13.897145 -157.320112)
			(xy 13.901002 -157.292297) (xy 13.897143 -157.264481) (xy 13.885859 -157.238766) (xy 13.868002 -157.217092)
			(xy 13.856716 -157.208728) (xy 13.83511 -157.193138) (xy 13.796696 -157.156222) (xy 13.764697 -157.113626)
			(xy 13.73994 -157.066451) (xy 13.723066 -157.015917) (xy 13.71451 -156.963332) (xy 13.713968 -156.936694)
			(xy 13.714478 -156.910707) (xy 13.722608 -156.859372) (xy 13.738669 -156.809942) (xy 13.762265 -156.763632)
			(xy 13.792815 -156.721584) (xy 13.829566 -156.684833) (xy 13.871614 -156.654283) (xy 13.917924 -156.630687)
			(xy 13.967354 -156.614626) (xy 14.018689 -156.606496) (xy 14.070663 -156.606496) (xy 14.121998 -156.614626)
			(xy 14.171428 -156.630687) (xy 14.217738 -156.654283) (xy 14.259786 -156.684833) (xy 14.296537 -156.721584)
			(xy 14.327087 -156.763632) (xy 14.350683 -156.809942) (xy 14.366744 -156.859372) (xy 14.374874 -156.910707)
			(xy 14.375384 -156.936694) (xy 14.374851 -156.963337) (xy 14.366328 -157.015936) (xy 14.349472 -157.066485)
			(xy 14.324718 -157.113671) (xy 14.29271 -157.156271) (xy 14.254277 -157.19318) (xy 14.232636 -157.208728)
			(xy 14.221352 -157.217097) (xy 14.203488 -157.238766) (xy 14.192199 -157.26448) (xy 14.188338 -157.292297)
			(xy 14.192197 -157.320113) (xy 14.203484 -157.345828) (xy 14.221347 -157.367498) (xy 14.232636 -157.37586)
			(xy 14.254226 -157.391472) (xy 14.292643 -157.428382) (xy 14.324645 -157.470973) (xy 14.349405 -157.518144)
			(xy 14.366283 -157.568674) (xy 14.374841 -157.621257) (xy 14.375343 -157.645862) (xy 15.329408 -157.645862)
			(xy 15.329848 -157.619547) (xy 15.337088 -157.567417) (xy 15.351412 -157.516774) (xy 15.37255 -157.468575)
			(xy 15.400101 -157.423732) (xy 15.433544 -157.383094) (xy 15.452598 -157.364938) (xy 15.459984 -157.357404)
			(xy 15.468517 -157.338133) (xy 15.469108 -157.3276) (xy 15.469108 -157.252924) (xy 15.468577 -157.242375)
			(xy 15.460043 -157.223079) (xy 15.452598 -157.215586) (xy 15.433542 -157.197431) (xy 15.400085 -157.156801)
			(xy 15.372526 -157.111961) (xy 15.351388 -157.06376) (xy 15.337071 -157.013112) (xy 15.329846 -156.960978)
			(xy 15.329408 -156.934662) (xy 15.329894 -156.907411) (xy 15.33765 -156.853463) (xy 15.353005 -156.801168)
			(xy 15.375647 -156.751591) (xy 15.405113 -156.705741) (xy 15.440804 -156.66455) (xy 15.481995 -156.628859)
			(xy 15.527845 -156.599393) (xy 15.577422 -156.576751) (xy 15.629717 -156.561396) (xy 15.683665 -156.55364)
			(xy 15.738167 -156.55364) (xy 15.792115 -156.561396) (xy 15.84441 -156.576751) (xy 15.893987 -156.599393)
			(xy 15.939837 -156.628859) (xy 15.958582 -156.645101) (xy 17.31399 -156.645101) (xy 17.318305 -156.587829)
			(xy 17.331153 -156.531851) (xy 17.352244 -156.478429) (xy 17.381102 -156.428772) (xy 17.417075 -156.383999)
			(xy 17.437862 -156.364178) (xy 17.445269 -156.356661) (xy 17.453792 -156.337378) (xy 17.454372 -156.32684)
			(xy 17.454372 -156.252164) (xy 17.45383 -156.241616) (xy 17.445305 -156.22232) (xy 17.437862 -156.214826)
			(xy 17.418819 -156.196658) (xy 17.385362 -156.15603) (xy 17.357802 -156.111192) (xy 17.336662 -156.062994)
			(xy 17.322342 -156.012349) (xy 17.315113 -155.960217) (xy 17.314672 -155.933902) (xy 17.315158 -155.906651)
			(xy 17.322914 -155.852703) (xy 17.338269 -155.800408) (xy 17.360911 -155.750831) (xy 17.390377 -155.704981)
			(xy 17.426068 -155.66379) (xy 17.467259 -155.628099) (xy 17.513109 -155.598633) (xy 17.562686 -155.575991)
			(xy 17.614981 -155.560636) (xy 17.668929 -155.55288) (xy 17.723431 -155.55288) (xy 17.777379 -155.560636)
			(xy 17.829674 -155.575991) (xy 17.879251 -155.598633) (xy 17.925101 -155.628099) (xy 17.966292 -155.66379)
			(xy 18.001983 -155.704981) (xy 18.031449 -155.750831) (xy 18.054091 -155.800408) (xy 18.069446 -155.852703)
			(xy 18.077202 -155.906651) (xy 18.077688 -155.933902) (xy 18.077226 -155.960216) (xy 18.06999 -156.012345)
			(xy 18.055671 -156.062988) (xy 18.034537 -156.111187) (xy 18.00699 -156.15603) (xy 17.97355 -156.19667)
			(xy 17.954498 -156.214826) (xy 17.947083 -156.222336) (xy 17.938566 -156.241625) (xy 17.937988 -156.252164)
			(xy 17.937988 -156.32684) (xy 17.938539 -156.337387) (xy 17.947059 -156.356682) (xy 17.954498 -156.364178)
			(xy 17.975289 -156.383995) (xy 18.011266 -156.428768) (xy 18.040127 -156.478425) (xy 18.061221 -156.531848)
			(xy 18.07407 -156.587828) (xy 18.078386 -156.645101) (xy 18.07407 -156.702375) (xy 18.072934 -156.707322)
			(xy 20.379798 -156.707322) (xy 20.38411 -156.650054) (xy 20.396954 -156.594078) (xy 20.41804 -156.540659)
			(xy 20.446892 -156.491002) (xy 20.482858 -156.446229) (xy 20.503642 -156.426408) (xy 20.511034 -156.418878)
			(xy 20.519566 -156.399605) (xy 20.520152 -156.38907) (xy 20.520152 -156.314394) (xy 20.519654 -156.30384)
			(xy 20.511098 -156.284544) (xy 20.503642 -156.277056) (xy 20.484561 -156.258926) (xy 20.451108 -156.21829)
			(xy 20.423554 -156.173444) (xy 20.402421 -156.125238) (xy 20.388108 -156.074587) (xy 20.380888 -156.022449)
			(xy 20.380452 -155.996132) (xy 20.380938 -155.968881) (xy 20.388694 -155.914933) (xy 20.404049 -155.862638)
			(xy 20.426691 -155.813061) (xy 20.456157 -155.767211) (xy 20.491848 -155.72602) (xy 20.533039 -155.690329)
			(xy 20.578889 -155.660863) (xy 20.628466 -155.638221) (xy 20.680761 -155.622866) (xy 20.734709 -155.61511)
			(xy 20.789211 -155.61511) (xy 20.843159 -155.622866) (xy 20.895454 -155.638221) (xy 20.945031 -155.660863)
			(xy 20.990881 -155.690329) (xy 21.032072 -155.72602) (xy 21.067763 -155.767211) (xy 21.097229 -155.813061)
			(xy 21.119871 -155.862638) (xy 21.135226 -155.914933) (xy 21.142982 -155.968881) (xy 21.143468 -155.996132)
			(xy 21.143032 -156.022447) (xy 21.135792 -156.074577) (xy 21.121468 -156.125221) (xy 21.100329 -156.17342)
			(xy 21.072777 -156.218263) (xy 21.039333 -156.258901) (xy 21.020278 -156.277056) (xy 21.01289 -156.284589)
			(xy 21.004359 -156.303861) (xy 21.003768 -156.314394) (xy 21.003768 -156.38907) (xy 21.004309 -156.399618)
			(xy 21.012837 -156.418913) (xy 21.020278 -156.426408) (xy 21.0411 -156.446195) (xy 21.077078 -156.490971)
			(xy 21.10594 -156.540633) (xy 21.127033 -156.59406) (xy 21.139882 -156.650044) (xy 21.144195 -156.707322)
			(xy 21.139875 -156.764599) (xy 21.12702 -156.820582) (xy 21.105921 -156.874006) (xy 21.077054 -156.923665)
			(xy 21.04107 -156.968437) (xy 21.020278 -156.988256) (xy 21.01289 -156.995789) (xy 21.004359 -157.015061)
			(xy 21.003768 -157.025594) (xy 21.003768 -157.10027) (xy 21.004309 -157.110818) (xy 21.012837 -157.130113)
			(xy 21.020278 -157.137608) (xy 21.039326 -157.155771) (xy 21.072785 -157.196399) (xy 21.100345 -157.241237)
			(xy 21.121485 -157.289437) (xy 21.135804 -157.340083) (xy 21.143029 -157.392216) (xy 21.143468 -157.418532)
			(xy 21.142982 -157.445783) (xy 21.135226 -157.499731) (xy 21.119871 -157.552026) (xy 21.097229 -157.601603)
			(xy 21.067763 -157.647453) (xy 21.032072 -157.688644) (xy 20.990881 -157.724335) (xy 20.945031 -157.753801)
			(xy 20.895454 -157.776443) (xy 20.843159 -157.791798) (xy 20.789211 -157.799554) (xy 20.734709 -157.799554)
			(xy 20.680761 -157.791798) (xy 20.628466 -157.776443) (xy 20.578889 -157.753801) (xy 20.533039 -157.724335)
			(xy 20.491848 -157.688644) (xy 20.456157 -157.647453) (xy 20.426691 -157.601603) (xy 20.404049 -157.552026)
			(xy 20.388694 -157.499731) (xy 20.380938 -157.445783) (xy 20.380452 -157.418532) (xy 20.380857 -157.392216)
			(xy 20.388103 -157.340084) (xy 20.402433 -157.289439) (xy 20.423577 -157.24124) (xy 20.451135 -157.196398)
			(xy 20.484585 -157.155762) (xy 20.503642 -157.137608) (xy 20.511034 -157.130078) (xy 20.519566 -157.110805)
			(xy 20.520152 -157.10027) (xy 20.520152 -157.025594) (xy 20.519654 -157.01504) (xy 20.511098 -156.995744)
			(xy 20.503642 -156.988256) (xy 20.482888 -156.968403) (xy 20.446916 -156.923634) (xy 20.418059 -156.87398)
			(xy 20.396967 -156.820564) (xy 20.384116 -156.764589) (xy 20.379798 -156.707322) (xy 18.072934 -156.707322)
			(xy 18.06122 -156.758355) (xy 18.040126 -156.811777) (xy 18.011264 -156.861435) (xy 17.975287 -156.906207)
			(xy 17.954498 -156.926026) (xy 17.947083 -156.933536) (xy 17.938566 -156.952825) (xy 17.937988 -156.963364)
			(xy 17.937988 -157.03804) (xy 17.938539 -157.048587) (xy 17.947059 -157.067882) (xy 17.954498 -157.075378)
			(xy 17.973536 -157.093552) (xy 18.006994 -157.134177) (xy 18.034556 -157.179014) (xy 18.055697 -157.227211)
			(xy 18.070018 -157.277855) (xy 18.077247 -157.329987) (xy 18.077688 -157.356302) (xy 18.077202 -157.383553)
			(xy 18.069446 -157.437501) (xy 18.054091 -157.489796) (xy 18.031449 -157.539373) (xy 18.001983 -157.585223)
			(xy 17.966292 -157.626414) (xy 17.925101 -157.662105) (xy 17.879251 -157.691571) (xy 17.829674 -157.714213)
			(xy 17.777379 -157.729568) (xy 17.723431 -157.737324) (xy 17.668929 -157.737324) (xy 17.614981 -157.729568)
			(xy 17.562686 -157.714213) (xy 17.513109 -157.691571) (xy 17.467259 -157.662105) (xy 17.426068 -157.626414)
			(xy 17.390377 -157.585223) (xy 17.360911 -157.539373) (xy 17.338269 -157.489796) (xy 17.322914 -157.437501)
			(xy 17.315158 -157.383553) (xy 17.314672 -157.356302) (xy 17.31515 -157.329988) (xy 17.322384 -157.277861)
			(xy 17.336701 -157.227219) (xy 17.357832 -157.17902) (xy 17.385376 -157.134176) (xy 17.418812 -157.093535)
			(xy 17.437862 -157.075378) (xy 17.445269 -157.067861) (xy 17.453792 -157.048578) (xy 17.454372 -157.03804)
			(xy 17.454372 -156.963364) (xy 17.45383 -156.952816) (xy 17.445305 -156.93352) (xy 17.437862 -156.926026)
			(xy 17.417077 -156.906203) (xy 17.381104 -156.861431) (xy 17.352245 -156.811773) (xy 17.331154 -156.758352)
			(xy 17.318305 -156.702373) (xy 17.31399 -156.645101) (xy 15.958582 -156.645101) (xy 15.981028 -156.66455)
			(xy 16.016719 -156.705741) (xy 16.046185 -156.751591) (xy 16.068827 -156.801168) (xy 16.084182 -156.853463)
			(xy 16.091938 -156.907411) (xy 16.092424 -156.934662) (xy 16.09199 -156.960977) (xy 16.084747 -157.013107)
			(xy 16.070421 -157.06375) (xy 16.049282 -157.111948) (xy 16.021731 -157.156791) (xy 15.988288 -157.19743)
			(xy 15.969234 -157.215586) (xy 15.961841 -157.223115) (xy 15.953311 -157.242389) (xy 15.952724 -157.252924)
			(xy 15.952724 -157.3276) (xy 15.953233 -157.338152) (xy 15.961781 -157.357448) (xy 15.969234 -157.364938)
			(xy 15.988307 -157.383075) (xy 16.021762 -157.42371) (xy 16.049317 -157.468554) (xy 16.070453 -157.516758)
			(xy 16.084766 -157.567409) (xy 16.091987 -157.619545) (xy 16.092424 -157.645862) (xy 16.091938 -157.673113)
			(xy 16.084182 -157.727061) (xy 16.068827 -157.779356) (xy 16.046185 -157.828933) (xy 16.016719 -157.874783)
			(xy 15.981028 -157.915974) (xy 15.939837 -157.951665) (xy 15.893987 -157.981131) (xy 15.84441 -158.003773)
			(xy 15.792115 -158.019128) (xy 15.738167 -158.026884) (xy 15.683665 -158.026884) (xy 15.629717 -158.019128)
			(xy 15.577422 -158.003773) (xy 15.527845 -157.981131) (xy 15.481995 -157.951665) (xy 15.440804 -157.915974)
			(xy 15.405113 -157.874783) (xy 15.375647 -157.828933) (xy 15.353005 -157.779356) (xy 15.33765 -157.727061)
			(xy 15.329894 -157.673113) (xy 15.329408 -157.645862) (xy 14.375343 -157.645862) (xy 14.375384 -157.647894)
			(xy 14.374874 -157.673881) (xy 14.366744 -157.725216) (xy 14.350683 -157.774646) (xy 14.327087 -157.820956)
			(xy 14.296537 -157.863004) (xy 14.259786 -157.899755) (xy 14.217738 -157.930305) (xy 14.171428 -157.953901)
			(xy 14.121998 -157.969962) (xy 14.070663 -157.978092) (xy 14.018689 -157.978092) (xy 13.967354 -157.969962)
			(xy 13.917924 -157.953901) (xy 13.871614 -157.930305) (xy 13.829566 -157.899755) (xy 13.792815 -157.863004)
			(xy 13.762265 -157.820956) (xy 13.738669 -157.774646) (xy 13.722608 -157.725216) (xy 13.714478 -157.673881)
			(xy 13.713968 -157.647894) (xy 13.475208 -157.647894) (xy 13.474698 -157.673881) (xy 13.466568 -157.725216)
			(xy 13.450507 -157.774646) (xy 13.426911 -157.820956) (xy 13.396361 -157.863004) (xy 13.35961 -157.899755)
			(xy 13.317562 -157.930305) (xy 13.271252 -157.953901) (xy 13.221822 -157.969962) (xy 13.170487 -157.978092)
			(xy 13.118513 -157.978092) (xy 13.067178 -157.969962) (xy 13.017748 -157.953901) (xy 12.971438 -157.930305)
			(xy 12.92939 -157.899755) (xy 12.892639 -157.863004) (xy 12.862089 -157.820956) (xy 12.838493 -157.774646)
			(xy 12.822432 -157.725216) (xy 12.814302 -157.673881) (xy 12.813792 -157.647894) (xy 12.575286 -157.647894)
			(xy 12.574776 -157.673881) (xy 12.566646 -157.725216) (xy 12.550585 -157.774646) (xy 12.526989 -157.820956)
			(xy 12.496439 -157.863004) (xy 12.459688 -157.899755) (xy 12.41764 -157.930305) (xy 12.37133 -157.953901)
			(xy 12.3219 -157.969962) (xy 12.270565 -157.978092) (xy 12.218591 -157.978092) (xy 12.167256 -157.969962)
			(xy 12.117826 -157.953901) (xy 12.071516 -157.930305) (xy 12.029468 -157.899755) (xy 11.992717 -157.863004)
			(xy 11.962167 -157.820956) (xy 11.938571 -157.774646) (xy 11.92251 -157.725216) (xy 11.91438 -157.673881)
			(xy 11.91387 -157.647894) (xy 11.675364 -157.647894) (xy 11.674854 -157.673881) (xy 11.666724 -157.725216)
			(xy 11.650663 -157.774646) (xy 11.627067 -157.820956) (xy 11.596517 -157.863004) (xy 11.559766 -157.899755)
			(xy 11.517718 -157.930305) (xy 11.471408 -157.953901) (xy 11.421978 -157.969962) (xy 11.370643 -157.978092)
			(xy 11.318669 -157.978092) (xy 11.267334 -157.969962) (xy 11.217904 -157.953901) (xy 11.171594 -157.930305)
			(xy 11.129546 -157.899755) (xy 11.092795 -157.863004) (xy 11.062245 -157.820956) (xy 11.038649 -157.774646)
			(xy 11.022588 -157.725216) (xy 11.014458 -157.673881) (xy 11.013948 -157.647894) (xy 7.375633 -157.647894)
			(xy 7.389055 -157.676525) (xy 7.405123 -157.729932) (xy 7.413243 -157.785108) (xy 7.413752 -157.812994)
			(xy 7.413243 -157.84088) (xy 7.405123 -157.896056) (xy 7.389055 -157.949463) (xy 7.365383 -157.99996)
			(xy 7.33461 -158.046473) (xy 7.32214 -158.06039) (xy 8.839706 -158.06039) (xy 8.843777 -158.004768)
			(xy 8.855903 -157.950331) (xy 8.875826 -157.89824) (xy 8.903122 -157.849605) (xy 8.937208 -157.805462)
			(xy 8.977357 -157.766753) (xy 9.022715 -157.734302) (xy 9.072315 -157.708801) (xy 9.125099 -157.690794)
			(xy 9.179942 -157.680664) (xy 9.235676 -157.678627) (xy 9.291113 -157.684727) (xy 9.34507 -157.698833)
			(xy 9.396399 -157.720645) (xy 9.444005 -157.749699) (xy 9.486873 -157.785374) (xy 9.52409 -157.826911)
			(xy 9.554863 -157.873424) (xy 9.578535 -157.923921) (xy 9.594603 -157.977328) (xy 9.602723 -158.032504)
			(xy 9.603232 -158.06039) (xy 9.602723 -158.088276) (xy 9.594603 -158.143452) (xy 9.578535 -158.196859)
			(xy 9.554863 -158.247356) (xy 9.52409 -158.293869) (xy 9.486873 -158.335406) (xy 9.444005 -158.371081)
			(xy 9.396399 -158.400135) (xy 9.34507 -158.421947) (xy 9.291113 -158.436053) (xy 9.235676 -158.442153)
			(xy 9.179942 -158.440116) (xy 9.125099 -158.429986) (xy 9.072315 -158.411979) (xy 9.022715 -158.386478)
			(xy 8.977357 -158.354027) (xy 8.937208 -158.315318) (xy 8.903122 -158.271175) (xy 8.875826 -158.22254)
			(xy 8.855903 -158.170449) (xy 8.843777 -158.116012) (xy 8.839706 -158.06039) (xy 7.32214 -158.06039)
			(xy 7.297393 -158.08801) (xy 7.254525 -158.123685) (xy 7.206919 -158.152739) (xy 7.15559 -158.174551)
			(xy 7.101633 -158.188657) (xy 7.046196 -158.194757) (xy 6.990462 -158.19272) (xy 6.935619 -158.18259)
			(xy 6.882835 -158.164583) (xy 6.833235 -158.139082) (xy 6.787877 -158.106631) (xy 6.747728 -158.067922)
			(xy 6.713642 -158.023779) (xy 6.686346 -157.975144) (xy 6.666423 -157.923053) (xy 6.654297 -157.868616)
			(xy 6.650226 -157.812994) (xy 5.1054 -157.812994) (xy 5.1054 -158.828994) (xy 6.650226 -158.828994)
			(xy 6.654297 -158.773372) (xy 6.666423 -158.718935) (xy 6.686346 -158.666844) (xy 6.713642 -158.618209)
			(xy 6.747728 -158.574066) (xy 6.787877 -158.535357) (xy 6.833235 -158.502906) (xy 6.882835 -158.477405)
			(xy 6.935619 -158.459398) (xy 6.990462 -158.449268) (xy 7.046196 -158.447231) (xy 7.101633 -158.453331)
			(xy 7.15559 -158.467437) (xy 7.206919 -158.489249) (xy 7.254525 -158.518303) (xy 7.297393 -158.553978)
			(xy 7.33461 -158.595515) (xy 7.365383 -158.642028) (xy 7.389055 -158.692525) (xy 7.405123 -158.745932)
			(xy 7.406208 -158.753302) (xy 16.516602 -158.753302) (xy 16.520673 -158.69768) (xy 16.532799 -158.643243)
			(xy 16.552722 -158.591152) (xy 16.580018 -158.542517) (xy 16.614104 -158.498374) (xy 16.654253 -158.459665)
			(xy 16.699611 -158.427214) (xy 16.749211 -158.401713) (xy 16.801995 -158.383706) (xy 16.856838 -158.373576)
			(xy 16.912572 -158.371539) (xy 16.968009 -158.377639) (xy 17.021966 -158.391745) (xy 17.073295 -158.413557)
			(xy 17.120901 -158.442611) (xy 17.163769 -158.478286) (xy 17.200986 -158.519823) (xy 17.231759 -158.566336)
			(xy 17.255431 -158.616833) (xy 17.271499 -158.67024) (xy 17.279619 -158.725416) (xy 17.280128 -158.753302)
			(xy 17.279619 -158.781188) (xy 17.271499 -158.836364) (xy 17.255431 -158.889771) (xy 17.231759 -158.940268)
			(xy 17.200986 -158.986781) (xy 17.163769 -159.028318) (xy 17.120901 -159.063993) (xy 17.073295 -159.093047)
			(xy 17.021966 -159.114859) (xy 16.968009 -159.128965) (xy 16.912572 -159.135065) (xy 16.856838 -159.133028)
			(xy 16.801995 -159.122898) (xy 16.749211 -159.104891) (xy 16.699611 -159.07939) (xy 16.654253 -159.046939)
			(xy 16.614104 -159.00823) (xy 16.580018 -158.964087) (xy 16.552722 -158.915452) (xy 16.532799 -158.863361)
			(xy 16.520673 -158.808924) (xy 16.516602 -158.753302) (xy 7.406208 -158.753302) (xy 7.413243 -158.801108)
			(xy 7.413752 -158.828994) (xy 7.413243 -158.85688) (xy 7.405123 -158.912056) (xy 7.389055 -158.965463)
			(xy 7.365383 -159.01596) (xy 7.33461 -159.062473) (xy 7.297393 -159.10401) (xy 7.254525 -159.139685)
			(xy 7.206919 -159.168739) (xy 7.15559 -159.190551) (xy 7.101633 -159.204657) (xy 7.046196 -159.210757)
			(xy 6.990462 -159.20872) (xy 6.935619 -159.19859) (xy 6.882835 -159.180583) (xy 6.833235 -159.155082)
			(xy 6.787877 -159.122631) (xy 6.747728 -159.083922) (xy 6.713642 -159.039779) (xy 6.686346 -158.991144)
			(xy 6.666423 -158.939053) (xy 6.654297 -158.884616) (xy 6.650226 -158.828994) (xy 5.1054 -158.828994)
			(xy 5.1054 -159.439102) (xy 8.908032 -159.439102) (xy 8.912103 -159.38348) (xy 8.924229 -159.329043)
			(xy 8.944152 -159.276952) (xy 8.971448 -159.228317) (xy 9.005534 -159.184174) (xy 9.045683 -159.145465)
			(xy 9.091041 -159.113014) (xy 9.140641 -159.087513) (xy 9.193425 -159.069506) (xy 9.248268 -159.059376)
			(xy 9.304002 -159.057339) (xy 9.359439 -159.063439) (xy 9.413396 -159.077545) (xy 9.464725 -159.099357)
			(xy 9.512331 -159.128411) (xy 9.555199 -159.164086) (xy 9.592416 -159.205623) (xy 9.623189 -159.252136)
			(xy 9.646861 -159.302633) (xy 9.662929 -159.35604) (xy 9.671049 -159.411216) (xy 9.671558 -159.439102)
			(xy 9.671049 -159.466988) (xy 9.662929 -159.522164) (xy 9.660026 -159.531812) (xy 12.11275 -159.531812)
			(xy 12.116821 -159.47619) (xy 12.128947 -159.421753) (xy 12.14887 -159.369662) (xy 12.176166 -159.321027)
			(xy 12.210252 -159.276884) (xy 12.250401 -159.238175) (xy 12.295759 -159.205724) (xy 12.345359 -159.180223)
			(xy 12.398143 -159.162216) (xy 12.452986 -159.152086) (xy 12.50872 -159.150049) (xy 12.564157 -159.156149)
			(xy 12.618114 -159.170255) (xy 12.669443 -159.192067) (xy 12.717049 -159.221121) (xy 12.759917 -159.256796)
			(xy 12.797134 -159.298333) (xy 12.827907 -159.344846) (xy 12.851579 -159.395343) (xy 12.867647 -159.44875)
			(xy 12.873516 -159.488632) (xy 14.395956 -159.488632) (xy 14.400027 -159.43301) (xy 14.412153 -159.378573)
			(xy 14.432076 -159.326482) (xy 14.459372 -159.277847) (xy 14.493458 -159.233704) (xy 14.533607 -159.194995)
			(xy 14.578965 -159.162544) (xy 14.628565 -159.137043) (xy 14.681349 -159.119036) (xy 14.736192 -159.108906)
			(xy 14.791926 -159.106869) (xy 14.847363 -159.112969) (xy 14.90132 -159.127075) (xy 14.952649 -159.148887)
			(xy 15.000255 -159.177941) (xy 15.043123 -159.213616) (xy 15.08034 -159.255153) (xy 15.111113 -159.301666)
			(xy 15.134785 -159.352163) (xy 15.150853 -159.40557) (xy 15.158973 -159.460746) (xy 15.159482 -159.488632)
			(xy 15.158973 -159.516518) (xy 15.150853 -159.571694) (xy 15.134785 -159.625101) (xy 15.111113 -159.675598)
			(xy 15.08034 -159.722111) (xy 15.043123 -159.763648) (xy 15.000255 -159.799323) (xy 14.952649 -159.828377)
			(xy 14.90132 -159.850189) (xy 14.847363 -159.864295) (xy 14.791926 -159.870395) (xy 14.736192 -159.868358)
			(xy 14.681349 -159.858228) (xy 14.628565 -159.840221) (xy 14.578965 -159.81472) (xy 14.533607 -159.782269)
			(xy 14.493458 -159.74356) (xy 14.459372 -159.699417) (xy 14.432076 -159.650782) (xy 14.412153 -159.598691)
			(xy 14.400027 -159.544254) (xy 14.395956 -159.488632) (xy 12.873516 -159.488632) (xy 12.875767 -159.503926)
			(xy 12.876276 -159.531812) (xy 12.875767 -159.559698) (xy 12.867647 -159.614874) (xy 12.851579 -159.668281)
			(xy 12.827907 -159.718778) (xy 12.797134 -159.765291) (xy 12.759917 -159.806828) (xy 12.717049 -159.842503)
			(xy 12.669443 -159.871557) (xy 12.618114 -159.893369) (xy 12.564157 -159.907475) (xy 12.50872 -159.913575)
			(xy 12.452986 -159.911538) (xy 12.398143 -159.901408) (xy 12.345359 -159.883401) (xy 12.295759 -159.8579)
			(xy 12.250401 -159.825449) (xy 12.210252 -159.78674) (xy 12.176166 -159.742597) (xy 12.14887 -159.693962)
			(xy 12.128947 -159.641871) (xy 12.116821 -159.587434) (xy 12.11275 -159.531812) (xy 9.660026 -159.531812)
			(xy 9.646861 -159.575571) (xy 9.623189 -159.626068) (xy 9.592416 -159.672581) (xy 9.555199 -159.714118)
			(xy 9.512331 -159.749793) (xy 9.464725 -159.778847) (xy 9.413396 -159.800659) (xy 9.359439 -159.814765)
			(xy 9.304002 -159.820865) (xy 9.248268 -159.818828) (xy 9.193425 -159.808698) (xy 9.140641 -159.790691)
			(xy 9.091041 -159.76519) (xy 9.045683 -159.732739) (xy 9.005534 -159.69403) (xy 8.971448 -159.649887)
			(xy 8.944152 -159.601252) (xy 8.924229 -159.549161) (xy 8.912103 -159.494724) (xy 8.908032 -159.439102)
			(xy 5.1054 -159.439102) (xy 5.1054 -159.844994) (xy 6.650226 -159.844994) (xy 6.654297 -159.789372)
			(xy 6.666423 -159.734935) (xy 6.686346 -159.682844) (xy 6.713642 -159.634209) (xy 6.747728 -159.590066)
			(xy 6.787877 -159.551357) (xy 6.833235 -159.518906) (xy 6.882835 -159.493405) (xy 6.935619 -159.475398)
			(xy 6.990462 -159.465268) (xy 7.046196 -159.463231) (xy 7.101633 -159.469331) (xy 7.15559 -159.483437)
			(xy 7.206919 -159.505249) (xy 7.254525 -159.534303) (xy 7.297393 -159.569978) (xy 7.33461 -159.611515)
			(xy 7.365383 -159.658028) (xy 7.389055 -159.708525) (xy 7.405123 -159.761932) (xy 7.413243 -159.817108)
			(xy 7.413752 -159.844994) (xy 7.413243 -159.87288) (xy 7.405123 -159.928056) (xy 7.389055 -159.981463)
			(xy 7.365383 -160.03196) (xy 7.33461 -160.078473) (xy 7.297393 -160.12001) (xy 7.254525 -160.155685)
			(xy 7.206919 -160.184739) (xy 7.15559 -160.206551) (xy 7.101633 -160.220657) (xy 7.046196 -160.226757)
			(xy 6.990462 -160.22472) (xy 6.935619 -160.21459) (xy 6.882835 -160.196583) (xy 6.833235 -160.171082)
			(xy 6.787877 -160.138631) (xy 6.747728 -160.099922) (xy 6.713642 -160.055779) (xy 6.686346 -160.007144)
			(xy 6.666423 -159.955053) (xy 6.654297 -159.900616) (xy 6.650226 -159.844994) (xy 5.1054 -159.844994)
			(xy 5.1054 -160.965896) (xy 8.93775 -160.965896) (xy 8.941821 -160.910274) (xy 8.953947 -160.855837)
			(xy 8.97387 -160.803746) (xy 9.001166 -160.755111) (xy 9.035252 -160.710968) (xy 9.075401 -160.672259)
			(xy 9.120759 -160.639808) (xy 9.170359 -160.614307) (xy 9.223143 -160.5963) (xy 9.277986 -160.58617)
			(xy 9.33372 -160.584133) (xy 9.389157 -160.590233) (xy 9.443114 -160.604339) (xy 9.494443 -160.626151)
			(xy 9.542049 -160.655205) (xy 9.584917 -160.69088) (xy 9.622134 -160.732417) (xy 9.652907 -160.77893)
			(xy 9.676579 -160.829427) (xy 9.692647 -160.882834) (xy 9.700767 -160.93801) (xy 9.701239 -160.963864)
			(xy 10.32967 -160.963864) (xy 10.333741 -160.908242) (xy 10.345867 -160.853805) (xy 10.36579 -160.801714)
			(xy 10.393086 -160.753079) (xy 10.427172 -160.708936) (xy 10.467321 -160.670227) (xy 10.512679 -160.637776)
			(xy 10.562279 -160.612275) (xy 10.615063 -160.594268) (xy 10.669906 -160.584138) (xy 10.72564 -160.582101)
			(xy 10.781077 -160.588201) (xy 10.835034 -160.602307) (xy 10.886363 -160.624119) (xy 10.933969 -160.653173)
			(xy 10.976837 -160.688848) (xy 11.014054 -160.730385) (xy 11.044827 -160.776898) (xy 11.068499 -160.827395)
			(xy 11.084567 -160.880802) (xy 11.092687 -160.935978) (xy 11.093196 -160.963864) (xy 11.093103 -160.968944)
			(xy 11.601448 -160.968944) (xy 11.605519 -160.913322) (xy 11.617645 -160.858885) (xy 11.637568 -160.806794)
			(xy 11.664864 -160.758159) (xy 11.69895 -160.714016) (xy 11.739099 -160.675307) (xy 11.784457 -160.642856)
			(xy 11.834057 -160.617355) (xy 11.886841 -160.599348) (xy 11.941684 -160.589218) (xy 11.997418 -160.587181)
			(xy 12.052855 -160.593281) (xy 12.106812 -160.607387) (xy 12.158141 -160.629199) (xy 12.205747 -160.658253)
			(xy 12.248615 -160.693928) (xy 12.285832 -160.735465) (xy 12.316605 -160.781978) (xy 12.340277 -160.832475)
			(xy 12.356345 -160.885882) (xy 12.358738 -160.902142) (xy 13.38275 -160.902142) (xy 13.386821 -160.84652)
			(xy 13.398947 -160.792083) (xy 13.41887 -160.739992) (xy 13.446166 -160.691357) (xy 13.480252 -160.647214)
			(xy 13.520401 -160.608505) (xy 13.565759 -160.576054) (xy 13.615359 -160.550553) (xy 13.668143 -160.532546)
			(xy 13.722986 -160.522416) (xy 13.77872 -160.520379) (xy 13.834157 -160.526479) (xy 13.888114 -160.540585)
			(xy 13.939443 -160.562397) (xy 13.987049 -160.591451) (xy 14.029917 -160.627126) (xy 14.067134 -160.668663)
			(xy 14.097907 -160.715176) (xy 14.121579 -160.765673) (xy 14.137647 -160.81908) (xy 14.145767 -160.874256)
			(xy 14.146276 -160.902142) (xy 14.145767 -160.930028) (xy 14.137647 -160.985204) (xy 14.121579 -161.038611)
			(xy 14.097907 -161.089108) (xy 14.067134 -161.135621) (xy 14.029917 -161.177158) (xy 13.987049 -161.212833)
			(xy 13.939443 -161.241887) (xy 13.888114 -161.263699) (xy 13.834157 -161.277805) (xy 13.77872 -161.283905)
			(xy 13.722986 -161.281868) (xy 13.668143 -161.271738) (xy 13.615359 -161.253731) (xy 13.565759 -161.22823)
			(xy 13.520401 -161.195779) (xy 13.480252 -161.15707) (xy 13.446166 -161.112927) (xy 13.41887 -161.064292)
			(xy 13.398947 -161.012201) (xy 13.386821 -160.957764) (xy 13.38275 -160.902142) (xy 12.358738 -160.902142)
			(xy 12.364465 -160.941058) (xy 12.364974 -160.968944) (xy 12.364465 -160.99683) (xy 12.356345 -161.052006)
			(xy 12.340277 -161.105413) (xy 12.316605 -161.15591) (xy 12.285832 -161.202423) (xy 12.248615 -161.24396)
			(xy 12.205747 -161.279635) (xy 12.158141 -161.308689) (xy 12.106812 -161.330501) (xy 12.052855 -161.344607)
			(xy 11.997418 -161.350707) (xy 11.941684 -161.34867) (xy 11.886841 -161.33854) (xy 11.834057 -161.320533)
			(xy 11.784457 -161.295032) (xy 11.739099 -161.262581) (xy 11.69895 -161.223872) (xy 11.664864 -161.179729)
			(xy 11.637568 -161.131094) (xy 11.617645 -161.079003) (xy 11.605519 -161.024566) (xy 11.601448 -160.968944)
			(xy 11.093103 -160.968944) (xy 11.092687 -160.99175) (xy 11.084567 -161.046926) (xy 11.068499 -161.100333)
			(xy 11.044827 -161.15083) (xy 11.014054 -161.197343) (xy 10.976837 -161.23888) (xy 10.933969 -161.274555)
			(xy 10.886363 -161.303609) (xy 10.835034 -161.325421) (xy 10.781077 -161.339527) (xy 10.72564 -161.345627)
			(xy 10.669906 -161.34359) (xy 10.615063 -161.33346) (xy 10.562279 -161.315453) (xy 10.512679 -161.289952)
			(xy 10.467321 -161.257501) (xy 10.427172 -161.218792) (xy 10.393086 -161.174649) (xy 10.36579 -161.126014)
			(xy 10.345867 -161.073923) (xy 10.333741 -161.019486) (xy 10.32967 -160.963864) (xy 9.701239 -160.963864)
			(xy 9.701276 -160.965896) (xy 9.700767 -160.993782) (xy 9.692647 -161.048958) (xy 9.676579 -161.102365)
			(xy 9.652907 -161.152862) (xy 9.622134 -161.199375) (xy 9.584917 -161.240912) (xy 9.542049 -161.276587)
			(xy 9.494443 -161.305641) (xy 9.443114 -161.327453) (xy 9.389157 -161.341559) (xy 9.33372 -161.347659)
			(xy 9.277986 -161.345622) (xy 9.223143 -161.335492) (xy 9.170359 -161.317485) (xy 9.120759 -161.291984)
			(xy 9.075401 -161.259533) (xy 9.035252 -161.220824) (xy 9.001166 -161.176681) (xy 8.97387 -161.128046)
			(xy 8.953947 -161.075955) (xy 8.941821 -161.021518) (xy 8.93775 -160.965896) (xy 5.1054 -160.965896)
			(xy 5.1054 -163.114736) (xy 16.04975 -163.114736) (xy 16.053821 -163.059114) (xy 16.065947 -163.004677)
			(xy 16.08587 -162.952586) (xy 16.113166 -162.903951) (xy 16.147252 -162.859808) (xy 16.187401 -162.821099)
			(xy 16.232759 -162.788648) (xy 16.282359 -162.763147) (xy 16.335143 -162.74514) (xy 16.389986 -162.73501)
			(xy 16.44572 -162.732973) (xy 16.501157 -162.739073) (xy 16.555114 -162.753179) (xy 16.606443 -162.774991)
			(xy 16.654049 -162.804045) (xy 16.696917 -162.83972) (xy 16.734134 -162.881257) (xy 16.764907 -162.92777)
			(xy 16.788579 -162.978267) (xy 16.804647 -163.031674) (xy 16.812767 -163.08685) (xy 16.813276 -163.114736)
			(xy 16.812767 -163.142622) (xy 16.804647 -163.197798) (xy 16.788579 -163.251205) (xy 16.764907 -163.301702)
			(xy 16.734134 -163.348215) (xy 16.696917 -163.389752) (xy 16.654049 -163.425427) (xy 16.606443 -163.454481)
			(xy 16.555114 -163.476293) (xy 16.501157 -163.490399) (xy 16.44572 -163.496499) (xy 16.389986 -163.494462)
			(xy 16.335143 -163.484332) (xy 16.282359 -163.466325) (xy 16.232759 -163.440824) (xy 16.187401 -163.408373)
			(xy 16.147252 -163.369664) (xy 16.113166 -163.325521) (xy 16.08587 -163.276886) (xy 16.065947 -163.224795)
			(xy 16.053821 -163.170358) (xy 16.04975 -163.114736) (xy 5.1054 -163.114736) (xy 5.1054 -167.667178)
			(xy 18.392138 -167.667178) (xy 18.396209 -167.611556) (xy 18.408335 -167.557119) (xy 18.428258 -167.505028)
			(xy 18.455554 -167.456393) (xy 18.48964 -167.41225) (xy 18.529789 -167.373541) (xy 18.575147 -167.34109)
			(xy 18.624747 -167.315589) (xy 18.677531 -167.297582) (xy 18.732374 -167.287452) (xy 18.788108 -167.285415)
			(xy 18.843545 -167.291515) (xy 18.897502 -167.305621) (xy 18.948831 -167.327433) (xy 18.996437 -167.356487)
			(xy 19.039305 -167.392162) (xy 19.076522 -167.433699) (xy 19.107295 -167.480212) (xy 19.130967 -167.530709)
			(xy 19.147035 -167.584116) (xy 19.149914 -167.603678) (xy 21.168612 -167.603678) (xy 21.172683 -167.548056)
			(xy 21.184809 -167.493619) (xy 21.204732 -167.441528) (xy 21.232028 -167.392893) (xy 21.266114 -167.34875)
			(xy 21.306263 -167.310041) (xy 21.351621 -167.27759) (xy 21.401221 -167.252089) (xy 21.454005 -167.234082)
			(xy 21.508848 -167.223952) (xy 21.564582 -167.221915) (xy 21.620019 -167.228015) (xy 21.673976 -167.242121)
			(xy 21.69359 -167.250456) (xy 23.214741 -167.250456) (xy 23.214741 -167.195944) (xy 23.222499 -167.141988)
			(xy 23.237858 -167.089685) (xy 23.260504 -167.040101) (xy 23.289977 -166.994244) (xy 23.325676 -166.953049)
			(xy 23.366874 -166.917354) (xy 23.412734 -166.887886) (xy 23.462321 -166.865244) (xy 23.514625 -166.849891)
			(xy 23.568582 -166.842138) (xy 23.595838 -166.841678) (xy 23.625175 -166.842247) (xy 23.683154 -166.851246)
			(xy 23.739073 -166.869012) (xy 23.791615 -166.895126) (xy 23.839542 -166.928972) (xy 23.881725 -166.969754)
			(xy 23.899876 -166.992808) (xy 23.899876 -166.993062) (xy 23.907479 -167.001907) (xy 23.928364 -167.012232)
			(xy 23.940008 -167.012874) (xy 24.032718 -167.013382) (xy 24.054054 -167.002968) (xy 24.061166 -166.99357)
			(xy 24.070432 -166.981847) (xy 24.090519 -166.959723) (xy 24.101298 -166.949374) (xy 24.101552 -166.94912)
			(xy 24.108437 -166.941841) (xy 24.116552 -166.923549) (xy 24.1173 -166.91356) (xy 24.119078 -166.830502)
			(xy 24.111712 -166.811706) (xy 24.104346 -166.80434) (xy 24.08411 -166.782802) (xy 24.049802 -166.734686)
			(xy 24.023324 -166.681855) (xy 24.005311 -166.625574) (xy 23.996191 -166.567187) (xy 23.995634 -166.53764)
			(xy 23.99612 -166.510389) (xy 24.003876 -166.456441) (xy 24.019231 -166.404146) (xy 24.041873 -166.354569)
			(xy 24.071339 -166.308719) (xy 24.10703 -166.267528) (xy 24.148221 -166.231837) (xy 24.194071 -166.202371)
			(xy 24.243648 -166.179729) (xy 24.295943 -166.164374) (xy 24.349891 -166.156618) (xy 24.404393 -166.156618)
			(xy 24.458341 -166.164374) (xy 24.510636 -166.179729) (xy 24.560213 -166.202371) (xy 24.606063 -166.231837)
			(xy 24.647254 -166.267528) (xy 24.682945 -166.308719) (xy 24.712411 -166.354569) (xy 24.735053 -166.404146)
			(xy 24.750408 -166.456441) (xy 24.758164 -166.510389) (xy 24.75865 -166.53764) (xy 24.758194 -166.56356)
			(xy 24.751159 -166.614922) (xy 24.737239 -166.664858) (xy 24.716688 -166.712452) (xy 24.689886 -166.756826)
			(xy 24.657325 -166.797165) (xy 24.638762 -166.815262) (xy 24.638508 -166.815516) (xy 24.631617 -166.82279)
			(xy 24.623503 -166.841085) (xy 24.62276 -166.851076) (xy 24.620982 -166.934134) (xy 24.628348 -166.95293)
			(xy 24.635714 -166.960296) (xy 24.655977 -166.981809) (xy 24.690279 -167.029933) (xy 24.716751 -167.08277)
			(xy 24.734758 -167.139057) (xy 24.743871 -167.197447) (xy 24.744426 -167.226996) (xy 24.743919 -167.254246)
			(xy 24.736163 -167.308192) (xy 24.720809 -167.360486) (xy 24.69817 -167.410062) (xy 24.668706 -167.455911)
			(xy 24.633017 -167.497101) (xy 24.591829 -167.532793) (xy 24.545981 -167.562259) (xy 24.496406 -167.584902)
			(xy 24.444114 -167.600258) (xy 24.390168 -167.608017) (xy 24.362918 -167.608504) (xy 24.33358 -167.607974)
			(xy 24.275599 -167.598967) (xy 24.219678 -167.581194) (xy 24.167136 -167.555073) (xy 24.119211 -167.52122)
			(xy 24.07703 -167.480431) (xy 24.05888 -167.457374) (xy 24.05888 -167.45712) (xy 24.0513 -167.448252)
			(xy 24.030398 -167.437941) (xy 24.018748 -167.437308) (xy 23.926038 -167.4368) (xy 23.904702 -167.447214)
			(xy 23.89759 -167.456612) (xy 23.879385 -167.479219) (xy 23.837332 -167.519221) (xy 23.789705 -167.552392)
			(xy 23.737602 -167.577965) (xy 23.682228 -167.595351) (xy 23.624858 -167.604149) (xy 23.595838 -167.604694)
			(xy 23.568582 -167.604262) (xy 23.514625 -167.596509) (xy 23.462321 -167.581156) (xy 23.412734 -167.558514)
			(xy 23.366874 -167.529046) (xy 23.325676 -167.493351) (xy 23.289977 -167.452156) (xy 23.260504 -167.406299)
			(xy 23.237858 -167.356715) (xy 23.222499 -167.304412) (xy 23.214741 -167.250456) (xy 21.69359 -167.250456)
			(xy 21.725305 -167.263933) (xy 21.772911 -167.292987) (xy 21.815779 -167.328662) (xy 21.852996 -167.370199)
			(xy 21.883769 -167.416712) (xy 21.907441 -167.467209) (xy 21.923509 -167.520616) (xy 21.931629 -167.575792)
			(xy 21.932138 -167.603678) (xy 21.931629 -167.631564) (xy 21.923509 -167.68674) (xy 21.907441 -167.740147)
			(xy 21.883769 -167.790644) (xy 21.852996 -167.837157) (xy 21.815779 -167.878694) (xy 21.772911 -167.914369)
			(xy 21.725305 -167.943423) (xy 21.673976 -167.965235) (xy 21.620019 -167.979341) (xy 21.564582 -167.985441)
			(xy 21.508848 -167.983404) (xy 21.454005 -167.973274) (xy 21.401221 -167.955267) (xy 21.351621 -167.929766)
			(xy 21.306263 -167.897315) (xy 21.266114 -167.858606) (xy 21.232028 -167.814463) (xy 21.204732 -167.765828)
			(xy 21.184809 -167.713737) (xy 21.172683 -167.6593) (xy 21.168612 -167.603678) (xy 19.149914 -167.603678)
			(xy 19.155155 -167.639292) (xy 19.155664 -167.667178) (xy 19.155155 -167.695064) (xy 19.147035 -167.75024)
			(xy 19.130967 -167.803647) (xy 19.107295 -167.854144) (xy 19.076522 -167.900657) (xy 19.039305 -167.942194)
			(xy 18.996437 -167.977869) (xy 18.948831 -168.006923) (xy 18.897502 -168.028735) (xy 18.843545 -168.042841)
			(xy 18.788108 -168.048941) (xy 18.732374 -168.046904) (xy 18.677531 -168.036774) (xy 18.624747 -168.018767)
			(xy 18.575147 -167.993266) (xy 18.529789 -167.960815) (xy 18.48964 -167.922106) (xy 18.455554 -167.877963)
			(xy 18.428258 -167.829328) (xy 18.408335 -167.777237) (xy 18.396209 -167.7228) (xy 18.392138 -167.667178)
			(xy 5.1054 -167.667178) (xy 5.1054 -168.417063) (xy 8.583373 -168.417063) (xy 8.583373 -168.362557)
			(xy 8.59113 -168.308606) (xy 8.606487 -168.256307) (xy 8.629129 -168.206727) (xy 8.658598 -168.160873)
			(xy 8.694292 -168.11968) (xy 8.735485 -168.083987) (xy 8.781339 -168.054518) (xy 8.830919 -168.031876)
			(xy 8.883217 -168.01652) (xy 8.937169 -168.008763) (xy 8.964422 -168.0083) (xy 8.991897 -168.008773)
			(xy 9.046277 -168.016668) (xy 9.09896 -168.032292) (xy 9.148852 -168.055319) (xy 9.19492 -168.085273)
			(xy 9.215882 -168.103042) (xy 9.223155 -168.108845) (xy 9.240617 -168.115223) (xy 9.249918 -168.115488)
			(xy 9.32815 -168.114218) (xy 9.345422 -168.107106) (xy 9.35228 -168.100756) (xy 9.373594 -168.08147)
			(xy 9.420959 -168.048905) (xy 9.472674 -168.023815) (xy 9.527568 -168.006768) (xy 9.584398 -167.99815)
			(xy 9.613138 -167.997632) (xy 9.640391 -167.998095) (xy 9.694342 -168.005852) (xy 9.74664 -168.021208)
			(xy 9.796221 -168.04385) (xy 9.842074 -168.073318) (xy 9.883267 -168.109012) (xy 9.918961 -168.150204)
			(xy 9.948429 -168.196058) (xy 9.971072 -168.245638) (xy 9.986428 -168.297936) (xy 9.994185 -168.351887)
			(xy 9.994185 -168.406393) (xy 9.986428 -168.460344) (xy 9.971072 -168.512642) (xy 9.948429 -168.562222)
			(xy 9.918961 -168.608076) (xy 9.883267 -168.649268) (xy 9.842074 -168.684962) (xy 9.796221 -168.71443)
			(xy 9.74664 -168.737072) (xy 9.694342 -168.752428) (xy 9.640391 -168.760185) (xy 9.613138 -168.760648)
			(xy 9.585664 -168.760152) (xy 9.531284 -168.752264) (xy 9.478601 -168.736647) (xy 9.428708 -168.713624)
			(xy 9.38264 -168.683673) (xy 9.361678 -168.665906) (xy 9.354383 -168.660134) (xy 9.336938 -168.653736)
			(xy 9.327642 -168.65346) (xy 9.24941 -168.65473) (xy 9.232138 -168.661842) (xy 9.22528 -168.668192)
			(xy 9.203948 -168.687457) (xy 9.156587 -168.720023) (xy 9.104877 -168.745116) (xy 9.049987 -168.762168)
			(xy 9.008124 -168.768522) (xy 23.884888 -168.768522) (xy 23.888959 -168.7129) (xy 23.901085 -168.658463)
			(xy 23.921008 -168.606372) (xy 23.948304 -168.557737) (xy 23.98239 -168.513594) (xy 24.022539 -168.474885)
			(xy 24.067897 -168.442434) (xy 24.117497 -168.416933) (xy 24.170281 -168.398926) (xy 24.225124 -168.388796)
			(xy 24.280858 -168.386759) (xy 24.336295 -168.392859) (xy 24.390252 -168.406965) (xy 24.441581 -168.428777)
			(xy 24.489187 -168.457831) (xy 24.532055 -168.493506) (xy 24.569272 -168.535043) (xy 24.600045 -168.581556)
			(xy 24.623717 -168.632053) (xy 24.639785 -168.68546) (xy 24.647905 -168.740636) (xy 24.648414 -168.768522)
			(xy 24.647905 -168.796408) (xy 24.639785 -168.851584) (xy 24.623717 -168.904991) (xy 24.600045 -168.955488)
			(xy 24.569272 -169.002001) (xy 24.532055 -169.043538) (xy 24.489187 -169.079213) (xy 24.441581 -169.108267)
			(xy 24.390252 -169.130079) (xy 24.336295 -169.144185) (xy 24.280858 -169.150285) (xy 24.225124 -169.148248)
			(xy 24.170281 -169.138118) (xy 24.117497 -169.120111) (xy 24.067897 -169.09461) (xy 24.022539 -169.062159)
			(xy 23.98239 -169.02345) (xy 23.948304 -168.979307) (xy 23.921008 -168.930672) (xy 23.901085 -168.878581)
			(xy 23.888959 -168.824144) (xy 23.884888 -168.768522) (xy 9.008124 -168.768522) (xy 8.993161 -168.770793)
			(xy 8.964422 -168.771316) (xy 8.937169 -168.770857) (xy 8.883217 -168.7631) (xy 8.830919 -168.747744)
			(xy 8.781339 -168.725102) (xy 8.735485 -168.695633) (xy 8.694292 -168.65994) (xy 8.658598 -168.618747)
			(xy 8.629129 -168.572893) (xy 8.606487 -168.523313) (xy 8.59113 -168.471014) (xy 8.583373 -168.417063)
			(xy 5.1054 -168.417063) (xy 5.1054 -169.517314) (xy 19.694904 -169.517314) (xy 19.698975 -169.461692)
			(xy 19.711101 -169.407255) (xy 19.731024 -169.355164) (xy 19.75832 -169.306529) (xy 19.792406 -169.262386)
			(xy 19.832555 -169.223677) (xy 19.877913 -169.191226) (xy 19.927513 -169.165725) (xy 19.980297 -169.147718)
			(xy 20.03514 -169.137588) (xy 20.090874 -169.135551) (xy 20.146311 -169.141651) (xy 20.200268 -169.155757)
			(xy 20.251597 -169.177569) (xy 20.299203 -169.206623) (xy 20.342071 -169.242298) (xy 20.379288 -169.283835)
			(xy 20.410061 -169.330348) (xy 20.433733 -169.380845) (xy 20.449801 -169.434252) (xy 20.457921 -169.489428)
			(xy 20.45843 -169.517314) (xy 20.457921 -169.5452) (xy 20.449801 -169.600376) (xy 20.433733 -169.653783)
			(xy 20.410061 -169.70428) (xy 20.379288 -169.750793) (xy 20.342071 -169.79233) (xy 20.299203 -169.828005)
			(xy 20.251597 -169.857059) (xy 20.200268 -169.878871) (xy 20.146311 -169.892977) (xy 20.090874 -169.899077)
			(xy 20.03514 -169.89704) (xy 19.980297 -169.88691) (xy 19.927513 -169.868903) (xy 19.877913 -169.843402)
			(xy 19.832555 -169.810951) (xy 19.792406 -169.772242) (xy 19.75832 -169.728099) (xy 19.731024 -169.679464)
			(xy 19.711101 -169.627373) (xy 19.698975 -169.572936) (xy 19.694904 -169.517314) (xy 5.1054 -169.517314)
			(xy 5.1054 -170.590281) (xy 8.57248 -170.590281) (xy 8.57248 -170.535779) (xy 8.580236 -170.481831)
			(xy 8.595591 -170.429537) (xy 8.618232 -170.37996) (xy 8.647698 -170.33411) (xy 8.68339 -170.29292)
			(xy 8.72458 -170.257228) (xy 8.77043 -170.227762) (xy 8.820007 -170.205121) (xy 8.872301 -170.189766)
			(xy 8.926249 -170.18201) (xy 8.9535 -170.181524) (xy 8.981589 -170.182012) (xy 9.037157 -170.190259)
			(xy 9.090913 -170.206574) (xy 9.141691 -170.230605) (xy 9.188391 -170.26183) (xy 9.209532 -170.28033)
			(xy 9.209786 -170.280584) (xy 9.216994 -170.286556) (xy 9.234468 -170.293221) (xy 9.243822 -170.293538)
			(xy 9.311894 -170.293538) (xy 9.32123 -170.293116) (xy 9.338682 -170.286482) (xy 9.34593 -170.280584)
			(xy 9.346184 -170.28033) (xy 9.367346 -170.26186) (xy 9.414058 -170.230668) (xy 9.464833 -170.206652)
			(xy 9.518577 -170.190328) (xy 9.574132 -170.182049) (xy 9.602216 -170.181524) (xy 9.629469 -170.181983)
			(xy 9.683421 -170.18974) (xy 9.735719 -170.205095) (xy 9.7853 -170.227738) (xy 9.831154 -170.257206)
			(xy 9.872348 -170.2929) (xy 9.908042 -170.334093) (xy 9.91985 -170.352466) (xy 20.610574 -170.352466)
			(xy 20.614645 -170.296844) (xy 20.626771 -170.242407) (xy 20.646694 -170.190316) (xy 20.67399 -170.141681)
			(xy 20.708076 -170.097538) (xy 20.748225 -170.058829) (xy 20.793583 -170.026378) (xy 20.843183 -170.000877)
			(xy 20.895967 -169.98287) (xy 20.95081 -169.97274) (xy 21.006544 -169.970703) (xy 21.061981 -169.976803)
			(xy 21.115938 -169.990909) (xy 21.167267 -170.012721) (xy 21.214873 -170.041775) (xy 21.257741 -170.07745)
			(xy 21.294958 -170.118987) (xy 21.325731 -170.1655) (xy 21.349403 -170.215997) (xy 21.365471 -170.269404)
			(xy 21.373591 -170.32458) (xy 21.3741 -170.352466) (xy 21.373591 -170.380352) (xy 21.365471 -170.435528)
			(xy 21.349403 -170.488935) (xy 21.325731 -170.539432) (xy 21.294958 -170.585945) (xy 21.257741 -170.627482)
			(xy 21.214873 -170.663157) (xy 21.167267 -170.692211) (xy 21.115938 -170.714023) (xy 21.061981 -170.728129)
			(xy 21.006544 -170.734229) (xy 20.95081 -170.732192) (xy 20.895967 -170.722062) (xy 20.843183 -170.704055)
			(xy 20.793583 -170.678554) (xy 20.748225 -170.646103) (xy 20.708076 -170.607394) (xy 20.67399 -170.563251)
			(xy 20.646694 -170.514616) (xy 20.626771 -170.462525) (xy 20.614645 -170.408088) (xy 20.610574 -170.352466)
			(xy 9.91985 -170.352466) (xy 9.93751 -170.379946) (xy 9.960153 -170.429527) (xy 9.97551 -170.481825)
			(xy 9.983267 -170.535777) (xy 9.983267 -170.590283) (xy 9.97551 -170.644235) (xy 9.960153 -170.696533)
			(xy 9.93751 -170.746114) (xy 9.908042 -170.791967) (xy 9.872348 -170.83316) (xy 9.831154 -170.868854)
			(xy 9.7853 -170.898322) (xy 9.735719 -170.920965) (xy 9.683421 -170.93632) (xy 9.629469 -170.944077)
			(xy 9.602216 -170.94454) (xy 9.574127 -170.944051) (xy 9.518559 -170.935806) (xy 9.464803 -170.919491)
			(xy 9.414025 -170.89546) (xy 9.367325 -170.864235) (xy 9.346184 -170.845734) (xy 9.34593 -170.84548)
			(xy 9.338721 -170.839511) (xy 9.321247 -170.832845) (xy 9.311894 -170.832526) (xy 9.243822 -170.832526)
			(xy 9.234488 -170.832963) (xy 9.217036 -170.839587) (xy 9.209786 -170.84548) (xy 9.209532 -170.845734)
			(xy 9.188359 -170.864191) (xy 9.141651 -170.895386) (xy 9.090878 -170.919405) (xy 9.037136 -170.935732)
			(xy 8.981583 -170.944014) (xy 8.9535 -170.94454) (xy 8.926249 -170.94405) (xy 8.872301 -170.936294)
			(xy 8.820007 -170.920939) (xy 8.77043 -170.898298) (xy 8.72458 -170.868832) (xy 8.68339 -170.83314)
			(xy 8.647698 -170.79195) (xy 8.618232 -170.7461) (xy 8.595591 -170.696523) (xy 8.580236 -170.644229)
			(xy 8.57248 -170.590281) (xy 5.1054 -170.590281) (xy 5.1054 -172.729398) (xy 20.58873 -172.729398)
			(xy 20.592801 -172.673776) (xy 20.604927 -172.619339) (xy 20.62485 -172.567248) (xy 20.652146 -172.518613)
			(xy 20.686232 -172.47447) (xy 20.726381 -172.435761) (xy 20.771739 -172.40331) (xy 20.821339 -172.377809)
			(xy 20.874123 -172.359802) (xy 20.928966 -172.349672) (xy 20.9847 -172.347635) (xy 21.040137 -172.353735)
			(xy 21.094094 -172.367841) (xy 21.145423 -172.389653) (xy 21.193029 -172.418707) (xy 21.235897 -172.454382)
			(xy 21.273114 -172.495919) (xy 21.303887 -172.542432) (xy 21.327559 -172.592929) (xy 21.343627 -172.646336)
			(xy 21.351747 -172.701512) (xy 21.352256 -172.729398) (xy 21.351747 -172.757284) (xy 21.343627 -172.81246)
			(xy 21.327559 -172.865867) (xy 21.303887 -172.916364) (xy 21.273114 -172.962877) (xy 21.235897 -173.004414)
			(xy 21.193029 -173.040089) (xy 21.145423 -173.069143) (xy 21.094094 -173.090955) (xy 21.040137 -173.105061)
			(xy 20.9847 -173.111161) (xy 20.928966 -173.109124) (xy 20.874123 -173.098994) (xy 20.821339 -173.080987)
			(xy 20.771739 -173.055486) (xy 20.726381 -173.023035) (xy 20.686232 -172.984326) (xy 20.652146 -172.940183)
			(xy 20.62485 -172.891548) (xy 20.604927 -172.839457) (xy 20.592801 -172.78502) (xy 20.58873 -172.729398)
			(xy 5.1054 -172.729398) (xy 5.1054 -173.282681) (xy 8.99412 -173.282681) (xy 8.99412 -173.228179)
			(xy 9.001876 -173.174231) (xy 9.017231 -173.121937) (xy 9.039872 -173.07236) (xy 9.069338 -173.02651)
			(xy 9.10503 -172.98532) (xy 9.14622 -172.949628) (xy 9.19207 -172.920162) (xy 9.241647 -172.897521)
			(xy 9.293941 -172.882166) (xy 9.347889 -172.87441) (xy 9.37514 -172.873924) (xy 9.404399 -172.874486)
			(xy 9.462231 -172.883433) (xy 9.518021 -172.901096) (xy 9.570464 -172.927062) (xy 9.618333 -172.960722)
			(xy 9.639808 -172.980604) (xy 9.647174 -172.987716) (xy 9.664954 -172.994828) (xy 9.755632 -172.994828)
			(xy 9.773412 -172.987716) (xy 9.780778 -172.980604) (xy 9.802223 -172.960685) (xy 9.850091 -172.92701)
			(xy 9.902541 -172.90104) (xy 9.958341 -172.883382) (xy 10.016182 -172.874453) (xy 10.045446 -172.873924)
			(xy 10.072699 -172.874383) (xy 10.126651 -172.88214) (xy 10.178949 -172.897495) (xy 10.22853 -172.920138)
			(xy 10.274384 -172.949606) (xy 10.315578 -172.9853) (xy 10.351272 -173.026493) (xy 10.38074 -173.072346)
			(xy 10.403383 -173.121927) (xy 10.41874 -173.174225) (xy 10.426497 -173.228177) (xy 10.426497 -173.282683)
			(xy 10.41874 -173.336635) (xy 10.403383 -173.388933) (xy 10.38074 -173.438514) (xy 10.351272 -173.484367)
			(xy 10.315578 -173.52556) (xy 10.274384 -173.561254) (xy 10.229336 -173.590204) (xy 19.616672 -173.590204)
			(xy 19.620743 -173.534582) (xy 19.632869 -173.480145) (xy 19.652792 -173.428054) (xy 19.680088 -173.379419)
			(xy 19.714174 -173.335276) (xy 19.754323 -173.296567) (xy 19.799681 -173.264116) (xy 19.849281 -173.238615)
			(xy 19.902065 -173.220608) (xy 19.956908 -173.210478) (xy 20.012642 -173.208441) (xy 20.068079 -173.214541)
			(xy 20.122036 -173.228647) (xy 20.173365 -173.250459) (xy 20.220971 -173.279513) (xy 20.263839 -173.315188)
			(xy 20.301056 -173.356725) (xy 20.331829 -173.403238) (xy 20.355501 -173.453735) (xy 20.371569 -173.507142)
			(xy 20.379689 -173.562318) (xy 20.380198 -173.590204) (xy 20.379689 -173.61809) (xy 20.371569 -173.673266)
			(xy 20.355501 -173.726673) (xy 20.331829 -173.77717) (xy 20.301056 -173.823683) (xy 20.263839 -173.86522)
			(xy 20.220971 -173.900895) (xy 20.173365 -173.929949) (xy 20.122036 -173.951761) (xy 20.068079 -173.965867)
			(xy 20.012642 -173.971967) (xy 19.956908 -173.96993) (xy 19.902065 -173.9598) (xy 19.849281 -173.941793)
			(xy 19.799681 -173.916292) (xy 19.754323 -173.883841) (xy 19.714174 -173.845132) (xy 19.680088 -173.800989)
			(xy 19.652792 -173.752354) (xy 19.632869 -173.700263) (xy 19.620743 -173.645826) (xy 19.616672 -173.590204)
			(xy 10.229336 -173.590204) (xy 10.22853 -173.590722) (xy 10.178949 -173.613365) (xy 10.126651 -173.62872)
			(xy 10.072699 -173.636477) (xy 10.045446 -173.63694) (xy 10.016186 -173.636396) (xy 9.958353 -173.627446)
			(xy 9.902562 -173.60978) (xy 9.85012 -173.58381) (xy 9.802252 -173.550144) (xy 9.780778 -173.53026)
			(xy 9.773412 -173.523148) (xy 9.755632 -173.516036) (xy 9.664954 -173.516036) (xy 9.647174 -173.523148)
			(xy 9.639808 -173.53026) (xy 9.618364 -173.550179) (xy 9.570496 -173.583855) (xy 9.518046 -173.609827)
			(xy 9.462246 -173.627484) (xy 9.404404 -173.636412) (xy 9.37514 -173.63694) (xy 9.347889 -173.63645)
			(xy 9.293941 -173.628694) (xy 9.241647 -173.613339) (xy 9.19207 -173.590698) (xy 9.14622 -173.561232)
			(xy 9.10503 -173.52554) (xy 9.069338 -173.48435) (xy 9.039872 -173.4385) (xy 9.017231 -173.388923)
			(xy 9.001876 -173.336629) (xy 8.99412 -173.282681) (xy 5.1054 -173.282681) (xy 5.1054 -174.271178)
			(xy 21.033738 -174.271178) (xy 21.037809 -174.215556) (xy 21.049935 -174.161119) (xy 21.069858 -174.109028)
			(xy 21.097154 -174.060393) (xy 21.13124 -174.01625) (xy 21.171389 -173.977541) (xy 21.216747 -173.94509)
			(xy 21.266347 -173.919589) (xy 21.319131 -173.901582) (xy 21.373974 -173.891452) (xy 21.429708 -173.889415)
			(xy 21.485145 -173.895515) (xy 21.539102 -173.909621) (xy 21.590431 -173.931433) (xy 21.638037 -173.960487)
			(xy 21.680905 -173.996162) (xy 21.718122 -174.037699) (xy 21.748895 -174.084212) (xy 21.772567 -174.134709)
			(xy 21.788635 -174.188116) (xy 21.796755 -174.243292) (xy 21.797264 -174.271178) (xy 21.796755 -174.299064)
			(xy 21.788635 -174.35424) (xy 21.772567 -174.407647) (xy 21.748895 -174.458144) (xy 21.718122 -174.504657)
			(xy 21.680905 -174.546194) (xy 21.638037 -174.581869) (xy 21.590431 -174.610923) (xy 21.539102 -174.632735)
			(xy 21.485145 -174.646841) (xy 21.429708 -174.652941) (xy 21.373974 -174.650904) (xy 21.319131 -174.640774)
			(xy 21.266347 -174.622767) (xy 21.216747 -174.597266) (xy 21.171389 -174.564815) (xy 21.13124 -174.526106)
			(xy 21.097154 -174.481963) (xy 21.069858 -174.433328) (xy 21.049935 -174.381237) (xy 21.037809 -174.3268)
			(xy 21.033738 -174.271178) (xy 5.1054 -174.271178) (xy 5.1054 -177.594081) (xy 8.398486 -177.594081)
			(xy 8.398486 -177.539579) (xy 8.406242 -177.485631) (xy 8.421598 -177.433336) (xy 8.444239 -177.383758)
			(xy 8.473705 -177.337907) (xy 8.509397 -177.296717) (xy 8.550587 -177.261025) (xy 8.596438 -177.231559)
			(xy 8.646016 -177.208918) (xy 8.698311 -177.193562) (xy 8.752259 -177.185806) (xy 8.77951 -177.18532)
			(xy 8.805824 -177.185774) (xy 8.857954 -177.193011) (xy 8.908597 -177.207332) (xy 8.956796 -177.228467)
			(xy 9.001639 -177.256016) (xy 9.042278 -177.289457) (xy 9.060434 -177.30851) (xy 9.06794 -177.31593)
			(xy 9.087232 -177.324444) (xy 9.097772 -177.32502) (xy 9.172448 -177.32502) (xy 9.182995 -177.32447)
			(xy 9.20229 -177.315949) (xy 9.209786 -177.30851) (xy 9.229606 -177.287722) (xy 9.274378 -177.251747)
			(xy 9.324036 -177.222887) (xy 9.377458 -177.201794) (xy 9.433437 -177.188945) (xy 9.49071 -177.18463)
			(xy 9.547983 -177.188945) (xy 9.603962 -177.201794) (xy 9.657384 -177.222887) (xy 9.707042 -177.251747)
			(xy 9.751814 -177.287722) (xy 9.771634 -177.30851) (xy 9.77914 -177.31593) (xy 9.798432 -177.324444)
			(xy 9.808972 -177.32502) (xy 9.883648 -177.32502) (xy 9.894195 -177.32447) (xy 9.91349 -177.315949)
			(xy 9.920986 -177.30851) (xy 9.939157 -177.28947) (xy 9.979783 -177.256011) (xy 10.02462 -177.22845)
			(xy 10.072818 -177.207309) (xy 10.123463 -177.192988) (xy 10.175595 -177.18576) (xy 10.20191 -177.18532)
			(xy 10.229161 -177.18581) (xy 10.283109 -177.193566) (xy 10.335403 -177.208921) (xy 10.38498 -177.231562)
			(xy 10.43083 -177.261028) (xy 10.47202 -177.29672) (xy 10.507712 -177.33791) (xy 10.537178 -177.38376)
			(xy 10.559819 -177.433337) (xy 10.575174 -177.485631) (xy 10.58293 -177.539579) (xy 10.58293 -177.594081)
			(xy 10.575174 -177.648029) (xy 10.559819 -177.700323) (xy 10.537178 -177.7499) (xy 10.507712 -177.79575)
			(xy 10.47202 -177.83694) (xy 10.43083 -177.872632) (xy 10.38498 -177.902098) (xy 10.335403 -177.924739)
			(xy 10.283109 -177.940094) (xy 10.229161 -177.94785) (xy 10.20191 -177.948336) (xy 10.175597 -177.94785)
			(xy 10.12347 -177.940618) (xy 10.072828 -177.926301) (xy 10.024629 -177.905172) (xy 9.979785 -177.87763)
			(xy 9.939144 -177.844195) (xy 9.920986 -177.825146) (xy 9.913465 -177.817743) (xy 9.894185 -177.809218)
			(xy 9.883648 -177.808636) (xy 9.808972 -177.808636) (xy 9.798424 -177.80918) (xy 9.779127 -177.817703)
			(xy 9.771634 -177.825146) (xy 9.751814 -177.845934) (xy 9.707042 -177.881909) (xy 9.657384 -177.910769)
			(xy 9.603962 -177.931862) (xy 9.547983 -177.944711) (xy 9.49071 -177.949026) (xy 9.433437 -177.944711)
			(xy 9.377458 -177.931862) (xy 9.324036 -177.910769) (xy 9.274378 -177.881909) (xy 9.229606 -177.845934)
			(xy 9.209786 -177.825146) (xy 9.202265 -177.817743) (xy 9.182985 -177.809218) (xy 9.172448 -177.808636)
			(xy 9.097772 -177.808636) (xy 9.087224 -177.80918) (xy 9.067927 -177.817703) (xy 9.060434 -177.825146)
			(xy 9.042313 -177.844235) (xy 9.001674 -177.877688) (xy 8.956827 -177.905241) (xy 8.908619 -177.926373)
			(xy 8.857966 -177.940684) (xy 8.805828 -177.947901) (xy 8.77951 -177.948336) (xy 8.752259 -177.947854)
			(xy 8.698311 -177.940098) (xy 8.646016 -177.924742) (xy 8.596438 -177.902101) (xy 8.550587 -177.872635)
			(xy 8.509397 -177.836943) (xy 8.473705 -177.795753) (xy 8.444239 -177.749902) (xy 8.421598 -177.700324)
			(xy 8.406242 -177.648029) (xy 8.398486 -177.594081) (xy 5.1054 -177.594081) (xy 5.1054 -180.365908)
			(xy 28.064204 -180.365908) (xy 28.068275 -180.310286) (xy 28.080401 -180.255849) (xy 28.100324 -180.203758)
			(xy 28.12762 -180.155123) (xy 28.161706 -180.11098) (xy 28.201855 -180.072271) (xy 28.247213 -180.03982)
			(xy 28.296813 -180.014319) (xy 28.349597 -179.996312) (xy 28.40444 -179.986182) (xy 28.460174 -179.984145)
			(xy 28.515611 -179.990245) (xy 28.569568 -180.004351) (xy 28.620897 -180.026163) (xy 28.668503 -180.055217)
			(xy 28.711371 -180.090892) (xy 28.748588 -180.132429) (xy 28.779361 -180.178942) (xy 28.803033 -180.229439)
			(xy 28.819101 -180.282846) (xy 28.827221 -180.338022) (xy 28.82773 -180.365908) (xy 28.827221 -180.393794)
			(xy 28.819101 -180.44897) (xy 28.803033 -180.502377) (xy 28.779361 -180.552874) (xy 28.748588 -180.599387)
			(xy 28.711371 -180.640924) (xy 28.668503 -180.676599) (xy 28.620897 -180.705653) (xy 28.569568 -180.727465)
			(xy 28.515611 -180.741571) (xy 28.460174 -180.747671) (xy 28.40444 -180.745634) (xy 28.349597 -180.735504)
			(xy 28.296813 -180.717497) (xy 28.247213 -180.691996) (xy 28.201855 -180.659545) (xy 28.161706 -180.620836)
			(xy 28.12762 -180.576693) (xy 28.100324 -180.528058) (xy 28.080401 -180.475967) (xy 28.068275 -180.42153)
			(xy 28.064204 -180.365908) (xy 5.1054 -180.365908) (xy 5.1054 -191.783208) (xy 29.869128 -191.783208)
			(xy 29.873199 -191.727586) (xy 29.885325 -191.673149) (xy 29.905248 -191.621058) (xy 29.932544 -191.572423)
			(xy 29.96663 -191.52828) (xy 30.006779 -191.489571) (xy 30.052137 -191.45712) (xy 30.101737 -191.431619)
			(xy 30.154521 -191.413612) (xy 30.209364 -191.403482) (xy 30.265098 -191.401445) (xy 30.320535 -191.407545)
			(xy 30.374492 -191.421651) (xy 30.425821 -191.443463) (xy 30.473427 -191.472517) (xy 30.516295 -191.508192)
			(xy 30.553512 -191.549729) (xy 30.584285 -191.596242) (xy 30.607957 -191.646739) (xy 30.624025 -191.700146)
			(xy 30.632145 -191.755322) (xy 30.632654 -191.783208) (xy 30.632145 -191.811094) (xy 30.624025 -191.86627)
			(xy 30.607957 -191.919677) (xy 30.584285 -191.970174) (xy 30.553512 -192.016687) (xy 30.516295 -192.058224)
			(xy 30.473427 -192.093899) (xy 30.425821 -192.122953) (xy 30.374492 -192.144765) (xy 30.320535 -192.158871)
			(xy 30.265098 -192.164971) (xy 30.209364 -192.162934) (xy 30.154521 -192.152804) (xy 30.101737 -192.134797)
			(xy 30.052137 -192.109296) (xy 30.006779 -192.076845) (xy 29.96663 -192.038136) (xy 29.932544 -191.993993)
			(xy 29.905248 -191.945358) (xy 29.885325 -191.893267) (xy 29.873199 -191.83883) (xy 29.869128 -191.783208)
			(xy 5.1054 -191.783208) (xy 5.1054 -192.745614) (xy 30.161482 -192.745614) (xy 30.165553 -192.689992)
			(xy 30.177679 -192.635555) (xy 30.197602 -192.583464) (xy 30.224898 -192.534829) (xy 30.258984 -192.490686)
			(xy 30.299133 -192.451977) (xy 30.344491 -192.419526) (xy 30.394091 -192.394025) (xy 30.446875 -192.376018)
			(xy 30.501718 -192.365888) (xy 30.557452 -192.363851) (xy 30.612889 -192.369951) (xy 30.666846 -192.384057)
			(xy 30.718175 -192.405869) (xy 30.765781 -192.434923) (xy 30.808649 -192.470598) (xy 30.845866 -192.512135)
			(xy 30.876639 -192.558648) (xy 30.900311 -192.609145) (xy 30.916379 -192.662552) (xy 30.924499 -192.717728)
			(xy 30.925008 -192.745614) (xy 30.924499 -192.7735) (xy 30.916379 -192.828676) (xy 30.900311 -192.882083)
			(xy 30.876639 -192.93258) (xy 30.845866 -192.979093) (xy 30.808649 -193.02063) (xy 30.765781 -193.056305)
			(xy 30.718175 -193.085359) (xy 30.666846 -193.107171) (xy 30.612889 -193.121277) (xy 30.557452 -193.127377)
			(xy 30.501718 -193.12534) (xy 30.446875 -193.11521) (xy 30.394091 -193.097203) (xy 30.344491 -193.071702)
			(xy 30.299133 -193.039251) (xy 30.258984 -193.000542) (xy 30.224898 -192.956399) (xy 30.197602 -192.907764)
			(xy 30.177679 -192.855673) (xy 30.165553 -192.801236) (xy 30.161482 -192.745614) (xy 5.1054 -192.745614)
			(xy 5.1054 -202.41387) (xy 27.454096 -202.41387) (xy 27.458167 -202.358248) (xy 27.470293 -202.303811)
			(xy 27.490216 -202.25172) (xy 27.517512 -202.203085) (xy 27.551598 -202.158942) (xy 27.591747 -202.120233)
			(xy 27.637105 -202.087782) (xy 27.686705 -202.062281) (xy 27.739489 -202.044274) (xy 27.794332 -202.034144)
			(xy 27.850066 -202.032107) (xy 27.905503 -202.038207) (xy 27.95946 -202.052313) (xy 28.010789 -202.074125)
			(xy 28.058395 -202.103179) (xy 28.101263 -202.138854) (xy 28.13848 -202.180391) (xy 28.169253 -202.226904)
			(xy 28.192925 -202.277401) (xy 28.208993 -202.330808) (xy 28.217113 -202.385984) (xy 28.217395 -202.401424)
			(xy 28.448252 -202.401424) (xy 28.452323 -202.345802) (xy 28.464449 -202.291365) (xy 28.484372 -202.239274)
			(xy 28.511668 -202.190639) (xy 28.545754 -202.146496) (xy 28.585903 -202.107787) (xy 28.631261 -202.075336)
			(xy 28.680861 -202.049835) (xy 28.733645 -202.031828) (xy 28.788488 -202.021698) (xy 28.844222 -202.019661)
			(xy 28.899659 -202.025761) (xy 28.953616 -202.039867) (xy 29.004945 -202.061679) (xy 29.052551 -202.090733)
			(xy 29.095419 -202.126408) (xy 29.132636 -202.167945) (xy 29.163409 -202.214458) (xy 29.187081 -202.264955)
			(xy 29.203149 -202.318362) (xy 29.211269 -202.373538) (xy 29.211449 -202.38339) (xy 29.7086 -202.38339)
			(xy 29.712671 -202.327768) (xy 29.724797 -202.273331) (xy 29.74472 -202.22124) (xy 29.772016 -202.172605)
			(xy 29.806102 -202.128462) (xy 29.846251 -202.089753) (xy 29.891609 -202.057302) (xy 29.941209 -202.031801)
			(xy 29.993993 -202.013794) (xy 30.048836 -202.003664) (xy 30.10457 -202.001627) (xy 30.160007 -202.007727)
			(xy 30.213964 -202.021833) (xy 30.265293 -202.043645) (xy 30.312899 -202.072699) (xy 30.355767 -202.108374)
			(xy 30.392984 -202.149911) (xy 30.423757 -202.196424) (xy 30.447429 -202.246921) (xy 30.463497 -202.300328)
			(xy 30.471617 -202.355504) (xy 30.472126 -202.38339) (xy 30.471617 -202.411276) (xy 30.463497 -202.466452)
			(xy 30.447429 -202.519859) (xy 30.423757 -202.570356) (xy 30.392984 -202.616869) (xy 30.355767 -202.658406)
			(xy 30.312899 -202.694081) (xy 30.265293 -202.723135) (xy 30.213964 -202.744947) (xy 30.160007 -202.759053)
			(xy 30.10457 -202.765153) (xy 30.048836 -202.763116) (xy 29.993993 -202.752986) (xy 29.941209 -202.734979)
			(xy 29.891609 -202.709478) (xy 29.846251 -202.677027) (xy 29.806102 -202.638318) (xy 29.772016 -202.594175)
			(xy 29.74472 -202.54554) (xy 29.724797 -202.493449) (xy 29.712671 -202.439012) (xy 29.7086 -202.38339)
			(xy 29.211449 -202.38339) (xy 29.211778 -202.401424) (xy 29.211269 -202.42931) (xy 29.203149 -202.484486)
			(xy 29.187081 -202.537893) (xy 29.163409 -202.58839) (xy 29.132636 -202.634903) (xy 29.095419 -202.67644)
			(xy 29.052551 -202.712115) (xy 29.004945 -202.741169) (xy 28.953616 -202.762981) (xy 28.899659 -202.777087)
			(xy 28.844222 -202.783187) (xy 28.788488 -202.78115) (xy 28.733645 -202.77102) (xy 28.680861 -202.753013)
			(xy 28.631261 -202.727512) (xy 28.585903 -202.695061) (xy 28.545754 -202.656352) (xy 28.511668 -202.612209)
			(xy 28.484372 -202.563574) (xy 28.464449 -202.511483) (xy 28.452323 -202.457046) (xy 28.448252 -202.401424)
			(xy 28.217395 -202.401424) (xy 28.217622 -202.41387) (xy 28.217113 -202.441756) (xy 28.208993 -202.496932)
			(xy 28.192925 -202.550339) (xy 28.169253 -202.600836) (xy 28.13848 -202.647349) (xy 28.101263 -202.688886)
			(xy 28.058395 -202.724561) (xy 28.010789 -202.753615) (xy 27.95946 -202.775427) (xy 27.905503 -202.789533)
			(xy 27.850066 -202.795633) (xy 27.794332 -202.793596) (xy 27.739489 -202.783466) (xy 27.686705 -202.765459)
			(xy 27.637105 -202.739958) (xy 27.591747 -202.707507) (xy 27.551598 -202.668798) (xy 27.517512 -202.624655)
			(xy 27.490216 -202.57602) (xy 27.470293 -202.523929) (xy 27.458167 -202.469492) (xy 27.454096 -202.41387)
			(xy 5.1054 -202.41387) (xy 5.1054 -209.478372) (xy 18.503138 -209.478372) (xy 18.503575 -209.452057)
			(xy 18.510814 -209.399927) (xy 18.525138 -209.349283) (xy 18.546277 -209.301084) (xy 18.573829 -209.256241)
			(xy 18.607273 -209.215603) (xy 18.626328 -209.197448) (xy 18.633744 -209.189938) (xy 18.642263 -209.17065)
			(xy 18.642838 -209.16011) (xy 18.642838 -209.085434) (xy 18.642293 -209.074886) (xy 18.633768 -209.055592)
			(xy 18.626328 -209.048096) (xy 18.607283 -209.02993) (xy 18.573824 -208.989303) (xy 18.546263 -208.944465)
			(xy 18.525122 -208.896266) (xy 18.510803 -208.84562) (xy 18.503577 -208.793488) (xy 18.503138 -208.767172)
			(xy 18.503624 -208.739921) (xy 18.51138 -208.685973) (xy 18.526735 -208.633678) (xy 18.549377 -208.584101)
			(xy 18.578843 -208.538251) (xy 18.614534 -208.49706) (xy 18.655725 -208.461369) (xy 18.701575 -208.431903)
			(xy 18.751152 -208.409261) (xy 18.803447 -208.393906) (xy 18.857395 -208.38615) (xy 18.911897 -208.38615)
			(xy 18.965845 -208.393906) (xy 19.01814 -208.409261) (xy 19.067717 -208.431903) (xy 19.113567 -208.461369)
			(xy 19.154758 -208.49706) (xy 19.190449 -208.538251) (xy 19.219915 -208.584101) (xy 19.242557 -208.633678)
			(xy 19.257912 -208.685973) (xy 19.265668 -208.739921) (xy 19.266154 -208.767172) (xy 19.265749 -208.793488)
			(xy 19.263405 -208.810352) (xy 21.535388 -208.810352) (xy 21.539459 -208.75473) (xy 21.551585 -208.700293)
			(xy 21.571508 -208.648202) (xy 21.598804 -208.599567) (xy 21.63289 -208.555424) (xy 21.673039 -208.516715)
			(xy 21.718397 -208.484264) (xy 21.767997 -208.458763) (xy 21.820781 -208.440756) (xy 21.875624 -208.430626)
			(xy 21.931358 -208.428589) (xy 21.986795 -208.434689) (xy 22.040752 -208.448795) (xy 22.092081 -208.470607)
			(xy 22.139687 -208.499661) (xy 22.182555 -208.535336) (xy 22.219772 -208.576873) (xy 22.250545 -208.623386)
			(xy 22.274217 -208.673883) (xy 22.290285 -208.72729) (xy 22.298405 -208.782466) (xy 22.298914 -208.810352)
			(xy 22.298405 -208.838238) (xy 22.290285 -208.893414) (xy 22.274217 -208.946821) (xy 22.250545 -208.997318)
			(xy 22.219772 -209.043831) (xy 22.182555 -209.085368) (xy 22.139687 -209.121043) (xy 22.092081 -209.150097)
			(xy 22.040752 -209.171909) (xy 21.986795 -209.186015) (xy 21.931358 -209.192115) (xy 21.875624 -209.190078)
			(xy 21.820781 -209.179948) (xy 21.767997 -209.161941) (xy 21.718397 -209.13644) (xy 21.673039 -209.103989)
			(xy 21.63289 -209.06528) (xy 21.598804 -209.021137) (xy 21.571508 -208.972502) (xy 21.551585 -208.920411)
			(xy 21.539459 -208.865974) (xy 21.535388 -208.810352) (xy 19.263405 -208.810352) (xy 19.258504 -208.84562)
			(xy 19.244173 -208.896265) (xy 19.223029 -208.944464) (xy 19.195471 -208.989305) (xy 19.162021 -209.029942)
			(xy 19.142964 -209.048096) (xy 19.135572 -209.055626) (xy 19.12704 -209.074899) (xy 19.126454 -209.085434)
			(xy 19.126454 -209.16011) (xy 19.126978 -209.17066) (xy 19.135518 -209.189954) (xy 19.142964 -209.197448)
			(xy 19.162048 -209.215575) (xy 19.1955 -209.256212) (xy 19.223054 -209.301059) (xy 19.244187 -209.349265)
			(xy 19.258499 -209.399917) (xy 19.265718 -209.452054) (xy 19.266154 -209.478372) (xy 19.265668 -209.505623)
			(xy 19.257912 -209.559571) (xy 19.242557 -209.611866) (xy 19.219915 -209.661443) (xy 19.190449 -209.707293)
			(xy 19.154758 -209.748484) (xy 19.113567 -209.784175) (xy 19.067717 -209.813641) (xy 19.01814 -209.836283)
			(xy 18.965845 -209.851638) (xy 18.911897 -209.859394) (xy 18.857395 -209.859394) (xy 18.803447 -209.851638)
			(xy 18.751152 -209.836283) (xy 18.701575 -209.813641) (xy 18.655725 -209.784175) (xy 18.614534 -209.748484)
			(xy 18.578843 -209.707293) (xy 18.549377 -209.661443) (xy 18.526735 -209.611866) (xy 18.51138 -209.559571)
			(xy 18.503624 -209.505623) (xy 18.503138 -209.478372) (xy 5.1054 -209.478372) (xy 5.1054 -210.113372)
			(xy 13.854428 -210.113372) (xy 13.858499 -210.05775) (xy 13.870625 -210.003313) (xy 13.890548 -209.951222)
			(xy 13.917844 -209.902587) (xy 13.95193 -209.858444) (xy 13.992079 -209.819735) (xy 14.037437 -209.787284)
			(xy 14.087037 -209.761783) (xy 14.139821 -209.743776) (xy 14.194664 -209.733646) (xy 14.250398 -209.731609)
			(xy 14.305835 -209.737709) (xy 14.359792 -209.751815) (xy 14.411121 -209.773627) (xy 14.458727 -209.802681)
			(xy 14.501595 -209.838356) (xy 14.538812 -209.879893) (xy 14.569585 -209.926406) (xy 14.593257 -209.976903)
			(xy 14.609325 -210.03031) (xy 14.617445 -210.085486) (xy 14.617954 -210.113372) (xy 17.054828 -210.113372)
			(xy 17.058899 -210.05775) (xy 17.071025 -210.003313) (xy 17.090948 -209.951222) (xy 17.118244 -209.902587)
			(xy 17.15233 -209.858444) (xy 17.192479 -209.819735) (xy 17.237837 -209.787284) (xy 17.287437 -209.761783)
			(xy 17.340221 -209.743776) (xy 17.395064 -209.733646) (xy 17.450798 -209.731609) (xy 17.506235 -209.737709)
			(xy 17.560192 -209.751815) (xy 17.611521 -209.773627) (xy 17.659127 -209.802681) (xy 17.701995 -209.838356)
			(xy 17.739212 -209.879893) (xy 17.769985 -209.926406) (xy 17.793657 -209.976903) (xy 17.809725 -210.03031)
			(xy 17.817845 -210.085486) (xy 17.818354 -210.113372) (xy 17.81789 -210.138772) (xy 17.943828 -210.138772)
			(xy 17.947899 -210.08315) (xy 17.960025 -210.028713) (xy 17.979948 -209.976622) (xy 18.007244 -209.927987)
			(xy 18.04133 -209.883844) (xy 18.081479 -209.845135) (xy 18.126837 -209.812684) (xy 18.176437 -209.787183)
			(xy 18.229221 -209.769176) (xy 18.284064 -209.759046) (xy 18.339798 -209.757009) (xy 18.395235 -209.763109)
			(xy 18.449192 -209.777215) (xy 18.500521 -209.799027) (xy 18.548127 -209.828081) (xy 18.590995 -209.863756)
			(xy 18.628212 -209.905293) (xy 18.658985 -209.951806) (xy 18.682657 -210.002303) (xy 18.698725 -210.05571)
			(xy 18.706845 -210.110886) (xy 18.707354 -210.138772) (xy 18.706845 -210.166658) (xy 18.698725 -210.221834)
			(xy 18.682657 -210.275241) (xy 18.658985 -210.325738) (xy 18.628212 -210.372251) (xy 18.590995 -210.413788)
			(xy 18.548127 -210.449463) (xy 18.500521 -210.478517) (xy 18.449192 -210.500329) (xy 18.395235 -210.514435)
			(xy 18.339798 -210.520535) (xy 18.284064 -210.518498) (xy 18.229221 -210.508368) (xy 18.176437 -210.490361)
			(xy 18.126837 -210.46486) (xy 18.081479 -210.432409) (xy 18.04133 -210.3937) (xy 18.007244 -210.349557)
			(xy 17.979948 -210.300922) (xy 17.960025 -210.248831) (xy 17.947899 -210.194394) (xy 17.943828 -210.138772)
			(xy 17.81789 -210.138772) (xy 17.817845 -210.141258) (xy 17.809725 -210.196434) (xy 17.793657 -210.249841)
			(xy 17.769985 -210.300338) (xy 17.739212 -210.346851) (xy 17.701995 -210.388388) (xy 17.659127 -210.424063)
			(xy 17.611521 -210.453117) (xy 17.560192 -210.474929) (xy 17.506235 -210.489035) (xy 17.450798 -210.495135)
			(xy 17.395064 -210.493098) (xy 17.340221 -210.482968) (xy 17.287437 -210.464961) (xy 17.237837 -210.43946)
			(xy 17.192479 -210.407009) (xy 17.15233 -210.3683) (xy 17.118244 -210.324157) (xy 17.090948 -210.275522)
			(xy 17.071025 -210.223431) (xy 17.058899 -210.168994) (xy 17.054828 -210.113372) (xy 14.617954 -210.113372)
			(xy 14.617445 -210.141258) (xy 14.609325 -210.196434) (xy 14.593257 -210.249841) (xy 14.569585 -210.300338)
			(xy 14.538812 -210.346851) (xy 14.501595 -210.388388) (xy 14.458727 -210.424063) (xy 14.411121 -210.453117)
			(xy 14.359792 -210.474929) (xy 14.305835 -210.489035) (xy 14.250398 -210.495135) (xy 14.194664 -210.493098)
			(xy 14.139821 -210.482968) (xy 14.087037 -210.464961) (xy 14.037437 -210.43946) (xy 13.992079 -210.407009)
			(xy 13.95193 -210.3683) (xy 13.917844 -210.324157) (xy 13.890548 -210.275522) (xy 13.870625 -210.223431)
			(xy 13.858499 -210.168994) (xy 13.854428 -210.113372) (xy 5.1054 -210.113372) (xy 5.1054 -212.807621)
			(xy 11.31543 -212.807621) (xy 11.31543 -212.753119) (xy 11.323186 -212.699172) (xy 11.338541 -212.646878)
			(xy 11.361182 -212.597301) (xy 11.390647 -212.551451) (xy 11.426338 -212.510261) (xy 11.467528 -212.47457)
			(xy 11.513378 -212.445104) (xy 11.562954 -212.422462) (xy 11.615248 -212.407107) (xy 11.669195 -212.39935)
			(xy 11.696446 -212.398864) (xy 11.723692 -212.399293) (xy 11.777628 -212.407058) (xy 11.82991 -212.422422)
			(xy 11.879471 -212.445072) (xy 11.925303 -212.474548) (xy 11.966472 -212.510248) (xy 12.002139 -212.551446)
			(xy 12.017248 -212.574124) (xy 12.022086 -212.581157) (xy 12.035497 -212.591704) (xy 12.051641 -212.597224)
			(xy 12.060174 -212.597492) (xy 12.145518 -212.597492) (xy 12.154038 -212.597173) (xy 12.17015 -212.591625)
			(xy 12.18356 -212.581112) (xy 12.188444 -212.574124) (xy 12.203523 -212.551427) (xy 12.239196 -212.510233)
			(xy 12.280371 -212.474539) (xy 12.326209 -212.445071) (xy 12.375776 -212.42243) (xy 12.428061 -212.407077)
			(xy 12.482 -212.399324) (xy 12.509246 -212.398864) (xy 12.535223 -212.399266) (xy 12.586696 -212.406315)
			(xy 12.636734 -212.42029) (xy 12.684411 -212.440933) (xy 12.728842 -212.467859) (xy 12.769204 -212.500572)
			(xy 12.804749 -212.538463) (xy 12.820142 -212.559392) (xy 12.827792 -212.568866) (xy 12.84939 -212.580023)
			(xy 12.861544 -212.580728) (xy 12.944348 -212.580728) (xy 12.956512 -212.580046) (xy 12.978134 -212.568901)
			(xy 12.98575 -212.559392) (xy 13.001177 -212.538491) (xy 13.036724 -212.500612) (xy 13.077084 -212.467909)
			(xy 13.121509 -212.440987) (xy 13.169179 -212.420345) (xy 13.219208 -212.406366) (xy 13.270673 -212.399307)
			(xy 13.296646 -212.398864) (xy 13.323899 -212.399323) (xy 13.377851 -212.40708) (xy 13.430149 -212.422435)
			(xy 13.47973 -212.445078) (xy 13.525584 -212.474546) (xy 13.566778 -212.51024) (xy 13.602472 -212.551433)
			(xy 13.63194 -212.597286) (xy 13.654583 -212.646867) (xy 13.66994 -212.699165) (xy 13.677697 -212.753117)
			(xy 13.677697 -212.807623) (xy 13.66994 -212.861575) (xy 13.654583 -212.913873) (xy 13.63194 -212.963454)
			(xy 13.602472 -213.009307) (xy 13.566778 -213.0505) (xy 13.525584 -213.086194) (xy 13.47973 -213.115662)
			(xy 13.430149 -213.138305) (xy 13.377851 -213.15366) (xy 13.323899 -213.161417) (xy 13.296646 -213.16188)
			(xy 13.27067 -213.161466) (xy 13.219198 -213.154416) (xy 13.169161 -213.140442) (xy 13.121485 -213.119801)
			(xy 13.077054 -213.092877) (xy 13.036691 -213.060167) (xy 13.001144 -213.02228) (xy 12.98575 -213.001352)
			(xy 12.978115 -212.991864) (xy 12.956505 -212.980717) (xy 12.944348 -212.980016) (xy 12.861544 -212.980016)
			(xy 12.849383 -212.980715) (xy 12.827762 -212.99185) (xy 12.820142 -213.001352) (xy 12.804733 -213.022266)
			(xy 12.769182 -213.060143) (xy 12.728818 -213.092844) (xy 12.684389 -213.119763) (xy 12.636718 -213.140403)
			(xy 12.586686 -213.154381) (xy 12.53522 -213.161438) (xy 12.509246 -213.16188) (xy 12.482001 -213.161437)
			(xy 12.428066 -213.153672) (xy 12.375786 -213.138309) (xy 12.326225 -213.115661) (xy 12.280393 -213.086187)
			(xy 12.239223 -213.05049) (xy 12.203555 -213.009296) (xy 12.188444 -212.98662) (xy 12.183567 -212.979618)
			(xy 12.170172 -212.96907) (xy 12.154045 -212.963533) (xy 12.145518 -212.963252) (xy 12.060174 -212.963252)
			(xy 12.051656 -212.96359) (xy 12.035548 -212.969134) (xy 12.022136 -212.979637) (xy 12.017248 -212.98662)
			(xy 12.002156 -213.009308) (xy 11.966487 -213.050504) (xy 11.925315 -213.086201) (xy 11.879479 -213.115671)
			(xy 11.829914 -213.138314) (xy 11.77763 -213.153668) (xy 11.723692 -213.16142) (xy 11.696446 -213.16188)
			(xy 11.669195 -213.16139) (xy 11.615248 -213.153633) (xy 11.562954 -213.138278) (xy 11.513378 -213.115636)
			(xy 11.467528 -213.08617) (xy 11.426338 -213.050479) (xy 11.390647 -213.009289) (xy 11.361182 -212.963439)
			(xy 11.338541 -212.913862) (xy 11.323186 -212.861568) (xy 11.31543 -212.807621) (xy 5.1054 -212.807621)
			(xy 5.1054 -214.151972) (xy 13.219428 -214.151972) (xy 13.223499 -214.09635) (xy 13.235625 -214.041913)
			(xy 13.255548 -213.989822) (xy 13.282844 -213.941187) (xy 13.31693 -213.897044) (xy 13.357079 -213.858335)
			(xy 13.402437 -213.825884) (xy 13.452037 -213.800383) (xy 13.504821 -213.782376) (xy 13.559664 -213.772246)
			(xy 13.615398 -213.770209) (xy 13.670835 -213.776309) (xy 13.724792 -213.790415) (xy 13.776121 -213.812227)
			(xy 13.823727 -213.841281) (xy 13.866595 -213.876956) (xy 13.903812 -213.918493) (xy 13.934585 -213.965006)
			(xy 13.958257 -214.015503) (xy 13.974325 -214.06891) (xy 13.978026 -214.09406) (xy 18.591782 -214.09406)
			(xy 18.595853 -214.038438) (xy 18.607979 -213.984001) (xy 18.627902 -213.93191) (xy 18.655198 -213.883275)
			(xy 18.689284 -213.839132) (xy 18.729433 -213.800423) (xy 18.774791 -213.767972) (xy 18.824391 -213.742471)
			(xy 18.877175 -213.724464) (xy 18.932018 -213.714334) (xy 18.987752 -213.712297) (xy 19.043189 -213.718397)
			(xy 19.097146 -213.732503) (xy 19.148475 -213.754315) (xy 19.196081 -213.783369) (xy 19.238949 -213.819044)
			(xy 19.276166 -213.860581) (xy 19.306939 -213.907094) (xy 19.330611 -213.957591) (xy 19.346679 -214.010998)
			(xy 19.354799 -214.066174) (xy 19.355308 -214.09406) (xy 19.354799 -214.121946) (xy 19.346679 -214.177122)
			(xy 19.330611 -214.230529) (xy 19.306939 -214.281026) (xy 19.276166 -214.327539) (xy 19.238949 -214.369076)
			(xy 19.196081 -214.404751) (xy 19.148475 -214.433805) (xy 19.097146 -214.455617) (xy 19.043189 -214.469723)
			(xy 18.987752 -214.475823) (xy 18.932018 -214.473786) (xy 18.877175 -214.463656) (xy 18.824391 -214.445649)
			(xy 18.774791 -214.420148) (xy 18.729433 -214.387697) (xy 18.689284 -214.348988) (xy 18.655198 -214.304845)
			(xy 18.627902 -214.25621) (xy 18.607979 -214.204119) (xy 18.595853 -214.149682) (xy 18.591782 -214.09406)
			(xy 13.978026 -214.09406) (xy 13.982445 -214.124086) (xy 13.982954 -214.151972) (xy 13.982445 -214.179858)
			(xy 13.974325 -214.235034) (xy 13.958257 -214.288441) (xy 13.934585 -214.338938) (xy 13.903812 -214.385451)
			(xy 13.866595 -214.426988) (xy 13.823727 -214.462663) (xy 13.776121 -214.491717) (xy 13.724792 -214.513529)
			(xy 13.670835 -214.527635) (xy 13.615398 -214.533735) (xy 13.559664 -214.531698) (xy 13.504821 -214.521568)
			(xy 13.452037 -214.503561) (xy 13.402437 -214.47806) (xy 13.357079 -214.445609) (xy 13.31693 -214.4069)
			(xy 13.282844 -214.362757) (xy 13.255548 -214.314122) (xy 13.235625 -214.262031) (xy 13.223499 -214.207594)
			(xy 13.219428 -214.151972) (xy 5.1054 -214.151972) (xy 5.1054 -215.320372) (xy 17.156428 -215.320372)
			(xy 17.160499 -215.26475) (xy 17.172625 -215.210313) (xy 17.192548 -215.158222) (xy 17.219844 -215.109587)
			(xy 17.25393 -215.065444) (xy 17.294079 -215.026735) (xy 17.339437 -214.994284) (xy 17.389037 -214.968783)
			(xy 17.441821 -214.950776) (xy 17.496664 -214.940646) (xy 17.552398 -214.938609) (xy 17.607835 -214.944709)
			(xy 17.661792 -214.958815) (xy 17.713121 -214.980627) (xy 17.760727 -215.009681) (xy 17.803595 -215.045356)
			(xy 17.840812 -215.086893) (xy 17.871585 -215.133406) (xy 17.895257 -215.183903) (xy 17.911325 -215.23731)
			(xy 17.919445 -215.292486) (xy 17.919954 -215.320372) (xy 17.919445 -215.348258) (xy 17.911325 -215.403434)
			(xy 17.908193 -215.413844) (xy 21.5552 -215.413844) (xy 21.559271 -215.358222) (xy 21.571397 -215.303785)
			(xy 21.59132 -215.251694) (xy 21.618616 -215.203059) (xy 21.652702 -215.158916) (xy 21.692851 -215.120207)
			(xy 21.738209 -215.087756) (xy 21.787809 -215.062255) (xy 21.840593 -215.044248) (xy 21.895436 -215.034118)
			(xy 21.95117 -215.032081) (xy 22.006607 -215.038181) (xy 22.060564 -215.052287) (xy 22.111893 -215.074099)
			(xy 22.159499 -215.103153) (xy 22.202367 -215.138828) (xy 22.239584 -215.180365) (xy 22.270357 -215.226878)
			(xy 22.294029 -215.277375) (xy 22.310097 -215.330782) (xy 22.318217 -215.385958) (xy 22.318726 -215.413844)
			(xy 22.318217 -215.44173) (xy 22.310097 -215.496906) (xy 22.294029 -215.550313) (xy 22.270357 -215.60081)
			(xy 22.239584 -215.647323) (xy 22.202367 -215.68886) (xy 22.159499 -215.724535) (xy 22.111893 -215.753589)
			(xy 22.060564 -215.775401) (xy 22.006607 -215.789507) (xy 21.95117 -215.795607) (xy 21.895436 -215.79357)
			(xy 21.840593 -215.78344) (xy 21.787809 -215.765433) (xy 21.738209 -215.739932) (xy 21.692851 -215.707481)
			(xy 21.652702 -215.668772) (xy 21.618616 -215.624629) (xy 21.59132 -215.575994) (xy 21.571397 -215.523903)
			(xy 21.559271 -215.469466) (xy 21.5552 -215.413844) (xy 17.908193 -215.413844) (xy 17.895257 -215.456841)
			(xy 17.871585 -215.507338) (xy 17.840812 -215.553851) (xy 17.803595 -215.595388) (xy 17.760727 -215.631063)
			(xy 17.713121 -215.660117) (xy 17.661792 -215.681929) (xy 17.607835 -215.696035) (xy 17.552398 -215.702135)
			(xy 17.496664 -215.700098) (xy 17.441821 -215.689968) (xy 17.389037 -215.671961) (xy 17.339437 -215.64646)
			(xy 17.294079 -215.614009) (xy 17.25393 -215.5753) (xy 17.219844 -215.531157) (xy 17.192548 -215.482522)
			(xy 17.172625 -215.430431) (xy 17.160499 -215.375994) (xy 17.156428 -215.320372) (xy 5.1054 -215.320372)
			(xy 5.1054 -216.082372) (xy 16.267428 -216.082372) (xy 16.271499 -216.02675) (xy 16.283625 -215.972313)
			(xy 16.303548 -215.920222) (xy 16.330844 -215.871587) (xy 16.36493 -215.827444) (xy 16.405079 -215.788735)
			(xy 16.450437 -215.756284) (xy 16.500037 -215.730783) (xy 16.552821 -215.712776) (xy 16.607664 -215.702646)
			(xy 16.663398 -215.700609) (xy 16.718835 -215.706709) (xy 16.772792 -215.720815) (xy 16.824121 -215.742627)
			(xy 16.871727 -215.771681) (xy 16.914595 -215.807356) (xy 16.951812 -215.848893) (xy 16.982585 -215.895406)
			(xy 17.006257 -215.945903) (xy 17.022325 -215.99931) (xy 17.030445 -216.054486) (xy 17.030954 -216.082372)
			(xy 17.030445 -216.110258) (xy 17.022325 -216.165434) (xy 17.006257 -216.218841) (xy 16.982585 -216.269338)
			(xy 16.951812 -216.315851) (xy 16.914595 -216.357388) (xy 16.871727 -216.393063) (xy 16.824121 -216.422117)
			(xy 16.772792 -216.443929) (xy 16.718835 -216.458035) (xy 16.663398 -216.464135) (xy 16.607664 -216.462098)
			(xy 16.552821 -216.451968) (xy 16.500037 -216.433961) (xy 16.450437 -216.40846) (xy 16.405079 -216.376009)
			(xy 16.36493 -216.3373) (xy 16.330844 -216.293157) (xy 16.303548 -216.244522) (xy 16.283625 -216.192431)
			(xy 16.271499 -216.137994) (xy 16.267428 -216.082372) (xy 5.1054 -216.082372) (xy 5.1054 -217.81516)
			(xy 30.71622 -217.81516) (xy 30.716641 -217.787906) (xy 30.724403 -217.733955) (xy 30.739765 -217.681657)
			(xy 30.762413 -217.632078) (xy 30.791886 -217.586227) (xy 30.827584 -217.545036) (xy 30.868781 -217.509345)
			(xy 30.914638 -217.47988) (xy 30.964221 -217.457241) (xy 31.016522 -217.441889) (xy 31.070474 -217.434136)
			(xy 31.097728 -217.433652) (xy 31.125673 -217.434113) (xy 31.180965 -217.442279) (xy 31.234476 -217.458416)
			(xy 31.285063 -217.482181) (xy 31.331646 -217.513066) (xy 31.373229 -217.55041) (xy 31.408925 -217.593418)
			(xy 31.423864 -217.61704) (xy 31.428709 -217.624326) (xy 31.442307 -217.63532) (xy 31.458807 -217.64111)
			(xy 31.467552 -217.641424) (xy 31.554928 -217.640916) (xy 31.563671 -217.640477) (xy 31.580114 -217.634513)
			(xy 31.593587 -217.623359) (xy 31.598362 -217.616024) (xy 31.598362 -217.61577) (xy 31.613144 -217.591569)
			(xy 31.648752 -217.547435) (xy 31.690503 -217.509062) (xy 31.737477 -217.477295) (xy 31.788638 -217.452835)
			(xy 31.842857 -217.436222) (xy 31.898938 -217.427822) (xy 31.927292 -217.427302) (xy 31.954546 -217.427744)
			(xy 32.008499 -217.435501) (xy 32.060799 -217.450856) (xy 32.110382 -217.473499) (xy 32.156237 -217.502968)
			(xy 32.197432 -217.538662) (xy 32.233128 -217.579856) (xy 32.262597 -217.625711) (xy 32.285241 -217.675293)
			(xy 32.300598 -217.727593) (xy 32.308355 -217.781546) (xy 32.308355 -217.808556) (xy 32.553146 -217.808556)
			(xy 32.557217 -217.752934) (xy 32.569343 -217.698497) (xy 32.589266 -217.646406) (xy 32.616562 -217.597771)
			(xy 32.650648 -217.553628) (xy 32.690797 -217.514919) (xy 32.736155 -217.482468) (xy 32.785755 -217.456967)
			(xy 32.838539 -217.43896) (xy 32.893382 -217.42883) (xy 32.949116 -217.426793) (xy 33.004553 -217.432893)
			(xy 33.05851 -217.446999) (xy 33.109839 -217.468811) (xy 33.157445 -217.497865) (xy 33.200313 -217.53354)
			(xy 33.23753 -217.575077) (xy 33.268303 -217.62159) (xy 33.291975 -217.672087) (xy 33.308043 -217.725494)
			(xy 33.31238 -217.754962) (xy 33.507678 -217.754962) (xy 33.511749 -217.69934) (xy 33.523875 -217.644903)
			(xy 33.543798 -217.592812) (xy 33.571094 -217.544177) (xy 33.60518 -217.500034) (xy 33.645329 -217.461325)
			(xy 33.690687 -217.428874) (xy 33.740287 -217.403373) (xy 33.793071 -217.385366) (xy 33.847914 -217.375236)
			(xy 33.903648 -217.373199) (xy 33.959085 -217.379299) (xy 34.013042 -217.393405) (xy 34.064371 -217.415217)
			(xy 34.111977 -217.444271) (xy 34.154845 -217.479946) (xy 34.192062 -217.521483) (xy 34.222835 -217.567996)
			(xy 34.246507 -217.618493) (xy 34.262575 -217.6719) (xy 34.270695 -217.727076) (xy 34.27093 -217.739976)
			(xy 34.38093 -217.739976) (xy 34.385001 -217.684354) (xy 34.397127 -217.629917) (xy 34.41705 -217.577826)
			(xy 34.444346 -217.529191) (xy 34.478432 -217.485048) (xy 34.518581 -217.446339) (xy 34.563939 -217.413888)
			(xy 34.613539 -217.388387) (xy 34.666323 -217.37038) (xy 34.721166 -217.36025) (xy 34.7769 -217.358213)
			(xy 34.832337 -217.364313) (xy 34.886294 -217.378419) (xy 34.937623 -217.400231) (xy 34.985229 -217.429285)
			(xy 35.028097 -217.46496) (xy 35.065314 -217.506497) (xy 35.096087 -217.55301) (xy 35.119759 -217.603507)
			(xy 35.135827 -217.656914) (xy 35.143947 -217.71209) (xy 35.144456 -217.739976) (xy 35.143947 -217.767862)
			(xy 35.135827 -217.823038) (xy 35.119759 -217.876445) (xy 35.096087 -217.926942) (xy 35.065314 -217.973455)
			(xy 35.028097 -218.014992) (xy 34.985229 -218.050667) (xy 34.937623 -218.079721) (xy 34.886294 -218.101533)
			(xy 34.832337 -218.115639) (xy 34.7769 -218.121739) (xy 34.721166 -218.119702) (xy 34.666323 -218.109572)
			(xy 34.613539 -218.091565) (xy 34.563939 -218.066064) (xy 34.518581 -218.033613) (xy 34.478432 -217.994904)
			(xy 34.444346 -217.950761) (xy 34.41705 -217.902126) (xy 34.397127 -217.850035) (xy 34.385001 -217.795598)
			(xy 34.38093 -217.739976) (xy 34.27093 -217.739976) (xy 34.271204 -217.754962) (xy 34.270695 -217.782848)
			(xy 34.262575 -217.838024) (xy 34.246507 -217.891431) (xy 34.222835 -217.941928) (xy 34.192062 -217.988441)
			(xy 34.154845 -218.029978) (xy 34.111977 -218.065653) (xy 34.064371 -218.094707) (xy 34.013042 -218.116519)
			(xy 33.959085 -218.130625) (xy 33.903648 -218.136725) (xy 33.847914 -218.134688) (xy 33.793071 -218.124558)
			(xy 33.740287 -218.106551) (xy 33.690687 -218.08105) (xy 33.645329 -218.048599) (xy 33.60518 -218.00989)
			(xy 33.571094 -217.965747) (xy 33.543798 -217.917112) (xy 33.523875 -217.865021) (xy 33.511749 -217.810584)
			(xy 33.507678 -217.754962) (xy 33.31238 -217.754962) (xy 33.316163 -217.78067) (xy 33.316672 -217.808556)
			(xy 33.316163 -217.836442) (xy 33.308043 -217.891618) (xy 33.291975 -217.945025) (xy 33.268303 -217.995522)
			(xy 33.23753 -218.042035) (xy 33.200313 -218.083572) (xy 33.157445 -218.119247) (xy 33.109839 -218.148301)
			(xy 33.05851 -218.170113) (xy 33.004553 -218.184219) (xy 32.949116 -218.190319) (xy 32.893382 -218.188282)
			(xy 32.838539 -218.178152) (xy 32.785755 -218.160145) (xy 32.736155 -218.134644) (xy 32.690797 -218.102193)
			(xy 32.650648 -218.063484) (xy 32.616562 -218.019341) (xy 32.589266 -217.970706) (xy 32.569343 -217.918615)
			(xy 32.557217 -217.864178) (xy 32.553146 -217.808556) (xy 32.308355 -217.808556) (xy 32.308355 -217.836054)
			(xy 32.300598 -217.890007) (xy 32.285241 -217.942307) (xy 32.262597 -217.991889) (xy 32.233128 -218.037744)
			(xy 32.197432 -218.078938) (xy 32.156237 -218.114632) (xy 32.110382 -218.144101) (xy 32.060799 -218.166744)
			(xy 32.008499 -218.182099) (xy 31.954546 -218.189856) (xy 31.927292 -218.190318) (xy 31.899346 -218.189855)
			(xy 31.844054 -218.181692) (xy 31.790543 -218.165556) (xy 31.739955 -218.141792) (xy 31.693372 -218.110907)
			(xy 31.651789 -218.073561) (xy 31.616094 -218.030553) (xy 31.601156 -218.00693) (xy 31.596308 -217.999647)
			(xy 31.58271 -217.988655) (xy 31.566212 -217.982863) (xy 31.557468 -217.982546) (xy 31.470092 -217.983054)
			(xy 31.461345 -217.983451) (xy 31.444903 -217.989437) (xy 31.431432 -218.000605) (xy 31.426658 -218.007946)
			(xy 31.426658 -218.0082) (xy 31.410572 -218.034504) (xy 31.371249 -218.08199) (xy 31.32478 -218.12251)
			(xy 31.298896 -218.139264) (xy 31.291714 -218.144076) (xy 31.280856 -218.157514) (xy 31.275105 -218.173805)
			(xy 31.274766 -218.182444) (xy 31.27502 -218.282266) (xy 31.28772 -218.305126) (xy 31.29915 -218.311984)
			(xy 31.322518 -218.327) (xy 31.365081 -218.362688) (xy 31.402018 -218.404171) (xy 31.432549 -218.450571)
			(xy 31.456029 -218.500909) (xy 31.471961 -218.554119) (xy 31.480009 -218.609078) (xy 31.480506 -218.63685)
			(xy 31.48002 -218.664101) (xy 31.472264 -218.718049) (xy 31.456909 -218.770344) (xy 31.434267 -218.819921)
			(xy 31.404801 -218.865771) (xy 31.36911 -218.906962) (xy 31.327919 -218.942653) (xy 31.282069 -218.972119)
			(xy 31.232492 -218.994761) (xy 31.180197 -219.010116) (xy 31.126249 -219.017872) (xy 31.071747 -219.017872)
			(xy 31.017799 -219.010116) (xy 30.965504 -218.994761) (xy 30.915927 -218.972119) (xy 30.870077 -218.942653)
			(xy 30.828886 -218.906962) (xy 30.793195 -218.865771) (xy 30.763729 -218.819921) (xy 30.741087 -218.770344)
			(xy 30.725732 -218.718049) (xy 30.717976 -218.664101) (xy 30.71749 -218.63685) (xy 30.717963 -218.609171)
			(xy 30.725982 -218.554398) (xy 30.741831 -218.501358) (xy 30.765176 -218.451164) (xy 30.795529 -218.404869)
			(xy 30.832251 -218.363446) (xy 30.874573 -218.327762) (xy 30.89783 -218.312746) (xy 30.905013 -218.307936)
			(xy 30.915869 -218.294496) (xy 30.921621 -218.278205) (xy 30.92196 -218.269566) (xy 30.921706 -218.169744)
			(xy 30.909006 -218.146884) (xy 30.897576 -218.140026) (xy 30.874195 -218.125029) (xy 30.831636 -218.089335)
			(xy 30.794702 -218.047848) (xy 30.764174 -218.001444) (xy 30.740696 -217.951104) (xy 30.724765 -217.897892)
			(xy 30.716717 -217.842933) (xy 30.71622 -217.81516) (xy 5.1054 -217.81516) (xy 5.1054 -218.29141)
			(xy 17.041874 -218.29141) (xy 17.045945 -218.235788) (xy 17.058071 -218.181351) (xy 17.077994 -218.12926)
			(xy 17.10529 -218.080625) (xy 17.139376 -218.036482) (xy 17.179525 -217.997773) (xy 17.224883 -217.965322)
			(xy 17.274483 -217.939821) (xy 17.327267 -217.921814) (xy 17.38211 -217.911684) (xy 17.437844 -217.909647)
			(xy 17.493281 -217.915747) (xy 17.547238 -217.929853) (xy 17.598567 -217.951665) (xy 17.646173 -217.980719)
			(xy 17.689041 -218.016394) (xy 17.726258 -218.057931) (xy 17.757031 -218.104444) (xy 17.780703 -218.154941)
			(xy 17.796771 -218.208348) (xy 17.804891 -218.263524) (xy 17.8054 -218.29141) (xy 17.804891 -218.319296)
			(xy 17.796771 -218.374472) (xy 17.780703 -218.427879) (xy 17.757031 -218.478376) (xy 17.726258 -218.524889)
			(xy 17.689041 -218.566426) (xy 17.646173 -218.602101) (xy 17.598567 -218.631155) (xy 17.547238 -218.652967)
			(xy 17.493281 -218.667073) (xy 17.437844 -218.673173) (xy 17.38211 -218.671136) (xy 17.327267 -218.661006)
			(xy 17.274483 -218.642999) (xy 17.224883 -218.617498) (xy 17.179525 -218.585047) (xy 17.139376 -218.546338)
			(xy 17.10529 -218.502195) (xy 17.077994 -218.45356) (xy 17.058071 -218.401469) (xy 17.045945 -218.347032)
			(xy 17.041874 -218.29141) (xy 5.1054 -218.29141) (xy 5.1054 -220.84665) (xy 15.866108 -220.84665)
			(xy 15.870179 -220.791028) (xy 15.882305 -220.736591) (xy 15.902228 -220.6845) (xy 15.929524 -220.635865)
			(xy 15.96361 -220.591722) (xy 16.003759 -220.553013) (xy 16.049117 -220.520562) (xy 16.098717 -220.495061)
			(xy 16.151501 -220.477054) (xy 16.206344 -220.466924) (xy 16.262078 -220.464887) (xy 16.317515 -220.470987)
			(xy 16.371472 -220.485093) (xy 16.422801 -220.506905) (xy 16.451343 -220.524324) (xy 25.975562 -220.524324)
			(xy 25.979633 -220.468702) (xy 25.991759 -220.414265) (xy 26.011682 -220.362174) (xy 26.038978 -220.313539)
			(xy 26.073064 -220.269396) (xy 26.113213 -220.230687) (xy 26.158571 -220.198236) (xy 26.208171 -220.172735)
			(xy 26.260955 -220.154728) (xy 26.315798 -220.144598) (xy 26.371532 -220.142561) (xy 26.426969 -220.148661)
			(xy 26.480926 -220.162767) (xy 26.532255 -220.184579) (xy 26.579861 -220.213633) (xy 26.622729 -220.249308)
			(xy 26.659946 -220.290845) (xy 26.690719 -220.337358) (xy 26.714391 -220.387855) (xy 26.730459 -220.441262)
			(xy 26.738579 -220.496438) (xy 26.739088 -220.524324) (xy 26.738579 -220.55221) (xy 26.730459 -220.607386)
			(xy 26.714391 -220.660793) (xy 26.690719 -220.71129) (xy 26.659946 -220.757803) (xy 26.622729 -220.79934)
			(xy 26.579861 -220.835015) (xy 26.532255 -220.864069) (xy 26.480926 -220.885881) (xy 26.426969 -220.899987)
			(xy 26.371532 -220.906087) (xy 26.315798 -220.90405) (xy 26.260955 -220.89392) (xy 26.208171 -220.875913)
			(xy 26.158571 -220.850412) (xy 26.113213 -220.817961) (xy 26.073064 -220.779252) (xy 26.038978 -220.735109)
			(xy 26.011682 -220.686474) (xy 25.991759 -220.634383) (xy 25.979633 -220.579946) (xy 25.975562 -220.524324)
			(xy 16.451343 -220.524324) (xy 16.470407 -220.535959) (xy 16.513275 -220.571634) (xy 16.550492 -220.613171)
			(xy 16.581265 -220.659684) (xy 16.604937 -220.710181) (xy 16.621005 -220.763588) (xy 16.629125 -220.818764)
			(xy 16.629634 -220.84665) (xy 16.629125 -220.874536) (xy 16.621005 -220.929712) (xy 16.604937 -220.983119)
			(xy 16.581265 -221.033616) (xy 16.550492 -221.080129) (xy 16.513275 -221.121666) (xy 16.470407 -221.157341)
			(xy 16.422801 -221.186395) (xy 16.371472 -221.208207) (xy 16.317515 -221.222313) (xy 16.262078 -221.228413)
			(xy 16.206344 -221.226376) (xy 16.151501 -221.216246) (xy 16.098717 -221.198239) (xy 16.049117 -221.172738)
			(xy 16.003759 -221.140287) (xy 15.96361 -221.101578) (xy 15.929524 -221.057435) (xy 15.902228 -221.0088)
			(xy 15.882305 -220.956709) (xy 15.870179 -220.902272) (xy 15.866108 -220.84665) (xy 5.1054 -220.84665)
			(xy 5.1054 -221.332806) (xy 22.477982 -221.332806) (xy 22.482053 -221.277184) (xy 22.494179 -221.222747)
			(xy 22.514102 -221.170656) (xy 22.541398 -221.122021) (xy 22.575484 -221.077878) (xy 22.615633 -221.039169)
			(xy 22.660991 -221.006718) (xy 22.710591 -220.981217) (xy 22.763375 -220.96321) (xy 22.818218 -220.95308)
			(xy 22.873952 -220.951043) (xy 22.929389 -220.957143) (xy 22.983346 -220.971249) (xy 23.034675 -220.993061)
			(xy 23.082281 -221.022115) (xy 23.125149 -221.05779) (xy 23.162366 -221.099327) (xy 23.193139 -221.14584)
			(xy 23.216811 -221.196337) (xy 23.232879 -221.249744) (xy 23.240999 -221.30492) (xy 23.241508 -221.332806)
			(xy 23.240999 -221.360692) (xy 23.232879 -221.415868) (xy 23.216811 -221.469275) (xy 23.193139 -221.519772)
			(xy 23.162366 -221.566285) (xy 23.125149 -221.607822) (xy 23.082281 -221.643497) (xy 23.034675 -221.672551)
			(xy 22.983346 -221.694363) (xy 22.929389 -221.708469) (xy 22.873952 -221.714569) (xy 22.818218 -221.712532)
			(xy 22.763375 -221.702402) (xy 22.710591 -221.684395) (xy 22.660991 -221.658894) (xy 22.615633 -221.626443)
			(xy 22.575484 -221.587734) (xy 22.541398 -221.543591) (xy 22.514102 -221.494956) (xy 22.494179 -221.442865)
			(xy 22.482053 -221.388428) (xy 22.477982 -221.332806) (xy 5.1054 -221.332806) (xy 5.1054 -222.172276)
			(xy 15.856202 -222.172276) (xy 15.860273 -222.116654) (xy 15.872399 -222.062217) (xy 15.892322 -222.010126)
			(xy 15.919618 -221.961491) (xy 15.953704 -221.917348) (xy 15.993853 -221.878639) (xy 16.039211 -221.846188)
			(xy 16.088811 -221.820687) (xy 16.141595 -221.80268) (xy 16.196438 -221.79255) (xy 16.252172 -221.790513)
			(xy 16.307609 -221.796613) (xy 16.361566 -221.810719) (xy 16.412895 -221.832531) (xy 16.460501 -221.861585)
			(xy 16.503369 -221.89726) (xy 16.540586 -221.938797) (xy 16.548351 -221.950534) (xy 17.087594 -221.950534)
			(xy 17.091665 -221.894912) (xy 17.103791 -221.840475) (xy 17.123714 -221.788384) (xy 17.15101 -221.739749)
			(xy 17.185096 -221.695606) (xy 17.225245 -221.656897) (xy 17.270603 -221.624446) (xy 17.320203 -221.598945)
			(xy 17.372987 -221.580938) (xy 17.42783 -221.570808) (xy 17.483564 -221.568771) (xy 17.539001 -221.574871)
			(xy 17.592958 -221.588977) (xy 17.644287 -221.610789) (xy 17.691893 -221.639843) (xy 17.734761 -221.675518)
			(xy 17.771978 -221.717055) (xy 17.802751 -221.763568) (xy 17.826423 -221.814065) (xy 17.842491 -221.867472)
			(xy 17.850611 -221.922648) (xy 17.85112 -221.950534) (xy 17.850611 -221.97842) (xy 17.842491 -222.033596)
			(xy 17.833398 -222.063818) (xy 25.616662 -222.063818) (xy 25.617148 -222.036567) (xy 25.624904 -221.982619)
			(xy 25.640259 -221.930324) (xy 25.662901 -221.880747) (xy 25.692367 -221.834897) (xy 25.728058 -221.793706)
			(xy 25.769249 -221.758015) (xy 25.815099 -221.728549) (xy 25.864676 -221.705907) (xy 25.916971 -221.690552)
			(xy 25.970919 -221.682796) (xy 26.025421 -221.682796) (xy 26.079369 -221.690552) (xy 26.131664 -221.705907)
			(xy 26.181241 -221.728549) (xy 26.227091 -221.758015) (xy 26.268282 -221.793706) (xy 26.303973 -221.834897)
			(xy 26.333439 -221.880747) (xy 26.356081 -221.930324) (xy 26.371436 -221.982619) (xy 26.379192 -222.036567)
			(xy 26.379678 -222.063818) (xy 26.379197 -222.090681) (xy 26.371658 -222.143877) (xy 26.356731 -222.195488)
			(xy 26.334711 -222.244495) (xy 26.306034 -222.289929) (xy 26.289 -222.310706) (xy 26.28138 -222.319596)
			(xy 26.275538 -222.342202) (xy 26.296112 -222.443548) (xy 26.310336 -222.46209) (xy 26.320496 -222.46717)
			(xy 26.343793 -222.479423) (xy 26.387068 -222.509392) (xy 26.425814 -222.545024) (xy 26.459295 -222.585642)
			(xy 26.486876 -222.630476) (xy 26.508034 -222.678676) (xy 26.522367 -222.729326) (xy 26.529603 -222.781465)
			(xy 26.530046 -222.807784) (xy 26.52956 -222.835035) (xy 26.521804 -222.888983) (xy 26.506449 -222.941278)
			(xy 26.483807 -222.990855) (xy 26.454341 -223.036705) (xy 26.41865 -223.077896) (xy 26.377459 -223.113587)
			(xy 26.331609 -223.143053) (xy 26.282032 -223.165695) (xy 26.229737 -223.18105) (xy 26.175789 -223.188806)
			(xy 26.121287 -223.188806) (xy 26.067339 -223.18105) (xy 26.015044 -223.165695) (xy 25.965467 -223.143053)
			(xy 25.919617 -223.113587) (xy 25.878426 -223.077896) (xy 25.842735 -223.036705) (xy 25.813269 -222.990855)
			(xy 25.790627 -222.941278) (xy 25.775272 -222.888983) (xy 25.767516 -222.835035) (xy 25.76703 -222.807784)
			(xy 25.767476 -222.78092) (xy 25.775027 -222.727724) (xy 25.789964 -222.676113) (xy 25.81199 -222.627106)
			(xy 25.840672 -222.581673) (xy 25.857708 -222.560896) (xy 25.865328 -222.552006) (xy 25.87117 -222.5294)
			(xy 25.850596 -222.428054) (xy 25.836372 -222.409512) (xy 25.826212 -222.404432) (xy 25.802918 -222.392174)
			(xy 25.759643 -222.362206) (xy 25.720897 -222.326575) (xy 25.687415 -222.285958) (xy 25.659833 -222.241124)
			(xy 25.638675 -222.192925) (xy 25.624341 -222.142276) (xy 25.617105 -222.090137) (xy 25.616662 -222.063818)
			(xy 17.833398 -222.063818) (xy 17.826423 -222.087003) (xy 17.802751 -222.1375) (xy 17.771978 -222.184013)
			(xy 17.734761 -222.22555) (xy 17.691893 -222.261225) (xy 17.644287 -222.290279) (xy 17.592958 -222.312091)
			(xy 17.539001 -222.326197) (xy 17.483564 -222.332297) (xy 17.42783 -222.33026) (xy 17.372987 -222.32013)
			(xy 17.320203 -222.302123) (xy 17.270603 -222.276622) (xy 17.225245 -222.244171) (xy 17.185096 -222.205462)
			(xy 17.15101 -222.161319) (xy 17.123714 -222.112684) (xy 17.103791 -222.060593) (xy 17.091665 -222.006156)
			(xy 17.087594 -221.950534) (xy 16.548351 -221.950534) (xy 16.571359 -221.98531) (xy 16.595031 -222.035807)
			(xy 16.611099 -222.089214) (xy 16.619219 -222.14439) (xy 16.619728 -222.172276) (xy 16.619219 -222.200162)
			(xy 16.611099 -222.255338) (xy 16.595031 -222.308745) (xy 16.571359 -222.359242) (xy 16.540586 -222.405755)
			(xy 16.503369 -222.447292) (xy 16.460501 -222.482967) (xy 16.412895 -222.512021) (xy 16.361566 -222.533833)
			(xy 16.307609 -222.547939) (xy 16.252172 -222.554039) (xy 16.196438 -222.552002) (xy 16.141595 -222.541872)
			(xy 16.088811 -222.523865) (xy 16.039211 -222.498364) (xy 15.993853 -222.465913) (xy 15.953704 -222.427204)
			(xy 15.919618 -222.383061) (xy 15.892322 -222.334426) (xy 15.872399 -222.282335) (xy 15.860273 -222.227898)
			(xy 15.856202 -222.172276) (xy 5.1054 -222.172276) (xy 5.1054 -223.147382) (xy 19.056094 -223.147382)
			(xy 19.060165 -223.09176) (xy 19.072291 -223.037323) (xy 19.092214 -222.985232) (xy 19.11951 -222.936597)
			(xy 19.153596 -222.892454) (xy 19.193745 -222.853745) (xy 19.239103 -222.821294) (xy 19.288703 -222.795793)
			(xy 19.341487 -222.777786) (xy 19.39633 -222.767656) (xy 19.452064 -222.765619) (xy 19.507501 -222.771719)
			(xy 19.561458 -222.785825) (xy 19.612787 -222.807637) (xy 19.660393 -222.836691) (xy 19.703261 -222.872366)
			(xy 19.740478 -222.913903) (xy 19.771251 -222.960416) (xy 19.794923 -223.010913) (xy 19.810991 -223.06432)
			(xy 19.813982 -223.084644) (xy 21.0472 -223.084644) (xy 21.051271 -223.029022) (xy 21.063397 -222.974585)
			(xy 21.08332 -222.922494) (xy 21.110616 -222.873859) (xy 21.144702 -222.829716) (xy 21.184851 -222.791007)
			(xy 21.230209 -222.758556) (xy 21.279809 -222.733055) (xy 21.332593 -222.715048) (xy 21.387436 -222.704918)
			(xy 21.44317 -222.702881) (xy 21.498607 -222.708981) (xy 21.552564 -222.723087) (xy 21.603893 -222.744899)
			(xy 21.651499 -222.773953) (xy 21.694367 -222.809628) (xy 21.731584 -222.851165) (xy 21.762357 -222.897678)
			(xy 21.786029 -222.948175) (xy 21.802097 -223.001582) (xy 21.810217 -223.056758) (xy 21.810726 -223.084644)
			(xy 21.810217 -223.11253) (xy 21.802097 -223.167706) (xy 21.786029 -223.221113) (xy 21.762357 -223.27161)
			(xy 21.731584 -223.318123) (xy 21.694367 -223.35966) (xy 21.651499 -223.395335) (xy 21.603893 -223.424389)
			(xy 21.552564 -223.446201) (xy 21.498607 -223.460307) (xy 21.44317 -223.466407) (xy 21.387436 -223.46437)
			(xy 21.332593 -223.45424) (xy 21.279809 -223.436233) (xy 21.230209 -223.410732) (xy 21.184851 -223.378281)
			(xy 21.144702 -223.339572) (xy 21.110616 -223.295429) (xy 21.08332 -223.246794) (xy 21.063397 -223.194703)
			(xy 21.051271 -223.140266) (xy 21.0472 -223.084644) (xy 19.813982 -223.084644) (xy 19.819111 -223.119496)
			(xy 19.81962 -223.147382) (xy 19.819111 -223.175268) (xy 19.810991 -223.230444) (xy 19.794923 -223.283851)
			(xy 19.771251 -223.334348) (xy 19.740478 -223.380861) (xy 19.703261 -223.422398) (xy 19.660393 -223.458073)
			(xy 19.612787 -223.487127) (xy 19.561458 -223.508939) (xy 19.507501 -223.523045) (xy 19.452064 -223.529145)
			(xy 19.39633 -223.527108) (xy 19.341487 -223.516978) (xy 19.288703 -223.498971) (xy 19.239103 -223.47347)
			(xy 19.193745 -223.441019) (xy 19.153596 -223.40231) (xy 19.11951 -223.358167) (xy 19.092214 -223.309532)
			(xy 19.072291 -223.257441) (xy 19.060165 -223.203004) (xy 19.056094 -223.147382) (xy 5.1054 -223.147382)
			(xy 5.1054 -224.536) (xy 27.78328 -224.536) (xy 27.787351 -224.480378) (xy 27.799477 -224.425941)
			(xy 27.8194 -224.37385) (xy 27.846696 -224.325215) (xy 27.880782 -224.281072) (xy 27.920931 -224.242363)
			(xy 27.966289 -224.209912) (xy 28.015889 -224.184411) (xy 28.068673 -224.166404) (xy 28.123516 -224.156274)
			(xy 28.17925 -224.154237) (xy 28.234687 -224.160337) (xy 28.288644 -224.174443) (xy 28.339973 -224.196255)
			(xy 28.387579 -224.225309) (xy 28.430447 -224.260984) (xy 28.467664 -224.302521) (xy 28.498437 -224.349034)
			(xy 28.522109 -224.399531) (xy 28.538177 -224.452938) (xy 28.546297 -224.508114) (xy 28.546806 -224.536)
			(xy 28.546297 -224.563886) (xy 28.538177 -224.619062) (xy 28.522109 -224.672469) (xy 28.498437 -224.722966)
			(xy 28.467664 -224.769479) (xy 28.430447 -224.811016) (xy 28.387579 -224.846691) (xy 28.339973 -224.875745)
			(xy 28.288644 -224.897557) (xy 28.234687 -224.911663) (xy 28.17925 -224.917763) (xy 28.123516 -224.915726)
			(xy 28.068673 -224.905596) (xy 28.015889 -224.887589) (xy 27.966289 -224.862088) (xy 27.920931 -224.829637)
			(xy 27.880782 -224.790928) (xy 27.846696 -224.746785) (xy 27.8194 -224.69815) (xy 27.799477 -224.646059)
			(xy 27.787351 -224.591622) (xy 27.78328 -224.536) (xy 5.1054 -224.536) (xy 5.1054 -225.82251) (xy 18.421094 -225.82251)
			(xy 18.425165 -225.766888) (xy 18.437291 -225.712451) (xy 18.457214 -225.66036) (xy 18.48451 -225.611725)
			(xy 18.518596 -225.567582) (xy 18.558745 -225.528873) (xy 18.604103 -225.496422) (xy 18.653703 -225.470921)
			(xy 18.706487 -225.452914) (xy 18.76133 -225.442784) (xy 18.817064 -225.440747) (xy 18.872501 -225.446847)
			(xy 18.926458 -225.460953) (xy 18.977787 -225.482765) (xy 19.025393 -225.511819) (xy 19.068261 -225.547494)
			(xy 19.105478 -225.589031) (xy 19.136251 -225.635544) (xy 19.158408 -225.68281) (xy 20.720048 -225.68281)
			(xy 20.724119 -225.627188) (xy 20.736245 -225.572751) (xy 20.756168 -225.52066) (xy 20.783464 -225.472025)
			(xy 20.81755 -225.427882) (xy 20.857699 -225.389173) (xy 20.903057 -225.356722) (xy 20.952657 -225.331221)
			(xy 21.005441 -225.313214) (xy 21.060284 -225.303084) (xy 21.116018 -225.301047) (xy 21.171455 -225.307147)
			(xy 21.225412 -225.321253) (xy 21.276741 -225.343065) (xy 21.324347 -225.372119) (xy 21.367215 -225.407794)
			(xy 21.404432 -225.449331) (xy 21.435205 -225.495844) (xy 21.458877 -225.546341) (xy 21.46058 -225.552)
			(xy 30.83128 -225.552) (xy 30.835351 -225.496378) (xy 30.847477 -225.441941) (xy 30.8674 -225.38985)
			(xy 30.894696 -225.341215) (xy 30.928782 -225.297072) (xy 30.968931 -225.258363) (xy 31.014289 -225.225912)
			(xy 31.063889 -225.200411) (xy 31.116673 -225.182404) (xy 31.171516 -225.172274) (xy 31.22725 -225.170237)
			(xy 31.282687 -225.176337) (xy 31.336644 -225.190443) (xy 31.387973 -225.212255) (xy 31.435579 -225.241309)
			(xy 31.478447 -225.276984) (xy 31.515664 -225.318521) (xy 31.546437 -225.365034) (xy 31.570109 -225.415531)
			(xy 31.586177 -225.468938) (xy 31.594297 -225.524114) (xy 31.594806 -225.552) (xy 31.594297 -225.579886)
			(xy 31.586177 -225.635062) (xy 31.570109 -225.688469) (xy 31.546437 -225.738966) (xy 31.515664 -225.785479)
			(xy 31.478447 -225.827016) (xy 31.435579 -225.862691) (xy 31.387973 -225.891745) (xy 31.336644 -225.913557)
			(xy 31.282687 -225.927663) (xy 31.22725 -225.933763) (xy 31.171516 -225.931726) (xy 31.116673 -225.921596)
			(xy 31.063889 -225.903589) (xy 31.014289 -225.878088) (xy 30.968931 -225.845637) (xy 30.928782 -225.806928)
			(xy 30.894696 -225.762785) (xy 30.8674 -225.71415) (xy 30.847477 -225.662059) (xy 30.835351 -225.607622)
			(xy 30.83128 -225.552) (xy 21.46058 -225.552) (xy 21.474945 -225.599748) (xy 21.483065 -225.654924)
			(xy 21.483574 -225.68281) (xy 21.483065 -225.710696) (xy 21.474945 -225.765872) (xy 21.458877 -225.819279)
			(xy 21.435205 -225.869776) (xy 21.404432 -225.916289) (xy 21.367215 -225.957826) (xy 21.324347 -225.993501)
			(xy 21.276741 -226.022555) (xy 21.225412 -226.044367) (xy 21.171455 -226.058473) (xy 21.116018 -226.064573)
			(xy 21.060284 -226.062536) (xy 21.005441 -226.052406) (xy 20.952657 -226.034399) (xy 20.903057 -226.008898)
			(xy 20.857699 -225.976447) (xy 20.81755 -225.937738) (xy 20.783464 -225.893595) (xy 20.756168 -225.84496)
			(xy 20.736245 -225.792869) (xy 20.724119 -225.738432) (xy 20.720048 -225.68281) (xy 19.158408 -225.68281)
			(xy 19.159923 -225.686041) (xy 19.175991 -225.739448) (xy 19.184111 -225.794624) (xy 19.18462 -225.82251)
			(xy 19.184111 -225.850396) (xy 19.175991 -225.905572) (xy 19.159923 -225.958979) (xy 19.136251 -226.009476)
			(xy 19.105478 -226.055989) (xy 19.068261 -226.097526) (xy 19.025393 -226.133201) (xy 18.977787 -226.162255)
			(xy 18.926458 -226.184067) (xy 18.872501 -226.198173) (xy 18.817064 -226.204273) (xy 18.76133 -226.202236)
			(xy 18.706487 -226.192106) (xy 18.653703 -226.174099) (xy 18.604103 -226.148598) (xy 18.558745 -226.116147)
			(xy 18.518596 -226.077438) (xy 18.48451 -226.033295) (xy 18.457214 -225.98466) (xy 18.437291 -225.932569)
			(xy 18.425165 -225.878132) (xy 18.421094 -225.82251) (xy 5.1054 -225.82251) (xy 5.1054 -226.324922)
			(xy 25.607262 -226.324922) (xy 25.611333 -226.2693) (xy 25.623459 -226.214863) (xy 25.643382 -226.162772)
			(xy 25.670678 -226.114137) (xy 25.704764 -226.069994) (xy 25.744913 -226.031285) (xy 25.790271 -225.998834)
			(xy 25.839871 -225.973333) (xy 25.892655 -225.955326) (xy 25.947498 -225.945196) (xy 26.003232 -225.943159)
			(xy 26.058669 -225.949259) (xy 26.112626 -225.963365) (xy 26.163955 -225.985177) (xy 26.211561 -226.014231)
			(xy 26.254429 -226.049906) (xy 26.291646 -226.091443) (xy 26.322419 -226.137956) (xy 26.346091 -226.188453)
			(xy 26.362159 -226.24186) (xy 26.370279 -226.297036) (xy 26.370788 -226.324922) (xy 26.370279 -226.352808)
			(xy 26.362159 -226.407984) (xy 26.346091 -226.461391) (xy 26.322419 -226.511888) (xy 26.291646 -226.558401)
			(xy 26.283045 -226.568) (xy 30.95828 -226.568) (xy 30.962351 -226.512378) (xy 30.974477 -226.457941)
			(xy 30.9944 -226.40585) (xy 31.021696 -226.357215) (xy 31.055782 -226.313072) (xy 31.095931 -226.274363)
			(xy 31.141289 -226.241912) (xy 31.190889 -226.216411) (xy 31.243673 -226.198404) (xy 31.298516 -226.188274)
			(xy 31.35425 -226.186237) (xy 31.409687 -226.192337) (xy 31.463644 -226.206443) (xy 31.514973 -226.228255)
			(xy 31.562579 -226.257309) (xy 31.605447 -226.292984) (xy 31.642664 -226.334521) (xy 31.673437 -226.381034)
			(xy 31.697109 -226.431531) (xy 31.713177 -226.484938) (xy 31.721297 -226.540114) (xy 31.721806 -226.568)
			(xy 31.721297 -226.595886) (xy 31.713177 -226.651062) (xy 31.697109 -226.704469) (xy 31.673437 -226.754966)
			(xy 31.642664 -226.801479) (xy 31.605447 -226.843016) (xy 31.562579 -226.878691) (xy 31.514973 -226.907745)
			(xy 31.463644 -226.929557) (xy 31.409687 -226.943663) (xy 31.35425 -226.949763) (xy 31.298516 -226.947726)
			(xy 31.243673 -226.937596) (xy 31.190889 -226.919589) (xy 31.141289 -226.894088) (xy 31.095931 -226.861637)
			(xy 31.055782 -226.822928) (xy 31.021696 -226.778785) (xy 30.9944 -226.73015) (xy 30.974477 -226.678059)
			(xy 30.962351 -226.623622) (xy 30.95828 -226.568) (xy 26.283045 -226.568) (xy 26.254429 -226.599938)
			(xy 26.211561 -226.635613) (xy 26.163955 -226.664667) (xy 26.112626 -226.686479) (xy 26.058669 -226.700585)
			(xy 26.003232 -226.706685) (xy 25.947498 -226.704648) (xy 25.892655 -226.694518) (xy 25.839871 -226.676511)
			(xy 25.790271 -226.65101) (xy 25.744913 -226.618559) (xy 25.704764 -226.57985) (xy 25.670678 -226.535707)
			(xy 25.643382 -226.487072) (xy 25.623459 -226.434981) (xy 25.611333 -226.380544) (xy 25.607262 -226.324922)
			(xy 5.1054 -226.324922) (xy 5.1054 -228.179884) (xy 17.914872 -228.179884) (xy 17.918943 -228.124262)
			(xy 17.931069 -228.069825) (xy 17.950992 -228.017734) (xy 17.978288 -227.969099) (xy 18.012374 -227.924956)
			(xy 18.052523 -227.886247) (xy 18.097881 -227.853796) (xy 18.147481 -227.828295) (xy 18.200265 -227.810288)
			(xy 18.255108 -227.800158) (xy 18.310842 -227.798121) (xy 18.366279 -227.804221) (xy 18.420236 -227.818327)
			(xy 18.471565 -227.840139) (xy 18.519171 -227.869193) (xy 18.562039 -227.904868) (xy 18.599256 -227.946405)
			(xy 18.630029 -227.992918) (xy 18.653701 -228.043415) (xy 18.661441 -228.06914) (xy 18.973544 -228.06914)
			(xy 18.977615 -228.013518) (xy 18.989741 -227.959081) (xy 19.009664 -227.90699) (xy 19.03696 -227.858355)
			(xy 19.071046 -227.814212) (xy 19.111195 -227.775503) (xy 19.156553 -227.743052) (xy 19.206153 -227.717551)
			(xy 19.258937 -227.699544) (xy 19.31378 -227.689414) (xy 19.369514 -227.687377) (xy 19.424951 -227.693477)
			(xy 19.478908 -227.707583) (xy 19.530237 -227.729395) (xy 19.577843 -227.758449) (xy 19.620711 -227.794124)
			(xy 19.657928 -227.835661) (xy 19.688701 -227.882174) (xy 19.712373 -227.932671) (xy 19.728441 -227.986078)
			(xy 19.736561 -228.041254) (xy 19.73707 -228.06914) (xy 19.736917 -228.077522) (xy 20.024088 -228.077522)
			(xy 20.028159 -228.0219) (xy 20.040285 -227.967463) (xy 20.060208 -227.915372) (xy 20.087504 -227.866737)
			(xy 20.12159 -227.822594) (xy 20.161739 -227.783885) (xy 20.207097 -227.751434) (xy 20.256697 -227.725933)
			(xy 20.309481 -227.707926) (xy 20.364324 -227.697796) (xy 20.420058 -227.695759) (xy 20.475495 -227.701859)
			(xy 20.529452 -227.715965) (xy 20.580781 -227.737777) (xy 20.628387 -227.766831) (xy 20.671255 -227.802506)
			(xy 20.708472 -227.844043) (xy 20.739245 -227.890556) (xy 20.762917 -227.941053) (xy 20.778985 -227.99446)
			(xy 20.787105 -228.049636) (xy 20.787614 -228.077522) (xy 20.787105 -228.105408) (xy 20.778985 -228.160584)
			(xy 20.762917 -228.213991) (xy 20.739245 -228.264488) (xy 20.708472 -228.311001) (xy 20.671255 -228.352538)
			(xy 20.628387 -228.388213) (xy 20.580781 -228.417267) (xy 20.529452 -228.439079) (xy 20.475495 -228.453185)
			(xy 20.420058 -228.459285) (xy 20.364324 -228.457248) (xy 20.309481 -228.447118) (xy 20.256697 -228.429111)
			(xy 20.207097 -228.40361) (xy 20.161739 -228.371159) (xy 20.12159 -228.33245) (xy 20.087504 -228.288307)
			(xy 20.060208 -228.239672) (xy 20.040285 -228.187581) (xy 20.028159 -228.133144) (xy 20.024088 -228.077522)
			(xy 19.736917 -228.077522) (xy 19.736561 -228.097026) (xy 19.728441 -228.152202) (xy 19.712373 -228.205609)
			(xy 19.688701 -228.256106) (xy 19.657928 -228.302619) (xy 19.620711 -228.344156) (xy 19.577843 -228.379831)
			(xy 19.530237 -228.408885) (xy 19.478908 -228.430697) (xy 19.424951 -228.444803) (xy 19.369514 -228.450903)
			(xy 19.31378 -228.448866) (xy 19.258937 -228.438736) (xy 19.206153 -228.420729) (xy 19.156553 -228.395228)
			(xy 19.111195 -228.362777) (xy 19.071046 -228.324068) (xy 19.03696 -228.279925) (xy 19.009664 -228.23129)
			(xy 18.989741 -228.179199) (xy 18.977615 -228.124762) (xy 18.973544 -228.06914) (xy 18.661441 -228.06914)
			(xy 18.669769 -228.096822) (xy 18.677889 -228.151998) (xy 18.678398 -228.179884) (xy 18.677889 -228.20777)
			(xy 18.669769 -228.262946) (xy 18.653701 -228.316353) (xy 18.630029 -228.36685) (xy 18.599256 -228.413363)
			(xy 18.562039 -228.4549) (xy 18.519171 -228.490575) (xy 18.471565 -228.519629) (xy 18.420236 -228.541441)
			(xy 18.366279 -228.555547) (xy 18.310842 -228.561647) (xy 18.255108 -228.55961) (xy 18.200265 -228.54948)
			(xy 18.147481 -228.531473) (xy 18.097881 -228.505972) (xy 18.052523 -228.473521) (xy 18.012374 -228.434812)
			(xy 17.978288 -228.390669) (xy 17.950992 -228.342034) (xy 17.931069 -228.289943) (xy 17.918943 -228.235506)
			(xy 17.914872 -228.179884) (xy 5.1054 -228.179884) (xy 5.1054 -228.981) (xy 16.03451 -228.981) (xy 16.038581 -228.925378)
			(xy 16.050707 -228.870941) (xy 16.07063 -228.81885) (xy 16.097926 -228.770215) (xy 16.132012 -228.726072)
			(xy 16.172161 -228.687363) (xy 16.217519 -228.654912) (xy 16.267119 -228.629411) (xy 16.319903 -228.611404)
			(xy 16.374746 -228.601274) (xy 16.43048 -228.599237) (xy 16.485917 -228.605337) (xy 16.539874 -228.619443)
			(xy 16.591203 -228.641255) (xy 16.638809 -228.670309) (xy 16.644362 -228.67493) (xy 25.95575 -228.67493)
			(xy 25.959821 -228.619308) (xy 25.971947 -228.564871) (xy 25.99187 -228.51278) (xy 26.019166 -228.464145)
			(xy 26.053252 -228.420002) (xy 26.093401 -228.381293) (xy 26.138759 -228.348842) (xy 26.188359 -228.323341)
			(xy 26.241143 -228.305334) (xy 26.295986 -228.295204) (xy 26.35172 -228.293167) (xy 26.407157 -228.299267)
			(xy 26.461114 -228.313373) (xy 26.512443 -228.335185) (xy 26.560049 -228.364239) (xy 26.602917 -228.399914)
			(xy 26.640134 -228.441451) (xy 26.670907 -228.487964) (xy 26.694579 -228.538461) (xy 26.710647 -228.591868)
			(xy 26.718767 -228.647044) (xy 26.719276 -228.67493) (xy 26.718767 -228.702816) (xy 26.710647 -228.757992)
			(xy 26.694579 -228.811399) (xy 26.670907 -228.861896) (xy 26.640134 -228.908409) (xy 26.602917 -228.949946)
			(xy 26.560049 -228.985621) (xy 26.512443 -229.014675) (xy 26.461114 -229.036487) (xy 26.407157 -229.050593)
			(xy 26.35172 -229.056693) (xy 26.295986 -229.054656) (xy 26.241143 -229.044526) (xy 26.188359 -229.026519)
			(xy 26.138759 -229.001018) (xy 26.093401 -228.968567) (xy 26.053252 -228.929858) (xy 26.019166 -228.885715)
			(xy 25.99187 -228.83708) (xy 25.971947 -228.784989) (xy 25.959821 -228.730552) (xy 25.95575 -228.67493)
			(xy 16.644362 -228.67493) (xy 16.681677 -228.705984) (xy 16.718894 -228.747521) (xy 16.749667 -228.794034)
			(xy 16.773339 -228.844531) (xy 16.789407 -228.897938) (xy 16.797527 -228.953114) (xy 16.798036 -228.981)
			(xy 16.797527 -229.008886) (xy 16.789407 -229.064062) (xy 16.773339 -229.117469) (xy 16.749667 -229.167966)
			(xy 16.718894 -229.214479) (xy 16.681677 -229.256016) (xy 16.638809 -229.291691) (xy 16.591203 -229.320745)
			(xy 16.539874 -229.342557) (xy 16.485917 -229.356663) (xy 16.43048 -229.362763) (xy 16.374746 -229.360726)
			(xy 16.319903 -229.350596) (xy 16.267119 -229.332589) (xy 16.217519 -229.307088) (xy 16.172161 -229.274637)
			(xy 16.132012 -229.235928) (xy 16.097926 -229.191785) (xy 16.07063 -229.14315) (xy 16.050707 -229.091059)
			(xy 16.038581 -229.036622) (xy 16.03451 -228.981) (xy 5.1054 -228.981) (xy 5.1054 -229.94493) (xy 12.84554 -229.94493)
			(xy 12.849611 -229.889308) (xy 12.861737 -229.834871) (xy 12.88166 -229.78278) (xy 12.908956 -229.734145)
			(xy 12.943042 -229.690002) (xy 12.983191 -229.651293) (xy 13.028549 -229.618842) (xy 13.078149 -229.593341)
			(xy 13.130933 -229.575334) (xy 13.185776 -229.565204) (xy 13.24151 -229.563167) (xy 13.296947 -229.569267)
			(xy 13.350904 -229.583373) (xy 13.402233 -229.605185) (xy 13.449839 -229.634239) (xy 13.492707 -229.669914)
			(xy 13.529924 -229.711451) (xy 13.560697 -229.757964) (xy 13.584369 -229.808461) (xy 13.600437 -229.861868)
			(xy 13.608557 -229.917044) (xy 13.609066 -229.94493) (xy 22.83028 -229.94493) (xy 22.834351 -229.889308)
			(xy 22.846477 -229.834871) (xy 22.8664 -229.78278) (xy 22.893696 -229.734145) (xy 22.927782 -229.690002)
			(xy 22.967931 -229.651293) (xy 23.013289 -229.618842) (xy 23.062889 -229.593341) (xy 23.115673 -229.575334)
			(xy 23.170516 -229.565204) (xy 23.22625 -229.563167) (xy 23.281687 -229.569267) (xy 23.335644 -229.583373)
			(xy 23.386973 -229.605185) (xy 23.434579 -229.634239) (xy 23.477447 -229.669914) (xy 23.514664 -229.711451)
			(xy 23.545437 -229.757964) (xy 23.569109 -229.808461) (xy 23.585177 -229.861868) (xy 23.593297 -229.917044)
			(xy 23.593806 -229.94493) (xy 23.593297 -229.972816) (xy 23.585177 -230.027992) (xy 23.569109 -230.081399)
			(xy 23.545437 -230.131896) (xy 23.514664 -230.178409) (xy 23.477447 -230.219946) (xy 23.434579 -230.255621)
			(xy 23.386973 -230.284675) (xy 23.335644 -230.306487) (xy 23.281687 -230.320593) (xy 23.22625 -230.326693)
			(xy 23.170516 -230.324656) (xy 23.115673 -230.314526) (xy 23.062889 -230.296519) (xy 23.013289 -230.271018)
			(xy 22.967931 -230.238567) (xy 22.927782 -230.199858) (xy 22.893696 -230.155715) (xy 22.8664 -230.10708)
			(xy 22.846477 -230.054989) (xy 22.834351 -230.000552) (xy 22.83028 -229.94493) (xy 13.609066 -229.94493)
			(xy 13.608557 -229.972816) (xy 13.600437 -230.027992) (xy 13.584369 -230.081399) (xy 13.560697 -230.131896)
			(xy 13.529924 -230.178409) (xy 13.492707 -230.219946) (xy 13.449839 -230.255621) (xy 13.402233 -230.284675)
			(xy 13.350904 -230.306487) (xy 13.296947 -230.320593) (xy 13.24151 -230.326693) (xy 13.185776 -230.324656)
			(xy 13.130933 -230.314526) (xy 13.078149 -230.296519) (xy 13.028549 -230.271018) (xy 12.983191 -230.238567)
			(xy 12.943042 -230.199858) (xy 12.908956 -230.155715) (xy 12.88166 -230.10708) (xy 12.861737 -230.054989)
			(xy 12.849611 -230.000552) (xy 12.84554 -229.94493) (xy 5.1054 -229.94493) (xy 5.1054 -231.203754)
			(xy 14.84833 -231.203754) (xy 14.852401 -231.148132) (xy 14.864527 -231.093695) (xy 14.88445 -231.041604)
			(xy 14.911746 -230.992969) (xy 14.945832 -230.948826) (xy 14.985981 -230.910117) (xy 15.031339 -230.877666)
			(xy 15.080939 -230.852165) (xy 15.133723 -230.834158) (xy 15.188566 -230.824028) (xy 15.2443 -230.821991)
			(xy 15.299737 -230.828091) (xy 15.353694 -230.842197) (xy 15.405023 -230.864009) (xy 15.452629 -230.893063)
			(xy 15.495497 -230.928738) (xy 15.532714 -230.970275) (xy 15.563487 -231.016788) (xy 15.587159 -231.067285)
			(xy 15.603227 -231.120692) (xy 15.610629 -231.170988) (xy 16.915382 -231.170988) (xy 16.919453 -231.115366)
			(xy 16.931579 -231.060929) (xy 16.951502 -231.008838) (xy 16.978798 -230.960203) (xy 17.012884 -230.91606)
			(xy 17.053033 -230.877351) (xy 17.098391 -230.8449) (xy 17.147991 -230.819399) (xy 17.200775 -230.801392)
			(xy 17.255618 -230.791262) (xy 17.311352 -230.789225) (xy 17.366789 -230.795325) (xy 17.420746 -230.809431)
			(xy 17.472075 -230.831243) (xy 17.519681 -230.860297) (xy 17.562549 -230.895972) (xy 17.599766 -230.937509)
			(xy 17.630539 -230.984022) (xy 17.654211 -231.034519) (xy 17.670279 -231.087926) (xy 17.678399 -231.143102)
			(xy 17.678908 -231.170988) (xy 17.678399 -231.198874) (xy 17.670279 -231.25405) (xy 17.654211 -231.307457)
			(xy 17.630539 -231.357954) (xy 17.599766 -231.404467) (xy 17.562549 -231.446004) (xy 17.519681 -231.481679)
			(xy 17.472075 -231.510733) (xy 17.420746 -231.532545) (xy 17.366789 -231.546651) (xy 17.311352 -231.552751)
			(xy 17.255618 -231.550714) (xy 17.200775 -231.540584) (xy 17.147991 -231.522577) (xy 17.098391 -231.497076)
			(xy 17.053033 -231.464625) (xy 17.012884 -231.425916) (xy 16.978798 -231.381773) (xy 16.951502 -231.333138)
			(xy 16.931579 -231.281047) (xy 16.919453 -231.22661) (xy 16.915382 -231.170988) (xy 15.610629 -231.170988)
			(xy 15.611347 -231.175868) (xy 15.611856 -231.203754) (xy 15.611347 -231.23164) (xy 15.603227 -231.286816)
			(xy 15.587159 -231.340223) (xy 15.563487 -231.39072) (xy 15.532714 -231.437233) (xy 15.495497 -231.47877)
			(xy 15.452629 -231.514445) (xy 15.405023 -231.543499) (xy 15.353694 -231.565311) (xy 15.299737 -231.579417)
			(xy 15.2443 -231.585517) (xy 15.188566 -231.58348) (xy 15.133723 -231.57335) (xy 15.080939 -231.555343)
			(xy 15.031339 -231.529842) (xy 14.985981 -231.497391) (xy 14.945832 -231.458682) (xy 14.911746 -231.414539)
			(xy 14.88445 -231.365904) (xy 14.864527 -231.313813) (xy 14.852401 -231.259376) (xy 14.84833 -231.203754)
			(xy 5.1054 -231.203754) (xy 5.1054 -231.95026) (xy 17.786094 -231.95026) (xy 17.790165 -231.894638)
			(xy 17.802291 -231.840201) (xy 17.822214 -231.78811) (xy 17.84951 -231.739475) (xy 17.883596 -231.695332)
			(xy 17.923745 -231.656623) (xy 17.969103 -231.624172) (xy 18.018703 -231.598671) (xy 18.071487 -231.580664)
			(xy 18.12633 -231.570534) (xy 18.182064 -231.568497) (xy 18.237501 -231.574597) (xy 18.291458 -231.588703)
			(xy 18.342787 -231.610515) (xy 18.390393 -231.639569) (xy 18.433261 -231.675244) (xy 18.470478 -231.716781)
			(xy 18.501251 -231.763294) (xy 18.524923 -231.813791) (xy 18.540991 -231.867198) (xy 18.549111 -231.922374)
			(xy 18.54962 -231.95026) (xy 18.549111 -231.978146) (xy 18.540991 -232.033322) (xy 18.524923 -232.086729)
			(xy 18.501251 -232.137226) (xy 18.470478 -232.183739) (xy 18.433261 -232.225276) (xy 18.390393 -232.260951)
			(xy 18.342787 -232.290005) (xy 18.291458 -232.311817) (xy 18.237501 -232.325923) (xy 18.182064 -232.332023)
			(xy 18.12633 -232.329986) (xy 18.071487 -232.319856) (xy 18.018703 -232.301849) (xy 17.969103 -232.276348)
			(xy 17.923745 -232.243897) (xy 17.883596 -232.205188) (xy 17.84951 -232.161045) (xy 17.822214 -232.11241)
			(xy 17.802291 -232.060319) (xy 17.790165 -232.005882) (xy 17.786094 -231.95026) (xy 5.1054 -231.95026)
			(xy 5.1054 -232.77322) (xy 11.918948 -232.77322) (xy 11.923019 -232.717598) (xy 11.935145 -232.663161)
			(xy 11.955068 -232.61107) (xy 11.982364 -232.562435) (xy 12.01645 -232.518292) (xy 12.056599 -232.479583)
			(xy 12.101957 -232.447132) (xy 12.151557 -232.421631) (xy 12.204341 -232.403624) (xy 12.259184 -232.393494)
			(xy 12.314918 -232.391457) (xy 12.370355 -232.397557) (xy 12.424312 -232.411663) (xy 12.475641 -232.433475)
			(xy 12.523247 -232.462529) (xy 12.566115 -232.498204) (xy 12.603332 -232.539741) (xy 12.634105 -232.586254)
			(xy 12.657777 -232.636751) (xy 12.673845 -232.690158) (xy 12.681965 -232.745334) (xy 12.682474 -232.77322)
			(xy 12.681965 -232.801106) (xy 12.673845 -232.856282) (xy 12.657777 -232.909689) (xy 12.634105 -232.960186)
			(xy 12.603332 -233.006699) (xy 12.566115 -233.048236) (xy 12.523247 -233.083911) (xy 12.475641 -233.112965)
			(xy 12.424312 -233.134777) (xy 12.370355 -233.148883) (xy 12.314918 -233.154983) (xy 12.259184 -233.152946)
			(xy 12.204341 -233.142816) (xy 12.151557 -233.124809) (xy 12.101957 -233.099308) (xy 12.056599 -233.066857)
			(xy 12.01645 -233.028148) (xy 11.982364 -232.984005) (xy 11.955068 -232.93537) (xy 11.935145 -232.883279)
			(xy 11.923019 -232.828842) (xy 11.918948 -232.77322) (xy 5.1054 -232.77322) (xy 5.1054 -233.590846)
			(xy 11.623038 -233.590846) (xy 11.627109 -233.535224) (xy 11.639235 -233.480787) (xy 11.659158 -233.428696)
			(xy 11.686454 -233.380061) (xy 11.72054 -233.335918) (xy 11.760689 -233.297209) (xy 11.806047 -233.264758)
			(xy 11.855647 -233.239257) (xy 11.908431 -233.22125) (xy 11.963274 -233.21112) (xy 12.019008 -233.209083)
			(xy 12.074445 -233.215183) (xy 12.128402 -233.229289) (xy 12.179731 -233.251101) (xy 12.227337 -233.280155)
			(xy 12.270205 -233.31583) (xy 12.307422 -233.357367) (xy 12.338195 -233.40388) (xy 12.361867 -233.454377)
			(xy 12.377935 -233.507784) (xy 12.386055 -233.56296) (xy 12.386564 -233.590846) (xy 12.386055 -233.618732)
			(xy 12.377935 -233.673908) (xy 12.361867 -233.727315) (xy 12.338195 -233.777812) (xy 12.307422 -233.824325)
			(xy 12.270205 -233.865862) (xy 12.227337 -233.901537) (xy 12.179731 -233.930591) (xy 12.128402 -233.952403)
			(xy 12.074445 -233.966509) (xy 12.019008 -233.972609) (xy 11.963274 -233.970572) (xy 11.908431 -233.960442)
			(xy 11.855647 -233.942435) (xy 11.806047 -233.916934) (xy 11.760689 -233.884483) (xy 11.72054 -233.845774)
			(xy 11.686454 -233.801631) (xy 11.659158 -233.752996) (xy 11.639235 -233.700905) (xy 11.627109 -233.646468)
			(xy 11.623038 -233.590846) (xy 5.1054 -233.590846) (xy 5.1054 -240.304828) (xy 20.088604 -240.304828)
			(xy 20.092675 -240.249206) (xy 20.104801 -240.194769) (xy 20.124724 -240.142678) (xy 20.15202 -240.094043)
			(xy 20.186106 -240.0499) (xy 20.226255 -240.011191) (xy 20.271613 -239.97874) (xy 20.321213 -239.953239)
			(xy 20.373997 -239.935232) (xy 20.42884 -239.925102) (xy 20.484574 -239.923065) (xy 20.540011 -239.929165)
			(xy 20.593968 -239.943271) (xy 20.645297 -239.965083) (xy 20.692903 -239.994137) (xy 20.735771 -240.029812)
			(xy 20.772988 -240.071349) (xy 20.803761 -240.117862) (xy 20.827433 -240.168359) (xy 20.843501 -240.221766)
			(xy 20.851621 -240.276942) (xy 20.85213 -240.304828) (xy 20.851621 -240.332714) (xy 20.843501 -240.38789)
			(xy 20.827433 -240.441297) (xy 20.803761 -240.491794) (xy 20.772988 -240.538307) (xy 20.735771 -240.579844)
			(xy 20.692903 -240.615519) (xy 20.645297 -240.644573) (xy 20.593968 -240.666385) (xy 20.540011 -240.680491)
			(xy 20.484574 -240.686591) (xy 20.42884 -240.684554) (xy 20.373997 -240.674424) (xy 20.321213 -240.656417)
			(xy 20.271613 -240.630916) (xy 20.226255 -240.598465) (xy 20.186106 -240.559756) (xy 20.15202 -240.515613)
			(xy 20.124724 -240.466978) (xy 20.104801 -240.414887) (xy 20.092675 -240.36045) (xy 20.088604 -240.304828)
			(xy 5.1054 -240.304828) (xy 5.1054 -241.112294) (xy 19.4724 -241.112294) (xy 19.476471 -241.056672)
			(xy 19.488597 -241.002235) (xy 19.50852 -240.950144) (xy 19.535816 -240.901509) (xy 19.569902 -240.857366)
			(xy 19.610051 -240.818657) (xy 19.655409 -240.786206) (xy 19.705009 -240.760705) (xy 19.757793 -240.742698)
			(xy 19.812636 -240.732568) (xy 19.86837 -240.730531) (xy 19.923807 -240.736631) (xy 19.977764 -240.750737)
			(xy 20.029093 -240.772549) (xy 20.076699 -240.801603) (xy 20.119567 -240.837278) (xy 20.156784 -240.878815)
			(xy 20.187557 -240.925328) (xy 20.211229 -240.975825) (xy 20.227297 -241.029232) (xy 20.235417 -241.084408)
			(xy 20.235926 -241.112294) (xy 20.235417 -241.14018) (xy 20.227297 -241.195356) (xy 20.211229 -241.248763)
			(xy 20.187557 -241.29926) (xy 20.156784 -241.345773) (xy 20.119567 -241.38731) (xy 20.076699 -241.422985)
			(xy 20.029093 -241.452039) (xy 19.977764 -241.473851) (xy 19.923807 -241.487957) (xy 19.86837 -241.494057)
			(xy 19.812636 -241.49202) (xy 19.757793 -241.48189) (xy 19.705009 -241.463883) (xy 19.655409 -241.438382)
			(xy 19.610051 -241.405931) (xy 19.569902 -241.367222) (xy 19.535816 -241.323079) (xy 19.50852 -241.274444)
			(xy 19.488597 -241.222353) (xy 19.476471 -241.167916) (xy 19.4724 -241.112294) (xy 5.1054 -241.112294)
			(xy 5.1054 -242.168934) (xy 19.00631 -242.168934) (xy 19.010381 -242.113312) (xy 19.022507 -242.058875)
			(xy 19.04243 -242.006784) (xy 19.069726 -241.958149) (xy 19.103812 -241.914006) (xy 19.143961 -241.875297)
			(xy 19.189319 -241.842846) (xy 19.238919 -241.817345) (xy 19.291703 -241.799338) (xy 19.346546 -241.789208)
			(xy 19.40228 -241.787171) (xy 19.457717 -241.793271) (xy 19.511674 -241.807377) (xy 19.563003 -241.829189)
			(xy 19.610609 -241.858243) (xy 19.653477 -241.893918) (xy 19.690694 -241.935455) (xy 19.721467 -241.981968)
			(xy 19.745139 -242.032465) (xy 19.761207 -242.085872) (xy 19.769327 -242.141048) (xy 19.769836 -242.168934)
			(xy 19.769327 -242.19682) (xy 19.761207 -242.251996) (xy 19.745139 -242.305403) (xy 19.721467 -242.3559)
			(xy 19.690694 -242.402413) (xy 19.653477 -242.44395) (xy 19.610609 -242.479625) (xy 19.563003 -242.508679)
			(xy 19.511674 -242.530491) (xy 19.457717 -242.544597) (xy 19.40228 -242.550697) (xy 19.346546 -242.54866)
			(xy 19.291703 -242.53853) (xy 19.238919 -242.520523) (xy 19.189319 -242.495022) (xy 19.143961 -242.462571)
			(xy 19.103812 -242.423862) (xy 19.069726 -242.379719) (xy 19.04243 -242.331084) (xy 19.022507 -242.278993)
			(xy 19.010381 -242.224556) (xy 19.00631 -242.168934) (xy 5.1054 -242.168934) (xy 5.1054 -249.00382)
			(xy 24.976836 -249.00382) (xy 24.97731 -248.976214) (xy 24.985267 -248.921579) (xy 25.001016 -248.868662)
			(xy 25.02423 -248.818567) (xy 25.054422 -248.772343) (xy 25.090963 -248.730954) (xy 25.11171 -248.712736)
			(xy 25.11933 -248.706386) (xy 25.128728 -248.688352) (xy 25.136094 -248.596658) (xy 25.129998 -248.577354)
			(xy 25.123394 -248.569734) (xy 25.10644 -248.54898) (xy 25.07791 -248.503616) (xy 25.056009 -248.454706)
			(xy 25.041166 -248.403212) (xy 25.033674 -248.350149) (xy 25.033224 -248.323354) (xy 25.03371 -248.296103)
			(xy 25.041466 -248.242155) (xy 25.056821 -248.18986) (xy 25.079463 -248.140283) (xy 25.108929 -248.094433)
			(xy 25.14462 -248.053242) (xy 25.185811 -248.017551) (xy 25.231661 -247.988085) (xy 25.281238 -247.965443)
			(xy 25.333533 -247.950088) (xy 25.387481 -247.942332) (xy 25.441983 -247.942332) (xy 25.495931 -247.950088)
			(xy 25.548226 -247.965443) (xy 25.597803 -247.988085) (xy 25.643653 -248.017551) (xy 25.684844 -248.053242)
			(xy 25.720535 -248.094433) (xy 25.750001 -248.140283) (xy 25.772643 -248.18986) (xy 25.787998 -248.242155)
			(xy 25.795754 -248.296103) (xy 25.79624 -248.323354) (xy 25.795756 -248.35096) (xy 25.787803 -248.405595)
			(xy 25.772056 -248.458512) (xy 25.748844 -248.508607) (xy 25.718653 -248.554832) (xy 25.682113 -248.596221)
			(xy 25.661366 -248.614438) (xy 25.653746 -248.620788) (xy 25.644348 -248.638822) (xy 25.636982 -248.730516)
			(xy 25.643078 -248.74982) (xy 25.649682 -248.75744) (xy 25.666636 -248.778194) (xy 25.695163 -248.82356)
			(xy 25.717063 -248.87247) (xy 25.731907 -248.923962) (xy 25.7394 -248.977025) (xy 25.739852 -249.00382)
			(xy 25.992836 -249.00382) (xy 25.993288 -248.97683) (xy 26.000894 -248.92339) (xy 26.015958 -248.871555)
			(xy 26.038178 -248.822361) (xy 26.067112 -248.776791) (xy 26.10218 -248.735755) (xy 26.122122 -248.717562)
			(xy 26.129418 -248.710472) (xy 26.138188 -248.692132) (xy 26.13914 -248.682002) (xy 26.14295 -248.609612)
			(xy 26.14299 -248.59934) (xy 26.135915 -248.580076) (xy 26.129234 -248.572274) (xy 26.110197 -248.550977)
			(xy 26.078029 -248.503778) (xy 26.053252 -248.452311) (xy 26.036422 -248.397728) (xy 26.027912 -248.341246)
			(xy 26.02738 -248.312686) (xy 26.027866 -248.285435) (xy 26.035622 -248.231487) (xy 26.050977 -248.179192)
			(xy 26.073619 -248.129615) (xy 26.103085 -248.083765) (xy 26.138776 -248.042574) (xy 26.179967 -248.006883)
			(xy 26.225817 -247.977417) (xy 26.275394 -247.954775) (xy 26.327689 -247.93942) (xy 26.381637 -247.931664)
			(xy 26.436139 -247.931664) (xy 26.490087 -247.93942) (xy 26.542382 -247.954775) (xy 26.591959 -247.977417)
			(xy 26.637809 -248.006883) (xy 26.679 -248.042574) (xy 26.714691 -248.083765) (xy 26.744157 -248.129615)
			(xy 26.766799 -248.179192) (xy 26.782154 -248.231487) (xy 26.78991 -248.285435) (xy 26.790396 -248.312686)
			(xy 26.789971 -248.339677) (xy 26.782362 -248.39312) (xy 26.767295 -248.444956) (xy 26.745069 -248.49415)
			(xy 26.71613 -248.539719) (xy 26.681056 -248.580753) (xy 26.66111 -248.598944) (xy 26.653801 -248.606022)
			(xy 26.64504 -248.624372) (xy 26.644092 -248.634504) (xy 26.640282 -248.706894) (xy 26.640231 -248.717167)
			(xy 26.647313 -248.736431) (xy 26.653998 -248.744232) (xy 26.673026 -248.765536) (xy 26.705199 -248.812732)
			(xy 26.729978 -248.864197) (xy 26.74681 -248.918779) (xy 26.75532 -248.975261) (xy 26.755852 -249.00382)
			(xy 26.755366 -249.031071) (xy 26.74761 -249.085019) (xy 26.732255 -249.137314) (xy 26.709613 -249.186891)
			(xy 26.680147 -249.232741) (xy 26.644456 -249.273932) (xy 26.603265 -249.309623) (xy 26.557415 -249.339089)
			(xy 26.507838 -249.361731) (xy 26.455543 -249.377086) (xy 26.401595 -249.384842) (xy 26.347093 -249.384842)
			(xy 26.293145 -249.377086) (xy 26.24085 -249.361731) (xy 26.191273 -249.339089) (xy 26.145423 -249.309623)
			(xy 26.104232 -249.273932) (xy 26.068541 -249.232741) (xy 26.039075 -249.186891) (xy 26.016433 -249.137314)
			(xy 26.001078 -249.085019) (xy 25.993322 -249.031071) (xy 25.992836 -249.00382) (xy 25.739852 -249.00382)
			(xy 25.739366 -249.031071) (xy 25.73161 -249.085019) (xy 25.716255 -249.137314) (xy 25.693613 -249.186891)
			(xy 25.664147 -249.232741) (xy 25.628456 -249.273932) (xy 25.587265 -249.309623) (xy 25.541415 -249.339089)
			(xy 25.491838 -249.361731) (xy 25.439543 -249.377086) (xy 25.385595 -249.384842) (xy 25.331093 -249.384842)
			(xy 25.277145 -249.377086) (xy 25.22485 -249.361731) (xy 25.175273 -249.339089) (xy 25.129423 -249.309623)
			(xy 25.088232 -249.273932) (xy 25.052541 -249.232741) (xy 25.023075 -249.186891) (xy 25.000433 -249.137314)
			(xy 24.985078 -249.085019) (xy 24.977322 -249.031071) (xy 24.976836 -249.00382) (xy 5.1054 -249.00382)
			(xy 5.1054 -249.235214) (xy 5.106416 -249.244866) (xy 5.108045 -249.252109) (xy 5.114887 -249.265277)
			(xy 5.119878 -249.270774) (xy 7.007606 -251.158502) (xy 23.960326 -251.158502) (xy 23.964397 -251.10288)
			(xy 23.976523 -251.048443) (xy 23.996446 -250.996352) (xy 24.023742 -250.947717) (xy 24.057828 -250.903574)
			(xy 24.097977 -250.864865) (xy 24.143335 -250.832414) (xy 24.192935 -250.806913) (xy 24.245719 -250.788906)
			(xy 24.300562 -250.778776) (xy 24.356296 -250.776739) (xy 24.411733 -250.782839) (xy 24.46569 -250.796945)
			(xy 24.517019 -250.818757) (xy 24.564625 -250.847811) (xy 24.607493 -250.883486) (xy 24.64471 -250.925023)
			(xy 24.675483 -250.971536) (xy 24.699155 -251.022033) (xy 24.715223 -251.07544) (xy 24.723343 -251.130616)
			(xy 24.723792 -251.1552) (xy 25.068782 -251.1552) (xy 25.072853 -251.099578) (xy 25.084979 -251.045141)
			(xy 25.104902 -250.99305) (xy 25.132198 -250.944415) (xy 25.166284 -250.900272) (xy 25.206433 -250.861563)
			(xy 25.251791 -250.829112) (xy 25.301391 -250.803611) (xy 25.354175 -250.785604) (xy 25.409018 -250.775474)
			(xy 25.464752 -250.773437) (xy 25.520189 -250.779537) (xy 25.574146 -250.793643) (xy 25.625475 -250.815455)
			(xy 25.673081 -250.844509) (xy 25.715949 -250.880184) (xy 25.753166 -250.921721) (xy 25.783939 -250.968234)
			(xy 25.807611 -251.018731) (xy 25.823679 -251.072138) (xy 25.831799 -251.127314) (xy 25.832308 -251.1552)
			(xy 25.832248 -251.158502) (xy 25.992326 -251.158502) (xy 25.996397 -251.10288) (xy 26.008523 -251.048443)
			(xy 26.028446 -250.996352) (xy 26.055742 -250.947717) (xy 26.089828 -250.903574) (xy 26.129977 -250.864865)
			(xy 26.175335 -250.832414) (xy 26.224935 -250.806913) (xy 26.277719 -250.788906) (xy 26.332562 -250.778776)
			(xy 26.388296 -250.776739) (xy 26.443733 -250.782839) (xy 26.49769 -250.796945) (xy 26.549019 -250.818757)
			(xy 26.596625 -250.847811) (xy 26.639493 -250.883486) (xy 26.67671 -250.925023) (xy 26.707483 -250.971536)
			(xy 26.731155 -251.022033) (xy 26.747223 -251.07544) (xy 26.755343 -251.130616) (xy 26.755852 -251.158502)
			(xy 27.008326 -251.158502) (xy 27.012397 -251.10288) (xy 27.024523 -251.048443) (xy 27.044446 -250.996352)
			(xy 27.071742 -250.947717) (xy 27.105828 -250.903574) (xy 27.145977 -250.864865) (xy 27.191335 -250.832414)
			(xy 27.240935 -250.806913) (xy 27.293719 -250.788906) (xy 27.348562 -250.778776) (xy 27.404296 -250.776739)
			(xy 27.459733 -250.782839) (xy 27.51369 -250.796945) (xy 27.565019 -250.818757) (xy 27.612625 -250.847811)
			(xy 27.655493 -250.883486) (xy 27.69271 -250.925023) (xy 27.723483 -250.971536) (xy 27.747155 -251.022033)
			(xy 27.763223 -251.07544) (xy 27.771343 -251.130616) (xy 27.771852 -251.158502) (xy 28.024326 -251.158502)
			(xy 28.028397 -251.10288) (xy 28.040523 -251.048443) (xy 28.060446 -250.996352) (xy 28.087742 -250.947717)
			(xy 28.121828 -250.903574) (xy 28.161977 -250.864865) (xy 28.207335 -250.832414) (xy 28.256935 -250.806913)
			(xy 28.309719 -250.788906) (xy 28.364562 -250.778776) (xy 28.420296 -250.776739) (xy 28.475733 -250.782839)
			(xy 28.52969 -250.796945) (xy 28.581019 -250.818757) (xy 28.628625 -250.847811) (xy 28.671493 -250.883486)
			(xy 28.70871 -250.925023) (xy 28.739483 -250.971536) (xy 28.763155 -251.022033) (xy 28.779223 -251.07544)
			(xy 28.787343 -251.130616) (xy 28.787852 -251.158502) (xy 29.040326 -251.158502) (xy 29.044397 -251.10288)
			(xy 29.056523 -251.048443) (xy 29.076446 -250.996352) (xy 29.103742 -250.947717) (xy 29.137828 -250.903574)
			(xy 29.177977 -250.864865) (xy 29.223335 -250.832414) (xy 29.272935 -250.806913) (xy 29.325719 -250.788906)
			(xy 29.380562 -250.778776) (xy 29.436296 -250.776739) (xy 29.491733 -250.782839) (xy 29.54569 -250.796945)
			(xy 29.597019 -250.818757) (xy 29.644625 -250.847811) (xy 29.687493 -250.883486) (xy 29.72471 -250.925023)
			(xy 29.755483 -250.971536) (xy 29.779155 -251.022033) (xy 29.795223 -251.07544) (xy 29.803343 -251.130616)
			(xy 29.803852 -251.158502) (xy 30.056326 -251.158502) (xy 30.060397 -251.10288) (xy 30.072523 -251.048443)
			(xy 30.092446 -250.996352) (xy 30.119742 -250.947717) (xy 30.153828 -250.903574) (xy 30.193977 -250.864865)
			(xy 30.239335 -250.832414) (xy 30.288935 -250.806913) (xy 30.341719 -250.788906) (xy 30.396562 -250.778776)
			(xy 30.452296 -250.776739) (xy 30.507733 -250.782839) (xy 30.56169 -250.796945) (xy 30.613019 -250.818757)
			(xy 30.660625 -250.847811) (xy 30.703493 -250.883486) (xy 30.74071 -250.925023) (xy 30.771483 -250.971536)
			(xy 30.795155 -251.022033) (xy 30.811223 -251.07544) (xy 30.819343 -251.130616) (xy 30.819852 -251.158502)
			(xy 31.072326 -251.158502) (xy 31.076397 -251.10288) (xy 31.088523 -251.048443) (xy 31.108446 -250.996352)
			(xy 31.135742 -250.947717) (xy 31.169828 -250.903574) (xy 31.209977 -250.864865) (xy 31.255335 -250.832414)
			(xy 31.304935 -250.806913) (xy 31.357719 -250.788906) (xy 31.412562 -250.778776) (xy 31.468296 -250.776739)
			(xy 31.523733 -250.782839) (xy 31.57769 -250.796945) (xy 31.629019 -250.818757) (xy 31.676625 -250.847811)
			(xy 31.719493 -250.883486) (xy 31.75671 -250.925023) (xy 31.787483 -250.971536) (xy 31.811155 -251.022033)
			(xy 31.827223 -251.07544) (xy 31.835343 -251.130616) (xy 31.835852 -251.158502) (xy 32.088326 -251.158502)
			(xy 32.092397 -251.10288) (xy 32.104523 -251.048443) (xy 32.124446 -250.996352) (xy 32.151742 -250.947717)
			(xy 32.185828 -250.903574) (xy 32.225977 -250.864865) (xy 32.271335 -250.832414) (xy 32.320935 -250.806913)
			(xy 32.373719 -250.788906) (xy 32.428562 -250.778776) (xy 32.484296 -250.776739) (xy 32.539733 -250.782839)
			(xy 32.59369 -250.796945) (xy 32.645019 -250.818757) (xy 32.692625 -250.847811) (xy 32.735493 -250.883486)
			(xy 32.77271 -250.925023) (xy 32.803483 -250.971536) (xy 32.827155 -251.022033) (xy 32.843223 -251.07544)
			(xy 32.851343 -251.130616) (xy 32.851852 -251.158502) (xy 33.104326 -251.158502) (xy 33.108397 -251.10288)
			(xy 33.120523 -251.048443) (xy 33.140446 -250.996352) (xy 33.167742 -250.947717) (xy 33.201828 -250.903574)
			(xy 33.241977 -250.864865) (xy 33.287335 -250.832414) (xy 33.336935 -250.806913) (xy 33.389719 -250.788906)
			(xy 33.444562 -250.778776) (xy 33.500296 -250.776739) (xy 33.555733 -250.782839) (xy 33.60969 -250.796945)
			(xy 33.661019 -250.818757) (xy 33.708625 -250.847811) (xy 33.751493 -250.883486) (xy 33.78871 -250.925023)
			(xy 33.819483 -250.971536) (xy 33.843155 -251.022033) (xy 33.859223 -251.07544) (xy 33.867343 -251.130616)
			(xy 33.867852 -251.158502) (xy 34.120326 -251.158502) (xy 34.124397 -251.10288) (xy 34.136523 -251.048443)
			(xy 34.156446 -250.996352) (xy 34.183742 -250.947717) (xy 34.217828 -250.903574) (xy 34.257977 -250.864865)
			(xy 34.303335 -250.832414) (xy 34.352935 -250.806913) (xy 34.405719 -250.788906) (xy 34.460562 -250.778776)
			(xy 34.516296 -250.776739) (xy 34.571733 -250.782839) (xy 34.62569 -250.796945) (xy 34.677019 -250.818757)
			(xy 34.724625 -250.847811) (xy 34.767493 -250.883486) (xy 34.80471 -250.925023) (xy 34.835483 -250.971536)
			(xy 34.859155 -251.022033) (xy 34.875223 -251.07544) (xy 34.883343 -251.130616) (xy 34.883852 -251.158502)
			(xy 35.136326 -251.158502) (xy 35.140397 -251.10288) (xy 35.152523 -251.048443) (xy 35.172446 -250.996352)
			(xy 35.199742 -250.947717) (xy 35.233828 -250.903574) (xy 35.273977 -250.864865) (xy 35.319335 -250.832414)
			(xy 35.368935 -250.806913) (xy 35.421719 -250.788906) (xy 35.476562 -250.778776) (xy 35.532296 -250.776739)
			(xy 35.587733 -250.782839) (xy 35.64169 -250.796945) (xy 35.693019 -250.818757) (xy 35.740625 -250.847811)
			(xy 35.783493 -250.883486) (xy 35.82071 -250.925023) (xy 35.851483 -250.971536) (xy 35.875155 -251.022033)
			(xy 35.891223 -251.07544) (xy 35.899343 -251.130616) (xy 35.899852 -251.158502) (xy 36.152326 -251.158502)
			(xy 36.156397 -251.10288) (xy 36.168523 -251.048443) (xy 36.188446 -250.996352) (xy 36.215742 -250.947717)
			(xy 36.249828 -250.903574) (xy 36.289977 -250.864865) (xy 36.335335 -250.832414) (xy 36.384935 -250.806913)
			(xy 36.437719 -250.788906) (xy 36.492562 -250.778776) (xy 36.548296 -250.776739) (xy 36.603733 -250.782839)
			(xy 36.65769 -250.796945) (xy 36.709019 -250.818757) (xy 36.756625 -250.847811) (xy 36.799493 -250.883486)
			(xy 36.83671 -250.925023) (xy 36.867483 -250.971536) (xy 36.891155 -251.022033) (xy 36.907223 -251.07544)
			(xy 36.915343 -251.130616) (xy 36.915852 -251.158502) (xy 37.168326 -251.158502) (xy 37.172397 -251.10288)
			(xy 37.184523 -251.048443) (xy 37.204446 -250.996352) (xy 37.231742 -250.947717) (xy 37.265828 -250.903574)
			(xy 37.305977 -250.864865) (xy 37.351335 -250.832414) (xy 37.400935 -250.806913) (xy 37.453719 -250.788906)
			(xy 37.508562 -250.778776) (xy 37.564296 -250.776739) (xy 37.619733 -250.782839) (xy 37.67369 -250.796945)
			(xy 37.725019 -250.818757) (xy 37.772625 -250.847811) (xy 37.815493 -250.883486) (xy 37.85271 -250.925023)
			(xy 37.883483 -250.971536) (xy 37.907155 -251.022033) (xy 37.923223 -251.07544) (xy 37.931343 -251.130616)
			(xy 37.931852 -251.158502) (xy 38.184326 -251.158502) (xy 38.188397 -251.10288) (xy 38.200523 -251.048443)
			(xy 38.220446 -250.996352) (xy 38.247742 -250.947717) (xy 38.281828 -250.903574) (xy 38.321977 -250.864865)
			(xy 38.367335 -250.832414) (xy 38.416935 -250.806913) (xy 38.469719 -250.788906) (xy 38.524562 -250.778776)
			(xy 38.580296 -250.776739) (xy 38.635733 -250.782839) (xy 38.68969 -250.796945) (xy 38.741019 -250.818757)
			(xy 38.788625 -250.847811) (xy 38.831493 -250.883486) (xy 38.86871 -250.925023) (xy 38.899483 -250.971536)
			(xy 38.923155 -251.022033) (xy 38.939223 -251.07544) (xy 38.947343 -251.130616) (xy 38.947852 -251.158502)
			(xy 38.947343 -251.186388) (xy 38.939223 -251.241564) (xy 38.923155 -251.294971) (xy 38.899483 -251.345468)
			(xy 38.86871 -251.391981) (xy 38.831493 -251.433518) (xy 38.788625 -251.469193) (xy 38.741019 -251.498247)
			(xy 38.68969 -251.520059) (xy 38.635733 -251.534165) (xy 38.580296 -251.540265) (xy 38.524562 -251.538228)
			(xy 38.469719 -251.528098) (xy 38.416935 -251.510091) (xy 38.367335 -251.48459) (xy 38.321977 -251.452139)
			(xy 38.281828 -251.41343) (xy 38.247742 -251.369287) (xy 38.220446 -251.320652) (xy 38.200523 -251.268561)
			(xy 38.188397 -251.214124) (xy 38.184326 -251.158502) (xy 37.931852 -251.158502) (xy 37.931343 -251.186388)
			(xy 37.923223 -251.241564) (xy 37.907155 -251.294971) (xy 37.883483 -251.345468) (xy 37.85271 -251.391981)
			(xy 37.815493 -251.433518) (xy 37.772625 -251.469193) (xy 37.725019 -251.498247) (xy 37.67369 -251.520059)
			(xy 37.619733 -251.534165) (xy 37.564296 -251.540265) (xy 37.508562 -251.538228) (xy 37.453719 -251.528098)
			(xy 37.400935 -251.510091) (xy 37.351335 -251.48459) (xy 37.305977 -251.452139) (xy 37.265828 -251.41343)
			(xy 37.231742 -251.369287) (xy 37.204446 -251.320652) (xy 37.184523 -251.268561) (xy 37.172397 -251.214124)
			(xy 37.168326 -251.158502) (xy 36.915852 -251.158502) (xy 36.915343 -251.186388) (xy 36.907223 -251.241564)
			(xy 36.891155 -251.294971) (xy 36.867483 -251.345468) (xy 36.83671 -251.391981) (xy 36.799493 -251.433518)
			(xy 36.756625 -251.469193) (xy 36.709019 -251.498247) (xy 36.65769 -251.520059) (xy 36.603733 -251.534165)
			(xy 36.548296 -251.540265) (xy 36.492562 -251.538228) (xy 36.437719 -251.528098) (xy 36.384935 -251.510091)
			(xy 36.335335 -251.48459) (xy 36.289977 -251.452139) (xy 36.249828 -251.41343) (xy 36.215742 -251.369287)
			(xy 36.188446 -251.320652) (xy 36.168523 -251.268561) (xy 36.156397 -251.214124) (xy 36.152326 -251.158502)
			(xy 35.899852 -251.158502) (xy 35.899343 -251.186388) (xy 35.891223 -251.241564) (xy 35.875155 -251.294971)
			(xy 35.851483 -251.345468) (xy 35.82071 -251.391981) (xy 35.783493 -251.433518) (xy 35.740625 -251.469193)
			(xy 35.693019 -251.498247) (xy 35.64169 -251.520059) (xy 35.587733 -251.534165) (xy 35.532296 -251.540265)
			(xy 35.476562 -251.538228) (xy 35.421719 -251.528098) (xy 35.368935 -251.510091) (xy 35.319335 -251.48459)
			(xy 35.273977 -251.452139) (xy 35.233828 -251.41343) (xy 35.199742 -251.369287) (xy 35.172446 -251.320652)
			(xy 35.152523 -251.268561) (xy 35.140397 -251.214124) (xy 35.136326 -251.158502) (xy 34.883852 -251.158502)
			(xy 34.883343 -251.186388) (xy 34.875223 -251.241564) (xy 34.859155 -251.294971) (xy 34.835483 -251.345468)
			(xy 34.80471 -251.391981) (xy 34.767493 -251.433518) (xy 34.724625 -251.469193) (xy 34.677019 -251.498247)
			(xy 34.62569 -251.520059) (xy 34.571733 -251.534165) (xy 34.516296 -251.540265) (xy 34.460562 -251.538228)
			(xy 34.405719 -251.528098) (xy 34.352935 -251.510091) (xy 34.303335 -251.48459) (xy 34.257977 -251.452139)
			(xy 34.217828 -251.41343) (xy 34.183742 -251.369287) (xy 34.156446 -251.320652) (xy 34.136523 -251.268561)
			(xy 34.124397 -251.214124) (xy 34.120326 -251.158502) (xy 33.867852 -251.158502) (xy 33.867343 -251.186388)
			(xy 33.859223 -251.241564) (xy 33.843155 -251.294971) (xy 33.819483 -251.345468) (xy 33.78871 -251.391981)
			(xy 33.751493 -251.433518) (xy 33.708625 -251.469193) (xy 33.661019 -251.498247) (xy 33.60969 -251.520059)
			(xy 33.555733 -251.534165) (xy 33.500296 -251.540265) (xy 33.444562 -251.538228) (xy 33.389719 -251.528098)
			(xy 33.336935 -251.510091) (xy 33.287335 -251.48459) (xy 33.241977 -251.452139) (xy 33.201828 -251.41343)
			(xy 33.167742 -251.369287) (xy 33.140446 -251.320652) (xy 33.120523 -251.268561) (xy 33.108397 -251.214124)
			(xy 33.104326 -251.158502) (xy 32.851852 -251.158502) (xy 32.851343 -251.186388) (xy 32.843223 -251.241564)
			(xy 32.827155 -251.294971) (xy 32.803483 -251.345468) (xy 32.77271 -251.391981) (xy 32.735493 -251.433518)
			(xy 32.692625 -251.469193) (xy 32.645019 -251.498247) (xy 32.59369 -251.520059) (xy 32.539733 -251.534165)
			(xy 32.484296 -251.540265) (xy 32.428562 -251.538228) (xy 32.373719 -251.528098) (xy 32.320935 -251.510091)
			(xy 32.271335 -251.48459) (xy 32.225977 -251.452139) (xy 32.185828 -251.41343) (xy 32.151742 -251.369287)
			(xy 32.124446 -251.320652) (xy 32.104523 -251.268561) (xy 32.092397 -251.214124) (xy 32.088326 -251.158502)
			(xy 31.835852 -251.158502) (xy 31.835343 -251.186388) (xy 31.827223 -251.241564) (xy 31.811155 -251.294971)
			(xy 31.787483 -251.345468) (xy 31.75671 -251.391981) (xy 31.719493 -251.433518) (xy 31.676625 -251.469193)
			(xy 31.629019 -251.498247) (xy 31.57769 -251.520059) (xy 31.523733 -251.534165) (xy 31.468296 -251.540265)
			(xy 31.412562 -251.538228) (xy 31.357719 -251.528098) (xy 31.304935 -251.510091) (xy 31.255335 -251.48459)
			(xy 31.209977 -251.452139) (xy 31.169828 -251.41343) (xy 31.135742 -251.369287) (xy 31.108446 -251.320652)
			(xy 31.088523 -251.268561) (xy 31.076397 -251.214124) (xy 31.072326 -251.158502) (xy 30.819852 -251.158502)
			(xy 30.819343 -251.186388) (xy 30.811223 -251.241564) (xy 30.795155 -251.294971) (xy 30.771483 -251.345468)
			(xy 30.74071 -251.391981) (xy 30.703493 -251.433518) (xy 30.660625 -251.469193) (xy 30.613019 -251.498247)
			(xy 30.56169 -251.520059) (xy 30.507733 -251.534165) (xy 30.452296 -251.540265) (xy 30.396562 -251.538228)
			(xy 30.341719 -251.528098) (xy 30.288935 -251.510091) (xy 30.239335 -251.48459) (xy 30.193977 -251.452139)
			(xy 30.153828 -251.41343) (xy 30.119742 -251.369287) (xy 30.092446 -251.320652) (xy 30.072523 -251.268561)
			(xy 30.060397 -251.214124) (xy 30.056326 -251.158502) (xy 29.803852 -251.158502) (xy 29.803343 -251.186388)
			(xy 29.795223 -251.241564) (xy 29.779155 -251.294971) (xy 29.755483 -251.345468) (xy 29.72471 -251.391981)
			(xy 29.687493 -251.433518) (xy 29.644625 -251.469193) (xy 29.597019 -251.498247) (xy 29.54569 -251.520059)
			(xy 29.491733 -251.534165) (xy 29.436296 -251.540265) (xy 29.380562 -251.538228) (xy 29.325719 -251.528098)
			(xy 29.272935 -251.510091) (xy 29.223335 -251.48459) (xy 29.177977 -251.452139) (xy 29.137828 -251.41343)
			(xy 29.103742 -251.369287) (xy 29.076446 -251.320652) (xy 29.056523 -251.268561) (xy 29.044397 -251.214124)
			(xy 29.040326 -251.158502) (xy 28.787852 -251.158502) (xy 28.787343 -251.186388) (xy 28.779223 -251.241564)
			(xy 28.763155 -251.294971) (xy 28.739483 -251.345468) (xy 28.70871 -251.391981) (xy 28.671493 -251.433518)
			(xy 28.628625 -251.469193) (xy 28.581019 -251.498247) (xy 28.52969 -251.520059) (xy 28.475733 -251.534165)
			(xy 28.420296 -251.540265) (xy 28.364562 -251.538228) (xy 28.309719 -251.528098) (xy 28.256935 -251.510091)
			(xy 28.207335 -251.48459) (xy 28.161977 -251.452139) (xy 28.121828 -251.41343) (xy 28.087742 -251.369287)
			(xy 28.060446 -251.320652) (xy 28.040523 -251.268561) (xy 28.028397 -251.214124) (xy 28.024326 -251.158502)
			(xy 27.771852 -251.158502) (xy 27.771343 -251.186388) (xy 27.763223 -251.241564) (xy 27.747155 -251.294971)
			(xy 27.723483 -251.345468) (xy 27.69271 -251.391981) (xy 27.655493 -251.433518) (xy 27.612625 -251.469193)
			(xy 27.565019 -251.498247) (xy 27.51369 -251.520059) (xy 27.459733 -251.534165) (xy 27.404296 -251.540265)
			(xy 27.348562 -251.538228) (xy 27.293719 -251.528098) (xy 27.240935 -251.510091) (xy 27.191335 -251.48459)
			(xy 27.145977 -251.452139) (xy 27.105828 -251.41343) (xy 27.071742 -251.369287) (xy 27.044446 -251.320652)
			(xy 27.024523 -251.268561) (xy 27.012397 -251.214124) (xy 27.008326 -251.158502) (xy 26.755852 -251.158502)
			(xy 26.755343 -251.186388) (xy 26.747223 -251.241564) (xy 26.731155 -251.294971) (xy 26.707483 -251.345468)
			(xy 26.67671 -251.391981) (xy 26.639493 -251.433518) (xy 26.596625 -251.469193) (xy 26.549019 -251.498247)
			(xy 26.49769 -251.520059) (xy 26.443733 -251.534165) (xy 26.388296 -251.540265) (xy 26.332562 -251.538228)
			(xy 26.277719 -251.528098) (xy 26.224935 -251.510091) (xy 26.175335 -251.48459) (xy 26.129977 -251.452139)
			(xy 26.089828 -251.41343) (xy 26.055742 -251.369287) (xy 26.028446 -251.320652) (xy 26.008523 -251.268561)
			(xy 25.996397 -251.214124) (xy 25.992326 -251.158502) (xy 25.832248 -251.158502) (xy 25.831799 -251.183086)
			(xy 25.823679 -251.238262) (xy 25.807611 -251.291669) (xy 25.783939 -251.342166) (xy 25.753166 -251.388679)
			(xy 25.715949 -251.430216) (xy 25.673081 -251.465891) (xy 25.625475 -251.494945) (xy 25.574146 -251.516757)
			(xy 25.520189 -251.530863) (xy 25.464752 -251.536963) (xy 25.409018 -251.534926) (xy 25.354175 -251.524796)
			(xy 25.301391 -251.506789) (xy 25.251791 -251.481288) (xy 25.206433 -251.448837) (xy 25.166284 -251.410128)
			(xy 25.132198 -251.365985) (xy 25.104902 -251.31735) (xy 25.084979 -251.265259) (xy 25.072853 -251.210822)
			(xy 25.068782 -251.1552) (xy 24.723792 -251.1552) (xy 24.723852 -251.158502) (xy 24.723343 -251.186388)
			(xy 24.715223 -251.241564) (xy 24.699155 -251.294971) (xy 24.675483 -251.345468) (xy 24.64471 -251.391981)
			(xy 24.607493 -251.433518) (xy 24.564625 -251.469193) (xy 24.517019 -251.498247) (xy 24.46569 -251.520059)
			(xy 24.411733 -251.534165) (xy 24.356296 -251.540265) (xy 24.300562 -251.538228) (xy 24.245719 -251.528098)
			(xy 24.192935 -251.510091) (xy 24.143335 -251.48459) (xy 24.097977 -251.452139) (xy 24.057828 -251.41343)
			(xy 24.023742 -251.369287) (xy 23.996446 -251.320652) (xy 23.976523 -251.268561) (xy 23.964397 -251.214124)
			(xy 23.960326 -251.158502) (xy 7.007606 -251.158502) (xy 9.469882 -253.620778) (xy 21.387306 -253.620778)
			(xy 21.391377 -253.565156) (xy 21.403503 -253.510719) (xy 21.423426 -253.458628) (xy 21.450722 -253.409993)
			(xy 21.484808 -253.36585) (xy 21.524957 -253.327141) (xy 21.570315 -253.29469) (xy 21.619915 -253.269189)
			(xy 21.672699 -253.251182) (xy 21.727542 -253.241052) (xy 21.783276 -253.239015) (xy 21.838713 -253.245115)
			(xy 21.89267 -253.259221) (xy 21.943999 -253.281033) (xy 21.991605 -253.310087) (xy 22.034473 -253.345762)
			(xy 22.07169 -253.387299) (xy 22.102463 -253.433812) (xy 22.113071 -253.45644) (xy 39.200326 -253.45644)
			(xy 39.204397 -253.400818) (xy 39.216523 -253.346381) (xy 39.236446 -253.29429) (xy 39.263742 -253.245655)
			(xy 39.297828 -253.201512) (xy 39.337977 -253.162803) (xy 39.383335 -253.130352) (xy 39.432935 -253.104851)
			(xy 39.485719 -253.086844) (xy 39.540562 -253.076714) (xy 39.596296 -253.074677) (xy 39.651733 -253.080777)
			(xy 39.70569 -253.094883) (xy 39.757019 -253.116695) (xy 39.804625 -253.145749) (xy 39.847493 -253.181424)
			(xy 39.88471 -253.222961) (xy 39.915483 -253.269474) (xy 39.939155 -253.319971) (xy 39.955223 -253.373378)
			(xy 39.963343 -253.428554) (xy 39.963852 -253.45644) (xy 39.963343 -253.484326) (xy 39.955223 -253.539502)
			(xy 39.939155 -253.592909) (xy 39.915483 -253.643406) (xy 39.88471 -253.689919) (xy 39.847493 -253.731456)
			(xy 39.804625 -253.767131) (xy 39.757019 -253.796185) (xy 39.70569 -253.817997) (xy 39.651733 -253.832103)
			(xy 39.596296 -253.838203) (xy 39.540562 -253.836166) (xy 39.485719 -253.826036) (xy 39.432935 -253.808029)
			(xy 39.383335 -253.782528) (xy 39.337977 -253.750077) (xy 39.297828 -253.711368) (xy 39.263742 -253.667225)
			(xy 39.236446 -253.61859) (xy 39.216523 -253.566499) (xy 39.204397 -253.512062) (xy 39.200326 -253.45644)
			(xy 22.113071 -253.45644) (xy 22.126135 -253.484309) (xy 22.142203 -253.537716) (xy 22.150323 -253.592892)
			(xy 22.150832 -253.620778) (xy 22.150323 -253.648664) (xy 22.142203 -253.70384) (xy 22.126135 -253.757247)
			(xy 22.102463 -253.807744) (xy 22.07169 -253.854257) (xy 22.034473 -253.895794) (xy 21.991605 -253.931469)
			(xy 21.943999 -253.960523) (xy 21.89267 -253.982335) (xy 21.838713 -253.996441) (xy 21.783276 -254.002541)
			(xy 21.727542 -254.000504) (xy 21.672699 -253.990374) (xy 21.619915 -253.972367) (xy 21.570315 -253.946866)
			(xy 21.524957 -253.914415) (xy 21.484808 -253.875706) (xy 21.450722 -253.831563) (xy 21.423426 -253.782928)
			(xy 21.403503 -253.730837) (xy 21.391377 -253.6764) (xy 21.387306 -253.620778) (xy 9.469882 -253.620778)
			(xy 10.4775 -254.628396) (xy 10.481659 -254.632159) (xy 10.491269 -254.637939) (xy 10.49655 -254.639826)
			(xy 10.505186 -254.64262) (xy 39.615364 -254.64262) (xy 39.625429 -254.643055) (xy 39.644014 -254.650788)
			(xy 39.651432 -254.657606) (xy 40.004238 -255.010412) (xy 40.009918 -255.015602) (xy 40.023625 -255.022574)
			(xy 40.031162 -255.024128) (xy 40.03167 -255.024128) (xy 40.039798 -255.02489) (xy 40.915844 -255.02489)
			(xy 40.924988 -255.024382) (xy 40.94226 -255.005586) (xy 40.947778 -254.997748) (xy 40.953107 -254.979349)
			(xy 40.952674 -254.969772) (xy 40.649144 -251.546106) (xy 40.648382 -251.545344) (xy 40.640254 -251.54255)
			(xy 40.636437 -251.541293) (xy 40.628523 -251.539893) (xy 40.624506 -251.539756) (xy 40.601646 -251.54001)
			(xy 40.598344 -251.54001) (xy 40.571089 -251.53955) (xy 40.517133 -251.531798) (xy 40.46483 -251.516446)
			(xy 40.415244 -251.493806) (xy 40.369385 -251.464339) (xy 40.328187 -251.428645) (xy 40.292489 -251.387451)
			(xy 40.263016 -251.341596) (xy 40.240371 -251.292013) (xy 40.225012 -251.239712) (xy 40.217254 -251.185757)
			(xy 40.216836 -251.158502) (xy 40.217288 -251.131727) (xy 40.224775 -251.078704) (xy 40.239601 -251.027249)
			(xy 40.261477 -250.978372) (xy 40.289972 -250.933033) (xy 40.324525 -250.892124) (xy 40.36446 -250.856448)
			(xy 40.40899 -250.826706) (xy 40.457241 -250.803483) (xy 40.508265 -250.787233) (xy 40.53459 -250.782328)
			(xy 40.56253 -250.777502) (xy 40.570658 -250.773946) (xy 40.579548 -250.76912) (xy 40.58031 -250.768358)
			(xy 30.608778 -138.330432) (xy 30.607436 -138.314458) (xy 30.605658 -138.282448) (xy 30.605222 -138.266424)
			(xy 30.091126 -117.095016) (xy 30.090872 -117.070886) (xy 30.092142 -117.017292) (xy 30.766258 -104.50957)
			(xy 30.76956 -104.46639) (xy 30.774132 -104.427782) (xy 32.304228 -93.25102) (xy 32.304482 -93.248734)
			(xy 32.30494 -93.238545) (xy 32.298721 -93.219138) (xy 32.285444 -93.203678) (xy 32.276542 -93.198696)
			(xy 32.263588 -93.192092) (xy 32.256631 -93.189096) (xy 32.241651 -93.186914) (xy 32.234124 -93.187774)
			(xy 32.226504 -93.189044) (xy 32.21228 -93.195902) (xy 32.206438 -93.201744) (xy 32.184974 -93.221746)
			(xy 32.137045 -93.255583) (xy 32.0845 -93.28168) (xy 32.028577 -93.29942) (xy 31.970597 -93.308385)
			(xy 31.941262 -93.308932) (xy 31.914011 -93.308444) (xy 31.860064 -93.300682) (xy 31.80777 -93.285323)
			(xy 31.758195 -93.262678) (xy 31.712346 -93.233209) (xy 31.671158 -93.197515) (xy 31.635468 -93.156323)
			(xy 31.606004 -93.110472) (xy 31.583364 -93.060894) (xy 31.56801 -93.008599) (xy 31.560254 -92.954651)
			(xy 31.560254 -92.900149) (xy 31.56801 -92.846201) (xy 31.583364 -92.793906) (xy 31.606004 -92.744328)
			(xy 31.635468 -92.698477) (xy 31.671158 -92.657285) (xy 31.712346 -92.621591) (xy 31.758195 -92.592122)
			(xy 31.80777 -92.569477) (xy 31.860064 -92.554118) (xy 31.914011 -92.546356) (xy 31.941262 -92.545916)
			(xy 31.968955 -92.546413) (xy 32.02376 -92.554421) (xy 32.076834 -92.570261) (xy 32.127064 -92.593599)
			(xy 32.173396 -92.623947) (xy 32.21486 -92.660669) (xy 32.250586 -92.702994) (xy 32.26562 -92.726256)
			(xy 32.265874 -92.726764) (xy 32.270284 -92.733197) (xy 32.282173 -92.743282) (xy 32.289242 -92.746576)
			(xy 32.296354 -92.749624) (xy 32.30372 -92.750132) (xy 32.307611 -92.75042) (xy 32.315395 -92.749914)
			(xy 32.319214 -92.749116) (xy 32.342836 -92.743782) (xy 32.351834 -92.740859) (xy 32.366935 -92.729484)
			(xy 32.37686 -92.713394) (xy 32.378904 -92.704158) (xy 32.52597 -91.631008) (xy 33.113726 -87.337392)
			(xy 33.113726 -87.336884) (xy 33.899602 -80.985868) (xy 34.367724 -77.198728) (xy 34.367978 -77.195172)
			(xy 34.775394 -69.486272) (xy 35.13709 -62.641988) (xy 35.13709 -62.6364) (xy 35.136328 -62.62243)
			(xy 35.135058 -62.602618) (xy 35.135058 -62.60211) (xy 35.08883 -61.78042) (xy 35.088241 -61.773491)
			(xy 35.083731 -61.760342) (xy 35.07994 -61.754512) (xy 35.07613 -61.748924) (xy 35.06597 -61.740542)
			(xy 35.05962 -61.737494) (xy 35.034671 -61.725329) (xy 34.988277 -61.694861) (xy 34.946785 -61.657994)
			(xy 34.911072 -61.615506) (xy 34.881889 -61.568293) (xy 34.859853 -61.51735) (xy 34.845429 -61.463753)
			(xy 34.841688 -61.43625) (xy 34.840672 -61.427106) (xy 34.839148 -61.391546) (xy 34.839642 -61.363911)
			(xy 34.84762 -61.30922) (xy 34.863401 -61.256251) (xy 34.886656 -61.206112) (xy 34.916899 -61.15985)
			(xy 34.953497 -61.118433) (xy 34.974276 -61.100208) (xy 34.98257 -61.092414) (xy 34.991941 -61.071705)
			(xy 34.99231 -61.06033) (xy 34.99231 -61.059568) (xy 34.989516 -60.980574) (xy 34.988906 -60.972672)
			(xy 34.983486 -60.957789) (xy 34.978848 -60.951364) (xy 34.977832 -60.94984) (xy 34.974784 -60.946538)
			(xy 34.969196 -60.94095) (xy 34.966148 -60.938664) (xy 34.942853 -60.920529) (xy 34.901613 -60.878289)
			(xy 34.867367 -60.830204) (xy 34.840931 -60.77742) (xy 34.822935 -60.721196) (xy 34.813808 -60.662872)
			(xy 34.81324 -60.633356) (xy 34.813494 -60.620148) (xy 34.814002 -60.61329) (xy 34.815526 -60.593986)
			(xy 34.815526 -60.593732) (xy 34.81578 -60.5917) (xy 34.816034 -60.588652) (xy 34.819716 -60.561578)
			(xy 34.833824 -60.508792) (xy 34.855316 -60.458557) (xy 34.883752 -60.411901) (xy 34.918552 -60.369778)
			(xy 34.959004 -60.333048) (xy 34.981388 -60.31738) (xy 34.981896 -60.317126) (xy 34.991558 -60.30951)
			(xy 35.002952 -60.287749) (xy 35.00374 -60.27547) (xy 34.916364 -58.729626) (xy 34.915346 -58.721894)
			(xy 34.909278 -58.707536) (xy 34.904426 -58.701432) (xy 34.904172 -58.701178) (xy 34.886402 -58.680217)
			(xy 34.856446 -58.634149) (xy 34.833417 -58.584257) (xy 34.817793 -58.531574) (xy 34.809898 -58.477193)
			(xy 34.80943 -58.449718) (xy 34.809964 -58.420752) (xy 34.818705 -58.363483) (xy 34.835989 -58.308189)
			(xy 34.861421 -58.256138) (xy 34.877502 -58.23204) (xy 34.878772 -58.230262) (xy 34.88269 -58.223427)
			(xy 34.886571 -58.208166) (xy 34.886392 -58.20029) (xy 34.83102 -57.217056) (xy 34.757614 -55.917846)
			(xy 34.685732 -54.644798) (xy 34.684264 -54.635128) (xy 34.675072 -54.617882) (xy 34.66008 -54.605348)
			(xy 34.650934 -54.601872) (xy 34.65068 -54.601872) (xy 34.625436 -54.59324) (xy 34.577456 -54.569913)
			(xy 34.533192 -54.540129) (xy 34.493509 -54.504471) (xy 34.45918 -54.463632) (xy 34.430874 -54.41841)
			(xy 34.409143 -54.369686) (xy 34.394411 -54.31841) (xy 34.386965 -54.265581) (xy 34.38652 -54.238906)
			(xy 34.386993 -54.211575) (xy 34.394799 -54.157472) (xy 34.410237 -54.105035) (xy 34.432992 -54.055333)
			(xy 34.462599 -54.009383) (xy 34.498454 -53.968123) (xy 34.539825 -53.932394) (xy 34.585866 -53.902928)
			(xy 34.610548 -53.89118) (xy 34.610802 -53.89118) (xy 34.617727 -53.887722) (xy 34.62923 -53.877376)
			(xy 34.633408 -53.87086) (xy 34.637218 -53.864764) (xy 34.640774 -53.850032) (xy 34.544 -52.13731)
			(xy 34.519616 -51.70551) (xy 34.518214 -51.692976) (xy 34.505026 -51.671516) (xy 34.49447 -51.664616)
			(xy 34.4932 -51.663854) (xy 34.487738 -51.660869) (xy 34.475789 -51.657397) (xy 34.469578 -51.656996)
			(xy 34.457132 -51.656488) (xy 34.445448 -51.66233) (xy 34.419082 -51.674738) (xy 34.363517 -51.692282)
			(xy 34.305927 -51.70115) (xy 34.276792 -51.7017) (xy 34.26587 -51.7017) (xy 34.238962 -51.700507)
			(xy 34.185861 -51.691489) (xy 34.134556 -51.67509) (xy 34.086069 -51.651637) (xy 34.041363 -51.621597)
			(xy 34.001327 -51.585566) (xy 33.966758 -51.544262) (xy 33.95218 -51.521614) (xy 33.948624 -51.515518)
			(xy 33.94583 -51.511454) (xy 33.936432 -51.505358) (xy 33.931353 -51.502344) (xy 33.920191 -51.498496)
			(xy 33.914334 -51.497738) (xy 33.904682 -51.496722) (xy 33.904174 -51.496722) (xy 33.840166 -51.490372)
			(xy 33.834578 -51.489864) (xy 33.828703 -51.489443) (xy 33.817029 -51.490983) (xy 33.811464 -51.492912)
			(xy 33.800542 -51.496976) (xy 33.792414 -51.505612) (xy 33.774349 -51.524146) (xy 33.734083 -51.556661)
			(xy 33.689793 -51.583438) (xy 33.64229 -51.603983) (xy 33.592447 -51.617921) (xy 33.541177 -51.624996)
			(xy 33.5153 -51.6255) (xy 33.514792 -51.6255) (xy 33.514284 -51.6255) (xy 33.49752 -51.625246) (xy 33.497266 -51.624992)
			(xy 33.470854 -51.623339) (xy 33.41883 -51.613654) (xy 33.368642 -51.596872) (xy 33.321255 -51.573317)
			(xy 33.277577 -51.54344) (xy 33.238447 -51.507814) (xy 33.204615 -51.467122) (xy 33.17673 -51.422147)
			(xy 33.155327 -51.373749) (xy 33.140817 -51.322859) (xy 33.133479 -51.270451) (xy 33.13303 -51.243992)
			(xy 33.133455 -51.218481) (xy 33.140251 -51.167913) (xy 33.153719 -51.118701) (xy 33.173622 -51.07172)
			(xy 33.199603 -51.027808) (xy 33.215072 -51.007518) (xy 33.217612 -51.00447) (xy 33.218628 -51.002946)
			(xy 33.22193 -50.996342) (xy 33.224273 -50.991119) (xy 33.226838 -50.979966) (xy 33.22701 -50.974244)
			(xy 33.22701 -50.94224) (xy 33.238186 -50.94224) (xy 33.238186 -50.89144) (xy 33.237852 -50.882836)
			(xy 33.23214 -50.866605) (xy 33.22701 -50.85969) (xy 33.22574 -50.858166) (xy 33.208347 -50.837289)
			(xy 33.17903 -50.791539) (xy 33.156503 -50.742091) (xy 33.141223 -50.689946) (xy 33.133498 -50.636161)
			(xy 33.13303 -50.608992) (xy 33.133494 -50.581741) (xy 33.141252 -50.527792) (xy 33.156609 -50.475498)
			(xy 33.179253 -50.425921) (xy 33.208721 -50.380072) (xy 33.244416 -50.338883) (xy 33.285609 -50.303194)
			(xy 33.331461 -50.273731) (xy 33.381041 -50.251093) (xy 33.433337 -50.235742) (xy 33.487286 -50.227991)
			(xy 33.514538 -50.227484) (xy 33.542578 -50.227982) (xy 33.598053 -50.2362) (xy 33.651727 -50.252452)
			(xy 33.702443 -50.276388) (xy 33.749106 -50.307493) (xy 33.790713 -50.345095) (xy 33.808924 -50.366422)
			(xy 33.809178 -50.366676) (xy 33.816036 -50.374804) (xy 33.837626 -50.385472) (xy 33.846262 -50.38979)
			(xy 33.84979 -50.391303) (xy 33.857189 -50.393349) (xy 33.860994 -50.393854) (xy 33.864296 -50.394108)
			(xy 33.92424 -50.394108) (xy 33.934654 -50.393092) (xy 33.946338 -50.389028) (xy 33.965642 -50.379376)
			(xy 33.969826 -50.377221) (xy 33.97737 -50.371597) (xy 33.980628 -50.3682) (xy 33.982152 -50.366168)
			(xy 34.001542 -50.343555) (xy 34.046119 -50.304048) (xy 34.096294 -50.271949) (xy 34.150847 -50.248038)
			(xy 34.17951 -50.23993) (xy 34.18332 -50.238914) (xy 34.187286 -50.237444) (xy 34.194689 -50.233352)
			(xy 34.198052 -50.230786) (xy 34.202116 -50.227484) (xy 34.208974 -50.219356) (xy 34.22142 -50.195988)
			(xy 34.225611 -50.186629) (xy 34.22692 -50.166182) (xy 34.22396 -50.156364) (xy 34.134806 -49.898554)
			(xy 34.129726 -49.883822) (xy 34.12599 -49.87459) (xy 34.112779 -49.859712) (xy 34.094914 -49.850952)
			(xy 34.085022 -49.849786) (xy 34.047938 -49.849786) (xy 34.043327 -49.849891) (xy 34.034256 -49.851559)
			(xy 34.029904 -49.853088) (xy 34.021776 -49.856136) (xy 34.014664 -49.862232) (xy 33.993731 -49.879871)
			(xy 33.947763 -49.90959) (xy 33.898016 -49.932426) (xy 33.845513 -49.94791) (xy 33.791335 -49.955723)
			(xy 33.763966 -49.956212) (xy 33.738455 -49.955785) (xy 33.687889 -49.948987) (xy 33.638677 -49.935517)
			(xy 33.591698 -49.915614) (xy 33.547786 -49.889633) (xy 33.527492 -49.87417) (xy 33.524444 -49.87163)
			(xy 33.52292 -49.870614) (xy 33.516316 -49.867312) (xy 33.511093 -49.86497) (xy 33.49994 -49.862408)
			(xy 33.494218 -49.862232) (xy 33.462214 -49.862232) (xy 33.462214 -49.851056) (xy 33.411414 -49.851056)
			(xy 33.402812 -49.851395) (xy 33.386589 -49.857117) (xy 33.379664 -49.862232) (xy 33.37814 -49.863502)
			(xy 33.357263 -49.880896) (xy 33.311514 -49.910214) (xy 33.262066 -49.932741) (xy 33.209921 -49.948021)
			(xy 33.156135 -49.955743) (xy 33.128966 -49.956212) (xy 33.103455 -49.955785) (xy 33.052889 -49.948987)
			(xy 33.003677 -49.935517) (xy 32.956698 -49.915614) (xy 32.912786 -49.889633) (xy 32.892492 -49.87417)
			(xy 32.889444 -49.87163) (xy 32.88792 -49.870614) (xy 32.881316 -49.867312) (xy 32.876093 -49.86497)
			(xy 32.86494 -49.862408) (xy 32.859218 -49.862232) (xy 32.827214 -49.862232) (xy 32.827214 -49.851056)
			(xy 32.776414 -49.851056) (xy 32.767812 -49.851395) (xy 32.751589 -49.857117) (xy 32.744664 -49.862232)
			(xy 32.74314 -49.863502) (xy 32.722263 -49.880896) (xy 32.676514 -49.910214) (xy 32.627066 -49.932741)
			(xy 32.574921 -49.948021) (xy 32.521135 -49.955743) (xy 32.493966 -49.956212) (xy 32.466716 -49.955724)
			(xy 32.412771 -49.947963) (xy 32.36048 -49.932605) (xy 32.310907 -49.909962) (xy 32.26506 -49.880494)
			(xy 32.223874 -49.844802) (xy 32.188185 -49.803613) (xy 32.158722 -49.757763) (xy 32.136083 -49.708188)
			(xy 32.120729 -49.655895) (xy 32.112974 -49.60195) (xy 32.112974 -49.54745) (xy 32.120729 -49.493505)
			(xy 32.136083 -49.441212) (xy 32.158722 -49.391637) (xy 32.188185 -49.345787) (xy 32.223874 -49.304598)
			(xy 32.26506 -49.268906) (xy 32.310907 -49.239438) (xy 32.36048 -49.216795) (xy 32.412771 -49.201437)
			(xy 32.466716 -49.193676) (xy 32.493966 -49.193196) (xy 32.519476 -49.193625) (xy 32.570041 -49.200427)
			(xy 32.619249 -49.213901) (xy 32.666226 -49.233807) (xy 32.710134 -49.25979) (xy 32.73044 -49.275238)
			(xy 32.733488 -49.277778) (xy 32.735012 -49.278794) (xy 32.741616 -49.282096) (xy 32.74684 -49.284435)
			(xy 32.757993 -49.286989) (xy 32.763714 -49.287176) (xy 32.795718 -49.287176) (xy 32.795718 -49.298352)
			(xy 32.846518 -49.298352) (xy 32.855124 -49.298024) (xy 32.871361 -49.292319) (xy 32.878268 -49.287176)
			(xy 32.879792 -49.285906) (xy 32.900669 -49.268514) (xy 32.946419 -49.239199) (xy 32.995867 -49.216675)
			(xy 33.048012 -49.2014) (xy 33.101798 -49.193681) (xy 33.128966 -49.193196) (xy 33.154476 -49.193625)
			(xy 33.205041 -49.200427) (xy 33.254249 -49.213901) (xy 33.301226 -49.233807) (xy 33.345134 -49.25979)
			(xy 33.36544 -49.275238) (xy 33.368488 -49.277778) (xy 33.370012 -49.278794) (xy 33.376616 -49.282096)
			(xy 33.38184 -49.284435) (xy 33.392993 -49.286989) (xy 33.398714 -49.287176) (xy 33.430718 -49.287176)
			(xy 33.430718 -49.298352) (xy 33.481518 -49.298352) (xy 33.490124 -49.298024) (xy 33.506361 -49.292319)
			(xy 33.513268 -49.287176) (xy 33.514792 -49.285906) (xy 33.522158 -49.279302) (xy 33.523174 -49.278794)
			(xy 33.524444 -49.277778) (xy 33.524952 -49.27727) (xy 33.54705 -49.26076) (xy 33.547304 -49.260506)
			(xy 33.547812 -49.260252) (xy 33.562544 -49.250346) (xy 33.563052 -49.250346) (xy 33.579308 -49.240694)
			(xy 33.584195 -49.237806) (xy 33.592656 -49.230242) (xy 33.596072 -49.225708) (xy 33.599628 -49.221136)
			(xy 33.603946 -49.210468) (xy 33.606994 -49.19091) (xy 33.617408 -49.125886) (xy 33.618119 -49.120139)
			(xy 33.617216 -49.108596) (xy 33.61563 -49.103026) (xy 33.614614 -49.099978) (xy 33.613091 -49.096154)
			(xy 33.609007 -49.089008) (xy 33.606486 -49.085754) (xy 27.867102 -42.828718) (xy 27.86283 -42.824913)
			(xy 27.852957 -42.81914) (xy 27.847544 -42.817288) (xy 27.840432 -42.81551) (xy 27.834571 -42.814705)
			(xy 27.822769 -42.81547) (xy 27.817064 -42.817034) (xy 27.816302 -42.817288) (xy 27.728672 -42.845482)
			(xy 27.719396 -42.848923) (xy 27.704229 -42.861596) (xy 27.699208 -42.87012) (xy 27.697397 -42.873796)
			(xy 27.694837 -42.881579) (xy 27.694128 -42.885614) (xy 27.693874 -42.887646) (xy 27.690006 -42.915018)
			(xy 27.675397 -42.968332) (xy 27.653245 -43.018979) (xy 27.624015 -43.065897) (xy 27.588317 -43.108105)
			(xy 27.546901 -43.144718) (xy 27.500634 -43.174968) (xy 27.450484 -43.198224) (xy 27.397503 -43.213996)
			(xy 27.3428 -43.221956) (xy 27.31516 -43.222418) (xy 27.28791 -43.221929) (xy 27.233965 -43.214168)
			(xy 27.181674 -43.198809) (xy 27.1321 -43.176165) (xy 27.086254 -43.146697) (xy 27.045067 -43.111005)
			(xy 27.009379 -43.069814) (xy 26.979916 -43.023965) (xy 26.957277 -42.974389) (xy 26.941923 -42.922096)
			(xy 26.934168 -42.86815) (xy 26.934168 -42.81365) (xy 26.941923 -42.759704) (xy 26.957277 -42.707411)
			(xy 26.979916 -42.657835) (xy 27.009379 -42.611986) (xy 27.045067 -42.570795) (xy 27.086254 -42.535103)
			(xy 27.1321 -42.505635) (xy 27.181674 -42.482991) (xy 27.233965 -42.467632) (xy 27.28791 -42.459871)
			(xy 27.31516 -42.459402) (xy 27.32278 -42.459402) (xy 27.3352 -42.458789) (xy 27.357177 -42.447212)
			(xy 27.36469 -42.437304) (xy 27.366468 -42.434256) (xy 27.370278 -42.427906) (xy 27.406092 -42.365168)
			(xy 27.406092 -42.36466) (xy 27.410664 -42.356278) (xy 27.413808 -42.350343) (xy 27.417152 -42.33734)
			(xy 27.417268 -42.330624) (xy 27.417014 -42.316908) (xy 27.409648 -42.30497) (xy 27.39009 -42.271696)
			(xy 27.389582 -42.27068) (xy 27.389328 -42.270426) (xy 26.82621 -41.331388) (xy 26.818844 -41.322498)
			(xy 26.81859 -41.322244) (xy 26.813256 -41.317164) (xy 26.806144 -41.313354) (xy 26.805382 -41.3131)
			(xy 26.781961 -41.3009) (xy 26.738426 -41.271007) (xy 26.699436 -41.235391) (xy 26.665735 -41.194734)
			(xy 26.637969 -41.149813) (xy 26.61667 -41.101489) (xy 26.602246 -41.050688) (xy 26.594972 -40.998383)
			(xy 26.594562 -40.971978) (xy 26.594562 -40.960548) (xy 26.594816 -40.953182) (xy 26.593038 -40.946324)
			(xy 26.592105 -40.942663) (xy 26.589302 -40.935647) (xy 26.58745 -40.932354) (xy 26.253948 -40.37711)
			(xy 26.25344 -40.376094) (xy 26.249376 -40.369744) (xy 26.243283 -40.36163) (xy 26.226258 -40.350619)
			(xy 26.216356 -40.348408) (xy 26.215848 -40.348408) (xy 26.189417 -40.343593) (xy 26.138154 -40.327516)
			(xy 26.089653 -40.304406) (xy 26.044875 -40.274719) (xy 26.004705 -40.239043) (xy 25.969939 -40.198084)
			(xy 25.941263 -40.152653) (xy 25.919245 -40.103647) (xy 25.90432 -40.052036) (xy 25.896785 -39.998842)
			(xy 25.896316 -39.97198) (xy 25.896316 -39.971726) (xy 25.8969 -39.941422) (xy 25.90647 -39.881575)
			(xy 25.915366 -39.8526) (xy 25.916636 -39.849044) (xy 25.91816 -39.840662) (xy 25.919255 -39.831777)
			(xy 25.915884 -39.814207) (xy 25.911556 -39.806372) (xy 25.911556 -39.806118) (xy 25.389586 -38.93566)
			(xy 25.384772 -38.928382) (xy 25.371278 -38.917335) (xy 25.354869 -38.91143) (xy 25.346152 -38.911022)
			(xy 25.344374 -38.911022) (xy 25.30348 -38.911784) (xy 25.29656 -38.912158) (xy 25.283298 -38.916155)
			(xy 25.277318 -38.919658) (xy 25.271476 -38.923214) (xy 25.262078 -38.933374) (xy 25.25903 -38.939724)
			(xy 25.245522 -38.965574) (xy 25.21245 -39.013615) (xy 25.173072 -39.05664) (xy 25.12814 -39.093827)
			(xy 25.078511 -39.124465) (xy 25.025133 -39.147971) (xy 24.969024 -39.163895) (xy 24.911256 -39.171933)
			(xy 24.882094 -39.172388) (xy 24.853227 -39.171915) (xy 24.796033 -39.164044) (xy 24.740446 -39.148449)
			(xy 24.687504 -39.125421) (xy 24.638195 -39.095392) (xy 24.593441 -39.05892) (xy 24.554076 -39.016688)
			(xy 24.520837 -38.969483) (xy 24.50719 -38.944042) (xy 24.505666 -38.940994) (xy 24.499004 -38.931099)
			(xy 24.478855 -38.918389) (xy 24.467058 -38.91661) (xy 24.458168 -38.916102) (xy 24.42972 -38.914324)
			(xy 24.418884 -38.914121) (xy 24.398626 -38.921766) (xy 24.390604 -38.929056) (xy 24.386794 -38.932866)
			(xy 24.385016 -38.935152) (xy 24.384254 -38.936168) (xy 24.366043 -38.958794) (xy 24.323937 -38.998799)
			(xy 24.276261 -39.031969) (xy 24.224114 -39.057542) (xy 24.168697 -39.074927) (xy 24.111288 -39.083725)
			(xy 24.082248 -39.08425) (xy 24.081994 -39.08425) (xy 24.05474 -39.083764) (xy 24.000787 -39.076006)
			(xy 23.948487 -39.060648) (xy 23.898905 -39.038004) (xy 23.853051 -39.008535) (xy 23.811857 -38.972839)
			(xy 23.776162 -38.931645) (xy 23.746693 -38.885789) (xy 23.72405 -38.836207) (xy 23.708693 -38.783907)
			(xy 23.700936 -38.729954) (xy 23.700936 -38.675446) (xy 23.708693 -38.621493) (xy 23.72405 -38.569193)
			(xy 23.746693 -38.519611) (xy 23.776162 -38.473755) (xy 23.811857 -38.432561) (xy 23.853051 -38.396865)
			(xy 23.898905 -38.367396) (xy 23.948487 -38.344752) (xy 24.000787 -38.329394) (xy 24.05474 -38.321636)
			(xy 24.081994 -38.321234) (xy 24.109452 -38.32171) (xy 24.163802 -38.329576) (xy 24.216465 -38.345146)
			(xy 24.266354 -38.368099) (xy 24.31244 -38.397962) (xy 24.353774 -38.434119) (xy 24.389502 -38.475824)
			(xy 24.404574 -38.49878) (xy 24.408384 -38.504876) (xy 24.416004 -38.511988) (xy 24.442674 -38.528244)
			(xy 24.447584 -38.530849) (xy 24.458224 -38.534056) (xy 24.463756 -38.534594) (xy 24.465534 -38.534594)
			(xy 24.488394 -38.536118) (xy 24.495016 -38.536337) (xy 24.508009 -38.533764) (xy 24.514048 -38.531038)
			(xy 24.519636 -38.528244) (xy 24.529542 -38.519608) (xy 24.533352 -38.513766) (xy 24.550254 -38.489796)
			(xy 24.589627 -38.446326) (xy 24.634645 -38.408731) (xy 24.684439 -38.377739) (xy 24.738047 -38.353945)
			(xy 24.794435 -38.337811) (xy 24.852515 -38.329647) (xy 24.88184 -38.329108) (xy 24.882348 -38.329108)
			(xy 24.894794 -38.329362) (xy 24.904954 -38.328346) (xy 24.90978 -38.327076) (xy 24.918094 -38.324025)
			(xy 24.932127 -38.313244) (xy 24.937212 -38.305994) (xy 24.954484 -38.274498) (xy 24.958294 -38.261544)
			(xy 24.958802 -38.256972) (xy 24.959056 -38.25367) (xy 24.959056 -38.231318) (xy 24.958827 -38.224945)
			(xy 24.955619 -38.212607) (xy 24.952706 -38.206934) (xy 24.698706 -37.783262) (xy 24.428958 -37.333428)
			(xy 24.426672 -37.329872) (xy 24.338534 -37.219636) (xy 24.310395 -37.183653) (xy 24.260086 -37.107402)
			(xy 24.216972 -37.026863) (xy 24.181415 -36.942715) (xy 24.167084 -36.899342) (xy 24.165306 -36.893754)
			(xy 24.125936 -36.827968) (xy 24.086566 -36.76269) (xy 24.078946 -36.756594) (xy 24.053866 -36.736641)
			(xy 24.010127 -36.689805) (xy 23.974843 -36.636309) (xy 23.961344 -36.607242) (xy 23.957534 -36.598352)
			(xy 23.921212 -36.56203) (xy 23.9138 -36.555346) (xy 23.895367 -36.547749) (xy 23.875429 -36.547749)
			(xy 23.856996 -36.555346) (xy 23.849584 -36.56203) (xy 23.84933 -36.562284) (xy 23.842265 -36.57014)
			(xy 23.834643 -36.58982) (xy 23.834598 -36.600384) (xy 23.834598 -36.600638) (xy 23.835106 -36.619688)
			(xy 23.83462 -36.646939) (xy 23.826864 -36.700887) (xy 23.811509 -36.753182) (xy 23.788867 -36.802759)
			(xy 23.759401 -36.848609) (xy 23.72371 -36.8898) (xy 23.682519 -36.925491) (xy 23.636669 -36.954957)
			(xy 23.587092 -36.977599) (xy 23.534797 -36.992954) (xy 23.480849 -37.00071) (xy 23.426347 -37.00071)
			(xy 23.372399 -36.992954) (xy 23.320104 -36.977599) (xy 23.270527 -36.954957) (xy 23.224677 -36.925491)
			(xy 23.183486 -36.8898) (xy 23.147795 -36.848609) (xy 23.118329 -36.802759) (xy 23.095687 -36.753182)
			(xy 23.080332 -36.700887) (xy 23.072576 -36.646939) (xy 23.07209 -36.619688) (xy 23.072559 -36.592702)
			(xy 23.080171 -36.539269) (xy 23.095242 -36.487443) (xy 23.117471 -36.43826) (xy 23.131526 -36.415218)
			(xy 23.135336 -36.409122) (xy 23.137368 -36.402518) (xy 23.138331 -36.398977) (xy 23.139348 -36.391709)
			(xy 23.1394 -36.38804) (xy 23.1394 -36.341304) (xy 23.135082 -36.330636) (xy 23.118826 -36.288218)
			(xy 23.116733 -36.28377) (xy 23.111107 -36.275711) (xy 23.10765 -36.272216) (xy 23.106634 -36.2712)
			(xy 23.079964 -36.247578) (xy 23.068788 -36.24453) (xy 23.042344 -36.23668) (xy 22.991873 -36.214422)
			(xy 22.94513 -36.185133) (xy 22.903087 -36.149423) (xy 22.86662 -36.108036) (xy 22.836487 -36.061833)
			(xy 22.813316 -36.011774) (xy 22.797588 -35.958903) (xy 22.789632 -35.904318) (xy 22.789134 -35.876738)
			(xy 22.789134 -35.87242) (xy 22.789642 -35.86226) (xy 22.789642 -35.85972) (xy 22.792182 -35.829494)
			(xy 22.796556 -35.79888) (xy 22.813909 -35.739527) (xy 22.826726 -35.711384) (xy 22.82952 -35.705796)
			(xy 22.831806 -35.695382) (xy 22.831806 -35.672522) (xy 22.831311 -35.663079) (xy 22.8244 -35.645495)
			(xy 22.818344 -35.638232) (xy 22.782784 -35.602672) (xy 22.752759 -35.57202) (xy 22.697544 -35.506334)
			(xy 22.648231 -35.436109) (xy 22.62632 -35.399218) (xy 22.621494 -35.390582) (xy 22.598126 -35.372802)
			(xy 22.594042 -35.369804) (xy 22.584957 -35.365325) (xy 22.580092 -35.363912) (xy 22.54885 -35.355784)
			(xy 22.548342 -35.355784) (xy 22.528276 -35.350958) (xy 22.517862 -35.349688) (xy 22.490176 -35.357816)
			(xy 22.48408 -35.361626) (xy 22.467168 -35.372326) (xy 22.432613 -35.392524) (xy 22.414992 -35.402012)
			(xy 22.371713 -35.424299) (xy 22.281671 -35.461318) (xy 22.188454 -35.489396) (xy 22.092946 -35.508266)
			(xy 21.996055 -35.517751) (xy 21.947378 -35.518344) (xy 21.898867 -35.517763) (xy 21.802303 -35.508344)
			(xy 21.754592 -35.499548) (xy 21.708734 -35.489966) (xy 21.618914 -35.46331) (xy 21.53199 -35.428348)
			(xy 21.448729 -35.385387) (xy 21.369865 -35.334805) (xy 21.296092 -35.277051) (xy 21.228061 -35.212631)
			(xy 21.196808 -35.17773) (xy 21.168735 -35.144917) (xy 21.117737 -35.075222) (xy 21.094954 -35.038538)
			(xy 21.092414 -35.034474) (xy 21.079968 -35.020758) (xy 21.076666 -35.018218) (xy 21.054527 -35.000023)
			(xy 21.015432 -34.958127) (xy 20.983033 -34.910862) (xy 20.958057 -34.859288) (xy 20.941065 -34.804561)
			(xy 20.932438 -34.747911) (xy 20.931886 -34.71926) (xy 20.931886 -34.718752) (xy 20.931886 -34.711894)
			(xy 20.932902 -34.689796) (xy 20.936966 -34.65576) (xy 20.939052 -34.643997) (xy 20.944519 -34.620739)
			(xy 20.947888 -34.609278) (xy 20.947888 -34.60877) (xy 20.949666 -34.602928) (xy 20.951952 -34.588196)
			(xy 20.951952 -34.584386) (xy 20.951698 -34.581592) (xy 20.94992 -34.521902) (xy 20.94992 -34.520886)
			(xy 20.950352 -34.478939) (xy 20.957397 -34.39534) (xy 20.971437 -34.312628) (xy 20.992371 -34.231387)
			(xy 21.020052 -34.152191) (xy 21.036788 -34.113724) (xy 21.038566 -34.10966) (xy 21.043138 -34.089594)
			(xy 21.043138 -34.088578) (xy 21.039582 -34.073338) (xy 21.036534 -34.063686) (xy 21.019854 -34.025283)
			(xy 20.992245 -33.946233) (xy 20.971367 -33.865145) (xy 20.957366 -33.78259) (xy 20.950341 -33.699153)
			(xy 20.94992 -33.657286) (xy 20.951952 -33.595564) (xy 20.952714 -33.585404) (xy 20.952714 -33.58388)
			(xy 20.951952 -33.581594) (xy 20.951444 -33.58007) (xy 20.950682 -33.578038) (xy 20.942046 -33.56356)
			(xy 20.935696 -33.555178) (xy 20.90801 -33.52546) (xy 20.904188 -33.52154) (xy 20.895224 -33.515257)
			(xy 20.89023 -33.513014) (xy 20.880578 -33.509204) (xy 20.873466 -33.509458) (xy 20.86991 -33.509458)
			(xy 20.853146 -33.509712) (xy 20.357592 -33.509712) (xy 20.314336 -33.509252) (xy 20.228148 -33.50176)
			(xy 20.142934 -33.486824) (xy 20.059336 -33.464557) (xy 20.018502 -33.450276) (xy 20.014202 -33.448826)
			(xy 20.005259 -33.447288) (xy 20.000722 -33.447228) (xy 19.967702 -33.459928) (xy 19.960844 -33.46577)
			(xy 19.92685 -33.494749) (xy 19.854535 -33.547201) (xy 19.77782 -33.592976) (xy 19.697318 -33.631708)
			(xy 19.613676 -33.663086) (xy 19.527563 -33.686859) (xy 19.439669 -33.702836) (xy 19.350699 -33.71089)
			(xy 19.306032 -33.711388) (xy 19.306032 -33.711642) (xy 19.30527 -33.711642) (xy 19.258788 -33.71111)
			(xy 19.166228 -33.702463) (xy 19.074874 -33.685237) (xy 18.985521 -33.659583) (xy 18.898944 -33.625722)
			(xy 18.815894 -33.583949) (xy 18.737094 -33.534626) (xy 18.663227 -33.478182) (xy 18.594935 -33.415108)
			(xy 18.532811 -33.34595) (xy 18.477395 -33.27131) (xy 18.452846 -33.231836) (xy 18.450306 -33.227772)
			(xy 18.43786 -33.214056) (xy 18.434558 -33.211516) (xy 18.412357 -33.193283) (xy 18.373155 -33.151289)
			(xy 18.340676 -33.103903) (xy 18.315651 -33.052192) (xy 18.298643 -32.997319) (xy 18.290035 -32.94052)
			(xy 18.289524 -32.911796) (xy 18.289778 -32.90062) (xy 18.290709 -32.878771) (xy 18.296951 -32.835484)
			(xy 18.302224 -32.81426) (xy 18.306542 -32.79902) (xy 18.308066 -32.791908) (xy 18.309844 -32.780986)
			(xy 18.309844 -32.777176) (xy 18.30959 -32.774382) (xy 18.307812 -32.714692) (xy 18.307812 -32.707326)
			(xy 18.308411 -32.670113) (xy 18.314469 -32.595927) (xy 18.326045 -32.522399) (xy 18.334228 -32.486092)
			(xy 18.345593 -32.440144) (xy 18.375869 -32.350457) (xy 18.39468 -32.307022) (xy 18.396458 -32.302958)
			(xy 18.40103 -32.282892) (xy 18.40103 -32.281876) (xy 18.396458 -32.26181) (xy 18.395188 -32.259016)
			(xy 18.379065 -32.222083) (xy 18.352128 -32.146124) (xy 18.3314 -32.068242) (xy 18.317016 -31.988942)
			(xy 18.312638 -31.948882) (xy 18.310374 -31.924434) (xy 18.307961 -31.87539) (xy 18.307812 -31.850838)
			(xy 18.307812 -31.850584) (xy 18.30959 -31.789878) (xy 18.309844 -31.78683) (xy 18.309844 -31.78302)
			(xy 18.308066 -31.772098) (xy 18.306542 -31.76524) (xy 18.298713 -31.7379) (xy 18.290293 -31.68166)
			(xy 18.289778 -31.653226) (xy 18.289778 -31.652972) (xy 18.290323 -31.623902) (xy 18.299133 -31.566432)
			(xy 18.316545 -31.51096) (xy 18.342157 -31.458764) (xy 18.375379 -31.41105) (xy 18.415444 -31.368917)
			(xy 18.438114 -31.350712) (xy 18.443194 -31.34614) (xy 18.449036 -31.339028) (xy 18.47182 -31.30176)
			(xy 18.522978 -31.23095) (xy 18.580138 -31.16489) (xy 18.642863 -31.104088) (xy 18.710669 -31.04901)
			(xy 18.783036 -31.00008) (xy 18.85941 -30.957673) (xy 18.899124 -30.939486) (xy 18.937488 -30.92286)
			(xy 19.016449 -30.895343) (xy 19.097437 -30.874533) (xy 19.179882 -30.860576) (xy 19.263207 -30.853569)
			(xy 19.305016 -30.853126) (xy 19.30527 -30.853126) (xy 19.347851 -30.853575) (xy 19.432702 -30.860841)
			(xy 19.516626 -30.875313) (xy 19.59901 -30.896886) (xy 19.679255 -30.925403) (xy 19.756778 -30.960657)
			(xy 19.831013 -31.002391) (xy 19.90142 -31.050301) (xy 19.967487 -31.104039) (xy 19.998436 -31.133288)
			(xy 20.004702 -31.137827) (xy 20.019179 -31.143265) (xy 20.026884 -31.143956) (xy 20.877022 -31.143956)
			(xy 20.88388 -31.143448) (xy 20.892668 -31.141911) (xy 20.908437 -31.133591) (xy 20.920383 -31.120355)
			(xy 20.924012 -31.112206) (xy 20.932648 -31.09087) (xy 20.93341 -31.08325) (xy 20.93341 -31.082996)
			(xy 20.934172 -31.07563) (xy 20.936352 -31.057837) (xy 20.943601 -31.022727) (xy 20.94865 -31.005526)
			(xy 20.950174 -30.998414) (xy 20.951952 -30.987492) (xy 20.951952 -30.983682) (xy 20.951698 -30.980888)
			(xy 20.94992 -30.92069) (xy 20.950361 -30.878825) (xy 20.9574 -30.79539) (xy 20.971402 -30.712838)
			(xy 20.992269 -30.631748) (xy 21.019855 -30.552692) (xy 21.036534 -30.51429) (xy 21.039582 -30.504638)
			(xy 21.043138 -30.489398) (xy 21.043138 -30.488382) (xy 21.038566 -30.468316) (xy 21.036788 -30.464252)
			(xy 21.020058 -30.425782) (xy 20.992365 -30.346589) (xy 20.971424 -30.265349) (xy 20.957384 -30.182637)
			(xy 20.950344 -30.099038) (xy 20.94992 -30.05709) (xy 20.94992 -30.047946) (xy 20.950936 -30.014926)
			(xy 20.950936 -30.014164) (xy 20.951952 -29.996384) (xy 20.952206 -29.99232) (xy 20.952714 -29.983684)
			(xy 20.95119 -29.97962) (xy 20.944078 -29.966666) (xy 20.937982 -29.95803) (xy 20.928584 -29.947108)
			(xy 20.919948 -29.942536) (xy 20.896072 -29.929836) (xy 20.88642 -29.928566) (xy 20.85968 -29.925389)
			(xy 20.806564 -29.916495) (xy 20.780248 -29.910786) (xy 20.77466 -29.909516) (xy 20.554696 -29.909516)
			(xy 20.51333 -29.909099) (xy 20.430882 -29.902246) (xy 20.349287 -29.888579) (xy 20.269106 -29.868193)
			(xy 20.190892 -29.841227) (xy 20.152868 -29.824934) (xy 20.143216 -29.820616) (xy 20.029932 -29.820616)
			(xy 20.025055 -29.820713) (xy 20.015466 -29.822504) (xy 20.010882 -29.824172) (xy 20.002246 -29.827728)
			(xy 19.99488 -29.83484) (xy 19.964008 -29.863777) (xy 19.898144 -29.916909) (xy 19.828013 -29.964267)
			(xy 19.754122 -30.005511) (xy 19.677 -30.040344) (xy 19.597204 -30.068515) (xy 19.515308 -30.089823)
			(xy 19.4319 -30.104113) (xy 19.347581 -30.111282) (xy 19.30527 -30.1117) (xy 19.258789 -30.111168)
			(xy 19.166229 -30.102521) (xy 19.074876 -30.085295) (xy 18.985524 -30.059639) (xy 18.898947 -30.025777)
			(xy 18.815899 -29.984003) (xy 18.737101 -29.934679) (xy 18.663236 -29.878234) (xy 18.594946 -29.815158)
			(xy 18.532824 -29.745999) (xy 18.477411 -29.671358) (xy 18.452846 -29.631894) (xy 18.450306 -29.62783)
			(xy 18.43786 -29.614114) (xy 18.434558 -29.611574) (xy 18.412417 -29.59338) (xy 18.373316 -29.551486)
			(xy 18.340911 -29.504221) (xy 18.315928 -29.452647) (xy 18.298929 -29.39792) (xy 18.290293 -29.341268)
			(xy 18.289778 -29.312616) (xy 18.289778 -29.312108) (xy 18.289778 -29.30525) (xy 18.290794 -29.283152)
			(xy 18.292572 -29.265118) (xy 18.294795 -29.248489) (xy 18.301789 -29.215675) (xy 18.306542 -29.199586)
			(xy 18.308066 -29.192474) (xy 18.309844 -29.181552) (xy 18.309844 -29.177742) (xy 18.30959 -29.174948)
			(xy 18.307812 -29.115258) (xy 18.307812 -29.114242) (xy 18.308246 -29.072295) (xy 18.315295 -28.988697)
			(xy 18.329337 -28.905987) (xy 18.350274 -28.824747) (xy 18.377959 -28.745553) (xy 18.39468 -28.70708)
			(xy 18.396458 -28.703016) (xy 18.40103 -28.68295) (xy 18.40103 -28.681934) (xy 18.396458 -28.661868)
			(xy 18.39468 -28.657804) (xy 18.378005 -28.619476) (xy 18.350384 -28.54058) (xy 18.329466 -28.459648)
			(xy 18.315397 -28.377249) (xy 18.308276 -28.293961) (xy 18.307812 -28.252166) (xy 18.307812 -28.250642)
			(xy 18.30959 -28.189936) (xy 18.309844 -28.187142) (xy 18.309844 -28.183332) (xy 18.308066 -28.17241)
			(xy 18.306542 -28.165298) (xy 18.298702 -28.137896) (xy 18.290288 -28.081527) (xy 18.289778 -28.05303)
			(xy 18.289778 -28.04668) (xy 18.290032 -28.038298) (xy 18.291302 -28.01874) (xy 18.291302 -28.018486)
			(xy 18.29181 -28.012898) (xy 18.29548 -27.983489) (xy 18.310741 -27.926223) (xy 18.334668 -27.872005)
			(xy 18.35023 -27.846782) (xy 18.353532 -27.841702) (xy 18.370739 -27.816869) (xy 18.4117 -27.772462)
			(xy 18.435066 -27.75331) (xy 18.440908 -27.747722) (xy 18.445734 -27.742388) (xy 18.45183 -27.73426)
			(xy 18.47483 -27.697231) (xy 18.526337 -27.626899) (xy 18.5547 -27.593798) (xy 18.583011 -27.562107)
			(xy 18.644207 -27.503135) (xy 18.7102 -27.449587) (xy 18.780512 -27.401849) (xy 18.854631 -27.360269)
			(xy 18.932021 -27.325149) (xy 19.012119 -27.296743) (xy 19.094344 -27.275258) (xy 19.178099 -27.26085)
			(xy 19.262777 -27.253622) (xy 19.30527 -27.253184) (xy 19.305524 -27.253184) (xy 19.353043 -27.25374)
			(xy 19.447647 -27.262801) (xy 19.540959 -27.280829) (xy 19.632131 -27.307659) (xy 19.720334 -27.343048)
			(xy 19.804766 -27.386675) (xy 19.84502 -27.411934) (xy 19.882957 -27.436961) (xy 19.954574 -27.492925)
			(xy 19.988022 -27.523694) (xy 19.993356 -27.528774) (xy 19.994626 -27.530044) (xy 19.99488 -27.530298)
			(xy 20.02028 -27.540458) (xy 20.024847 -27.542215) (xy 20.034439 -27.544138) (xy 20.03933 -27.544268)
			(xy 22.130512 -27.544268) (xy 22.173502 -27.544757) (xy 22.259157 -27.55223) (xy 22.343852 -27.567042)
			(xy 22.42696 -27.589083) (xy 22.46757 -27.603196) (xy 22.50948 -27.619452) (xy 23.769506 -28.139136)
			(xy 28.39796 -28.139136) (xy 28.402031 -28.083514) (xy 28.414157 -28.029077) (xy 28.43408 -27.976986)
			(xy 28.461376 -27.928351) (xy 28.495462 -27.884208) (xy 28.535611 -27.845499) (xy 28.580969 -27.813048)
			(xy 28.630569 -27.787547) (xy 28.683353 -27.76954) (xy 28.738196 -27.75941) (xy 28.79393 -27.757373)
			(xy 28.849367 -27.763473) (xy 28.903324 -27.777579) (xy 28.954653 -27.799391) (xy 29.002259 -27.828445)
			(xy 29.045127 -27.86412) (xy 29.082344 -27.905657) (xy 29.113117 -27.95217) (xy 29.136789 -28.002667)
			(xy 29.152857 -28.056074) (xy 29.160977 -28.11125) (xy 29.161486 -28.139136) (xy 29.66796 -28.139136)
			(xy 29.672031 -28.083514) (xy 29.684157 -28.029077) (xy 29.70408 -27.976986) (xy 29.731376 -27.928351)
			(xy 29.765462 -27.884208) (xy 29.805611 -27.845499) (xy 29.850969 -27.813048) (xy 29.900569 -27.787547)
			(xy 29.953353 -27.76954) (xy 30.008196 -27.75941) (xy 30.06393 -27.757373) (xy 30.119367 -27.763473)
			(xy 30.173324 -27.777579) (xy 30.224653 -27.799391) (xy 30.272259 -27.828445) (xy 30.315127 -27.86412)
			(xy 30.352344 -27.905657) (xy 30.383117 -27.95217) (xy 30.406789 -28.002667) (xy 30.422857 -28.056074)
			(xy 30.430977 -28.11125) (xy 30.431486 -28.139136) (xy 30.430977 -28.167022) (xy 30.422857 -28.222198)
			(xy 30.406789 -28.275605) (xy 30.383117 -28.326102) (xy 30.352344 -28.372615) (xy 30.315127 -28.414152)
			(xy 30.272259 -28.449827) (xy 30.224653 -28.478881) (xy 30.173324 -28.500693) (xy 30.119367 -28.514799)
			(xy 30.06393 -28.520899) (xy 30.008196 -28.518862) (xy 29.953353 -28.508732) (xy 29.900569 -28.490725)
			(xy 29.850969 -28.465224) (xy 29.805611 -28.432773) (xy 29.765462 -28.394064) (xy 29.731376 -28.349921)
			(xy 29.70408 -28.301286) (xy 29.684157 -28.249195) (xy 29.672031 -28.194758) (xy 29.66796 -28.139136)
			(xy 29.161486 -28.139136) (xy 29.160977 -28.167022) (xy 29.152857 -28.222198) (xy 29.136789 -28.275605)
			(xy 29.113117 -28.326102) (xy 29.082344 -28.372615) (xy 29.045127 -28.414152) (xy 29.002259 -28.449827)
			(xy 28.954653 -28.478881) (xy 28.903324 -28.500693) (xy 28.849367 -28.514799) (xy 28.79393 -28.520899)
			(xy 28.738196 -28.518862) (xy 28.683353 -28.508732) (xy 28.630569 -28.490725) (xy 28.580969 -28.465224)
			(xy 28.535611 -28.432773) (xy 28.495462 -28.394064) (xy 28.461376 -28.349921) (xy 28.43408 -28.301286)
			(xy 28.414157 -28.249195) (xy 28.402031 -28.194758) (xy 28.39796 -28.139136) (xy 23.769506 -28.139136)
			(xy 24.281892 -28.350464) (xy 24.320873 -28.367008) (xy 24.396147 -28.405816) (xy 24.467856 -28.45087)
			(xy 24.535484 -28.501847) (xy 24.598542 -28.558379) (xy 24.656576 -28.620058) (xy 24.683212 -28.652978)
			(xy 25.055308 -29.12237) (xy 34.606992 -29.12237) (xy 34.606992 -28.25877) (xy 34.607482 -28.228802)
			(xy 34.615305 -28.16938) (xy 34.630818 -28.111487) (xy 34.653754 -28.056114) (xy 34.683721 -28.004208)
			(xy 34.720208 -27.956658) (xy 34.762588 -27.914278) (xy 34.810138 -27.877791) (xy 34.862044 -27.847824)
			(xy 34.917417 -27.824888) (xy 34.97531 -27.809375) (xy 35.034732 -27.801552) (xy 35.094668 -27.801552)
			(xy 35.15409 -27.809375) (xy 35.211983 -27.824888) (xy 35.267356 -27.847824) (xy 35.319262 -27.877791)
			(xy 35.366812 -27.914278) (xy 35.409192 -27.956658) (xy 35.445679 -28.004208) (xy 35.475646 -28.056114)
			(xy 35.498582 -28.111487) (xy 35.514095 -28.16938) (xy 35.521918 -28.228802) (xy 35.522408 -28.25877)
			(xy 35.522408 -29.12237) (xy 35.521918 -29.152338) (xy 35.514095 -29.21176) (xy 35.498582 -29.269653)
			(xy 35.475646 -29.325026) (xy 35.445679 -29.376932) (xy 35.409192 -29.424482) (xy 35.366812 -29.466862)
			(xy 35.319262 -29.503349) (xy 35.267356 -29.533316) (xy 35.211983 -29.556252) (xy 35.15409 -29.571765)
			(xy 35.094668 -29.579588) (xy 35.034732 -29.579588) (xy 34.97531 -29.571765) (xy 34.917417 -29.556252)
			(xy 34.862044 -29.533316) (xy 34.810138 -29.503349) (xy 34.762588 -29.466862) (xy 34.720208 -29.424482)
			(xy 34.683721 -29.376932) (xy 34.653754 -29.325026) (xy 34.630818 -29.269653) (xy 34.615305 -29.21176)
			(xy 34.607482 -29.152338) (xy 34.606992 -29.12237) (xy 25.055308 -29.12237) (xy 26.049778 -30.376876)
			(xy 26.888948 -30.376876) (xy 26.889503 -30.34796) (xy 26.898222 -30.29079) (xy 26.915471 -30.235591)
			(xy 26.940856 -30.183629) (xy 26.973794 -30.136094) (xy 27.013531 -30.094077) (xy 27.036014 -30.075886)
			(xy 27.04482 -30.068277) (xy 27.055003 -30.047378) (xy 27.055572 -30.035754) (xy 27.055572 -29.955998)
			(xy 27.055029 -29.944366) (xy 27.044844 -29.923456) (xy 27.036014 -29.915866) (xy 27.013517 -29.897691)
			(xy 26.973782 -29.855668) (xy 26.940844 -29.80813) (xy 26.915458 -29.756166) (xy 26.898205 -29.700965)
			(xy 26.88948 -29.643793) (xy 26.888948 -29.614876) (xy 26.889434 -29.587625) (xy 26.89719 -29.533677)
			(xy 26.912545 -29.481382) (xy 26.935187 -29.431805) (xy 26.964653 -29.385955) (xy 27.000344 -29.344764)
			(xy 27.041535 -29.309073) (xy 27.087385 -29.279607) (xy 27.136962 -29.256965) (xy 27.189257 -29.24161)
			(xy 27.243205 -29.233854) (xy 27.297707 -29.233854) (xy 27.351655 -29.24161) (xy 27.40395 -29.256965)
			(xy 27.453527 -29.279607) (xy 27.499377 -29.309073) (xy 27.540568 -29.344764) (xy 27.576259 -29.385955)
			(xy 27.605725 -29.431805) (xy 27.628367 -29.481382) (xy 27.643722 -29.533677) (xy 27.651478 -29.587625)
			(xy 27.651964 -29.614876) (xy 27.651442 -29.643793) (xy 27.642716 -29.700965) (xy 27.625459 -29.756164)
			(xy 27.600069 -29.808126) (xy 27.567125 -29.85566) (xy 27.527384 -29.897676) (xy 27.504898 -29.915866)
			(xy 27.496116 -29.923497) (xy 27.485919 -29.94438) (xy 27.48534 -29.955998) (xy 27.48534 -30.035754)
			(xy 27.485848 -30.04739) (xy 27.496058 -30.0683) (xy 27.504898 -30.075886) (xy 27.527374 -30.094085)
			(xy 27.56711 -30.136103) (xy 27.60005 -30.183637) (xy 27.62544 -30.235596) (xy 27.642697 -30.290792)
			(xy 27.651428 -30.34796) (xy 27.651964 -30.376876) (xy 29.929074 -30.376876) (xy 29.929619 -30.34796)
			(xy 29.938339 -30.290789) (xy 29.955589 -30.235589) (xy 29.980976 -30.183627) (xy 30.013916 -30.136092)
			(xy 30.053655 -30.094076) (xy 30.07614 -30.075886) (xy 30.08495 -30.068282) (xy 30.09513 -30.047379)
			(xy 30.095698 -30.035754) (xy 30.095698 -29.955998) (xy 30.095147 -29.944368) (xy 30.084967 -29.923458)
			(xy 30.07614 -29.915866) (xy 30.053649 -29.897684) (xy 30.013912 -29.855664) (xy 29.980973 -29.808127)
			(xy 29.955585 -29.756164) (xy 29.938332 -29.700964) (xy 29.929606 -29.643793) (xy 29.929074 -29.614876)
			(xy 29.92956 -29.587625) (xy 29.937316 -29.533677) (xy 29.952671 -29.481382) (xy 29.975313 -29.431805)
			(xy 30.004779 -29.385955) (xy 30.04047 -29.344764) (xy 30.081661 -29.309073) (xy 30.127511 -29.279607)
			(xy 30.177088 -29.256965) (xy 30.229383 -29.24161) (xy 30.283331 -29.233854) (xy 30.337833 -29.233854)
			(xy 30.391781 -29.24161) (xy 30.444076 -29.256965) (xy 30.493653 -29.279607) (xy 30.539503 -29.309073)
			(xy 30.580694 -29.344764) (xy 30.616385 -29.385955) (xy 30.645851 -29.431805) (xy 30.668493 -29.481382)
			(xy 30.683848 -29.533677) (xy 30.691604 -29.587625) (xy 30.69209 -29.614876) (xy 30.691558 -29.643792)
			(xy 30.682832 -29.700963) (xy 30.665577 -29.756162) (xy 30.640188 -29.808124) (xy 30.607247 -29.855658)
			(xy 30.567508 -29.897675) (xy 30.545024 -29.915866) (xy 30.53623 -29.923485) (xy 30.526042 -29.944377)
			(xy 30.525466 -29.955998) (xy 30.525466 -30.035754) (xy 30.525965 -30.047392) (xy 30.53618 -30.068302)
			(xy 30.545024 -30.075886) (xy 30.567506 -30.094079) (xy 30.60724 -30.136099) (xy 30.640178 -30.183634)
			(xy 30.665567 -30.235594) (xy 30.682824 -30.290791) (xy 30.691554 -30.34796) (xy 30.69209 -30.376876)
			(xy 30.691604 -30.404127) (xy 30.683848 -30.458075) (xy 30.668493 -30.51037) (xy 30.645851 -30.559947)
			(xy 30.616385 -30.605797) (xy 30.580694 -30.646988) (xy 30.539503 -30.682679) (xy 30.493653 -30.712145)
			(xy 30.444076 -30.734787) (xy 30.391781 -30.750142) (xy 30.337833 -30.757898) (xy 30.283331 -30.757898)
			(xy 30.229383 -30.750142) (xy 30.177088 -30.734787) (xy 30.127511 -30.712145) (xy 30.081661 -30.682679)
			(xy 30.04047 -30.646988) (xy 30.004779 -30.605797) (xy 29.975313 -30.559947) (xy 29.952671 -30.51037)
			(xy 29.937316 -30.458075) (xy 29.92956 -30.404127) (xy 29.929074 -30.376876) (xy 27.651964 -30.376876)
			(xy 27.651478 -30.404127) (xy 27.643722 -30.458075) (xy 27.628367 -30.51037) (xy 27.605725 -30.559947)
			(xy 27.576259 -30.605797) (xy 27.540568 -30.646988) (xy 27.499377 -30.682679) (xy 27.453527 -30.712145)
			(xy 27.40395 -30.734787) (xy 27.351655 -30.750142) (xy 27.297707 -30.757898) (xy 27.243205 -30.757898)
			(xy 27.189257 -30.750142) (xy 27.136962 -30.734787) (xy 27.087385 -30.712145) (xy 27.041535 -30.682679)
			(xy 27.000344 -30.646988) (xy 26.964653 -30.605797) (xy 26.935187 -30.559947) (xy 26.912545 -30.51037)
			(xy 26.89719 -30.458075) (xy 26.889434 -30.404127) (xy 26.888948 -30.376876) (xy 26.049778 -30.376876)
			(xy 26.482279 -30.922468) (xy 32.752792 -30.922468) (xy 32.752792 -30.058868) (xy 32.753282 -30.0289)
			(xy 32.761105 -29.969478) (xy 32.776618 -29.911585) (xy 32.799554 -29.856212) (xy 32.829521 -29.804306)
			(xy 32.866008 -29.756756) (xy 32.908388 -29.714376) (xy 32.955938 -29.677889) (xy 33.007844 -29.647922)
			(xy 33.063217 -29.624986) (xy 33.12111 -29.609473) (xy 33.180532 -29.60165) (xy 33.240468 -29.60165)
			(xy 33.29989 -29.609473) (xy 33.357783 -29.624986) (xy 33.413156 -29.647922) (xy 33.465062 -29.677889)
			(xy 33.512612 -29.714376) (xy 33.554992 -29.756756) (xy 33.591479 -29.804306) (xy 33.621446 -29.856212)
			(xy 33.644382 -29.911585) (xy 33.659895 -29.969478) (xy 33.667718 -30.0289) (xy 33.668208 -30.058868)
			(xy 33.668208 -30.922468) (xy 33.667718 -30.952436) (xy 33.659895 -31.011858) (xy 33.644382 -31.069751)
			(xy 33.621446 -31.125124) (xy 33.591479 -31.17703) (xy 33.554992 -31.22458) (xy 33.512612 -31.26696)
			(xy 33.465062 -31.303447) (xy 33.413156 -31.333414) (xy 33.357783 -31.35635) (xy 33.29989 -31.371863)
			(xy 33.240468 -31.379686) (xy 33.180532 -31.379686) (xy 33.12111 -31.371863) (xy 33.063217 -31.35635)
			(xy 33.007844 -31.333414) (xy 32.955938 -31.303447) (xy 32.908388 -31.26696) (xy 32.866008 -31.22458)
			(xy 32.829521 -31.17703) (xy 32.799554 -31.125124) (xy 32.776618 -31.069751) (xy 32.761105 -31.011858)
			(xy 32.753282 -30.952436) (xy 32.752792 -30.922468) (xy 26.482279 -30.922468) (xy 26.541476 -30.997144)
			(xy 26.54427 -31.000446) (xy 26.910538 -31.366714) (xy 26.918887 -31.374196) (xy 26.939979 -31.381712)
			(xy 26.951178 -31.381192) (xy 26.981912 -31.378398) (xy 26.98242 -31.378398) (xy 26.991818 -31.377382)
			(xy 26.996559 -31.377031) (xy 27.006021 -31.377934) (xy 27.010614 -31.37916) (xy 27.0129 -31.379668)
			(xy 27.033728 -31.384748) (xy 27.045158 -31.382462) (xy 27.065224 -31.353252) (xy 27.080528 -31.331566)
			(xy 27.116177 -31.292245) (xy 27.156936 -31.258247) (xy 27.202016 -31.230231) (xy 27.250545 -31.208738)
			(xy 27.301587 -31.194183) (xy 27.354154 -31.186848) (xy 27.380692 -31.186374) (xy 27.407944 -31.186859)
			(xy 27.461894 -31.194615) (xy 27.51419 -31.209969) (xy 27.56377 -31.232609) (xy 27.609622 -31.262075)
			(xy 27.650815 -31.297766) (xy 27.686509 -31.338957) (xy 27.715978 -31.384807) (xy 27.738622 -31.434385)
			(xy 27.75398 -31.486681) (xy 27.761739 -31.54063) (xy 27.7622 -31.567882) (xy 27.761652 -31.596996)
			(xy 27.752806 -31.654549) (xy 27.735317 -31.710089) (xy 27.730797 -31.719266) (xy 28.285438 -31.719266)
			(xy 28.289509 -31.663644) (xy 28.301635 -31.609207) (xy 28.321558 -31.557116) (xy 28.348854 -31.508481)
			(xy 28.38294 -31.464338) (xy 28.423089 -31.425629) (xy 28.468447 -31.393178) (xy 28.518047 -31.367677)
			(xy 28.570831 -31.34967) (xy 28.625674 -31.33954) (xy 28.681408 -31.337503) (xy 28.736845 -31.343603)
			(xy 28.790802 -31.357709) (xy 28.842131 -31.379521) (xy 28.889737 -31.408575) (xy 28.932605 -31.44425)
			(xy 28.969822 -31.485787) (xy 29.000595 -31.5323) (xy 29.024267 -31.582797) (xy 29.040335 -31.636204)
			(xy 29.044485 -31.664402) (xy 29.561026 -31.664402) (xy 29.565097 -31.60878) (xy 29.577223 -31.554343)
			(xy 29.597146 -31.502252) (xy 29.624442 -31.453617) (xy 29.658528 -31.409474) (xy 29.698677 -31.370765)
			(xy 29.744035 -31.338314) (xy 29.793635 -31.312813) (xy 29.846419 -31.294806) (xy 29.901262 -31.284676)
			(xy 29.956996 -31.282639) (xy 30.012433 -31.288739) (xy 30.06639 -31.302845) (xy 30.117719 -31.324657)
			(xy 30.165325 -31.353711) (xy 30.208193 -31.389386) (xy 30.24541 -31.430923) (xy 30.276183 -31.477436)
			(xy 30.299855 -31.527933) (xy 30.315923 -31.58134) (xy 30.324043 -31.636516) (xy 30.324552 -31.664402)
			(xy 30.324043 -31.692288) (xy 30.315923 -31.747464) (xy 30.306983 -31.777178) (xy 30.8262 -31.777178)
			(xy 30.830271 -31.721556) (xy 30.842397 -31.667119) (xy 30.86232 -31.615028) (xy 30.889616 -31.566393)
			(xy 30.923702 -31.52225) (xy 30.963851 -31.483541) (xy 31.009209 -31.45109) (xy 31.058809 -31.425589)
			(xy 31.111593 -31.407582) (xy 31.166436 -31.397452) (xy 31.22217 -31.395415) (xy 31.277607 -31.401515)
			(xy 31.331564 -31.415621) (xy 31.382893 -31.437433) (xy 31.430499 -31.466487) (xy 31.473367 -31.502162)
			(xy 31.510584 -31.543699) (xy 31.541357 -31.590212) (xy 31.565029 -31.640709) (xy 31.581097 -31.694116)
			(xy 31.589217 -31.749292) (xy 31.589726 -31.777178) (xy 31.589217 -31.805064) (xy 31.581097 -31.86024)
			(xy 31.565029 -31.913647) (xy 31.541357 -31.964144) (xy 31.510584 -32.010657) (xy 31.473367 -32.052194)
			(xy 31.430499 -32.087869) (xy 31.382893 -32.116923) (xy 31.331564 -32.138735) (xy 31.277607 -32.152841)
			(xy 31.22217 -32.158941) (xy 31.166436 -32.156904) (xy 31.111593 -32.146774) (xy 31.058809 -32.128767)
			(xy 31.009209 -32.103266) (xy 30.963851 -32.070815) (xy 30.923702 -32.032106) (xy 30.889616 -31.987963)
			(xy 30.86232 -31.939328) (xy 30.842397 -31.887237) (xy 30.830271 -31.8328) (xy 30.8262 -31.777178)
			(xy 30.306983 -31.777178) (xy 30.299855 -31.800871) (xy 30.276183 -31.851368) (xy 30.24541 -31.897881)
			(xy 30.208193 -31.939418) (xy 30.165325 -31.975093) (xy 30.117719 -32.004147) (xy 30.06639 -32.025959)
			(xy 30.012433 -32.040065) (xy 29.956996 -32.046165) (xy 29.901262 -32.044128) (xy 29.846419 -32.033998)
			(xy 29.793635 -32.015991) (xy 29.744035 -31.99049) (xy 29.698677 -31.958039) (xy 29.658528 -31.91933)
			(xy 29.624442 -31.875187) (xy 29.597146 -31.826552) (xy 29.577223 -31.774461) (xy 29.565097 -31.720024)
			(xy 29.561026 -31.664402) (xy 29.044485 -31.664402) (xy 29.048455 -31.69138) (xy 29.048964 -31.719266)
			(xy 29.048455 -31.747152) (xy 29.040335 -31.802328) (xy 29.024267 -31.855735) (xy 29.000595 -31.906232)
			(xy 28.969822 -31.952745) (xy 28.932605 -31.994282) (xy 28.889737 -32.029957) (xy 28.842131 -32.059011)
			(xy 28.790802 -32.080823) (xy 28.736845 -32.094929) (xy 28.681408 -32.101029) (xy 28.625674 -32.098992)
			(xy 28.570831 -32.088862) (xy 28.518047 -32.070855) (xy 28.468447 -32.045354) (xy 28.423089 -32.012903)
			(xy 28.38294 -31.974194) (xy 28.348854 -31.930051) (xy 28.321558 -31.881416) (xy 28.301635 -31.829325)
			(xy 28.289509 -31.774888) (xy 28.285438 -31.719266) (xy 27.730797 -31.719266) (xy 27.709591 -31.762326)
			(xy 27.676226 -31.810048) (xy 27.635996 -31.852145) (xy 27.589836 -31.887639) (xy 27.564588 -31.902146)
			(xy 27.555952 -31.906972) (xy 27.53741 -31.929832) (xy 27.534298 -31.933831) (xy 27.52956 -31.942787)
			(xy 27.528012 -31.947612) (xy 27.519884 -31.97606) (xy 27.517598 -31.98241) (xy 27.510486 -31.998666)
			(xy 27.506232 -32.010238) (xy 27.507958 -32.034792) (xy 27.513788 -32.045656) (xy 27.787346 -32.490918)
			(xy 27.92956 -32.722312) (xy 34.606992 -32.722312) (xy 34.606992 -31.858712) (xy 34.607482 -31.828744)
			(xy 34.615305 -31.769322) (xy 34.630818 -31.711429) (xy 34.653754 -31.656056) (xy 34.683721 -31.60415)
			(xy 34.720208 -31.5566) (xy 34.762588 -31.51422) (xy 34.810138 -31.477733) (xy 34.862044 -31.447766)
			(xy 34.917417 -31.42483) (xy 34.97531 -31.409317) (xy 35.034732 -31.401494) (xy 35.094668 -31.401494)
			(xy 35.15409 -31.409317) (xy 35.211983 -31.42483) (xy 35.267356 -31.447766) (xy 35.319262 -31.477733)
			(xy 35.366812 -31.51422) (xy 35.409192 -31.5566) (xy 35.445679 -31.60415) (xy 35.475646 -31.656056)
			(xy 35.498582 -31.711429) (xy 35.514095 -31.769322) (xy 35.521918 -31.828744) (xy 35.522408 -31.858712)
			(xy 35.522408 -32.722312) (xy 35.521918 -32.75228) (xy 35.514095 -32.811702) (xy 35.498582 -32.869595)
			(xy 35.475646 -32.924968) (xy 35.445679 -32.976874) (xy 35.409192 -33.024424) (xy 35.366812 -33.066804)
			(xy 35.319262 -33.103291) (xy 35.267356 -33.133258) (xy 35.211983 -33.156194) (xy 35.15409 -33.171707)
			(xy 35.094668 -33.17953) (xy 35.034732 -33.17953) (xy 34.97531 -33.171707) (xy 34.917417 -33.156194)
			(xy 34.862044 -33.133258) (xy 34.810138 -33.103291) (xy 34.762588 -33.066804) (xy 34.720208 -33.024424)
			(xy 34.683721 -32.976874) (xy 34.653754 -32.924968) (xy 34.630818 -32.869595) (xy 34.615305 -32.811702)
			(xy 34.607482 -32.75228) (xy 34.606992 -32.722312) (xy 27.92956 -32.722312) (xy 28.001214 -32.838898)
			(xy 28.001722 -32.83966) (xy 28.008326 -32.848042) (xy 28.014168 -32.853376) (xy 28.04033 -32.87141)
			(xy 28.050744 -32.873442) (xy 28.076493 -32.878851) (xy 28.126299 -32.895809) (xy 28.173303 -32.919451)
			(xy 28.216611 -32.949328) (xy 28.255401 -32.984875) (xy 28.288938 -33.025415) (xy 28.316585 -33.07018)
			(xy 28.337817 -33.11832) (xy 28.352231 -33.168922) (xy 28.359554 -33.221024) (xy 28.360116 -33.24733)
			(xy 28.360116 -33.2486) (xy 28.360116 -33.25368) (xy 28.359608 -33.270444) (xy 28.3591 -33.279842)
			(xy 28.36164 -33.28797) (xy 28.363129 -33.292415) (xy 28.367475 -33.300721) (xy 28.370276 -33.30448)
			(xy 28.903676 -33.977834) (xy 29.335379 -34.52241) (xy 32.752792 -34.52241) (xy 32.752792 -33.65881)
			(xy 32.753282 -33.628842) (xy 32.761105 -33.56942) (xy 32.776618 -33.511527) (xy 32.799554 -33.456154)
			(xy 32.829521 -33.404248) (xy 32.866008 -33.356698) (xy 32.908388 -33.314318) (xy 32.955938 -33.277831)
			(xy 33.007844 -33.247864) (xy 33.063217 -33.224928) (xy 33.12111 -33.209415) (xy 33.180532 -33.201592)
			(xy 33.240468 -33.201592) (xy 33.29989 -33.209415) (xy 33.357783 -33.224928) (xy 33.413156 -33.247864)
			(xy 33.465062 -33.277831) (xy 33.512612 -33.314318) (xy 33.554992 -33.356698) (xy 33.591479 -33.404248)
			(xy 33.621446 -33.456154) (xy 33.644382 -33.511527) (xy 33.659895 -33.56942) (xy 33.667718 -33.628842)
			(xy 33.668208 -33.65881) (xy 33.668208 -34.52241) (xy 33.667718 -34.552378) (xy 33.659895 -34.6118)
			(xy 33.644382 -34.669693) (xy 33.621446 -34.725066) (xy 33.591479 -34.776972) (xy 33.554992 -34.824522)
			(xy 33.512612 -34.866902) (xy 33.465062 -34.903389) (xy 33.413156 -34.933356) (xy 33.357783 -34.956292)
			(xy 33.29989 -34.971805) (xy 33.240468 -34.979628) (xy 33.180532 -34.979628) (xy 33.12111 -34.971805)
			(xy 33.063217 -34.956292) (xy 33.007844 -34.933356) (xy 32.955938 -34.903389) (xy 32.908388 -34.866902)
			(xy 32.866008 -34.824522) (xy 32.829521 -34.776972) (xy 32.799554 -34.725066) (xy 32.776618 -34.669693)
			(xy 32.761105 -34.6118) (xy 32.753282 -34.552378) (xy 32.752792 -34.52241) (xy 29.335379 -34.52241)
			(xy 29.784802 -35.089338) (xy 29.791208 -35.096729) (xy 29.808197 -35.106384) (xy 29.817822 -35.108134)
			(xy 29.822648 -35.108388) (xy 29.825696 -35.108642) (xy 29.9085 -35.102292) (xy 29.91231 -35.102038)
			(xy 29.924464 -35.100413) (xy 29.945291 -35.08754) (xy 29.952188 -35.0774) (xy 29.952696 -35.076638)
			(xy 29.952696 -35.076384) (xy 29.967345 -35.051649) (xy 30.002916 -35.006491) (xy 30.04486 -34.967181)
			(xy 30.092227 -34.934609) (xy 30.143944 -34.909513) (xy 30.198842 -34.89246) (xy 30.255677 -34.883838)
			(xy 30.28442 -34.883344) (xy 30.311672 -34.883831) (xy 30.36562 -34.89159) (xy 30.417915 -34.906946)
			(xy 30.467493 -34.929588) (xy 30.513344 -34.959054) (xy 30.554536 -34.994745) (xy 30.590229 -35.035934)
			(xy 30.619699 -35.081783) (xy 30.642344 -35.131359) (xy 30.657704 -35.183653) (xy 30.665467 -35.2376)
			(xy 30.665928 -35.264852) (xy 30.66547 -35.291461) (xy 30.658082 -35.344163) (xy 30.643444 -35.395327)
			(xy 30.621839 -35.443962) (xy 30.593687 -35.489122) (xy 30.559532 -35.529934) (xy 30.520039 -35.565604)
			(xy 30.475973 -35.595441) (xy 30.428189 -35.618866) (xy 30.403038 -35.627564) (xy 30.391862 -35.63112)
			(xy 30.367224 -35.65525) (xy 30.362907 -35.659704) (xy 30.356365 -35.670239) (xy 30.35427 -35.676078)
			(xy 30.332426 -35.744658) (xy 30.329478 -35.755866) (xy 30.332907 -35.778762) (xy 30.33903 -35.7886)
			(xy 30.734035 -36.286948) (xy 31.200342 -36.286948) (xy 31.204413 -36.231326) (xy 31.216539 -36.176889)
			(xy 31.236462 -36.124798) (xy 31.263758 -36.076163) (xy 31.297844 -36.03202) (xy 31.337993 -35.993311)
			(xy 31.383351 -35.96086) (xy 31.432951 -35.935359) (xy 31.485735 -35.917352) (xy 31.540578 -35.907222)
			(xy 31.596312 -35.905185) (xy 31.651749 -35.911285) (xy 31.705706 -35.925391) (xy 31.757035 -35.947203)
			(xy 31.804641 -35.976257) (xy 31.847509 -36.011932) (xy 31.884726 -36.053469) (xy 31.915499 -36.099982)
			(xy 31.939171 -36.150479) (xy 31.955239 -36.203886) (xy 31.963359 -36.259062) (xy 31.963868 -36.286948)
			(xy 31.963359 -36.314834) (xy 31.955239 -36.37001) (xy 31.939171 -36.423417) (xy 31.915499 -36.473914)
			(xy 31.887954 -36.515548) (xy 33.014156 -36.515548) (xy 33.018227 -36.459926) (xy 33.030353 -36.405489)
			(xy 33.050276 -36.353398) (xy 33.077572 -36.304763) (xy 33.111658 -36.26062) (xy 33.151807 -36.221911)
			(xy 33.197165 -36.18946) (xy 33.246765 -36.163959) (xy 33.299549 -36.145952) (xy 33.354392 -36.135822)
			(xy 33.410126 -36.133785) (xy 33.465563 -36.139885) (xy 33.51952 -36.153991) (xy 33.570849 -36.175803)
			(xy 33.618455 -36.204857) (xy 33.661323 -36.240532) (xy 33.69854 -36.282069) (xy 33.729313 -36.328582)
			(xy 33.752985 -36.379079) (xy 33.769053 -36.432486) (xy 33.777173 -36.487662) (xy 33.777682 -36.515548)
			(xy 33.777173 -36.543434) (xy 33.769053 -36.59861) (xy 33.768596 -36.60013) (xy 37.998153 -36.60013)
			(xy 38.002158 -36.512222) (xy 38.014141 -36.425042) (xy 38.034001 -36.339313) (xy 38.061576 -36.255745)
			(xy 38.096635 -36.175031) (xy 38.138888 -36.097839) (xy 38.187986 -36.02481) (xy 38.243522 -35.956548)
			(xy 38.305034 -35.893618) (xy 38.372015 -35.836544) (xy 38.443908 -35.785796) (xy 38.520117 -35.741796)
			(xy 38.600012 -35.704909) (xy 38.682931 -35.67544) (xy 38.768186 -35.653633) (xy 38.85507 -35.639669)
			(xy 38.942864 -35.633663) (xy 39.030841 -35.635667) (xy 39.118271 -35.645662) (xy 39.20443 -35.663566)
			(xy 39.288604 -35.68923) (xy 39.370095 -35.722443) (xy 39.448229 -35.762929) (xy 39.522357 -35.810351)
			(xy 39.591865 -35.864318) (xy 39.605164 -35.876738) (xy 44.717206 -35.876738) (xy 44.721277 -35.821116)
			(xy 44.733403 -35.766679) (xy 44.753326 -35.714588) (xy 44.780622 -35.665953) (xy 44.814708 -35.62181)
			(xy 44.854857 -35.583101) (xy 44.900215 -35.55065) (xy 44.949815 -35.525149) (xy 45.002599 -35.507142)
			(xy 45.057442 -35.497012) (xy 45.113176 -35.494975) (xy 45.168613 -35.501075) (xy 45.22257 -35.515181)
			(xy 45.273899 -35.536993) (xy 45.321505 -35.566047) (xy 45.364373 -35.601722) (xy 45.40159 -35.643259)
			(xy 45.432363 -35.689772) (xy 45.456035 -35.740269) (xy 45.472103 -35.793676) (xy 45.480223 -35.848852)
			(xy 45.480732 -35.876738) (xy 45.480223 -35.904624) (xy 45.472103 -35.9598) (xy 45.456035 -36.013207)
			(xy 45.432363 -36.063704) (xy 45.40159 -36.110217) (xy 45.364373 -36.151754) (xy 45.321505 -36.187429)
			(xy 45.273899 -36.216483) (xy 45.22257 -36.238295) (xy 45.168613 -36.252401) (xy 45.113176 -36.258501)
			(xy 45.057442 -36.256464) (xy 45.002599 -36.246334) (xy 44.949815 -36.228327) (xy 44.900215 -36.202826)
			(xy 44.854857 -36.170375) (xy 44.814708 -36.131666) (xy 44.780622 -36.087523) (xy 44.753326 -36.038888)
			(xy 44.733403 -35.986797) (xy 44.721277 -35.93236) (xy 44.717206 -35.876738) (xy 39.605164 -35.876738)
			(xy 39.656179 -35.924383) (xy 39.714763 -35.990047) (xy 39.767134 -36.060766) (xy 39.812857 -36.135954)
			(xy 39.851554 -36.214989) (xy 39.882903 -36.297215) (xy 39.906645 -36.381951) (xy 39.922583 -36.468495)
			(xy 39.926369 -36.50996) (xy 46.613824 -36.50996) (xy 46.617895 -36.454338) (xy 46.630021 -36.399901)
			(xy 46.649944 -36.34781) (xy 46.67724 -36.299175) (xy 46.711326 -36.255032) (xy 46.751475 -36.216323)
			(xy 46.796833 -36.183872) (xy 46.846433 -36.158371) (xy 46.899217 -36.140364) (xy 46.95406 -36.130234)
			(xy 47.009794 -36.128197) (xy 47.065231 -36.134297) (xy 47.119188 -36.148403) (xy 47.170517 -36.170215)
			(xy 47.218123 -36.199269) (xy 47.260991 -36.234944) (xy 47.298208 -36.276481) (xy 47.328981 -36.322994)
			(xy 47.352653 -36.373491) (xy 47.368721 -36.426898) (xy 47.376841 -36.482074) (xy 47.37735 -36.50996)
			(xy 47.376841 -36.537846) (xy 47.368721 -36.593022) (xy 47.352653 -36.646429) (xy 47.328981 -36.696926)
			(xy 47.298208 -36.743439) (xy 47.260991 -36.784976) (xy 47.218123 -36.820651) (xy 47.170517 -36.849705)
			(xy 47.119188 -36.871517) (xy 47.065231 -36.885623) (xy 47.009794 -36.891723) (xy 46.95406 -36.889686)
			(xy 46.899217 -36.879556) (xy 46.846433 -36.861549) (xy 46.796833 -36.836048) (xy 46.751475 -36.803597)
			(xy 46.711326 -36.764888) (xy 46.67724 -36.720745) (xy 46.649944 -36.67211) (xy 46.630021 -36.620019)
			(xy 46.617895 -36.565582) (xy 46.613824 -36.50996) (xy 39.926369 -36.50996) (xy 39.930585 -36.55613)
			(xy 39.931086 -36.60013) (xy 39.930585 -36.64413) (xy 39.922583 -36.731765) (xy 39.906645 -36.818309)
			(xy 39.882903 -36.903045) (xy 39.851554 -36.985271) (xy 39.812857 -37.064306) (xy 39.767134 -37.139494)
			(xy 39.714763 -37.210213) (xy 39.656179 -37.275877) (xy 39.591865 -37.335942) (xy 39.522357 -37.389909)
			(xy 39.448229 -37.437331) (xy 39.375223 -37.47516) (xy 43.759118 -37.47516) (xy 43.763189 -37.419538)
			(xy 43.775315 -37.365101) (xy 43.795238 -37.31301) (xy 43.822534 -37.264375) (xy 43.85662 -37.220232)
			(xy 43.896769 -37.181523) (xy 43.942127 -37.149072) (xy 43.991727 -37.123571) (xy 44.044511 -37.105564)
			(xy 44.099354 -37.095434) (xy 44.155088 -37.093397) (xy 44.210525 -37.099497) (xy 44.264482 -37.113603)
			(xy 44.315811 -37.135415) (xy 44.363417 -37.164469) (xy 44.406285 -37.200144) (xy 44.443502 -37.241681)
			(xy 44.474275 -37.288194) (xy 44.497947 -37.338691) (xy 44.514015 -37.392098) (xy 44.522135 -37.447274)
			(xy 44.522644 -37.47516) (xy 44.522135 -37.503046) (xy 44.514015 -37.558222) (xy 44.497947 -37.611629)
			(xy 44.474275 -37.662126) (xy 44.474122 -37.662358) (xy 45.948344 -37.662358) (xy 45.952415 -37.606736)
			(xy 45.964541 -37.552299) (xy 45.984464 -37.500208) (xy 46.01176 -37.451573) (xy 46.045846 -37.40743)
			(xy 46.085995 -37.368721) (xy 46.131353 -37.33627) (xy 46.180953 -37.310769) (xy 46.233737 -37.292762)
			(xy 46.28858 -37.282632) (xy 46.344314 -37.280595) (xy 46.399751 -37.286695) (xy 46.453708 -37.300801)
			(xy 46.505037 -37.322613) (xy 46.552643 -37.351667) (xy 46.595511 -37.387342) (xy 46.632728 -37.428879)
			(xy 46.663501 -37.475392) (xy 46.687173 -37.525889) (xy 46.703241 -37.579296) (xy 46.711361 -37.634472)
			(xy 46.71187 -37.662358) (xy 46.711361 -37.690244) (xy 46.703241 -37.74542) (xy 46.687173 -37.798827)
			(xy 46.663501 -37.849324) (xy 46.632728 -37.895837) (xy 46.595511 -37.937374) (xy 46.552643 -37.973049)
			(xy 46.505037 -38.002103) (xy 46.453708 -38.023915) (xy 46.399751 -38.038021) (xy 46.344314 -38.044121)
			(xy 46.28858 -38.042084) (xy 46.233737 -38.031954) (xy 46.180953 -38.013947) (xy 46.131353 -37.988446)
			(xy 46.085995 -37.955995) (xy 46.045846 -37.917286) (xy 46.01176 -37.873143) (xy 45.984464 -37.824508)
			(xy 45.964541 -37.772417) (xy 45.952415 -37.71798) (xy 45.948344 -37.662358) (xy 44.474122 -37.662358)
			(xy 44.443502 -37.708639) (xy 44.406285 -37.750176) (xy 44.363417 -37.785851) (xy 44.315811 -37.814905)
			(xy 44.264482 -37.836717) (xy 44.210525 -37.850823) (xy 44.155088 -37.856923) (xy 44.099354 -37.854886)
			(xy 44.044511 -37.844756) (xy 43.991727 -37.826749) (xy 43.942127 -37.801248) (xy 43.896769 -37.768797)
			(xy 43.85662 -37.730088) (xy 43.822534 -37.685945) (xy 43.795238 -37.63731) (xy 43.775315 -37.585219)
			(xy 43.763189 -37.530782) (xy 43.759118 -37.47516) (xy 39.375223 -37.47516) (xy 39.370095 -37.477817)
			(xy 39.288604 -37.51103) (xy 39.20443 -37.536694) (xy 39.118271 -37.554598) (xy 39.030841 -37.564593)
			(xy 38.942864 -37.566597) (xy 38.85507 -37.560591) (xy 38.768186 -37.546627) (xy 38.682931 -37.52482)
			(xy 38.600012 -37.495351) (xy 38.520117 -37.458464) (xy 38.443908 -37.414464) (xy 38.372015 -37.363716)
			(xy 38.305034 -37.306642) (xy 38.243522 -37.243712) (xy 38.187986 -37.17545) (xy 38.138888 -37.102421)
			(xy 38.096635 -37.025229) (xy 38.061576 -36.944515) (xy 38.034001 -36.860947) (xy 38.014141 -36.775218)
			(xy 38.002158 -36.688038) (xy 37.998153 -36.60013) (xy 33.768596 -36.60013) (xy 33.752985 -36.652017)
			(xy 33.729313 -36.702514) (xy 33.69854 -36.749027) (xy 33.661323 -36.790564) (xy 33.618455 -36.826239)
			(xy 33.570849 -36.855293) (xy 33.51952 -36.877105) (xy 33.465563 -36.891211) (xy 33.410126 -36.897311)
			(xy 33.354392 -36.895274) (xy 33.299549 -36.885144) (xy 33.246765 -36.867137) (xy 33.197165 -36.841636)
			(xy 33.151807 -36.809185) (xy 33.111658 -36.770476) (xy 33.077572 -36.726333) (xy 33.050276 -36.677698)
			(xy 33.030353 -36.625607) (xy 33.018227 -36.57117) (xy 33.014156 -36.515548) (xy 31.887954 -36.515548)
			(xy 31.884726 -36.520427) (xy 31.847509 -36.561964) (xy 31.804641 -36.597639) (xy 31.757035 -36.626693)
			(xy 31.705706 -36.648505) (xy 31.651749 -36.662611) (xy 31.596312 -36.668711) (xy 31.540578 -36.666674)
			(xy 31.485735 -36.656544) (xy 31.432951 -36.638537) (xy 31.383351 -36.613036) (xy 31.337993 -36.580585)
			(xy 31.297844 -36.541876) (xy 31.263758 -36.497733) (xy 31.236462 -36.449098) (xy 31.216539 -36.397007)
			(xy 31.204413 -36.34257) (xy 31.200342 -36.286948) (xy 30.734035 -36.286948) (xy 31.628334 -37.415216)
			(xy 31.635551 -37.422549) (xy 31.654176 -37.431245) (xy 31.674719 -37.43196) (xy 31.684468 -37.428678)
			(xy 31.687262 -37.427408) (xy 31.712314 -37.416421) (xy 31.764777 -37.400927) (xy 31.818915 -37.393083)
			(xy 31.846266 -37.39261) (xy 31.846774 -37.39261) (xy 31.874028 -37.393072) (xy 31.92798 -37.400826)
			(xy 31.98028 -37.41618) (xy 32.029863 -37.438821) (xy 32.075718 -37.468288) (xy 32.116912 -37.503982)
			(xy 32.152607 -37.545176) (xy 32.182075 -37.59103) (xy 32.204718 -37.640612) (xy 32.220073 -37.692912)
			(xy 32.227828 -37.746864) (xy 32.228282 -37.774118) (xy 32.227875 -37.799339) (xy 32.22123 -37.849342)
			(xy 32.208058 -37.898034) (xy 32.188588 -37.944568) (xy 32.163161 -37.988132) (xy 32.148018 -38.008306)
			(xy 32.147764 -38.00856) (xy 32.142751 -38.015512) (xy 32.13728 -38.031743) (xy 32.137096 -38.04031)
			(xy 32.137096 -38.048184) (xy 32.142684 -38.063932) (xy 34.682664 -41.268751) (xy 41.84395 -41.268751)
			(xy 41.84395 -41.214249) (xy 41.851706 -41.1603) (xy 41.86706 -41.108005) (xy 41.8897 -41.058427)
			(xy 41.919165 -41.012575) (xy 41.954854 -40.971383) (xy 41.996043 -40.935689) (xy 42.041892 -40.906219)
			(xy 42.091467 -40.883574) (xy 42.143761 -40.868214) (xy 42.197709 -40.860453) (xy 42.22496 -40.859964)
			(xy 42.2537 -40.860461) (xy 42.310528 -40.869091) (xy 42.365419 -40.886148) (xy 42.41713 -40.911246)
			(xy 42.464492 -40.943815) (xy 42.485818 -40.963088) (xy 42.492676 -40.969692) (xy 42.51071 -40.976804)
			(xy 42.59961 -40.976804) (xy 42.617644 -40.969692) (xy 42.624502 -40.963088) (xy 42.645853 -40.943845)
			(xy 42.693207 -40.911273) (xy 42.744913 -40.886174) (xy 42.799799 -40.869117) (xy 42.856622 -40.860488)
			(xy 42.88536 -40.859964) (xy 42.912613 -40.860481) (xy 42.966564 -40.868232) (xy 43.018863 -40.883584)
			(xy 43.068444 -40.906222) (xy 43.114299 -40.935687) (xy 43.155494 -40.971378) (xy 43.191189 -41.012569)
			(xy 43.220658 -41.05842) (xy 43.243302 -41.108) (xy 43.258659 -41.160297) (xy 43.266417 -41.214247)
			(xy 43.266417 -41.268753) (xy 43.258659 -41.322703) (xy 43.243302 -41.375) (xy 43.220658 -41.42458)
			(xy 43.191189 -41.470431) (xy 43.155494 -41.511622) (xy 43.114299 -41.547313) (xy 43.068444 -41.576778)
			(xy 43.018863 -41.599416) (xy 42.966564 -41.614768) (xy 42.912613 -41.622519) (xy 42.88536 -41.62298)
			(xy 42.856621 -41.622459) (xy 42.799795 -41.613833) (xy 42.744905 -41.596781) (xy 42.693193 -41.571689)
			(xy 42.64583 -41.539126) (xy 42.624502 -41.519856) (xy 42.617644 -41.513252) (xy 42.59961 -41.50614)
			(xy 42.51071 -41.50614) (xy 42.492676 -41.513252) (xy 42.485818 -41.519856) (xy 42.464506 -41.539145)
			(xy 42.41714 -41.571709) (xy 42.365425 -41.596798) (xy 42.310531 -41.613844) (xy 42.2537 -41.622462)
			(xy 42.22496 -41.62298) (xy 42.197709 -41.622547) (xy 42.143761 -41.614786) (xy 42.091467 -41.599426)
			(xy 42.041892 -41.576781) (xy 41.996043 -41.547311) (xy 41.954854 -41.511617) (xy 41.919165 -41.470425)
			(xy 41.8897 -41.424573) (xy 41.86706 -41.374995) (xy 41.851706 -41.3227) (xy 41.84395 -41.268751)
			(xy 34.682664 -41.268751) (xy 36.296669 -43.305222) (xy 44.307252 -43.305222) (xy 44.307718 -43.277852)
			(xy 44.315534 -43.223672) (xy 44.331022 -43.171168) (xy 44.353864 -43.121422) (xy 44.38359 -43.075455)
			(xy 44.401232 -43.054524) (xy 44.401486 -43.05427) (xy 44.407048 -43.047166) (xy 44.41331 -43.030263)
			(xy 44.413678 -43.02125) (xy 44.413678 -42.954194) (xy 44.413329 -42.945176) (xy 44.407076 -42.928259)
			(xy 44.401486 -42.921174) (xy 44.401232 -42.921174) (xy 44.401232 -42.92092) (xy 44.383594 -42.899987)
			(xy 44.353881 -42.854015) (xy 44.331044 -42.804268) (xy 44.315553 -42.751767) (xy 44.307725 -42.697591)
			(xy 44.307252 -42.670222) (xy 44.307802 -42.641484) (xy 44.31642 -42.584659) (xy 44.333465 -42.529769)
			(xy 44.35855 -42.478057) (xy 44.391109 -42.430692) (xy 44.410376 -42.409364) (xy 44.41698 -42.402506)
			(xy 44.424092 -42.384472) (xy 44.424092 -42.295572) (xy 44.41698 -42.277538) (xy 44.410376 -42.27068)
			(xy 44.391129 -42.249333) (xy 44.358567 -42.201973) (xy 44.333478 -42.150264) (xy 44.316428 -42.095377)
			(xy 44.307805 -42.038553) (xy 44.307802 -41.981079) (xy 44.316421 -41.924255) (xy 44.333466 -41.869366)
			(xy 44.358551 -41.817655) (xy 44.391109 -41.770292) (xy 44.410376 -41.748964) (xy 44.41698 -41.742106)
			(xy 44.424092 -41.724072) (xy 44.424092 -41.635172) (xy 44.41698 -41.617138) (xy 44.410376 -41.61028)
			(xy 44.391122 -41.588938) (xy 44.358552 -41.541581) (xy 44.333456 -41.489873) (xy 44.316401 -41.434985)
			(xy 44.307775 -41.37816) (xy 44.307252 -41.349422) (xy 44.307738 -41.322171) (xy 44.315494 -41.268223)
			(xy 44.330849 -41.215928) (xy 44.353491 -41.166351) (xy 44.382957 -41.120501) (xy 44.418648 -41.07931)
			(xy 44.459839 -41.043619) (xy 44.505689 -41.014153) (xy 44.555266 -40.991511) (xy 44.607561 -40.976156)
			(xy 44.661509 -40.9684) (xy 44.716011 -40.9684) (xy 44.769959 -40.976156) (xy 44.822254 -40.991511)
			(xy 44.871831 -41.014153) (xy 44.917681 -41.043619) (xy 44.958872 -41.07931) (xy 44.994563 -41.120501)
			(xy 45.024029 -41.166351) (xy 45.046671 -41.215928) (xy 45.062026 -41.268223) (xy 45.069782 -41.322171)
			(xy 45.070268 -41.349422) (xy 45.069739 -41.37816) (xy 45.061115 -41.434987) (xy 45.044065 -41.489877)
			(xy 45.018975 -41.541589) (xy 44.986413 -41.588952) (xy 44.967144 -41.61028) (xy 44.96054 -41.617138)
			(xy 44.953428 -41.635172) (xy 44.953428 -41.724072) (xy 44.96054 -41.742106) (xy 44.967144 -41.748964)
			(xy 44.986438 -41.770271) (xy 45.019005 -41.817636) (xy 45.044098 -41.869351) (xy 45.061148 -41.924245)
			(xy 45.069769 -41.981076) (xy 45.069767 -42.038556) (xy 45.06114 -42.095386) (xy 45.044086 -42.150279)
			(xy 45.018989 -42.201992) (xy 44.986418 -42.249354) (xy 44.967144 -42.27068) (xy 44.96054 -42.277538)
			(xy 44.953428 -42.295572) (xy 44.953428 -42.384472) (xy 44.96054 -42.402506) (xy 44.967144 -42.409364)
			(xy 44.986422 -42.430685) (xy 45.018988 -42.478048) (xy 45.044079 -42.529761) (xy 45.061128 -42.584654)
			(xy 45.069749 -42.641482) (xy 45.070268 -42.670222) (xy 45.069823 -42.697593) (xy 45.062001 -42.751773)
			(xy 45.046508 -42.804277) (xy 45.025951 -42.849038) (xy 46.891954 -42.849038) (xy 46.896025 -42.793416)
			(xy 46.908151 -42.738979) (xy 46.928074 -42.686888) (xy 46.95537 -42.638253) (xy 46.989456 -42.59411)
			(xy 47.029605 -42.555401) (xy 47.074963 -42.52295) (xy 47.124563 -42.497449) (xy 47.177347 -42.479442)
			(xy 47.23219 -42.469312) (xy 47.287924 -42.467275) (xy 47.343361 -42.473375) (xy 47.397318 -42.487481)
			(xy 47.448647 -42.509293) (xy 47.496253 -42.538347) (xy 47.539121 -42.574022) (xy 47.576338 -42.615559)
			(xy 47.607111 -42.662072) (xy 47.630783 -42.712569) (xy 47.646851 -42.765976) (xy 47.654971 -42.821152)
			(xy 47.65548 -42.849038) (xy 47.654971 -42.876924) (xy 47.646851 -42.9321) (xy 47.630783 -42.985507)
			(xy 47.607111 -43.036004) (xy 47.576338 -43.082517) (xy 47.539121 -43.124054) (xy 47.496253 -43.159729)
			(xy 47.448647 -43.188783) (xy 47.397318 -43.210595) (xy 47.343361 -43.224701) (xy 47.287924 -43.230801)
			(xy 47.23219 -43.228764) (xy 47.177347 -43.218634) (xy 47.124563 -43.200627) (xy 47.074963 -43.175126)
			(xy 47.029605 -43.142675) (xy 46.989456 -43.103966) (xy 46.95537 -43.059823) (xy 46.928074 -43.011188)
			(xy 46.908151 -42.959097) (xy 46.896025 -42.90466) (xy 46.891954 -42.849038) (xy 45.025951 -42.849038)
			(xy 45.023661 -42.854024) (xy 44.993932 -42.899989) (xy 44.976288 -42.92092) (xy 44.976034 -42.921174)
			(xy 44.970444 -42.928258) (xy 44.964201 -42.945177) (xy 44.963842 -42.954194) (xy 44.963842 -43.02125)
			(xy 44.964214 -43.030266) (xy 44.97045 -43.047183) (xy 44.976034 -43.05427) (xy 44.976288 -43.05427)
			(xy 44.976288 -43.054524) (xy 44.993903 -43.075475) (xy 45.023619 -43.121443) (xy 45.04646 -43.171185)
			(xy 45.061956 -43.223682) (xy 45.069791 -43.277854) (xy 45.070268 -43.305222) (xy 45.069782 -43.332473)
			(xy 45.062026 -43.386421) (xy 45.046671 -43.438716) (xy 45.024029 -43.488293) (xy 44.994563 -43.534143)
			(xy 44.958872 -43.575334) (xy 44.917681 -43.611025) (xy 44.871831 -43.640491) (xy 44.822254 -43.663133)
			(xy 44.769959 -43.678488) (xy 44.716011 -43.686244) (xy 44.661509 -43.686244) (xy 44.607561 -43.678488)
			(xy 44.555266 -43.663133) (xy 44.505689 -43.640491) (xy 44.459839 -43.611025) (xy 44.418648 -43.575334)
			(xy 44.382957 -43.534143) (xy 44.353491 -43.488293) (xy 44.330849 -43.438716) (xy 44.315494 -43.386421)
			(xy 44.307738 -43.332473) (xy 44.307252 -43.305222) (xy 36.296669 -43.305222) (xy 36.638288 -43.73626)
			(xy 46.213012 -43.73626) (xy 46.217083 -43.680638) (xy 46.229209 -43.626201) (xy 46.249132 -43.57411)
			(xy 46.276428 -43.525475) (xy 46.310514 -43.481332) (xy 46.350663 -43.442623) (xy 46.396021 -43.410172)
			(xy 46.445621 -43.384671) (xy 46.498405 -43.366664) (xy 46.553248 -43.356534) (xy 46.608982 -43.354497)
			(xy 46.664419 -43.360597) (xy 46.718376 -43.374703) (xy 46.769705 -43.396515) (xy 46.817311 -43.425569)
			(xy 46.860179 -43.461244) (xy 46.897396 -43.502781) (xy 46.928169 -43.549294) (xy 46.951841 -43.599791)
			(xy 46.967909 -43.653198) (xy 46.976029 -43.708374) (xy 46.976538 -43.73626) (xy 46.976029 -43.764146)
			(xy 46.967909 -43.819322) (xy 46.9566 -43.85691) (xy 50.719734 -43.85691) (xy 50.723805 -43.801288)
			(xy 50.735931 -43.746851) (xy 50.755854 -43.69476) (xy 50.78315 -43.646125) (xy 50.817236 -43.601982)
			(xy 50.857385 -43.563273) (xy 50.902743 -43.530822) (xy 50.952343 -43.505321) (xy 51.005127 -43.487314)
			(xy 51.05997 -43.477184) (xy 51.115704 -43.475147) (xy 51.171141 -43.481247) (xy 51.225098 -43.495353)
			(xy 51.276427 -43.517165) (xy 51.324033 -43.546219) (xy 51.366901 -43.581894) (xy 51.404118 -43.623431)
			(xy 51.434891 -43.669944) (xy 51.458563 -43.720441) (xy 51.474631 -43.773848) (xy 51.482751 -43.829024)
			(xy 51.48326 -43.85691) (xy 51.482751 -43.884796) (xy 51.474631 -43.939972) (xy 51.458563 -43.993379)
			(xy 51.434891 -44.043876) (xy 51.404118 -44.090389) (xy 51.366901 -44.131926) (xy 51.324033 -44.167601)
			(xy 51.276427 -44.196655) (xy 51.225098 -44.218467) (xy 51.171141 -44.232573) (xy 51.115704 -44.238673)
			(xy 51.05997 -44.236636) (xy 51.005127 -44.226506) (xy 50.952343 -44.208499) (xy 50.902743 -44.182998)
			(xy 50.857385 -44.150547) (xy 50.817236 -44.111838) (xy 50.78315 -44.067695) (xy 50.755854 -44.01906)
			(xy 50.735931 -43.966969) (xy 50.723805 -43.912532) (xy 50.719734 -43.85691) (xy 46.9566 -43.85691)
			(xy 46.951841 -43.872729) (xy 46.928169 -43.923226) (xy 46.897396 -43.969739) (xy 46.860179 -44.011276)
			(xy 46.817311 -44.046951) (xy 46.769705 -44.076005) (xy 46.718376 -44.097817) (xy 46.664419 -44.111923)
			(xy 46.608982 -44.118023) (xy 46.553248 -44.115986) (xy 46.498405 -44.105856) (xy 46.445621 -44.087849)
			(xy 46.396021 -44.062348) (xy 46.350663 -44.029897) (xy 46.310514 -43.991188) (xy 46.276428 -43.947045)
			(xy 46.249132 -43.89841) (xy 46.229209 -43.846319) (xy 46.217083 -43.791882) (xy 46.213012 -43.73626)
			(xy 36.638288 -43.73626) (xy 36.70935 -43.825922) (xy 36.735718 -43.859889) (xy 36.783156 -43.931618)
			(xy 36.804092 -43.969178) (xy 37.426898 -45.114464) (xy 46.065438 -45.114464) (xy 46.069509 -45.058842)
			(xy 46.081635 -45.004405) (xy 46.101558 -44.952314) (xy 46.128854 -44.903679) (xy 46.16294 -44.859536)
			(xy 46.203089 -44.820827) (xy 46.248447 -44.788376) (xy 46.298047 -44.762875) (xy 46.350831 -44.744868)
			(xy 46.405674 -44.734738) (xy 46.461408 -44.732701) (xy 46.516845 -44.738801) (xy 46.570802 -44.752907)
			(xy 46.622131 -44.774719) (xy 46.669737 -44.803773) (xy 46.712605 -44.839448) (xy 46.742587 -44.87291)
			(xy 52.93309 -44.87291) (xy 52.937161 -44.817288) (xy 52.949287 -44.762851) (xy 52.96921 -44.71076)
			(xy 52.996506 -44.662125) (xy 53.030592 -44.617982) (xy 53.070741 -44.579273) (xy 53.116099 -44.546822)
			(xy 53.165699 -44.521321) (xy 53.218483 -44.503314) (xy 53.273326 -44.493184) (xy 53.32906 -44.491147)
			(xy 53.384497 -44.497247) (xy 53.438454 -44.511353) (xy 53.489783 -44.533165) (xy 53.537389 -44.562219)
			(xy 53.580257 -44.597894) (xy 53.617474 -44.639431) (xy 53.648247 -44.685944) (xy 53.671919 -44.736441)
			(xy 53.687987 -44.789848) (xy 53.696107 -44.845024) (xy 53.696616 -44.87291) (xy 53.696107 -44.900796)
			(xy 53.687987 -44.955972) (xy 53.671919 -45.009379) (xy 53.648247 -45.059876) (xy 53.617474 -45.106389)
			(xy 53.580257 -45.147926) (xy 53.537389 -45.183601) (xy 53.489783 -45.212655) (xy 53.438454 -45.234467)
			(xy 53.384497 -45.248573) (xy 53.32906 -45.254673) (xy 53.273326 -45.252636) (xy 53.218483 -45.242506)
			(xy 53.165699 -45.224499) (xy 53.116099 -45.198998) (xy 53.070741 -45.166547) (xy 53.030592 -45.127838)
			(xy 52.996506 -45.083695) (xy 52.96921 -45.03506) (xy 52.949287 -44.982969) (xy 52.937161 -44.928532)
			(xy 52.93309 -44.87291) (xy 46.742587 -44.87291) (xy 46.749822 -44.880985) (xy 46.780595 -44.927498)
			(xy 46.804267 -44.977995) (xy 46.820335 -45.031402) (xy 46.828455 -45.086578) (xy 46.828964 -45.114464)
			(xy 46.828455 -45.14235) (xy 46.820335 -45.197526) (xy 46.804267 -45.250933) (xy 46.780595 -45.30143)
			(xy 46.749822 -45.347943) (xy 46.74418 -45.35424) (xy 50.703732 -45.35424) (xy 50.707803 -45.298618)
			(xy 50.719929 -45.244181) (xy 50.739852 -45.19209) (xy 50.767148 -45.143455) (xy 50.801234 -45.099312)
			(xy 50.841383 -45.060603) (xy 50.886741 -45.028152) (xy 50.936341 -45.002651) (xy 50.989125 -44.984644)
			(xy 51.043968 -44.974514) (xy 51.099702 -44.972477) (xy 51.155139 -44.978577) (xy 51.209096 -44.992683)
			(xy 51.260425 -45.014495) (xy 51.308031 -45.043549) (xy 51.350899 -45.079224) (xy 51.388116 -45.120761)
			(xy 51.418889 -45.167274) (xy 51.442561 -45.217771) (xy 51.458629 -45.271178) (xy 51.466749 -45.326354)
			(xy 51.467258 -45.35424) (xy 51.466749 -45.382126) (xy 51.458629 -45.437302) (xy 51.442561 -45.490709)
			(xy 51.418889 -45.541206) (xy 51.388116 -45.587719) (xy 51.350899 -45.629256) (xy 51.308031 -45.664931)
			(xy 51.260425 -45.693985) (xy 51.209096 -45.715797) (xy 51.155139 -45.729903) (xy 51.099702 -45.736003)
			(xy 51.043968 -45.733966) (xy 50.989125 -45.723836) (xy 50.936341 -45.705829) (xy 50.886741 -45.680328)
			(xy 50.841383 -45.647877) (xy 50.801234 -45.609168) (xy 50.767148 -45.565025) (xy 50.739852 -45.51639)
			(xy 50.719929 -45.464299) (xy 50.707803 -45.409862) (xy 50.703732 -45.35424) (xy 46.74418 -45.35424)
			(xy 46.712605 -45.38948) (xy 46.669737 -45.425155) (xy 46.622131 -45.454209) (xy 46.570802 -45.476021)
			(xy 46.516845 -45.490127) (xy 46.461408 -45.496227) (xy 46.405674 -45.49419) (xy 46.350831 -45.48406)
			(xy 46.298047 -45.466053) (xy 46.248447 -45.440552) (xy 46.203089 -45.408101) (xy 46.16294 -45.369392)
			(xy 46.128854 -45.325249) (xy 46.101558 -45.276614) (xy 46.081635 -45.224523) (xy 46.069509 -45.170086)
			(xy 46.065438 -45.114464) (xy 37.426898 -45.114464) (xy 37.729668 -45.671232) (xy 37.73297 -45.676058)
			(xy 38.105581 -46.082204) (xy 44.05249 -46.082204) (xy 44.052959 -46.054951) (xy 44.060715 -46.001001)
			(xy 44.076071 -45.948703) (xy 44.098713 -45.899123) (xy 44.12818 -45.85327) (xy 44.163873 -45.812077)
			(xy 44.205065 -45.776384) (xy 44.250918 -45.746916) (xy 44.300497 -45.724273) (xy 44.352795 -45.708917)
			(xy 44.406745 -45.701159) (xy 44.433998 -45.700696) (xy 44.460901 -45.70116) (xy 44.51417 -45.708731)
			(xy 44.565849 -45.72371) (xy 44.61491 -45.7458) (xy 44.660383 -45.774562) (xy 44.701364 -45.809427)
			(xy 44.737042 -45.849702) (xy 44.75226 -45.871892) (xy 44.759372 -45.882814) (xy 44.782232 -45.894752)
			(xy 44.8945 -45.89272) (xy 44.916852 -45.879766) (xy 44.92371 -45.86859) (xy 44.938638 -45.844993)
			(xy 44.974316 -45.802041) (xy 45.015873 -45.764748) (xy 45.062422 -45.73391) (xy 45.112969 -45.710186)
			(xy 45.166433 -45.694082) (xy 45.221674 -45.685943) (xy 45.249592 -45.685456) (xy 45.276585 -45.685922)
			(xy 45.330033 -45.693527) (xy 45.381876 -45.708586) (xy 45.431081 -45.730799) (xy 45.476665 -45.759722)
			(xy 45.497496 -45.776896) (xy 45.505624 -45.784008) (xy 45.526198 -45.790104) (xy 45.611542 -45.779182)
			(xy 45.622082 -45.777389) (xy 45.640367 -45.766348) (xy 45.646848 -45.757846) (xy 45.662178 -45.736598)
			(xy 45.697769 -45.698145) (xy 45.73829 -45.664928) (xy 45.782977 -45.637572) (xy 45.830989 -45.616591)
			(xy 45.881421 -45.602382) (xy 45.933324 -45.595211) (xy 45.959522 -45.594778) (xy 45.986771 -45.595294)
			(xy 46.040714 -45.603053) (xy 46.093005 -45.618409) (xy 46.142577 -45.64105) (xy 46.188423 -45.670516)
			(xy 46.229609 -45.706206) (xy 46.265297 -45.747395) (xy 46.29476 -45.793242) (xy 46.317399 -45.842816)
			(xy 46.332752 -45.895107) (xy 46.340508 -45.949051) (xy 46.340508 -46.003549) (xy 46.332752 -46.057493)
			(xy 46.317399 -46.109784) (xy 46.29476 -46.159358) (xy 46.265297 -46.205205) (xy 46.229609 -46.246394)
			(xy 46.188423 -46.282084) (xy 46.142577 -46.31155) (xy 46.093005 -46.334191) (xy 46.040714 -46.349547)
			(xy 45.986771 -46.357306) (xy 45.959522 -46.357794) (xy 45.93253 -46.357308) (xy 45.879083 -46.349706)
			(xy 45.82724 -46.334651) (xy 45.778035 -46.312443) (xy 45.73245 -46.283525) (xy 45.711618 -46.266354)
			(xy 45.70349 -46.259242) (xy 45.682916 -46.253146) (xy 45.597572 -46.264068) (xy 45.587026 -46.265836)
			(xy 45.568745 -46.276896) (xy 45.562266 -46.285404) (xy 45.544654 -46.309705) (xy 45.503058 -46.352964)
			(xy 45.479462 -46.37151) (xy 45.471588 -46.377352) (xy 45.461174 -46.394878) (xy 45.447966 -46.485302)
			(xy 45.452792 -46.504606) (xy 45.458634 -46.51248) (xy 45.458634 -46.512734) (xy 45.476132 -46.537482)
			(xy 45.503937 -46.591333) (xy 45.522875 -46.648904) (xy 45.530078 -46.693836) (xy 50.676302 -46.693836)
			(xy 50.676788 -46.666585) (xy 50.684544 -46.612637) (xy 50.699899 -46.560342) (xy 50.722541 -46.510765)
			(xy 50.752007 -46.464915) (xy 50.787698 -46.423724) (xy 50.828889 -46.388033) (xy 50.874739 -46.358567)
			(xy 50.924316 -46.335925) (xy 50.976611 -46.32057) (xy 51.030559 -46.312814) (xy 51.085061 -46.312814)
			(xy 51.139009 -46.32057) (xy 51.191304 -46.335925) (xy 51.240881 -46.358567) (xy 51.286731 -46.388033)
			(xy 51.327922 -46.423724) (xy 51.363613 -46.464915) (xy 51.393079 -46.510765) (xy 51.415721 -46.560342)
			(xy 51.431076 -46.612637) (xy 51.438832 -46.666585) (xy 51.439318 -46.693836) (xy 51.438843 -46.720263)
			(xy 51.431534 -46.772611) (xy 51.417061 -46.823446) (xy 51.395702 -46.871793) (xy 51.382168 -46.894496)
			(xy 51.381914 -46.89475) (xy 51.376577 -46.904768) (xy 51.374321 -46.927318) (xy 51.377596 -46.938184)
			(xy 51.403758 -47.01286) (xy 51.408139 -47.023377) (xy 51.42423 -47.039465) (xy 51.434746 -47.043848)
			(xy 51.435 -47.043848) (xy 51.459499 -47.052944) (xy 51.505952 -47.076881) (xy 51.548706 -47.106932)
			(xy 51.586959 -47.142535) (xy 51.619998 -47.183025) (xy 51.647203 -47.227643) (xy 51.668066 -47.275556)
			(xy 51.682197 -47.325868) (xy 51.689331 -47.377637) (xy 51.689762 -47.403766) (xy 51.689276 -47.431017)
			(xy 51.687753 -47.441612) (xy 52.961792 -47.441612) (xy 52.965863 -47.38599) (xy 52.977989 -47.331553)
			(xy 52.997912 -47.279462) (xy 53.025208 -47.230827) (xy 53.059294 -47.186684) (xy 53.099443 -47.147975)
			(xy 53.144801 -47.115524) (xy 53.194401 -47.090023) (xy 53.247185 -47.072016) (xy 53.302028 -47.061886)
			(xy 53.357762 -47.059849) (xy 53.413199 -47.065949) (xy 53.467156 -47.080055) (xy 53.518485 -47.101867)
			(xy 53.566091 -47.130921) (xy 53.608959 -47.166596) (xy 53.646176 -47.208133) (xy 53.676949 -47.254646)
			(xy 53.700621 -47.305143) (xy 53.716689 -47.35855) (xy 53.724809 -47.413726) (xy 53.725318 -47.441612)
			(xy 53.724809 -47.469498) (xy 53.716689 -47.524674) (xy 53.700621 -47.578081) (xy 53.676949 -47.628578)
			(xy 53.646176 -47.675091) (xy 53.608959 -47.716628) (xy 53.566091 -47.752303) (xy 53.518485 -47.781357)
			(xy 53.467156 -47.803169) (xy 53.413199 -47.817275) (xy 53.357762 -47.823375) (xy 53.302028 -47.821338)
			(xy 53.247185 -47.811208) (xy 53.194401 -47.793201) (xy 53.144801 -47.7677) (xy 53.099443 -47.735249)
			(xy 53.059294 -47.69654) (xy 53.025208 -47.652397) (xy 52.997912 -47.603762) (xy 52.977989 -47.551671)
			(xy 52.965863 -47.497234) (xy 52.961792 -47.441612) (xy 51.687753 -47.441612) (xy 51.68152 -47.484965)
			(xy 51.666165 -47.53726) (xy 51.643523 -47.586837) (xy 51.614057 -47.632687) (xy 51.578366 -47.673878)
			(xy 51.537175 -47.709569) (xy 51.491325 -47.739035) (xy 51.441748 -47.761677) (xy 51.389453 -47.777032)
			(xy 51.335505 -47.784788) (xy 51.281003 -47.784788) (xy 51.227055 -47.777032) (xy 51.17476 -47.761677)
			(xy 51.125183 -47.739035) (xy 51.079333 -47.709569) (xy 51.038142 -47.673878) (xy 51.002451 -47.632687)
			(xy 50.972985 -47.586837) (xy 50.950343 -47.53726) (xy 50.934988 -47.484965) (xy 50.927232 -47.431017)
			(xy 50.926746 -47.403766) (xy 50.927213 -47.377338) (xy 50.934523 -47.32499) (xy 50.948998 -47.274155)
			(xy 50.97036 -47.225809) (xy 50.983896 -47.203106) (xy 50.98415 -47.202852) (xy 50.989485 -47.192834)
			(xy 50.991744 -47.170284) (xy 50.988468 -47.159418) (xy 50.962306 -47.084742) (xy 50.95794 -47.074217)
			(xy 50.941839 -47.058132) (xy 50.931318 -47.053754) (xy 50.931064 -47.053754) (xy 50.906558 -47.044677)
			(xy 50.860105 -47.020736) (xy 50.817353 -46.990681) (xy 50.779101 -46.955075) (xy 50.746064 -46.914583)
			(xy 50.71886 -46.869963) (xy 50.697998 -46.822048) (xy 50.683867 -46.771736) (xy 50.676733 -46.719966)
			(xy 50.676302 -46.693836) (xy 45.530078 -46.693836) (xy 45.532468 -46.708745) (xy 45.533056 -46.739048)
			(xy 45.532567 -46.766298) (xy 45.524805 -46.820243) (xy 45.509446 -46.872535) (xy 45.486803 -46.922109)
			(xy 45.457336 -46.967957) (xy 45.421646 -47.009146) (xy 45.380457 -47.044836) (xy 45.334609 -47.074303)
			(xy 45.285035 -47.096946) (xy 45.232743 -47.112305) (xy 45.178798 -47.120067) (xy 45.151548 -47.120556)
			(xy 45.125514 -47.120131) (xy 45.07393 -47.113038) (xy 45.023788 -47.099003) (xy 44.976018 -47.078287)
			(xy 44.931504 -47.051274) (xy 44.91101 -47.035212) (xy 44.903257 -47.029464) (xy 44.884843 -47.023727)
			(xy 44.875196 -47.024036) (xy 44.79544 -47.030386) (xy 44.77766 -47.039022) (xy 44.77131 -47.046388)
			(xy 44.753147 -47.066051) (xy 44.712235 -47.100572) (xy 44.666903 -47.129039) (xy 44.618038 -47.150893)
			(xy 44.566599 -47.165707) (xy 44.513595 -47.173189) (xy 44.48683 -47.173642) (xy 44.459581 -47.173094)
			(xy 44.405637 -47.165342) (xy 44.353346 -47.149993) (xy 44.303771 -47.127358) (xy 44.257922 -47.097898)
			(xy 44.216733 -47.062213) (xy 44.181041 -47.021029) (xy 44.151573 -46.975185) (xy 44.12893 -46.925614)
			(xy 44.113571 -46.873325) (xy 44.105811 -46.819383) (xy 44.105322 -46.792134) (xy 44.105841 -46.76336)
			(xy 44.114492 -46.706465) (xy 44.13159 -46.651514) (xy 44.156745 -46.599754) (xy 44.189387 -46.552358)
			(xy 44.2087 -46.531022) (xy 44.216066 -46.523148) (xy 44.223178 -46.503336) (xy 44.215812 -46.40707)
			(xy 44.205906 -46.388274) (xy 44.197524 -46.38167) (xy 44.17534 -46.363444) (xy 44.13613 -46.321509)
			(xy 44.103644 -46.274174) (xy 44.078615 -46.222506) (xy 44.061609 -46.167672) (xy 44.053008 -46.110909)
			(xy 44.05249 -46.082204) (xy 38.105581 -46.082204) (xy 38.16477 -46.14672) (xy 38.191721 -46.176731)
			(xy 38.241203 -46.240441) (xy 38.285329 -46.30797) (xy 38.323806 -46.37887) (xy 38.356379 -46.45267)
			(xy 38.370002 -46.490636) (xy 38.714172 -47.481236) (xy 38.71595 -47.485554) (xy 38.814756 -47.667418)
			(xy 38.834828 -47.705317) (xy 38.869164 -47.783913) (xy 38.883336 -47.82439) (xy 39.046493 -48.30699)
			(xy 50.553872 -48.30699) (xy 50.557943 -48.251368) (xy 50.570069 -48.196931) (xy 50.589992 -48.14484)
			(xy 50.617288 -48.096205) (xy 50.651374 -48.052062) (xy 50.691523 -48.013353) (xy 50.736881 -47.980902)
			(xy 50.786481 -47.955401) (xy 50.839265 -47.937394) (xy 50.894108 -47.927264) (xy 50.949842 -47.925227)
			(xy 51.005279 -47.931327) (xy 51.059236 -47.945433) (xy 51.110565 -47.967245) (xy 51.158171 -47.996299)
			(xy 51.201039 -48.031974) (xy 51.238256 -48.073511) (xy 51.269029 -48.120024) (xy 51.292701 -48.170521)
			(xy 51.308769 -48.223928) (xy 51.316889 -48.279104) (xy 51.317398 -48.30699) (xy 51.316889 -48.334876)
			(xy 51.308769 -48.390052) (xy 51.292701 -48.443459) (xy 51.269029 -48.493956) (xy 51.238256 -48.540469)
			(xy 51.201039 -48.582006) (xy 51.158171 -48.617681) (xy 51.110565 -48.646735) (xy 51.059236 -48.668547)
			(xy 51.005279 -48.682653) (xy 50.949842 -48.688753) (xy 50.894108 -48.686716) (xy 50.839265 -48.676586)
			(xy 50.786481 -48.658579) (xy 50.736881 -48.633078) (xy 50.691523 -48.600627) (xy 50.651374 -48.561918)
			(xy 50.617288 -48.517775) (xy 50.589992 -48.46914) (xy 50.570069 -48.417049) (xy 50.557943 -48.362612)
			(xy 50.553872 -48.30699) (xy 39.046493 -48.30699) (xy 39.197284 -48.753014) (xy 47.168306 -48.753014)
			(xy 47.172377 -48.697392) (xy 47.184503 -48.642955) (xy 47.204426 -48.590864) (xy 47.231722 -48.542229)
			(xy 47.265808 -48.498086) (xy 47.305957 -48.459377) (xy 47.351315 -48.426926) (xy 47.400915 -48.401425)
			(xy 47.453699 -48.383418) (xy 47.508542 -48.373288) (xy 47.564276 -48.371251) (xy 47.619713 -48.377351)
			(xy 47.67367 -48.391457) (xy 47.724999 -48.413269) (xy 47.772605 -48.442323) (xy 47.815473 -48.477998)
			(xy 47.85269 -48.519535) (xy 47.883463 -48.566048) (xy 47.907135 -48.616545) (xy 47.923203 -48.669952)
			(xy 47.931323 -48.725128) (xy 47.931832 -48.753014) (xy 47.931323 -48.7809) (xy 47.923203 -48.836076)
			(xy 47.907135 -48.889483) (xy 47.905739 -48.89246) (xy 49.214022 -48.89246) (xy 49.218093 -48.836838)
			(xy 49.230219 -48.782401) (xy 49.250142 -48.73031) (xy 49.277438 -48.681675) (xy 49.311524 -48.637532)
			(xy 49.351673 -48.598823) (xy 49.397031 -48.566372) (xy 49.446631 -48.540871) (xy 49.499415 -48.522864)
			(xy 49.554258 -48.512734) (xy 49.609992 -48.510697) (xy 49.665429 -48.516797) (xy 49.719386 -48.530903)
			(xy 49.770715 -48.552715) (xy 49.818321 -48.581769) (xy 49.861189 -48.617444) (xy 49.898406 -48.658981)
			(xy 49.929179 -48.705494) (xy 49.952851 -48.755991) (xy 49.968919 -48.809398) (xy 49.977039 -48.864574)
			(xy 49.977548 -48.89246) (xy 49.977039 -48.920346) (xy 49.974601 -48.93691) (xy 52.93309 -48.93691)
			(xy 52.937161 -48.881288) (xy 52.949287 -48.826851) (xy 52.96921 -48.77476) (xy 52.996506 -48.726125)
			(xy 53.030592 -48.681982) (xy 53.070741 -48.643273) (xy 53.116099 -48.610822) (xy 53.165699 -48.585321)
			(xy 53.218483 -48.567314) (xy 53.273326 -48.557184) (xy 53.32906 -48.555147) (xy 53.384497 -48.561247)
			(xy 53.438454 -48.575353) (xy 53.489783 -48.597165) (xy 53.537389 -48.626219) (xy 53.580257 -48.661894)
			(xy 53.617474 -48.703431) (xy 53.648247 -48.749944) (xy 53.671919 -48.800441) (xy 53.687987 -48.853848)
			(xy 53.696107 -48.909024) (xy 53.696616 -48.93691) (xy 53.696107 -48.964796) (xy 53.687987 -49.019972)
			(xy 53.671919 -49.073379) (xy 53.648247 -49.123876) (xy 53.617474 -49.170389) (xy 53.580257 -49.211926)
			(xy 53.537389 -49.247601) (xy 53.489783 -49.276655) (xy 53.438454 -49.298467) (xy 53.384497 -49.312573)
			(xy 53.32906 -49.318673) (xy 53.273326 -49.316636) (xy 53.218483 -49.306506) (xy 53.165699 -49.288499)
			(xy 53.116099 -49.262998) (xy 53.070741 -49.230547) (xy 53.030592 -49.191838) (xy 52.996506 -49.147695)
			(xy 52.96921 -49.09906) (xy 52.949287 -49.046969) (xy 52.937161 -48.992532) (xy 52.93309 -48.93691)
			(xy 49.974601 -48.93691) (xy 49.968919 -48.975522) (xy 49.952851 -49.028929) (xy 49.929179 -49.079426)
			(xy 49.898406 -49.125939) (xy 49.861189 -49.167476) (xy 49.818321 -49.203151) (xy 49.770715 -49.232205)
			(xy 49.719386 -49.254017) (xy 49.665429 -49.268123) (xy 49.609992 -49.274223) (xy 49.554258 -49.272186)
			(xy 49.499415 -49.262056) (xy 49.446631 -49.244049) (xy 49.397031 -49.218548) (xy 49.351673 -49.186097)
			(xy 49.311524 -49.147388) (xy 49.277438 -49.103245) (xy 49.250142 -49.05461) (xy 49.230219 -49.002519)
			(xy 49.218093 -48.948082) (xy 49.214022 -48.89246) (xy 47.905739 -48.89246) (xy 47.883463 -48.93998)
			(xy 47.85269 -48.986493) (xy 47.815473 -49.02803) (xy 47.772605 -49.063705) (xy 47.724999 -49.092759)
			(xy 47.67367 -49.114571) (xy 47.619713 -49.128677) (xy 47.564276 -49.134777) (xy 47.508542 -49.13274)
			(xy 47.453699 -49.12261) (xy 47.400915 -49.104603) (xy 47.351315 -49.079102) (xy 47.305957 -49.046651)
			(xy 47.265808 -49.007942) (xy 47.231722 -48.963799) (xy 47.204426 -48.915164) (xy 47.184503 -48.863073)
			(xy 47.172377 -48.808636) (xy 47.168306 -48.753014) (xy 39.197284 -48.753014) (xy 39.602942 -49.95291)
			(xy 52.93309 -49.95291) (xy 52.937161 -49.897288) (xy 52.949287 -49.842851) (xy 52.96921 -49.79076)
			(xy 52.996506 -49.742125) (xy 53.030592 -49.697982) (xy 53.070741 -49.659273) (xy 53.116099 -49.626822)
			(xy 53.165699 -49.601321) (xy 53.218483 -49.583314) (xy 53.273326 -49.573184) (xy 53.32906 -49.571147)
			(xy 53.384497 -49.577247) (xy 53.438454 -49.591353) (xy 53.489783 -49.613165) (xy 53.537389 -49.642219)
			(xy 53.580257 -49.677894) (xy 53.617474 -49.719431) (xy 53.648247 -49.765944) (xy 53.671919 -49.816441)
			(xy 53.687987 -49.869848) (xy 53.696107 -49.925024) (xy 53.696616 -49.95291) (xy 53.696107 -49.980796)
			(xy 53.687987 -50.035972) (xy 53.671919 -50.089379) (xy 53.648247 -50.139876) (xy 53.617474 -50.186389)
			(xy 53.580257 -50.227926) (xy 53.537389 -50.263601) (xy 53.489783 -50.292655) (xy 53.438454 -50.314467)
			(xy 53.384497 -50.328573) (xy 53.32906 -50.334673) (xy 53.273326 -50.332636) (xy 53.218483 -50.322506)
			(xy 53.165699 -50.304499) (xy 53.116099 -50.278998) (xy 53.070741 -50.246547) (xy 53.030592 -50.207838)
			(xy 52.996506 -50.163695) (xy 52.96921 -50.11506) (xy 52.949287 -50.062969) (xy 52.937161 -50.008532)
			(xy 52.93309 -49.95291) (xy 39.602942 -49.95291) (xy 39.631366 -50.036984) (xy 39.645103 -50.079111)
			(xy 39.665931 -50.165242) (xy 39.679039 -50.252881) (xy 39.682166 -50.29708) (xy 39.693088 -50.480214)
			(xy 39.725086 -51.019456) (xy 50.749452 -51.019456) (xy 50.753523 -50.963834) (xy 50.765649 -50.909397)
			(xy 50.785572 -50.857306) (xy 50.812868 -50.808671) (xy 50.846954 -50.764528) (xy 50.887103 -50.725819)
			(xy 50.932461 -50.693368) (xy 50.982061 -50.667867) (xy 51.034845 -50.64986) (xy 51.089688 -50.63973)
			(xy 51.145422 -50.637693) (xy 51.200859 -50.643793) (xy 51.254816 -50.657899) (xy 51.306145 -50.679711)
			(xy 51.353751 -50.708765) (xy 51.396619 -50.74444) (xy 51.433836 -50.785977) (xy 51.464609 -50.83249)
			(xy 51.488281 -50.882987) (xy 51.504349 -50.936394) (xy 51.512469 -50.99157) (xy 51.512978 -51.019456)
			(xy 51.512469 -51.047342) (xy 51.504349 -51.102518) (xy 51.488281 -51.155925) (xy 51.464609 -51.206422)
			(xy 51.433836 -51.252935) (xy 51.396619 -51.294472) (xy 51.353751 -51.330147) (xy 51.306145 -51.359201)
			(xy 51.254816 -51.381013) (xy 51.200859 -51.395119) (xy 51.145422 -51.401219) (xy 51.089688 -51.399182)
			(xy 51.034845 -51.389052) (xy 50.982061 -51.371045) (xy 50.932461 -51.345544) (xy 50.887103 -51.313093)
			(xy 50.846954 -51.274384) (xy 50.812868 -51.230241) (xy 50.785572 -51.181606) (xy 50.765649 -51.129515)
			(xy 50.753523 -51.075078) (xy 50.749452 -51.019456) (xy 39.725086 -51.019456) (xy 39.732712 -51.14798)
			(xy 39.785666 -52.035456) (xy 52.941218 -52.035456) (xy 52.945289 -51.979834) (xy 52.957415 -51.925397)
			(xy 52.977338 -51.873306) (xy 53.004634 -51.824671) (xy 53.03872 -51.780528) (xy 53.078869 -51.741819)
			(xy 53.124227 -51.709368) (xy 53.173827 -51.683867) (xy 53.226611 -51.66586) (xy 53.281454 -51.65573)
			(xy 53.337188 -51.653693) (xy 53.392625 -51.659793) (xy 53.446582 -51.673899) (xy 53.497911 -51.695711)
			(xy 53.545517 -51.724765) (xy 53.588385 -51.76044) (xy 53.625602 -51.801977) (xy 53.656375 -51.84849)
			(xy 53.680047 -51.898987) (xy 53.696115 -51.952394) (xy 53.704235 -52.00757) (xy 53.704744 -52.035456)
			(xy 53.704235 -52.063342) (xy 53.696115 -52.118518) (xy 53.680047 -52.171925) (xy 53.656375 -52.222422)
			(xy 53.625602 -52.268935) (xy 53.588385 -52.310472) (xy 53.545517 -52.346147) (xy 53.497911 -52.375201)
			(xy 53.446582 -52.397013) (xy 53.392625 -52.411119) (xy 53.337188 -52.417219) (xy 53.281454 -52.415182)
			(xy 53.226611 -52.405052) (xy 53.173827 -52.387045) (xy 53.124227 -52.361544) (xy 53.078869 -52.329093)
			(xy 53.03872 -52.290384) (xy 53.004634 -52.246241) (xy 52.977338 -52.197606) (xy 52.957415 -52.145515)
			(xy 52.945289 -52.091078) (xy 52.941218 -52.035456) (xy 39.785666 -52.035456) (xy 39.807642 -52.403756)
			(xy 39.809923 -52.415108) (xy 39.823024 -52.434172) (xy 39.843128 -52.445613) (xy 39.854632 -52.446936)
			(xy 39.86276 -52.446936) (xy 39.8653 -52.446682) (xy 39.90213 -52.444904) (xy 39.929379 -52.445392)
			(xy 39.983323 -52.453152) (xy 40.035614 -52.46851) (xy 40.085186 -52.491153) (xy 40.131032 -52.52062)
			(xy 40.172218 -52.556312) (xy 40.207905 -52.597502) (xy 40.237367 -52.643351) (xy 40.260004 -52.692926)
			(xy 40.275357 -52.745218) (xy 40.283111 -52.799162) (xy 40.283638 -52.826412) (xy 40.283212 -52.851923)
			(xy 40.276416 -52.90249) (xy 40.262946 -52.951702) (xy 40.243042 -52.998681) (xy 40.217059 -53.042591)
			(xy 40.201596 -53.062886) (xy 40.199056 -53.065934) (xy 40.19804 -53.067458) (xy 40.194738 -53.074062)
			(xy 40.192392 -53.079284) (xy 40.189825 -53.090438) (xy 40.189658 -53.09616) (xy 40.189658 -53.128164)
			(xy 40.178482 -53.128164) (xy 40.178482 -53.178964) (xy 40.178816 -53.187568) (xy 40.184526 -53.2038)
			(xy 40.189658 -53.210714) (xy 40.190928 -53.212238) (xy 40.208322 -53.233115) (xy 40.237641 -53.278864)
			(xy 40.260169 -53.328312) (xy 40.275451 -53.380457) (xy 40.283176 -53.434243) (xy 40.283638 -53.461412)
			(xy 40.283212 -53.486923) (xy 40.276416 -53.53749) (xy 40.262946 -53.586702) (xy 40.243042 -53.633681)
			(xy 40.217059 -53.677591) (xy 40.201596 -53.697886) (xy 40.199056 -53.700934) (xy 40.19804 -53.702458)
			(xy 40.194738 -53.709062) (xy 40.192392 -53.714284) (xy 40.189825 -53.725438) (xy 40.189658 -53.73116)
			(xy 40.189658 -53.763164) (xy 40.178482 -53.763164) (xy 40.178482 -53.813964) (xy 40.178816 -53.822568)
			(xy 40.184526 -53.8388) (xy 40.189658 -53.845714) (xy 40.190928 -53.847238) (xy 40.208322 -53.868115)
			(xy 40.237641 -53.913864) (xy 40.260169 -53.963312) (xy 40.275451 -54.015457) (xy 40.283176 -54.069243)
			(xy 40.283638 -54.096412) (xy 40.283212 -54.121923) (xy 40.276416 -54.17249) (xy 40.262946 -54.221702)
			(xy 40.243042 -54.268681) (xy 40.217059 -54.312591) (xy 40.201596 -54.332886) (xy 40.199056 -54.335934)
			(xy 40.19804 -54.337458) (xy 40.194738 -54.344062) (xy 40.192392 -54.349284) (xy 40.189825 -54.360438)
			(xy 40.189658 -54.36616) (xy 40.189658 -54.398164) (xy 40.178482 -54.398164) (xy 40.178482 -54.448964)
			(xy 40.178816 -54.457568) (xy 40.184526 -54.4738) (xy 40.189658 -54.480714) (xy 40.190928 -54.482238)
			(xy 40.208322 -54.503115) (xy 40.237641 -54.548864) (xy 40.260169 -54.598312) (xy 40.275451 -54.650457)
			(xy 40.283176 -54.704243) (xy 40.283638 -54.731412) (xy 40.283173 -54.75877) (xy 40.278512 -54.791102)
			(xy 42.176446 -54.791102) (xy 42.176902 -54.763731) (xy 42.184721 -54.709551) (xy 42.200211 -54.657048)
			(xy 42.223056 -54.607301) (xy 42.252783 -54.561335) (xy 42.270426 -54.540404) (xy 42.27068 -54.54015)
			(xy 42.276261 -54.53306) (xy 42.282509 -54.516146) (xy 42.282872 -54.50713) (xy 42.282872 -54.440074)
			(xy 42.282534 -54.431055) (xy 42.276274 -54.414138) (xy 42.27068 -54.407054) (xy 42.270426 -54.407054)
			(xy 42.270426 -54.4068) (xy 42.252787 -54.385866) (xy 42.223063 -54.339898) (xy 42.200217 -54.290152)
			(xy 42.184721 -54.23765) (xy 42.176892 -54.183472) (xy 42.176892 -54.128731) (xy 42.18472 -54.074553)
			(xy 42.200216 -54.022051) (xy 42.223061 -53.972305) (xy 42.252785 -53.926337) (xy 42.270426 -53.905404)
			(xy 42.27068 -53.90515) (xy 42.276261 -53.89806) (xy 42.282509 -53.881146) (xy 42.282872 -53.87213)
			(xy 42.282872 -53.805074) (xy 42.282534 -53.796055) (xy 42.276274 -53.779138) (xy 42.27068 -53.772054)
			(xy 42.270426 -53.772054) (xy 42.270426 -53.7718) (xy 42.252787 -53.750866) (xy 42.223063 -53.704898)
			(xy 42.200217 -53.655152) (xy 42.184721 -53.60265) (xy 42.176892 -53.548472) (xy 42.176892 -53.493731)
			(xy 42.18472 -53.439553) (xy 42.200216 -53.387051) (xy 42.223061 -53.337305) (xy 42.252785 -53.291337)
			(xy 42.270426 -53.270404) (xy 42.27068 -53.27015) (xy 42.276261 -53.26306) (xy 42.282509 -53.246146)
			(xy 42.282872 -53.23713) (xy 42.282872 -53.170074) (xy 42.282534 -53.161055) (xy 42.276274 -53.144138)
			(xy 42.27068 -53.137054) (xy 42.270426 -53.137054) (xy 42.270426 -53.1368) (xy 42.252777 -53.115875)
			(xy 42.223066 -53.069901) (xy 42.200232 -53.020152) (xy 42.184743 -52.967649) (xy 42.176918 -52.913472)
			(xy 42.176446 -52.886102) (xy 42.176932 -52.858851) (xy 42.184688 -52.804903) (xy 42.200043 -52.752608)
			(xy 42.222685 -52.703031) (xy 42.252151 -52.657181) (xy 42.287842 -52.61599) (xy 42.329033 -52.580299)
			(xy 42.374883 -52.550833) (xy 42.42446 -52.528191) (xy 42.476755 -52.512836) (xy 42.530703 -52.50508)
			(xy 42.585205 -52.50508) (xy 42.639153 -52.512836) (xy 42.691448 -52.528191) (xy 42.730557 -52.546052)
			(xy 47.679573 -52.546052) (xy 47.679573 -52.491548) (xy 47.68733 -52.437599) (xy 47.702686 -52.385303)
			(xy 47.725328 -52.335724) (xy 47.754796 -52.289873) (xy 47.790489 -52.248682) (xy 47.831681 -52.21299)
			(xy 47.877533 -52.183523) (xy 47.927112 -52.160883) (xy 47.979409 -52.145528) (xy 48.033358 -52.137773)
			(xy 48.06061 -52.13731) (xy 48.087981 -52.137768) (xy 48.14216 -52.145587) (xy 48.194663 -52.161078)
			(xy 48.24441 -52.183922) (xy 48.290377 -52.213648) (xy 48.311308 -52.23129) (xy 48.311562 -52.231544)
			(xy 48.318651 -52.237126) (xy 48.335566 -52.243374) (xy 48.344582 -52.243736) (xy 48.411638 -52.243736)
			(xy 48.420656 -52.243389) (xy 48.437572 -52.237134) (xy 48.444658 -52.231544) (xy 48.444658 -52.23129)
			(xy 48.444912 -52.23129) (xy 48.465845 -52.213649) (xy 48.511813 -52.183925) (xy 48.561559 -52.161079)
			(xy 48.614061 -52.145583) (xy 48.668239 -52.137754) (xy 48.722981 -52.137754) (xy 48.777159 -52.145583)
			(xy 48.829661 -52.161079) (xy 48.879407 -52.183925) (xy 48.925375 -52.213649) (xy 48.946308 -52.23129)
			(xy 48.946562 -52.231544) (xy 48.953651 -52.237126) (xy 48.970566 -52.243374) (xy 48.979582 -52.243736)
			(xy 49.046638 -52.243736) (xy 49.055656 -52.243389) (xy 49.072572 -52.237134) (xy 49.079658 -52.231544)
			(xy 49.079658 -52.23129) (xy 49.079912 -52.23129) (xy 49.100865 -52.213677) (xy 49.146832 -52.183962)
			(xy 49.196574 -52.161121) (xy 49.24907 -52.145624) (xy 49.303242 -52.137788) (xy 49.33061 -52.13731)
			(xy 49.357862 -52.137761) (xy 49.411811 -52.145519) (xy 49.464107 -52.160875) (xy 49.513686 -52.183518)
			(xy 49.559537 -52.212986) (xy 49.600728 -52.248679) (xy 49.63642 -52.289871) (xy 49.665887 -52.335723)
			(xy 49.688528 -52.385302) (xy 49.703884 -52.437599) (xy 49.71164 -52.491548) (xy 49.71164 -52.546052)
			(xy 49.705696 -52.587398) (xy 50.755294 -52.587398) (xy 50.759365 -52.531776) (xy 50.771491 -52.477339)
			(xy 50.791414 -52.425248) (xy 50.81871 -52.376613) (xy 50.852796 -52.33247) (xy 50.892945 -52.293761)
			(xy 50.938303 -52.26131) (xy 50.987903 -52.235809) (xy 51.040687 -52.217802) (xy 51.09553 -52.207672)
			(xy 51.151264 -52.205635) (xy 51.206701 -52.211735) (xy 51.260658 -52.225841) (xy 51.311987 -52.247653)
			(xy 51.359593 -52.276707) (xy 51.402461 -52.312382) (xy 51.439678 -52.353919) (xy 51.470451 -52.400432)
			(xy 51.494123 -52.450929) (xy 51.510191 -52.504336) (xy 51.517787 -52.555953) (xy 58.583779 -52.555953)
			(xy 58.583779 -52.501447) (xy 58.591537 -52.447497) (xy 58.606893 -52.3952) (xy 58.629536 -52.345621)
			(xy 58.659005 -52.29977) (xy 58.6947 -52.258579) (xy 58.735894 -52.222887) (xy 58.781748 -52.193422)
			(xy 58.831329 -52.170783) (xy 58.883627 -52.15543) (xy 58.937577 -52.147677) (xy 58.96483 -52.147216)
			(xy 58.992201 -52.147661) (xy 59.046381 -52.155483) (xy 59.098885 -52.170977) (xy 59.148631 -52.193823)
			(xy 59.194597 -52.223553) (xy 59.215528 -52.241196) (xy 59.215782 -52.24145) (xy 59.222865 -52.247041)
			(xy 59.239785 -52.253284) (xy 59.248802 -52.253642) (xy 59.315858 -52.253642) (xy 59.324874 -52.253278)
			(xy 59.341792 -52.247037) (xy 59.348878 -52.24145) (xy 59.348878 -52.241196) (xy 59.349132 -52.241196)
			(xy 59.370078 -52.223575) (xy 59.416047 -52.19386) (xy 59.465791 -52.171021) (xy 59.518289 -52.155526)
			(xy 59.572462 -52.147693) (xy 59.59983 -52.147216) (xy 59.627082 -52.147656) (xy 59.681029 -52.155416)
			(xy 59.733324 -52.170775) (xy 59.7829 -52.193419) (xy 59.82875 -52.222888) (xy 59.869939 -52.258582)
			(xy 59.90563 -52.299774) (xy 59.935095 -52.345626) (xy 59.957735 -52.395204) (xy 59.97309 -52.4475)
			(xy 59.980846 -52.501448) (xy 59.980846 -52.555952) (xy 59.97309 -52.6099) (xy 59.957735 -52.662196)
			(xy 59.935095 -52.711774) (xy 59.90563 -52.757626) (xy 59.869939 -52.798818) (xy 59.82875 -52.834512)
			(xy 59.7829 -52.863981) (xy 59.733324 -52.886625) (xy 59.681029 -52.901984) (xy 59.627082 -52.909744)
			(xy 59.59983 -52.910232) (xy 59.57246 -52.909765) (xy 59.51828 -52.90195) (xy 59.465776 -52.886462)
			(xy 59.416029 -52.86362) (xy 59.370063 -52.833894) (xy 59.349132 -52.816252) (xy 59.348878 -52.815998)
			(xy 59.341802 -52.810396) (xy 59.324877 -52.804159) (xy 59.315858 -52.803806) (xy 59.248802 -52.803806)
			(xy 59.239785 -52.804163) (xy 59.222868 -52.81041) (xy 59.215782 -52.815998) (xy 59.215782 -52.816252)
			(xy 59.215528 -52.816252) (xy 59.19459 -52.833884) (xy 59.14862 -52.863599) (xy 59.098874 -52.886437)
			(xy 59.046374 -52.901929) (xy 58.992199 -52.909758) (xy 58.96483 -52.910232) (xy 58.937577 -52.909723)
			(xy 58.883627 -52.90197) (xy 58.831329 -52.886617) (xy 58.781748 -52.863978) (xy 58.735894 -52.834513)
			(xy 58.6947 -52.798821) (xy 58.659005 -52.75763) (xy 58.629536 -52.711779) (xy 58.606893 -52.6622)
			(xy 58.591537 -52.609903) (xy 58.583779 -52.555953) (xy 51.517787 -52.555953) (xy 51.518311 -52.559512)
			(xy 51.51882 -52.587398) (xy 51.518311 -52.615284) (xy 51.510191 -52.67046) (xy 51.494123 -52.723867)
			(xy 51.470451 -52.774364) (xy 51.439678 -52.820877) (xy 51.402461 -52.862414) (xy 51.359593 -52.898089)
			(xy 51.311987 -52.927143) (xy 51.260658 -52.948955) (xy 51.206701 -52.963061) (xy 51.151264 -52.969161)
			(xy 51.09553 -52.967124) (xy 51.040687 -52.956994) (xy 50.987903 -52.938987) (xy 50.938303 -52.913486)
			(xy 50.892945 -52.881035) (xy 50.852796 -52.842326) (xy 50.81871 -52.798183) (xy 50.791414 -52.749548)
			(xy 50.771491 -52.697457) (xy 50.759365 -52.64302) (xy 50.755294 -52.587398) (xy 49.705696 -52.587398)
			(xy 49.703884 -52.600001) (xy 49.688528 -52.652298) (xy 49.665887 -52.701877) (xy 49.63642 -52.747729)
			(xy 49.600728 -52.788921) (xy 49.559537 -52.824614) (xy 49.513686 -52.854082) (xy 49.464107 -52.876725)
			(xy 49.411811 -52.892081) (xy 49.357862 -52.899839) (xy 49.33061 -52.900326) (xy 49.303239 -52.899872)
			(xy 49.249059 -52.892054) (xy 49.196555 -52.876563) (xy 49.146808 -52.853718) (xy 49.100843 -52.82399)
			(xy 49.079912 -52.806346) (xy 49.079658 -52.806092) (xy 49.07256 -52.800523) (xy 49.055652 -52.794266)
			(xy 49.046638 -52.7939) (xy 48.979582 -52.7939) (xy 48.970564 -52.794249) (xy 48.953647 -52.800502)
			(xy 48.946562 -52.806092) (xy 48.946308 -52.806346) (xy 48.925375 -52.823987) (xy 48.879407 -52.853711)
			(xy 48.829661 -52.876557) (xy 48.777159 -52.892053) (xy 48.722981 -52.899882) (xy 48.668239 -52.899882)
			(xy 48.614061 -52.892053) (xy 48.561559 -52.876557) (xy 48.511813 -52.853711) (xy 48.465845 -52.823987)
			(xy 48.444912 -52.806346) (xy 48.444658 -52.806092) (xy 48.43756 -52.800523) (xy 48.420652 -52.794266)
			(xy 48.411638 -52.7939) (xy 48.344582 -52.7939) (xy 48.335564 -52.794249) (xy 48.318647 -52.800502)
			(xy 48.311562 -52.806092) (xy 48.311562 -52.806346) (xy 48.311308 -52.806346) (xy 48.290377 -52.823986)
			(xy 48.244405 -52.8537) (xy 48.194657 -52.876536) (xy 48.142156 -52.892027) (xy 48.087979 -52.899853)
			(xy 48.06061 -52.900326) (xy 48.033358 -52.899827) (xy 47.979409 -52.892072) (xy 47.927112 -52.876717)
			(xy 47.877533 -52.854077) (xy 47.831681 -52.82461) (xy 47.790489 -52.788918) (xy 47.754796 -52.747727)
			(xy 47.725328 -52.701876) (xy 47.702686 -52.652297) (xy 47.68733 -52.600001) (xy 47.679573 -52.546052)
			(xy 42.730557 -52.546052) (xy 42.741025 -52.550833) (xy 42.786875 -52.580299) (xy 42.828066 -52.61599)
			(xy 42.863757 -52.657181) (xy 42.893223 -52.703031) (xy 42.915865 -52.752608) (xy 42.93122 -52.804903)
			(xy 42.938976 -52.858851) (xy 42.939462 -52.886102) (xy 42.939006 -52.913473) (xy 42.931187 -52.967653)
			(xy 42.915696 -53.020156) (xy 42.892852 -53.069903) (xy 42.863125 -53.115869) (xy 42.845482 -53.1368)
			(xy 42.845228 -53.137054) (xy 42.839646 -53.144143) (xy 42.833399 -53.161058) (xy 42.833036 -53.170074)
			(xy 42.833036 -53.23713) (xy 42.833371 -53.246149) (xy 42.839633 -53.263067) (xy 42.845228 -53.27015)
			(xy 42.845482 -53.27015) (xy 42.845482 -53.270404) (xy 42.863124 -53.291335) (xy 42.892848 -53.337304)
			(xy 42.915693 -53.38705) (xy 42.931189 -53.439552) (xy 42.939017 -53.493731) (xy 42.939017 -53.548472)
			(xy 42.931188 -53.602651) (xy 42.915692 -53.655153) (xy 42.892847 -53.704899) (xy 42.863122 -53.750867)
			(xy 42.846552 -53.77053) (xy 43.210734 -53.77053) (xy 43.211261 -53.741613) (xy 43.219986 -53.684442)
			(xy 43.237242 -53.629243) (xy 43.262632 -53.577281) (xy 43.295574 -53.529747) (xy 43.335315 -53.48773)
			(xy 43.3578 -53.46954) (xy 43.366579 -53.461906) (xy 43.376778 -53.441026) (xy 43.377358 -53.429408)
			(xy 43.377358 -53.349652) (xy 43.376847 -53.338016) (xy 43.36664 -53.317106) (xy 43.3578 -53.30952)
			(xy 43.335326 -53.291318) (xy 43.29559 -53.2493) (xy 43.26265 -53.201768) (xy 43.23726 -53.149809)
			(xy 43.220002 -53.094613) (xy 43.21127 -53.037445) (xy 43.210734 -53.00853) (xy 43.211183 -52.981276)
			(xy 43.218937 -52.927322) (xy 43.234292 -52.875022) (xy 43.256934 -52.825439) (xy 43.286403 -52.779584)
			(xy 43.322098 -52.738389) (xy 43.363293 -52.702695) (xy 43.409149 -52.673228) (xy 43.458733 -52.650587)
			(xy 43.511034 -52.635235) (xy 43.564988 -52.627482) (xy 43.592242 -52.627022) (xy 43.618557 -52.627454)
			(xy 43.670688 -52.634695) (xy 43.721331 -52.649021) (xy 43.76953 -52.67016) (xy 43.814373 -52.697712)
			(xy 43.855011 -52.731157) (xy 43.873166 -52.750212) (xy 43.880697 -52.757603) (xy 43.89997 -52.766133)
			(xy 43.910504 -52.766722) (xy 43.98518 -52.766722) (xy 43.995729 -52.766189) (xy 44.015024 -52.757656)
			(xy 44.022518 -52.750212) (xy 44.040674 -52.731157) (xy 44.081303 -52.697699) (xy 44.126144 -52.67014)
			(xy 44.174344 -52.649001) (xy 44.224992 -52.634684) (xy 44.277126 -52.62746) (xy 44.303442 -52.627022)
			(xy 44.330696 -52.627439) (xy 44.384647 -52.635202) (xy 44.436945 -52.650564) (xy 44.486525 -52.673212)
			(xy 44.532376 -52.702685) (xy 44.573567 -52.738384) (xy 44.609258 -52.779581) (xy 44.638723 -52.825439)
			(xy 44.661361 -52.875022) (xy 44.676713 -52.927323) (xy 44.684466 -52.981276) (xy 44.68495 -53.00853)
			(xy 44.684484 -53.036197) (xy 44.682253 -53.051456) (xy 52.941218 -53.051456) (xy 52.945289 -52.995834)
			(xy 52.957415 -52.941397) (xy 52.977338 -52.889306) (xy 53.004634 -52.840671) (xy 53.03872 -52.796528)
			(xy 53.078869 -52.757819) (xy 53.124227 -52.725368) (xy 53.173827 -52.699867) (xy 53.226611 -52.68186)
			(xy 53.281454 -52.67173) (xy 53.337188 -52.669693) (xy 53.392625 -52.675793) (xy 53.446582 -52.689899)
			(xy 53.497911 -52.711711) (xy 53.545517 -52.740765) (xy 53.588385 -52.77644) (xy 53.625602 -52.817977)
			(xy 53.656375 -52.86449) (xy 53.680047 -52.914987) (xy 53.696115 -52.968394) (xy 53.704235 -53.02357)
			(xy 53.704744 -53.051456) (xy 53.704235 -53.079342) (xy 53.696115 -53.134518) (xy 53.680047 -53.187925)
			(xy 53.656375 -53.238422) (xy 53.625602 -53.284935) (xy 53.588385 -53.326472) (xy 53.545517 -53.362147)
			(xy 53.497911 -53.391201) (xy 53.446582 -53.413013) (xy 53.392625 -53.427119) (xy 53.337188 -53.433219)
			(xy 53.281454 -53.431182) (xy 53.226611 -53.421052) (xy 53.173827 -53.403045) (xy 53.124227 -53.377544)
			(xy 53.078869 -53.345093) (xy 53.03872 -53.306384) (xy 53.004634 -53.262241) (xy 52.977338 -53.213606)
			(xy 52.957415 -53.161515) (xy 52.945289 -53.107078) (xy 52.941218 -53.051456) (xy 44.682253 -53.051456)
			(xy 44.676479 -53.090949) (xy 44.660656 -53.143973) (xy 44.637346 -53.194158) (xy 44.607037 -53.240453)
			(xy 44.570364 -53.281889) (xy 44.528095 -53.317599) (xy 44.504864 -53.332634) (xy 44.495176 -53.339257)
			(xy 44.482737 -53.359128) (xy 44.480988 -53.370734) (xy 44.473114 -53.450744) (xy 44.472473 -53.462382)
			(xy 44.480561 -53.484219) (xy 44.488608 -53.492654) (xy 44.488862 -53.492908) (xy 44.507422 -53.51101)
			(xy 44.540004 -53.551336) (xy 44.566821 -53.595706) (xy 44.587377 -53.643301) (xy 44.601295 -53.693242)
			(xy 44.608316 -53.744608) (xy 44.60875 -53.77053) (xy 44.60825 -53.79778) (xy 44.600491 -53.851725)
			(xy 44.585134 -53.904017) (xy 44.562492 -53.953592) (xy 44.533027 -53.99944) (xy 44.497337 -54.040629)
			(xy 44.456149 -54.07632) (xy 44.410302 -54.105787) (xy 44.360728 -54.12843) (xy 44.308437 -54.143788)
			(xy 44.254492 -54.151549) (xy 44.227242 -54.152038) (xy 44.199872 -54.151562) (xy 44.145693 -54.143749)
			(xy 44.093189 -54.128263) (xy 44.043442 -54.105423) (xy 43.997475 -54.075699) (xy 43.976544 -54.058058)
			(xy 43.97629 -54.057804) (xy 43.96921 -54.052208) (xy 43.952288 -54.045967) (xy 43.94327 -54.045612)
			(xy 43.876214 -54.045612) (xy 43.867197 -54.045973) (xy 43.85028 -54.052217) (xy 43.843194 -54.057804)
			(xy 43.843194 -54.058058) (xy 43.84294 -54.058058) (xy 43.821998 -54.075685) (xy 43.776029 -54.1054)
			(xy 43.726284 -54.128239) (xy 43.673785 -54.143733) (xy 43.619611 -54.151563) (xy 43.592242 -54.152038)
			(xy 43.564992 -54.151506) (xy 43.511045 -54.143755) (xy 43.45875 -54.128406) (xy 43.409172 -54.105771)
			(xy 43.36332 -54.07631) (xy 43.322128 -54.040623) (xy 43.286433 -53.999438) (xy 43.256964 -53.953591)
			(xy 43.234319 -53.904018) (xy 43.21896 -53.851726) (xy 43.211199 -53.79778) (xy 43.210734 -53.77053)
			(xy 42.846552 -53.77053) (xy 42.845482 -53.7718) (xy 42.845228 -53.772054) (xy 42.839646 -53.779143)
			(xy 42.833399 -53.796058) (xy 42.833036 -53.805074) (xy 42.833036 -53.87213) (xy 42.833371 -53.881149)
			(xy 42.839633 -53.898067) (xy 42.845228 -53.90515) (xy 42.845482 -53.90515) (xy 42.845482 -53.905404)
			(xy 42.863124 -53.926335) (xy 42.892848 -53.972304) (xy 42.915693 -54.02205) (xy 42.931189 -54.074552)
			(xy 42.939017 -54.128731) (xy 42.939017 -54.183472) (xy 42.931188 -54.237651) (xy 42.915692 -54.290153)
			(xy 42.9019 -54.320186) (xy 45.130466 -54.320186) (xy 45.130908 -54.292815) (xy 45.138729 -54.238634)
			(xy 45.154223 -54.18613) (xy 45.17707 -54.136383) (xy 45.206801 -54.090418) (xy 45.224446 -54.069488)
			(xy 45.2247 -54.069234) (xy 45.230278 -54.062142) (xy 45.23653 -54.045229) (xy 45.236892 -54.036214)
			(xy 45.236892 -53.969158) (xy 45.236509 -53.960144) (xy 45.23028 -53.943227) (xy 45.2247 -53.936138)
			(xy 45.224446 -53.936138) (xy 45.224446 -53.935884) (xy 45.20684 -53.914925) (xy 45.177122 -53.86896)
			(xy 45.154279 -53.81922) (xy 45.13878 -53.766725) (xy 45.130944 -53.712553) (xy 45.130466 -53.685186)
			(xy 45.130952 -53.657935) (xy 45.138708 -53.603987) (xy 45.154063 -53.551692) (xy 45.176705 -53.502115)
			(xy 45.206171 -53.456265) (xy 45.241862 -53.415074) (xy 45.283053 -53.379383) (xy 45.328903 -53.349917)
			(xy 45.37848 -53.327275) (xy 45.430775 -53.31192) (xy 45.484723 -53.304164) (xy 45.539225 -53.304164)
			(xy 45.593173 -53.31192) (xy 45.645468 -53.327275) (xy 45.695045 -53.349917) (xy 45.740895 -53.379383)
			(xy 45.782086 -53.415074) (xy 45.817777 -53.456265) (xy 45.843668 -53.496552) (xy 58.133464 -53.496552)
			(xy 58.133464 -53.442048) (xy 58.14122 -53.3881) (xy 58.156575 -53.335804) (xy 58.179216 -53.286226)
			(xy 58.208683 -53.240374) (xy 58.244374 -53.199183) (xy 58.285565 -53.16349) (xy 58.331415 -53.134022)
			(xy 58.380993 -53.11138) (xy 58.433288 -53.096023) (xy 58.487236 -53.088265) (xy 58.514488 -53.087778)
			(xy 58.541859 -53.088232) (xy 58.596039 -53.09605) (xy 58.648543 -53.111541) (xy 58.69829 -53.134386)
			(xy 58.744256 -53.164114) (xy 58.765186 -53.181758) (xy 58.76544 -53.182012) (xy 58.772539 -53.187581)
			(xy 58.789446 -53.193838) (xy 58.79846 -53.194204) (xy 58.865516 -53.194204) (xy 58.874534 -53.193854)
			(xy 58.89145 -53.187601) (xy 58.898536 -53.182012) (xy 58.898536 -53.181758) (xy 58.89879 -53.181758)
			(xy 58.919709 -53.164103) (xy 58.965686 -53.134395) (xy 59.015437 -53.111563) (xy 59.06794 -53.096075)
			(xy 59.122118 -53.08825) (xy 59.149488 -53.087778) (xy 59.17674 -53.088268) (xy 59.230691 -53.096024)
			(xy 59.282988 -53.111378) (xy 59.332568 -53.134019) (xy 59.378421 -53.163486) (xy 59.419613 -53.199178)
			(xy 59.455307 -53.24037) (xy 59.484775 -53.286222) (xy 59.507418 -53.335801) (xy 59.522774 -53.388098)
			(xy 59.530531 -53.442048) (xy 59.530531 -53.496552) (xy 59.522774 -53.550502) (xy 59.507418 -53.602799)
			(xy 59.484775 -53.652378) (xy 59.455307 -53.69823) (xy 59.419613 -53.739422) (xy 59.378421 -53.775114)
			(xy 59.332568 -53.804581) (xy 59.282988 -53.827222) (xy 59.230691 -53.842576) (xy 59.17674 -53.850332)
			(xy 59.149488 -53.850794) (xy 59.122117 -53.850336) (xy 59.067938 -53.842517) (xy 59.015435 -53.827026)
			(xy 58.965688 -53.804182) (xy 58.919721 -53.774456) (xy 58.89879 -53.756814) (xy 58.898536 -53.75656)
			(xy 58.891447 -53.750977) (xy 58.874532 -53.744729) (xy 58.865516 -53.744368) (xy 58.79846 -53.744368)
			(xy 58.789442 -53.744713) (xy 58.772525 -53.75097) (xy 58.76544 -53.75656) (xy 58.76544 -53.756814)
			(xy 58.765186 -53.756814) (xy 58.744234 -53.774428) (xy 58.698267 -53.804143) (xy 58.648524 -53.826984)
			(xy 58.596028 -53.842481) (xy 58.541856 -53.850316) (xy 58.514488 -53.850794) (xy 58.487236 -53.850335)
			(xy 58.433288 -53.842577) (xy 58.380993 -53.82722) (xy 58.331415 -53.804578) (xy 58.285565 -53.77511)
			(xy 58.244374 -53.739417) (xy 58.208683 -53.698226) (xy 58.179216 -53.652374) (xy 58.156575 -53.602796)
			(xy 58.14122 -53.5505) (xy 58.133464 -53.496552) (xy 45.843668 -53.496552) (xy 45.847243 -53.502115)
			(xy 45.869885 -53.551692) (xy 45.88524 -53.603987) (xy 45.892996 -53.657935) (xy 45.893482 -53.685186)
			(xy 45.893012 -53.712556) (xy 45.885196 -53.766735) (xy 45.869708 -53.819238) (xy 45.846867 -53.868985)
			(xy 45.817143 -53.914952) (xy 45.799502 -53.935884) (xy 45.799248 -53.936138) (xy 45.793675 -53.943234)
			(xy 45.787421 -53.960144) (xy 45.787056 -53.969158) (xy 45.787056 -54.036214) (xy 45.787394 -54.045233)
			(xy 45.793654 -54.06215) (xy 45.799248 -54.069234) (xy 45.799502 -54.069234) (xy 45.799502 -54.069488)
			(xy 45.817149 -54.090414) (xy 45.84686 -54.136388) (xy 45.869694 -54.186137) (xy 45.885183 -54.238639)
			(xy 45.893009 -54.292816) (xy 45.893482 -54.320186) (xy 45.892996 -54.347437) (xy 45.88524 -54.401385)
			(xy 45.869885 -54.45368) (xy 45.847243 -54.503257) (xy 45.817777 -54.549107) (xy 45.782086 -54.590298)
			(xy 45.740895 -54.625989) (xy 45.695045 -54.655455) (xy 45.645468 -54.678097) (xy 45.593173 -54.693452)
			(xy 45.539225 -54.701208) (xy 45.484723 -54.701208) (xy 45.430775 -54.693452) (xy 45.37848 -54.678097)
			(xy 45.328903 -54.655455) (xy 45.283053 -54.625989) (xy 45.241862 -54.590298) (xy 45.206171 -54.549107)
			(xy 45.176705 -54.503257) (xy 45.154063 -54.45368) (xy 45.138708 -54.401385) (xy 45.130952 -54.347437)
			(xy 45.130466 -54.320186) (xy 42.9019 -54.320186) (xy 42.892847 -54.339899) (xy 42.863122 -54.385867)
			(xy 42.845482 -54.4068) (xy 42.845228 -54.407054) (xy 42.839646 -54.414143) (xy 42.833399 -54.431058)
			(xy 42.833036 -54.440074) (xy 42.833036 -54.50713) (xy 42.833371 -54.516149) (xy 42.839633 -54.533067)
			(xy 42.845228 -54.54015) (xy 42.845482 -54.54015) (xy 42.845482 -54.540404) (xy 42.863134 -54.561326)
			(xy 42.892844 -54.607301) (xy 42.915678 -54.657051) (xy 42.931166 -54.709554) (xy 42.93899 -54.763732)
			(xy 42.939107 -54.770528) (xy 46.071028 -54.770528) (xy 46.071504 -54.743158) (xy 46.079318 -54.688979)
			(xy 46.094805 -54.636476) (xy 46.117644 -54.586729) (xy 46.147367 -54.540762) (xy 46.165008 -54.51983)
			(xy 46.165262 -54.519576) (xy 46.170872 -54.512506) (xy 46.177103 -54.495576) (xy 46.177454 -54.486556)
			(xy 46.177454 -54.4195) (xy 46.177107 -54.410482) (xy 46.170853 -54.393565) (xy 46.165262 -54.38648)
			(xy 46.165008 -54.38648) (xy 46.165008 -54.386226) (xy 46.147369 -54.365294) (xy 46.117657 -54.319321)
			(xy 46.094821 -54.269574) (xy 46.07933 -54.217073) (xy 46.071502 -54.162897) (xy 46.071028 -54.135528)
			(xy 46.071514 -54.108277) (xy 46.07927 -54.054329) (xy 46.094625 -54.002034) (xy 46.117267 -53.952457)
			(xy 46.146733 -53.906607) (xy 46.182424 -53.865416) (xy 46.223615 -53.829725) (xy 46.269465 -53.800259)
			(xy 46.319042 -53.777617) (xy 46.371337 -53.762262) (xy 46.425285 -53.754506) (xy 46.479787 -53.754506)
			(xy 46.533735 -53.762262) (xy 46.58603 -53.777617) (xy 46.635607 -53.800259) (xy 46.681457 -53.829725)
			(xy 46.722648 -53.865416) (xy 46.758339 -53.906607) (xy 46.787805 -53.952457) (xy 46.79288 -53.96357)
			(xy 50.772058 -53.96357) (xy 50.776129 -53.907948) (xy 50.788255 -53.853511) (xy 50.808178 -53.80142)
			(xy 50.835474 -53.752785) (xy 50.86956 -53.708642) (xy 50.909709 -53.669933) (xy 50.955067 -53.637482)
			(xy 51.004667 -53.611981) (xy 51.057451 -53.593974) (xy 51.112294 -53.583844) (xy 51.168028 -53.581807)
			(xy 51.223465 -53.587907) (xy 51.277422 -53.602013) (xy 51.328751 -53.623825) (xy 51.376357 -53.652879)
			(xy 51.419225 -53.688554) (xy 51.456442 -53.730091) (xy 51.487215 -53.776604) (xy 51.510887 -53.827101)
			(xy 51.526955 -53.880508) (xy 51.535075 -53.935684) (xy 51.535584 -53.96357) (xy 51.535075 -53.991456)
			(xy 51.526955 -54.046632) (xy 51.510887 -54.100039) (xy 51.487215 -54.150536) (xy 51.456442 -54.197049)
			(xy 51.419225 -54.238586) (xy 51.376357 -54.274261) (xy 51.328751 -54.303315) (xy 51.277422 -54.325127)
			(xy 51.223465 -54.339233) (xy 51.168028 -54.345333) (xy 51.112294 -54.343296) (xy 51.057451 -54.333166)
			(xy 51.004667 -54.315159) (xy 50.955067 -54.289658) (xy 50.909709 -54.257207) (xy 50.86956 -54.218498)
			(xy 50.835474 -54.174355) (xy 50.808178 -54.12572) (xy 50.788255 -54.073629) (xy 50.776129 -54.019192)
			(xy 50.772058 -53.96357) (xy 46.79288 -53.96357) (xy 46.810447 -54.002034) (xy 46.825802 -54.054329)
			(xy 46.833558 -54.108277) (xy 46.834044 -54.135528) (xy 46.833608 -54.162899) (xy 46.825785 -54.21708)
			(xy 46.81029 -54.269584) (xy 46.787441 -54.319331) (xy 46.757709 -54.365296) (xy 46.740064 -54.386226)
			(xy 46.73981 -54.38648) (xy 46.734227 -54.393569) (xy 46.727978 -54.410484) (xy 46.727618 -54.4195)
			(xy 46.727618 -54.486556) (xy 46.727992 -54.495571) (xy 46.734228 -54.512488) (xy 46.73981 -54.519576)
			(xy 46.740064 -54.519576) (xy 46.740064 -54.51983) (xy 46.757678 -54.540782) (xy 46.787395 -54.586749)
			(xy 46.810236 -54.636491) (xy 46.825733 -54.688988) (xy 46.833567 -54.74316) (xy 46.834044 -54.770528)
			(xy 46.833558 -54.797779) (xy 46.825802 -54.851727) (xy 46.810447 -54.904022) (xy 46.787805 -54.953599)
			(xy 46.765021 -54.989051) (xy 55.901068 -54.989051) (xy 55.901068 -54.934549) (xy 55.908824 -54.880601)
			(xy 55.924179 -54.828307) (xy 55.946819 -54.778729) (xy 55.976284 -54.732879) (xy 56.011975 -54.691688)
			(xy 56.053164 -54.655995) (xy 56.099013 -54.626528) (xy 56.14859 -54.603885) (xy 56.200884 -54.588528)
			(xy 56.254831 -54.580769) (xy 56.282082 -54.580282) (xy 56.310173 -54.580791) (xy 56.36575 -54.589016)
			(xy 56.419518 -54.605304) (xy 56.470316 -54.629305) (xy 56.517043 -54.660497) (xy 56.558688 -54.698207)
			(xy 56.594351 -54.741619) (xy 56.609234 -54.765448) (xy 56.614568 -54.774338) (xy 56.631586 -54.78653)
			(xy 56.724804 -54.80685) (xy 56.745378 -54.802532) (xy 56.754014 -54.79669) (xy 56.778072 -54.780681)
			(xy 56.830006 -54.75534) (xy 56.885165 -54.738117) (xy 56.942291 -54.729405) (xy 56.971184 -54.728872)
			(xy 56.998434 -54.729393) (xy 57.052379 -54.737147) (xy 57.104672 -54.752499) (xy 57.154248 -54.775137)
			(xy 57.200097 -54.804599) (xy 57.241287 -54.840287) (xy 57.276979 -54.881474) (xy 57.306446 -54.92732)
			(xy 57.329088 -54.976894) (xy 57.344445 -55.029185) (xy 57.352204 -55.08313) (xy 57.352692 -55.11038)
			(xy 57.352216 -55.13775) (xy 57.344401 -55.191929) (xy 57.328914 -55.244432) (xy 57.306075 -55.294179)
			(xy 57.276352 -55.340146) (xy 57.258712 -55.361078) (xy 57.258458 -55.361332) (xy 57.252889 -55.36843)
			(xy 57.246633 -55.385338) (xy 57.246266 -55.394352) (xy 57.246266 -55.461408) (xy 57.246626 -55.470424)
			(xy 57.252872 -55.487341) (xy 57.258458 -55.494428) (xy 57.258712 -55.494428) (xy 57.258712 -55.494682)
			(xy 57.276331 -55.515631) (xy 57.306054 -55.561597) (xy 57.328898 -55.611341) (xy 57.344394 -55.66384)
			(xy 57.352224 -55.718016) (xy 57.352226 -55.772754) (xy 57.344401 -55.82693) (xy 57.328909 -55.879431)
			(xy 57.306069 -55.929176) (xy 57.27635 -55.975145) (xy 57.258712 -55.996078) (xy 57.258458 -55.996332)
			(xy 57.252889 -56.00343) (xy 57.246633 -56.020338) (xy 57.246266 -56.029352) (xy 57.246266 -56.096408)
			(xy 57.246626 -56.105424) (xy 57.252872 -56.122341) (xy 57.258458 -56.129428) (xy 57.258712 -56.129428)
			(xy 57.258712 -56.129682) (xy 57.276358 -56.150608) (xy 57.306068 -56.196583) (xy 57.328903 -56.246332)
			(xy 57.344392 -56.298834) (xy 57.352219 -56.35301) (xy 57.352692 -56.38038) (xy 57.352206 -56.407631)
			(xy 57.34445 -56.461579) (xy 57.329095 -56.513874) (xy 57.306453 -56.563451) (xy 57.276987 -56.609301)
			(xy 57.241296 -56.650492) (xy 57.200105 -56.686183) (xy 57.154255 -56.715649) (xy 57.104678 -56.738291)
			(xy 57.052383 -56.753646) (xy 56.998435 -56.761402) (xy 56.943933 -56.761402) (xy 56.889985 -56.753646)
			(xy 56.83769 -56.738291) (xy 56.788113 -56.715649) (xy 56.742263 -56.686183) (xy 56.701072 -56.650492)
			(xy 56.665381 -56.609301) (xy 56.635915 -56.563451) (xy 56.613273 -56.513874) (xy 56.597918 -56.461579)
			(xy 56.590162 -56.407631) (xy 56.589676 -56.38038) (xy 56.590112 -56.353008) (xy 56.597934 -56.298827)
			(xy 56.613429 -56.246323) (xy 56.636278 -56.196577) (xy 56.666011 -56.150612) (xy 56.683656 -56.129682)
			(xy 56.68391 -56.129428) (xy 56.689492 -56.122338) (xy 56.695741 -56.105424) (xy 56.696102 -56.096408)
			(xy 56.696102 -56.029352) (xy 56.695719 -56.020338) (xy 56.689489 -56.003421) (xy 56.68391 -55.996332)
			(xy 56.683656 -55.996332) (xy 56.683656 -55.996078) (xy 56.665995 -55.975162) (xy 56.636268 -55.929192)
			(xy 56.613422 -55.879443) (xy 56.597926 -55.826938) (xy 56.590099 -55.772757) (xy 56.590101 -55.718013)
			(xy 56.597933 -55.663832) (xy 56.613433 -55.611329) (xy 56.636283 -55.561582) (xy 56.666013 -55.515614)
			(xy 56.683656 -55.494682) (xy 56.68391 -55.494428) (xy 56.689492 -55.487338) (xy 56.695741 -55.470424)
			(xy 56.696102 -55.461408) (xy 56.696102 -55.394352) (xy 56.695719 -55.385338) (xy 56.689489 -55.368421)
			(xy 56.68391 -55.361332) (xy 56.683656 -55.360824) (xy 56.67271 -55.348091) (xy 56.65287 -55.320999)
			(xy 56.644032 -55.306722) (xy 56.638698 -55.297832) (xy 56.62168 -55.28564) (xy 56.528462 -55.26532)
			(xy 56.507888 -55.269638) (xy 56.499252 -55.27548) (xy 56.475174 -55.291458) (xy 56.423248 -55.316806)
			(xy 56.368094 -55.334038) (xy 56.310973 -55.34276) (xy 56.282082 -55.343298) (xy 56.254831 -55.342831)
			(xy 56.200884 -55.335072) (xy 56.14859 -55.319715) (xy 56.099013 -55.297072) (xy 56.053164 -55.267605)
			(xy 56.011975 -55.231912) (xy 55.976284 -55.190721) (xy 55.946819 -55.144871) (xy 55.924179 -55.095293)
			(xy 55.908824 -55.042999) (xy 55.901068 -54.989051) (xy 46.765021 -54.989051) (xy 46.758339 -54.999449)
			(xy 46.722648 -55.04064) (xy 46.681457 -55.076331) (xy 46.635607 -55.105797) (xy 46.58603 -55.128439)
			(xy 46.533735 -55.143794) (xy 46.479787 -55.15155) (xy 46.425285 -55.15155) (xy 46.371337 -55.143794)
			(xy 46.319042 -55.128439) (xy 46.269465 -55.105797) (xy 46.223615 -55.076331) (xy 46.182424 -55.04064)
			(xy 46.146733 -54.999449) (xy 46.117267 -54.953599) (xy 46.094625 -54.904022) (xy 46.07927 -54.851727)
			(xy 46.071514 -54.797779) (xy 46.071028 -54.770528) (xy 42.939107 -54.770528) (xy 42.939462 -54.791102)
			(xy 42.938976 -54.818353) (xy 42.93122 -54.872301) (xy 42.915865 -54.924596) (xy 42.893223 -54.974173)
			(xy 42.863757 -55.020023) (xy 42.828066 -55.061214) (xy 42.786875 -55.096905) (xy 42.741025 -55.126371)
			(xy 42.691448 -55.149013) (xy 42.639153 -55.164368) (xy 42.585205 -55.172124) (xy 42.530703 -55.172124)
			(xy 42.476755 -55.164368) (xy 42.42446 -55.149013) (xy 42.374883 -55.126371) (xy 42.329033 -55.096905)
			(xy 42.287842 -55.061214) (xy 42.252151 -55.020023) (xy 42.222685 -54.974173) (xy 42.200043 -54.924596)
			(xy 42.184688 -54.872301) (xy 42.176932 -54.818353) (xy 42.176446 -54.791102) (xy 40.278512 -54.791102)
			(xy 40.275366 -54.812925) (xy 40.259898 -54.865408) (xy 40.237089 -54.915142) (xy 40.207406 -54.961105)
			(xy 40.171458 -55.002354) (xy 40.129984 -55.038042) (xy 40.083835 -55.067436) (xy 40.033959 -55.089932)
			(xy 40.007794 -55.097934) (xy 40.005 -55.098696) (xy 39.995326 -55.102601) (xy 39.98 -55.116724)
			(xy 39.971557 -55.135778) (xy 39.970964 -55.146194) (xy 40.005274 -55.722266) (xy 51.834032 -55.722266)
			(xy 51.838103 -55.666644) (xy 51.850229 -55.612207) (xy 51.870152 -55.560116) (xy 51.897448 -55.511481)
			(xy 51.931534 -55.467338) (xy 51.971683 -55.428629) (xy 52.017041 -55.396178) (xy 52.066641 -55.370677)
			(xy 52.119425 -55.35267) (xy 52.174268 -55.34254) (xy 52.230002 -55.340503) (xy 52.285439 -55.346603)
			(xy 52.339396 -55.360709) (xy 52.390725 -55.382521) (xy 52.438331 -55.411575) (xy 52.449477 -55.420851)
			(xy 54.224668 -55.420851) (xy 54.224668 -55.366349) (xy 54.232424 -55.312401) (xy 54.247779 -55.260107)
			(xy 54.270419 -55.210529) (xy 54.299884 -55.164679) (xy 54.335575 -55.123488) (xy 54.376764 -55.087795)
			(xy 54.422613 -55.058328) (xy 54.47219 -55.035685) (xy 54.524484 -55.020328) (xy 54.578431 -55.012569)
			(xy 54.605682 -55.012082) (xy 54.631995 -55.012567) (xy 54.684123 -55.019799) (xy 54.734765 -55.034115)
			(xy 54.782964 -55.055244) (xy 54.827808 -55.082787) (xy 54.868449 -55.116222) (xy 54.886606 -55.135272)
			(xy 54.894127 -55.142674) (xy 54.913407 -55.151199) (xy 54.923944 -55.151782) (xy 54.99862 -55.151782)
			(xy 55.009167 -55.151228) (xy 55.028463 -55.142711) (xy 55.035958 -55.135272) (xy 55.054087 -55.11619)
			(xy 55.094723 -55.082736) (xy 55.139569 -55.055181) (xy 55.187775 -55.034048) (xy 55.238427 -55.019736)
			(xy 55.290564 -55.012517) (xy 55.316882 -55.012082) (xy 55.344135 -55.012564) (xy 55.398086 -55.020319)
			(xy 55.450385 -55.035673) (xy 55.499966 -55.058314) (xy 55.54582 -55.08778) (xy 55.587014 -55.123473)
			(xy 55.622709 -55.164665) (xy 55.652178 -55.210518) (xy 55.674821 -55.260098) (xy 55.690177 -55.312396)
			(xy 55.697935 -55.366347) (xy 55.697935 -55.420853) (xy 55.690177 -55.474804) (xy 55.674821 -55.527102)
			(xy 55.652178 -55.576682) (xy 55.622709 -55.622535) (xy 55.587014 -55.663727) (xy 55.54582 -55.69942)
			(xy 55.499966 -55.728886) (xy 55.450385 -55.751527) (xy 55.398086 -55.766881) (xy 55.344135 -55.774636)
			(xy 55.316882 -55.775098) (xy 55.290568 -55.774643) (xy 55.238439 -55.767406) (xy 55.187796 -55.753084)
			(xy 55.139597 -55.73195) (xy 55.094753 -55.704401) (xy 55.054114 -55.670961) (xy 55.035958 -55.651908)
			(xy 55.028453 -55.644487) (xy 55.00916 -55.635974) (xy 54.99862 -55.635398) (xy 54.923944 -55.635398)
			(xy 54.913396 -55.635938) (xy 54.8941 -55.644466) (xy 54.886606 -55.651908) (xy 54.868442 -55.670955)
			(xy 54.827814 -55.704413) (xy 54.782975 -55.731973) (xy 54.734776 -55.753113) (xy 54.68413 -55.767432)
			(xy 54.631998 -55.774658) (xy 54.605682 -55.775098) (xy 54.578431 -55.774631) (xy 54.524484 -55.766872)
			(xy 54.47219 -55.751515) (xy 54.422613 -55.728872) (xy 54.376764 -55.699405) (xy 54.335575 -55.663712)
			(xy 54.299884 -55.622521) (xy 54.270419 -55.576671) (xy 54.247779 -55.527093) (xy 54.232424 -55.474799)
			(xy 54.224668 -55.420851) (xy 52.449477 -55.420851) (xy 52.481199 -55.44725) (xy 52.518416 -55.488787)
			(xy 52.549189 -55.5353) (xy 52.572861 -55.585797) (xy 52.588929 -55.639204) (xy 52.597049 -55.69438)
			(xy 52.597558 -55.722266) (xy 52.597049 -55.750152) (xy 52.588929 -55.805328) (xy 52.572861 -55.858735)
			(xy 52.549189 -55.909232) (xy 52.518416 -55.955745) (xy 52.481199 -55.997282) (xy 52.438331 -56.032957)
			(xy 52.390725 -56.062011) (xy 52.339396 -56.083823) (xy 52.285439 -56.097929) (xy 52.230002 -56.104029)
			(xy 52.174268 -56.101992) (xy 52.119425 -56.091862) (xy 52.066641 -56.073855) (xy 52.017041 -56.048354)
			(xy 51.971683 -56.015903) (xy 51.931534 -55.977194) (xy 51.897448 -55.933051) (xy 51.870152 -55.884416)
			(xy 51.850229 -55.832325) (xy 51.838103 -55.777888) (xy 51.834032 -55.722266) (xy 40.005274 -55.722266)
			(xy 40.048434 -56.446928) (xy 40.049616 -56.455291) (xy 40.056741 -56.470593) (xy 40.068468 -56.482734)
			(xy 40.075866 -56.486806) (xy 40.09898 -56.499122) (xy 40.141899 -56.529136) (xy 40.180311 -56.564737)
			(xy 40.213494 -56.605256) (xy 40.240824 -56.649933) (xy 40.261787 -56.697928) (xy 40.275989 -56.748338)
			(xy 40.283165 -56.800218) (xy 40.283638 -56.826404) (xy 40.283638 -56.832754) (xy 40.283221 -56.847824)
			(xy 40.280297 -56.877831) (xy 40.277796 -56.892698) (xy 40.271704 -56.92374) (xy 40.250623 -56.983379)
			(xy 40.239805 -57.002934) (xy 47.563532 -57.002934) (xy 47.56403 -56.974842) (xy 47.572253 -56.919264)
			(xy 47.588542 -56.865494) (xy 47.612544 -56.814696) (xy 47.643739 -56.767969) (xy 47.681452 -56.726324)
			(xy 47.724867 -56.690663) (xy 47.748698 -56.675782) (xy 47.757588 -56.670448) (xy 47.76978 -56.65343)
			(xy 47.7901 -56.560212) (xy 47.785782 -56.539638) (xy 47.77994 -56.531002) (xy 47.763931 -56.506944)
			(xy 47.738592 -56.45501) (xy 47.721369 -56.39985) (xy 47.712656 -56.342725) (xy 47.712122 -56.313832)
			(xy 47.712585 -56.286579) (xy 47.720339 -56.232626) (xy 47.735692 -56.180326) (xy 47.758333 -56.130744)
			(xy 47.7878 -56.08489) (xy 47.823494 -56.043696) (xy 47.864688 -56.008002) (xy 47.910543 -55.978534)
			(xy 47.960125 -55.955893) (xy 48.012424 -55.940539) (xy 48.066377 -55.932785) (xy 48.09363 -55.932324)
			(xy 48.121001 -55.932767) (xy 48.175181 -55.940589) (xy 48.227685 -55.956083) (xy 48.277432 -55.978931)
			(xy 48.323397 -56.00866) (xy 48.344328 -56.026304) (xy 48.344582 -56.026558) (xy 48.351665 -56.03215)
			(xy 48.368585 -56.038392) (xy 48.377602 -56.03875) (xy 48.444658 -56.03875) (xy 48.453674 -56.038384)
			(xy 48.470592 -56.032144) (xy 48.477678 -56.026558) (xy 48.477678 -56.026304) (xy 48.477932 -56.026304)
			(xy 48.498865 -56.008663) (xy 48.544833 -55.978939) (xy 48.594579 -55.956093) (xy 48.647081 -55.940597)
			(xy 48.701259 -55.932768) (xy 48.756001 -55.932768) (xy 48.810179 -55.940597) (xy 48.862681 -55.956093)
			(xy 48.912427 -55.978939) (xy 48.958395 -56.008663) (xy 48.979328 -56.026304) (xy 48.979582 -56.026558)
			(xy 48.986665 -56.03215) (xy 49.003585 -56.038392) (xy 49.012602 -56.03875) (xy 49.079658 -56.03875)
			(xy 49.088674 -56.038384) (xy 49.105592 -56.032144) (xy 49.112678 -56.026558) (xy 49.112678 -56.026304)
			(xy 49.112932 -56.026304) (xy 49.133879 -56.008684) (xy 49.179848 -55.978969) (xy 49.229592 -55.956129)
			(xy 49.282089 -55.940634) (xy 49.336262 -55.932801) (xy 49.36363 -55.932324) (xy 49.390882 -55.932748)
			(xy 49.444831 -55.940509) (xy 49.497127 -55.955868) (xy 49.546704 -55.978512) (xy 49.592555 -56.007982)
			(xy 49.633745 -56.043676) (xy 49.669436 -56.084869) (xy 49.698902 -56.130722) (xy 49.721543 -56.180301)
			(xy 49.736898 -56.232598) (xy 49.744654 -56.286548) (xy 49.744654 -56.297068) (xy 50.086512 -56.297068)
			(xy 50.090583 -56.241446) (xy 50.102709 -56.187009) (xy 50.122632 -56.134918) (xy 50.149928 -56.086283)
			(xy 50.184014 -56.04214) (xy 50.224163 -56.003431) (xy 50.269521 -55.97098) (xy 50.319121 -55.945479)
			(xy 50.371905 -55.927472) (xy 50.426748 -55.917342) (xy 50.482482 -55.915305) (xy 50.537919 -55.921405)
			(xy 50.591876 -55.935511) (xy 50.643205 -55.957323) (xy 50.690811 -55.986377) (xy 50.733679 -56.022052)
			(xy 50.770896 -56.063589) (xy 50.801669 -56.110102) (xy 50.825341 -56.160599) (xy 50.841409 -56.214006)
			(xy 50.849529 -56.269182) (xy 50.850038 -56.297068) (xy 50.849529 -56.324954) (xy 50.841409 -56.38013)
			(xy 50.825341 -56.433537) (xy 50.801669 -56.484034) (xy 50.770896 -56.530547) (xy 50.733679 -56.572084)
			(xy 50.690811 -56.607759) (xy 50.643205 -56.636813) (xy 50.591876 -56.658625) (xy 50.537919 -56.672731)
			(xy 50.482482 -56.678831) (xy 50.426748 -56.676794) (xy 50.371905 -56.666664) (xy 50.319121 -56.648657)
			(xy 50.269521 -56.623156) (xy 50.224163 -56.590705) (xy 50.184014 -56.551996) (xy 50.149928 -56.507853)
			(xy 50.122632 -56.459218) (xy 50.102709 -56.407127) (xy 50.090583 -56.35269) (xy 50.086512 -56.297068)
			(xy 49.744654 -56.297068) (xy 49.744654 -56.341052) (xy 49.736898 -56.395002) (xy 49.721543 -56.447299)
			(xy 49.698902 -56.496878) (xy 49.669436 -56.542731) (xy 49.633745 -56.583924) (xy 49.592555 -56.619618)
			(xy 49.546704 -56.649088) (xy 49.497127 -56.671732) (xy 49.444831 -56.687091) (xy 49.390882 -56.694852)
			(xy 49.36363 -56.69534) (xy 49.33626 -56.694871) (xy 49.28208 -56.687056) (xy 49.229577 -56.671569)
			(xy 49.17983 -56.648727) (xy 49.133863 -56.619002) (xy 49.112932 -56.60136) (xy 49.112678 -56.601106)
			(xy 49.105601 -56.595505) (xy 49.088677 -56.589267) (xy 49.079658 -56.588914) (xy 49.012602 -56.588914)
			(xy 49.003585 -56.589269) (xy 48.986668 -56.595518) (xy 48.979582 -56.601106) (xy 48.979582 -56.60136)
			(xy 48.979328 -56.60136) (xy 48.958395 -56.619001) (xy 48.912427 -56.648725) (xy 48.862681 -56.671571)
			(xy 48.810179 -56.687067) (xy 48.756001 -56.694896) (xy 48.701259 -56.694896) (xy 48.647081 -56.687067)
			(xy 48.594579 -56.671571) (xy 48.544833 -56.648725) (xy 48.498865 -56.619001) (xy 48.477932 -56.60136)
			(xy 48.477678 -56.601106) (xy 48.470601 -56.595505) (xy 48.453677 -56.589267) (xy 48.444658 -56.588914)
			(xy 48.377602 -56.588914) (xy 48.368585 -56.589269) (xy 48.351668 -56.595518) (xy 48.344582 -56.601106)
			(xy 48.344074 -56.60136) (xy 48.331339 -56.612303) (xy 48.304248 -56.632145) (xy 48.289972 -56.640984)
			(xy 48.281082 -56.646318) (xy 48.26889 -56.663336) (xy 48.24857 -56.756554) (xy 48.252888 -56.777128)
			(xy 48.25873 -56.785764) (xy 48.27472 -56.809834) (xy 48.300064 -56.861763) (xy 48.317293 -56.91692)
			(xy 48.326011 -56.974042) (xy 48.326548 -57.002934) (xy 48.326062 -57.030185) (xy 48.318306 -57.084133)
			(xy 48.302951 -57.136428) (xy 48.280309 -57.186005) (xy 48.250843 -57.231855) (xy 48.215152 -57.273046)
			(xy 48.173961 -57.308737) (xy 48.128111 -57.338203) (xy 48.078534 -57.360845) (xy 48.026239 -57.3762)
			(xy 47.972291 -57.383956) (xy 47.917789 -57.383956) (xy 47.863841 -57.3762) (xy 47.811546 -57.360845)
			(xy 47.761969 -57.338203) (xy 47.716119 -57.308737) (xy 47.674928 -57.273046) (xy 47.639237 -57.231855)
			(xy 47.609771 -57.186005) (xy 47.587129 -57.136428) (xy 47.571774 -57.084133) (xy 47.564018 -57.030185)
			(xy 47.563532 -57.002934) (xy 40.239805 -57.002934) (xy 40.220003 -57.038729) (xy 40.200834 -57.063894)
			(xy 40.1955 -57.070498) (xy 40.192198 -57.079642) (xy 40.190674 -57.085484) (xy 40.189658 -57.09539)
			(xy 40.189658 -57.128156) (xy 40.178482 -57.128156) (xy 40.178482 -57.178956) (xy 40.178815 -57.18756)
			(xy 40.184523 -57.203794) (xy 40.189658 -57.210706) (xy 40.190928 -57.21223) (xy 40.208322 -57.233106)
			(xy 40.237642 -57.278856) (xy 40.260172 -57.328304) (xy 40.275454 -57.380449) (xy 40.283181 -57.434235)
			(xy 40.283638 -57.461404) (xy 40.283256 -57.48528) (xy 56.60593 -57.48528) (xy 56.610001 -57.429658)
			(xy 56.622127 -57.375221) (xy 56.64205 -57.32313) (xy 56.669346 -57.274495) (xy 56.703432 -57.230352)
			(xy 56.743581 -57.191643) (xy 56.788939 -57.159192) (xy 56.838539 -57.133691) (xy 56.891323 -57.115684)
			(xy 56.946166 -57.105554) (xy 57.0019 -57.103517) (xy 57.057337 -57.109617) (xy 57.111294 -57.123723)
			(xy 57.162623 -57.145535) (xy 57.210229 -57.174589) (xy 57.253097 -57.210264) (xy 57.290314 -57.251801)
			(xy 57.321087 -57.298314) (xy 57.344759 -57.348811) (xy 57.360827 -57.402218) (xy 57.368947 -57.457394)
			(xy 57.369456 -57.48528) (xy 57.368947 -57.513166) (xy 57.360827 -57.568342) (xy 57.344759 -57.621749)
			(xy 57.321087 -57.672246) (xy 57.290314 -57.718759) (xy 57.253097 -57.760296) (xy 57.210229 -57.795971)
			(xy 57.162623 -57.825025) (xy 57.111294 -57.846837) (xy 57.057337 -57.860943) (xy 57.0019 -57.867043)
			(xy 56.946166 -57.865006) (xy 56.891323 -57.854876) (xy 56.838539 -57.836869) (xy 56.788939 -57.811368)
			(xy 56.743581 -57.778917) (xy 56.703432 -57.740208) (xy 56.669346 -57.696065) (xy 56.64205 -57.64743)
			(xy 56.622127 -57.595339) (xy 56.610001 -57.540902) (xy 56.60593 -57.48528) (xy 40.283256 -57.48528)
			(xy 40.283228 -57.487021) (xy 40.276376 -57.537796) (xy 40.262781 -57.587194) (xy 40.242689 -57.634325)
			(xy 40.216463 -57.678339) (xy 40.200834 -57.69864) (xy 40.20058 -57.698894) (xy 40.199056 -57.700672)
			(xy 40.194751 -57.707198) (xy 40.189954 -57.72207) (xy 40.189658 -57.729882) (xy 40.189658 -57.763156)
			(xy 40.178482 -57.763156) (xy 40.178482 -57.813956) (xy 40.178815 -57.82256) (xy 40.184523 -57.838794)
			(xy 40.189658 -57.845706) (xy 40.190928 -57.84723) (xy 40.208322 -57.868106) (xy 40.237642 -57.913856)
			(xy 40.260172 -57.963304) (xy 40.275454 -58.015449) (xy 40.283181 -58.069235) (xy 40.283638 -58.096404)
			(xy 40.283228 -58.122021) (xy 40.276376 -58.172796) (xy 40.262781 -58.222194) (xy 40.242689 -58.269325)
			(xy 40.216463 -58.313339) (xy 40.200834 -58.33364) (xy 40.20058 -58.333894) (xy 40.199056 -58.335672)
			(xy 40.194751 -58.342198) (xy 40.189954 -58.35707) (xy 40.189658 -58.364882) (xy 40.189658 -58.398156)
			(xy 40.178482 -58.398156) (xy 40.178482 -58.448956) (xy 40.178815 -58.45756) (xy 40.184523 -58.473794)
			(xy 40.189658 -58.480706) (xy 40.190928 -58.48223) (xy 40.208322 -58.503106) (xy 40.237642 -58.548856)
			(xy 40.260172 -58.598304) (xy 40.275454 -58.650449) (xy 40.279604 -58.679334) (xy 47.995332 -58.679334)
			(xy 47.995745 -58.653018) (xy 48.00299 -58.600887) (xy 48.017319 -58.550243) (xy 48.038461 -58.502044)
			(xy 48.066017 -58.457202) (xy 48.099466 -58.416565) (xy 48.118522 -58.39841) (xy 48.125925 -58.39089)
			(xy 48.134448 -58.371608) (xy 48.135032 -58.361072) (xy 48.135032 -58.286396) (xy 48.134509 -58.275846)
			(xy 48.125968 -58.256551) (xy 48.118522 -58.249058) (xy 48.099457 -58.230912) (xy 48.066 -58.19028)
			(xy 48.038442 -58.145438) (xy 48.017305 -58.097236) (xy 48.00299 -58.046586) (xy 47.995768 -57.994451)
			(xy 47.995332 -57.968134) (xy 47.995818 -57.940883) (xy 48.003574 -57.886935) (xy 48.018929 -57.83464)
			(xy 48.041571 -57.785063) (xy 48.071037 -57.739213) (xy 48.106728 -57.698022) (xy 48.147919 -57.662331)
			(xy 48.193769 -57.632865) (xy 48.243346 -57.610223) (xy 48.295641 -57.594868) (xy 48.349589 -57.587112)
			(xy 48.404091 -57.587112) (xy 48.458039 -57.594868) (xy 48.510334 -57.610223) (xy 48.559911 -57.632865)
			(xy 48.605761 -57.662331) (xy 48.646952 -57.698022) (xy 48.682643 -57.739213) (xy 48.712109 -57.785063)
			(xy 48.734751 -57.83464) (xy 48.750106 -57.886935) (xy 48.757862 -57.940883) (xy 48.758348 -57.968134)
			(xy 48.75792 -57.994449) (xy 48.750679 -58.04658) (xy 48.743411 -58.072274) (xy 51.993544 -58.072274)
			(xy 51.997615 -58.016652) (xy 52.009741 -57.962215) (xy 52.029664 -57.910124) (xy 52.05696 -57.861489)
			(xy 52.091046 -57.817346) (xy 52.131195 -57.778637) (xy 52.176553 -57.746186) (xy 52.226153 -57.720685)
			(xy 52.278937 -57.702678) (xy 52.33378 -57.692548) (xy 52.389514 -57.690511) (xy 52.444951 -57.696611)
			(xy 52.498908 -57.710717) (xy 52.550237 -57.732529) (xy 52.597843 -57.761583) (xy 52.640711 -57.797258)
			(xy 52.677928 -57.838795) (xy 52.708701 -57.885308) (xy 52.732373 -57.935805) (xy 52.748441 -57.989212)
			(xy 52.756561 -58.044388) (xy 52.75707 -58.072274) (xy 52.757 -58.076084) (xy 57.358024 -58.076084)
			(xy 57.362095 -58.020462) (xy 57.374221 -57.966025) (xy 57.394144 -57.913934) (xy 57.42144 -57.865299)
			(xy 57.455526 -57.821156) (xy 57.495675 -57.782447) (xy 57.541033 -57.749996) (xy 57.590633 -57.724495)
			(xy 57.643417 -57.706488) (xy 57.69826 -57.696358) (xy 57.753994 -57.694321) (xy 57.809431 -57.700421)
			(xy 57.863388 -57.714527) (xy 57.914717 -57.736339) (xy 57.962323 -57.765393) (xy 58.005191 -57.801068)
			(xy 58.042408 -57.842605) (xy 58.058744 -57.867296) (xy 59.643008 -57.867296) (xy 59.647079 -57.811674)
			(xy 59.659205 -57.757237) (xy 59.679128 -57.705146) (xy 59.706424 -57.656511) (xy 59.74051 -57.612368)
			(xy 59.780659 -57.573659) (xy 59.826017 -57.541208) (xy 59.875617 -57.515707) (xy 59.928401 -57.4977)
			(xy 59.983244 -57.48757) (xy 60.038978 -57.485533) (xy 60.094415 -57.491633) (xy 60.148372 -57.505739)
			(xy 60.199701 -57.527551) (xy 60.247307 -57.556605) (xy 60.290175 -57.59228) (xy 60.327392 -57.633817)
			(xy 60.358165 -57.68033) (xy 60.381837 -57.730827) (xy 60.397905 -57.784234) (xy 60.406025 -57.83941)
			(xy 60.406534 -57.867296) (xy 60.406025 -57.895182) (xy 60.397905 -57.950358) (xy 60.381837 -58.003765)
			(xy 60.358165 -58.054262) (xy 60.327392 -58.100775) (xy 60.290175 -58.142312) (xy 60.247307 -58.177987)
			(xy 60.199701 -58.207041) (xy 60.148372 -58.228853) (xy 60.094415 -58.242959) (xy 60.038978 -58.249059)
			(xy 59.983244 -58.247022) (xy 59.928401 -58.236892) (xy 59.875617 -58.218885) (xy 59.826017 -58.193384)
			(xy 59.780659 -58.160933) (xy 59.74051 -58.122224) (xy 59.706424 -58.078081) (xy 59.679128 -58.029446)
			(xy 59.659205 -57.977355) (xy 59.647079 -57.922918) (xy 59.643008 -57.867296) (xy 58.058744 -57.867296)
			(xy 58.073181 -57.889118) (xy 58.096853 -57.939615) (xy 58.112921 -57.993022) (xy 58.121041 -58.048198)
			(xy 58.12155 -58.076084) (xy 58.121041 -58.10397) (xy 58.112921 -58.159146) (xy 58.096853 -58.212553)
			(xy 58.073181 -58.26305) (xy 58.042408 -58.309563) (xy 58.005191 -58.3511) (xy 57.962323 -58.386775)
			(xy 57.914717 -58.415829) (xy 57.863388 -58.437641) (xy 57.809431 -58.451747) (xy 57.753994 -58.457847)
			(xy 57.69826 -58.45581) (xy 57.643417 -58.44568) (xy 57.590633 -58.427673) (xy 57.541033 -58.402172)
			(xy 57.495675 -58.369721) (xy 57.455526 -58.331012) (xy 57.42144 -58.286869) (xy 57.394144 -58.238234)
			(xy 57.374221 -58.186143) (xy 57.362095 -58.131706) (xy 57.358024 -58.076084) (xy 52.757 -58.076084)
			(xy 52.756561 -58.10016) (xy 52.748441 -58.155336) (xy 52.732373 -58.208743) (xy 52.708701 -58.25924)
			(xy 52.677928 -58.305753) (xy 52.640711 -58.34729) (xy 52.597843 -58.382965) (xy 52.550237 -58.412019)
			(xy 52.498908 -58.433831) (xy 52.444951 -58.447937) (xy 52.389514 -58.454037) (xy 52.33378 -58.452)
			(xy 52.278937 -58.44187) (xy 52.226153 -58.423863) (xy 52.176553 -58.398362) (xy 52.131195 -58.365911)
			(xy 52.091046 -58.327202) (xy 52.05696 -58.283059) (xy 52.029664 -58.234424) (xy 52.009741 -58.182333)
			(xy 51.997615 -58.127896) (xy 51.993544 -58.072274) (xy 48.743411 -58.072274) (xy 48.736354 -58.097225)
			(xy 48.715214 -58.145424) (xy 48.68766 -58.190266) (xy 48.654213 -58.230903) (xy 48.635158 -58.249058)
			(xy 48.627781 -58.256601) (xy 48.619241 -58.275864) (xy 48.618648 -58.286396) (xy 48.618648 -58.361072)
			(xy 48.619165 -58.371623) (xy 48.627707 -58.39092) (xy 48.635158 -58.39841) (xy 48.654222 -58.416556)
			(xy 48.687677 -58.457189) (xy 48.715233 -58.502032) (xy 48.736369 -58.550234) (xy 48.739475 -58.561224)
			(xy 58.562238 -58.561224) (xy 58.566309 -58.505602) (xy 58.578435 -58.451165) (xy 58.598358 -58.399074)
			(xy 58.625654 -58.350439) (xy 58.65974 -58.306296) (xy 58.699889 -58.267587) (xy 58.745247 -58.235136)
			(xy 58.794847 -58.209635) (xy 58.847631 -58.191628) (xy 58.902474 -58.181498) (xy 58.958208 -58.179461)
			(xy 59.013645 -58.185561) (xy 59.067602 -58.199667) (xy 59.118931 -58.221479) (xy 59.166537 -58.250533)
			(xy 59.209405 -58.286208) (xy 59.246622 -58.327745) (xy 59.277395 -58.374258) (xy 59.301067 -58.424755)
			(xy 59.317135 -58.478162) (xy 59.325255 -58.533338) (xy 59.325764 -58.561224) (xy 59.325255 -58.58911)
			(xy 59.317135 -58.644286) (xy 59.301067 -58.697693) (xy 59.277395 -58.74819) (xy 59.246622 -58.794703)
			(xy 59.209405 -58.83624) (xy 59.166537 -58.871915) (xy 59.118931 -58.900969) (xy 59.067602 -58.922781)
			(xy 59.013645 -58.936887) (xy 58.958208 -58.942987) (xy 58.902474 -58.94095) (xy 58.847631 -58.93082)
			(xy 58.794847 -58.912813) (xy 58.745247 -58.887312) (xy 58.699889 -58.854861) (xy 58.65974 -58.816152)
			(xy 58.625654 -58.772009) (xy 58.598358 -58.723374) (xy 58.578435 -58.671283) (xy 58.566309 -58.616846)
			(xy 58.562238 -58.561224) (xy 48.739475 -58.561224) (xy 48.750685 -58.600883) (xy 48.75791 -58.653018)
			(xy 48.758348 -58.679334) (xy 48.757862 -58.706585) (xy 48.750106 -58.760533) (xy 48.734751 -58.812828)
			(xy 48.712109 -58.862405) (xy 48.682643 -58.908255) (xy 48.646952 -58.949446) (xy 48.605761 -58.985137)
			(xy 48.559911 -59.014603) (xy 48.510334 -59.037245) (xy 48.458039 -59.0526) (xy 48.404091 -59.060356)
			(xy 48.349589 -59.060356) (xy 48.295641 -59.0526) (xy 48.243346 -59.037245) (xy 48.193769 -59.014603)
			(xy 48.147919 -58.985137) (xy 48.106728 -58.949446) (xy 48.071037 -58.908255) (xy 48.041571 -58.862405)
			(xy 48.018929 -58.812828) (xy 48.003574 -58.760533) (xy 47.995818 -58.706585) (xy 47.995332 -58.679334)
			(xy 40.279604 -58.679334) (xy 40.283181 -58.704235) (xy 40.283638 -58.731404) (xy 40.283638 -58.731658)
			(xy 40.28304 -58.761843) (xy 40.273494 -58.821456) (xy 40.254696 -58.878827) (xy 40.227113 -58.932529)
			(xy 40.209724 -58.95721) (xy 40.204136 -58.96483) (xy 40.20185 -58.97245) (xy 40.200676 -58.976729)
			(xy 40.199646 -58.985542) (xy 40.199818 -58.989976) (xy 40.210821 -59.174634) (xy 57.093102 -59.174634)
			(xy 57.097173 -59.119012) (xy 57.109299 -59.064575) (xy 57.129222 -59.012484) (xy 57.156518 -58.963849)
			(xy 57.190604 -58.919706) (xy 57.230753 -58.880997) (xy 57.276111 -58.848546) (xy 57.325711 -58.823045)
			(xy 57.378495 -58.805038) (xy 57.433338 -58.794908) (xy 57.489072 -58.792871) (xy 57.544509 -58.798971)
			(xy 57.598466 -58.813077) (xy 57.649795 -58.834889) (xy 57.697401 -58.863943) (xy 57.740269 -58.899618)
			(xy 57.777486 -58.941155) (xy 57.808259 -58.987668) (xy 57.831931 -59.038165) (xy 57.847999 -59.091572)
			(xy 57.856119 -59.146748) (xy 57.856628 -59.174634) (xy 57.856119 -59.20252) (xy 57.847999 -59.257696)
			(xy 57.831931 -59.311103) (xy 57.808259 -59.3616) (xy 57.777486 -59.408113) (xy 57.740269 -59.44965)
			(xy 57.697401 -59.485325) (xy 57.649795 -59.514379) (xy 57.598466 -59.536191) (xy 57.544509 -59.550297)
			(xy 57.489072 -59.556397) (xy 57.433338 -59.55436) (xy 57.378495 -59.54423) (xy 57.325711 -59.526223)
			(xy 57.276111 -59.500722) (xy 57.230753 -59.468271) (xy 57.190604 -59.429562) (xy 57.156518 -59.385419)
			(xy 57.129222 -59.336784) (xy 57.109299 -59.284693) (xy 57.097173 -59.230256) (xy 57.093102 -59.174634)
			(xy 40.210821 -59.174634) (xy 40.261147 -60.019251) (xy 48.135784 -60.019251) (xy 48.135784 -59.964749)
			(xy 48.14354 -59.910803) (xy 48.158895 -59.85851) (xy 48.181535 -59.808934) (xy 48.211 -59.763084)
			(xy 48.246691 -59.721895) (xy 48.287879 -59.686204) (xy 48.333728 -59.656738) (xy 48.383304 -59.634097)
			(xy 48.435597 -59.618741) (xy 48.489543 -59.610984) (xy 48.516794 -59.610498) (xy 48.544164 -59.610968)
			(xy 48.598343 -59.618785) (xy 48.650846 -59.634273) (xy 48.700593 -59.657114) (xy 48.74656 -59.686837)
			(xy 48.767492 -59.704478) (xy 48.767746 -59.704732) (xy 48.774841 -59.710306) (xy 48.791751 -59.716559)
			(xy 48.800766 -59.716924) (xy 48.867822 -59.716924) (xy 48.876839 -59.716573) (xy 48.893756 -59.710321)
			(xy 48.900842 -59.704732) (xy 48.900842 -59.704478) (xy 48.901096 -59.704478) (xy 48.922029 -59.686837)
			(xy 48.967997 -59.657113) (xy 49.017743 -59.634267) (xy 49.070245 -59.618771) (xy 49.124423 -59.610942)
			(xy 49.179165 -59.610942) (xy 49.233343 -59.618771) (xy 49.285845 -59.634267) (xy 49.335591 -59.657113)
			(xy 49.381559 -59.686837) (xy 49.402492 -59.704478) (xy 49.402746 -59.704732) (xy 49.409841 -59.710306)
			(xy 49.426751 -59.716559) (xy 49.435766 -59.716924) (xy 49.502822 -59.716924) (xy 49.511839 -59.716573)
			(xy 49.528756 -59.710321) (xy 49.535842 -59.704732) (xy 49.535842 -59.704478) (xy 49.536096 -59.704478)
			(xy 49.557016 -59.686824) (xy 49.602992 -59.657115) (xy 49.652743 -59.634282) (xy 49.705246 -59.618795)
			(xy 49.759424 -59.61097) (xy 49.786794 -59.610498) (xy 49.814048 -59.610949) (xy 49.868 -59.618705)
			(xy 49.920299 -59.634061) (xy 49.969881 -59.656704) (xy 50.015736 -59.686172) (xy 50.05693 -59.721866)
			(xy 50.092624 -59.76306) (xy 50.122094 -59.808914) (xy 50.144737 -59.858495) (xy 50.160093 -59.910794)
			(xy 50.167851 -59.964746) (xy 50.167851 -60.019254) (xy 50.160093 -60.073206) (xy 50.144737 -60.125505)
			(xy 50.122094 -60.175086) (xy 50.092624 -60.22094) (xy 50.05693 -60.262134) (xy 50.015736 -60.297828)
			(xy 49.969881 -60.327296) (xy 49.920299 -60.349939) (xy 49.868 -60.365295) (xy 49.814048 -60.373051)
			(xy 49.786794 -60.373514) (xy 49.759424 -60.373048) (xy 49.705245 -60.36523) (xy 49.652742 -60.34974)
			(xy 49.602995 -60.326899) (xy 49.557028 -60.297175) (xy 49.536096 -60.279534) (xy 49.535842 -60.27928)
			(xy 49.528749 -60.273703) (xy 49.511837 -60.267451) (xy 49.502822 -60.267088) (xy 49.435766 -60.267088)
			(xy 49.426748 -60.267431) (xy 49.409831 -60.273688) (xy 49.402746 -60.27928) (xy 49.402492 -60.279534)
			(xy 49.381559 -60.297175) (xy 49.335591 -60.326899) (xy 49.285845 -60.349745) (xy 49.233343 -60.365241)
			(xy 49.179165 -60.37307) (xy 49.124423 -60.37307) (xy 49.070245 -60.365241) (xy 49.017743 -60.349745)
			(xy 48.967997 -60.326899) (xy 48.922029 -60.297175) (xy 48.901096 -60.279534) (xy 48.900842 -60.27928)
			(xy 48.893749 -60.273703) (xy 48.876837 -60.267451) (xy 48.867822 -60.267088) (xy 48.800766 -60.267088)
			(xy 48.791748 -60.267431) (xy 48.774831 -60.273688) (xy 48.767746 -60.27928) (xy 48.767746 -60.279534)
			(xy 48.767492 -60.279534) (xy 48.746578 -60.297196) (xy 48.7006 -60.326903) (xy 48.650848 -60.349734)
			(xy 48.598343 -60.36522) (xy 48.544164 -60.373043) (xy 48.516794 -60.373514) (xy 48.489543 -60.373016)
			(xy 48.435597 -60.365259) (xy 48.383304 -60.349903) (xy 48.333728 -60.327262) (xy 48.287879 -60.297796)
			(xy 48.246691 -60.262105) (xy 48.211 -60.220916) (xy 48.181535 -60.175066) (xy 48.158895 -60.12549)
			(xy 48.14354 -60.073197) (xy 48.135784 -60.019251) (xy 40.261147 -60.019251) (xy 40.297738 -60.633356)
			(xy 59.796932 -60.633356) (xy 59.801003 -60.577734) (xy 59.813129 -60.523297) (xy 59.833052 -60.471206)
			(xy 59.860348 -60.422571) (xy 59.894434 -60.378428) (xy 59.934583 -60.339719) (xy 59.979941 -60.307268)
			(xy 60.029541 -60.281767) (xy 60.082325 -60.26376) (xy 60.137168 -60.25363) (xy 60.192902 -60.251593)
			(xy 60.248339 -60.257693) (xy 60.302296 -60.271799) (xy 60.353625 -60.293611) (xy 60.401231 -60.322665)
			(xy 60.444099 -60.35834) (xy 60.481316 -60.399877) (xy 60.512089 -60.44639) (xy 60.535761 -60.496887)
			(xy 60.551829 -60.550294) (xy 60.559949 -60.60547) (xy 60.560458 -60.633356) (xy 60.559949 -60.661242)
			(xy 60.551829 -60.716418) (xy 60.535761 -60.769825) (xy 60.512089 -60.820322) (xy 60.481316 -60.866835)
			(xy 60.444099 -60.908372) (xy 60.401231 -60.944047) (xy 60.353625 -60.973101) (xy 60.302296 -60.994913)
			(xy 60.248339 -61.009019) (xy 60.192902 -61.015119) (xy 60.137168 -61.013082) (xy 60.082325 -61.002952)
			(xy 60.029541 -60.984945) (xy 59.979941 -60.959444) (xy 59.934583 -60.926993) (xy 59.894434 -60.888284)
			(xy 59.860348 -60.844141) (xy 59.833052 -60.795506) (xy 59.813129 -60.743415) (xy 59.801003 -60.688978)
			(xy 59.796932 -60.633356) (xy 40.297738 -60.633356) (xy 40.348651 -61.487812) (xy 58.304428 -61.487812)
			(xy 58.308499 -61.43219) (xy 58.320625 -61.377753) (xy 58.340548 -61.325662) (xy 58.367844 -61.277027)
			(xy 58.40193 -61.232884) (xy 58.442079 -61.194175) (xy 58.487437 -61.161724) (xy 58.537037 -61.136223)
			(xy 58.589821 -61.118216) (xy 58.644664 -61.108086) (xy 58.700398 -61.106049) (xy 58.755835 -61.112149)
			(xy 58.809792 -61.126255) (xy 58.861121 -61.148067) (xy 58.908727 -61.177121) (xy 58.951595 -61.212796)
			(xy 58.988812 -61.254333) (xy 59.019585 -61.300846) (xy 59.043257 -61.351343) (xy 59.059325 -61.40475)
			(xy 59.067445 -61.459926) (xy 59.067954 -61.487812) (xy 59.067445 -61.515698) (xy 59.059325 -61.570874)
			(xy 59.043257 -61.624281) (xy 59.019585 -61.674778) (xy 58.988812 -61.721291) (xy 58.951595 -61.762828)
			(xy 58.908727 -61.798503) (xy 58.861121 -61.827557) (xy 58.809792 -61.849369) (xy 58.755835 -61.863475)
			(xy 58.700398 -61.869575) (xy 58.644664 -61.867538) (xy 58.589821 -61.857408) (xy 58.537037 -61.839401)
			(xy 58.487437 -61.8139) (xy 58.442079 -61.781449) (xy 58.40193 -61.74274) (xy 58.367844 -61.698597)
			(xy 58.340548 -61.649962) (xy 58.320625 -61.597871) (xy 58.308499 -61.543434) (xy 58.304428 -61.487812)
			(xy 40.348651 -61.487812) (xy 40.38346 -62.072012) (xy 40.384834 -62.121034) (xy 56.242202 -62.121034)
			(xy 56.246273 -62.065412) (xy 56.258399 -62.010975) (xy 56.278322 -61.958884) (xy 56.305618 -61.910249)
			(xy 56.339704 -61.866106) (xy 56.379853 -61.827397) (xy 56.425211 -61.794946) (xy 56.474811 -61.769445)
			(xy 56.527595 -61.751438) (xy 56.582438 -61.741308) (xy 56.638172 -61.739271) (xy 56.693609 -61.745371)
			(xy 56.747566 -61.759477) (xy 56.798895 -61.781289) (xy 56.846501 -61.810343) (xy 56.889369 -61.846018)
			(xy 56.926586 -61.887555) (xy 56.957359 -61.934068) (xy 56.981031 -61.984565) (xy 56.997099 -62.037972)
			(xy 57.005219 -62.093148) (xy 57.005728 -62.121034) (xy 57.005219 -62.14892) (xy 56.997099 -62.204096)
			(xy 56.981031 -62.257503) (xy 56.957359 -62.308) (xy 56.926586 -62.354513) (xy 56.889369 -62.39605)
			(xy 56.846501 -62.431725) (xy 56.798895 -62.460779) (xy 56.747566 -62.482591) (xy 56.693609 -62.496697)
			(xy 56.638172 -62.502797) (xy 56.582438 -62.50076) (xy 56.527595 -62.49063) (xy 56.474811 -62.472623)
			(xy 56.425211 -62.447122) (xy 56.379853 -62.414671) (xy 56.339704 -62.375962) (xy 56.305618 -62.331819)
			(xy 56.278322 -62.283184) (xy 56.258399 -62.231093) (xy 56.246273 -62.176656) (xy 56.242202 -62.121034)
			(xy 40.384834 -62.121034) (xy 40.384984 -62.126368) (xy 40.389556 -63.02502) (xy 40.389556 -63.026036)
			(xy 40.390572 -63.074804) (xy 40.390572 -63.075566) (xy 40.38981 -63.110364) (xy 40.38981 -63.112396)
			(xy 40.390308 -63.213553) (xy 48.120765 -63.213553) (xy 48.120765 -63.159047) (xy 48.128522 -63.105097)
			(xy 48.143878 -63.0528) (xy 48.166521 -63.003221) (xy 48.195989 -62.957369) (xy 48.231682 -62.916177)
			(xy 48.272875 -62.880484) (xy 48.318728 -62.851017) (xy 48.368308 -62.828376) (xy 48.420605 -62.813021)
			(xy 48.474555 -62.805265) (xy 48.501808 -62.804802) (xy 48.529178 -62.805263) (xy 48.583358 -62.813082)
			(xy 48.635861 -62.828572) (xy 48.685608 -62.851415) (xy 48.731574 -62.88114) (xy 48.752506 -62.898782)
			(xy 48.75276 -62.899036) (xy 48.759851 -62.904616) (xy 48.776765 -62.910866) (xy 48.78578 -62.911228)
			(xy 48.852836 -62.911228) (xy 48.861854 -62.910882) (xy 48.87877 -62.904626) (xy 48.885856 -62.899036)
			(xy 48.885856 -62.898782) (xy 48.88611 -62.898782) (xy 48.907043 -62.881141) (xy 48.953011 -62.851417)
			(xy 49.002757 -62.828571) (xy 49.055259 -62.813075) (xy 49.109437 -62.805246) (xy 49.164179 -62.805246)
			(xy 49.218357 -62.813075) (xy 49.270859 -62.828571) (xy 49.320605 -62.851417) (xy 49.366573 -62.881141)
			(xy 49.387506 -62.898782) (xy 49.38776 -62.899036) (xy 49.394851 -62.904616) (xy 49.411765 -62.910866)
			(xy 49.42078 -62.911228) (xy 49.487836 -62.911228) (xy 49.496854 -62.910882) (xy 49.51377 -62.904626)
			(xy 49.520856 -62.899036) (xy 49.520856 -62.898782) (xy 49.52111 -62.898782) (xy 49.542025 -62.881122)
			(xy 49.588003 -62.851414) (xy 49.637755 -62.828582) (xy 49.690259 -62.813096) (xy 49.744438 -62.805273)
			(xy 49.771808 -62.804802) (xy 49.79906 -62.805268) (xy 49.853008 -62.813026) (xy 49.905303 -62.828382)
			(xy 49.954881 -62.851024) (xy 50.000731 -62.880492) (xy 50.041922 -62.916184) (xy 50.077613 -62.957375)
			(xy 50.107079 -63.003226) (xy 50.129721 -63.052804) (xy 50.139537 -63.086234) (xy 53.387496 -63.086234)
			(xy 53.391567 -63.030612) (xy 53.403693 -62.976175) (xy 53.423616 -62.924084) (xy 53.450912 -62.875449)
			(xy 53.484998 -62.831306) (xy 53.525147 -62.792597) (xy 53.570505 -62.760146) (xy 53.620105 -62.734645)
			(xy 53.672889 -62.716638) (xy 53.727732 -62.706508) (xy 53.783466 -62.704471) (xy 53.838903 -62.710571)
			(xy 53.89286 -62.724677) (xy 53.944189 -62.746489) (xy 53.991795 -62.775543) (xy 54.034663 -62.811218)
			(xy 54.07188 -62.852755) (xy 54.102653 -62.899268) (xy 54.126325 -62.949765) (xy 54.142393 -63.003172)
			(xy 54.150513 -63.058348) (xy 54.151022 -63.086234) (xy 54.150513 -63.11412) (xy 54.142393 -63.169296)
			(xy 54.126325 -63.222703) (xy 54.102653 -63.2732) (xy 54.1025 -63.273432) (xy 55.576722 -63.273432)
			(xy 55.580793 -63.21781) (xy 55.592919 -63.163373) (xy 55.612842 -63.111282) (xy 55.640138 -63.062647)
			(xy 55.674224 -63.018504) (xy 55.714373 -62.979795) (xy 55.759731 -62.947344) (xy 55.809331 -62.921843)
			(xy 55.862115 -62.903836) (xy 55.916958 -62.893706) (xy 55.972692 -62.891669) (xy 56.028129 -62.897769)
			(xy 56.082086 -62.911875) (xy 56.133415 -62.933687) (xy 56.181021 -62.962741) (xy 56.223889 -62.998416)
			(xy 56.261106 -63.039953) (xy 56.291879 -63.086466) (xy 56.315551 -63.136963) (xy 56.331619 -63.19037)
			(xy 56.339739 -63.245546) (xy 56.340248 -63.273432) (xy 56.339739 -63.301318) (xy 56.331619 -63.356494)
			(xy 56.315551 -63.409901) (xy 56.291879 -63.460398) (xy 56.261106 -63.506911) (xy 56.223889 -63.548448)
			(xy 56.181021 -63.584123) (xy 56.133415 -63.613177) (xy 56.082086 -63.634989) (xy 56.028129 -63.649095)
			(xy 55.972692 -63.655195) (xy 55.916958 -63.653158) (xy 55.862115 -63.643028) (xy 55.809331 -63.625021)
			(xy 55.759731 -63.59952) (xy 55.714373 -63.567069) (xy 55.674224 -63.52836) (xy 55.640138 -63.484217)
			(xy 55.612842 -63.435582) (xy 55.592919 -63.383491) (xy 55.580793 -63.329054) (xy 55.576722 -63.273432)
			(xy 54.1025 -63.273432) (xy 54.07188 -63.319713) (xy 54.034663 -63.36125) (xy 53.991795 -63.396925)
			(xy 53.944189 -63.425979) (xy 53.89286 -63.447791) (xy 53.838903 -63.461897) (xy 53.783466 -63.467997)
			(xy 53.727732 -63.46596) (xy 53.672889 -63.45583) (xy 53.620105 -63.437823) (xy 53.570505 -63.412322)
			(xy 53.525147 -63.379871) (xy 53.484998 -63.341162) (xy 53.450912 -63.297019) (xy 53.423616 -63.248384)
			(xy 53.403693 -63.196293) (xy 53.391567 -63.141856) (xy 53.387496 -63.086234) (xy 50.139537 -63.086234)
			(xy 50.145076 -63.1051) (xy 50.152832 -63.159048) (xy 50.152832 -63.213552) (xy 50.145076 -63.2675)
			(xy 50.129721 -63.319796) (xy 50.107079 -63.369374) (xy 50.077613 -63.415225) (xy 50.041922 -63.456416)
			(xy 50.000731 -63.492108) (xy 49.954881 -63.521576) (xy 49.905303 -63.544218) (xy 49.853008 -63.559574)
			(xy 49.79906 -63.567332) (xy 49.771808 -63.567818) (xy 49.744437 -63.567367) (xy 49.690256 -63.559549)
			(xy 49.637752 -63.544057) (xy 49.588006 -63.521212) (xy 49.54204 -63.491482) (xy 49.52111 -63.473838)
			(xy 49.520856 -63.473584) (xy 49.513759 -63.468013) (xy 49.49685 -63.461757) (xy 49.487836 -63.461392)
			(xy 49.42078 -63.461392) (xy 49.411762 -63.461741) (xy 49.394846 -63.467995) (xy 49.38776 -63.473584)
			(xy 49.387506 -63.473838) (xy 49.366573 -63.491479) (xy 49.320605 -63.521203) (xy 49.270859 -63.544049)
			(xy 49.218357 -63.559545) (xy 49.164179 -63.567374) (xy 49.109437 -63.567374) (xy 49.055259 -63.559545)
			(xy 49.002757 -63.544049) (xy 48.953011 -63.521203) (xy 48.907043 -63.491479) (xy 48.88611 -63.473838)
			(xy 48.885856 -63.473584) (xy 48.878759 -63.468013) (xy 48.86185 -63.461757) (xy 48.852836 -63.461392)
			(xy 48.78578 -63.461392) (xy 48.776762 -63.461741) (xy 48.759846 -63.467995) (xy 48.75276 -63.473584)
			(xy 48.75276 -63.473838) (xy 48.752506 -63.473838) (xy 48.731588 -63.491494) (xy 48.685611 -63.521202)
			(xy 48.635859 -63.544034) (xy 48.583356 -63.559522) (xy 48.529178 -63.567346) (xy 48.501808 -63.567818)
			(xy 48.474555 -63.567335) (xy 48.420605 -63.559579) (xy 48.368308 -63.544224) (xy 48.318728 -63.521583)
			(xy 48.272875 -63.492116) (xy 48.231682 -63.456423) (xy 48.195989 -63.415231) (xy 48.166521 -63.369379)
			(xy 48.143878 -63.3198) (xy 48.128522 -63.267503) (xy 48.120765 -63.213553) (xy 40.390308 -63.213553)
			(xy 40.395713 -64.312292) (xy 58.9059 -64.312292) (xy 58.909971 -64.25667) (xy 58.922097 -64.202233)
			(xy 58.94202 -64.150142) (xy 58.969316 -64.101507) (xy 59.003402 -64.057364) (xy 59.043551 -64.018655)
			(xy 59.088909 -63.986204) (xy 59.138509 -63.960703) (xy 59.191293 -63.942696) (xy 59.246136 -63.932566)
			(xy 59.30187 -63.930529) (xy 59.357307 -63.936629) (xy 59.411264 -63.950735) (xy 59.462593 -63.972547)
			(xy 59.510199 -64.001601) (xy 59.553067 -64.037276) (xy 59.590284 -64.078813) (xy 59.621057 -64.125326)
			(xy 59.644729 -64.175823) (xy 59.660797 -64.22923) (xy 59.668917 -64.284406) (xy 59.669426 -64.312292)
			(xy 59.668917 -64.340178) (xy 59.660797 -64.395354) (xy 59.644729 -64.448761) (xy 59.621057 -64.499258)
			(xy 59.590284 -64.545771) (xy 59.553067 -64.587308) (xy 59.510199 -64.622983) (xy 59.462593 -64.652037)
			(xy 59.411264 -64.673849) (xy 59.357307 -64.687955) (xy 59.30187 -64.694055) (xy 59.246136 -64.692018)
			(xy 59.191293 -64.681888) (xy 59.138509 -64.663881) (xy 59.088909 -64.63838) (xy 59.043551 -64.605929)
			(xy 59.003402 -64.56722) (xy 58.969316 -64.523077) (xy 58.94202 -64.474442) (xy 58.922097 -64.422351)
			(xy 58.909971 -64.367914) (xy 58.9059 -64.312292) (xy 40.395713 -64.312292) (xy 40.399592 -65.100962)
			(xy 46.132494 -65.100962) (xy 46.136565 -65.04534) (xy 46.148691 -64.990903) (xy 46.168614 -64.938812)
			(xy 46.19591 -64.890177) (xy 46.229996 -64.846034) (xy 46.270145 -64.807325) (xy 46.315503 -64.774874)
			(xy 46.365103 -64.749373) (xy 46.417887 -64.731366) (xy 46.47273 -64.721236) (xy 46.528464 -64.719199)
			(xy 46.583901 -64.725299) (xy 46.637858 -64.739405) (xy 46.689187 -64.761217) (xy 46.736793 -64.790271)
			(xy 46.779661 -64.825946) (xy 46.816878 -64.867483) (xy 46.847651 -64.913996) (xy 46.871323 -64.964493)
			(xy 46.887391 -65.0179) (xy 46.895511 -65.073076) (xy 46.89602 -65.100962) (xy 46.895511 -65.128848)
			(xy 46.887391 -65.184024) (xy 46.871323 -65.237431) (xy 46.847651 -65.287928) (xy 46.816878 -65.334441)
			(xy 46.779661 -65.375978) (xy 46.736793 -65.411653) (xy 46.689187 -65.440707) (xy 46.637858 -65.462519)
			(xy 46.583901 -65.476625) (xy 46.528464 -65.482725) (xy 46.47273 -65.480688) (xy 46.417887 -65.470558)
			(xy 46.365103 -65.452551) (xy 46.315503 -65.42705) (xy 46.270145 -65.394599) (xy 46.229996 -65.35589)
			(xy 46.19591 -65.311747) (xy 46.168614 -65.263112) (xy 46.148691 -65.211021) (xy 46.136565 -65.156584)
			(xy 46.132494 -65.100962) (xy 40.399592 -65.100962) (xy 40.400732 -65.33261) (xy 40.402207 -65.344471)
			(xy 40.414403 -65.364991) (xy 40.4241 -65.37198) (xy 40.501824 -65.418208) (xy 40.507376 -65.421083)
			(xy 40.519453 -65.424304) (xy 40.5257 -65.424558) (xy 40.543988 -65.419986) (xy 40.554656 -65.415922)
			(xy 40.581697 -65.40273) (xy 40.638896 -65.384072) (xy 40.69831 -65.374603) (xy 40.728392 -65.374012)
			(xy 40.731948 -65.374012) (xy 40.759047 -65.374718) (xy 40.812643 -65.382848) (xy 40.864548 -65.398483)
			(xy 40.913717 -65.421307) (xy 40.95916 -65.450862) (xy 40.999962 -65.486552) (xy 41.035301 -65.527658)
			(xy 41.064465 -65.573353) (xy 41.086868 -65.622716) (xy 41.102057 -65.674753) (xy 41.109728 -65.728416)
			(xy 41.110154 -65.75552) (xy 41.109667 -65.782772) (xy 41.101908 -65.83672) (xy 41.086552 -65.889015)
			(xy 41.06391 -65.938592) (xy 41.034444 -65.984443) (xy 40.998753 -66.025635) (xy 40.957564 -66.061329)
			(xy 40.911715 -66.090798) (xy 40.862139 -66.113443) (xy 40.809845 -66.128803) (xy 40.755897 -66.136565)
			(xy 40.728646 -66.137028) (xy 40.727884 -66.137028) (xy 40.697653 -66.136431) (xy 40.637956 -66.126843)
			(xy 40.580524 -66.107944) (xy 40.553386 -66.09461) (xy 40.553132 -66.094356) (xy 40.552878 -66.094102)
			(xy 40.547097 -66.091373) (xy 40.534633 -66.088542) (xy 40.52824 -66.088514) (xy 40.514778 -66.089022)
			(xy 40.428926 -66.141346) (xy 40.421691 -66.146229) (xy 40.410774 -66.159835) (xy 40.405042 -66.17631)
			(xy 40.404796 -66.185034) (xy 40.405558 -66.37274) (xy 40.405812 -66.402458) (xy 40.407082 -66.685668)
			(xy 40.408543 -66.697339) (xy 40.420442 -66.717599) (xy 40.429942 -66.72453) (xy 40.432482 -66.726054)
			(xy 40.444928 -66.733166) (xy 40.497506 -66.763392) (xy 40.503383 -66.766537) (xy 40.516245 -66.770017)
			(xy 40.522906 -66.77025) (xy 40.558466 -66.77025) (xy 40.568118 -66.76517) (xy 40.595922 -66.751038)
			(xy 40.654984 -66.73101) (xy 40.716514 -66.720836) (xy 40.747696 -66.720212) (xy 40.77374 -66.720675)
			(xy 40.825338 -66.727798) (xy 40.875489 -66.741873) (xy 40.92326 -66.762636) (xy 40.967763 -66.789704)
			(xy 40.988234 -66.80581) (xy 40.98925 -66.806318) (xy 40.992044 -66.808604) (xy 41.008046 -66.814192)
			(xy 41.049448 -66.814192) (xy 41.049448 -66.826638) (xy 41.098978 -66.826638) (xy 41.103804 -66.826384)
			(xy 41.111216 -66.825416) (xy 41.125034 -66.819735) (xy 41.130982 -66.815208) (xy 41.131998 -66.814192)
			(xy 41.152929 -66.79655) (xy 41.198896 -66.766825) (xy 41.248643 -66.743982) (xy 41.301146 -66.728491)
			(xy 41.355326 -66.720673) (xy 41.382696 -66.720212) (xy 41.409948 -66.720675) (xy 41.463896 -66.728431)
			(xy 41.516192 -66.743786) (xy 41.56577 -66.766427) (xy 41.611621 -66.795893) (xy 41.652812 -66.831585)
			(xy 41.688504 -66.872776) (xy 41.717971 -66.918627) (xy 41.740613 -66.968205) (xy 41.755968 -67.0205)
			(xy 41.763725 -67.074448) (xy 41.763725 -67.128952) (xy 41.755968 -67.1829) (xy 41.740613 -67.235195)
			(xy 41.717971 -67.284773) (xy 41.688504 -67.330624) (xy 41.652812 -67.371815) (xy 41.611621 -67.407507)
			(xy 41.56577 -67.436973) (xy 41.516192 -67.459614) (xy 41.463896 -67.474969) (xy 41.409948 -67.482725)
			(xy 41.382696 -67.483228) (xy 41.356652 -67.482765) (xy 41.305054 -67.475641) (xy 41.254903 -67.461567)
			(xy 41.207131 -67.440804) (xy 41.162627 -67.413738) (xy 41.142158 -67.39763) (xy 41.141142 -67.397122)
			(xy 41.138348 -67.394836) (xy 41.122346 -67.389248) (xy 41.080944 -67.389248) (xy 41.080944 -67.376802)
			(xy 41.031414 -67.376802) (xy 41.026588 -67.377056) (xy 41.019175 -67.378023) (xy 41.005355 -67.3837)
			(xy 40.99941 -67.388232) (xy 40.998394 -67.389248) (xy 40.977464 -67.406892) (xy 40.931498 -67.436621)
			(xy 40.881751 -67.459467) (xy 40.829247 -67.474958) (xy 40.775067 -67.482777) (xy 40.747696 -67.483228)
			(xy 40.747442 -67.483228) (xy 40.715825 -67.482581) (xy 40.653461 -67.472113) (xy 40.593671 -67.451521)
			(xy 40.565578 -67.437) (xy 40.562022 -67.435222) (xy 40.554454 -67.431325) (xy 40.53771 -67.428314)
			(xy 40.520909 -67.430989) (xy 40.513254 -67.434714) (xy 40.434514 -67.48145) (xy 40.427554 -67.486342)
			(xy 40.426223 -67.488054) (xy 44.779182 -67.488054) (xy 44.783253 -67.432432) (xy 44.795379 -67.377995)
			(xy 44.815302 -67.325904) (xy 44.842598 -67.277269) (xy 44.876684 -67.233126) (xy 44.916833 -67.194417)
			(xy 44.962191 -67.161966) (xy 45.011791 -67.136465) (xy 45.064575 -67.118458) (xy 45.119418 -67.108328)
			(xy 45.175152 -67.106291) (xy 45.230589 -67.112391) (xy 45.284546 -67.126497) (xy 45.335875 -67.148309)
			(xy 45.383481 -67.177363) (xy 45.426349 -67.213038) (xy 45.463566 -67.254575) (xy 45.494339 -67.301088)
			(xy 45.518011 -67.351585) (xy 45.534079 -67.404992) (xy 45.542199 -67.460168) (xy 45.542708 -67.488054)
			(xy 45.542199 -67.51594) (xy 45.539014 -67.537584) (xy 46.07128 -67.537584) (xy 46.075351 -67.481962)
			(xy 46.087477 -67.427525) (xy 46.1074 -67.375434) (xy 46.134696 -67.326799) (xy 46.168782 -67.282656)
			(xy 46.208931 -67.243947) (xy 46.254289 -67.211496) (xy 46.303889 -67.185995) (xy 46.356673 -67.167988)
			(xy 46.411516 -67.157858) (xy 46.46725 -67.155821) (xy 46.522687 -67.161921) (xy 46.576644 -67.176027)
			(xy 46.627973 -67.197839) (xy 46.675579 -67.226893) (xy 46.718447 -67.262568) (xy 46.755664 -67.304105)
			(xy 46.786437 -67.350618) (xy 46.810109 -67.401115) (xy 46.826177 -67.454522) (xy 46.834297 -67.509698)
			(xy 46.834806 -67.537584) (xy 46.834297 -67.56547) (xy 46.830252 -67.592956) (xy 47.345344 -67.592956)
			(xy 47.349415 -67.537334) (xy 47.361541 -67.482897) (xy 47.381464 -67.430806) (xy 47.40876 -67.382171)
			(xy 47.442846 -67.338028) (xy 47.482995 -67.299319) (xy 47.528353 -67.266868) (xy 47.577953 -67.241367)
			(xy 47.630737 -67.22336) (xy 47.68558 -67.21323) (xy 47.741314 -67.211193) (xy 47.796751 -67.217293)
			(xy 47.850708 -67.231399) (xy 47.902037 -67.253211) (xy 47.949643 -67.282265) (xy 47.992511 -67.31794)
			(xy 48.029728 -67.359477) (xy 48.060501 -67.40599) (xy 48.084173 -67.456487) (xy 48.100241 -67.509894)
			(xy 48.108358 -67.565048) (xy 50.446716 -67.565048) (xy 50.446716 -67.510552) (xy 50.454472 -67.456611)
			(xy 50.469824 -67.404323) (xy 50.492462 -67.354751) (xy 50.521924 -67.308906) (xy 50.557611 -67.267721)
			(xy 50.598795 -67.232033) (xy 50.644639 -67.202569) (xy 50.69421 -67.179929) (xy 50.746497 -67.164574)
			(xy 50.800438 -67.156817) (xy 50.827686 -67.15633) (xy 50.855056 -67.156797) (xy 50.909236 -67.164613)
			(xy 50.961739 -67.180102) (xy 51.011486 -67.202944) (xy 51.057453 -67.232668) (xy 51.078384 -67.25031)
			(xy 51.078638 -67.250564) (xy 51.085733 -67.256138) (xy 51.102643 -67.262391) (xy 51.111658 -67.262756)
			(xy 51.178714 -67.262756) (xy 51.187733 -67.262415) (xy 51.20465 -67.256158) (xy 51.211734 -67.250564)
			(xy 51.211734 -67.25031) (xy 51.211988 -67.25031) (xy 51.232915 -67.232665) (xy 51.278889 -67.202953)
			(xy 51.328638 -67.180118) (xy 51.38114 -67.164629) (xy 51.435316 -67.156803) (xy 51.462686 -67.15633)
			(xy 51.489942 -67.156716) (xy 51.5439 -67.164472) (xy 51.596205 -67.179828) (xy 51.645792 -67.202472)
			(xy 51.691651 -67.231943) (xy 51.73285 -67.26764) (xy 51.768549 -67.308837) (xy 51.798021 -67.354696)
			(xy 51.820667 -67.404282) (xy 51.836025 -67.456586) (xy 51.843783 -67.510544) (xy 51.843783 -67.565056)
			(xy 51.836025 -67.619014) (xy 51.820667 -67.671318) (xy 51.798021 -67.720904) (xy 51.768549 -67.766763)
			(xy 51.73285 -67.80796) (xy 51.691651 -67.843657) (xy 51.645792 -67.873128) (xy 51.596205 -67.895772)
			(xy 51.5439 -67.911128) (xy 51.489942 -67.918884) (xy 51.462686 -67.919346) (xy 51.435315 -67.918901)
			(xy 51.381134 -67.91108) (xy 51.32863 -67.895587) (xy 51.278884 -67.87274) (xy 51.232918 -67.84301)
			(xy 51.211988 -67.825366) (xy 51.211734 -67.825112) (xy 51.204641 -67.819535) (xy 51.187729 -67.813282)
			(xy 51.178714 -67.81292) (xy 51.111658 -67.81292) (xy 51.102643 -67.813301) (xy 51.085726 -67.819531)
			(xy 51.078638 -67.825112) (xy 51.078638 -67.825366) (xy 51.078384 -67.825366) (xy 51.057427 -67.842974)
			(xy 51.011461 -67.872692) (xy 50.96172 -67.895534) (xy 50.909225 -67.911032) (xy 50.855054 -67.918868)
			(xy 50.827686 -67.919346) (xy 50.800438 -67.918783) (xy 50.746497 -67.911026) (xy 50.69421 -67.895671)
			(xy 50.644639 -67.873031) (xy 50.598795 -67.843567) (xy 50.557611 -67.807879) (xy 50.521924 -67.766694)
			(xy 50.492462 -67.720849) (xy 50.469824 -67.671277) (xy 50.454472 -67.618989) (xy 50.446716 -67.565048)
			(xy 48.108358 -67.565048) (xy 48.108361 -67.56507) (xy 48.10887 -67.592956) (xy 48.108361 -67.620842)
			(xy 48.100241 -67.676018) (xy 48.084173 -67.729425) (xy 48.060501 -67.779922) (xy 48.029728 -67.826435)
			(xy 47.992511 -67.867972) (xy 47.949643 -67.903647) (xy 47.902037 -67.932701) (xy 47.850708 -67.954513)
			(xy 47.796751 -67.968619) (xy 47.741314 -67.974719) (xy 47.68558 -67.972682) (xy 47.630737 -67.962552)
			(xy 47.577953 -67.944545) (xy 47.528353 -67.919044) (xy 47.482995 -67.886593) (xy 47.442846 -67.847884)
			(xy 47.40876 -67.803741) (xy 47.381464 -67.755106) (xy 47.361541 -67.703015) (xy 47.349415 -67.648578)
			(xy 47.345344 -67.592956) (xy 46.830252 -67.592956) (xy 46.826177 -67.620646) (xy 46.810109 -67.674053)
			(xy 46.786437 -67.72455) (xy 46.755664 -67.771063) (xy 46.718447 -67.8126) (xy 46.675579 -67.848275)
			(xy 46.627973 -67.877329) (xy 46.576644 -67.899141) (xy 46.522687 -67.913247) (xy 46.46725 -67.919347)
			(xy 46.411516 -67.91731) (xy 46.356673 -67.90718) (xy 46.303889 -67.889173) (xy 46.254289 -67.863672)
			(xy 46.208931 -67.831221) (xy 46.168782 -67.792512) (xy 46.134696 -67.748369) (xy 46.1074 -67.699734)
			(xy 46.087477 -67.647643) (xy 46.075351 -67.593206) (xy 46.07128 -67.537584) (xy 45.539014 -67.537584)
			(xy 45.534079 -67.571116) (xy 45.518011 -67.624523) (xy 45.494339 -67.67502) (xy 45.463566 -67.721533)
			(xy 45.426349 -67.76307) (xy 45.383481 -67.798745) (xy 45.335875 -67.827799) (xy 45.284546 -67.849611)
			(xy 45.230589 -67.863717) (xy 45.175152 -67.869817) (xy 45.119418 -67.86778) (xy 45.064575 -67.85765)
			(xy 45.011791 -67.839643) (xy 44.962191 -67.814142) (xy 44.916833 -67.781691) (xy 44.876684 -67.742982)
			(xy 44.842598 -67.698839) (xy 44.815302 -67.650204) (xy 44.795379 -67.598113) (xy 44.783253 -67.543676)
			(xy 44.779182 -67.488054) (xy 40.426223 -67.488054) (xy 40.417117 -67.499764) (xy 40.411675 -67.515872)
			(xy 40.4114 -67.524376) (xy 40.416537 -68.586604) (xy 42.625264 -68.586604) (xy 42.625717 -68.559233)
			(xy 42.633535 -68.505053) (xy 42.649027 -68.452549) (xy 42.671872 -68.402802) (xy 42.701601 -68.356837)
			(xy 42.719244 -68.335906) (xy 42.719498 -68.335652) (xy 42.725069 -68.328555) (xy 42.731325 -68.311646)
			(xy 42.73169 -68.302632) (xy 42.73169 -68.235576) (xy 42.731347 -68.226558) (xy 42.72509 -68.209641)
			(xy 42.719498 -68.202556) (xy 42.719244 -68.202556) (xy 42.719244 -68.202302) (xy 42.701599 -68.181374)
			(xy 42.671887 -68.135401) (xy 42.649051 -68.085652) (xy 42.633562 -68.033151) (xy 42.625736 -67.978974)
			(xy 42.625264 -67.951604) (xy 42.625781 -67.924354) (xy 42.633537 -67.870409) (xy 42.64889 -67.818117)
			(xy 42.671529 -67.768541) (xy 42.700992 -67.722692) (xy 42.73668 -67.681503) (xy 42.777866 -67.645811)
			(xy 42.823713 -67.616344) (xy 42.873287 -67.593701) (xy 42.925578 -67.578343) (xy 42.979522 -67.570584)
			(xy 43.006772 -67.570096) (xy 43.033088 -67.570517) (xy 43.085218 -67.577761) (xy 43.135862 -67.59209)
			(xy 43.18406 -67.613231) (xy 43.228903 -67.640785) (xy 43.269541 -67.674231) (xy 43.287696 -67.693286)
			(xy 43.295219 -67.700686) (xy 43.314498 -67.709212) (xy 43.325034 -67.709796) (xy 43.39971 -67.709796)
			(xy 43.410262 -67.709287) (xy 43.429557 -67.700738) (xy 43.437048 -67.693286) (xy 43.455184 -67.674212)
			(xy 43.495819 -67.640757) (xy 43.540663 -67.6132) (xy 43.588867 -67.592065) (xy 43.639518 -67.577752)
			(xy 43.691655 -67.570532) (xy 43.717972 -67.570096) (xy 43.745342 -67.570579) (xy 43.79952 -67.578393)
			(xy 43.852023 -67.593878) (xy 43.90177 -67.616716) (xy 43.947738 -67.646437) (xy 43.96867 -67.664076)
			(xy 43.968924 -67.66433) (xy 43.975997 -67.669936) (xy 43.992924 -67.67617) (xy 44.001944 -67.676522)
			(xy 44.069 -67.676522) (xy 44.078016 -67.67616) (xy 44.094933 -67.669915) (xy 44.10202 -67.66433)
			(xy 44.10202 -67.664076) (xy 44.102274 -67.664076) (xy 44.123202 -67.646432) (xy 44.169176 -67.616722)
			(xy 44.218925 -67.593887) (xy 44.271426 -67.578397) (xy 44.325603 -67.57057) (xy 44.352972 -67.570096)
			(xy 44.380224 -67.570581) (xy 44.434175 -67.578335) (xy 44.486472 -67.593687) (xy 44.536053 -67.616327)
			(xy 44.581906 -67.645792) (xy 44.623099 -67.681484) (xy 44.658793 -67.722675) (xy 44.688262 -67.768526)
			(xy 44.710904 -67.818105) (xy 44.72626 -67.870402) (xy 44.734017 -67.924352) (xy 44.73448 -67.951604)
			(xy 44.734021 -67.978975) (xy 44.726202 -68.033154) (xy 44.710712 -68.085658) (xy 44.687868 -68.135404)
			(xy 44.658142 -68.181371) (xy 44.6405 -68.202302) (xy 44.640246 -68.202556) (xy 44.634665 -68.209646)
			(xy 44.628416 -68.22656) (xy 44.628054 -68.235576) (xy 44.628054 -68.302632) (xy 44.628384 -68.311652)
			(xy 44.634649 -68.328569) (xy 44.640246 -68.335652) (xy 44.6405 -68.335652) (xy 44.6405 -68.335906)
			(xy 44.658155 -68.356825) (xy 44.687865 -68.402801) (xy 44.710698 -68.452552) (xy 44.726185 -68.505056)
			(xy 44.734008 -68.559234) (xy 44.73448 -68.586604) (xy 44.734048 -68.613858) (xy 44.72629 -68.667812)
			(xy 44.710932 -68.720112) (xy 44.694299 -68.75653) (xy 48.170338 -68.75653) (xy 48.170812 -68.72916)
			(xy 48.178627 -68.674981) (xy 48.194113 -68.622477) (xy 48.216954 -68.57273) (xy 48.246677 -68.526764)
			(xy 48.264318 -68.505832) (xy 48.264572 -68.505578) (xy 48.270182 -68.498508) (xy 48.276413 -68.481578)
			(xy 48.276764 -68.472558) (xy 48.276764 -68.405502) (xy 48.276414 -68.396484) (xy 48.270162 -68.379567)
			(xy 48.264572 -68.372482) (xy 48.264318 -68.372482) (xy 48.264318 -68.372228) (xy 48.246681 -68.351294)
			(xy 48.216969 -68.305322) (xy 48.194132 -68.255575) (xy 48.17864 -68.203075) (xy 48.170812 -68.148899)
			(xy 48.170338 -68.12153) (xy 48.170783 -68.094276) (xy 48.178537 -68.040322) (xy 48.193892 -67.988021)
			(xy 48.216534 -67.938438) (xy 48.246004 -67.892582) (xy 48.281699 -67.851388) (xy 48.322895 -67.815694)
			(xy 48.368752 -67.786227) (xy 48.418336 -67.763586) (xy 48.470637 -67.748234) (xy 48.524592 -67.740482)
			(xy 48.551846 -67.740022) (xy 48.579215 -67.740514) (xy 48.633394 -67.748325) (xy 48.685897 -67.763808)
			(xy 48.735644 -67.786644) (xy 48.781612 -67.816363) (xy 48.802544 -67.834002) (xy 48.802798 -67.834256)
			(xy 48.809876 -67.839855) (xy 48.8268 -67.846093) (xy 48.835818 -67.846448) (xy 48.902874 -67.846448)
			(xy 48.911891 -67.84609) (xy 48.928809 -67.839844) (xy 48.935894 -67.834256) (xy 48.935894 -67.834002)
			(xy 48.936148 -67.834002) (xy 48.957089 -67.816374) (xy 49.003059 -67.786661) (xy 49.052805 -67.763822)
			(xy 49.105303 -67.748329) (xy 49.159477 -67.740498) (xy 49.186846 -67.740022) (xy 49.213161 -67.740452)
			(xy 49.265292 -67.747693) (xy 49.315935 -67.762019) (xy 49.364134 -67.783159) (xy 49.408977 -67.810712)
			(xy 49.449615 -67.844157) (xy 49.46777 -67.863212) (xy 49.475299 -67.870604) (xy 49.494574 -67.879134)
			(xy 49.505108 -67.879722) (xy 49.579784 -67.879722) (xy 49.590333 -67.879191) (xy 49.609628 -67.870657)
			(xy 49.617122 -67.863212) (xy 49.635276 -67.844155) (xy 49.675906 -67.810698) (xy 49.720746 -67.783138)
			(xy 49.768948 -67.762) (xy 49.819595 -67.747683) (xy 49.87173 -67.74046) (xy 49.898046 -67.740022)
			(xy 49.9253 -67.740435) (xy 49.979252 -67.748199) (xy 50.03155 -67.763561) (xy 50.081129 -67.78621)
			(xy 50.126981 -67.815684) (xy 50.168171 -67.851383) (xy 50.203862 -67.89258) (xy 50.233327 -67.938438)
			(xy 50.255965 -67.988022) (xy 50.271318 -68.040323) (xy 50.27907 -68.094276) (xy 50.279554 -68.12153)
			(xy 50.279117 -68.148901) (xy 50.271294 -68.203082) (xy 50.255798 -68.255586) (xy 50.23295 -68.305332)
			(xy 50.203219 -68.351298) (xy 50.185574 -68.372228) (xy 50.18532 -68.372482) (xy 50.179725 -68.379563)
			(xy 50.173486 -68.396484) (xy 50.173128 -68.405502) (xy 50.173128 -68.472558) (xy 50.173499 -68.481574)
			(xy 50.179736 -68.498491) (xy 50.18532 -68.505578) (xy 50.185574 -68.505578) (xy 50.185574 -68.505832)
			(xy 50.203191 -68.526782) (xy 50.232907 -68.57275) (xy 50.255747 -68.622492) (xy 50.271244 -68.674989)
			(xy 50.279077 -68.729162) (xy 50.279554 -68.75653) (xy 50.27905 -68.78378) (xy 50.271291 -68.837725)
			(xy 50.255934 -68.890016) (xy 50.233293 -68.93959) (xy 50.203828 -68.985438) (xy 50.168138 -69.026627)
			(xy 50.126951 -69.062318) (xy 50.081105 -69.091785) (xy 50.031531 -69.114429) (xy 49.97924 -69.129787)
			(xy 49.925296 -69.137549) (xy 49.898046 -69.138038) (xy 49.87173 -69.137626) (xy 49.819598 -69.130383)
			(xy 49.768954 -69.116054) (xy 49.720754 -69.094911) (xy 49.675912 -69.067355) (xy 49.635276 -69.033905)
			(xy 49.617122 -69.014848) (xy 49.609588 -69.007461) (xy 49.590318 -68.998927) (xy 49.579784 -68.998338)
			(xy 49.505108 -68.998338) (xy 49.494556 -68.998847) (xy 49.47526 -69.007395) (xy 49.46777 -69.014848)
			(xy 49.449631 -69.03392) (xy 49.408997 -69.067374) (xy 49.364153 -69.09493) (xy 49.315949 -69.116065)
			(xy 49.265299 -69.130379) (xy 49.213163 -69.137601) (xy 49.186846 -69.138038) (xy 49.159476 -69.13756)
			(xy 49.105297 -69.129747) (xy 49.052793 -69.114262) (xy 49.003046 -69.091422) (xy 48.957079 -69.061699)
			(xy 48.936148 -69.044058) (xy 48.935894 -69.043804) (xy 48.928813 -69.038209) (xy 48.911892 -69.031967)
			(xy 48.902874 -69.031612) (xy 48.835818 -69.031612) (xy 48.826802 -69.031975) (xy 48.809884 -69.038218)
			(xy 48.802798 -69.043804) (xy 48.802798 -69.044058) (xy 48.802544 -69.044058) (xy 48.781601 -69.061683)
			(xy 48.735632 -69.091399) (xy 48.685887 -69.114238) (xy 48.633389 -69.129732) (xy 48.579215 -69.137563)
			(xy 48.551846 -69.138038) (xy 48.524596 -69.137502) (xy 48.470649 -69.129752) (xy 48.418354 -69.114403)
			(xy 48.368776 -69.091768) (xy 48.322924 -69.062308) (xy 48.281732 -69.026622) (xy 48.246038 -68.985437)
			(xy 48.216568 -68.939591) (xy 48.193923 -68.890017) (xy 48.178564 -68.837725) (xy 48.170803 -68.78378)
			(xy 48.170338 -68.75653) (xy 44.694299 -68.75653) (xy 44.688287 -68.769694) (xy 44.658816 -68.815548)
			(xy 44.623119 -68.856742) (xy 44.581923 -68.892435) (xy 44.536066 -68.921902) (xy 44.486482 -68.944543)
			(xy 44.43418 -68.959897) (xy 44.380226 -68.967651) (xy 44.352972 -68.968112) (xy 44.325601 -68.967659)
			(xy 44.271422 -68.959838) (xy 44.218919 -68.944345) (xy 44.169172 -68.921501) (xy 44.123206 -68.891774)
			(xy 44.102274 -68.874132) (xy 44.10202 -68.873878) (xy 44.094934 -68.868291) (xy 44.078017 -68.862045)
			(xy 44.069 -68.861686) (xy 44.001944 -68.861686) (xy 43.99293 -68.862067) (xy 43.976013 -68.868298)
			(xy 43.968924 -68.873878) (xy 43.968924 -68.874132) (xy 43.96867 -68.874132) (xy 43.947726 -68.891757)
			(xy 43.901756 -68.92147) (xy 43.852012 -68.944308) (xy 43.799514 -68.959802) (xy 43.74534 -68.967635)
			(xy 43.717972 -68.968112) (xy 43.691658 -68.967659) (xy 43.639529 -68.960421) (xy 43.588886 -68.946099)
			(xy 43.540687 -68.924963) (xy 43.495844 -68.897415) (xy 43.455204 -68.863974) (xy 43.437048 -68.844922)
			(xy 43.429545 -68.837499) (xy 43.410251 -68.828986) (xy 43.39971 -68.828412) (xy 43.325034 -68.828412)
			(xy 43.314484 -68.828942) (xy 43.295189 -68.837476) (xy 43.287696 -68.844922) (xy 43.26954 -68.863977)
			(xy 43.22891 -68.897433) (xy 43.184069 -68.924992) (xy 43.135869 -68.94613) (xy 43.085222 -68.960448)
			(xy 43.033088 -68.967673) (xy 43.006772 -68.968112) (xy 42.97952 -68.967648) (xy 42.925572 -68.959888)
			(xy 42.873277 -68.94453) (xy 42.8237 -68.921885) (xy 42.77785 -68.892417) (xy 42.73666 -68.856723)
			(xy 42.700969 -68.815531) (xy 42.671503 -68.769679) (xy 42.648862 -68.7201) (xy 42.633507 -68.667805)
			(xy 42.62575 -68.613856) (xy 42.625264 -68.586604) (xy 40.416537 -68.586604) (xy 40.430897 -71.555864)
			(xy 45.194472 -71.555864) (xy 45.198543 -71.500242) (xy 45.210669 -71.445805) (xy 45.230592 -71.393714)
			(xy 45.257888 -71.345079) (xy 45.291974 -71.300936) (xy 45.332123 -71.262227) (xy 45.377481 -71.229776)
			(xy 45.427081 -71.204275) (xy 45.479865 -71.186268) (xy 45.534708 -71.176138) (xy 45.590442 -71.174101)
			(xy 45.645879 -71.180201) (xy 45.699836 -71.194307) (xy 45.751165 -71.216119) (xy 45.798771 -71.245173)
			(xy 45.841639 -71.280848) (xy 45.878856 -71.322385) (xy 45.909629 -71.368898) (xy 45.933301 -71.419395)
			(xy 45.949369 -71.472802) (xy 45.957489 -71.527978) (xy 45.957998 -71.555864) (xy 45.957489 -71.58375)
			(xy 45.95165 -71.623428) (xy 46.703486 -71.623428) (xy 46.707557 -71.567806) (xy 46.719683 -71.513369)
			(xy 46.739606 -71.461278) (xy 46.766902 -71.412643) (xy 46.800988 -71.3685) (xy 46.841137 -71.329791)
			(xy 46.886495 -71.29734) (xy 46.936095 -71.271839) (xy 46.988879 -71.253832) (xy 47.043722 -71.243702)
			(xy 47.099456 -71.241665) (xy 47.154893 -71.247765) (xy 47.20885 -71.261871) (xy 47.260179 -71.283683)
			(xy 47.307785 -71.312737) (xy 47.350653 -71.348412) (xy 47.38787 -71.389949) (xy 47.418643 -71.436462)
			(xy 47.442315 -71.486959) (xy 47.458383 -71.540366) (xy 47.466503 -71.595542) (xy 47.467012 -71.623428)
			(xy 47.466503 -71.651314) (xy 47.458383 -71.70649) (xy 47.442315 -71.759897) (xy 47.418643 -71.810394)
			(xy 47.38787 -71.856907) (xy 47.350653 -71.898444) (xy 47.307785 -71.934119) (xy 47.260179 -71.963173)
			(xy 47.20885 -71.984985) (xy 47.154893 -71.999091) (xy 47.099456 -72.005191) (xy 47.043722 -72.003154)
			(xy 46.988879 -71.993024) (xy 46.936095 -71.975017) (xy 46.886495 -71.949516) (xy 46.841137 -71.917065)
			(xy 46.800988 -71.878356) (xy 46.766902 -71.834213) (xy 46.739606 -71.785578) (xy 46.719683 -71.733487)
			(xy 46.707557 -71.67905) (xy 46.703486 -71.623428) (xy 45.95165 -71.623428) (xy 45.949369 -71.638926)
			(xy 45.933301 -71.692333) (xy 45.909629 -71.74283) (xy 45.878856 -71.789343) (xy 45.841639 -71.83088)
			(xy 45.798771 -71.866555) (xy 45.751165 -71.895609) (xy 45.699836 -71.917421) (xy 45.645879 -71.931527)
			(xy 45.590442 -71.937627) (xy 45.534708 -71.93559) (xy 45.479865 -71.92546) (xy 45.427081 -71.907453)
			(xy 45.377481 -71.881952) (xy 45.332123 -71.849501) (xy 45.291974 -71.810792) (xy 45.257888 -71.766649)
			(xy 45.230592 -71.718014) (xy 45.210669 -71.665923) (xy 45.198543 -71.611486) (xy 45.194472 -71.555864)
			(xy 40.430897 -71.555864) (xy 40.464909 -78.58887) (xy 41.399966 -78.58887) (xy 41.404037 -78.533248)
			(xy 41.416163 -78.478811) (xy 41.436086 -78.42672) (xy 41.463382 -78.378085) (xy 41.497468 -78.333942)
			(xy 41.537617 -78.295233) (xy 41.582975 -78.262782) (xy 41.632575 -78.237281) (xy 41.685359 -78.219274)
			(xy 41.740202 -78.209144) (xy 41.795936 -78.207107) (xy 41.851373 -78.213207) (xy 41.90533 -78.227313)
			(xy 41.956659 -78.249125) (xy 42.004265 -78.278179) (xy 42.047133 -78.313854) (xy 42.08435 -78.355391)
			(xy 42.115123 -78.401904) (xy 42.138795 -78.452401) (xy 42.154863 -78.505808) (xy 42.162983 -78.560984)
			(xy 42.163492 -78.58887) (xy 42.162983 -78.616756) (xy 42.154863 -78.671932) (xy 42.138795 -78.725339)
			(xy 42.115123 -78.775836) (xy 42.08435 -78.822349) (xy 42.047133 -78.863886) (xy 42.004265 -78.899561)
			(xy 41.956659 -78.928615) (xy 41.90533 -78.950427) (xy 41.851373 -78.964533) (xy 41.795936 -78.970633)
			(xy 41.740202 -78.968596) (xy 41.685359 -78.958466) (xy 41.632575 -78.940459) (xy 41.582975 -78.914958)
			(xy 41.537617 -78.882507) (xy 41.497468 -78.843798) (xy 41.463382 -78.799655) (xy 41.436086 -78.75102)
			(xy 41.416163 -78.698929) (xy 41.404037 -78.644492) (xy 41.399966 -78.58887) (xy 40.464909 -78.58887)
			(xy 40.467692 -79.164434) (xy 42.852592 -79.164434) (xy 42.856663 -79.108812) (xy 42.868789 -79.054375)
			(xy 42.888712 -79.002284) (xy 42.916008 -78.953649) (xy 42.950094 -78.909506) (xy 42.990243 -78.870797)
			(xy 43.035601 -78.838346) (xy 43.085201 -78.812845) (xy 43.137985 -78.794838) (xy 43.192828 -78.784708)
			(xy 43.248562 -78.782671) (xy 43.303999 -78.788771) (xy 43.357956 -78.802877) (xy 43.409285 -78.824689)
			(xy 43.456891 -78.853743) (xy 43.499759 -78.889418) (xy 43.536976 -78.930955) (xy 43.567749 -78.977468)
			(xy 43.591421 -79.027965) (xy 43.607489 -79.081372) (xy 43.615609 -79.136548) (xy 43.616118 -79.164434)
			(xy 43.615609 -79.19232) (xy 43.607489 -79.247496) (xy 43.591421 -79.300903) (xy 43.567749 -79.3514)
			(xy 43.536976 -79.397913) (xy 43.499759 -79.43945) (xy 43.456891 -79.475125) (xy 43.409285 -79.504179)
			(xy 43.357956 -79.525991) (xy 43.303999 -79.540097) (xy 43.248562 -79.546197) (xy 43.192828 -79.54416)
			(xy 43.137985 -79.53403) (xy 43.085201 -79.516023) (xy 43.035601 -79.490522) (xy 42.990243 -79.458071)
			(xy 42.950094 -79.419362) (xy 42.916008 -79.375219) (xy 42.888712 -79.326584) (xy 42.868789 -79.274493)
			(xy 42.856663 -79.220056) (xy 42.852592 -79.164434) (xy 40.467692 -79.164434) (xy 40.496037 -85.025538)
			(xy 44.856389 -85.025538) (xy 44.856389 -84.896398) (xy 44.864339 -84.767503) (xy 44.880209 -84.639343)
			(xy 44.903938 -84.512402) (xy 44.935437 -84.387163) (xy 44.974586 -84.2641) (xy 45.021237 -84.143681)
			(xy 45.075212 -84.026362) (xy 45.136307 -83.912588) (xy 45.20429 -83.802791) (xy 45.278904 -83.697388)
			(xy 45.359865 -83.596778) (xy 45.446865 -83.501343) (xy 45.539576 -83.411444) (xy 45.637646 -83.327423)
			(xy 45.740701 -83.249599) (xy 45.848352 -83.178267) (xy 45.960191 -83.113697) (xy 46.075792 -83.056135)
			(xy 46.194717 -83.005798) (xy 46.316516 -82.962878) (xy 46.440726 -82.927537) (xy 46.566875 -82.89991)
			(xy 46.694487 -82.880101) (xy 46.823076 -82.868185) (xy 46.952154 -82.864209) (xy 47.081232 -82.868185)
			(xy 47.209821 -82.880101) (xy 47.337433 -82.89991) (xy 47.463582 -82.927537) (xy 47.587792 -82.962878)
			(xy 47.709591 -83.005798) (xy 47.828516 -83.056135) (xy 47.944117 -83.113697) (xy 48.055956 -83.178267)
			(xy 48.163607 -83.249599) (xy 48.266662 -83.327423) (xy 48.364732 -83.411444) (xy 48.457443 -83.501343)
			(xy 48.544443 -83.596778) (xy 48.625404 -83.697388) (xy 48.700018 -83.802791) (xy 48.768001 -83.912588)
			(xy 48.829096 -84.026362) (xy 48.883071 -84.143681) (xy 48.929722 -84.2641) (xy 48.968871 -84.387163)
			(xy 49.00037 -84.512402) (xy 49.024099 -84.639343) (xy 49.039969 -84.767503) (xy 49.047919 -84.896398)
			(xy 49.048416 -84.960968) (xy 49.047919 -85.025538) (xy 49.039969 -85.154433) (xy 49.024099 -85.282593)
			(xy 49.00037 -85.409534) (xy 48.968871 -85.534773) (xy 48.929722 -85.657836) (xy 48.883071 -85.778255)
			(xy 48.829096 -85.895574) (xy 48.768001 -86.009348) (xy 48.700018 -86.119145) (xy 48.625404 -86.224548)
			(xy 48.544443 -86.325158) (xy 48.457443 -86.420593) (xy 48.364732 -86.510492) (xy 48.266662 -86.594513)
			(xy 48.163607 -86.672337) (xy 48.055956 -86.743669) (xy 47.944117 -86.808239) (xy 47.828516 -86.865801)
			(xy 47.709591 -86.916138) (xy 47.587792 -86.959058) (xy 47.463582 -86.994399) (xy 47.337433 -87.022026)
			(xy 47.209821 -87.041835) (xy 47.081232 -87.053751) (xy 46.952154 -87.057728) (xy 46.823076 -87.053751)
			(xy 46.694487 -87.041835) (xy 46.566875 -87.022026) (xy 46.440726 -86.994399) (xy 46.316516 -86.959058)
			(xy 46.194717 -86.916138) (xy 46.075792 -86.865801) (xy 45.960191 -86.808239) (xy 45.848352 -86.743669)
			(xy 45.740701 -86.672337) (xy 45.637646 -86.594513) (xy 45.539576 -86.510492) (xy 45.446865 -86.420593)
			(xy 45.359865 -86.325158) (xy 45.278904 -86.224548) (xy 45.20429 -86.119145) (xy 45.136307 -86.009348)
			(xy 45.075212 -85.895574) (xy 45.021237 -85.778255) (xy 44.974586 -85.657836) (xy 44.935437 -85.534773)
			(xy 44.903938 -85.409534) (xy 44.880209 -85.282593) (xy 44.864339 -85.154433) (xy 44.856389 -85.025538)
			(xy 40.496037 -85.025538) (xy 40.591486 -104.7623) (xy 40.591486 -104.763316) (xy 40.739822 -111.735362)
			(xy 40.740076 -111.75619) (xy 40.740076 -111.756698) (xy 40.739568 -111.789972) (xy 40.739568 -111.79048)
			(xy 40.73906 -111.799116) (xy 40.73906 -111.801148) (xy 40.738552 -111.805212) (xy 40.738552 -111.807752)
			(xy 40.738044 -111.81588) (xy 40.633904 -113.53927) (xy 40.633904 -113.542826) (xy 40.707818 -128.83134)
			(xy 40.742362 -135.965438) (xy 40.742616 -135.968994) (xy 40.742616 -135.971788) (xy 40.742433 -135.995959)
			(xy 40.740018 -136.04424) (xy 40.73779 -136.068308) (xy 40.729408 -136.152128) (xy 40.729408 -136.153144)
			(xy 40.729154 -136.155938) (xy 40.731948 -136.354566) (xy 40.731948 -136.368536) (xy 40.731517 -136.410141)
			(xy 40.724523 -136.493055) (xy 40.717978 -136.534144) (xy 40.71366 -136.558274) (xy 40.710866 -136.572244)
			(xy 40.668448 -136.773666) (xy 40.667686 -136.779254) (xy 40.27424 -140.772388) (xy 40.273867 -140.776993)
			(xy 40.274626 -140.786199) (xy 40.275764 -140.790676) (xy 40.27805 -140.799566) (xy 40.283384 -140.807186)
			(xy 40.3002 -140.831637) (xy 40.326867 -140.884646) (xy 40.345013 -140.941143) (xy 40.354202 -140.999766)
			(xy 40.354758 -141.029436) (xy 40.354313 -141.055478) (xy 40.347223 -141.107078) (xy 40.33318 -141.157233)
			(xy 40.312445 -141.205012) (xy 40.285404 -141.249526) (xy 40.252559 -141.289949) (xy 40.233854 -141.308074)
			(xy 40.22725 -141.31417) (xy 40.218868 -141.330934) (xy 40.113712 -142.400782) (xy 40.113291 -142.407282)
			(xy 40.115345 -142.42014) (xy 40.117776 -142.426182) (xy 40.120316 -142.432024) (xy 40.127936 -142.441676)
			(xy 40.13327 -142.445994) (xy 40.154702 -142.463078) (xy 40.192919 -142.502363) (xy 40.225131 -142.546705)
			(xy 40.250675 -142.595196) (xy 40.269029 -142.646838) (xy 40.279815 -142.700574) (xy 40.282811 -142.755299)
			(xy 40.277957 -142.809891) (xy 40.265352 -142.863229) (xy 40.245255 -142.914219) (xy 40.218077 -142.961814)
			(xy 40.201596 -142.983712) (xy 40.18361 -143.005921) (xy 40.142102 -143.0452) (xy 40.095182 -143.077825)
			(xy 40.06977 -143.0909) (xy 40.063985 -143.093919) (xy 40.054086 -143.102413) (xy 40.050212 -143.107664)
			(xy 40.046656 -143.112998) (xy 40.042084 -143.124936) (xy 40.021256 -143.337026) (xy 39.836344 -145.214848)
			(xy 39.83609 -145.222976) (xy 41.021 -164.701474) (xy 41.290494 -169.132758) (xy 41.372282 -170.478704)
			(xy 42.228262 -184.543446) (xy 42.228843 -184.547793) (xy 42.231268 -184.55622) (xy 42.233088 -184.56021)
			(xy 42.235374 -184.564528) (xy 42.23766 -184.56783) (xy 42.245024 -184.576876) (xy 42.265657 -184.587705)
			(xy 42.277284 -184.588658) (xy 43.311318 -184.61482) (xy 43.320468 -184.614345) (xy 43.337524 -184.607696)
			(xy 43.344592 -184.601866) (xy 43.346878 -184.59958) (xy 43.350313 -184.595893) (xy 43.355806 -184.587445)
			(xy 43.3578 -184.582816) (xy 43.36161 -184.57291) (xy 42.693082 -165.810184) (xy 42.693082 -165.80866)
			(xy 41.517824 -147.54606) (xy 41.516875 -147.530266) (xy 41.515859 -147.498637) (xy 41.515792 -147.482814)
			(xy 41.515792 -147.480528) (xy 41.516046 -147.450048) (xy 41.516046 -147.449032) (xy 41.516808 -147.433792)
			(xy 41.516808 -147.433284) (xy 41.532302 -147.121372) (xy 41.532302 -147.117308) (xy 41.523412 -146.986244)
			(xy 41.5163 -146.882358) (xy 41.515294 -146.865549) (xy 41.514279 -146.831887) (xy 41.514268 -146.815048)
			(xy 41.514268 -146.814794) (xy 41.522142 -116.429536) (xy 41.522779 -116.37772) (xy 41.533471 -116.274641)
			(xy 41.543478 -116.223796) (xy 41.821354 -114.90706) (xy 41.83172 -114.860634) (xy 41.860144 -114.769848)
			(xy 41.89708 -114.68218) (xy 41.942193 -114.598425) (xy 41.968166 -114.558572) (xy 43.513248 -112.248188)
			(xy 43.541956 -112.206391) (xy 43.606601 -112.128262) (xy 43.64228 -112.092232) (xy 44.63542 -111.11357)
			(xy 44.638584 -111.109825) (xy 44.643565 -111.101382) (xy 44.645326 -111.096806) (xy 45.43806 -108.580936)
			(xy 47.13097 -103.15702) (xy 47.130716 -103.15575) (xy 47.106332 -103.134414) (xy 47.086287 -103.116202)
			(xy 47.051029 -103.075093) (xy 47.021934 -103.029414) (xy 46.999586 -102.980082) (xy 46.984434 -102.928087)
			(xy 46.976782 -102.874473) (xy 46.976284 -102.847394) (xy 46.976786 -102.81961) (xy 46.984851 -102.764629)
			(xy 47.000808 -102.711401) (xy 47.024321 -102.661052) (xy 47.05489 -102.614647) (xy 47.09187 -102.57317)
			(xy 47.134478 -102.537498) (xy 47.181811 -102.508386) (xy 47.232867 -102.486451) (xy 47.286566 -102.472157)
			(xy 47.314104 -102.468426) (xy 47.314358 -102.468426) (xy 47.321497 -102.467311) (xy 47.334774 -102.461632)
			(xy 47.34052 -102.45725) (xy 47.346362 -102.452424) (xy 47.35449 -102.440232) (xy 47.440088 -102.165912)
			(xy 47.70755 -101.30917) (xy 47.708058 -101.307138) (xy 48.174656 -99.593146) (xy 48.174656 -99.592638)
			(xy 49.046638 -96.239076) (xy 49.046638 -96.238822) (xy 49.047146 -96.237298) (xy 49.0474 -96.236028)
			(xy 49.047654 -96.232472) (xy 49.048184 -96.220138) (xy 49.03874 -96.197357) (xy 49.02962 -96.189038)
			(xy 48.970438 -96.144588) (xy 48.96993 -96.14408) (xy 48.950118 -96.129602) (xy 48.942575 -96.124914)
			(xy 48.925356 -96.120616) (xy 48.907705 -96.122478) (xy 48.899572 -96.126046) (xy 48.895508 -96.128332)
			(xy 48.874934 -96.140524) (xy 48.874426 -96.140778) (xy 48.873156 -96.14154) (xy 48.833096 -96.163911)
			(xy 48.749845 -96.202503) (xy 48.66359 -96.233808) (xy 48.574966 -96.257596) (xy 48.484628 -96.27369)
			(xy 48.393242 -96.281973) (xy 48.301482 -96.282382) (xy 48.210025 -96.274915) (xy 48.119547 -96.259628)
			(xy 48.030715 -96.236632) (xy 47.944183 -96.206098) (xy 47.860591 -96.16825) (xy 47.780556 -96.123369)
			(xy 47.704667 -96.071784) (xy 47.633485 -96.013878) (xy 47.567535 -95.950076) (xy 47.507304 -95.88085)
			(xy 47.453236 -95.806711) (xy 47.405729 -95.728205) (xy 47.365135 -95.645912) (xy 47.331753 -95.560439)
			(xy 47.305829 -95.472416) (xy 47.287554 -95.382493) (xy 47.277064 -95.291334) (xy 47.274436 -95.199611)
			(xy 47.279688 -95.108001) (xy 47.292783 -95.017179) (xy 47.313624 -94.927817) (xy 47.342057 -94.840572)
			(xy 47.377871 -94.756089) (xy 47.39894 -94.71533) (xy 47.421254 -94.674253) (xy 47.472056 -94.595772)
			(xy 47.529525 -94.522033) (xy 47.593221 -94.453602) (xy 47.662657 -94.391003) (xy 47.737301 -94.334714)
			(xy 47.81658 -94.285168) (xy 47.899888 -94.242744) (xy 47.986587 -94.207766) (xy 48.076012 -94.180503)
			(xy 48.167478 -94.161164) (xy 48.260285 -94.149896) (xy 48.353721 -94.146786) (xy 48.447072 -94.151858)
			(xy 48.539621 -94.165073) (xy 48.630661 -94.18633) (xy 48.719493 -94.215466) (xy 48.805438 -94.252257)
			(xy 48.887836 -94.296422) (xy 48.966057 -94.347623) (xy 49.039502 -94.405467) (xy 49.107607 -94.469512)
			(xy 49.169852 -94.539266) (xy 49.225759 -94.614195) (xy 49.274901 -94.693726) (xy 49.3169 -94.77725)
			(xy 49.334674 -94.820486) (xy 49.337976 -94.829122) (xy 49.341278 -94.833186) (xy 49.350168 -94.841568)
			(xy 49.35728 -94.846394) (xy 49.362178 -94.849061) (xy 49.372817 -94.852398) (xy 49.378362 -94.852998)
			(xy 49.43475 -94.85249) (xy 49.476914 -94.852236) (xy 49.490122 -94.850458) (xy 59.598306 -68.147184)
			(xy 59.59983 -68.141088) (xy 59.59983 -68.14058) (xy 60.159138 -65.09131) (xy 60.630816 -62.520322)
			(xy 60.631518 -62.51083) (xy 60.626688 -62.492434) (xy 60.621418 -62.484508) (xy 60.59678 -62.450472)
			(xy 60.596526 -62.450218) (xy 60.590155 -62.442284) (xy 60.57274 -62.431791) (xy 60.562744 -62.429898)
			(xy 60.555378 -62.428882) (xy 60.55487 -62.428882) (xy 60.546742 -62.427358) (xy 60.543186 -62.42685)
			(xy 60.542678 -62.42685) (xy 60.517786 -62.421262) (xy 60.517532 -62.421262) (xy 60.510674 -62.419484)
			(xy 60.49645 -62.419992) (xy 60.4901 -62.422024) (xy 60.483462 -62.42434) (xy 60.471732 -62.432077)
			(xy 60.466986 -62.437264) (xy 60.463938 -62.44082) (xy 60.41009 -62.503304) (xy 60.405063 -62.510187)
			(xy 60.399487 -62.526282) (xy 60.399168 -62.5348) (xy 60.399168 -62.54877) (xy 60.401962 -62.563248)
			(xy 60.404502 -62.57163) (xy 60.40501 -62.573154) (xy 60.41611 -62.605173) (xy 60.428112 -62.671862)
			(xy 60.428886 -62.705742) (xy 60.428378 -62.71641) (xy 60.427189 -62.743159) (xy 60.418247 -62.795952)
			(xy 60.402014 -62.846976) (xy 60.378807 -62.895229) (xy 60.349084 -62.939766) (xy 60.313427 -62.97971)
			(xy 60.272536 -63.014278) (xy 60.227215 -63.04279) (xy 60.178353 -63.064687) (xy 60.12691 -63.07954)
			(xy 60.073896 -63.087055) (xy 60.047124 -63.087504) (xy 60.01987 -63.087042) (xy 59.965917 -63.079288)
			(xy 59.913617 -63.063934) (xy 59.864035 -63.041294) (xy 59.818179 -63.011826) (xy 59.776984 -62.976133)
			(xy 59.741288 -62.93494) (xy 59.711818 -62.889087) (xy 59.689174 -62.839505) (xy 59.673817 -62.787206)
			(xy 59.666059 -62.733254) (xy 59.666059 -62.678746) (xy 59.673817 -62.624794) (xy 59.689174 -62.572495)
			(xy 59.711818 -62.522913) (xy 59.741288 -62.47706) (xy 59.776984 -62.435867) (xy 59.818179 -62.400174)
			(xy 59.864035 -62.370706) (xy 59.913617 -62.348066) (xy 59.965917 -62.332712) (xy 60.01987 -62.324958)
			(xy 60.047124 -62.324488) (xy 60.047886 -62.324488) (xy 60.070456 -62.324833) (xy 60.115278 -62.330175)
			(xy 60.137294 -62.335156) (xy 60.140342 -62.335918) (xy 60.149486 -62.336934) (xy 60.161373 -62.337185)
			(xy 60.183341 -62.328169) (xy 60.19165 -62.319662) (xy 60.250578 -62.251336) (xy 60.255004 -62.245862)
			(xy 60.260937 -62.233103) (xy 60.262262 -62.22619) (xy 60.263131 -62.219231) (xy 60.261459 -62.205311)
			(xy 60.25896 -62.198758) (xy 60.25896 -62.198504) (xy 60.249631 -62.175121) (xy 60.236505 -62.126517)
			(xy 60.229882 -62.07661) (xy 60.229496 -62.051438) (xy 60.229957 -62.024183) (xy 60.237709 -61.970229)
			(xy 60.253062 -61.917926) (xy 60.275703 -61.868342) (xy 60.30517 -61.822484) (xy 60.340863 -61.781287)
			(xy 60.382057 -61.74559) (xy 60.427912 -61.716119) (xy 60.477495 -61.693474) (xy 60.529795 -61.678117)
			(xy 60.58375 -61.670359) (xy 60.611004 -61.66993) (xy 60.611766 -61.66993) (xy 60.633162 -61.670258)
			(xy 60.67568 -61.675094) (xy 60.696602 -61.679582) (xy 60.701682 -61.680852) (xy 60.710241 -61.682201)
			(xy 60.727381 -61.679737) (xy 60.73521 -61.676026) (xy 60.739528 -61.673486) (xy 60.774326 -61.650372)
			(xy 60.782673 -61.644309) (xy 60.794091 -61.627146) (xy 60.796424 -61.617098) (xy 60.813442 -61.524642)
			(xy 60.820046 -61.48832) (xy 60.922408 -60.930536) (xy 60.923377 -60.924641) (xy 60.922854 -60.912707)
			(xy 60.921392 -60.906914) (xy 60.91809 -60.895992) (xy 60.910216 -60.887356) (xy 60.891226 -60.865227)
			(xy 60.85949 -60.81631) (xy 60.835558 -60.763137) (xy 60.819987 -60.706945) (xy 60.815982 -60.67806)
			(xy 60.814458 -60.66409) (xy 60.813188 -60.633356) (xy 60.813749 -60.604108) (xy 60.822676 -60.546298)
			(xy 60.840314 -60.490524) (xy 60.866251 -60.438093) (xy 60.89988 -60.39023) (xy 60.940414 -60.348056)
			(xy 60.986906 -60.312555) (xy 61.012324 -60.298076) (xy 61.012578 -60.298076) (xy 61.01868 -60.294421)
			(xy 61.028733 -60.284365) (xy 61.03239 -60.278264) (xy 61.03239 -60.27801) (xy 61.035705 -60.27153)
			(xy 61.038939 -60.257345) (xy 61.03874 -60.25007) (xy 60.943236 -58.759344) (xy 60.942838 -58.754617)
			(xy 60.940535 -58.745415) (xy 60.938664 -58.741056) (xy 60.934854 -58.732928) (xy 60.927742 -58.72607)
			(xy 60.909413 -58.708023) (xy 60.877276 -58.667858) (xy 60.850824 -58.623742) (xy 60.830535 -58.576473)
			(xy 60.816777 -58.526908) (xy 60.8098 -58.475945) (xy 60.809378 -58.450226) (xy 60.809378 -58.449718)
			(xy 60.809443 -58.439858) (xy 60.810461 -58.420163) (xy 60.81141 -58.410348) (xy 60.811918 -58.405014)
			(xy 60.815403 -58.379318) (xy 60.828418 -58.329123) (xy 60.848096 -58.281146) (xy 60.874075 -58.236269)
			(xy 60.889642 -58.21553) (xy 60.894722 -58.208926) (xy 60.905898 -58.17743) (xy 60.905898 -58.174128)
			(xy 60.89269 -57.967372) (xy 60.879736 -57.76595) (xy 60.680092 -54.642004) (xy 60.678422 -54.632674)
			(xy 60.669335 -54.616062) (xy 60.654864 -54.603849) (xy 60.646056 -54.600348) (xy 60.645802 -54.600348)
			(xy 60.620938 -54.591474) (xy 60.573731 -54.567837) (xy 60.530235 -54.537917) (xy 60.491282 -54.502283)
			(xy 60.457615 -54.461618) (xy 60.429878 -54.416698) (xy 60.408601 -54.368382) (xy 60.394191 -54.317593)
			(xy 60.386923 -54.265303) (xy 60.386468 -54.238906) (xy 60.386938 -54.212269) (xy 60.394359 -54.159515)
			(xy 60.409043 -54.108305) (xy 60.430705 -54.059634) (xy 60.458924 -54.014448) (xy 60.493152 -53.973625)
			(xy 60.532725 -53.937957) (xy 60.576872 -53.908139) (xy 60.60059 -53.896006) (xy 60.603638 -53.894482)
			(xy 60.611615 -53.889341) (xy 60.62347 -53.874544) (xy 60.629207 -53.856472) (xy 60.629038 -53.846984)
			(xy 60.496958 -51.781964) (xy 60.495646 -51.770824) (xy 60.484827 -51.751206) (xy 60.47613 -51.744118)
			(xy 60.44438 -51.721004) (xy 60.41136 -51.697128) (xy 60.402192 -51.691666) (xy 60.381195 -51.687979)
			(xy 60.37072 -51.690016) (xy 60.370466 -51.690016) (xy 60.347422 -51.695489) (xy 60.300422 -51.701353)
			(xy 60.27674 -51.7017) (xy 60.265818 -51.7017) (xy 60.238912 -51.700504) (xy 60.185815 -51.691479)
			(xy 60.134515 -51.675076) (xy 60.086034 -51.651619) (xy 60.041333 -51.621576) (xy 60.001304 -51.585544)
			(xy 59.96674 -51.544239) (xy 59.952128 -51.521614) (xy 59.948572 -51.515518) (xy 59.945778 -51.511454)
			(xy 59.93638 -51.505358) (xy 59.931303 -51.502339) (xy 59.920142 -51.498481) (xy 59.914282 -51.497738)
			(xy 59.90463 -51.496722) (xy 59.904122 -51.496722) (xy 59.840114 -51.490372) (xy 59.834526 -51.489864)
			(xy 59.82865 -51.489438) (xy 59.816972 -51.490967) (xy 59.811412 -51.492912) (xy 59.80049 -51.496976)
			(xy 59.792362 -51.505612) (xy 59.774298 -51.524148) (xy 59.734033 -51.556669) (xy 59.689743 -51.583451)
			(xy 59.642241 -51.604002) (xy 59.592397 -51.617946) (xy 59.541126 -51.625027) (xy 59.515248 -51.6255)
			(xy 59.51474 -51.6255) (xy 59.514232 -51.6255) (xy 59.497468 -51.625246) (xy 59.497214 -51.624992)
			(xy 59.470805 -51.623336) (xy 59.418786 -51.613645) (xy 59.368604 -51.596859) (xy 59.321223 -51.573301)
			(xy 59.277552 -51.543422) (xy 59.238427 -51.507797) (xy 59.204601 -51.467107) (xy 59.17672 -51.422133)
			(xy 59.155321 -51.373739) (xy 59.140814 -51.322852) (xy 59.133476 -51.270449) (xy 59.132978 -51.243992)
			(xy 59.133403 -51.218481) (xy 59.140198 -51.167912) (xy 59.153665 -51.118699) (xy 59.173565 -51.071717)
			(xy 59.199543 -51.027803) (xy 59.21502 -51.007518) (xy 59.21756 -51.00447) (xy 59.218576 -51.002946)
			(xy 59.221878 -50.996342) (xy 59.224223 -50.99112) (xy 59.226791 -50.979966) (xy 59.226958 -50.974244)
			(xy 59.226958 -50.94224) (xy 59.238134 -50.94224) (xy 59.238134 -50.89144) (xy 59.237799 -50.882837)
			(xy 59.232082 -50.866609) (xy 59.226958 -50.85969) (xy 59.225688 -50.858166) (xy 59.208293 -50.83729)
			(xy 59.178973 -50.791541) (xy 59.156443 -50.742093) (xy 59.14116 -50.689948) (xy 59.133434 -50.636161)
			(xy 59.132978 -50.608992) (xy 59.133464 -50.581741) (xy 59.141222 -50.527793) (xy 59.156577 -50.475499)
			(xy 59.179219 -50.425921) (xy 59.208685 -50.380071) (xy 59.244376 -50.338881) (xy 59.285566 -50.303189)
			(xy 59.331416 -50.273722) (xy 59.380993 -50.251079) (xy 59.433287 -50.235723) (xy 59.487235 -50.227965)
			(xy 59.514486 -50.227484) (xy 59.542525 -50.227986) (xy 59.597996 -50.236209) (xy 59.651665 -50.252466)
			(xy 59.702375 -50.276407) (xy 59.749034 -50.307514) (xy 59.790635 -50.345118) (xy 59.808872 -50.366422)
			(xy 59.809126 -50.366676) (xy 59.815984 -50.374804) (xy 59.837574 -50.385472) (xy 59.84621 -50.38979)
			(xy 59.849739 -50.3913) (xy 59.857138 -50.393339) (xy 59.860942 -50.393854) (xy 59.864244 -50.394108)
			(xy 59.923934 -50.394108) (xy 59.929659 -50.393962) (xy 59.94082 -50.391401) (xy 59.946032 -50.389028)
			(xy 59.96432 -50.380138) (xy 59.974226 -50.373788) (xy 59.978036 -50.37074) (xy 59.981592 -50.366676)
			(xy 60.001998 -50.342896) (xy 60.049191 -50.301678) (xy 60.102473 -50.268707) (xy 60.131198 -50.256186)
			(xy 60.141296 -50.25205) (xy 60.161883 -50.244806) (xy 60.172346 -50.241708) (xy 60.182506 -50.238914)
			(xy 60.190634 -50.23231) (xy 60.194476 -50.22896) (xy 60.200884 -50.221032) (xy 60.203334 -50.216562)
			(xy 60.220606 -50.183288) (xy 60.225 -50.173925) (xy 60.226592 -50.153325) (xy 60.223654 -50.14341)
			(xy 60.128912 -49.86782) (xy 60.124988 -49.858032) (xy 60.11072 -49.842535) (xy 60.091437 -49.834054)
			(xy 60.080906 -49.83353) (xy 60.075064 -49.83353) (xy 60.07058 -49.833671) (xy 60.061766 -49.835333)
			(xy 60.057538 -49.836832) (xy 60.03036 -49.848008) (xy 60.023502 -49.854358) (xy 60.002199 -49.873386)
			(xy 59.954999 -49.90555) (xy 59.903534 -49.930323) (xy 59.848952 -49.947153) (xy 59.792473 -49.955664)
			(xy 59.763914 -49.956212) (xy 59.738402 -49.955788) (xy 59.687833 -49.948996) (xy 59.638618 -49.935531)
			(xy 59.591634 -49.915633) (xy 59.547718 -49.889655) (xy 59.52744 -49.87417) (xy 59.524392 -49.87163)
			(xy 59.522868 -49.870614) (xy 59.516264 -49.867312) (xy 59.511042 -49.864965) (xy 59.499889 -49.862393)
			(xy 59.494166 -49.862232) (xy 59.462162 -49.862232) (xy 59.462162 -49.851056) (xy 59.411362 -49.851056)
			(xy 59.402758 -49.851387) (xy 59.386524 -49.857098) (xy 59.379612 -49.862232) (xy 59.378088 -49.863502)
			(xy 59.357211 -49.880893) (xy 59.31146 -49.910205) (xy 59.262011 -49.932725) (xy 59.209866 -49.947998)
			(xy 59.156082 -49.955713) (xy 59.128914 -49.956212) (xy 59.103402 -49.955788) (xy 59.052833 -49.948996)
			(xy 59.003618 -49.935531) (xy 58.956634 -49.915633) (xy 58.912718 -49.889655) (xy 58.89244 -49.87417)
			(xy 58.889392 -49.87163) (xy 58.887868 -49.870614) (xy 58.881264 -49.867312) (xy 58.876042 -49.864965)
			(xy 58.864889 -49.862393) (xy 58.859166 -49.862232) (xy 58.827162 -49.862232) (xy 58.827162 -49.851056)
			(xy 58.776362 -49.851056) (xy 58.767758 -49.851387) (xy 58.751524 -49.857098) (xy 58.744612 -49.862232)
			(xy 58.743088 -49.863502) (xy 58.722211 -49.880893) (xy 58.67646 -49.910205) (xy 58.627011 -49.932725)
			(xy 58.574866 -49.947998) (xy 58.521082 -49.955713) (xy 58.493914 -49.956212) (xy 58.46666 -49.95575)
			(xy 58.412707 -49.947994) (xy 58.360407 -49.932639) (xy 58.310825 -49.909997) (xy 58.264969 -49.880529)
			(xy 58.223775 -49.844835) (xy 58.188079 -49.803642) (xy 58.158609 -49.757788) (xy 58.135966 -49.708206)
			(xy 58.120609 -49.655906) (xy 58.112851 -49.601954) (xy 58.112851 -49.547446) (xy 58.120609 -49.493494)
			(xy 58.135966 -49.441194) (xy 58.158609 -49.391612) (xy 58.188079 -49.345758) (xy 58.223775 -49.304565)
			(xy 58.264969 -49.268871) (xy 58.310825 -49.239403) (xy 58.360407 -49.216761) (xy 58.412707 -49.201406)
			(xy 58.46666 -49.19365) (xy 58.493914 -49.193196) (xy 58.519425 -49.193622) (xy 58.569993 -49.200417)
			(xy 58.619206 -49.213886) (xy 58.666187 -49.233787) (xy 58.710099 -49.259767) (xy 58.730388 -49.275238)
			(xy 58.733436 -49.277778) (xy 58.73496 -49.278794) (xy 58.741564 -49.282096) (xy 58.746787 -49.28444)
			(xy 58.75794 -49.287005) (xy 58.763662 -49.287176) (xy 58.795666 -49.287176) (xy 58.795666 -49.298352)
			(xy 58.846466 -49.298352) (xy 58.855069 -49.298016) (xy 58.871297 -49.2923) (xy 58.878216 -49.287176)
			(xy 58.87974 -49.285906) (xy 58.900616 -49.268511) (xy 58.946365 -49.23919) (xy 58.995813 -49.216659)
			(xy 59.047958 -49.201377) (xy 59.101745 -49.193651) (xy 59.128914 -49.193196) (xy 59.154425 -49.193622)
			(xy 59.204993 -49.200417) (xy 59.254206 -49.213886) (xy 59.301187 -49.233787) (xy 59.345099 -49.259767)
			(xy 59.365388 -49.275238) (xy 59.368436 -49.277778) (xy 59.36996 -49.278794) (xy 59.376564 -49.282096)
			(xy 59.381787 -49.28444) (xy 59.39294 -49.287005) (xy 59.398662 -49.287176) (xy 59.430666 -49.287176)
			(xy 59.430666 -49.298352) (xy 59.481466 -49.298352) (xy 59.490069 -49.298016) (xy 59.506297 -49.2923)
			(xy 59.513216 -49.287176) (xy 59.51474 -49.285906) (xy 59.522106 -49.279302) (xy 59.523122 -49.278794)
			(xy 59.524392 -49.277778) (xy 59.5249 -49.27727) (xy 59.546998 -49.26076) (xy 59.547252 -49.260506)
			(xy 59.54776 -49.260252) (xy 59.57062 -49.24552) (xy 59.571636 -49.245012) (xy 59.582304 -49.23917)
			(xy 59.589416 -49.235106) (xy 59.595766 -49.226216) (xy 59.599054 -49.22139) (xy 59.603547 -49.210613)
			(xy 59.604656 -49.20488) (xy 59.612022 -49.159922) (xy 59.61253 -49.156112) (xy 59.613207 -49.150964)
			(xy 59.612687 -49.140596) (xy 59.611514 -49.135538) (xy 59.610752 -49.132744) (xy 59.609441 -49.128878)
			(xy 59.605742 -49.1216) (xy 59.603386 -49.118266) (xy 59.431682 -48.895508) (xy 59.428888 -48.892206)
			(xy 53.869336 -42.831766) (xy 53.860959 -42.823429) (xy 53.838981 -42.814816) (xy 53.827172 -42.815256)
			(xy 53.815996 -42.817542) (xy 53.765704 -42.834052) (xy 53.765196 -42.834052) (xy 53.751226 -42.83837)
			(xy 53.747079 -42.839749) (xy 53.739286 -42.843702) (xy 53.735732 -42.846244) (xy 53.727567 -42.853038)
			(xy 53.717192 -42.871546) (xy 53.715666 -42.882058) (xy 53.71213 -42.911431) (xy 53.697547 -42.968766)
			(xy 53.67473 -43.02335) (xy 53.64417 -43.074007) (xy 53.606526 -43.119645) (xy 53.562607 -43.159282)
			(xy 53.513359 -43.192065) (xy 53.459844 -43.217287) (xy 53.403214 -43.234405) (xy 53.344688 -43.24305)
			(xy 53.315108 -43.2435) (xy 53.286348 -43.243012) (xy 53.229414 -43.234827) (xy 53.174223 -43.218623)
			(xy 53.121901 -43.194729) (xy 53.073512 -43.163632) (xy 53.030041 -43.125965) (xy 52.992373 -43.082495)
			(xy 52.961275 -43.034106) (xy 52.93738 -42.981784) (xy 52.921175 -42.926594) (xy 52.912989 -42.86966)
			(xy 52.912989 -42.81214) (xy 52.921175 -42.755206) (xy 52.93738 -42.700016) (xy 52.961275 -42.647694)
			(xy 52.992373 -42.599305) (xy 53.030041 -42.555835) (xy 53.073512 -42.518168) (xy 53.121901 -42.487071)
			(xy 53.174223 -42.463177) (xy 53.229414 -42.446973) (xy 53.286348 -42.438788) (xy 53.315108 -42.43832)
			(xy 53.31587 -42.43832) (xy 53.334717 -42.438563) (xy 53.372244 -42.442121) (xy 53.3908 -42.445432)
			(xy 53.402621 -42.447083) (xy 53.42556 -42.440608) (xy 53.434742 -42.432986) (xy 53.47081 -42.399966)
			(xy 53.462936 -42.388536) (xy 53.394864 -42.314622) (xy 53.360287 -42.275895) (xy 53.298565 -42.192408)
			(xy 53.271674 -42.147998) (xy 53.109622 -41.873424) (xy 52.768754 -41.296336) (xy 52.75961 -41.285922)
			(xy 52.756054 -41.283382) (xy 52.734854 -41.26791) (xy 52.696495 -41.232092) (xy 52.6796 -41.212008)
			(xy 52.662443 -41.190038) (xy 52.634008 -41.142096) (xy 52.622958 -41.116504) (xy 52.622196 -41.114218)
			(xy 52.612844 -41.08999) (xy 52.600096 -41.039647) (xy 52.596796 -41.013888) (xy 52.595526 -41.002966)
			(xy 52.361846 -40.60698) (xy 52.306728 -40.513762) (xy 52.229766 -40.383714) (xy 52.229766 -40.383206)
			(xy 52.219352 -40.366188) (xy 52.191354 -40.36153) (xy 52.136961 -40.345324) (xy 52.085417 -40.321564)
			(xy 52.037766 -40.290732) (xy 51.994971 -40.25345) (xy 51.957899 -40.210474) (xy 51.9273 -40.162672)
			(xy 51.903792 -40.111013) (xy 51.887852 -40.056541) (xy 51.879802 -40.000358) (xy 51.879246 -39.97198)
			(xy 51.879246 -39.971726) (xy 51.879816 -39.941665) (xy 51.888875 -39.88223) (xy 51.89728 -39.853362)
			(xy 51.89989 -39.843036) (xy 51.897383 -39.821911) (xy 51.892454 -39.812468) (xy 51.580542 -39.284148)
			(xy 51.38166 -38.94709) (xy 51.375772 -38.938826) (xy 51.358997 -38.927438) (xy 51.349148 -38.924992)
			(xy 51.339242 -38.923976) (xy 51.265836 -38.923722) (xy 51.251866 -38.9255) (xy 51.246024 -38.927278)
			(xy 51.240436 -38.930326) (xy 51.239928 -38.930326) (xy 51.216306 -38.943788) (xy 51.212758 -38.946283)
			(xy 51.206494 -38.952281) (xy 51.20386 -38.955726) (xy 51.202082 -38.958266) (xy 51.186927 -38.980784)
			(xy 51.151258 -39.021694) (xy 51.110145 -39.05713) (xy 51.06442 -39.086375) (xy 51.015009 -39.108836)
			(xy 50.962911 -39.12406) (xy 50.909181 -39.131738) (xy 50.882042 -39.132256) (xy 50.869304 -39.132179)
			(xy 50.843882 -39.130528) (xy 50.831242 -39.128954) (xy 50.803751 -39.124758) (xy 50.750294 -39.109436)
			(xy 50.699631 -39.086507) (xy 50.652838 -39.05646) (xy 50.610909 -39.019932) (xy 50.574733 -38.977698)
			(xy 50.559462 -38.954456) (xy 50.555906 -38.948868) (xy 50.551588 -38.944804) (xy 50.54346 -38.938454)
			(xy 50.512472 -38.919658) (xy 50.49901 -38.918896) (xy 50.429668 -38.914324) (xy 50.418828 -38.914111)
			(xy 50.398556 -38.921743) (xy 50.390552 -38.929056) (xy 50.386742 -38.932866) (xy 50.384964 -38.935152)
			(xy 50.384202 -38.936168) (xy 50.36599 -38.958792) (xy 50.323882 -38.99879) (xy 50.276205 -39.031954)
			(xy 50.224058 -39.05752) (xy 50.168642 -39.074898) (xy 50.111234 -39.083688) (xy 50.082196 -39.08425)
			(xy 50.081942 -39.08425) (xy 50.054684 -39.08379) (xy 50.000723 -39.076037) (xy 49.948414 -39.060683)
			(xy 49.898823 -39.03804) (xy 49.85296 -39.00857) (xy 49.811757 -38.972872) (xy 49.776055 -38.931674)
			(xy 49.74658 -38.885814) (xy 49.723932 -38.836225) (xy 49.708572 -38.783918) (xy 49.700813 -38.729958)
			(xy 49.700813 -38.675442) (xy 49.708572 -38.621482) (xy 49.723932 -38.569175) (xy 49.74658 -38.519586)
			(xy 49.776055 -38.473726) (xy 49.811757 -38.432528) (xy 49.85296 -38.39683) (xy 49.898823 -38.36736)
			(xy 49.948414 -38.344717) (xy 50.000723 -38.329363) (xy 50.054684 -38.32161) (xy 50.081942 -38.321234)
			(xy 50.10941 -38.321715) (xy 50.163778 -38.3296) (xy 50.216453 -38.3452) (xy 50.266347 -38.368193)
			(xy 50.312427 -38.398104) (xy 50.353741 -38.434314) (xy 50.389435 -38.476074) (xy 50.404522 -38.499034)
			(xy 50.407824 -38.504368) (xy 50.411888 -38.508432) (xy 50.420778 -38.515036) (xy 50.440336 -38.527228)
			(xy 50.442114 -38.528244) (xy 50.446457 -38.530545) (xy 50.455794 -38.533615) (xy 50.460656 -38.53434)
			(xy 50.463958 -38.534594) (xy 50.467514 -38.534848) (xy 50.53711 -38.539166) (xy 50.542386 -38.539164)
			(xy 50.552757 -38.537243) (xy 50.557684 -38.535356) (xy 50.561748 -38.533324) (xy 50.566489 -38.530706)
			(xy 50.574821 -38.523792) (xy 50.578258 -38.519608) (xy 50.578766 -38.5191) (xy 50.580798 -38.51656)
			(xy 50.598188 -38.494996) (xy 50.638155 -38.456637) (xy 50.683249 -38.424461) (xy 50.732523 -38.399146)
			(xy 50.78494 -38.381223) (xy 50.839398 -38.37107) (xy 50.867056 -38.369494) (xy 50.880518 -38.368986)
			(xy 50.891948 -38.361874) (xy 50.897338 -38.358226) (xy 50.90621 -38.348709) (xy 50.909474 -38.343078)
			(xy 50.955448 -38.259004) (xy 50.957734 -38.25494) (xy 50.95748 -38.235128) (xy 50.953416 -38.22192)
			(xy 50.950114 -38.216586) (xy 50.950114 -38.216078) (xy 50.692812 -37.780468) (xy 50.691288 -37.778182)
			(xy 50.688673 -37.774384) (xy 50.682278 -37.767741) (xy 50.678588 -37.764974) (xy 50.645381 -37.740703)
			(xy 50.582686 -37.68745) (xy 50.524634 -37.629171) (xy 50.471627 -37.566269) (xy 50.424032 -37.499178)
			(xy 50.402744 -37.463984) (xy 50.1777 -37.083238) (xy 50.155456 -37.044637) (xy 50.117213 -36.964165)
			(xy 50.086374 -36.880575) (xy 50.06319 -36.794548) (xy 50.055018 -36.750752) (xy 50.053494 -36.744402)
			(xy 50.051482 -36.738568) (xy 50.045059 -36.728034) (xy 50.040794 -36.723574) (xy 50.022989 -36.705171)
			(xy 49.99196 -36.664437) (xy 49.966652 -36.619922) (xy 49.95672 -36.59632) (xy 49.951386 -36.58235)
			(xy 49.947576 -36.571682) (xy 49.527968 -36.145724) (xy 49.520541 -36.13878) (xy 49.501805 -36.13093)
			(xy 49.491646 -36.130484) (xy 49.477676 -36.130484) (xy 49.46771 -36.130962) (xy 49.449273 -36.138537)
			(xy 49.441862 -36.145216) (xy 49.441608 -36.14547) (xy 49.419982 -36.166446) (xy 49.371346 -36.201997)
			(xy 49.317728 -36.229466) (xy 49.260461 -36.248168) (xy 49.200966 -36.257641) (xy 49.170844 -36.258246)
			(xy 49.143588 -36.257786) (xy 49.08963 -36.250035) (xy 49.037325 -36.234683) (xy 48.987737 -36.212043)
			(xy 48.941875 -36.182577) (xy 48.900674 -36.146884) (xy 48.864972 -36.10569) (xy 48.835496 -36.059835)
			(xy 48.812846 -36.010252) (xy 48.797483 -35.95795) (xy 48.78972 -35.903994) (xy 48.789336 -35.876738)
			(xy 48.789336 -35.86353) (xy 48.790911 -35.833962) (xy 48.802066 -35.775814) (xy 48.822078 -35.72009)
			(xy 48.850465 -35.66813) (xy 48.868076 -35.644328) (xy 48.87087 -35.640772) (xy 48.871378 -35.64001)
			(xy 48.87341 -35.635692) (xy 48.876176 -35.629728) (xy 48.878866 -35.616865) (xy 48.878744 -35.610292)
			(xy 48.87722 -35.581082) (xy 48.87722 -35.580828) (xy 48.876592 -35.574142) (xy 48.872347 -35.561407)
			(xy 48.868838 -35.555682) (xy 48.862488 -35.547808) (xy 48.678084 -35.363404) (xy 48.644556 -35.328098)
			(xy 48.644048 -35.32759) (xy 48.64354 -35.326828) (xy 48.640238 -35.323526) (xy 48.63973 -35.32251)
			(xy 48.637952 -35.320732) (xy 48.63592 -35.318446) (xy 48.628808 -35.312096) (xy 48.621442 -35.308794)
			(xy 48.617733 -35.307231) (xy 48.609947 -35.305192) (xy 48.605948 -35.30473) (xy 48.589184 -35.302952)
			(xy 48.584317 -35.302574) (xy 48.574596 -35.303469) (xy 48.56988 -35.30473) (xy 48.56099 -35.30727)
			(xy 48.553116 -35.313112) (xy 48.516326 -35.340592) (xy 48.438563 -35.389444) (xy 48.356641 -35.430944)
			(xy 48.271252 -35.464741) (xy 48.183118 -35.49055) (xy 48.092986 -35.508151) (xy 48.001619 -35.517396)
			(xy 47.955708 -35.518344) (xy 47.947326 -35.518344) (xy 47.904835 -35.517898) (xy 47.82016 -35.51066)
			(xy 47.736409 -35.496243) (xy 47.654189 -35.474753) (xy 47.574095 -35.446343) (xy 47.496709 -35.411222)
			(xy 47.422593 -35.369642) (xy 47.352283 -35.321907) (xy 47.28629 -35.268362) (xy 47.225093 -35.209396)
			(xy 47.196756 -35.17773) (xy 47.168682 -35.144918) (xy 47.117682 -35.075224) (xy 47.094902 -35.038538)
			(xy 47.092362 -35.034474) (xy 47.079916 -35.020758) (xy 47.076614 -35.018218) (xy 47.054478 -35.000022)
			(xy 47.015387 -34.958124) (xy 46.982993 -34.910858) (xy 46.958021 -34.859284) (xy 46.941031 -34.804559)
			(xy 46.932405 -34.74791) (xy 46.931834 -34.71926) (xy 46.931834 -34.718752) (xy 46.931834 -34.711894)
			(xy 46.93285 -34.689796) (xy 46.936914 -34.65576) (xy 46.939 -34.643997) (xy 46.944466 -34.620739)
			(xy 46.947836 -34.609278) (xy 46.947836 -34.60877) (xy 46.949614 -34.602928) (xy 46.9519 -34.588196)
			(xy 46.9519 -34.584386) (xy 46.951646 -34.581592) (xy 46.949868 -34.521902) (xy 46.949868 -34.520886)
			(xy 46.9503 -34.478939) (xy 46.957346 -34.39534) (xy 46.971386 -34.312629) (xy 46.992321 -34.231388)
			(xy 47.020003 -34.152192) (xy 47.036736 -34.113724) (xy 47.038514 -34.10966) (xy 47.043086 -34.089594)
			(xy 47.043086 -34.088578) (xy 47.03953 -34.073338) (xy 47.036482 -34.063686) (xy 47.019802 -34.025283)
			(xy 46.992191 -33.946233) (xy 46.971312 -33.865145) (xy 46.95731 -33.782591) (xy 46.950285 -33.699153)
			(xy 46.949868 -33.657286) (xy 46.9519 -33.595564) (xy 46.952662 -33.584134) (xy 46.949868 -33.575498)
			(xy 46.948197 -33.57135) (xy 46.943602 -33.56368) (xy 46.940724 -33.560258) (xy 46.90618 -33.523936)
			(xy 46.899378 -33.517895) (xy 46.882721 -33.510612) (xy 46.873668 -33.509712) (xy 46.640242 -33.509712)
			(xy 46.599798 -33.509277) (xy 46.51918 -33.502667) (xy 46.479206 -33.496504) (xy 46.47819 -33.496504)
			(xy 46.47311 -33.495742) (xy 46.47184 -33.495742) (xy 46.430773 -33.493161) (xy 46.349238 -33.482031)
			(xy 46.268909 -33.464168) (xy 46.190341 -33.439695) (xy 46.152054 -33.424622) (xy 46.148752 -33.423352)
			(xy 46.142402 -33.420812) (xy 46.029626 -33.420812) (xy 46.01999 -33.421271) (xy 46.002098 -33.428443)
			(xy 45.994828 -33.434782) (xy 45.96395 -33.463704) (xy 45.898076 -33.516805) (xy 45.827939 -33.564132)
			(xy 45.754044 -33.605344) (xy 45.676921 -33.640144) (xy 45.597126 -33.668284) (xy 45.515234 -33.689559)
			(xy 45.431833 -33.703818) (xy 45.347524 -33.710956) (xy 45.305218 -33.711388) (xy 45.258745 -33.710851)
			(xy 45.166203 -33.702198) (xy 45.074868 -33.684974) (xy 44.98553 -33.659329) (xy 44.898965 -33.625485)
			(xy 44.815924 -33.583736) (xy 44.737126 -33.534443) (xy 44.663255 -33.478035) (xy 44.594951 -33.415)
			(xy 44.532806 -33.345884) (xy 44.47736 -33.271288) (xy 44.452794 -33.231836) (xy 44.45127 -33.22955)
			(xy 44.450254 -33.227772) (xy 44.447735 -33.223793) (xy 44.441468 -33.216766) (xy 44.437808 -33.213802)
			(xy 44.415185 -33.195589) (xy 44.375189 -33.15348) (xy 44.342027 -33.105803) (xy 44.316464 -33.053656)
			(xy 44.299087 -32.998241) (xy 44.290297 -32.940834) (xy 44.289726 -32.911796) (xy 44.289726 -32.911034)
			(xy 44.29023 -32.882599) (xy 44.298648 -32.826357) (xy 44.30649 -32.79902) (xy 44.308014 -32.791908)
			(xy 44.309792 -32.780986) (xy 44.309792 -32.777176) (xy 44.309538 -32.774382) (xy 44.30776 -32.714692)
			(xy 44.30776 -32.707326) (xy 44.308359 -32.670113) (xy 44.314417 -32.595927) (xy 44.325994 -32.522399)
			(xy 44.334176 -32.486092) (xy 44.345542 -32.440144) (xy 44.375819 -32.350458) (xy 44.394628 -32.307022)
			(xy 44.396406 -32.302958) (xy 44.400978 -32.282892) (xy 44.400978 -32.281876) (xy 44.396406 -32.26181)
			(xy 44.395136 -32.259016) (xy 44.379012 -32.222083) (xy 44.352074 -32.146125) (xy 44.331345 -32.068242)
			(xy 44.31696 -31.988943) (xy 44.312586 -31.948882) (xy 44.310322 -31.924434) (xy 44.30791 -31.87539)
			(xy 44.30776 -31.850838) (xy 44.30776 -31.850584) (xy 44.309538 -31.789878) (xy 44.309792 -31.78683)
			(xy 44.309792 -31.78302) (xy 44.308014 -31.772098) (xy 44.30649 -31.76524) (xy 44.298662 -31.7379)
			(xy 44.290243 -31.68166) (xy 44.289726 -31.653226) (xy 44.289726 -31.652972) (xy 44.290271 -31.623902)
			(xy 44.299082 -31.566434) (xy 44.316495 -31.510963) (xy 44.34211 -31.458769) (xy 44.375334 -31.411058)
			(xy 44.415402 -31.36893) (xy 44.438062 -31.350712) (xy 44.443142 -31.34614) (xy 44.448984 -31.339028)
			(xy 44.471769 -31.301761) (xy 44.522928 -31.230953) (xy 44.58009 -31.164895) (xy 44.642816 -31.104096)
			(xy 44.710623 -31.049021) (xy 44.782992 -31.000094) (xy 44.859366 -30.957691) (xy 44.899072 -30.939486)
			(xy 44.937435 -30.922858) (xy 45.016396 -30.895337) (xy 45.097384 -30.874523) (xy 45.179829 -30.860561)
			(xy 45.263154 -30.85355) (xy 45.304964 -30.853126) (xy 45.305218 -30.853126) (xy 45.3478 -30.853573)
			(xy 45.432653 -30.860834) (xy 45.516579 -30.875302) (xy 45.598966 -30.896872) (xy 45.679214 -30.925387)
			(xy 45.756739 -30.960638) (xy 45.830977 -31.002369) (xy 45.901388 -31.050277) (xy 45.967458 -31.104013)
			(xy 45.998384 -31.133288) (xy 46.004651 -31.137821) (xy 46.019129 -31.143246) (xy 46.026832 -31.143956)
			(xy 46.87697 -31.143956) (xy 46.883828 -31.143448) (xy 46.892621 -31.141918) (xy 46.908404 -31.133607)
			(xy 46.920363 -31.120372) (xy 46.92396 -31.112206) (xy 46.932596 -31.09087) (xy 46.933358 -31.08325)
			(xy 46.933358 -31.082996) (xy 46.93412 -31.07563) (xy 46.936297 -31.057836) (xy 46.943546 -31.022726)
			(xy 46.948598 -31.005526) (xy 46.950122 -30.998414) (xy 46.9519 -30.987492) (xy 46.9519 -30.983682)
			(xy 46.951646 -30.980888) (xy 46.949868 -30.92069) (xy 46.950309 -30.878824) (xy 46.957347 -30.79539)
			(xy 46.971349 -30.712837) (xy 46.992215 -30.631748) (xy 47.019799 -30.55269) (xy 47.036482 -30.51429)
			(xy 47.03953 -30.504638) (xy 47.043086 -30.489398) (xy 47.043086 -30.488382) (xy 47.038514 -30.468316)
			(xy 47.036736 -30.464252) (xy 47.017177 -30.419035) (xy 46.986026 -30.325565) (xy 46.964231 -30.229482)
			(xy 46.952002 -30.13172) (xy 46.950122 -30.08249) (xy 46.949868 -30.058614) (xy 46.949868 -30.056836)
			(xy 46.950122 -30.034738) (xy 46.950376 -30.03042) (xy 46.950376 -30.029912) (xy 46.95063 -30.021784)
			(xy 46.95063 -30.019752) (xy 46.94682 -30.0101) (xy 46.944847 -30.00562) (xy 46.939475 -29.997438)
			(xy 46.936152 -29.993844) (xy 46.891956 -29.948632) (xy 46.884718 -29.94239) (xy 46.866962 -29.935353)
			(xy 46.857412 -29.934916) (xy 46.845728 -29.934916) (xy 46.799007 -29.934339) (xy 46.705988 -29.925452)
			(xy 46.614223 -29.907819) (xy 46.524534 -29.8816) (xy 46.437722 -29.847028) (xy 46.395894 -29.826204)
			(xy 46.390468 -29.823617) (xy 46.378788 -29.820784) (xy 46.37278 -29.820616) (xy 46.039278 -29.820616)
			(xy 46.034387 -29.82075) (xy 46.024792 -29.822663) (xy 46.020228 -29.824426) (xy 45.995082 -29.834586)
			(xy 45.98797 -29.84119) (xy 45.953477 -29.872859) (xy 45.879513 -29.930298) (xy 45.800493 -29.980554)
			(xy 45.717112 -30.023185) (xy 45.630104 -30.057816) (xy 45.540234 -30.084143) (xy 45.448292 -30.101934)
			(xy 45.355088 -30.111032) (xy 45.308266 -30.1117) (xy 45.29836 -30.1117) (xy 45.25153 -30.11084)
			(xy 45.158335 -30.10141) (xy 45.066434 -30.083285) (xy 44.976638 -30.056625) (xy 44.889736 -30.021663)
			(xy 44.806495 -29.978709) (xy 44.727647 -29.928141) (xy 44.653887 -29.870403) (xy 44.585864 -29.806005)
			(xy 44.554648 -29.771086) (xy 44.526576 -29.738273) (xy 44.475578 -29.668577) (xy 44.452794 -29.631894)
			(xy 44.450254 -29.62783) (xy 44.437808 -29.614114) (xy 44.434506 -29.611574) (xy 44.412367 -29.593378)
			(xy 44.373272 -29.551482) (xy 44.340871 -29.504217) (xy 44.315892 -29.452643) (xy 44.298895 -29.397918)
			(xy 44.290261 -29.341267) (xy 44.289726 -29.312616) (xy 44.289726 -29.312108) (xy 44.289726 -29.30525)
			(xy 44.290742 -29.283152) (xy 44.294806 -29.249116) (xy 44.29689 -29.237353) (xy 44.302353 -29.214094)
			(xy 44.305728 -29.202634) (xy 44.305728 -29.202126) (xy 44.307506 -29.196284) (xy 44.309792 -29.181552)
			(xy 44.309792 -29.177742) (xy 44.309538 -29.174948) (xy 44.30776 -29.115258) (xy 44.30776 -29.114242)
			(xy 44.308194 -29.072295) (xy 44.315243 -28.988698) (xy 44.329286 -28.905987) (xy 44.350224 -28.824748)
			(xy 44.37791 -28.745554) (xy 44.394628 -28.70708) (xy 44.396406 -28.703016) (xy 44.400978 -28.68295)
			(xy 44.400978 -28.681934) (xy 44.396406 -28.661868) (xy 44.394628 -28.657804) (xy 44.377954 -28.619476)
			(xy 44.350334 -28.540579) (xy 44.329417 -28.459647) (xy 44.315349 -28.377248) (xy 44.308229 -28.293961)
			(xy 44.30776 -28.252166) (xy 44.30776 -28.250642) (xy 44.309538 -28.189936) (xy 44.309792 -28.187142)
			(xy 44.309792 -28.183332) (xy 44.308014 -28.17241) (xy 44.30649 -28.165298) (xy 44.298651 -28.137896)
			(xy 44.290238 -28.081527) (xy 44.289726 -28.05303) (xy 44.289726 -28.04668) (xy 44.28998 -28.038298)
			(xy 44.29125 -28.01874) (xy 44.29125 -28.018486) (xy 44.291758 -28.012898) (xy 44.295429 -27.983489)
			(xy 44.310691 -27.926225) (xy 44.334621 -27.872007) (xy 44.350178 -27.846782) (xy 44.35348 -27.841702)
			(xy 44.370685 -27.816867) (xy 44.411643 -27.772456) (xy 44.435014 -27.75331) (xy 44.440856 -27.747722)
			(xy 44.445682 -27.742388) (xy 44.451778 -27.73426) (xy 44.474778 -27.697232) (xy 44.526288 -27.626901)
			(xy 44.554648 -27.593798) (xy 44.58296 -27.562108) (xy 44.644156 -27.50314) (xy 44.71015 -27.449594)
			(xy 44.780462 -27.40186) (xy 44.854582 -27.360284) (xy 44.931972 -27.325168) (xy 45.01207 -27.296766)
			(xy 45.094294 -27.275284) (xy 45.178049 -27.26088) (xy 45.262726 -27.253656) (xy 45.305218 -27.253184)
			(xy 45.305472 -27.253184) (xy 45.352991 -27.253738) (xy 45.447598 -27.262794) (xy 45.540912 -27.280817)
			(xy 45.632087 -27.307644) (xy 45.720292 -27.343029) (xy 45.804728 -27.386653) (xy 45.844968 -27.411934)
			(xy 45.882903 -27.436962) (xy 45.954519 -27.492929) (xy 45.98797 -27.523694) (xy 45.993304 -27.528774)
			(xy 45.994574 -27.530044) (xy 45.994828 -27.530298) (xy 46.020228 -27.540458) (xy 46.024795 -27.542211)
			(xy 46.034388 -27.544124) (xy 46.039278 -27.544268) (xy 47.940468 -27.544268) (xy 47.985932 -27.544795)
			(xy 48.076478 -27.553123) (xy 48.165889 -27.569669) (xy 48.25342 -27.594293) (xy 48.296068 -27.610054)
			(xy 48.322484 -27.620722) (xy 49.688242 -28.189428) (xy 49.710513 -28.198784) (xy 49.75422 -28.219368)
			(xy 49.775618 -28.230576) (xy 49.787048 -28.235148) (xy 49.788064 -28.235402) (xy 49.796489 -28.237185)
			(xy 49.813627 -28.235626) (xy 49.821592 -28.232354) (xy 49.843436 -28.222194) (xy 49.850548 -28.21432)
			(xy 49.868714 -28.194744) (xy 49.909576 -28.160356) (xy 49.954834 -28.132004) (xy 50.003604 -28.110241)
			(xy 50.054933 -28.095493) (xy 50.107817 -28.088047) (xy 50.13452 -28.087574) (xy 50.161771 -28.088061)
			(xy 50.215717 -28.09582) (xy 50.268011 -28.111177) (xy 50.317587 -28.133819) (xy 50.32586 -28.139136)
			(xy 54.397908 -28.139136) (xy 54.401979 -28.083514) (xy 54.414105 -28.029077) (xy 54.434028 -27.976986)
			(xy 54.461324 -27.928351) (xy 54.49541 -27.884208) (xy 54.535559 -27.845499) (xy 54.580917 -27.813048)
			(xy 54.630517 -27.787547) (xy 54.683301 -27.76954) (xy 54.738144 -27.75941) (xy 54.793878 -27.757373)
			(xy 54.849315 -27.763473) (xy 54.903272 -27.777579) (xy 54.954601 -27.799391) (xy 55.002207 -27.828445)
			(xy 55.045075 -27.86412) (xy 55.082292 -27.905657) (xy 55.113065 -27.95217) (xy 55.136737 -28.002667)
			(xy 55.152805 -28.056074) (xy 55.160925 -28.11125) (xy 55.161434 -28.139136) (xy 55.667908 -28.139136)
			(xy 55.671979 -28.083514) (xy 55.684105 -28.029077) (xy 55.704028 -27.976986) (xy 55.731324 -27.928351)
			(xy 55.76541 -27.884208) (xy 55.805559 -27.845499) (xy 55.850917 -27.813048) (xy 55.900517 -27.787547)
			(xy 55.953301 -27.76954) (xy 56.008144 -27.75941) (xy 56.063878 -27.757373) (xy 56.119315 -27.763473)
			(xy 56.173272 -27.777579) (xy 56.224601 -27.799391) (xy 56.272207 -27.828445) (xy 56.315075 -27.86412)
			(xy 56.352292 -27.905657) (xy 56.383065 -27.95217) (xy 56.406737 -28.002667) (xy 56.422805 -28.056074)
			(xy 56.430925 -28.11125) (xy 56.431434 -28.139136) (xy 56.430925 -28.167022) (xy 56.422805 -28.222198)
			(xy 56.406737 -28.275605) (xy 56.383065 -28.326102) (xy 56.352292 -28.372615) (xy 56.315075 -28.414152)
			(xy 56.272207 -28.449827) (xy 56.224601 -28.478881) (xy 56.173272 -28.500693) (xy 56.119315 -28.514799)
			(xy 56.063878 -28.520899) (xy 56.008144 -28.518862) (xy 55.953301 -28.508732) (xy 55.900517 -28.490725)
			(xy 55.850917 -28.465224) (xy 55.805559 -28.432773) (xy 55.76541 -28.394064) (xy 55.731324 -28.349921)
			(xy 55.704028 -28.301286) (xy 55.684105 -28.249195) (xy 55.671979 -28.194758) (xy 55.667908 -28.139136)
			(xy 55.161434 -28.139136) (xy 55.160925 -28.167022) (xy 55.152805 -28.222198) (xy 55.136737 -28.275605)
			(xy 55.113065 -28.326102) (xy 55.082292 -28.372615) (xy 55.045075 -28.414152) (xy 55.002207 -28.449827)
			(xy 54.954601 -28.478881) (xy 54.903272 -28.500693) (xy 54.849315 -28.514799) (xy 54.793878 -28.520899)
			(xy 54.738144 -28.518862) (xy 54.683301 -28.508732) (xy 54.630517 -28.490725) (xy 54.580917 -28.465224)
			(xy 54.535559 -28.432773) (xy 54.49541 -28.394064) (xy 54.461324 -28.349921) (xy 54.434028 -28.301286)
			(xy 54.414105 -28.249195) (xy 54.401979 -28.194758) (xy 54.397908 -28.139136) (xy 50.32586 -28.139136)
			(xy 50.363436 -28.163285) (xy 50.404625 -28.198976) (xy 50.440316 -28.240166) (xy 50.469782 -28.286015)
			(xy 50.492424 -28.335591) (xy 50.507781 -28.387885) (xy 50.515539 -28.441831) (xy 50.516028 -28.469082)
			(xy 50.515576 -28.495877) (xy 50.508082 -28.548939) (xy 50.493238 -28.600431) (xy 50.471336 -28.64934)
			(xy 50.442807 -28.694704) (xy 50.425858 -28.715462) (xy 50.421198 -28.721249) (xy 50.415123 -28.734801)
			(xy 50.41392 -28.742132) (xy 50.413666 -28.751022) (xy 50.41519 -28.78201) (xy 50.415444 -28.788614)
			(xy 50.415698 -28.7909) (xy 50.416882 -28.799723) (xy 50.424404 -28.815844) (xy 50.43043 -28.822396)
			(xy 50.517044 -28.908502) (xy 50.732378 -29.12237) (xy 60.60694 -29.12237) (xy 60.60694 -28.25877)
			(xy 60.60743 -28.228802) (xy 60.615253 -28.16938) (xy 60.630766 -28.111487) (xy 60.653702 -28.056114)
			(xy 60.683669 -28.004208) (xy 60.720156 -27.956658) (xy 60.762536 -27.914278) (xy 60.810086 -27.877791)
			(xy 60.861992 -27.847824) (xy 60.917365 -27.824888) (xy 60.975258 -27.809375) (xy 61.03468 -27.801552)
			(xy 61.094616 -27.801552) (xy 61.154038 -27.809375) (xy 61.211931 -27.824888) (xy 61.267304 -27.847824)
			(xy 61.31921 -27.877791) (xy 61.36676 -27.914278) (xy 61.40914 -27.956658) (xy 61.445627 -28.004208)
			(xy 61.475594 -28.056114) (xy 61.49853 -28.111487) (xy 61.514043 -28.16938) (xy 61.521866 -28.228802)
			(xy 61.522356 -28.25877) (xy 61.522356 -29.12237) (xy 61.521866 -29.152338) (xy 61.514043 -29.21176)
			(xy 61.49853 -29.269653) (xy 61.475594 -29.325026) (xy 61.445627 -29.376932) (xy 61.40914 -29.424482)
			(xy 61.36676 -29.466862) (xy 61.31921 -29.503349) (xy 61.267304 -29.533316) (xy 61.211931 -29.556252)
			(xy 61.154038 -29.571765) (xy 61.094616 -29.579588) (xy 61.03468 -29.579588) (xy 60.975258 -29.571765)
			(xy 60.917365 -29.556252) (xy 60.861992 -29.533316) (xy 60.810086 -29.503349) (xy 60.762536 -29.466862)
			(xy 60.720156 -29.424482) (xy 60.683669 -29.376932) (xy 60.653702 -29.325026) (xy 60.630766 -29.269653)
			(xy 60.615253 -29.21176) (xy 60.60743 -29.152338) (xy 60.60694 -29.12237) (xy 50.732378 -29.12237)
			(xy 51.076606 -29.464254) (xy 51.083013 -29.470131) (xy 51.098728 -29.477542) (xy 51.10734 -29.478732)
			(xy 51.115976 -29.479494) (xy 51.132994 -29.475176) (xy 51.140868 -29.469842) (xy 51.14798 -29.465016)
			(xy 51.148488 -29.465016) (xy 51.157886 -29.45892) (xy 51.15814 -29.45892) (xy 51.158902 -29.458412)
			(xy 51.16957 -29.452316) (xy 51.197639 -29.437169) (xy 51.25759 -29.415411) (xy 51.32032 -29.403905)
			(xy 51.352196 -29.402786) (xy 51.364134 -29.402786) (xy 51.390777 -29.403693) (xy 51.44343 -29.41203)
			(xy 51.49441 -29.427614) (xy 51.542725 -29.450143) (xy 51.587433 -29.479177) (xy 51.627665 -29.514152)
			(xy 51.662637 -29.554386) (xy 51.691669 -29.599097) (xy 51.714195 -29.647413) (xy 51.729776 -29.698394)
			(xy 51.738109 -29.751048) (xy 51.739038 -29.77769) (xy 51.739038 -29.784294) (xy 51.739038 -29.784802)
			(xy 51.73861 -29.810394) (xy 51.731731 -29.861114) (xy 51.725322 -29.885894) (xy 51.716435 -29.915881)
			(xy 51.690269 -29.972683) (xy 51.673252 -29.998924) (xy 51.668426 -30.005782) (xy 51.662838 -30.014418)
			(xy 51.664616 -30.032198) (xy 51.665851 -30.040893) (xy 51.673374 -30.05675) (xy 51.679348 -30.063186)
			(xy 51.994944 -30.376876) (xy 52.888896 -30.376876) (xy 52.889433 -30.347959) (xy 52.898153 -30.290787)
			(xy 52.915405 -30.235587) (xy 52.940793 -30.183625) (xy 52.973735 -30.136091) (xy 53.013476 -30.094075)
			(xy 53.035962 -30.075886) (xy 53.044776 -30.068286) (xy 53.054953 -30.047379) (xy 53.05552 -30.035754)
			(xy 53.05552 -29.955998) (xy 53.054961 -29.944369) (xy 53.044785 -29.92346) (xy 53.035962 -29.915866)
			(xy 53.013454 -29.897704) (xy 52.973722 -29.855677) (xy 52.940787 -29.808136) (xy 52.915403 -29.756169)
			(xy 52.898152 -29.700967) (xy 52.889428 -29.643794) (xy 52.888896 -29.614876) (xy 52.889382 -29.587625)
			(xy 52.897138 -29.533677) (xy 52.912493 -29.481382) (xy 52.935135 -29.431805) (xy 52.964601 -29.385955)
			(xy 53.000292 -29.344764) (xy 53.041483 -29.309073) (xy 53.087333 -29.279607) (xy 53.13691 -29.256965)
			(xy 53.189205 -29.24161) (xy 53.243153 -29.233854) (xy 53.297655 -29.233854) (xy 53.351603 -29.24161)
			(xy 53.403898 -29.256965) (xy 53.453475 -29.279607) (xy 53.499325 -29.309073) (xy 53.540516 -29.344764)
			(xy 53.576207 -29.385955) (xy 53.605673 -29.431805) (xy 53.628315 -29.481382) (xy 53.64367 -29.533677)
			(xy 53.651426 -29.587625) (xy 53.651912 -29.614876) (xy 53.65141 -29.643794) (xy 53.642682 -29.700967)
			(xy 53.625423 -29.756168) (xy 53.600029 -29.80813) (xy 53.567081 -29.855664) (xy 53.527334 -29.897678)
			(xy 53.504846 -29.915866) (xy 53.496055 -29.923488) (xy 53.485865 -29.944378) (xy 53.485288 -29.955998)
			(xy 53.485288 -30.035754) (xy 53.485815 -30.047387) (xy 53.496013 -30.068296) (xy 53.504846 -30.075886)
			(xy 53.527332 -30.094073) (xy 53.567065 -30.136095) (xy 53.600003 -30.183631) (xy 53.62539 -30.235593)
			(xy 53.642646 -30.290791) (xy 53.651376 -30.34796) (xy 53.651912 -30.376876) (xy 55.929022 -30.376876)
			(xy 55.929586 -30.347961) (xy 55.938305 -30.290791) (xy 55.955553 -30.235593) (xy 55.980936 -30.183631)
			(xy 56.013872 -30.136096) (xy 56.053606 -30.094077) (xy 56.076088 -30.075886) (xy 56.08489 -30.068273)
			(xy 56.095077 -30.047377) (xy 56.095646 -30.035754) (xy 56.095646 -29.955998) (xy 56.095113 -29.944365)
			(xy 56.084922 -29.923454) (xy 56.076088 -29.915866) (xy 56.053586 -29.897697) (xy 56.013852 -29.855672)
			(xy 55.980916 -29.808133) (xy 55.955531 -29.756167) (xy 55.938279 -29.700966) (xy 55.929554 -29.643793)
			(xy 55.929022 -29.614876) (xy 55.929508 -29.587625) (xy 55.937264 -29.533677) (xy 55.952619 -29.481382)
			(xy 55.975261 -29.431805) (xy 56.004727 -29.385955) (xy 56.040418 -29.344764) (xy 56.081609 -29.309073)
			(xy 56.127459 -29.279607) (xy 56.177036 -29.256965) (xy 56.229331 -29.24161) (xy 56.283279 -29.233854)
			(xy 56.337781 -29.233854) (xy 56.391729 -29.24161) (xy 56.444024 -29.256965) (xy 56.493601 -29.279607)
			(xy 56.539451 -29.309073) (xy 56.580642 -29.344764) (xy 56.616333 -29.385955) (xy 56.645799 -29.431805)
			(xy 56.668441 -29.481382) (xy 56.683796 -29.533677) (xy 56.691552 -29.587625) (xy 56.692038 -29.614876)
			(xy 56.691526 -29.643793) (xy 56.682799 -29.700966) (xy 56.665541 -29.756166) (xy 56.640149 -29.808128)
			(xy 56.607203 -29.855662) (xy 56.567459 -29.897677) (xy 56.544972 -29.915866) (xy 56.536185 -29.923493)
			(xy 56.525992 -29.944379) (xy 56.525414 -29.955998) (xy 56.525414 -30.035754) (xy 56.525931 -30.047389)
			(xy 56.536135 -30.068298) (xy 56.544972 -30.075886) (xy 56.567443 -30.094092) (xy 56.60718 -30.136108)
			(xy 56.640122 -30.183639) (xy 56.665512 -30.235598) (xy 56.682771 -30.290793) (xy 56.691502 -30.347961)
			(xy 56.692038 -30.376876) (xy 56.691552 -30.404127) (xy 56.683796 -30.458075) (xy 56.668441 -30.51037)
			(xy 56.645799 -30.559947) (xy 56.616333 -30.605797) (xy 56.580642 -30.646988) (xy 56.539451 -30.682679)
			(xy 56.493601 -30.712145) (xy 56.444024 -30.734787) (xy 56.391729 -30.750142) (xy 56.337781 -30.757898)
			(xy 56.283279 -30.757898) (xy 56.229331 -30.750142) (xy 56.177036 -30.734787) (xy 56.127459 -30.712145)
			(xy 56.081609 -30.682679) (xy 56.040418 -30.646988) (xy 56.004727 -30.605797) (xy 55.975261 -30.559947)
			(xy 55.952619 -30.51037) (xy 55.937264 -30.458075) (xy 55.929508 -30.404127) (xy 55.929022 -30.376876)
			(xy 53.651912 -30.376876) (xy 53.651426 -30.404127) (xy 53.64367 -30.458075) (xy 53.628315 -30.51037)
			(xy 53.605673 -30.559947) (xy 53.576207 -30.605797) (xy 53.540516 -30.646988) (xy 53.499325 -30.682679)
			(xy 53.453475 -30.712145) (xy 53.403898 -30.734787) (xy 53.351603 -30.750142) (xy 53.297655 -30.757898)
			(xy 53.243153 -30.757898) (xy 53.189205 -30.750142) (xy 53.13691 -30.734787) (xy 53.087333 -30.712145)
			(xy 53.041483 -30.682679) (xy 53.000292 -30.646988) (xy 52.964601 -30.605797) (xy 52.935135 -30.559947)
			(xy 52.912493 -30.51037) (xy 52.897138 -30.458075) (xy 52.889382 -30.404127) (xy 52.888896 -30.376876)
			(xy 51.994944 -30.376876) (xy 52.54385 -30.922468) (xy 58.75274 -30.922468) (xy 58.75274 -30.058868)
			(xy 58.75323 -30.0289) (xy 58.761053 -29.969478) (xy 58.776566 -29.911585) (xy 58.799502 -29.856212)
			(xy 58.829469 -29.804306) (xy 58.865956 -29.756756) (xy 58.908336 -29.714376) (xy 58.955886 -29.677889)
			(xy 59.007792 -29.647922) (xy 59.063165 -29.624986) (xy 59.121058 -29.609473) (xy 59.18048 -29.60165)
			(xy 59.240416 -29.60165) (xy 59.299838 -29.609473) (xy 59.357731 -29.624986) (xy 59.413104 -29.647922)
			(xy 59.46501 -29.677889) (xy 59.51256 -29.714376) (xy 59.55494 -29.756756) (xy 59.591427 -29.804306)
			(xy 59.621394 -29.856212) (xy 59.64433 -29.911585) (xy 59.659843 -29.969478) (xy 59.667666 -30.0289)
			(xy 59.668156 -30.058868) (xy 59.668156 -30.922468) (xy 59.667666 -30.952436) (xy 59.659843 -31.011858)
			(xy 59.64433 -31.069751) (xy 59.621394 -31.125124) (xy 59.591427 -31.17703) (xy 59.55494 -31.22458)
			(xy 59.51256 -31.26696) (xy 59.46501 -31.303447) (xy 59.413104 -31.333414) (xy 59.357731 -31.35635)
			(xy 59.299838 -31.371863) (xy 59.240416 -31.379686) (xy 59.18048 -31.379686) (xy 59.121058 -31.371863)
			(xy 59.063165 -31.35635) (xy 59.007792 -31.333414) (xy 58.955886 -31.303447) (xy 58.908336 -31.26696)
			(xy 58.865956 -31.22458) (xy 58.829469 -31.17703) (xy 58.799502 -31.125124) (xy 58.776566 -31.069751)
			(xy 58.761053 -31.011858) (xy 58.75323 -30.952436) (xy 58.75274 -30.922468) (xy 52.54385 -30.922468)
			(xy 52.773072 -31.150306) (xy 52.801103 -31.178679) (xy 52.85305 -31.239209) (xy 52.899998 -31.303693)
			(xy 52.921154 -31.337504) (xy 52.922932 -31.340298) (xy 52.932838 -31.3563) (xy 52.939926 -31.366199)
			(xy 52.960875 -31.378536) (xy 52.97297 -31.379922) (xy 53.01996 -31.380684) (xy 53.028179 -31.380034)
			(xy 53.043593 -31.374205) (xy 53.050186 -31.369254) (xy 53.050948 -31.368746) (xy 53.053996 -31.365952)
			(xy 53.061362 -31.358586) (xy 53.064156 -31.354522) (xy 53.064664 -31.354014) (xy 53.064664 -31.353506)
			(xy 53.080001 -31.331793) (xy 53.115719 -31.292422) (xy 53.156547 -31.258378) (xy 53.201697 -31.230318)
			(xy 53.250299 -31.208783) (xy 53.301415 -31.194189) (xy 53.354061 -31.186817) (xy 53.38064 -31.186374)
			(xy 53.40789 -31.186862) (xy 53.461834 -31.194624) (xy 53.514125 -31.209982) (xy 53.563699 -31.232625)
			(xy 53.609545 -31.262092) (xy 53.650732 -31.297783) (xy 53.686421 -31.338972) (xy 53.715885 -31.384821)
			(xy 53.738526 -31.434395) (xy 53.753881 -31.486687) (xy 53.761639 -31.540632) (xy 53.762148 -31.567882)
			(xy 53.761646 -31.595678) (xy 53.753577 -31.650683) (xy 53.737606 -31.703932) (xy 53.730441 -31.719266)
			(xy 54.285386 -31.719266) (xy 54.289457 -31.663644) (xy 54.301583 -31.609207) (xy 54.321506 -31.557116)
			(xy 54.348802 -31.508481) (xy 54.382888 -31.464338) (xy 54.423037 -31.425629) (xy 54.468395 -31.393178)
			(xy 54.517995 -31.367677) (xy 54.570779 -31.34967) (xy 54.625622 -31.33954) (xy 54.681356 -31.337503)
			(xy 54.736793 -31.343603) (xy 54.79075 -31.357709) (xy 54.842079 -31.379521) (xy 54.889685 -31.408575)
			(xy 54.932553 -31.44425) (xy 54.96977 -31.485787) (xy 55.000543 -31.5323) (xy 55.024215 -31.582797)
			(xy 55.040283 -31.636204) (xy 55.044433 -31.664402) (xy 55.560974 -31.664402) (xy 55.565045 -31.60878)
			(xy 55.577171 -31.554343) (xy 55.597094 -31.502252) (xy 55.62439 -31.453617) (xy 55.658476 -31.409474)
			(xy 55.698625 -31.370765) (xy 55.743983 -31.338314) (xy 55.793583 -31.312813) (xy 55.846367 -31.294806)
			(xy 55.90121 -31.284676) (xy 55.956944 -31.282639) (xy 56.012381 -31.288739) (xy 56.066338 -31.302845)
			(xy 56.117667 -31.324657) (xy 56.165273 -31.353711) (xy 56.208141 -31.389386) (xy 56.245358 -31.430923)
			(xy 56.276131 -31.477436) (xy 56.299803 -31.527933) (xy 56.315871 -31.58134) (xy 56.323991 -31.636516)
			(xy 56.3245 -31.664402) (xy 56.323991 -31.692288) (xy 56.315871 -31.747464) (xy 56.306931 -31.777178)
			(xy 56.826148 -31.777178) (xy 56.830219 -31.721556) (xy 56.842345 -31.667119) (xy 56.862268 -31.615028)
			(xy 56.889564 -31.566393) (xy 56.92365 -31.52225) (xy 56.963799 -31.483541) (xy 57.009157 -31.45109)
			(xy 57.058757 -31.425589) (xy 57.111541 -31.407582) (xy 57.166384 -31.397452) (xy 57.222118 -31.395415)
			(xy 57.277555 -31.401515) (xy 57.331512 -31.415621) (xy 57.382841 -31.437433) (xy 57.430447 -31.466487)
			(xy 57.473315 -31.502162) (xy 57.510532 -31.543699) (xy 57.541305 -31.590212) (xy 57.564977 -31.640709)
			(xy 57.581045 -31.694116) (xy 57.589165 -31.749292) (xy 57.589674 -31.777178) (xy 57.589165 -31.805064)
			(xy 57.581045 -31.86024) (xy 57.564977 -31.913647) (xy 57.541305 -31.964144) (xy 57.510532 -32.010657)
			(xy 57.473315 -32.052194) (xy 57.430447 -32.087869) (xy 57.382841 -32.116923) (xy 57.331512 -32.138735)
			(xy 57.277555 -32.152841) (xy 57.222118 -32.158941) (xy 57.166384 -32.156904) (xy 57.111541 -32.146774)
			(xy 57.058757 -32.128767) (xy 57.009157 -32.103266) (xy 56.963799 -32.070815) (xy 56.92365 -32.032106)
			(xy 56.889564 -31.987963) (xy 56.862268 -31.939328) (xy 56.842345 -31.887237) (xy 56.830219 -31.8328)
			(xy 56.826148 -31.777178) (xy 56.306931 -31.777178) (xy 56.299803 -31.800871) (xy 56.276131 -31.851368)
			(xy 56.245358 -31.897881) (xy 56.208141 -31.939418) (xy 56.165273 -31.975093) (xy 56.117667 -32.004147)
			(xy 56.066338 -32.025959) (xy 56.012381 -32.040065) (xy 55.956944 -32.046165) (xy 55.90121 -32.044128)
			(xy 55.846367 -32.033998) (xy 55.793583 -32.015991) (xy 55.743983 -31.99049) (xy 55.698625 -31.958039)
			(xy 55.658476 -31.91933) (xy 55.62439 -31.875187) (xy 55.597094 -31.826552) (xy 55.577171 -31.774461)
			(xy 55.565045 -31.720024) (xy 55.560974 -31.664402) (xy 55.044433 -31.664402) (xy 55.048403 -31.69138)
			(xy 55.048912 -31.719266) (xy 55.048403 -31.747152) (xy 55.040283 -31.802328) (xy 55.024215 -31.855735)
			(xy 55.000543 -31.906232) (xy 54.96977 -31.952745) (xy 54.932553 -31.994282) (xy 54.889685 -32.029957)
			(xy 54.842079 -32.059011) (xy 54.79075 -32.080823) (xy 54.736793 -32.094929) (xy 54.681356 -32.101029)
			(xy 54.625622 -32.098992) (xy 54.570779 -32.088862) (xy 54.517995 -32.070855) (xy 54.468395 -32.045354)
			(xy 54.423037 -32.012903) (xy 54.382888 -31.974194) (xy 54.348802 -31.930051) (xy 54.321506 -31.881416)
			(xy 54.301583 -31.829325) (xy 54.289457 -31.774888) (xy 54.285386 -31.719266) (xy 53.730441 -31.719266)
			(xy 53.714073 -31.754299) (xy 53.683477 -31.800714) (xy 53.646465 -31.842195) (xy 53.603822 -31.877863)
			(xy 53.556452 -31.90696) (xy 53.505359 -31.928872) (xy 53.451627 -31.943132) (xy 53.424074 -31.94685)
			(xy 53.422042 -31.947104) (xy 53.410493 -31.949509) (xy 53.391283 -31.963151) (xy 53.385212 -31.973266)
			(xy 53.3654 -32.013652) (xy 53.36286 -32.018986) (xy 53.358958 -32.029584) (xy 53.359743 -32.052126)
			(xy 53.364384 -32.06242) (xy 53.767811 -32.722312) (xy 60.60694 -32.722312) (xy 60.60694 -31.858712)
			(xy 60.60743 -31.828744) (xy 60.615253 -31.769322) (xy 60.630766 -31.711429) (xy 60.653702 -31.656056)
			(xy 60.683669 -31.60415) (xy 60.720156 -31.5566) (xy 60.762536 -31.51422) (xy 60.810086 -31.477733)
			(xy 60.861992 -31.447766) (xy 60.917365 -31.42483) (xy 60.975258 -31.409317) (xy 61.03468 -31.401494)
			(xy 61.094616 -31.401494) (xy 61.154038 -31.409317) (xy 61.211931 -31.42483) (xy 61.267304 -31.447766)
			(xy 61.31921 -31.477733) (xy 61.36676 -31.51422) (xy 61.40914 -31.5566) (xy 61.445627 -31.60415)
			(xy 61.475594 -31.656056) (xy 61.49853 -31.711429) (xy 61.514043 -31.769322) (xy 61.521866 -31.828744)
			(xy 61.522356 -31.858712) (xy 61.522356 -32.722312) (xy 61.521866 -32.75228) (xy 61.514043 -32.811702)
			(xy 61.49853 -32.869595) (xy 61.475594 -32.924968) (xy 61.445627 -32.976874) (xy 61.40914 -33.024424)
			(xy 61.36676 -33.066804) (xy 61.31921 -33.103291) (xy 61.267304 -33.133258) (xy 61.211931 -33.156194)
			(xy 61.154038 -33.171707) (xy 61.094616 -33.17953) (xy 61.03468 -33.17953) (xy 60.975258 -33.171707)
			(xy 60.917365 -33.156194) (xy 60.861992 -33.133258) (xy 60.810086 -33.103291) (xy 60.762536 -33.066804)
			(xy 60.720156 -33.024424) (xy 60.683669 -32.976874) (xy 60.653702 -32.924968) (xy 60.630766 -32.869595)
			(xy 60.615253 -32.811702) (xy 60.60743 -32.75228) (xy 60.60694 -32.722312) (xy 53.767811 -32.722312)
			(xy 54.042818 -33.172146) (xy 54.416706 -33.783524) (xy 54.422414 -33.792044) (xy 54.439057 -33.803994)
			(xy 54.448964 -33.806638) (xy 54.45125 -33.807146) (xy 54.477091 -33.812127) (xy 54.527185 -33.828251)
			(xy 54.574593 -33.851097) (xy 54.618417 -33.880232) (xy 54.657828 -33.915106) (xy 54.692081 -33.955058)
			(xy 54.720527 -33.999333) (xy 54.742628 -34.047092) (xy 54.757965 -34.097433) (xy 54.76625 -34.149402)
			(xy 54.767226 -34.1757) (xy 54.766972 -34.189162) (xy 54.766448 -34.208111) (xy 54.762124 -34.245772)
			(xy 54.758336 -34.264346) (xy 54.755796 -34.275776) (xy 54.758336 -34.28619) (xy 54.75974 -34.291634)
			(xy 54.764603 -34.301768) (xy 54.767988 -34.306256) (xy 54.940292 -34.52241) (xy 58.75274 -34.52241)
			(xy 58.75274 -33.65881) (xy 58.75323 -33.628842) (xy 58.761053 -33.56942) (xy 58.776566 -33.511527)
			(xy 58.799502 -33.456154) (xy 58.829469 -33.404248) (xy 58.865956 -33.356698) (xy 58.908336 -33.314318)
			(xy 58.955886 -33.277831) (xy 59.007792 -33.247864) (xy 59.063165 -33.224928) (xy 59.121058 -33.209415)
			(xy 59.18048 -33.201592) (xy 59.240416 -33.201592) (xy 59.299838 -33.209415) (xy 59.357731 -33.224928)
			(xy 59.413104 -33.247864) (xy 59.46501 -33.277831) (xy 59.51256 -33.314318) (xy 59.55494 -33.356698)
			(xy 59.591427 -33.404248) (xy 59.621394 -33.456154) (xy 59.64433 -33.511527) (xy 59.659843 -33.56942)
			(xy 59.667666 -33.628842) (xy 59.668156 -33.65881) (xy 59.668156 -34.52241) (xy 59.667666 -34.552378)
			(xy 59.659843 -34.6118) (xy 59.64433 -34.669693) (xy 59.621394 -34.725066) (xy 59.591427 -34.776972)
			(xy 59.55494 -34.824522) (xy 59.51256 -34.866902) (xy 59.46501 -34.903389) (xy 59.413104 -34.933356)
			(xy 59.357731 -34.956292) (xy 59.299838 -34.971805) (xy 59.240416 -34.979628) (xy 59.18048 -34.979628)
			(xy 59.121058 -34.971805) (xy 59.063165 -34.956292) (xy 59.007792 -34.933356) (xy 58.955886 -34.903389)
			(xy 58.908336 -34.866902) (xy 58.865956 -34.824522) (xy 58.829469 -34.776972) (xy 58.799502 -34.725066)
			(xy 58.776566 -34.669693) (xy 58.761053 -34.6118) (xy 58.75323 -34.552378) (xy 58.75274 -34.52241)
			(xy 54.940292 -34.52241) (xy 55.532117 -35.264852) (xy 55.90235 -35.264852) (xy 55.906421 -35.20923)
			(xy 55.918547 -35.154793) (xy 55.93847 -35.102702) (xy 55.965766 -35.054067) (xy 55.999852 -35.009924)
			(xy 56.040001 -34.971215) (xy 56.085359 -34.938764) (xy 56.134959 -34.913263) (xy 56.187743 -34.895256)
			(xy 56.242586 -34.885126) (xy 56.29832 -34.883089) (xy 56.353757 -34.889189) (xy 56.407714 -34.903295)
			(xy 56.459043 -34.925107) (xy 56.506649 -34.954161) (xy 56.549517 -34.989836) (xy 56.586734 -35.031373)
			(xy 56.617507 -35.077886) (xy 56.641179 -35.128383) (xy 56.657247 -35.18179) (xy 56.665367 -35.236966)
			(xy 56.665876 -35.264852) (xy 56.665367 -35.292738) (xy 56.657247 -35.347914) (xy 56.641179 -35.401321)
			(xy 56.617507 -35.451818) (xy 56.586734 -35.498331) (xy 56.549517 -35.539868) (xy 56.506649 -35.575543)
			(xy 56.459043 -35.604597) (xy 56.407714 -35.626409) (xy 56.353757 -35.640515) (xy 56.29832 -35.646615)
			(xy 56.242586 -35.644578) (xy 56.187743 -35.634448) (xy 56.134959 -35.616441) (xy 56.085359 -35.59094)
			(xy 56.040001 -35.558489) (xy 55.999852 -35.51978) (xy 55.965766 -35.475637) (xy 55.93847 -35.427002)
			(xy 55.918547 -35.374911) (xy 55.906421 -35.320474) (xy 55.90235 -35.264852) (xy 55.532117 -35.264852)
			(xy 56.346863 -36.286948) (xy 57.20029 -36.286948) (xy 57.204361 -36.231326) (xy 57.216487 -36.176889)
			(xy 57.23641 -36.124798) (xy 57.263706 -36.076163) (xy 57.297792 -36.03202) (xy 57.337941 -35.993311)
			(xy 57.383299 -35.96086) (xy 57.432899 -35.935359) (xy 57.485683 -35.917352) (xy 57.540526 -35.907222)
			(xy 57.59626 -35.905185) (xy 57.651697 -35.911285) (xy 57.705654 -35.925391) (xy 57.756983 -35.947203)
			(xy 57.804589 -35.976257) (xy 57.847457 -36.011932) (xy 57.884674 -36.053469) (xy 57.915447 -36.099982)
			(xy 57.939119 -36.150479) (xy 57.955187 -36.203886) (xy 57.963307 -36.259062) (xy 57.963816 -36.286948)
			(xy 57.963307 -36.314834) (xy 57.955187 -36.37001) (xy 57.939119 -36.423417) (xy 57.915447 -36.473914)
			(xy 57.887902 -36.515548) (xy 59.014104 -36.515548) (xy 59.018175 -36.459926) (xy 59.030301 -36.405489)
			(xy 59.050224 -36.353398) (xy 59.07752 -36.304763) (xy 59.111606 -36.26062) (xy 59.151755 -36.221911)
			(xy 59.197113 -36.18946) (xy 59.246713 -36.163959) (xy 59.299497 -36.145952) (xy 59.35434 -36.135822)
			(xy 59.410074 -36.133785) (xy 59.465511 -36.139885) (xy 59.519468 -36.153991) (xy 59.570797 -36.175803)
			(xy 59.618403 -36.204857) (xy 59.661271 -36.240532) (xy 59.698488 -36.282069) (xy 59.729261 -36.328582)
			(xy 59.752933 -36.379079) (xy 59.769001 -36.432486) (xy 59.777121 -36.487662) (xy 59.77763 -36.515548)
			(xy 59.777121 -36.543434) (xy 59.769001 -36.59861) (xy 59.768544 -36.60013) (xy 63.998101 -36.60013)
			(xy 64.002106 -36.512222) (xy 64.014089 -36.425042) (xy 64.033949 -36.339313) (xy 64.061524 -36.255745)
			(xy 64.096583 -36.175031) (xy 64.138836 -36.097839) (xy 64.187934 -36.02481) (xy 64.24347 -35.956548)
			(xy 64.304982 -35.893618) (xy 64.371963 -35.836544) (xy 64.443856 -35.785796) (xy 64.520065 -35.741796)
			(xy 64.59996 -35.704909) (xy 64.682879 -35.67544) (xy 64.768134 -35.653633) (xy 64.855018 -35.639669)
			(xy 64.942812 -35.633663) (xy 65.030789 -35.635667) (xy 65.118219 -35.645662) (xy 65.204378 -35.663566)
			(xy 65.288552 -35.68923) (xy 65.370043 -35.722443) (xy 65.448177 -35.762929) (xy 65.522305 -35.810351)
			(xy 65.591813 -35.864318) (xy 65.605112 -35.876738) (xy 70.717154 -35.876738) (xy 70.721225 -35.821116)
			(xy 70.733351 -35.766679) (xy 70.753274 -35.714588) (xy 70.78057 -35.665953) (xy 70.814656 -35.62181)
			(xy 70.854805 -35.583101) (xy 70.900163 -35.55065) (xy 70.949763 -35.525149) (xy 71.002547 -35.507142)
			(xy 71.05739 -35.497012) (xy 71.113124 -35.494975) (xy 71.168561 -35.501075) (xy 71.222518 -35.515181)
			(xy 71.273847 -35.536993) (xy 71.321453 -35.566047) (xy 71.364321 -35.601722) (xy 71.401538 -35.643259)
			(xy 71.432311 -35.689772) (xy 71.455983 -35.740269) (xy 71.472051 -35.793676) (xy 71.480171 -35.848852)
			(xy 71.48068 -35.876738) (xy 71.480171 -35.904624) (xy 71.472051 -35.9598) (xy 71.455983 -36.013207)
			(xy 71.432311 -36.063704) (xy 71.401538 -36.110217) (xy 71.364321 -36.151754) (xy 71.321453 -36.187429)
			(xy 71.273847 -36.216483) (xy 71.222518 -36.238295) (xy 71.168561 -36.252401) (xy 71.113124 -36.258501)
			(xy 71.05739 -36.256464) (xy 71.002547 -36.246334) (xy 70.949763 -36.228327) (xy 70.900163 -36.202826)
			(xy 70.854805 -36.170375) (xy 70.814656 -36.131666) (xy 70.78057 -36.087523) (xy 70.753274 -36.038888)
			(xy 70.733351 -35.986797) (xy 70.721225 -35.93236) (xy 70.717154 -35.876738) (xy 65.605112 -35.876738)
			(xy 65.656127 -35.924383) (xy 65.714711 -35.990047) (xy 65.767082 -36.060766) (xy 65.812805 -36.135954)
			(xy 65.851502 -36.214989) (xy 65.882851 -36.297215) (xy 65.906593 -36.381951) (xy 65.922531 -36.468495)
			(xy 65.926317 -36.50996) (xy 72.613772 -36.50996) (xy 72.617843 -36.454338) (xy 72.629969 -36.399901)
			(xy 72.649892 -36.34781) (xy 72.677188 -36.299175) (xy 72.711274 -36.255032) (xy 72.751423 -36.216323)
			(xy 72.796781 -36.183872) (xy 72.846381 -36.158371) (xy 72.899165 -36.140364) (xy 72.954008 -36.130234)
			(xy 73.009742 -36.128197) (xy 73.065179 -36.134297) (xy 73.119136 -36.148403) (xy 73.170465 -36.170215)
			(xy 73.218071 -36.199269) (xy 73.260939 -36.234944) (xy 73.298156 -36.276481) (xy 73.328929 -36.322994)
			(xy 73.352601 -36.373491) (xy 73.368669 -36.426898) (xy 73.376789 -36.482074) (xy 73.377298 -36.50996)
			(xy 73.376789 -36.537846) (xy 73.368669 -36.593022) (xy 73.352601 -36.646429) (xy 73.328929 -36.696926)
			(xy 73.298156 -36.743439) (xy 73.260939 -36.784976) (xy 73.218071 -36.820651) (xy 73.170465 -36.849705)
			(xy 73.119136 -36.871517) (xy 73.065179 -36.885623) (xy 73.009742 -36.891723) (xy 72.954008 -36.889686)
			(xy 72.899165 -36.879556) (xy 72.846381 -36.861549) (xy 72.796781 -36.836048) (xy 72.751423 -36.803597)
			(xy 72.711274 -36.764888) (xy 72.677188 -36.720745) (xy 72.649892 -36.67211) (xy 72.629969 -36.620019)
			(xy 72.617843 -36.565582) (xy 72.613772 -36.50996) (xy 65.926317 -36.50996) (xy 65.930533 -36.55613)
			(xy 65.931034 -36.60013) (xy 65.930533 -36.64413) (xy 65.922531 -36.731765) (xy 65.906593 -36.818309)
			(xy 65.882851 -36.903045) (xy 65.851502 -36.985271) (xy 65.812805 -37.064306) (xy 65.767082 -37.139494)
			(xy 65.714711 -37.210213) (xy 65.656127 -37.275877) (xy 65.591813 -37.335942) (xy 65.522305 -37.389909)
			(xy 65.448177 -37.437331) (xy 65.375171 -37.47516) (xy 69.759066 -37.47516) (xy 69.763137 -37.419538)
			(xy 69.775263 -37.365101) (xy 69.795186 -37.31301) (xy 69.822482 -37.264375) (xy 69.856568 -37.220232)
			(xy 69.896717 -37.181523) (xy 69.942075 -37.149072) (xy 69.991675 -37.123571) (xy 70.044459 -37.105564)
			(xy 70.099302 -37.095434) (xy 70.155036 -37.093397) (xy 70.210473 -37.099497) (xy 70.26443 -37.113603)
			(xy 70.315759 -37.135415) (xy 70.363365 -37.164469) (xy 70.406233 -37.200144) (xy 70.44345 -37.241681)
			(xy 70.474223 -37.288194) (xy 70.497895 -37.338691) (xy 70.513963 -37.392098) (xy 70.522083 -37.447274)
			(xy 70.522592 -37.47516) (xy 70.522083 -37.503046) (xy 70.513963 -37.558222) (xy 70.497895 -37.611629)
			(xy 70.474223 -37.662126) (xy 70.47407 -37.662358) (xy 71.948292 -37.662358) (xy 71.952363 -37.606736)
			(xy 71.964489 -37.552299) (xy 71.984412 -37.500208) (xy 72.011708 -37.451573) (xy 72.045794 -37.40743)
			(xy 72.085943 -37.368721) (xy 72.131301 -37.33627) (xy 72.180901 -37.310769) (xy 72.233685 -37.292762)
			(xy 72.288528 -37.282632) (xy 72.344262 -37.280595) (xy 72.399699 -37.286695) (xy 72.453656 -37.300801)
			(xy 72.504985 -37.322613) (xy 72.552591 -37.351667) (xy 72.595459 -37.387342) (xy 72.632676 -37.428879)
			(xy 72.663449 -37.475392) (xy 72.687121 -37.525889) (xy 72.703189 -37.579296) (xy 72.711309 -37.634472)
			(xy 72.711818 -37.662358) (xy 72.711309 -37.690244) (xy 72.703189 -37.74542) (xy 72.687121 -37.798827)
			(xy 72.663449 -37.849324) (xy 72.632676 -37.895837) (xy 72.595459 -37.937374) (xy 72.552591 -37.973049)
			(xy 72.504985 -38.002103) (xy 72.453656 -38.023915) (xy 72.399699 -38.038021) (xy 72.344262 -38.044121)
			(xy 72.288528 -38.042084) (xy 72.233685 -38.031954) (xy 72.180901 -38.013947) (xy 72.131301 -37.988446)
			(xy 72.085943 -37.955995) (xy 72.045794 -37.917286) (xy 72.011708 -37.873143) (xy 71.984412 -37.824508)
			(xy 71.964489 -37.772417) (xy 71.952363 -37.71798) (xy 71.948292 -37.662358) (xy 70.47407 -37.662358)
			(xy 70.44345 -37.708639) (xy 70.406233 -37.750176) (xy 70.363365 -37.785851) (xy 70.315759 -37.814905)
			(xy 70.26443 -37.836717) (xy 70.210473 -37.850823) (xy 70.155036 -37.856923) (xy 70.099302 -37.854886)
			(xy 70.044459 -37.844756) (xy 69.991675 -37.826749) (xy 69.942075 -37.801248) (xy 69.896717 -37.768797)
			(xy 69.856568 -37.730088) (xy 69.822482 -37.685945) (xy 69.795186 -37.63731) (xy 69.775263 -37.585219)
			(xy 69.763137 -37.530782) (xy 69.759066 -37.47516) (xy 65.375171 -37.47516) (xy 65.370043 -37.477817)
			(xy 65.288552 -37.51103) (xy 65.204378 -37.536694) (xy 65.118219 -37.554598) (xy 65.030789 -37.564593)
			(xy 64.942812 -37.566597) (xy 64.855018 -37.560591) (xy 64.768134 -37.546627) (xy 64.682879 -37.52482)
			(xy 64.59996 -37.495351) (xy 64.520065 -37.458464) (xy 64.443856 -37.414464) (xy 64.371963 -37.363716)
			(xy 64.304982 -37.306642) (xy 64.24347 -37.243712) (xy 64.187934 -37.17545) (xy 64.138836 -37.102421)
			(xy 64.096583 -37.025229) (xy 64.061524 -36.944515) (xy 64.033949 -36.860947) (xy 64.014089 -36.775218)
			(xy 64.002106 -36.688038) (xy 63.998101 -36.60013) (xy 59.768544 -36.60013) (xy 59.752933 -36.652017)
			(xy 59.729261 -36.702514) (xy 59.698488 -36.749027) (xy 59.661271 -36.790564) (xy 59.618403 -36.826239)
			(xy 59.570797 -36.855293) (xy 59.519468 -36.877105) (xy 59.465511 -36.891211) (xy 59.410074 -36.897311)
			(xy 59.35434 -36.895274) (xy 59.299497 -36.885144) (xy 59.246713 -36.867137) (xy 59.197113 -36.841636)
			(xy 59.151755 -36.809185) (xy 59.111606 -36.770476) (xy 59.07752 -36.726333) (xy 59.050224 -36.677698)
			(xy 59.030301 -36.625607) (xy 59.018175 -36.57117) (xy 59.014104 -36.515548) (xy 57.887902 -36.515548)
			(xy 57.884674 -36.520427) (xy 57.847457 -36.561964) (xy 57.804589 -36.597639) (xy 57.756983 -36.626693)
			(xy 57.705654 -36.648505) (xy 57.651697 -36.662611) (xy 57.59626 -36.668711) (xy 57.540526 -36.666674)
			(xy 57.485683 -36.656544) (xy 57.432899 -36.638537) (xy 57.383299 -36.613036) (xy 57.337941 -36.580585)
			(xy 57.297792 -36.541876) (xy 57.263706 -36.497733) (xy 57.23641 -36.449098) (xy 57.216487 -36.397007)
			(xy 57.204361 -36.34257) (xy 57.20029 -36.286948) (xy 56.346863 -36.286948) (xy 57.366916 -37.5666)
			(xy 57.371886 -37.572409) (xy 57.384554 -37.580954) (xy 57.391808 -37.583364) (xy 57.395952 -37.584577)
			(xy 57.404509 -37.585726) (xy 57.408826 -37.58565) (xy 57.446418 -37.58438) (xy 57.492646 -37.582602)
			(xy 57.504066 -37.581152) (xy 57.523894 -37.569502) (xy 57.530746 -37.56025) (xy 57.546039 -37.538477)
			(xy 57.581695 -37.498985) (xy 57.622494 -37.464832) (xy 57.667645 -37.436682) (xy 57.71627 -37.415082)
			(xy 57.767426 -37.40045) (xy 57.820118 -37.393071) (xy 57.846722 -37.39261) (xy 57.873972 -37.393098)
			(xy 57.927916 -37.400857) (xy 57.980207 -37.416214) (xy 58.02978 -37.438857) (xy 58.075627 -37.468324)
			(xy 58.116813 -37.504016) (xy 58.1525 -37.545205) (xy 58.181962 -37.591055) (xy 58.2046 -37.64063)
			(xy 58.219952 -37.692923) (xy 58.227705 -37.746868) (xy 58.22823 -37.774118) (xy 58.227716 -37.80275)
			(xy 58.219155 -37.859371) (xy 58.202228 -37.914077) (xy 58.177316 -37.965639) (xy 58.144977 -38.012898)
			(xy 58.105939 -38.054794) (xy 58.061078 -38.090385) (xy 58.011401 -38.118872) (xy 57.984898 -38.129718)
			(xy 57.982104 -38.130734) (xy 57.972127 -38.136004) (xy 57.957646 -38.153273) (xy 57.954164 -38.164008)
			(xy 57.932828 -38.242748) (xy 57.931812 -38.246812) (xy 57.930347 -38.257669) (xy 57.935741 -38.278877)
			(xy 57.942226 -38.287706) (xy 60.318961 -41.268755) (xy 67.843827 -41.268755) (xy 67.843827 -41.214245)
			(xy 67.851585 -41.160289) (xy 67.866942 -41.107987) (xy 67.889587 -41.058402) (xy 67.919058 -41.012545)
			(xy 67.954755 -40.971349) (xy 67.995952 -40.935653) (xy 68.041809 -40.906183) (xy 68.091394 -40.883539)
			(xy 68.143697 -40.868183) (xy 68.197653 -40.860426) (xy 68.224908 -40.859964) (xy 68.253647 -40.860492)
			(xy 68.310473 -40.869115) (xy 68.365364 -40.886165) (xy 68.417075 -40.911255) (xy 68.464439 -40.943818)
			(xy 68.485766 -40.963088) (xy 68.492624 -40.969692) (xy 68.510658 -40.976804) (xy 68.599558 -40.976804)
			(xy 68.617592 -40.969692) (xy 68.62445 -40.963088) (xy 68.645781 -40.943822) (xy 68.693141 -40.911253)
			(xy 68.744852 -40.886159) (xy 68.799742 -40.869107) (xy 68.856569 -40.860484) (xy 68.885308 -40.859964)
			(xy 68.912557 -40.860507) (xy 68.9665 -40.868264) (xy 69.01879 -40.883618) (xy 69.068362 -40.906258)
			(xy 69.114208 -40.935722) (xy 69.155394 -40.971411) (xy 69.191082 -41.012598) (xy 69.220546 -41.058445)
			(xy 69.243185 -41.108018) (xy 69.258538 -41.160308) (xy 69.266294 -41.214251) (xy 69.266294 -41.268749)
			(xy 69.258538 -41.322692) (xy 69.243185 -41.374982) (xy 69.220546 -41.424555) (xy 69.191082 -41.470402)
			(xy 69.155394 -41.511589) (xy 69.114208 -41.547277) (xy 69.068362 -41.576742) (xy 69.01879 -41.599382)
			(xy 68.9665 -41.614736) (xy 68.912557 -41.622493) (xy 68.885308 -41.62298) (xy 68.85657 -41.62243)
			(xy 68.799745 -41.613811) (xy 68.744855 -41.596765) (xy 68.693143 -41.57168) (xy 68.645779 -41.539123)
			(xy 68.62445 -41.519856) (xy 68.617592 -41.513252) (xy 68.599558 -41.50614) (xy 68.510658 -41.50614)
			(xy 68.492624 -41.513252) (xy 68.485766 -41.519856) (xy 68.464435 -41.539122) (xy 68.417074 -41.571689)
			(xy 68.365363 -41.596783) (xy 68.310474 -41.613834) (xy 68.253647 -41.622458) (xy 68.224908 -41.62298)
			(xy 68.197653 -41.622574) (xy 68.143697 -41.614817) (xy 68.091394 -41.599461) (xy 68.041809 -41.576817)
			(xy 67.995952 -41.547347) (xy 67.954755 -41.511651) (xy 67.919058 -41.470455) (xy 67.889587 -41.424598)
			(xy 67.866942 -41.375013) (xy 67.851585 -41.322711) (xy 67.843827 -41.268755) (xy 60.318961 -41.268755)
			(xy 61.942599 -43.305222) (xy 70.3072 -43.305222) (xy 70.307679 -43.277852) (xy 70.315494 -43.223674)
			(xy 70.33098 -43.171171) (xy 70.353819 -43.121424) (xy 70.38354 -43.075456) (xy 70.40118 -43.054524)
			(xy 70.401434 -43.05427) (xy 70.407001 -43.04717) (xy 70.413258 -43.030263) (xy 70.413626 -43.02125)
			(xy 70.413626 -42.954194) (xy 70.413266 -42.945178) (xy 70.40702 -42.928261) (xy 70.401434 -42.921174)
			(xy 70.40118 -42.921174) (xy 70.40118 -42.92092) (xy 70.383534 -42.899994) (xy 70.353824 -42.854019)
			(xy 70.330989 -42.80427) (xy 70.3155 -42.751768) (xy 70.307673 -42.697592) (xy 70.3072 -42.670222)
			(xy 70.307737 -42.641484) (xy 70.316356 -42.584657) (xy 70.333403 -42.529766) (xy 70.358492 -42.478054)
			(xy 70.391054 -42.430691) (xy 70.410324 -42.409364) (xy 70.416928 -42.402506) (xy 70.42404 -42.384472)
			(xy 70.42404 -42.295572) (xy 70.416928 -42.277538) (xy 70.410324 -42.27068) (xy 70.391075 -42.249334)
			(xy 70.358509 -42.201975) (xy 70.333416 -42.150266) (xy 70.316365 -42.095379) (xy 70.30774 -42.038554)
			(xy 70.307738 -41.981078) (xy 70.316357 -41.924253) (xy 70.333404 -41.869364) (xy 70.358493 -41.817653)
			(xy 70.391055 -41.770291) (xy 70.410324 -41.748964) (xy 70.416928 -41.742106) (xy 70.42404 -41.724072)
			(xy 70.42404 -41.635172) (xy 70.416928 -41.617138) (xy 70.410324 -41.61028) (xy 70.391061 -41.588946)
			(xy 70.358494 -41.541586) (xy 70.333401 -41.489876) (xy 70.316348 -41.434987) (xy 70.307723 -41.37816)
			(xy 70.3072 -41.349422) (xy 70.307686 -41.322171) (xy 70.315442 -41.268223) (xy 70.330797 -41.215928)
			(xy 70.353439 -41.166351) (xy 70.382905 -41.120501) (xy 70.418596 -41.07931) (xy 70.459787 -41.043619)
			(xy 70.505637 -41.014153) (xy 70.555214 -40.991511) (xy 70.607509 -40.976156) (xy 70.661457 -40.9684)
			(xy 70.715959 -40.9684) (xy 70.769907 -40.976156) (xy 70.822202 -40.991511) (xy 70.871779 -41.014153)
			(xy 70.917629 -41.043619) (xy 70.95882 -41.07931) (xy 70.994511 -41.120501) (xy 71.023977 -41.166351)
			(xy 71.046619 -41.215928) (xy 71.061974 -41.268223) (xy 71.06973 -41.322171) (xy 71.070216 -41.349422)
			(xy 71.069701 -41.378161) (xy 71.061076 -41.434989) (xy 71.044023 -41.489879) (xy 71.01893 -41.541591)
			(xy 70.986363 -41.588953) (xy 70.967092 -41.61028) (xy 70.960488 -41.617138) (xy 70.953376 -41.635172)
			(xy 70.953376 -41.724072) (xy 70.960488 -41.742106) (xy 70.967092 -41.748964) (xy 70.986384 -41.770272)
			(xy 71.018947 -41.817638) (xy 71.044036 -41.869353) (xy 71.061084 -41.924247) (xy 71.069704 -41.981076)
			(xy 71.069702 -42.038556) (xy 71.061077 -42.095385) (xy 71.044025 -42.150277) (xy 71.018931 -42.201989)
			(xy 70.986364 -42.249353) (xy 70.967092 -42.27068) (xy 70.960488 -42.277538) (xy 70.953376 -42.295572)
			(xy 70.953376 -42.384472) (xy 70.960488 -42.402506) (xy 70.967092 -42.409364) (xy 70.986378 -42.430678)
			(xy 71.018941 -42.478044) (xy 71.04403 -42.529759) (xy 71.061077 -42.584652) (xy 71.069697 -42.641482)
			(xy 71.070216 -42.670222) (xy 71.069783 -42.697594) (xy 71.061961 -42.751775) (xy 71.046465 -42.804279)
			(xy 71.025906 -42.849038) (xy 72.891902 -42.849038) (xy 72.895973 -42.793416) (xy 72.908099 -42.738979)
			(xy 72.928022 -42.686888) (xy 72.955318 -42.638253) (xy 72.989404 -42.59411) (xy 73.029553 -42.555401)
			(xy 73.074911 -42.52295) (xy 73.124511 -42.497449) (xy 73.177295 -42.479442) (xy 73.232138 -42.469312)
			(xy 73.287872 -42.467275) (xy 73.343309 -42.473375) (xy 73.397266 -42.487481) (xy 73.448595 -42.509293)
			(xy 73.496201 -42.538347) (xy 73.539069 -42.574022) (xy 73.576286 -42.615559) (xy 73.607059 -42.662072)
			(xy 73.630731 -42.712569) (xy 73.646799 -42.765976) (xy 73.654919 -42.821152) (xy 73.655428 -42.849038)
			(xy 73.654919 -42.876924) (xy 73.646799 -42.9321) (xy 73.630731 -42.985507) (xy 73.607059 -43.036004)
			(xy 73.576286 -43.082517) (xy 73.539069 -43.124054) (xy 73.496201 -43.159729) (xy 73.448595 -43.188783)
			(xy 73.397266 -43.210595) (xy 73.343309 -43.224701) (xy 73.287872 -43.230801) (xy 73.232138 -43.228764)
			(xy 73.177295 -43.218634) (xy 73.124511 -43.200627) (xy 73.074911 -43.175126) (xy 73.029553 -43.142675)
			(xy 72.989404 -43.103966) (xy 72.955318 -43.059823) (xy 72.928022 -43.011188) (xy 72.908099 -42.959097)
			(xy 72.895973 -42.90466) (xy 72.891902 -42.849038) (xy 71.025906 -42.849038) (xy 71.023615 -42.854026)
			(xy 70.993882 -42.89999) (xy 70.976236 -42.92092) (xy 70.975982 -42.921174) (xy 70.970398 -42.928262)
			(xy 70.96415 -42.945178) (xy 70.96379 -42.954194) (xy 70.96379 -43.02125) (xy 70.964173 -43.030264)
			(xy 70.970403 -43.047181) (xy 70.975982 -43.05427) (xy 70.976236 -43.05427) (xy 70.976236 -43.054524)
			(xy 70.993859 -43.075469) (xy 71.023572 -43.121439) (xy 71.04641 -43.171183) (xy 71.061905 -43.223681)
			(xy 71.069739 -43.277854) (xy 71.070216 -43.305222) (xy 71.06973 -43.332473) (xy 71.061974 -43.386421)
			(xy 71.046619 -43.438716) (xy 71.023977 -43.488293) (xy 70.994511 -43.534143) (xy 70.95882 -43.575334)
			(xy 70.917629 -43.611025) (xy 70.871779 -43.640491) (xy 70.822202 -43.663133) (xy 70.769907 -43.678488)
			(xy 70.715959 -43.686244) (xy 70.661457 -43.686244) (xy 70.607509 -43.678488) (xy 70.555214 -43.663133)
			(xy 70.505637 -43.640491) (xy 70.459787 -43.611025) (xy 70.418596 -43.575334) (xy 70.382905 -43.534143)
			(xy 70.353439 -43.488293) (xy 70.330797 -43.438716) (xy 70.315442 -43.386421) (xy 70.307686 -43.332473)
			(xy 70.3072 -43.305222) (xy 61.942599 -43.305222) (xy 62.286258 -43.73626) (xy 72.21296 -43.73626)
			(xy 72.217031 -43.680638) (xy 72.229157 -43.626201) (xy 72.24908 -43.57411) (xy 72.276376 -43.525475)
			(xy 72.310462 -43.481332) (xy 72.350611 -43.442623) (xy 72.395969 -43.410172) (xy 72.445569 -43.384671)
			(xy 72.498353 -43.366664) (xy 72.553196 -43.356534) (xy 72.60893 -43.354497) (xy 72.664367 -43.360597)
			(xy 72.718324 -43.374703) (xy 72.769653 -43.396515) (xy 72.817259 -43.425569) (xy 72.860127 -43.461244)
			(xy 72.897344 -43.502781) (xy 72.928117 -43.549294) (xy 72.951789 -43.599791) (xy 72.967857 -43.653198)
			(xy 72.975977 -43.708374) (xy 72.976486 -43.73626) (xy 72.975977 -43.764146) (xy 72.967857 -43.819322)
			(xy 72.956548 -43.85691) (xy 76.719682 -43.85691) (xy 76.723753 -43.801288) (xy 76.735879 -43.746851)
			(xy 76.755802 -43.69476) (xy 76.783098 -43.646125) (xy 76.817184 -43.601982) (xy 76.857333 -43.563273)
			(xy 76.902691 -43.530822) (xy 76.952291 -43.505321) (xy 77.005075 -43.487314) (xy 77.059918 -43.477184)
			(xy 77.115652 -43.475147) (xy 77.171089 -43.481247) (xy 77.225046 -43.495353) (xy 77.276375 -43.517165)
			(xy 77.323981 -43.546219) (xy 77.366849 -43.581894) (xy 77.404066 -43.623431) (xy 77.434839 -43.669944)
			(xy 77.458511 -43.720441) (xy 77.474579 -43.773848) (xy 77.482699 -43.829024) (xy 77.483208 -43.85691)
			(xy 77.482699 -43.884796) (xy 77.474579 -43.939972) (xy 77.458511 -43.993379) (xy 77.434839 -44.043876)
			(xy 77.404066 -44.090389) (xy 77.366849 -44.131926) (xy 77.323981 -44.167601) (xy 77.276375 -44.196655)
			(xy 77.225046 -44.218467) (xy 77.171089 -44.232573) (xy 77.115652 -44.238673) (xy 77.059918 -44.236636)
			(xy 77.005075 -44.226506) (xy 76.952291 -44.208499) (xy 76.902691 -44.182998) (xy 76.857333 -44.150547)
			(xy 76.817184 -44.111838) (xy 76.783098 -44.067695) (xy 76.755802 -44.01906) (xy 76.735879 -43.966969)
			(xy 76.723753 -43.912532) (xy 76.719682 -43.85691) (xy 72.956548 -43.85691) (xy 72.951789 -43.872729)
			(xy 72.928117 -43.923226) (xy 72.897344 -43.969739) (xy 72.860127 -44.011276) (xy 72.817259 -44.046951)
			(xy 72.769653 -44.076005) (xy 72.718324 -44.097817) (xy 72.664367 -44.111923) (xy 72.60893 -44.118023)
			(xy 72.553196 -44.115986) (xy 72.498353 -44.105856) (xy 72.445569 -44.087849) (xy 72.395969 -44.062348)
			(xy 72.350611 -44.029897) (xy 72.310462 -43.991188) (xy 72.276376 -43.947045) (xy 72.24908 -43.89841)
			(xy 72.229157 -43.846319) (xy 72.217031 -43.791882) (xy 72.21296 -43.73626) (xy 62.286258 -43.73626)
			(xy 63.385074 -45.114464) (xy 72.065386 -45.114464) (xy 72.069457 -45.058842) (xy 72.081583 -45.004405)
			(xy 72.101506 -44.952314) (xy 72.128802 -44.903679) (xy 72.162888 -44.859536) (xy 72.203037 -44.820827)
			(xy 72.248395 -44.788376) (xy 72.297995 -44.762875) (xy 72.350779 -44.744868) (xy 72.405622 -44.734738)
			(xy 72.461356 -44.732701) (xy 72.516793 -44.738801) (xy 72.57075 -44.752907) (xy 72.622079 -44.774719)
			(xy 72.669685 -44.803773) (xy 72.712553 -44.839448) (xy 72.742535 -44.87291) (xy 78.933038 -44.87291)
			(xy 78.937109 -44.817288) (xy 78.949235 -44.762851) (xy 78.969158 -44.71076) (xy 78.996454 -44.662125)
			(xy 79.03054 -44.617982) (xy 79.070689 -44.579273) (xy 79.116047 -44.546822) (xy 79.165647 -44.521321)
			(xy 79.218431 -44.503314) (xy 79.273274 -44.493184) (xy 79.329008 -44.491147) (xy 79.384445 -44.497247)
			(xy 79.438402 -44.511353) (xy 79.489731 -44.533165) (xy 79.537337 -44.562219) (xy 79.580205 -44.597894)
			(xy 79.617422 -44.639431) (xy 79.648195 -44.685944) (xy 79.671867 -44.736441) (xy 79.687935 -44.789848)
			(xy 79.696055 -44.845024) (xy 79.696564 -44.87291) (xy 79.696055 -44.900796) (xy 79.687935 -44.955972)
			(xy 79.671867 -45.009379) (xy 79.648195 -45.059876) (xy 79.617422 -45.106389) (xy 79.580205 -45.147926)
			(xy 79.537337 -45.183601) (xy 79.489731 -45.212655) (xy 79.438402 -45.234467) (xy 79.384445 -45.248573)
			(xy 79.329008 -45.254673) (xy 79.273274 -45.252636) (xy 79.218431 -45.242506) (xy 79.165647 -45.224499)
			(xy 79.116047 -45.198998) (xy 79.070689 -45.166547) (xy 79.03054 -45.127838) (xy 78.996454 -45.083695)
			(xy 78.969158 -45.03506) (xy 78.949235 -44.982969) (xy 78.937109 -44.928532) (xy 78.933038 -44.87291)
			(xy 72.742535 -44.87291) (xy 72.74977 -44.880985) (xy 72.780543 -44.927498) (xy 72.804215 -44.977995)
			(xy 72.820283 -45.031402) (xy 72.828403 -45.086578) (xy 72.828912 -45.114464) (xy 72.828403 -45.14235)
			(xy 72.820283 -45.197526) (xy 72.804215 -45.250933) (xy 72.780543 -45.30143) (xy 72.74977 -45.347943)
			(xy 72.744128 -45.35424) (xy 76.70368 -45.35424) (xy 76.707751 -45.298618) (xy 76.719877 -45.244181)
			(xy 76.7398 -45.19209) (xy 76.767096 -45.143455) (xy 76.801182 -45.099312) (xy 76.841331 -45.060603)
			(xy 76.886689 -45.028152) (xy 76.936289 -45.002651) (xy 76.989073 -44.984644) (xy 77.043916 -44.974514)
			(xy 77.09965 -44.972477) (xy 77.155087 -44.978577) (xy 77.209044 -44.992683) (xy 77.260373 -45.014495)
			(xy 77.307979 -45.043549) (xy 77.350847 -45.079224) (xy 77.388064 -45.120761) (xy 77.418837 -45.167274)
			(xy 77.442509 -45.217771) (xy 77.458577 -45.271178) (xy 77.466697 -45.326354) (xy 77.467206 -45.35424)
			(xy 77.466697 -45.382126) (xy 77.458577 -45.437302) (xy 77.442509 -45.490709) (xy 77.418837 -45.541206)
			(xy 77.388064 -45.587719) (xy 77.350847 -45.629256) (xy 77.307979 -45.664931) (xy 77.260373 -45.693985)
			(xy 77.209044 -45.715797) (xy 77.155087 -45.729903) (xy 77.09965 -45.736003) (xy 77.043916 -45.733966)
			(xy 76.989073 -45.723836) (xy 76.936289 -45.705829) (xy 76.886689 -45.680328) (xy 76.841331 -45.647877)
			(xy 76.801182 -45.609168) (xy 76.767096 -45.565025) (xy 76.7398 -45.51639) (xy 76.719877 -45.464299)
			(xy 76.707751 -45.409862) (xy 76.70368 -45.35424) (xy 72.744128 -45.35424) (xy 72.712553 -45.38948)
			(xy 72.669685 -45.425155) (xy 72.622079 -45.454209) (xy 72.57075 -45.476021) (xy 72.516793 -45.490127)
			(xy 72.461356 -45.496227) (xy 72.405622 -45.49419) (xy 72.350779 -45.48406) (xy 72.297995 -45.466053)
			(xy 72.248395 -45.440552) (xy 72.203037 -45.408101) (xy 72.162888 -45.369392) (xy 72.128802 -45.325249)
			(xy 72.101506 -45.276614) (xy 72.081583 -45.224523) (xy 72.069457 -45.170086) (xy 72.065386 -45.114464)
			(xy 63.385074 -45.114464) (xy 64.156635 -46.082204) (xy 70.052438 -46.082204) (xy 70.052859 -46.054949)
			(xy 70.060617 -46.000994) (xy 70.075975 -45.948693) (xy 70.09862 -45.89911) (xy 70.128092 -45.853254)
			(xy 70.16379 -45.81206) (xy 70.204988 -45.776367) (xy 70.250847 -45.7469) (xy 70.300432 -45.72426)
			(xy 70.352735 -45.708908) (xy 70.406691 -45.701156) (xy 70.433946 -45.700696) (xy 70.46085 -45.701123)
			(xy 70.514121 -45.708701) (xy 70.5658 -45.723687) (xy 70.614862 -45.745783) (xy 70.660334 -45.77455)
			(xy 70.701315 -45.80942) (xy 70.736991 -45.8497) (xy 70.752208 -45.871892) (xy 70.75932 -45.882814)
			(xy 70.78218 -45.894752) (xy 70.894448 -45.89272) (xy 70.9168 -45.879766) (xy 70.923658 -45.86859)
			(xy 70.938554 -45.844971) (xy 70.974237 -45.80202) (xy 71.0158 -45.764728) (xy 71.062354 -45.733892)
			(xy 71.112906 -45.710172) (xy 71.166375 -45.694073) (xy 71.22162 -45.68594) (xy 71.24954 -45.685456)
			(xy 71.276534 -45.685894) (xy 71.329983 -45.693506) (xy 71.381827 -45.708571) (xy 71.431031 -45.73079)
			(xy 71.476614 -45.75972) (xy 71.497444 -45.776896) (xy 71.505572 -45.784008) (xy 71.526146 -45.790104)
			(xy 71.61149 -45.779182) (xy 71.622036 -45.777413) (xy 71.640318 -45.766355) (xy 71.646796 -45.757846)
			(xy 71.662158 -45.736622) (xy 71.697744 -45.698169) (xy 71.738259 -45.66495) (xy 71.782941 -45.637591)
			(xy 71.830948 -45.616606) (xy 71.881375 -45.602391) (xy 71.933274 -45.595214) (xy 71.95947 -45.594778)
			(xy 71.986723 -45.595267) (xy 72.040675 -45.60302) (xy 72.092975 -45.618373) (xy 72.142557 -45.641013)
			(xy 72.188412 -45.670479) (xy 72.229607 -45.706172) (xy 72.265303 -45.747364) (xy 72.294772 -45.793217)
			(xy 72.317416 -45.842797) (xy 72.332773 -45.895095) (xy 72.340531 -45.949047) (xy 72.340531 -46.003553)
			(xy 72.332773 -46.057505) (xy 72.317416 -46.109803) (xy 72.294772 -46.159383) (xy 72.265303 -46.205236)
			(xy 72.229607 -46.246428) (xy 72.188412 -46.282121) (xy 72.142557 -46.311587) (xy 72.092975 -46.334227)
			(xy 72.040675 -46.34958) (xy 71.986723 -46.357333) (xy 71.95947 -46.357794) (xy 71.932477 -46.357338)
			(xy 71.879029 -46.349729) (xy 71.827186 -46.334667) (xy 71.777981 -46.312452) (xy 71.732397 -46.283528)
			(xy 71.711566 -46.266354) (xy 71.703438 -46.259242) (xy 71.682864 -46.253146) (xy 71.59752 -46.264068)
			(xy 71.58698 -46.26586) (xy 71.568696 -46.276903) (xy 71.562214 -46.285404) (xy 71.544596 -46.3097)
			(xy 71.503004 -46.352962) (xy 71.47941 -46.37151) (xy 71.471536 -46.377352) (xy 71.461122 -46.394878)
			(xy 71.447914 -46.485302) (xy 71.45274 -46.504606) (xy 71.458582 -46.51248) (xy 71.458582 -46.512734)
			(xy 71.476086 -46.537478) (xy 71.503888 -46.591331) (xy 71.522824 -46.648903) (xy 71.530027 -46.693836)
			(xy 76.67625 -46.693836) (xy 76.676736 -46.666585) (xy 76.684492 -46.612637) (xy 76.699847 -46.560342)
			(xy 76.722489 -46.510765) (xy 76.751955 -46.464915) (xy 76.787646 -46.423724) (xy 76.828837 -46.388033)
			(xy 76.874687 -46.358567) (xy 76.924264 -46.335925) (xy 76.976559 -46.32057) (xy 77.030507 -46.312814)
			(xy 77.085009 -46.312814) (xy 77.138957 -46.32057) (xy 77.191252 -46.335925) (xy 77.240829 -46.358567)
			(xy 77.286679 -46.388033) (xy 77.32787 -46.423724) (xy 77.363561 -46.464915) (xy 77.393027 -46.510765)
			(xy 77.415669 -46.560342) (xy 77.431024 -46.612637) (xy 77.43878 -46.666585) (xy 77.439266 -46.693836)
			(xy 77.438798 -46.720264) (xy 77.431488 -46.772611) (xy 77.417013 -46.823446) (xy 77.395652 -46.871793)
			(xy 77.382116 -46.894496) (xy 77.381862 -46.89475) (xy 77.376525 -46.904768) (xy 77.374267 -46.927318)
			(xy 77.377544 -46.938184) (xy 77.403706 -47.01286) (xy 77.408066 -47.023388) (xy 77.424171 -47.039472)
			(xy 77.434694 -47.043848) (xy 77.434948 -47.043848) (xy 77.459457 -47.052916) (xy 77.50591 -47.076859)
			(xy 77.548661 -47.106915) (xy 77.586913 -47.142523) (xy 77.61995 -47.183016) (xy 77.647153 -47.227637)
			(xy 77.668015 -47.275552) (xy 77.682145 -47.325866) (xy 77.689279 -47.377636) (xy 77.68971 -47.403766)
			(xy 77.689224 -47.431017) (xy 77.687701 -47.441612) (xy 78.96174 -47.441612) (xy 78.965811 -47.38599)
			(xy 78.977937 -47.331553) (xy 78.99786 -47.279462) (xy 79.025156 -47.230827) (xy 79.059242 -47.186684)
			(xy 79.099391 -47.147975) (xy 79.144749 -47.115524) (xy 79.194349 -47.090023) (xy 79.247133 -47.072016)
			(xy 79.301976 -47.061886) (xy 79.35771 -47.059849) (xy 79.413147 -47.065949) (xy 79.467104 -47.080055)
			(xy 79.518433 -47.101867) (xy 79.566039 -47.130921) (xy 79.608907 -47.166596) (xy 79.646124 -47.208133)
			(xy 79.676897 -47.254646) (xy 79.700569 -47.305143) (xy 79.716637 -47.35855) (xy 79.724757 -47.413726)
			(xy 79.725266 -47.441612) (xy 79.724757 -47.469498) (xy 79.716637 -47.524674) (xy 79.700569 -47.578081)
			(xy 79.676897 -47.628578) (xy 79.646124 -47.675091) (xy 79.608907 -47.716628) (xy 79.566039 -47.752303)
			(xy 79.518433 -47.781357) (xy 79.467104 -47.803169) (xy 79.413147 -47.817275) (xy 79.35771 -47.823375)
			(xy 79.301976 -47.821338) (xy 79.247133 -47.811208) (xy 79.194349 -47.793201) (xy 79.144749 -47.7677)
			(xy 79.099391 -47.735249) (xy 79.059242 -47.69654) (xy 79.025156 -47.652397) (xy 78.99786 -47.603762)
			(xy 78.977937 -47.551671) (xy 78.965811 -47.497234) (xy 78.96174 -47.441612) (xy 77.687701 -47.441612)
			(xy 77.681468 -47.484965) (xy 77.666113 -47.53726) (xy 77.643471 -47.586837) (xy 77.614005 -47.632687)
			(xy 77.578314 -47.673878) (xy 77.537123 -47.709569) (xy 77.491273 -47.739035) (xy 77.441696 -47.761677)
			(xy 77.389401 -47.777032) (xy 77.335453 -47.784788) (xy 77.280951 -47.784788) (xy 77.227003 -47.777032)
			(xy 77.174708 -47.761677) (xy 77.125131 -47.739035) (xy 77.079281 -47.709569) (xy 77.03809 -47.673878)
			(xy 77.002399 -47.632687) (xy 76.972933 -47.586837) (xy 76.950291 -47.53726) (xy 76.934936 -47.484965)
			(xy 76.92718 -47.431017) (xy 76.926694 -47.403766) (xy 76.927168 -47.377339) (xy 76.934477 -47.324991)
			(xy 76.94895 -47.274156) (xy 76.970309 -47.225809) (xy 76.983844 -47.203106) (xy 76.984098 -47.202852)
			(xy 76.989433 -47.192833) (xy 76.991694 -47.170283) (xy 76.988416 -47.159418) (xy 76.962254 -47.084742)
			(xy 76.957866 -47.074228) (xy 76.94178 -47.058139) (xy 76.931266 -47.053754) (xy 76.931012 -47.053754)
			(xy 76.906495 -47.044706) (xy 76.860044 -47.020759) (xy 76.817293 -46.990699) (xy 76.779042 -46.955089)
			(xy 76.746007 -46.914593) (xy 76.718805 -46.86997) (xy 76.697944 -46.822053) (xy 76.683815 -46.771738)
			(xy 76.676681 -46.719966) (xy 76.67625 -46.693836) (xy 71.530027 -46.693836) (xy 71.532417 -46.708745)
			(xy 71.533004 -46.739048) (xy 71.532567 -46.766301) (xy 71.524804 -46.82025) (xy 71.509442 -46.872546)
			(xy 71.486795 -46.922124) (xy 71.457324 -46.967974) (xy 71.421627 -47.009164) (xy 71.380433 -47.044855)
			(xy 71.334578 -47.07432) (xy 71.284997 -47.09696) (xy 71.232699 -47.112315) (xy 71.178749 -47.120071)
			(xy 71.151496 -47.120556) (xy 71.125463 -47.120104) (xy 71.07388 -47.113017) (xy 71.023739 -47.098988)
			(xy 70.975968 -47.078278) (xy 70.931453 -47.051271) (xy 70.910958 -47.035212) (xy 70.903191 -47.029486)
			(xy 70.884788 -47.023736) (xy 70.875144 -47.024036) (xy 70.795388 -47.030386) (xy 70.777608 -47.039022)
			(xy 70.771258 -47.046388) (xy 70.753071 -47.066028) (xy 70.712165 -47.10055) (xy 70.666837 -47.12902)
			(xy 70.617977 -47.150879) (xy 70.566542 -47.165698) (xy 70.513541 -47.173186) (xy 70.486778 -47.173642)
			(xy 70.459528 -47.173143) (xy 70.405582 -47.165384) (xy 70.35329 -47.150028) (xy 70.303715 -47.127387)
			(xy 70.257866 -47.097921) (xy 70.216677 -47.062231) (xy 70.180986 -47.021043) (xy 70.151519 -46.975196)
			(xy 70.128876 -46.925621) (xy 70.113518 -46.873329) (xy 70.105758 -46.819384) (xy 70.10527 -46.792134)
			(xy 70.105803 -46.76336) (xy 70.114453 -46.706467) (xy 70.131548 -46.651517) (xy 70.156699 -46.599757)
			(xy 70.189337 -46.55236) (xy 70.208648 -46.531022) (xy 70.216014 -46.523148) (xy 70.223126 -46.503336)
			(xy 70.21576 -46.40707) (xy 70.205854 -46.388274) (xy 70.197472 -46.38167) (xy 70.175277 -46.363457)
			(xy 70.13607 -46.321518) (xy 70.103587 -46.274179) (xy 70.078561 -46.222509) (xy 70.061556 -46.167674)
			(xy 70.052956 -46.11091) (xy 70.052438 -46.082204) (xy 64.156635 -46.082204) (xy 64.333628 -46.3042)
			(xy 64.359439 -46.337245) (xy 64.406044 -46.406958) (xy 64.446626 -46.480341) (xy 64.4809 -46.556873)
			(xy 64.495172 -46.5963) (xy 65.250845 -48.753014) (xy 73.168254 -48.753014) (xy 73.172325 -48.697392)
			(xy 73.184451 -48.642955) (xy 73.204374 -48.590864) (xy 73.23167 -48.542229) (xy 73.265756 -48.498086)
			(xy 73.305905 -48.459377) (xy 73.351263 -48.426926) (xy 73.400863 -48.401425) (xy 73.453647 -48.383418)
			(xy 73.50849 -48.373288) (xy 73.564224 -48.371251) (xy 73.619661 -48.377351) (xy 73.673618 -48.391457)
			(xy 73.724947 -48.413269) (xy 73.772553 -48.442323) (xy 73.815421 -48.477998) (xy 73.852638 -48.519535)
			(xy 73.883411 -48.566048) (xy 73.907083 -48.616545) (xy 73.923151 -48.669952) (xy 73.931271 -48.725128)
			(xy 73.93178 -48.753014) (xy 73.931271 -48.7809) (xy 73.923151 -48.836076) (xy 73.907083 -48.889483)
			(xy 73.892893 -48.919754) (xy 75.214938 -48.919754) (xy 75.214938 -48.865246) (xy 75.222695 -48.811294)
			(xy 75.238051 -48.758995) (xy 75.260694 -48.709413) (xy 75.290162 -48.663559) (xy 75.325856 -48.622364)
			(xy 75.367049 -48.586669) (xy 75.412903 -48.557199) (xy 75.462484 -48.534555) (xy 75.514782 -48.519197)
			(xy 75.568734 -48.511439) (xy 75.595988 -48.510952) (xy 75.622735 -48.511351) (xy 75.675703 -48.518842)
			(xy 75.727107 -48.533652) (xy 75.775942 -48.55549) (xy 75.821251 -48.58393) (xy 75.862148 -48.618414)
			(xy 75.897832 -48.658268) (xy 75.927606 -48.702711) (xy 75.93965 -48.726598) (xy 75.943618 -48.734179)
			(xy 75.955675 -48.746307) (xy 75.971069 -48.753753) (xy 75.979528 -48.755046) (xy 76.077826 -48.766222)
			(xy 76.101956 -48.75657) (xy 76.110084 -48.74641) (xy 76.128305 -48.724697) (xy 76.170056 -48.686361)
			(xy 76.21702 -48.654627) (xy 76.268163 -48.630191) (xy 76.32236 -48.613594) (xy 76.378416 -48.605199)
			(xy 76.406756 -48.604678) (xy 76.407518 -48.604678) (xy 76.425537 -48.604901) (xy 76.461412 -48.608334)
			(xy 76.479146 -48.611536) (xy 76.49337 -48.61433) (xy 76.519786 -48.604424) (xy 76.593192 -48.51019)
			(xy 76.596494 -48.481742) (xy 76.590398 -48.468788) (xy 76.579001 -48.443355) (xy 76.562925 -48.389993)
			(xy 76.554809 -48.334856) (xy 76.55433 -48.30699) (xy 76.554789 -48.27974) (xy 76.562546 -48.225796)
			(xy 76.577901 -48.173504) (xy 76.600542 -48.12393) (xy 76.630007 -48.078082) (xy 76.665697 -48.036894)
			(xy 76.706885 -48.001205) (xy 76.752733 -47.97174) (xy 76.802308 -47.9491) (xy 76.8546 -47.933745)
			(xy 76.908544 -47.925989) (xy 76.963044 -47.925988) (xy 77.016989 -47.933743) (xy 77.069281 -47.949096)
			(xy 77.118856 -47.971734) (xy 77.164705 -48.001198) (xy 77.205894 -48.036886) (xy 77.241585 -48.078073)
			(xy 77.271052 -48.123919) (xy 77.293694 -48.173493) (xy 77.309051 -48.225784) (xy 77.31681 -48.279728)
			(xy 77.316813 -48.334228) (xy 77.309061 -48.388173) (xy 77.29371 -48.440466) (xy 77.271073 -48.490042)
			(xy 77.241612 -48.535892) (xy 77.205925 -48.577083) (xy 77.16474 -48.612776) (xy 77.118895 -48.642244)
			(xy 77.069322 -48.664889) (xy 77.017032 -48.680248) (xy 76.963088 -48.688009) (xy 76.935838 -48.688498)
			(xy 76.935076 -48.688498) (xy 76.917057 -48.688277) (xy 76.881182 -48.684843) (xy 76.863448 -48.68164)
			(xy 76.849224 -48.678846) (xy 76.822808 -48.688752) (xy 76.749402 -48.782986) (xy 76.7461 -48.811434)
			(xy 76.752196 -48.824388) (xy 76.763585 -48.849824) (xy 76.779663 -48.903185) (xy 76.78463 -48.93691)
			(xy 78.933038 -48.93691) (xy 78.937109 -48.881288) (xy 78.949235 -48.826851) (xy 78.969158 -48.77476)
			(xy 78.996454 -48.726125) (xy 79.03054 -48.681982) (xy 79.070689 -48.643273) (xy 79.116047 -48.610822)
			(xy 79.165647 -48.585321) (xy 79.218431 -48.567314) (xy 79.273274 -48.557184) (xy 79.329008 -48.555147)
			(xy 79.384445 -48.561247) (xy 79.438402 -48.575353) (xy 79.489731 -48.597165) (xy 79.537337 -48.626219)
			(xy 79.580205 -48.661894) (xy 79.617422 -48.703431) (xy 79.648195 -48.749944) (xy 79.671867 -48.800441)
			(xy 79.687935 -48.853848) (xy 79.696055 -48.909024) (xy 79.696564 -48.93691) (xy 79.696055 -48.964796)
			(xy 79.687935 -49.019972) (xy 79.671867 -49.073379) (xy 79.648195 -49.123876) (xy 79.617422 -49.170389)
			(xy 79.580205 -49.211926) (xy 79.537337 -49.247601) (xy 79.489731 -49.276655) (xy 79.438402 -49.298467)
			(xy 79.384445 -49.312573) (xy 79.329008 -49.318673) (xy 79.273274 -49.316636) (xy 79.218431 -49.306506)
			(xy 79.165647 -49.288499) (xy 79.116047 -49.262998) (xy 79.070689 -49.230547) (xy 79.03054 -49.191838)
			(xy 78.996454 -49.147695) (xy 78.969158 -49.09906) (xy 78.949235 -49.046969) (xy 78.937109 -48.992532)
			(xy 78.933038 -48.93691) (xy 76.78463 -48.93691) (xy 76.787783 -48.958321) (xy 76.788264 -48.986186)
			(xy 76.787832 -49.013441) (xy 76.780075 -49.067395) (xy 76.764719 -49.119696) (xy 76.742075 -49.169279)
			(xy 76.712604 -49.215134) (xy 76.676907 -49.256328) (xy 76.63571 -49.292022) (xy 76.589853 -49.321489)
			(xy 76.540268 -49.344129) (xy 76.487965 -49.359482) (xy 76.434011 -49.367234) (xy 76.406756 -49.367694)
			(xy 76.380011 -49.367232) (xy 76.327047 -49.359748) (xy 76.275646 -49.344946) (xy 76.226813 -49.323116)
			(xy 76.181504 -49.294686) (xy 76.140606 -49.26021) (xy 76.104919 -49.220365) (xy 76.075141 -49.17593)
			(xy 76.063094 -49.152048) (xy 76.059082 -49.144493) (xy 76.047046 -49.132359) (xy 76.031668 -49.124901)
			(xy 76.023216 -49.1236) (xy 75.924918 -49.112424) (xy 75.900788 -49.122076) (xy 75.89266 -49.132236)
			(xy 75.874426 -49.153937) (xy 75.832677 -49.192272) (xy 75.785715 -49.224007) (xy 75.734574 -49.248443)
			(xy 75.680381 -49.265044) (xy 75.624327 -49.273444) (xy 75.595988 -49.273968) (xy 75.568734 -49.273561)
			(xy 75.514782 -49.265803) (xy 75.462484 -49.250445) (xy 75.412903 -49.227801) (xy 75.367049 -49.198331)
			(xy 75.325856 -49.162636) (xy 75.290162 -49.121441) (xy 75.260694 -49.075587) (xy 75.238051 -49.026005)
			(xy 75.222695 -48.973706) (xy 75.214938 -48.919754) (xy 73.892893 -48.919754) (xy 73.883411 -48.93998)
			(xy 73.852638 -48.986493) (xy 73.815421 -49.02803) (xy 73.772553 -49.063705) (xy 73.724947 -49.092759)
			(xy 73.673618 -49.114571) (xy 73.619661 -49.128677) (xy 73.564224 -49.134777) (xy 73.50849 -49.13274)
			(xy 73.453647 -49.12261) (xy 73.400863 -49.104603) (xy 73.351263 -49.079102) (xy 73.305905 -49.046651)
			(xy 73.265756 -49.007942) (xy 73.23167 -48.963799) (xy 73.204374 -48.915164) (xy 73.184451 -48.863073)
			(xy 73.172325 -48.808636) (xy 73.168254 -48.753014) (xy 65.250845 -48.753014) (xy 65.52184 -49.526444)
			(xy 65.536454 -49.569763) (xy 65.558634 -49.658462) (xy 65.572608 -49.748818) (xy 65.575942 -49.794414)
			(xy 65.585761 -49.95291) (xy 78.933038 -49.95291) (xy 78.937109 -49.897288) (xy 78.949235 -49.842851)
			(xy 78.969158 -49.79076) (xy 78.996454 -49.742125) (xy 79.03054 -49.697982) (xy 79.070689 -49.659273)
			(xy 79.116047 -49.626822) (xy 79.165647 -49.601321) (xy 79.218431 -49.583314) (xy 79.273274 -49.573184)
			(xy 79.329008 -49.571147) (xy 79.384445 -49.577247) (xy 79.438402 -49.591353) (xy 79.489731 -49.613165)
			(xy 79.537337 -49.642219) (xy 79.580205 -49.677894) (xy 79.617422 -49.719431) (xy 79.648195 -49.765944)
			(xy 79.671867 -49.816441) (xy 79.687935 -49.869848) (xy 79.696055 -49.925024) (xy 79.696564 -49.95291)
			(xy 79.696055 -49.980796) (xy 79.687935 -50.035972) (xy 79.671867 -50.089379) (xy 79.648195 -50.139876)
			(xy 79.617422 -50.186389) (xy 79.580205 -50.227926) (xy 79.537337 -50.263601) (xy 79.489731 -50.292655)
			(xy 79.438402 -50.314467) (xy 79.384445 -50.328573) (xy 79.329008 -50.334673) (xy 79.273274 -50.332636)
			(xy 79.218431 -50.322506) (xy 79.165647 -50.304499) (xy 79.116047 -50.278998) (xy 79.070689 -50.246547)
			(xy 79.03054 -50.207838) (xy 78.996454 -50.163695) (xy 78.969158 -50.11506) (xy 78.949235 -50.062969)
			(xy 78.937109 -50.008532) (xy 78.933038 -49.95291) (xy 65.585761 -49.95291) (xy 65.651835 -51.019456)
			(xy 76.7494 -51.019456) (xy 76.753471 -50.963834) (xy 76.765597 -50.909397) (xy 76.78552 -50.857306)
			(xy 76.812816 -50.808671) (xy 76.846902 -50.764528) (xy 76.887051 -50.725819) (xy 76.932409 -50.693368)
			(xy 76.982009 -50.667867) (xy 77.034793 -50.64986) (xy 77.089636 -50.63973) (xy 77.14537 -50.637693)
			(xy 77.200807 -50.643793) (xy 77.254764 -50.657899) (xy 77.306093 -50.679711) (xy 77.353699 -50.708765)
			(xy 77.396567 -50.74444) (xy 77.433784 -50.785977) (xy 77.464557 -50.83249) (xy 77.488229 -50.882987)
			(xy 77.504297 -50.936394) (xy 77.512417 -50.99157) (xy 77.512926 -51.019456) (xy 77.512417 -51.047342)
			(xy 77.504297 -51.102518) (xy 77.488229 -51.155925) (xy 77.464557 -51.206422) (xy 77.433784 -51.252935)
			(xy 77.396567 -51.294472) (xy 77.353699 -51.330147) (xy 77.306093 -51.359201) (xy 77.254764 -51.381013)
			(xy 77.200807 -51.395119) (xy 77.14537 -51.401219) (xy 77.089636 -51.399182) (xy 77.034793 -51.389052)
			(xy 76.982009 -51.371045) (xy 76.932409 -51.345544) (xy 76.887051 -51.313093) (xy 76.846902 -51.274384)
			(xy 76.812816 -51.230241) (xy 76.78552 -51.181606) (xy 76.765597 -51.129515) (xy 76.753471 -51.075078)
			(xy 76.7494 -51.019456) (xy 65.651835 -51.019456) (xy 65.714777 -52.035456) (xy 78.941166 -52.035456)
			(xy 78.945237 -51.979834) (xy 78.957363 -51.925397) (xy 78.977286 -51.873306) (xy 79.004582 -51.824671)
			(xy 79.038668 -51.780528) (xy 79.078817 -51.741819) (xy 79.124175 -51.709368) (xy 79.173775 -51.683867)
			(xy 79.226559 -51.66586) (xy 79.281402 -51.65573) (xy 79.337136 -51.653693) (xy 79.392573 -51.659793)
			(xy 79.44653 -51.673899) (xy 79.497859 -51.695711) (xy 79.545465 -51.724765) (xy 79.588333 -51.76044)
			(xy 79.62555 -51.801977) (xy 79.656323 -51.84849) (xy 79.679995 -51.898987) (xy 79.696063 -51.952394)
			(xy 79.704183 -52.00757) (xy 79.704692 -52.035456) (xy 79.704183 -52.063342) (xy 79.696063 -52.118518)
			(xy 79.679995 -52.171925) (xy 79.656323 -52.222422) (xy 79.62555 -52.268935) (xy 79.588333 -52.310472)
			(xy 79.545465 -52.346147) (xy 79.497859 -52.375201) (xy 79.44653 -52.397013) (xy 79.392573 -52.411119)
			(xy 79.337136 -52.417219) (xy 79.281402 -52.415182) (xy 79.226559 -52.405052) (xy 79.173775 -52.387045)
			(xy 79.124175 -52.361544) (xy 79.078817 -52.329093) (xy 79.038668 -52.290384) (xy 79.004582 -52.246241)
			(xy 78.977286 -52.197606) (xy 78.957363 -52.145515) (xy 78.945237 -52.091078) (xy 78.941166 -52.035456)
			(xy 65.714777 -52.035456) (xy 65.735454 -52.369212) (xy 65.736566 -52.379843) (xy 65.746427 -52.398787)
			(xy 65.754504 -52.405788) (xy 65.797176 -52.439824) (xy 65.804639 -52.445293) (xy 65.822214 -52.451038)
			(xy 65.831466 -52.451) (xy 65.836292 -52.450492) (xy 65.837308 -52.450492) (xy 65.837562 -52.450238)
			(xy 65.837816 -52.450238) (xy 65.839086 -52.449984) (xy 65.854533 -52.447605) (xy 65.885687 -52.445061)
			(xy 65.901316 -52.444904) (xy 65.902078 -52.444904) (xy 65.929332 -52.445366) (xy 65.983284 -52.45312)
			(xy 66.035584 -52.468475) (xy 66.085166 -52.491116) (xy 66.131021 -52.520584) (xy 66.172215 -52.556277)
			(xy 66.20791 -52.597471) (xy 66.237379 -52.643325) (xy 66.260022 -52.692907) (xy 66.275378 -52.745206)
			(xy 66.283133 -52.799158) (xy 66.283586 -52.826412) (xy 66.283161 -52.851923) (xy 66.276365 -52.902491)
			(xy 66.262896 -52.951703) (xy 66.242994 -52.998684) (xy 66.217014 -53.042596) (xy 66.201544 -53.062886)
			(xy 66.199004 -53.065934) (xy 66.197988 -53.067458) (xy 66.194686 -53.074062) (xy 66.192343 -53.079285)
			(xy 66.189778 -53.090438) (xy 66.189606 -53.09616) (xy 66.189606 -53.128164) (xy 66.17843 -53.128164)
			(xy 66.17843 -53.178964) (xy 66.178765 -53.187567) (xy 66.18448 -53.203797) (xy 66.189606 -53.210714)
			(xy 66.190876 -53.212238) (xy 66.208272 -53.233114) (xy 66.237595 -53.278862) (xy 66.260126 -53.32831)
			(xy 66.27541 -53.380455) (xy 66.283136 -53.434243) (xy 66.283586 -53.461412) (xy 66.283161 -53.486923)
			(xy 66.276365 -53.537491) (xy 66.262896 -53.586703) (xy 66.242994 -53.633684) (xy 66.217014 -53.677596)
			(xy 66.201544 -53.697886) (xy 66.199004 -53.700934) (xy 66.197988 -53.702458) (xy 66.194686 -53.709062)
			(xy 66.192343 -53.714285) (xy 66.189778 -53.725438) (xy 66.189606 -53.73116) (xy 66.189606 -53.763164)
			(xy 66.17843 -53.763164) (xy 66.17843 -53.813964) (xy 66.178765 -53.822567) (xy 66.18448 -53.838797)
			(xy 66.189606 -53.845714) (xy 66.190876 -53.847238) (xy 66.208272 -53.868114) (xy 66.237595 -53.913862)
			(xy 66.260126 -53.96331) (xy 66.27541 -54.015455) (xy 66.283136 -54.069243) (xy 66.283586 -54.096412)
			(xy 66.283161 -54.121923) (xy 66.276365 -54.172491) (xy 66.262896 -54.221703) (xy 66.242994 -54.268684)
			(xy 66.217014 -54.312596) (xy 66.201544 -54.332886) (xy 66.199004 -54.335934) (xy 66.197988 -54.337458)
			(xy 66.194686 -54.344062) (xy 66.192343 -54.349285) (xy 66.189778 -54.360438) (xy 66.189606 -54.36616)
			(xy 66.189606 -54.398164) (xy 66.17843 -54.398164) (xy 66.17843 -54.448964) (xy 66.178765 -54.457567)
			(xy 66.18448 -54.473797) (xy 66.189606 -54.480714) (xy 66.190876 -54.482238) (xy 66.208272 -54.503114)
			(xy 66.237595 -54.548862) (xy 66.260126 -54.59831) (xy 66.27541 -54.650455) (xy 66.283136 -54.704243)
			(xy 66.283586 -54.731412) (xy 66.283109 -54.758855) (xy 66.278439 -54.791102) (xy 68.176394 -54.791102)
			(xy 68.176863 -54.763732) (xy 68.18468 -54.709553) (xy 68.200169 -54.65705) (xy 68.22301 -54.607303)
			(xy 68.252733 -54.561336) (xy 68.270374 -54.540404) (xy 68.270628 -54.54015) (xy 68.276203 -54.533056)
			(xy 68.282456 -54.516145) (xy 68.28282 -54.50713) (xy 68.28282 -54.440074) (xy 68.282471 -54.431056)
			(xy 68.276218 -54.41414) (xy 68.270628 -54.407054) (xy 68.270374 -54.407054) (xy 68.270374 -54.4068)
			(xy 68.252733 -54.385867) (xy 68.223005 -54.3399) (xy 68.200157 -54.290154) (xy 68.184658 -54.237652)
			(xy 68.176828 -54.183473) (xy 68.176828 -54.12873) (xy 68.184657 -54.074551) (xy 68.200155 -54.022049)
			(xy 68.223003 -53.972303) (xy 68.252731 -53.926336) (xy 68.270374 -53.905404) (xy 68.270628 -53.90515)
			(xy 68.276203 -53.898056) (xy 68.282456 -53.881145) (xy 68.28282 -53.87213) (xy 68.28282 -53.805074)
			(xy 68.282471 -53.796056) (xy 68.276218 -53.77914) (xy 68.270628 -53.772054) (xy 68.270374 -53.772054)
			(xy 68.270374 -53.7718) (xy 68.252733 -53.750867) (xy 68.223005 -53.7049) (xy 68.200157 -53.655154)
			(xy 68.184658 -53.602652) (xy 68.176828 -53.548473) (xy 68.176828 -53.49373) (xy 68.184657 -53.439551)
			(xy 68.200155 -53.387049) (xy 68.223003 -53.337303) (xy 68.252731 -53.291336) (xy 68.270374 -53.270404)
			(xy 68.270628 -53.27015) (xy 68.276203 -53.263056) (xy 68.282456 -53.246145) (xy 68.28282 -53.23713)
			(xy 68.28282 -53.170074) (xy 68.282471 -53.161056) (xy 68.276218 -53.14414) (xy 68.270628 -53.137054)
			(xy 68.270374 -53.137054) (xy 68.270374 -53.1368) (xy 68.252717 -53.115882) (xy 68.223009 -53.069905)
			(xy 68.200177 -53.020154) (xy 68.18469 -52.96765) (xy 68.176866 -52.913472) (xy 68.176394 -52.886102)
			(xy 68.17688 -52.858851) (xy 68.184636 -52.804903) (xy 68.199991 -52.752608) (xy 68.222633 -52.703031)
			(xy 68.252099 -52.657181) (xy 68.28779 -52.61599) (xy 68.328981 -52.580299) (xy 68.374831 -52.550833)
			(xy 68.424408 -52.528191) (xy 68.476703 -52.512836) (xy 68.530651 -52.50508) (xy 68.585153 -52.50508)
			(xy 68.639101 -52.512836) (xy 68.691396 -52.528191) (xy 68.730496 -52.546048) (xy 73.679596 -52.546048)
			(xy 73.679596 -52.491552) (xy 73.687351 -52.437611) (xy 73.702703 -52.385322) (xy 73.72534 -52.33575)
			(xy 73.754801 -52.289903) (xy 73.790487 -52.248716) (xy 73.83167 -52.213027) (xy 73.877513 -52.183561)
			(xy 73.927082 -52.160918) (xy 73.979369 -52.14556) (xy 74.03331 -52.137799) (xy 74.060558 -52.13731)
			(xy 74.087927 -52.137798) (xy 74.142106 -52.14561) (xy 74.194609 -52.161094) (xy 74.244356 -52.183931)
			(xy 74.290324 -52.213651) (xy 74.311256 -52.23129) (xy 74.31151 -52.231544) (xy 74.318586 -52.237146)
			(xy 74.335511 -52.243382) (xy 74.34453 -52.243736) (xy 74.411586 -52.243736) (xy 74.420601 -52.243364)
			(xy 74.437518 -52.237126) (xy 74.444606 -52.231544) (xy 74.444606 -52.23129) (xy 74.44486 -52.23129)
			(xy 74.465793 -52.213649) (xy 74.511761 -52.183925) (xy 74.561507 -52.161079) (xy 74.614009 -52.145583)
			(xy 74.668187 -52.137754) (xy 74.722929 -52.137754) (xy 74.777107 -52.145583) (xy 74.829609 -52.161079)
			(xy 74.879355 -52.183925) (xy 74.925323 -52.213649) (xy 74.946256 -52.23129) (xy 74.94651 -52.231544)
			(xy 74.953586 -52.237146) (xy 74.970511 -52.243382) (xy 74.97953 -52.243736) (xy 75.046586 -52.243736)
			(xy 75.055601 -52.243364) (xy 75.072518 -52.237126) (xy 75.079606 -52.231544) (xy 75.079606 -52.23129)
			(xy 75.07986 -52.23129) (xy 75.100795 -52.213655) (xy 75.146767 -52.183943) (xy 75.196514 -52.161106)
			(xy 75.249014 -52.145614) (xy 75.303189 -52.137785) (xy 75.330558 -52.13731) (xy 75.357814 -52.137734)
			(xy 75.411772 -52.145487) (xy 75.464078 -52.16084) (xy 75.513665 -52.183481) (xy 75.559526 -52.212949)
			(xy 75.600726 -52.248645) (xy 75.636426 -52.28984) (xy 75.665899 -52.335698) (xy 75.688546 -52.385283)
			(xy 75.703905 -52.437587) (xy 75.711663 -52.491544) (xy 75.711663 -52.546056) (xy 75.705719 -52.587398)
			(xy 76.755242 -52.587398) (xy 76.759313 -52.531776) (xy 76.771439 -52.477339) (xy 76.791362 -52.425248)
			(xy 76.818658 -52.376613) (xy 76.852744 -52.33247) (xy 76.892893 -52.293761) (xy 76.938251 -52.26131)
			(xy 76.987851 -52.235809) (xy 77.040635 -52.217802) (xy 77.095478 -52.207672) (xy 77.151212 -52.205635)
			(xy 77.206649 -52.211735) (xy 77.260606 -52.225841) (xy 77.311935 -52.247653) (xy 77.359541 -52.276707)
			(xy 77.402409 -52.312382) (xy 77.439626 -52.353919) (xy 77.470399 -52.400432) (xy 77.494071 -52.450929)
			(xy 77.510139 -52.504336) (xy 77.517735 -52.555949) (xy 84.583802 -52.555949) (xy 84.583802 -52.501452)
			(xy 84.591558 -52.447509) (xy 84.606911 -52.39522) (xy 84.629549 -52.345647) (xy 84.659011 -52.299801)
			(xy 84.694698 -52.258614) (xy 84.735883 -52.222924) (xy 84.781728 -52.193459) (xy 84.831299 -52.170818)
			(xy 84.883588 -52.155462) (xy 84.93753 -52.147704) (xy 84.964778 -52.147216) (xy 84.992148 -52.147691)
			(xy 85.046327 -52.155506) (xy 85.09883 -52.170993) (xy 85.148577 -52.193833) (xy 85.194544 -52.223556)
			(xy 85.215476 -52.241196) (xy 85.21573 -52.24145) (xy 85.222828 -52.247019) (xy 85.239736 -52.253275)
			(xy 85.24875 -52.253642) (xy 85.315806 -52.253642) (xy 85.324825 -52.2533) (xy 85.341742 -52.247043)
			(xy 85.348826 -52.24145) (xy 85.348826 -52.241196) (xy 85.34908 -52.241196) (xy 85.370008 -52.223552)
			(xy 85.415982 -52.193841) (xy 85.465731 -52.171006) (xy 85.518232 -52.155516) (xy 85.572409 -52.147689)
			(xy 85.599778 -52.147216) (xy 85.627034 -52.147629) (xy 85.68099 -52.155384) (xy 85.733294 -52.170739)
			(xy 85.78288 -52.193382) (xy 85.828739 -52.222851) (xy 85.869937 -52.258547) (xy 85.905635 -52.299743)
			(xy 85.935107 -52.3456) (xy 85.957753 -52.395185) (xy 85.973111 -52.447488) (xy 85.980869 -52.501444)
			(xy 85.980869 -52.555956) (xy 85.973111 -52.609912) (xy 85.957753 -52.662215) (xy 85.935107 -52.7118)
			(xy 85.905635 -52.757657) (xy 85.869937 -52.798853) (xy 85.828739 -52.834549) (xy 85.78288 -52.864018)
			(xy 85.733294 -52.886661) (xy 85.68099 -52.902016) (xy 85.627034 -52.909771) (xy 85.599778 -52.910232)
			(xy 85.572407 -52.909795) (xy 85.518225 -52.901973) (xy 85.465721 -52.886478) (xy 85.415975 -52.863629)
			(xy 85.37001 -52.833897) (xy 85.34908 -52.816252) (xy 85.348826 -52.815998) (xy 85.341736 -52.810416)
			(xy 85.324822 -52.804167) (xy 85.315806 -52.803806) (xy 85.24875 -52.803806) (xy 85.239735 -52.804186)
			(xy 85.222818 -52.810418) (xy 85.21573 -52.815998) (xy 85.21573 -52.816252) (xy 85.215476 -52.816252)
			(xy 85.19452 -52.833861) (xy 85.148554 -52.863579) (xy 85.098813 -52.886422) (xy 85.046318 -52.90192)
			(xy 84.992146 -52.909755) (xy 84.964778 -52.910232) (xy 84.93753 -52.909696) (xy 84.883588 -52.901938)
			(xy 84.831299 -52.886582) (xy 84.781728 -52.863941) (xy 84.735883 -52.834476) (xy 84.694698 -52.798786)
			(xy 84.659011 -52.757599) (xy 84.629549 -52.711753) (xy 84.606911 -52.66218) (xy 84.591558 -52.609891)
			(xy 84.583802 -52.555949) (xy 77.517735 -52.555949) (xy 77.518259 -52.559512) (xy 77.518768 -52.587398)
			(xy 77.518259 -52.615284) (xy 77.510139 -52.67046) (xy 77.494071 -52.723867) (xy 77.470399 -52.774364)
			(xy 77.439626 -52.820877) (xy 77.402409 -52.862414) (xy 77.359541 -52.898089) (xy 77.311935 -52.927143)
			(xy 77.260606 -52.948955) (xy 77.206649 -52.963061) (xy 77.151212 -52.969161) (xy 77.095478 -52.967124)
			(xy 77.040635 -52.956994) (xy 76.987851 -52.938987) (xy 76.938251 -52.913486) (xy 76.892893 -52.881035)
			(xy 76.852744 -52.842326) (xy 76.818658 -52.798183) (xy 76.791362 -52.749548) (xy 76.771439 -52.697457)
			(xy 76.759313 -52.64302) (xy 76.755242 -52.587398) (xy 75.705719 -52.587398) (xy 75.703905 -52.600013)
			(xy 75.688546 -52.652317) (xy 75.665899 -52.701902) (xy 75.636426 -52.74776) (xy 75.600726 -52.788955)
			(xy 75.559526 -52.824651) (xy 75.513665 -52.854119) (xy 75.464078 -52.87676) (xy 75.411772 -52.892113)
			(xy 75.357814 -52.899866) (xy 75.330558 -52.900326) (xy 75.303188 -52.899844) (xy 75.249009 -52.892033)
			(xy 75.196505 -52.876548) (xy 75.146758 -52.85371) (xy 75.100791 -52.823987) (xy 75.07986 -52.806346)
			(xy 75.079606 -52.806092) (xy 75.072523 -52.800501) (xy 75.055603 -52.794257) (xy 75.046586 -52.7939)
			(xy 74.97953 -52.7939) (xy 74.970515 -52.794271) (xy 74.953597 -52.800509) (xy 74.94651 -52.806092)
			(xy 74.946256 -52.806346) (xy 74.925323 -52.823987) (xy 74.879355 -52.853711) (xy 74.829609 -52.876557)
			(xy 74.777107 -52.892053) (xy 74.722929 -52.899882) (xy 74.668187 -52.899882) (xy 74.614009 -52.892053)
			(xy 74.561507 -52.876557) (xy 74.511761 -52.853711) (xy 74.465793 -52.823987) (xy 74.44486 -52.806346)
			(xy 74.444606 -52.806092) (xy 74.437523 -52.800501) (xy 74.420603 -52.794257) (xy 74.411586 -52.7939)
			(xy 74.34453 -52.7939) (xy 74.335515 -52.794271) (xy 74.318597 -52.800509) (xy 74.31151 -52.806092)
			(xy 74.31151 -52.806346) (xy 74.311256 -52.806346) (xy 74.290307 -52.823964) (xy 74.244339 -52.853681)
			(xy 74.194596 -52.876522) (xy 74.142099 -52.892018) (xy 74.087926 -52.89985) (xy 74.060558 -52.900326)
			(xy 74.03331 -52.899801) (xy 73.979369 -52.89204) (xy 73.927082 -52.876682) (xy 73.877513 -52.854039)
			(xy 73.83167 -52.824573) (xy 73.790487 -52.788884) (xy 73.754801 -52.747697) (xy 73.72534 -52.70185)
			(xy 73.702703 -52.652278) (xy 73.687351 -52.599989) (xy 73.679596 -52.546048) (xy 68.730496 -52.546048)
			(xy 68.740973 -52.550833) (xy 68.786823 -52.580299) (xy 68.828014 -52.61599) (xy 68.863705 -52.657181)
			(xy 68.893171 -52.703031) (xy 68.915813 -52.752608) (xy 68.931168 -52.804903) (xy 68.938924 -52.858851)
			(xy 68.93941 -52.886102) (xy 68.938943 -52.913472) (xy 68.931125 -52.967651) (xy 68.915636 -53.020154)
			(xy 68.892794 -53.069901) (xy 68.863071 -53.115868) (xy 68.84543 -53.1368) (xy 68.845176 -53.137054)
			(xy 68.8396 -53.144148) (xy 68.833348 -53.161059) (xy 68.832984 -53.170074) (xy 68.832984 -53.23713)
			(xy 68.83333 -53.246148) (xy 68.839585 -53.263065) (xy 68.845176 -53.27015) (xy 68.84543 -53.27015)
			(xy 68.84543 -53.270404) (xy 68.863074 -53.291334) (xy 68.892802 -53.337301) (xy 68.91565 -53.387048)
			(xy 68.931148 -53.439551) (xy 68.938978 -53.49373) (xy 68.938977 -53.548473) (xy 68.931148 -53.602652)
			(xy 68.915649 -53.655155) (xy 68.892801 -53.704901) (xy 68.863073 -53.750868) (xy 68.8465 -53.77053)
			(xy 69.210682 -53.77053) (xy 69.211191 -53.741612) (xy 69.219917 -53.684439) (xy 69.237175 -53.629239)
			(xy 69.262568 -53.577276) (xy 69.295515 -53.529743) (xy 69.33526 -53.487728) (xy 69.357748 -53.46954)
			(xy 69.366535 -53.461914) (xy 69.376728 -53.441027) (xy 69.377306 -53.429408) (xy 69.377306 -53.349652)
			(xy 69.376778 -53.338019) (xy 69.366581 -53.31711) (xy 69.357748 -53.30952) (xy 69.335263 -53.291331)
			(xy 69.295531 -53.249309) (xy 69.262593 -53.201773) (xy 69.237206 -53.149812) (xy 69.219949 -53.094615)
			(xy 69.211218 -53.037446) (xy 69.210682 -53.00853) (xy 69.211183 -52.981278) (xy 69.218936 -52.927329)
			(xy 69.234288 -52.875033) (xy 69.256926 -52.825453) (xy 69.28639 -52.779601) (xy 69.32208 -52.738408)
			(xy 69.363269 -52.702714) (xy 69.409118 -52.673245) (xy 69.458695 -52.650602) (xy 69.51099 -52.635244)
			(xy 69.564938 -52.627486) (xy 69.59219 -52.627022) (xy 69.618504 -52.627489) (xy 69.670633 -52.634723)
			(xy 69.721276 -52.649042) (xy 69.769475 -52.670174) (xy 69.814318 -52.697721) (xy 69.854958 -52.73116)
			(xy 69.873114 -52.750212) (xy 69.880627 -52.757624) (xy 69.899914 -52.766142) (xy 69.910452 -52.766722)
			(xy 69.985128 -52.766722) (xy 69.995674 -52.766161) (xy 70.014969 -52.757648) (xy 70.022466 -52.750212)
			(xy 70.040599 -52.731134) (xy 70.081233 -52.697678) (xy 70.126078 -52.670122) (xy 70.174283 -52.648987)
			(xy 70.224935 -52.634675) (xy 70.277072 -52.627457) (xy 70.30339 -52.627022) (xy 70.330644 -52.627465)
			(xy 70.384597 -52.635221) (xy 70.436897 -52.650577) (xy 70.486479 -52.673221) (xy 70.532334 -52.702691)
			(xy 70.573528 -52.738387) (xy 70.609221 -52.779582) (xy 70.638689 -52.825438) (xy 70.66133 -52.875022)
			(xy 70.676683 -52.927322) (xy 70.684437 -52.981276) (xy 70.684898 -53.00853) (xy 70.68441 -53.036196)
			(xy 70.682179 -53.051456) (xy 78.941166 -53.051456) (xy 78.945237 -52.995834) (xy 78.957363 -52.941397)
			(xy 78.977286 -52.889306) (xy 79.004582 -52.840671) (xy 79.038668 -52.796528) (xy 79.078817 -52.757819)
			(xy 79.124175 -52.725368) (xy 79.173775 -52.699867) (xy 79.226559 -52.68186) (xy 79.281402 -52.67173)
			(xy 79.337136 -52.669693) (xy 79.392573 -52.675793) (xy 79.44653 -52.689899) (xy 79.497859 -52.711711)
			(xy 79.545465 -52.740765) (xy 79.588333 -52.77644) (xy 79.62555 -52.817977) (xy 79.656323 -52.86449)
			(xy 79.679995 -52.914987) (xy 79.696063 -52.968394) (xy 79.704183 -53.02357) (xy 79.704692 -53.051456)
			(xy 79.704183 -53.079342) (xy 79.696063 -53.134518) (xy 79.679995 -53.187925) (xy 79.656323 -53.238422)
			(xy 79.62555 -53.284935) (xy 79.588333 -53.326472) (xy 79.545465 -53.362147) (xy 79.497859 -53.391201)
			(xy 79.44653 -53.413013) (xy 79.392573 -53.427119) (xy 79.337136 -53.433219) (xy 79.281402 -53.431182)
			(xy 79.226559 -53.421052) (xy 79.173775 -53.403045) (xy 79.124175 -53.377544) (xy 79.078817 -53.345093)
			(xy 79.038668 -53.306384) (xy 79.004582 -53.262241) (xy 78.977286 -53.213606) (xy 78.957363 -53.161515)
			(xy 78.945237 -53.107078) (xy 78.941166 -53.051456) (xy 70.682179 -53.051456) (xy 70.676407 -53.090946)
			(xy 70.660586 -53.143969) (xy 70.637279 -53.194153) (xy 70.606974 -53.240448) (xy 70.570305 -53.281885)
			(xy 70.52804 -53.317598) (xy 70.504812 -53.332634) (xy 70.495114 -53.339245) (xy 70.482682 -53.359125)
			(xy 70.480936 -53.370734) (xy 70.473062 -53.450744) (xy 70.472407 -53.462383) (xy 70.480503 -53.484222)
			(xy 70.488556 -53.492654) (xy 70.48881 -53.492908) (xy 70.507379 -53.511001) (xy 70.539958 -53.55133)
			(xy 70.566773 -53.595702) (xy 70.587328 -53.643298) (xy 70.601244 -53.69324) (xy 70.608264 -53.744608)
			(xy 70.608698 -53.77053) (xy 70.60825 -53.797782) (xy 70.600489 -53.851732) (xy 70.58513 -53.904028)
			(xy 70.562484 -53.953606) (xy 70.533014 -53.999457) (xy 70.497319 -54.040647) (xy 70.456125 -54.076338)
			(xy 70.410271 -54.105804) (xy 70.360691 -54.128444) (xy 70.308393 -54.143798) (xy 70.254442 -54.151553)
			(xy 70.22719 -54.152038) (xy 70.199819 -54.151593) (xy 70.145638 -54.143772) (xy 70.093134 -54.128279)
			(xy 70.043388 -54.105432) (xy 69.997422 -54.075702) (xy 69.976492 -54.058058) (xy 69.976238 -54.057804)
			(xy 69.969144 -54.052228) (xy 69.952233 -54.045975) (xy 69.943218 -54.045612) (xy 69.876162 -54.045612)
			(xy 69.867143 -54.045948) (xy 69.850226 -54.05221) (xy 69.843142 -54.057804) (xy 69.843142 -54.058058)
			(xy 69.842888 -54.058058) (xy 69.821928 -54.075663) (xy 69.775964 -54.105381) (xy 69.726223 -54.128224)
			(xy 69.673728 -54.143723) (xy 69.619557 -54.15156) (xy 69.59219 -54.152038) (xy 69.56494 -54.151532)
			(xy 69.510994 -54.143775) (xy 69.458702 -54.12842) (xy 69.409127 -54.10578) (xy 69.363278 -54.076315)
			(xy 69.322088 -54.040626) (xy 69.286397 -53.999438) (xy 69.25693 -53.953591) (xy 69.234287 -53.904017)
			(xy 69.21893 -53.851725) (xy 69.21117 -53.79778) (xy 69.210682 -53.77053) (xy 68.8465 -53.77053)
			(xy 68.84543 -53.7718) (xy 68.845176 -53.772054) (xy 68.8396 -53.779148) (xy 68.833348 -53.796059)
			(xy 68.832984 -53.805074) (xy 68.832984 -53.87213) (xy 68.83333 -53.881148) (xy 68.839585 -53.898065)
			(xy 68.845176 -53.90515) (xy 68.84543 -53.90515) (xy 68.84543 -53.905404) (xy 68.863074 -53.926334)
			(xy 68.892802 -53.972301) (xy 68.91565 -54.022048) (xy 68.931148 -54.074551) (xy 68.938978 -54.12873)
			(xy 68.938977 -54.183473) (xy 68.931148 -54.237652) (xy 68.915649 -54.290155) (xy 68.901856 -54.320186)
			(xy 71.130414 -54.320186) (xy 71.130868 -54.292815) (xy 71.138689 -54.238636) (xy 71.15418 -54.186132)
			(xy 71.177025 -54.136386) (xy 71.206752 -54.090419) (xy 71.224394 -54.069488) (xy 71.224648 -54.069234)
			(xy 71.230232 -54.062146) (xy 71.236479 -54.04523) (xy 71.23684 -54.036214) (xy 71.23684 -53.969158)
			(xy 71.236468 -53.960142) (xy 71.230232 -53.943225) (xy 71.224648 -53.936138) (xy 71.224394 -53.936138)
			(xy 71.224394 -53.935884) (xy 71.20678 -53.914932) (xy 71.177065 -53.868964) (xy 71.154224 -53.819222)
			(xy 71.138727 -53.766726) (xy 71.130892 -53.712554) (xy 71.130414 -53.685186) (xy 71.1309 -53.657935)
			(xy 71.138656 -53.603987) (xy 71.154011 -53.551692) (xy 71.176653 -53.502115) (xy 71.206119 -53.456265)
			(xy 71.24181 -53.415074) (xy 71.283001 -53.379383) (xy 71.328851 -53.349917) (xy 71.378428 -53.327275)
			(xy 71.430723 -53.31192) (xy 71.484671 -53.304164) (xy 71.539173 -53.304164) (xy 71.593121 -53.31192)
			(xy 71.645416 -53.327275) (xy 71.694993 -53.349917) (xy 71.740843 -53.379383) (xy 71.782034 -53.415074)
			(xy 71.817725 -53.456265) (xy 71.843618 -53.496556) (xy 84.133341 -53.496556) (xy 84.133341 -53.442044)
			(xy 84.141099 -53.388088) (xy 84.156458 -53.335786) (xy 84.179104 -53.286201) (xy 84.208576 -53.240345)
			(xy 84.244275 -53.199149) (xy 84.285474 -53.163454) (xy 84.331333 -53.133986) (xy 84.380919 -53.111345)
			(xy 84.433224 -53.095992) (xy 84.48718 -53.088238) (xy 84.514436 -53.087778) (xy 84.541808 -53.088204)
			(xy 84.595989 -53.096029) (xy 84.648494 -53.111526) (xy 84.69824 -53.134377) (xy 84.744204 -53.164112)
			(xy 84.765134 -53.181758) (xy 84.765388 -53.182012) (xy 84.772473 -53.187601) (xy 84.789391 -53.193846)
			(xy 84.798408 -53.194204) (xy 84.865464 -53.194204) (xy 84.874479 -53.193829) (xy 84.891396 -53.187594)
			(xy 84.898484 -53.182012) (xy 84.898484 -53.181758) (xy 84.898738 -53.181758) (xy 84.919677 -53.164128)
			(xy 84.965648 -53.134416) (xy 85.015394 -53.111579) (xy 85.067893 -53.096085) (xy 85.122067 -53.088254)
			(xy 85.149436 -53.087778) (xy 85.176685 -53.088295) (xy 85.230626 -53.096055) (xy 85.282915 -53.111413)
			(xy 85.332486 -53.134055) (xy 85.37833 -53.163521) (xy 85.419514 -53.199211) (xy 85.4552 -53.240399)
			(xy 85.484662 -53.286246) (xy 85.5073 -53.335819) (xy 85.522653 -53.388109) (xy 85.530408 -53.442051)
			(xy 85.530408 -53.496549) (xy 85.522653 -53.550491) (xy 85.5073 -53.602781) (xy 85.484662 -53.652354)
			(xy 85.4552 -53.698201) (xy 85.419514 -53.739389) (xy 85.37833 -53.775079) (xy 85.332486 -53.804545)
			(xy 85.282915 -53.827187) (xy 85.230626 -53.842545) (xy 85.176685 -53.850305) (xy 85.149436 -53.850794)
			(xy 85.122066 -53.850308) (xy 85.067888 -53.842495) (xy 85.015385 -53.827011) (xy 84.965638 -53.804174)
			(xy 84.91967 -53.774453) (xy 84.898738 -53.756814) (xy 84.898484 -53.75656) (xy 84.89141 -53.750956)
			(xy 84.874483 -53.744721) (xy 84.865464 -53.744368) (xy 84.798408 -53.744368) (xy 84.789392 -53.744736)
			(xy 84.772476 -53.750977) (xy 84.765388 -53.75656) (xy 84.765388 -53.756814) (xy 84.765134 -53.756814)
			(xy 84.744202 -53.774453) (xy 84.698229 -53.804164) (xy 84.648481 -53.827) (xy 84.595981 -53.842491)
			(xy 84.541805 -53.85032) (xy 84.514436 -53.850794) (xy 84.48718 -53.850362) (xy 84.433224 -53.842608)
			(xy 84.380919 -53.827255) (xy 84.331333 -53.804614) (xy 84.285474 -53.775146) (xy 84.244275 -53.739451)
			(xy 84.208576 -53.698255) (xy 84.179104 -53.652399) (xy 84.156458 -53.602814) (xy 84.141099 -53.550512)
			(xy 84.133341 -53.496556) (xy 71.843618 -53.496556) (xy 71.847191 -53.502115) (xy 71.869833 -53.551692)
			(xy 71.885188 -53.603987) (xy 71.892944 -53.657935) (xy 71.89343 -53.685186) (xy 71.892973 -53.712557)
			(xy 71.885155 -53.766737) (xy 71.869665 -53.819241) (xy 71.846821 -53.868988) (xy 71.817093 -53.914953)
			(xy 71.79945 -53.935884) (xy 71.799196 -53.936138) (xy 71.793629 -53.943238) (xy 71.787371 -53.960144)
			(xy 71.787004 -53.969158) (xy 71.787004 -54.036214) (xy 71.787354 -54.045232) (xy 71.793606 -54.062149)
			(xy 71.799196 -54.069234) (xy 71.79945 -54.069234) (xy 71.79945 -54.069488) (xy 71.817089 -54.09042)
			(xy 71.846803 -54.136392) (xy 71.869639 -54.18614) (xy 71.88513 -54.238641) (xy 71.892957 -54.292817)
			(xy 71.89343 -54.320186) (xy 71.892944 -54.347437) (xy 71.885188 -54.401385) (xy 71.869833 -54.45368)
			(xy 71.847191 -54.503257) (xy 71.817725 -54.549107) (xy 71.782034 -54.590298) (xy 71.740843 -54.625989)
			(xy 71.694993 -54.655455) (xy 71.645416 -54.678097) (xy 71.593121 -54.693452) (xy 71.539173 -54.701208)
			(xy 71.484671 -54.701208) (xy 71.430723 -54.693452) (xy 71.378428 -54.678097) (xy 71.328851 -54.655455)
			(xy 71.283001 -54.625989) (xy 71.24181 -54.590298) (xy 71.206119 -54.549107) (xy 71.176653 -54.503257)
			(xy 71.154011 -54.45368) (xy 71.138656 -54.401385) (xy 71.1309 -54.347437) (xy 71.130414 -54.320186)
			(xy 68.901856 -54.320186) (xy 68.892801 -54.339901) (xy 68.863073 -54.385868) (xy 68.84543 -54.4068)
			(xy 68.845176 -54.407054) (xy 68.8396 -54.414148) (xy 68.833348 -54.431059) (xy 68.832984 -54.440074)
			(xy 68.832984 -54.50713) (xy 68.83333 -54.516148) (xy 68.839585 -54.533065) (xy 68.845176 -54.54015)
			(xy 68.84543 -54.54015) (xy 68.84543 -54.540404) (xy 68.863089 -54.56132) (xy 68.892797 -54.607298)
			(xy 68.915629 -54.657049) (xy 68.931115 -54.709553) (xy 68.938938 -54.763732) (xy 68.939055 -54.770528)
			(xy 72.070976 -54.770528) (xy 72.07144 -54.743157) (xy 72.079255 -54.688978) (xy 72.094744 -54.636474)
			(xy 72.117587 -54.586727) (xy 72.147313 -54.540761) (xy 72.164956 -54.51983) (xy 72.16521 -54.519576)
			(xy 72.170814 -54.512501) (xy 72.17705 -54.495575) (xy 72.177402 -54.486556) (xy 72.177402 -54.4195)
			(xy 72.177045 -54.410483) (xy 72.170797 -54.393566) (xy 72.16521 -54.38648) (xy 72.164956 -54.38648)
			(xy 72.164956 -54.386226) (xy 72.147308 -54.365301) (xy 72.117599 -54.319326) (xy 72.094766 -54.269576)
			(xy 72.079276 -54.217074) (xy 72.071449 -54.162898) (xy 72.070976 -54.135528) (xy 72.071462 -54.108277)
			(xy 72.079218 -54.054329) (xy 72.094573 -54.002034) (xy 72.117215 -53.952457) (xy 72.146681 -53.906607)
			(xy 72.182372 -53.865416) (xy 72.223563 -53.829725) (xy 72.269413 -53.800259) (xy 72.31899 -53.777617)
			(xy 72.371285 -53.762262) (xy 72.425233 -53.754506) (xy 72.479735 -53.754506) (xy 72.533683 -53.762262)
			(xy 72.585978 -53.777617) (xy 72.635555 -53.800259) (xy 72.681405 -53.829725) (xy 72.722596 -53.865416)
			(xy 72.758287 -53.906607) (xy 72.787753 -53.952457) (xy 72.792828 -53.96357) (xy 76.772006 -53.96357)
			(xy 76.776077 -53.907948) (xy 76.788203 -53.853511) (xy 76.808126 -53.80142) (xy 76.835422 -53.752785)
			(xy 76.869508 -53.708642) (xy 76.909657 -53.669933) (xy 76.955015 -53.637482) (xy 77.004615 -53.611981)
			(xy 77.057399 -53.593974) (xy 77.112242 -53.583844) (xy 77.167976 -53.581807) (xy 77.223413 -53.587907)
			(xy 77.27737 -53.602013) (xy 77.328699 -53.623825) (xy 77.376305 -53.652879) (xy 77.419173 -53.688554)
			(xy 77.45639 -53.730091) (xy 77.487163 -53.776604) (xy 77.510835 -53.827101) (xy 77.526903 -53.880508)
			(xy 77.535023 -53.935684) (xy 77.535532 -53.96357) (xy 77.535023 -53.991456) (xy 77.526903 -54.046632)
			(xy 77.510835 -54.100039) (xy 77.487163 -54.150536) (xy 77.45639 -54.197049) (xy 77.419173 -54.238586)
			(xy 77.376305 -54.274261) (xy 77.328699 -54.303315) (xy 77.27737 -54.325127) (xy 77.223413 -54.339233)
			(xy 77.167976 -54.345333) (xy 77.112242 -54.343296) (xy 77.057399 -54.333166) (xy 77.004615 -54.315159)
			(xy 76.955015 -54.289658) (xy 76.909657 -54.257207) (xy 76.869508 -54.218498) (xy 76.835422 -54.174355)
			(xy 76.808126 -54.12572) (xy 76.788203 -54.073629) (xy 76.776077 -54.019192) (xy 76.772006 -53.96357)
			(xy 72.792828 -53.96357) (xy 72.810395 -54.002034) (xy 72.82575 -54.054329) (xy 72.833506 -54.108277)
			(xy 72.833992 -54.135528) (xy 72.833544 -54.162899) (xy 72.825722 -54.217079) (xy 72.810229 -54.269582)
			(xy 72.787383 -54.319329) (xy 72.757655 -54.365295) (xy 72.740012 -54.386226) (xy 72.739758 -54.38648)
			(xy 72.734169 -54.393564) (xy 72.727925 -54.410483) (xy 72.727566 -54.4195) (xy 72.727566 -54.486556)
			(xy 72.727951 -54.49557) (xy 72.73418 -54.512487) (xy 72.739758 -54.519576) (xy 72.740012 -54.519576)
			(xy 72.740012 -54.51983) (xy 72.757634 -54.540776) (xy 72.787348 -54.586745) (xy 72.810187 -54.636489)
			(xy 72.825682 -54.688987) (xy 72.833515 -54.74316) (xy 72.833992 -54.770528) (xy 72.833506 -54.797779)
			(xy 72.82575 -54.851727) (xy 72.810395 -54.904022) (xy 72.787753 -54.953599) (xy 72.764967 -54.989055)
			(xy 81.900945 -54.989055) (xy 81.900945 -54.934545) (xy 81.908703 -54.88059) (xy 81.924061 -54.828288)
			(xy 81.946706 -54.778705) (xy 81.976178 -54.732849) (xy 82.011876 -54.691654) (xy 82.053073 -54.65596)
			(xy 82.098931 -54.626492) (xy 82.148516 -54.60385) (xy 82.200819 -54.588497) (xy 82.254775 -54.580743)
			(xy 82.28203 -54.580282) (xy 82.310122 -54.580753) (xy 82.365701 -54.588985) (xy 82.41947 -54.60528)
			(xy 82.470268 -54.629286) (xy 82.516994 -54.660485) (xy 82.558639 -54.6982) (xy 82.5943 -54.741616)
			(xy 82.609182 -54.765448) (xy 82.614516 -54.774338) (xy 82.631534 -54.78653) (xy 82.724752 -54.80685)
			(xy 82.745326 -54.802532) (xy 82.753962 -54.79669) (xy 82.778034 -54.780703) (xy 82.829963 -54.755357)
			(xy 82.885118 -54.738128) (xy 82.94224 -54.729409) (xy 82.971132 -54.728872) (xy 82.998383 -54.729348)
			(xy 83.05233 -54.737108) (xy 83.104624 -54.752467) (xy 83.1542 -54.77511) (xy 83.200049 -54.804578)
			(xy 83.241238 -54.84027) (xy 83.27693 -54.88146) (xy 83.306396 -54.927311) (xy 83.329038 -54.976887)
			(xy 83.344394 -55.029182) (xy 83.352153 -55.083129) (xy 83.35264 -55.11038) (xy 83.352177 -55.137751)
			(xy 83.344361 -55.19193) (xy 83.328872 -55.244434) (xy 83.306029 -55.294181) (xy 83.276302 -55.340147)
			(xy 83.25866 -55.361078) (xy 83.258406 -55.361332) (xy 83.252842 -55.368434) (xy 83.246582 -55.385339)
			(xy 83.246214 -55.394352) (xy 83.246214 -55.461408) (xy 83.246564 -55.470426) (xy 83.252816 -55.487343)
			(xy 83.258406 -55.494428) (xy 83.25866 -55.494428) (xy 83.25866 -55.494682) (xy 83.276282 -55.51563)
			(xy 83.306008 -55.561595) (xy 83.328856 -55.611339) (xy 83.344354 -55.663839) (xy 83.352185 -55.718015)
			(xy 83.352187 -55.772755) (xy 83.34436 -55.826932) (xy 83.328866 -55.879433) (xy 83.306023 -55.929178)
			(xy 83.2763 -55.975146) (xy 83.25866 -55.996078) (xy 83.258406 -55.996332) (xy 83.252842 -56.003434)
			(xy 83.246582 -56.020339) (xy 83.246214 -56.029352) (xy 83.246214 -56.096408) (xy 83.246564 -56.105426)
			(xy 83.252816 -56.122343) (xy 83.258406 -56.129428) (xy 83.25866 -56.129428) (xy 83.25866 -56.129682)
			(xy 83.276298 -56.150615) (xy 83.306011 -56.196587) (xy 83.328848 -56.246334) (xy 83.344339 -56.298835)
			(xy 83.352167 -56.353011) (xy 83.35264 -56.38038) (xy 83.352154 -56.407631) (xy 83.344398 -56.461579)
			(xy 83.329043 -56.513874) (xy 83.306401 -56.563451) (xy 83.276935 -56.609301) (xy 83.241244 -56.650492)
			(xy 83.200053 -56.686183) (xy 83.154203 -56.715649) (xy 83.104626 -56.738291) (xy 83.052331 -56.753646)
			(xy 82.998383 -56.761402) (xy 82.943881 -56.761402) (xy 82.889933 -56.753646) (xy 82.837638 -56.738291)
			(xy 82.788061 -56.715649) (xy 82.742211 -56.686183) (xy 82.70102 -56.650492) (xy 82.665329 -56.609301)
			(xy 82.635863 -56.563451) (xy 82.613221 -56.513874) (xy 82.597866 -56.461579) (xy 82.59011 -56.407631)
			(xy 82.589624 -56.38038) (xy 82.590072 -56.353009) (xy 82.597894 -56.298829) (xy 82.613387 -56.246325)
			(xy 82.636232 -56.196579) (xy 82.665961 -56.150613) (xy 82.683604 -56.129682) (xy 82.683858 -56.129428)
			(xy 82.689446 -56.122343) (xy 82.69569 -56.105425) (xy 82.69605 -56.096408) (xy 82.69605 -56.029352)
			(xy 82.695679 -56.020336) (xy 82.689442 -56.003419) (xy 82.683858 -55.996332) (xy 82.683604 -55.996332)
			(xy 82.683604 -55.996078) (xy 82.665945 -55.975161) (xy 82.636222 -55.92919) (xy 82.61338 -55.879441)
			(xy 82.597886 -55.826936) (xy 82.59006 -55.772756) (xy 82.590062 -55.718014) (xy 82.597892 -55.663834)
			(xy 82.61339 -55.611331) (xy 82.636237 -55.561584) (xy 82.665963 -55.515615) (xy 82.683604 -55.494682)
			(xy 82.683858 -55.494428) (xy 82.689446 -55.487343) (xy 82.69569 -55.470425) (xy 82.69605 -55.461408)
			(xy 82.69605 -55.394352) (xy 82.695679 -55.385336) (xy 82.689442 -55.368419) (xy 82.683858 -55.361332)
			(xy 82.683604 -55.360824) (xy 82.672661 -55.348089) (xy 82.652819 -55.320998) (xy 82.64398 -55.306722)
			(xy 82.638646 -55.297832) (xy 82.621628 -55.28564) (xy 82.52841 -55.26532) (xy 82.507836 -55.269638)
			(xy 82.4992 -55.27548) (xy 82.475136 -55.29148) (xy 82.423205 -55.316823) (xy 82.368047 -55.334049)
			(xy 82.310923 -55.342764) (xy 82.28203 -55.343298) (xy 82.254775 -55.342857) (xy 82.200819 -55.335103)
			(xy 82.148516 -55.31975) (xy 82.098931 -55.297108) (xy 82.053073 -55.26764) (xy 82.011876 -55.231946)
			(xy 81.976178 -55.190751) (xy 81.946706 -55.144895) (xy 81.924061 -55.095312) (xy 81.908703 -55.04301)
			(xy 81.900945 -54.989055) (xy 72.764967 -54.989055) (xy 72.758287 -54.999449) (xy 72.722596 -55.04064)
			(xy 72.681405 -55.076331) (xy 72.635555 -55.105797) (xy 72.585978 -55.128439) (xy 72.533683 -55.143794)
			(xy 72.479735 -55.15155) (xy 72.425233 -55.15155) (xy 72.371285 -55.143794) (xy 72.31899 -55.128439)
			(xy 72.269413 -55.105797) (xy 72.223563 -55.076331) (xy 72.182372 -55.04064) (xy 72.146681 -54.999449)
			(xy 72.117215 -54.953599) (xy 72.094573 -54.904022) (xy 72.079218 -54.851727) (xy 72.071462 -54.797779)
			(xy 72.070976 -54.770528) (xy 68.939055 -54.770528) (xy 68.93941 -54.791102) (xy 68.938924 -54.818353)
			(xy 68.931168 -54.872301) (xy 68.915813 -54.924596) (xy 68.893171 -54.974173) (xy 68.863705 -55.020023)
			(xy 68.828014 -55.061214) (xy 68.786823 -55.096905) (xy 68.740973 -55.126371) (xy 68.691396 -55.149013)
			(xy 68.639101 -55.164368) (xy 68.585153 -55.172124) (xy 68.530651 -55.172124) (xy 68.476703 -55.164368)
			(xy 68.424408 -55.149013) (xy 68.374831 -55.126371) (xy 68.328981 -55.096905) (xy 68.28779 -55.061214)
			(xy 68.252099 -55.020023) (xy 68.222633 -54.974173) (xy 68.199991 -54.924596) (xy 68.184636 -54.872301)
			(xy 68.17688 -54.818353) (xy 68.176394 -54.791102) (xy 66.278439 -54.791102) (xy 66.275243 -54.813176)
			(xy 66.259676 -54.865809) (xy 66.236728 -54.915669) (xy 66.206873 -54.961726) (xy 66.170728 -55.003031)
			(xy 66.129037 -55.03873) (xy 66.082662 -55.068088) (xy 66.032558 -55.090499) (xy 65.979761 -55.1055)
			(xy 65.952624 -55.109618) (xy 65.946528 -55.11038) (xy 65.942718 -55.110888) (xy 65.926208 -55.120286)
			(xy 65.920112 -55.127652) (xy 65.914368 -55.135274) (xy 65.908485 -55.153416) (xy 65.908682 -55.162958)
			(xy 65.943226 -55.721758) (xy 65.943257 -55.722266) (xy 77.83398 -55.722266) (xy 77.838051 -55.666644)
			(xy 77.850177 -55.612207) (xy 77.8701 -55.560116) (xy 77.897396 -55.511481) (xy 77.931482 -55.467338)
			(xy 77.971631 -55.428629) (xy 78.016989 -55.396178) (xy 78.066589 -55.370677) (xy 78.119373 -55.35267)
			(xy 78.174216 -55.34254) (xy 78.22995 -55.340503) (xy 78.285387 -55.346603) (xy 78.339344 -55.360709)
			(xy 78.390673 -55.382521) (xy 78.438279 -55.411575) (xy 78.44943 -55.420855) (xy 80.224545 -55.420855)
			(xy 80.224545 -55.366345) (xy 80.232303 -55.31239) (xy 80.247661 -55.260088) (xy 80.270306 -55.210505)
			(xy 80.299778 -55.164649) (xy 80.335476 -55.123454) (xy 80.376673 -55.08776) (xy 80.422531 -55.058292)
			(xy 80.472116 -55.03565) (xy 80.524419 -55.020297) (xy 80.578375 -55.012543) (xy 80.60563 -55.012082)
			(xy 80.631944 -55.012535) (xy 80.684073 -55.019774) (xy 80.734716 -55.034096) (xy 80.782915 -55.055231)
			(xy 80.827758 -55.082779) (xy 80.868397 -55.11622) (xy 80.886554 -55.135272) (xy 80.894057 -55.142695)
			(xy 80.913351 -55.151208) (xy 80.923892 -55.151782) (xy 80.998568 -55.151782) (xy 81.009118 -55.151255)
			(xy 81.028414 -55.142719) (xy 81.035906 -55.135272) (xy 81.05406 -55.116215) (xy 81.094691 -55.082759)
			(xy 81.139532 -55.055201) (xy 81.187733 -55.034063) (xy 81.23838 -55.019746) (xy 81.290514 -55.012521)
			(xy 81.31683 -55.012082) (xy 81.344079 -55.01259) (xy 81.398022 -55.02035) (xy 81.450312 -55.035707)
			(xy 81.499884 -55.05835) (xy 81.545729 -55.087816) (xy 81.586915 -55.123506) (xy 81.622602 -55.164695)
			(xy 81.652065 -55.210542) (xy 81.674703 -55.260116) (xy 81.690056 -55.312407) (xy 81.697812 -55.366351)
			(xy 81.697812 -55.420849) (xy 81.690056 -55.474793) (xy 81.674703 -55.527084) (xy 81.652065 -55.576658)
			(xy 81.622602 -55.622505) (xy 81.586915 -55.663694) (xy 81.545729 -55.699384) (xy 81.499884 -55.72885)
			(xy 81.450312 -55.751493) (xy 81.398022 -55.76685) (xy 81.344079 -55.77461) (xy 81.31683 -55.775098)
			(xy 81.290514 -55.774678) (xy 81.238384 -55.767433) (xy 81.18774 -55.753105) (xy 81.139541 -55.731964)
			(xy 81.094699 -55.704409) (xy 81.054061 -55.670963) (xy 81.035906 -55.651908) (xy 81.028383 -55.644508)
			(xy 81.009104 -55.635983) (xy 80.998568 -55.635398) (xy 80.923892 -55.635398) (xy 80.91334 -55.63591)
			(xy 80.894045 -55.644457) (xy 80.886554 -55.651908) (xy 80.868415 -55.67098) (xy 80.827782 -55.704436)
			(xy 80.782938 -55.731992) (xy 80.734734 -55.753128) (xy 80.684084 -55.767441) (xy 80.631947 -55.774662)
			(xy 80.60563 -55.775098) (xy 80.578375 -55.774657) (xy 80.524419 -55.766903) (xy 80.472116 -55.75155)
			(xy 80.422531 -55.728908) (xy 80.376673 -55.69944) (xy 80.335476 -55.663746) (xy 80.299778 -55.622551)
			(xy 80.270306 -55.576695) (xy 80.247661 -55.527112) (xy 80.232303 -55.47481) (xy 80.224545 -55.420855)
			(xy 78.44943 -55.420855) (xy 78.481147 -55.44725) (xy 78.518364 -55.488787) (xy 78.549137 -55.5353)
			(xy 78.572809 -55.585797) (xy 78.588877 -55.639204) (xy 78.596997 -55.69438) (xy 78.597506 -55.722266)
			(xy 78.596997 -55.750152) (xy 78.588877 -55.805328) (xy 78.572809 -55.858735) (xy 78.549137 -55.909232)
			(xy 78.518364 -55.955745) (xy 78.481147 -55.997282) (xy 78.438279 -56.032957) (xy 78.390673 -56.062011)
			(xy 78.339344 -56.083823) (xy 78.285387 -56.097929) (xy 78.22995 -56.104029) (xy 78.174216 -56.101992)
			(xy 78.119373 -56.091862) (xy 78.066589 -56.073855) (xy 78.016989 -56.048354) (xy 77.971631 -56.015903)
			(xy 77.931482 -55.977194) (xy 77.897396 -55.933051) (xy 77.8701 -55.884416) (xy 77.850177 -55.832325)
			(xy 77.838051 -55.777888) (xy 77.83398 -55.722266) (xy 65.943257 -55.722266) (xy 65.968626 -56.133746)
			(xy 65.986152 -56.416448) (xy 65.987082 -56.423837) (xy 65.992632 -56.437649) (xy 65.997074 -56.443626)
			(xy 66.001646 -56.449214) (xy 66.022982 -56.464454) (xy 66.02984 -56.466994) (xy 66.057292 -56.477323)
			(xy 66.108898 -56.505192) (xy 66.155634 -56.540628) (xy 66.196398 -56.582797) (xy 66.230231 -56.630706)
			(xy 66.256336 -56.683226) (xy 66.274099 -56.739123) (xy 66.283102 -56.797079) (xy 66.283586 -56.826404)
			(xy 66.283586 -56.832754) (xy 66.283169 -56.847824) (xy 66.280245 -56.877831) (xy 66.277744 -56.892698)
			(xy 66.271651 -56.923739) (xy 66.250568 -56.983377) (xy 66.239747 -57.002934) (xy 73.56348 -57.002934)
			(xy 73.564003 -56.974843) (xy 73.572225 -56.919268) (xy 73.588511 -56.865499) (xy 73.612509 -56.814702)
			(xy 73.6437 -56.767975) (xy 73.681408 -56.726329) (xy 73.724817 -56.690665) (xy 73.748646 -56.675782)
			(xy 73.757536 -56.670448) (xy 73.769728 -56.65343) (xy 73.790048 -56.560212) (xy 73.78573 -56.539638)
			(xy 73.779888 -56.531002) (xy 73.763885 -56.50694) (xy 73.738544 -56.455008) (xy 73.721319 -56.399849)
			(xy 73.712604 -56.342725) (xy 73.71207 -56.313832) (xy 73.712585 -56.286581) (xy 73.720337 -56.232633)
			(xy 73.735688 -56.180337) (xy 73.758325 -56.130759) (xy 73.787788 -56.084907) (xy 73.823476 -56.043714)
			(xy 73.864663 -56.00802) (xy 73.910511 -55.978551) (xy 73.960087 -55.955907) (xy 74.01238 -55.940549)
			(xy 74.066327 -55.932789) (xy 74.093578 -55.932324) (xy 74.120948 -55.932797) (xy 74.175127 -55.940612)
			(xy 74.22763 -55.956099) (xy 74.277377 -55.97894) (xy 74.323344 -56.008663) (xy 74.344276 -56.026304)
			(xy 74.34453 -56.026558) (xy 74.351627 -56.032128) (xy 74.368536 -56.038383) (xy 74.37755 -56.03875)
			(xy 74.444606 -56.03875) (xy 74.453624 -56.038406) (xy 74.470542 -56.032151) (xy 74.477626 -56.026558)
			(xy 74.477626 -56.026304) (xy 74.47788 -56.026304) (xy 74.498813 -56.008663) (xy 74.544781 -55.978939)
			(xy 74.594527 -55.956093) (xy 74.647029 -55.940597) (xy 74.701207 -55.932768) (xy 74.755949 -55.932768)
			(xy 74.810127 -55.940597) (xy 74.862629 -55.956093) (xy 74.912375 -55.978939) (xy 74.958343 -56.008663)
			(xy 74.979276 -56.026304) (xy 74.97953 -56.026558) (xy 74.986627 -56.032128) (xy 75.003536 -56.038383)
			(xy 75.01255 -56.03875) (xy 75.079606 -56.03875) (xy 75.088624 -56.038406) (xy 75.105542 -56.032151)
			(xy 75.112626 -56.026558) (xy 75.112626 -56.026304) (xy 75.11288 -56.026304) (xy 75.133809 -56.008661)
			(xy 75.179783 -55.97895) (xy 75.229531 -55.956115) (xy 75.282032 -55.940624) (xy 75.336209 -55.932797)
			(xy 75.363578 -55.932324) (xy 75.390834 -55.932721) (xy 75.444792 -55.940477) (xy 75.497097 -55.955832)
			(xy 75.546684 -55.978475) (xy 75.592544 -56.007945) (xy 75.633743 -56.043642) (xy 75.669442 -56.084838)
			(xy 75.698914 -56.130697) (xy 75.72156 -56.180282) (xy 75.736919 -56.232586) (xy 75.744677 -56.286544)
			(xy 75.744677 -56.297068) (xy 76.08646 -56.297068) (xy 76.090531 -56.241446) (xy 76.102657 -56.187009)
			(xy 76.12258 -56.134918) (xy 76.149876 -56.086283) (xy 76.183962 -56.04214) (xy 76.224111 -56.003431)
			(xy 76.269469 -55.97098) (xy 76.319069 -55.945479) (xy 76.371853 -55.927472) (xy 76.426696 -55.917342)
			(xy 76.48243 -55.915305) (xy 76.537867 -55.921405) (xy 76.591824 -55.935511) (xy 76.643153 -55.957323)
			(xy 76.690759 -55.986377) (xy 76.733627 -56.022052) (xy 76.770844 -56.063589) (xy 76.801617 -56.110102)
			(xy 76.825289 -56.160599) (xy 76.841357 -56.214006) (xy 76.849477 -56.269182) (xy 76.849986 -56.297068)
			(xy 76.849477 -56.324954) (xy 76.841357 -56.38013) (xy 76.825289 -56.433537) (xy 76.801617 -56.484034)
			(xy 76.770844 -56.530547) (xy 76.733627 -56.572084) (xy 76.690759 -56.607759) (xy 76.643153 -56.636813)
			(xy 76.591824 -56.658625) (xy 76.537867 -56.672731) (xy 76.48243 -56.678831) (xy 76.426696 -56.676794)
			(xy 76.371853 -56.666664) (xy 76.319069 -56.648657) (xy 76.269469 -56.623156) (xy 76.224111 -56.590705)
			(xy 76.183962 -56.551996) (xy 76.149876 -56.507853) (xy 76.12258 -56.459218) (xy 76.102657 -56.407127)
			(xy 76.090531 -56.35269) (xy 76.08646 -56.297068) (xy 75.744677 -56.297068) (xy 75.744677 -56.341056)
			(xy 75.736919 -56.395014) (xy 75.72156 -56.447318) (xy 75.698914 -56.496903) (xy 75.669442 -56.542762)
			(xy 75.633743 -56.583958) (xy 75.592544 -56.619655) (xy 75.546684 -56.649125) (xy 75.497097 -56.671768)
			(xy 75.444792 -56.687123) (xy 75.390834 -56.694879) (xy 75.363578 -56.69534) (xy 75.336207 -56.694901)
			(xy 75.282026 -56.687079) (xy 75.229522 -56.671585) (xy 75.179775 -56.648736) (xy 75.13381 -56.619005)
			(xy 75.11288 -56.60136) (xy 75.112626 -56.601106) (xy 75.105536 -56.595525) (xy 75.088622 -56.589275)
			(xy 75.079606 -56.588914) (xy 75.01255 -56.588914) (xy 75.003535 -56.589292) (xy 74.986618 -56.595525)
			(xy 74.97953 -56.601106) (xy 74.97953 -56.60136) (xy 74.979276 -56.60136) (xy 74.958343 -56.619001)
			(xy 74.912375 -56.648725) (xy 74.862629 -56.671571) (xy 74.810127 -56.687067) (xy 74.755949 -56.694896)
			(xy 74.701207 -56.694896) (xy 74.647029 -56.687067) (xy 74.594527 -56.671571) (xy 74.544781 -56.648725)
			(xy 74.498813 -56.619001) (xy 74.47788 -56.60136) (xy 74.477626 -56.601106) (xy 74.470536 -56.595525)
			(xy 74.453622 -56.589275) (xy 74.444606 -56.588914) (xy 74.37755 -56.588914) (xy 74.368535 -56.589292)
			(xy 74.351618 -56.595525) (xy 74.34453 -56.601106) (xy 74.344022 -56.60136) (xy 74.33129 -56.612307)
			(xy 74.304197 -56.632146) (xy 74.28992 -56.640984) (xy 74.28103 -56.646318) (xy 74.268838 -56.663336)
			(xy 74.248518 -56.756554) (xy 74.252836 -56.777128) (xy 74.258678 -56.785764) (xy 74.274662 -56.809838)
			(xy 74.300009 -56.861765) (xy 74.317239 -56.91692) (xy 74.325959 -56.974042) (xy 74.326496 -57.002934)
			(xy 74.32601 -57.030185) (xy 74.318254 -57.084133) (xy 74.302899 -57.136428) (xy 74.280257 -57.186005)
			(xy 74.250791 -57.231855) (xy 74.2151 -57.273046) (xy 74.173909 -57.308737) (xy 74.128059 -57.338203)
			(xy 74.078482 -57.360845) (xy 74.026187 -57.3762) (xy 73.972239 -57.383956) (xy 73.917737 -57.383956)
			(xy 73.863789 -57.3762) (xy 73.811494 -57.360845) (xy 73.761917 -57.338203) (xy 73.716067 -57.308737)
			(xy 73.674876 -57.273046) (xy 73.639185 -57.231855) (xy 73.609719 -57.186005) (xy 73.587077 -57.136428)
			(xy 73.571722 -57.084133) (xy 73.563966 -57.030185) (xy 73.56348 -57.002934) (xy 66.239747 -57.002934)
			(xy 66.219945 -57.038725) (xy 66.200782 -57.063894) (xy 66.195448 -57.070498) (xy 66.192146 -57.079642)
			(xy 66.190622 -57.085484) (xy 66.189606 -57.09539) (xy 66.189606 -57.128156) (xy 66.17843 -57.128156)
			(xy 66.17843 -57.178956) (xy 66.178764 -57.18756) (xy 66.184476 -57.203791) (xy 66.189606 -57.210706)
			(xy 66.190876 -57.21223) (xy 66.208273 -57.233105) (xy 66.237596 -57.278854) (xy 66.260129 -57.328301)
			(xy 66.275414 -57.380447) (xy 66.283141 -57.434234) (xy 66.283586 -57.461404) (xy 66.283204 -57.48528)
			(xy 82.605878 -57.48528) (xy 82.609949 -57.429658) (xy 82.622075 -57.375221) (xy 82.641998 -57.32313)
			(xy 82.669294 -57.274495) (xy 82.70338 -57.230352) (xy 82.743529 -57.191643) (xy 82.788887 -57.159192)
			(xy 82.838487 -57.133691) (xy 82.891271 -57.115684) (xy 82.946114 -57.105554) (xy 83.001848 -57.103517)
			(xy 83.057285 -57.109617) (xy 83.111242 -57.123723) (xy 83.162571 -57.145535) (xy 83.210177 -57.174589)
			(xy 83.253045 -57.210264) (xy 83.290262 -57.251801) (xy 83.321035 -57.298314) (xy 83.344707 -57.348811)
			(xy 83.360775 -57.402218) (xy 83.368895 -57.457394) (xy 83.369404 -57.48528) (xy 83.368895 -57.513166)
			(xy 83.360775 -57.568342) (xy 83.344707 -57.621749) (xy 83.321035 -57.672246) (xy 83.290262 -57.718759)
			(xy 83.253045 -57.760296) (xy 83.210177 -57.795971) (xy 83.162571 -57.825025) (xy 83.111242 -57.846837)
			(xy 83.057285 -57.860943) (xy 83.001848 -57.867043) (xy 82.946114 -57.865006) (xy 82.891271 -57.854876)
			(xy 82.838487 -57.836869) (xy 82.788887 -57.811368) (xy 82.743529 -57.778917) (xy 82.70338 -57.740208)
			(xy 82.669294 -57.696065) (xy 82.641998 -57.64743) (xy 82.622075 -57.595339) (xy 82.609949 -57.540902)
			(xy 82.605878 -57.48528) (xy 66.283204 -57.48528) (xy 66.283176 -57.487021) (xy 66.276323 -57.537795)
			(xy 66.262726 -57.587192) (xy 66.242633 -57.634322) (xy 66.216404 -57.678333) (xy 66.200782 -57.69864)
			(xy 66.200528 -57.698894) (xy 66.199004 -57.700672) (xy 66.194703 -57.7072) (xy 66.189911 -57.722071)
			(xy 66.189606 -57.729882) (xy 66.189606 -57.763156) (xy 66.17843 -57.763156) (xy 66.17843 -57.813956)
			(xy 66.178764 -57.82256) (xy 66.184476 -57.838791) (xy 66.189606 -57.845706) (xy 66.190876 -57.84723)
			(xy 66.208273 -57.868105) (xy 66.237596 -57.913854) (xy 66.260129 -57.963301) (xy 66.275414 -58.015447)
			(xy 66.283141 -58.069234) (xy 66.283586 -58.096404) (xy 66.283176 -58.122021) (xy 66.276323 -58.172795)
			(xy 66.262726 -58.222192) (xy 66.242633 -58.269322) (xy 66.216404 -58.313333) (xy 66.200782 -58.33364)
			(xy 66.200528 -58.333894) (xy 66.199004 -58.335672) (xy 66.194703 -58.3422) (xy 66.189911 -58.357071)
			(xy 66.189606 -58.364882) (xy 66.189606 -58.398156) (xy 66.17843 -58.398156) (xy 66.17843 -58.448956)
			(xy 66.178764 -58.45756) (xy 66.184476 -58.473791) (xy 66.189606 -58.480706) (xy 66.190876 -58.48223)
			(xy 66.208273 -58.503105) (xy 66.237596 -58.548854) (xy 66.260129 -58.598301) (xy 66.275414 -58.650447)
			(xy 66.279564 -58.679334) (xy 73.99528 -58.679334) (xy 73.99571 -58.653019) (xy 74.002953 -58.600889)
			(xy 74.01728 -58.550246) (xy 74.03842 -58.502047) (xy 74.065972 -58.457204) (xy 74.099416 -58.416566)
			(xy 74.11847 -58.39841) (xy 74.125865 -58.390883) (xy 74.134394 -58.371607) (xy 74.13498 -58.361072)
			(xy 74.13498 -58.286396) (xy 74.134472 -58.275844) (xy 74.125923 -58.256548) (xy 74.11847 -58.249058)
			(xy 74.099395 -58.230922) (xy 74.065941 -58.190287) (xy 74.038385 -58.145443) (xy 74.01725 -58.097238)
			(xy 74.002937 -58.046588) (xy 73.995716 -57.994451) (xy 73.99528 -57.968134) (xy 73.995766 -57.940883)
			(xy 74.003522 -57.886935) (xy 74.018877 -57.83464) (xy 74.041519 -57.785063) (xy 74.070985 -57.739213)
			(xy 74.106676 -57.698022) (xy 74.147867 -57.662331) (xy 74.193717 -57.632865) (xy 74.243294 -57.610223)
			(xy 74.295589 -57.594868) (xy 74.349537 -57.587112) (xy 74.404039 -57.587112) (xy 74.457987 -57.594868)
			(xy 74.510282 -57.610223) (xy 74.559859 -57.632865) (xy 74.605709 -57.662331) (xy 74.6469 -57.698022)
			(xy 74.682591 -57.739213) (xy 74.712057 -57.785063) (xy 74.734699 -57.83464) (xy 74.750054 -57.886935)
			(xy 74.75781 -57.940883) (xy 74.758296 -57.968134) (xy 74.757853 -57.994449) (xy 74.750613 -58.046578)
			(xy 74.743345 -58.072274) (xy 77.993492 -58.072274) (xy 77.997563 -58.016652) (xy 78.009689 -57.962215)
			(xy 78.029612 -57.910124) (xy 78.056908 -57.861489) (xy 78.090994 -57.817346) (xy 78.131143 -57.778637)
			(xy 78.176501 -57.746186) (xy 78.226101 -57.720685) (xy 78.278885 -57.702678) (xy 78.333728 -57.692548)
			(xy 78.389462 -57.690511) (xy 78.444899 -57.696611) (xy 78.498856 -57.710717) (xy 78.550185 -57.732529)
			(xy 78.597791 -57.761583) (xy 78.640659 -57.797258) (xy 78.677876 -57.838795) (xy 78.708649 -57.885308)
			(xy 78.732321 -57.935805) (xy 78.748389 -57.989212) (xy 78.756509 -58.044388) (xy 78.757018 -58.072274)
			(xy 78.756948 -58.076084) (xy 83.357972 -58.076084) (xy 83.362043 -58.020462) (xy 83.374169 -57.966025)
			(xy 83.394092 -57.913934) (xy 83.421388 -57.865299) (xy 83.455474 -57.821156) (xy 83.495623 -57.782447)
			(xy 83.540981 -57.749996) (xy 83.590581 -57.724495) (xy 83.643365 -57.706488) (xy 83.698208 -57.696358)
			(xy 83.753942 -57.694321) (xy 83.809379 -57.700421) (xy 83.863336 -57.714527) (xy 83.914665 -57.736339)
			(xy 83.962271 -57.765393) (xy 84.005139 -57.801068) (xy 84.042356 -57.842605) (xy 84.058692 -57.867296)
			(xy 85.642956 -57.867296) (xy 85.647027 -57.811674) (xy 85.659153 -57.757237) (xy 85.679076 -57.705146)
			(xy 85.706372 -57.656511) (xy 85.740458 -57.612368) (xy 85.780607 -57.573659) (xy 85.825965 -57.541208)
			(xy 85.875565 -57.515707) (xy 85.928349 -57.4977) (xy 85.983192 -57.48757) (xy 86.038926 -57.485533)
			(xy 86.094363 -57.491633) (xy 86.14832 -57.505739) (xy 86.199649 -57.527551) (xy 86.247255 -57.556605)
			(xy 86.290123 -57.59228) (xy 86.32734 -57.633817) (xy 86.358113 -57.68033) (xy 86.381785 -57.730827)
			(xy 86.397853 -57.784234) (xy 86.405973 -57.83941) (xy 86.406482 -57.867296) (xy 86.405973 -57.895182)
			(xy 86.397853 -57.950358) (xy 86.381785 -58.003765) (xy 86.358113 -58.054262) (xy 86.32734 -58.100775)
			(xy 86.290123 -58.142312) (xy 86.247255 -58.177987) (xy 86.199649 -58.207041) (xy 86.14832 -58.228853)
			(xy 86.094363 -58.242959) (xy 86.038926 -58.249059) (xy 85.983192 -58.247022) (xy 85.928349 -58.236892)
			(xy 85.875565 -58.218885) (xy 85.825965 -58.193384) (xy 85.780607 -58.160933) (xy 85.740458 -58.122224)
			(xy 85.706372 -58.078081) (xy 85.679076 -58.029446) (xy 85.659153 -57.977355) (xy 85.647027 -57.922918)
			(xy 85.642956 -57.867296) (xy 84.058692 -57.867296) (xy 84.073129 -57.889118) (xy 84.096801 -57.939615)
			(xy 84.112869 -57.993022) (xy 84.120989 -58.048198) (xy 84.121498 -58.076084) (xy 84.120989 -58.10397)
			(xy 84.112869 -58.159146) (xy 84.096801 -58.212553) (xy 84.073129 -58.26305) (xy 84.042356 -58.309563)
			(xy 84.005139 -58.3511) (xy 83.962271 -58.386775) (xy 83.914665 -58.415829) (xy 83.863336 -58.437641)
			(xy 83.809379 -58.451747) (xy 83.753942 -58.457847) (xy 83.698208 -58.45581) (xy 83.643365 -58.44568)
			(xy 83.590581 -58.427673) (xy 83.540981 -58.402172) (xy 83.495623 -58.369721) (xy 83.455474 -58.331012)
			(xy 83.421388 -58.286869) (xy 83.394092 -58.238234) (xy 83.374169 -58.186143) (xy 83.362043 -58.131706)
			(xy 83.357972 -58.076084) (xy 78.756948 -58.076084) (xy 78.756509 -58.10016) (xy 78.748389 -58.155336)
			(xy 78.732321 -58.208743) (xy 78.708649 -58.25924) (xy 78.677876 -58.305753) (xy 78.640659 -58.34729)
			(xy 78.597791 -58.382965) (xy 78.550185 -58.412019) (xy 78.498856 -58.433831) (xy 78.444899 -58.447937)
			(xy 78.389462 -58.454037) (xy 78.333728 -58.452) (xy 78.278885 -58.44187) (xy 78.226101 -58.423863)
			(xy 78.176501 -58.398362) (xy 78.131143 -58.365911) (xy 78.090994 -58.327202) (xy 78.056908 -58.283059)
			(xy 78.029612 -58.234424) (xy 78.009689 -58.182333) (xy 77.997563 -58.127896) (xy 77.993492 -58.072274)
			(xy 74.743345 -58.072274) (xy 74.736289 -58.097222) (xy 74.715152 -58.145421) (xy 74.687602 -58.190263)
			(xy 74.654159 -58.230902) (xy 74.635106 -58.249058) (xy 74.627722 -58.256594) (xy 74.619187 -58.275863)
			(xy 74.618596 -58.286396) (xy 74.618596 -58.361072) (xy 74.619128 -58.371621) (xy 74.627661 -58.390917)
			(xy 74.635106 -58.39841) (xy 74.654161 -58.416567) (xy 74.687618 -58.457196) (xy 74.715177 -58.502036)
			(xy 74.736315 -58.550237) (xy 74.739421 -58.561224) (xy 84.562186 -58.561224) (xy 84.566257 -58.505602)
			(xy 84.578383 -58.451165) (xy 84.598306 -58.399074) (xy 84.625602 -58.350439) (xy 84.659688 -58.306296)
			(xy 84.699837 -58.267587) (xy 84.745195 -58.235136) (xy 84.794795 -58.209635) (xy 84.847579 -58.191628)
			(xy 84.902422 -58.181498) (xy 84.958156 -58.179461) (xy 85.013593 -58.185561) (xy 85.06755 -58.199667)
			(xy 85.118879 -58.221479) (xy 85.166485 -58.250533) (xy 85.209353 -58.286208) (xy 85.24657 -58.327745)
			(xy 85.277343 -58.374258) (xy 85.301015 -58.424755) (xy 85.317083 -58.478162) (xy 85.325203 -58.533338)
			(xy 85.325712 -58.561224) (xy 85.325203 -58.58911) (xy 85.317083 -58.644286) (xy 85.301015 -58.697693)
			(xy 85.277343 -58.74819) (xy 85.24657 -58.794703) (xy 85.209353 -58.83624) (xy 85.166485 -58.871915)
			(xy 85.118879 -58.900969) (xy 85.06755 -58.922781) (xy 85.013593 -58.936887) (xy 84.958156 -58.942987)
			(xy 84.902422 -58.94095) (xy 84.847579 -58.93082) (xy 84.794795 -58.912813) (xy 84.745195 -58.887312)
			(xy 84.699837 -58.854861) (xy 84.659688 -58.816152) (xy 84.625602 -58.772009) (xy 84.598306 -58.723374)
			(xy 84.578383 -58.671283) (xy 84.566257 -58.616846) (xy 84.562186 -58.561224) (xy 74.739421 -58.561224)
			(xy 74.750633 -58.600884) (xy 74.757857 -58.653018) (xy 74.758296 -58.679334) (xy 74.75781 -58.706585)
			(xy 74.750054 -58.760533) (xy 74.734699 -58.812828) (xy 74.712057 -58.862405) (xy 74.682591 -58.908255)
			(xy 74.6469 -58.949446) (xy 74.605709 -58.985137) (xy 74.559859 -59.014603) (xy 74.510282 -59.037245)
			(xy 74.457987 -59.0526) (xy 74.404039 -59.060356) (xy 74.349537 -59.060356) (xy 74.295589 -59.0526)
			(xy 74.243294 -59.037245) (xy 74.193717 -59.014603) (xy 74.147867 -58.985137) (xy 74.106676 -58.949446)
			(xy 74.070985 -58.908255) (xy 74.041519 -58.862405) (xy 74.018877 -58.812828) (xy 74.003522 -58.760533)
			(xy 73.995766 -58.706585) (xy 73.99528 -58.679334) (xy 66.279564 -58.679334) (xy 66.283141 -58.704234)
			(xy 66.283586 -58.731404) (xy 66.283586 -58.739024) (xy 66.28241 -58.769203) (xy 66.271712 -58.828641)
			(xy 66.25179 -58.885653) (xy 66.22314 -58.938818) (xy 66.186476 -58.986808) (xy 66.164968 -59.00801)
			(xy 66.162174 -59.01055) (xy 66.1557 -59.018432) (xy 66.149028 -59.037689) (xy 66.14922 -59.047888)
			(xy 66.157055 -59.174634) (xy 83.09305 -59.174634) (xy 83.097121 -59.119012) (xy 83.109247 -59.064575)
			(xy 83.12917 -59.012484) (xy 83.156466 -58.963849) (xy 83.190552 -58.919706) (xy 83.230701 -58.880997)
			(xy 83.276059 -58.848546) (xy 83.325659 -58.823045) (xy 83.378443 -58.805038) (xy 83.433286 -58.794908)
			(xy 83.48902 -58.792871) (xy 83.544457 -58.798971) (xy 83.598414 -58.813077) (xy 83.649743 -58.834889)
			(xy 83.697349 -58.863943) (xy 83.740217 -58.899618) (xy 83.777434 -58.941155) (xy 83.808207 -58.987668)
			(xy 83.831879 -59.038165) (xy 83.847947 -59.091572) (xy 83.856067 -59.146748) (xy 83.856576 -59.174634)
			(xy 83.856067 -59.20252) (xy 83.847947 -59.257696) (xy 83.831879 -59.311103) (xy 83.808207 -59.3616)
			(xy 83.777434 -59.408113) (xy 83.740217 -59.44965) (xy 83.697349 -59.485325) (xy 83.649743 -59.514379)
			(xy 83.598414 -59.536191) (xy 83.544457 -59.550297) (xy 83.48902 -59.556397) (xy 83.433286 -59.55436)
			(xy 83.378443 -59.54423) (xy 83.325659 -59.526223) (xy 83.276059 -59.500722) (xy 83.230701 -59.468271)
			(xy 83.190552 -59.429562) (xy 83.156466 -59.385419) (xy 83.12917 -59.336784) (xy 83.109247 -59.284693)
			(xy 83.097121 -59.230256) (xy 83.09305 -59.174634) (xy 66.157055 -59.174634) (xy 66.20927 -60.019254)
			(xy 74.135661 -60.019254) (xy 74.135661 -59.964746) (xy 74.143419 -59.910792) (xy 74.158777 -59.858492)
			(xy 74.181423 -59.808909) (xy 74.210894 -59.763055) (xy 74.246592 -59.721862) (xy 74.287789 -59.686169)
			(xy 74.333646 -59.656702) (xy 74.383231 -59.634063) (xy 74.435533 -59.61871) (xy 74.489488 -59.610958)
			(xy 74.516742 -59.610498) (xy 74.544111 -59.610999) (xy 74.598289 -59.618808) (xy 74.650791 -59.634289)
			(xy 74.700539 -59.657123) (xy 74.746507 -59.68684) (xy 74.76744 -59.704478) (xy 74.767694 -59.704732)
			(xy 74.774775 -59.710326) (xy 74.791696 -59.716567) (xy 74.800714 -59.716924) (xy 74.86777 -59.716924)
			(xy 74.876785 -59.716547) (xy 74.893702 -59.710313) (xy 74.90079 -59.704732) (xy 74.90079 -59.704478)
			(xy 74.901044 -59.704478) (xy 74.921977 -59.686837) (xy 74.967945 -59.657113) (xy 75.017691 -59.634267)
			(xy 75.070193 -59.618771) (xy 75.124371 -59.610942) (xy 75.179113 -59.610942) (xy 75.233291 -59.618771)
			(xy 75.285793 -59.634267) (xy 75.335539 -59.657113) (xy 75.381507 -59.686837) (xy 75.40244 -59.704478)
			(xy 75.402694 -59.704732) (xy 75.409775 -59.710326) (xy 75.426696 -59.716567) (xy 75.435714 -59.716924)
			(xy 75.50277 -59.716924) (xy 75.511785 -59.716547) (xy 75.528702 -59.710313) (xy 75.53579 -59.704732)
			(xy 75.53579 -59.704478) (xy 75.536044 -59.704478) (xy 75.556984 -59.686848) (xy 75.602955 -59.657136)
			(xy 75.6527 -59.634298) (xy 75.705199 -59.618805) (xy 75.759373 -59.610974) (xy 75.786742 -59.610498)
			(xy 75.813992 -59.610975) (xy 75.867936 -59.618736) (xy 75.920226 -59.634095) (xy 75.969799 -59.656739)
			(xy 76.015645 -59.686207) (xy 76.056831 -59.721899) (xy 76.092518 -59.763089) (xy 76.121981 -59.808938)
			(xy 76.14462 -59.858513) (xy 76.159973 -59.910805) (xy 76.167728 -59.96475) (xy 76.167728 -60.01925)
			(xy 76.159973 -60.073195) (xy 76.14462 -60.125487) (xy 76.121981 -60.175062) (xy 76.092518 -60.220911)
			(xy 76.056831 -60.262101) (xy 76.015645 -60.297793) (xy 75.969799 -60.327261) (xy 75.920226 -60.349905)
			(xy 75.867936 -60.365264) (xy 75.813992 -60.373025) (xy 75.786742 -60.373514) (xy 75.759373 -60.37302)
			(xy 75.705195 -60.365208) (xy 75.652692 -60.349726) (xy 75.602945 -60.32689) (xy 75.556977 -60.297172)
			(xy 75.536044 -60.279534) (xy 75.53579 -60.27928) (xy 75.528712 -60.273681) (xy 75.511789 -60.267442)
			(xy 75.50277 -60.267088) (xy 75.435714 -60.267088) (xy 75.426698 -60.267454) (xy 75.409781 -60.273696)
			(xy 75.402694 -60.27928) (xy 75.40244 -60.279534) (xy 75.381507 -60.297175) (xy 75.335539 -60.326899)
			(xy 75.285793 -60.349745) (xy 75.233291 -60.365241) (xy 75.179113 -60.37307) (xy 75.124371 -60.37307)
			(xy 75.070193 -60.365241) (xy 75.017691 -60.349745) (xy 74.967945 -60.326899) (xy 74.921977 -60.297175)
			(xy 74.901044 -60.279534) (xy 74.90079 -60.27928) (xy 74.893712 -60.273681) (xy 74.876789 -60.267442)
			(xy 74.86777 -60.267088) (xy 74.800714 -60.267088) (xy 74.791698 -60.267454) (xy 74.774781 -60.273696)
			(xy 74.767694 -60.27928) (xy 74.767694 -60.279534) (xy 74.76744 -60.279534) (xy 74.746508 -60.297173)
			(xy 74.700535 -60.326884) (xy 74.650787 -60.349719) (xy 74.598287 -60.36521) (xy 74.544111 -60.373039)
			(xy 74.516742 -60.373514) (xy 74.489488 -60.373042) (xy 74.435533 -60.36529) (xy 74.383231 -60.349937)
			(xy 74.333646 -60.327298) (xy 74.287789 -60.297831) (xy 74.246592 -60.262138) (xy 74.210894 -60.220945)
			(xy 74.181423 -60.175091) (xy 74.158777 -60.125508) (xy 74.143419 -60.073208) (xy 74.135661 -60.019254)
			(xy 66.20927 -60.019254) (xy 66.241676 -60.54344) (xy 66.243708 -60.604908) (xy 66.243708 -60.605416)
			(xy 66.242953 -60.633356) (xy 85.79688 -60.633356) (xy 85.800951 -60.577734) (xy 85.813077 -60.523297)
			(xy 85.833 -60.471206) (xy 85.860296 -60.422571) (xy 85.894382 -60.378428) (xy 85.934531 -60.339719)
			(xy 85.979889 -60.307268) (xy 86.029489 -60.281767) (xy 86.082273 -60.26376) (xy 86.137116 -60.25363)
			(xy 86.19285 -60.251593) (xy 86.248287 -60.257693) (xy 86.302244 -60.271799) (xy 86.353573 -60.293611)
			(xy 86.401179 -60.322665) (xy 86.444047 -60.35834) (xy 86.481264 -60.399877) (xy 86.512037 -60.44639)
			(xy 86.535709 -60.496887) (xy 86.551777 -60.550294) (xy 86.559897 -60.60547) (xy 86.560406 -60.633356)
			(xy 86.559897 -60.661242) (xy 86.551777 -60.716418) (xy 86.535709 -60.769825) (xy 86.512037 -60.820322)
			(xy 86.481264 -60.866835) (xy 86.444047 -60.908372) (xy 86.401179 -60.944047) (xy 86.353573 -60.973101)
			(xy 86.302244 -60.994913) (xy 86.248287 -61.009019) (xy 86.19285 -61.015119) (xy 86.137116 -61.013082)
			(xy 86.082273 -61.002952) (xy 86.029489 -60.984945) (xy 85.979889 -60.959444) (xy 85.934531 -60.926993)
			(xy 85.894382 -60.888284) (xy 85.860296 -60.844141) (xy 85.833 -60.795506) (xy 85.813077 -60.743415)
			(xy 85.800951 -60.688978) (xy 85.79688 -60.633356) (xy 66.242953 -60.633356) (xy 66.242438 -60.652406)
			(xy 66.202769 -61.487812) (xy 84.304376 -61.487812) (xy 84.308447 -61.43219) (xy 84.320573 -61.377753)
			(xy 84.340496 -61.325662) (xy 84.367792 -61.277027) (xy 84.401878 -61.232884) (xy 84.442027 -61.194175)
			(xy 84.487385 -61.161724) (xy 84.536985 -61.136223) (xy 84.589769 -61.118216) (xy 84.644612 -61.108086)
			(xy 84.700346 -61.106049) (xy 84.755783 -61.112149) (xy 84.80974 -61.126255) (xy 84.861069 -61.148067)
			(xy 84.908675 -61.177121) (xy 84.951543 -61.212796) (xy 84.98876 -61.254333) (xy 85.019533 -61.300846)
			(xy 85.043205 -61.351343) (xy 85.059273 -61.40475) (xy 85.067393 -61.459926) (xy 85.067902 -61.487812)
			(xy 85.067393 -61.515698) (xy 85.059273 -61.570874) (xy 85.043205 -61.624281) (xy 85.019533 -61.674778)
			(xy 84.98876 -61.721291) (xy 84.951543 -61.762828) (xy 84.908675 -61.798503) (xy 84.861069 -61.827557)
			(xy 84.80974 -61.849369) (xy 84.755783 -61.863475) (xy 84.700346 -61.869575) (xy 84.644612 -61.867538)
			(xy 84.589769 -61.857408) (xy 84.536985 -61.839401) (xy 84.487385 -61.8139) (xy 84.442027 -61.781449)
			(xy 84.401878 -61.74274) (xy 84.367792 -61.698597) (xy 84.340496 -61.649962) (xy 84.320573 -61.597871)
			(xy 84.308447 -61.543434) (xy 84.304376 -61.487812) (xy 66.202769 -61.487812) (xy 66.172701 -62.121034)
			(xy 82.24215 -62.121034) (xy 82.246221 -62.065412) (xy 82.258347 -62.010975) (xy 82.27827 -61.958884)
			(xy 82.305566 -61.910249) (xy 82.339652 -61.866106) (xy 82.379801 -61.827397) (xy 82.425159 -61.794946)
			(xy 82.474759 -61.769445) (xy 82.527543 -61.751438) (xy 82.582386 -61.741308) (xy 82.63812 -61.739271)
			(xy 82.693557 -61.745371) (xy 82.747514 -61.759477) (xy 82.798843 -61.781289) (xy 82.846449 -61.810343)
			(xy 82.889317 -61.846018) (xy 82.926534 -61.887555) (xy 82.957307 -61.934068) (xy 82.980979 -61.984565)
			(xy 82.997047 -62.037972) (xy 83.005167 -62.093148) (xy 83.005676 -62.121034) (xy 83.005167 -62.14892)
			(xy 82.997047 -62.204096) (xy 82.980979 -62.257503) (xy 82.957307 -62.308) (xy 82.926534 -62.354513)
			(xy 82.889317 -62.39605) (xy 82.846449 -62.431725) (xy 82.798843 -62.460779) (xy 82.747514 -62.482591)
			(xy 82.693557 -62.496697) (xy 82.63812 -62.502797) (xy 82.582386 -62.50076) (xy 82.527543 -62.49063)
			(xy 82.474759 -62.472623) (xy 82.425159 -62.447122) (xy 82.379801 -62.414671) (xy 82.339652 -62.375962)
			(xy 82.305566 -62.331819) (xy 82.27827 -62.283184) (xy 82.258347 -62.231093) (xy 82.246221 -62.176656)
			(xy 82.24215 -62.121034) (xy 66.172701 -62.121034) (xy 66.120823 -63.213549) (xy 74.120788 -63.213549)
			(xy 74.120788 -63.159052) (xy 74.128543 -63.105109) (xy 74.143896 -63.052819) (xy 74.166533 -63.003246)
			(xy 74.195994 -62.957399) (xy 74.23168 -62.916211) (xy 74.272864 -62.880521) (xy 74.318708 -62.851054)
			(xy 74.368278 -62.828411) (xy 74.420566 -62.813053) (xy 74.474508 -62.805291) (xy 74.501756 -62.804802)
			(xy 74.529125 -62.805293) (xy 74.583303 -62.813105) (xy 74.635806 -62.828588) (xy 74.685553 -62.851424)
			(xy 74.731521 -62.881143) (xy 74.752454 -62.898782) (xy 74.752708 -62.899036) (xy 74.759785 -62.904636)
			(xy 74.776709 -62.910874) (xy 74.785728 -62.911228) (xy 74.852784 -62.911228) (xy 74.861799 -62.910857)
			(xy 74.878716 -62.904618) (xy 74.885804 -62.899036) (xy 74.885804 -62.898782) (xy 74.886058 -62.898782)
			(xy 74.906991 -62.881141) (xy 74.952959 -62.851417) (xy 75.002705 -62.828571) (xy 75.055207 -62.813075)
			(xy 75.109385 -62.805246) (xy 75.164127 -62.805246) (xy 75.218305 -62.813075) (xy 75.270807 -62.828571)
			(xy 75.320553 -62.851417) (xy 75.366521 -62.881141) (xy 75.387454 -62.898782) (xy 75.387708 -62.899036)
			(xy 75.394785 -62.904636) (xy 75.411709 -62.910874) (xy 75.420728 -62.911228) (xy 75.487784 -62.911228)
			(xy 75.496799 -62.910857) (xy 75.513716 -62.904618) (xy 75.520804 -62.899036) (xy 75.520804 -62.898782)
			(xy 75.521058 -62.898782) (xy 75.541993 -62.881146) (xy 75.587965 -62.851435) (xy 75.637712 -62.828598)
			(xy 75.690212 -62.813106) (xy 75.744387 -62.805277) (xy 75.771756 -62.804802) (xy 75.799012 -62.805242)
			(xy 75.852969 -62.812994) (xy 75.905273 -62.828347) (xy 75.95486 -62.850987) (xy 76.00072 -62.880455)
			(xy 76.041919 -62.916149) (xy 76.077619 -62.957344) (xy 76.107092 -63.003201) (xy 76.129738 -63.052785)
			(xy 76.13956 -63.086234) (xy 79.387444 -63.086234) (xy 79.391515 -63.030612) (xy 79.403641 -62.976175)
			(xy 79.423564 -62.924084) (xy 79.45086 -62.875449) (xy 79.484946 -62.831306) (xy 79.525095 -62.792597)
			(xy 79.570453 -62.760146) (xy 79.620053 -62.734645) (xy 79.672837 -62.716638) (xy 79.72768 -62.706508)
			(xy 79.783414 -62.704471) (xy 79.838851 -62.710571) (xy 79.892808 -62.724677) (xy 79.944137 -62.746489)
			(xy 79.991743 -62.775543) (xy 80.034611 -62.811218) (xy 80.071828 -62.852755) (xy 80.102601 -62.899268)
			(xy 80.126273 -62.949765) (xy 80.142341 -63.003172) (xy 80.150461 -63.058348) (xy 80.15097 -63.086234)
			(xy 80.150461 -63.11412) (xy 80.142341 -63.169296) (xy 80.126273 -63.222703) (xy 80.102601 -63.2732)
			(xy 80.102448 -63.273432) (xy 81.57667 -63.273432) (xy 81.580741 -63.21781) (xy 81.592867 -63.163373)
			(xy 81.61279 -63.111282) (xy 81.640086 -63.062647) (xy 81.674172 -63.018504) (xy 81.714321 -62.979795)
			(xy 81.759679 -62.947344) (xy 81.809279 -62.921843) (xy 81.862063 -62.903836) (xy 81.916906 -62.893706)
			(xy 81.97264 -62.891669) (xy 82.028077 -62.897769) (xy 82.082034 -62.911875) (xy 82.133363 -62.933687)
			(xy 82.180969 -62.962741) (xy 82.223837 -62.998416) (xy 82.261054 -63.039953) (xy 82.291827 -63.086466)
			(xy 82.315499 -63.136963) (xy 82.331567 -63.19037) (xy 82.339687 -63.245546) (xy 82.340196 -63.273432)
			(xy 82.339687 -63.301318) (xy 82.331567 -63.356494) (xy 82.315499 -63.409901) (xy 82.291827 -63.460398)
			(xy 82.261054 -63.506911) (xy 82.223837 -63.548448) (xy 82.180969 -63.584123) (xy 82.133363 -63.613177)
			(xy 82.082034 -63.634989) (xy 82.028077 -63.649095) (xy 81.97264 -63.655195) (xy 81.916906 -63.653158)
			(xy 81.862063 -63.643028) (xy 81.809279 -63.625021) (xy 81.759679 -63.59952) (xy 81.714321 -63.567069)
			(xy 81.674172 -63.52836) (xy 81.640086 -63.484217) (xy 81.61279 -63.435582) (xy 81.592867 -63.383491)
			(xy 81.580741 -63.329054) (xy 81.57667 -63.273432) (xy 80.102448 -63.273432) (xy 80.071828 -63.319713)
			(xy 80.034611 -63.36125) (xy 79.991743 -63.396925) (xy 79.944137 -63.425979) (xy 79.892808 -63.447791)
			(xy 79.838851 -63.461897) (xy 79.783414 -63.467997) (xy 79.72768 -63.46596) (xy 79.672837 -63.45583)
			(xy 79.620053 -63.437823) (xy 79.570453 -63.412322) (xy 79.525095 -63.379871) (xy 79.484946 -63.341162)
			(xy 79.45086 -63.297019) (xy 79.423564 -63.248384) (xy 79.403641 -63.196293) (xy 79.391515 -63.141856)
			(xy 79.387444 -63.086234) (xy 76.13956 -63.086234) (xy 76.145097 -63.105088) (xy 76.152855 -63.159044)
			(xy 76.152855 -63.213556) (xy 76.145097 -63.267512) (xy 76.129738 -63.319815) (xy 76.107092 -63.369399)
			(xy 76.077619 -63.415256) (xy 76.041919 -63.456451) (xy 76.00072 -63.492145) (xy 75.95486 -63.521613)
			(xy 75.905273 -63.544253) (xy 75.852969 -63.559606) (xy 75.799012 -63.567358) (xy 75.771756 -63.567818)
			(xy 75.744386 -63.567339) (xy 75.690207 -63.559527) (xy 75.637703 -63.544042) (xy 75.587956 -63.521203)
			(xy 75.541989 -63.491479) (xy 75.521058 -63.473838) (xy 75.520804 -63.473584) (xy 75.513722 -63.467991)
			(xy 75.496802 -63.461749) (xy 75.487784 -63.461392) (xy 75.420728 -63.461392) (xy 75.411713 -63.461764)
			(xy 75.394796 -63.468001) (xy 75.387708 -63.473584) (xy 75.387454 -63.473838) (xy 75.366521 -63.491479)
			(xy 75.320553 -63.521203) (xy 75.270807 -63.544049) (xy 75.218305 -63.559545) (xy 75.164127 -63.567374)
			(xy 75.109385 -63.567374) (xy 75.055207 -63.559545) (xy 75.002705 -63.544049) (xy 74.952959 -63.521203)
			(xy 74.906991 -63.491479) (xy 74.886058 -63.473838) (xy 74.885804 -63.473584) (xy 74.878722 -63.467991)
			(xy 74.861802 -63.461749) (xy 74.852784 -63.461392) (xy 74.785728 -63.461392) (xy 74.776713 -63.461764)
			(xy 74.759796 -63.468001) (xy 74.752708 -63.473584) (xy 74.752708 -63.473838) (xy 74.752454 -63.473838)
			(xy 74.731518 -63.491472) (xy 74.685545 -63.521183) (xy 74.635799 -63.54402) (xy 74.583299 -63.559512)
			(xy 74.529125 -63.567343) (xy 74.501756 -63.567818) (xy 74.474508 -63.567309) (xy 74.420566 -63.559547)
			(xy 74.368278 -63.544189) (xy 74.318708 -63.521546) (xy 74.272864 -63.492079) (xy 74.23168 -63.456389)
			(xy 74.195994 -63.415201) (xy 74.166533 -63.369354) (xy 74.143896 -63.319781) (xy 74.128543 -63.267491)
			(xy 74.120788 -63.213549) (xy 66.120823 -63.213549) (xy 66.0312 -65.100962) (xy 72.132442 -65.100962)
			(xy 72.136513 -65.04534) (xy 72.148639 -64.990903) (xy 72.168562 -64.938812) (xy 72.195858 -64.890177)
			(xy 72.229944 -64.846034) (xy 72.270093 -64.807325) (xy 72.315451 -64.774874) (xy 72.365051 -64.749373)
			(xy 72.417835 -64.731366) (xy 72.472678 -64.721236) (xy 72.528412 -64.719199) (xy 72.583849 -64.725299)
			(xy 72.637806 -64.739405) (xy 72.689135 -64.761217) (xy 72.736741 -64.790271) (xy 72.779609 -64.825946)
			(xy 72.816826 -64.867483) (xy 72.847599 -64.913996) (xy 72.871271 -64.964493) (xy 72.887339 -65.0179)
			(xy 72.895459 -65.073076) (xy 72.895968 -65.100962) (xy 72.895459 -65.128848) (xy 72.887339 -65.184024)
			(xy 72.871271 -65.237431) (xy 72.847599 -65.287928) (xy 72.816826 -65.334441) (xy 72.779609 -65.375978)
			(xy 72.736741 -65.411653) (xy 72.689135 -65.440707) (xy 72.637806 -65.462519) (xy 72.583849 -65.476625)
			(xy 72.528412 -65.482725) (xy 72.472678 -65.480688) (xy 72.417835 -65.470558) (xy 72.365051 -65.452551)
			(xy 72.315451 -65.42705) (xy 72.270093 -65.394599) (xy 72.229944 -65.35589) (xy 72.195858 -65.311747)
			(xy 72.168562 -65.263112) (xy 72.148639 -65.211021) (xy 72.136513 -65.156584) (xy 72.132442 -65.100962)
			(xy 66.0312 -65.100962) (xy 66.000119 -65.75552) (xy 66.346576 -65.75552) (xy 66.350647 -65.699898)
			(xy 66.362773 -65.645461) (xy 66.382696 -65.59337) (xy 66.409992 -65.544735) (xy 66.444078 -65.500592)
			(xy 66.484227 -65.461883) (xy 66.529585 -65.429432) (xy 66.579185 -65.403931) (xy 66.631969 -65.385924)
			(xy 66.686812 -65.375794) (xy 66.742546 -65.373757) (xy 66.797983 -65.379857) (xy 66.85194 -65.393963)
			(xy 66.903269 -65.415775) (xy 66.950875 -65.444829) (xy 66.993743 -65.480504) (xy 67.03096 -65.522041)
			(xy 67.061733 -65.568554) (xy 67.085405 -65.619051) (xy 67.101473 -65.672458) (xy 67.109593 -65.727634)
			(xy 67.110102 -65.75552) (xy 67.109593 -65.783406) (xy 67.101473 -65.838582) (xy 67.085405 -65.891989)
			(xy 67.061733 -65.942486) (xy 67.03096 -65.988999) (xy 66.993743 -66.030536) (xy 66.950875 -66.066211)
			(xy 66.903269 -66.095265) (xy 66.85194 -66.117077) (xy 66.797983 -66.131183) (xy 66.742546 -66.137283)
			(xy 66.686812 -66.135246) (xy 66.631969 -66.125116) (xy 66.579185 -66.107109) (xy 66.529585 -66.081608)
			(xy 66.484227 -66.049157) (xy 66.444078 -66.010448) (xy 66.409992 -65.966305) (xy 66.382696 -65.91767)
			(xy 66.362773 -65.865579) (xy 66.350647 -65.811142) (xy 66.346576 -65.75552) (xy 66.000119 -65.75552)
			(xy 65.934902 -67.128953) (xy 66.366575 -67.128953) (xy 66.366575 -67.074447) (xy 66.374333 -67.020495)
			(xy 66.389691 -66.968196) (xy 66.412335 -66.918616) (xy 66.441806 -66.872763) (xy 66.477502 -66.831571)
			(xy 66.518698 -66.795879) (xy 66.564554 -66.766414) (xy 66.614137 -66.743775) (xy 66.666438 -66.728424)
			(xy 66.720391 -66.720672) (xy 66.747644 -66.720212) (xy 66.775013 -66.720708) (xy 66.829191 -66.728518)
			(xy 66.881694 -66.744) (xy 66.931441 -66.766835) (xy 66.977409 -66.796554) (xy 66.998342 -66.814192)
			(xy 66.998596 -66.814446) (xy 67.005676 -66.820043) (xy 67.022598 -66.826282) (xy 67.031616 -66.826638)
			(xy 67.098672 -66.826638) (xy 67.107686 -66.826259) (xy 67.124603 -66.820026) (xy 67.131692 -66.814446)
			(xy 67.131692 -66.814192) (xy 67.131946 -66.814192) (xy 67.152887 -66.796564) (xy 67.198857 -66.76685)
			(xy 67.248603 -66.744013) (xy 67.301101 -66.728519) (xy 67.355275 -66.720688) (xy 67.382644 -66.720212)
			(xy 67.409895 -66.720661) (xy 67.46384 -66.728423) (xy 67.516133 -66.743783) (xy 67.565707 -66.766427)
			(xy 67.611554 -66.795896) (xy 67.652741 -66.83159) (xy 67.68843 -66.872781) (xy 67.717894 -66.918632)
			(xy 67.740533 -66.968209) (xy 67.755887 -67.020503) (xy 67.763642 -67.074449) (xy 67.763642 -67.128951)
			(xy 67.755887 -67.182897) (xy 67.740533 -67.235191) (xy 67.717894 -67.284768) (xy 67.68843 -67.330619)
			(xy 67.652741 -67.37181) (xy 67.611554 -67.407504) (xy 67.565707 -67.436973) (xy 67.516133 -67.459617)
			(xy 67.46384 -67.474977) (xy 67.409895 -67.482739) (xy 67.382644 -67.483228) (xy 67.355274 -67.482754)
			(xy 67.301094 -67.474941) (xy 67.248591 -67.459454) (xy 67.198844 -67.436614) (xy 67.152877 -67.40689)
			(xy 67.131946 -67.389248) (xy 67.131692 -67.388994) (xy 67.124612 -67.383397) (xy 67.10769 -67.377157)
			(xy 67.098672 -67.376802) (xy 67.031616 -67.376802) (xy 67.0226 -67.377166) (xy 67.005683 -67.383409)
			(xy 66.998596 -67.388994) (xy 66.998596 -67.389248) (xy 66.998342 -67.389248) (xy 66.977398 -67.406873)
			(xy 66.931429 -67.436589) (xy 66.881685 -67.459428) (xy 66.829187 -67.474922) (xy 66.775013 -67.482753)
			(xy 66.747644 -67.483228) (xy 66.720391 -67.482728) (xy 66.666438 -67.474976) (xy 66.614137 -67.459625)
			(xy 66.564554 -67.436986) (xy 66.518698 -67.407521) (xy 66.477502 -67.371829) (xy 66.441806 -67.330637)
			(xy 66.412335 -67.284784) (xy 66.389691 -67.235204) (xy 66.374333 -67.182905) (xy 66.366575 -67.128953)
			(xy 65.934902 -67.128953) (xy 65.91785 -67.488054) (xy 70.77913 -67.488054) (xy 70.783201 -67.432432)
			(xy 70.795327 -67.377995) (xy 70.81525 -67.325904) (xy 70.842546 -67.277269) (xy 70.876632 -67.233126)
			(xy 70.916781 -67.194417) (xy 70.962139 -67.161966) (xy 71.011739 -67.136465) (xy 71.064523 -67.118458)
			(xy 71.119366 -67.108328) (xy 71.1751 -67.106291) (xy 71.230537 -67.112391) (xy 71.284494 -67.126497)
			(xy 71.335823 -67.148309) (xy 71.383429 -67.177363) (xy 71.426297 -67.213038) (xy 71.463514 -67.254575)
			(xy 71.494287 -67.301088) (xy 71.517959 -67.351585) (xy 71.534027 -67.404992) (xy 71.542147 -67.460168)
			(xy 71.542656 -67.488054) (xy 71.542147 -67.51594) (xy 71.538962 -67.537584) (xy 72.071228 -67.537584)
			(xy 72.075299 -67.481962) (xy 72.087425 -67.427525) (xy 72.107348 -67.375434) (xy 72.134644 -67.326799)
			(xy 72.16873 -67.282656) (xy 72.208879 -67.243947) (xy 72.254237 -67.211496) (xy 72.303837 -67.185995)
			(xy 72.356621 -67.167988) (xy 72.411464 -67.157858) (xy 72.467198 -67.155821) (xy 72.522635 -67.161921)
			(xy 72.576592 -67.176027) (xy 72.627921 -67.197839) (xy 72.675527 -67.226893) (xy 72.718395 -67.262568)
			(xy 72.755612 -67.304105) (xy 72.786385 -67.350618) (xy 72.810057 -67.401115) (xy 72.826125 -67.454522)
			(xy 72.834245 -67.509698) (xy 72.834754 -67.537584) (xy 72.834245 -67.56547) (xy 72.8302 -67.592956)
			(xy 73.345292 -67.592956) (xy 73.349363 -67.537334) (xy 73.361489 -67.482897) (xy 73.381412 -67.430806)
			(xy 73.408708 -67.382171) (xy 73.442794 -67.338028) (xy 73.482943 -67.299319) (xy 73.528301 -67.266868)
			(xy 73.577901 -67.241367) (xy 73.630685 -67.22336) (xy 73.685528 -67.21323) (xy 73.741262 -67.211193)
			(xy 73.796699 -67.217293) (xy 73.850656 -67.231399) (xy 73.901985 -67.253211) (xy 73.949591 -67.282265)
			(xy 73.992459 -67.31794) (xy 74.029676 -67.359477) (xy 74.060449 -67.40599) (xy 74.084121 -67.456487)
			(xy 74.100189 -67.509894) (xy 74.108306 -67.565052) (xy 76.446593 -67.565052) (xy 76.446593 -67.510548)
			(xy 76.45435 -67.4566) (xy 76.469707 -67.404304) (xy 76.492349 -67.354727) (xy 76.521818 -67.308877)
			(xy 76.557511 -67.267687) (xy 76.598704 -67.231997) (xy 76.644557 -67.202533) (xy 76.694136 -67.179895)
			(xy 76.746433 -67.164543) (xy 76.800382 -67.156791) (xy 76.827634 -67.15633) (xy 76.855005 -67.156769)
			(xy 76.909186 -67.164592) (xy 76.96169 -67.180087) (xy 77.011436 -67.202935) (xy 77.057401 -67.232666)
			(xy 77.078332 -67.25031) (xy 77.078586 -67.250564) (xy 77.085667 -67.256158) (xy 77.102588 -67.262399)
			(xy 77.111606 -67.262756) (xy 77.178662 -67.262756) (xy 77.187678 -67.26239) (xy 77.204596 -67.25615)
			(xy 77.211682 -67.250564) (xy 77.211682 -67.25031) (xy 77.211936 -67.25031) (xy 77.232883 -67.232689)
			(xy 77.278851 -67.202974) (xy 77.328595 -67.180135) (xy 77.381093 -67.164639) (xy 77.435266 -67.156806)
			(xy 77.462634 -67.15633) (xy 77.489886 -67.156742) (xy 77.543836 -67.164503) (xy 77.596132 -67.179863)
			(xy 77.64571 -67.202508) (xy 77.69156 -67.231978) (xy 77.732751 -67.267674) (xy 77.768442 -67.308867)
			(xy 77.797908 -67.35472) (xy 77.820549 -67.4043) (xy 77.835904 -67.456597) (xy 77.84366 -67.510548)
			(xy 77.84366 -67.565052) (xy 77.835904 -67.619003) (xy 77.820549 -67.6713) (xy 77.797908 -67.72088)
			(xy 77.768442 -67.766733) (xy 77.732751 -67.807926) (xy 77.69156 -67.843622) (xy 77.64571 -67.873092)
			(xy 77.596132 -67.895737) (xy 77.543836 -67.911097) (xy 77.489886 -67.918858) (xy 77.462634 -67.919346)
			(xy 77.435264 -67.918873) (xy 77.381085 -67.911059) (xy 77.328581 -67.895572) (xy 77.278834 -67.872732)
			(xy 77.232867 -67.843007) (xy 77.211936 -67.825366) (xy 77.211682 -67.825112) (xy 77.204604 -67.819513)
			(xy 77.187681 -67.813273) (xy 77.178662 -67.81292) (xy 77.111606 -67.81292) (xy 77.102589 -67.813275)
			(xy 77.085672 -67.819524) (xy 77.078586 -67.825112) (xy 77.078586 -67.825366) (xy 77.078332 -67.825366)
			(xy 77.057394 -67.842998) (xy 77.011424 -67.872712) (xy 76.961678 -67.89555) (xy 76.909178 -67.911043)
			(xy 76.855003 -67.918872) (xy 76.827634 -67.919346) (xy 76.800382 -67.918809) (xy 76.746433 -67.911057)
			(xy 76.694136 -67.895705) (xy 76.644557 -67.873067) (xy 76.598704 -67.843603) (xy 76.557511 -67.807913)
			(xy 76.521818 -67.766723) (xy 76.492349 -67.720873) (xy 76.469707 -67.671296) (xy 76.45435 -67.619)
			(xy 76.446593 -67.565052) (xy 74.108306 -67.565052) (xy 74.108309 -67.56507) (xy 74.108818 -67.592956)
			(xy 74.108309 -67.620842) (xy 74.100189 -67.676018) (xy 74.084121 -67.729425) (xy 74.060449 -67.779922)
			(xy 74.029676 -67.826435) (xy 73.992459 -67.867972) (xy 73.949591 -67.903647) (xy 73.901985 -67.932701)
			(xy 73.850656 -67.954513) (xy 73.796699 -67.968619) (xy 73.741262 -67.974719) (xy 73.685528 -67.972682)
			(xy 73.630685 -67.962552) (xy 73.577901 -67.944545) (xy 73.528301 -67.919044) (xy 73.482943 -67.886593)
			(xy 73.442794 -67.847884) (xy 73.408708 -67.803741) (xy 73.381412 -67.755106) (xy 73.361489 -67.703015)
			(xy 73.349363 -67.648578) (xy 73.345292 -67.592956) (xy 72.8302 -67.592956) (xy 72.826125 -67.620646)
			(xy 72.810057 -67.674053) (xy 72.786385 -67.72455) (xy 72.755612 -67.771063) (xy 72.718395 -67.8126)
			(xy 72.675527 -67.848275) (xy 72.627921 -67.877329) (xy 72.576592 -67.899141) (xy 72.522635 -67.913247)
			(xy 72.467198 -67.919347) (xy 72.411464 -67.91731) (xy 72.356621 -67.90718) (xy 72.303837 -67.889173)
			(xy 72.254237 -67.863672) (xy 72.208879 -67.831221) (xy 72.16873 -67.792512) (xy 72.134644 -67.748369)
			(xy 72.107348 -67.699734) (xy 72.087425 -67.647643) (xy 72.075299 -67.593206) (xy 72.071228 -67.537584)
			(xy 71.538962 -67.537584) (xy 71.534027 -67.571116) (xy 71.517959 -67.624523) (xy 71.494287 -67.67502)
			(xy 71.463514 -67.721533) (xy 71.426297 -67.76307) (xy 71.383429 -67.798745) (xy 71.335823 -67.827799)
			(xy 71.284494 -67.849611) (xy 71.230537 -67.863717) (xy 71.1751 -67.869817) (xy 71.119366 -67.86778)
			(xy 71.064523 -67.85765) (xy 71.011739 -67.839643) (xy 70.962139 -67.814142) (xy 70.916781 -67.781691)
			(xy 70.876632 -67.742982) (xy 70.842546 -67.698839) (xy 70.81525 -67.650204) (xy 70.795327 -67.598113)
			(xy 70.783201 -67.543676) (xy 70.77913 -67.488054) (xy 65.91785 -67.488054) (xy 65.865686 -68.586604)
			(xy 68.625212 -68.586604) (xy 68.625677 -68.559234) (xy 68.633495 -68.505054) (xy 68.648984 -68.452551)
			(xy 68.671826 -68.402804) (xy 68.701551 -68.356838) (xy 68.719192 -68.335906) (xy 68.719446 -68.335652)
			(xy 68.725023 -68.328559) (xy 68.731274 -68.311647) (xy 68.731638 -68.302632) (xy 68.731638 -68.235576)
			(xy 68.731284 -68.226559) (xy 68.725034 -68.209642) (xy 68.719446 -68.202556) (xy 68.719192 -68.202556)
			(xy 68.719192 -68.202302) (xy 68.701539 -68.181381) (xy 68.67183 -68.135405) (xy 68.648996 -68.085655)
			(xy 68.633509 -68.033152) (xy 68.625684 -67.978974) (xy 68.625212 -67.951604) (xy 68.625659 -67.92435)
			(xy 68.633416 -67.870398) (xy 68.648773 -67.818098) (xy 68.671416 -67.768517) (xy 68.700886 -67.722663)
			(xy 68.736581 -67.68147) (xy 68.777776 -67.645776) (xy 68.823631 -67.616308) (xy 68.873213 -67.593667)
			(xy 68.925513 -67.578313) (xy 68.979466 -67.570558) (xy 69.00672 -67.570096) (xy 69.033034 -67.570551)
			(xy 69.085163 -67.577789) (xy 69.135806 -67.59211) (xy 69.184005 -67.613245) (xy 69.228848 -67.640793)
			(xy 69.269488 -67.674234) (xy 69.287644 -67.693286) (xy 69.295149 -67.700707) (xy 69.314442 -67.709221)
			(xy 69.324982 -67.709796) (xy 69.399658 -67.709796) (xy 69.410207 -67.709259) (xy 69.429502 -67.70073)
			(xy 69.436996 -67.693286) (xy 69.455158 -67.674237) (xy 69.495786 -67.64078) (xy 69.540626 -67.61322)
			(xy 69.588825 -67.592081) (xy 69.639471 -67.577762) (xy 69.691604 -67.570535) (xy 69.71792 -67.570096)
			(xy 69.745291 -67.570551) (xy 69.79947 -67.578372) (xy 69.851973 -67.593864) (xy 69.90172 -67.616708)
			(xy 69.947686 -67.646434) (xy 69.968618 -67.664076) (xy 69.968872 -67.66433) (xy 69.97596 -67.669914)
			(xy 69.992876 -67.676161) (xy 70.001892 -67.676522) (xy 70.068948 -67.676522) (xy 70.077962 -67.676135)
			(xy 70.094879 -67.669908) (xy 70.101968 -67.66433) (xy 70.101968 -67.664076) (xy 70.102222 -67.664076)
			(xy 70.12317 -67.646456) (xy 70.169139 -67.616742) (xy 70.218882 -67.593903) (xy 70.271379 -67.578407)
			(xy 70.325552 -67.570573) (xy 70.35292 -67.570096) (xy 70.380172 -67.570559) (xy 70.434121 -67.578319)
			(xy 70.486416 -67.593676) (xy 70.535994 -67.61632) (xy 70.581844 -67.645789) (xy 70.623034 -67.681483)
			(xy 70.658725 -67.722675) (xy 70.688191 -67.768527) (xy 70.710832 -67.818106) (xy 70.726187 -67.870403)
			(xy 70.733943 -67.924352) (xy 70.734428 -67.951604) (xy 70.733982 -67.978975) (xy 70.726162 -68.033156)
			(xy 70.710669 -68.08566) (xy 70.687823 -68.135406) (xy 70.658092 -68.181372) (xy 70.640448 -68.202302)
			(xy 70.640194 -68.202556) (xy 70.634619 -68.209651) (xy 70.628366 -68.226561) (xy 70.628002 -68.235576)
			(xy 70.628002 -68.302632) (xy 70.628343 -68.31165) (xy 70.634602 -68.328567) (xy 70.640194 -68.335652)
			(xy 70.640448 -68.335652) (xy 70.640448 -68.335906) (xy 70.658095 -68.356832) (xy 70.687808 -68.402805)
			(xy 70.710643 -68.452554) (xy 70.726132 -68.505057) (xy 70.733956 -68.559234) (xy 70.734428 -68.586604)
			(xy 70.733926 -68.613854) (xy 70.726169 -68.667801) (xy 70.710815 -68.720094) (xy 70.694176 -68.75653)
			(xy 74.170286 -68.75653) (xy 74.170773 -68.729161) (xy 74.178586 -68.674983) (xy 74.194071 -68.62248)
			(xy 74.216908 -68.572733) (xy 74.246627 -68.526765) (xy 74.264266 -68.505832) (xy 74.26452 -68.505578)
			(xy 74.270124 -68.498504) (xy 74.27636 -68.481577) (xy 74.276712 -68.472558) (xy 74.276712 -68.405502)
			(xy 74.276351 -68.396486) (xy 74.270106 -68.379569) (xy 74.26452 -68.372482) (xy 74.264266 -68.372482)
			(xy 74.264266 -68.372228) (xy 74.246621 -68.351301) (xy 74.216911 -68.305326) (xy 74.194077 -68.255577)
			(xy 74.178587 -68.203076) (xy 74.17076 -68.148899) (xy 74.170286 -68.12153) (xy 74.170783 -68.094278)
			(xy 74.178536 -68.040329) (xy 74.193888 -67.988032) (xy 74.216526 -67.938452) (xy 74.245991 -67.892599)
			(xy 74.281681 -67.851406) (xy 74.32287 -67.815712) (xy 74.368721 -67.786244) (xy 74.418298 -67.7636)
			(xy 74.470594 -67.748244) (xy 74.524542 -67.740486) (xy 74.551794 -67.740022) (xy 74.579164 -67.740486)
			(xy 74.633344 -67.748304) (xy 74.685847 -67.763793) (xy 74.735594 -67.786635) (xy 74.781561 -67.81636)
			(xy 74.802492 -67.834002) (xy 74.802746 -67.834256) (xy 74.809839 -67.839833) (xy 74.826751 -67.846084)
			(xy 74.835766 -67.846448) (xy 74.902822 -67.846448) (xy 74.911841 -67.846113) (xy 74.928759 -67.839852)
			(xy 74.935842 -67.834256) (xy 74.935842 -67.834002) (xy 74.936096 -67.834002) (xy 74.957019 -67.816352)
			(xy 75.002994 -67.786641) (xy 75.052744 -67.763808) (xy 75.105247 -67.748319) (xy 75.159424 -67.740494)
			(xy 75.186794 -67.740022) (xy 75.213108 -67.740486) (xy 75.265237 -67.747721) (xy 75.31588 -67.76204)
			(xy 75.364079 -67.783173) (xy 75.408923 -67.81072) (xy 75.449562 -67.84416) (xy 75.467718 -67.863212)
			(xy 75.475229 -67.870625) (xy 75.494517 -67.879143) (xy 75.505056 -67.879722) (xy 75.579732 -67.879722)
			(xy 75.590278 -67.879163) (xy 75.609573 -67.870648) (xy 75.61707 -67.863212) (xy 75.63525 -67.84418)
			(xy 75.675874 -67.810721) (xy 75.720709 -67.783158) (xy 75.768905 -67.762015) (xy 75.819549 -67.747693)
			(xy 75.871679 -67.740463) (xy 75.897994 -67.740022) (xy 75.925248 -67.740461) (xy 75.979201 -67.748218)
			(xy 76.031502 -67.763575) (xy 76.081084 -67.786219) (xy 76.126938 -67.815689) (xy 76.168132 -67.851385)
			(xy 76.203826 -67.892581) (xy 76.233293 -67.938437) (xy 76.255934 -67.988021) (xy 76.271287 -68.040322)
			(xy 76.279041 -68.094276) (xy 76.279502 -68.12153) (xy 76.279053 -68.148901) (xy 76.271231 -68.203081)
			(xy 76.255738 -68.255584) (xy 76.232892 -68.30533) (xy 76.203165 -68.351297) (xy 76.185522 -68.372228)
			(xy 76.185268 -68.372482) (xy 76.179679 -68.379567) (xy 76.173435 -68.396485) (xy 76.173076 -68.405502)
			(xy 76.173076 -68.472558) (xy 76.173458 -68.481572) (xy 76.179689 -68.498489) (xy 76.185268 -68.505578)
			(xy 76.185522 -68.505578) (xy 76.185522 -68.505832) (xy 76.203146 -68.526776) (xy 76.232859 -68.572746)
			(xy 76.255698 -68.62249) (xy 76.271193 -68.674988) (xy 76.279025 -68.729162) (xy 76.279502 -68.75653)
			(xy 76.27905 -68.783782) (xy 76.271289 -68.837732) (xy 76.25593 -68.890027) (xy 76.233285 -68.939605)
			(xy 76.203815 -68.985456) (xy 76.16812 -69.026646) (xy 76.126927 -69.062337) (xy 76.081073 -69.091802)
			(xy 76.031493 -69.114443) (xy 75.979196 -69.129797) (xy 75.925246 -69.137553) (xy 75.897994 -69.138038)
			(xy 75.871679 -69.137594) (xy 75.819549 -69.130357) (xy 75.768905 -69.116035) (xy 75.720705 -69.094898)
			(xy 75.675863 -69.067347) (xy 75.635225 -69.033903) (xy 75.61707 -69.014848) (xy 75.609555 -69.007438)
			(xy 75.59027 -68.998917) (xy 75.579732 -68.998338) (xy 75.505056 -68.998338) (xy 75.494507 -68.998873)
			(xy 75.475211 -69.007403) (xy 75.467718 -69.014848) (xy 75.449556 -69.033897) (xy 75.408927 -69.067353)
			(xy 75.364087 -69.094912) (xy 75.315888 -69.116051) (xy 75.265242 -69.13037) (xy 75.21311 -69.137598)
			(xy 75.186794 -69.138038) (xy 75.159423 -69.137591) (xy 75.105242 -69.129771) (xy 75.052739 -69.114278)
			(xy 75.002992 -69.091432) (xy 74.957026 -69.061702) (xy 74.936096 -69.044058) (xy 74.935842 -69.043804)
			(xy 74.928747 -69.038229) (xy 74.911837 -69.031975) (xy 74.902822 -69.031612) (xy 74.835766 -69.031612)
			(xy 74.826747 -69.03195) (xy 74.80983 -69.038211) (xy 74.802746 -69.043804) (xy 74.802746 -69.044058)
			(xy 74.802492 -69.044058) (xy 74.781568 -69.061708) (xy 74.735594 -69.091419) (xy 74.685844 -69.114254)
			(xy 74.633342 -69.129742) (xy 74.579164 -69.137567) (xy 74.551794 -69.138038) (xy 74.524544 -69.137528)
			(xy 74.470599 -69.129771) (xy 74.418306 -69.114417) (xy 74.368731 -69.091777) (xy 74.322882 -69.062313)
			(xy 74.281693 -69.026624) (xy 74.246001 -68.985437) (xy 74.216534 -68.93959) (xy 74.193891 -68.890016)
			(xy 74.178534 -68.837725) (xy 74.170774 -68.78378) (xy 74.170286 -68.75653) (xy 70.694176 -68.75653)
			(xy 70.688175 -68.76967) (xy 70.65871 -68.815519) (xy 70.62302 -68.856709) (xy 70.581832 -68.8924)
			(xy 70.535984 -68.921867) (xy 70.486409 -68.944509) (xy 70.434116 -68.959866) (xy 70.38017 -68.967625)
			(xy 70.35292 -68.968112) (xy 70.32555 -68.967631) (xy 70.271372 -68.959817) (xy 70.218869 -68.944331)
			(xy 70.169122 -68.921492) (xy 70.123154 -68.891771) (xy 70.102222 -68.874132) (xy 70.101968 -68.873878)
			(xy 70.094868 -68.868311) (xy 70.077961 -68.862053) (xy 70.068948 -68.861686) (xy 70.001892 -68.861686)
			(xy 69.992875 -68.862042) (xy 69.975958 -68.868291) (xy 69.968872 -68.873878) (xy 69.968872 -68.874132)
			(xy 69.968618 -68.874132) (xy 69.947694 -68.891781) (xy 69.901719 -68.92149) (xy 69.851969 -68.944324)
			(xy 69.799467 -68.959813) (xy 69.74529 -68.967639) (xy 69.71792 -68.968112) (xy 69.691607 -68.967627)
			(xy 69.639479 -68.960396) (xy 69.588837 -68.94608) (xy 69.540638 -68.92495) (xy 69.495794 -68.897407)
			(xy 69.455153 -68.863972) (xy 69.436996 -68.844922) (xy 69.429475 -68.83752) (xy 69.410195 -68.828995)
			(xy 69.399658 -68.828412) (xy 69.324982 -68.828412) (xy 69.314435 -68.828968) (xy 69.295139 -68.837484)
			(xy 69.287644 -68.844922) (xy 69.269513 -68.864002) (xy 69.228878 -68.897456) (xy 69.184032 -68.925011)
			(xy 69.135826 -68.946145) (xy 69.085175 -68.960458) (xy 69.033037 -68.967677) (xy 69.00672 -68.968112)
			(xy 68.979468 -68.967626) (xy 68.925518 -68.959872) (xy 68.873221 -68.944519) (xy 68.823641 -68.921879)
			(xy 68.777788 -68.892413) (xy 68.736595 -68.856722) (xy 68.700901 -68.815531) (xy 68.671433 -68.76968)
			(xy 68.64879 -68.720102) (xy 68.633433 -68.667806) (xy 68.625676 -68.613856) (xy 68.625212 -68.586604)
			(xy 65.865686 -68.586604) (xy 65.815464 -69.64426) (xy 65.814297 -69.666429) (xy 65.81023 -69.710642)
			(xy 65.807336 -69.732652) (xy 65.805558 -69.745606) (xy 65.801748 -69.771514) (xy 65.801748 -69.771768)
			(xy 65.800986 -69.775832) (xy 65.800986 -69.77634) (xy 65.548676 -71.555864) (xy 71.19442 -71.555864)
			(xy 71.198491 -71.500242) (xy 71.210617 -71.445805) (xy 71.23054 -71.393714) (xy 71.257836 -71.345079)
			(xy 71.291922 -71.300936) (xy 71.332071 -71.262227) (xy 71.377429 -71.229776) (xy 71.427029 -71.204275)
			(xy 71.479813 -71.186268) (xy 71.534656 -71.176138) (xy 71.59039 -71.174101) (xy 71.645827 -71.180201)
			(xy 71.699784 -71.194307) (xy 71.751113 -71.216119) (xy 71.798719 -71.245173) (xy 71.841587 -71.280848)
			(xy 71.878804 -71.322385) (xy 71.909577 -71.368898) (xy 71.933249 -71.419395) (xy 71.949317 -71.472802)
			(xy 71.957437 -71.527978) (xy 71.957946 -71.555864) (xy 71.957437 -71.58375) (xy 71.951598 -71.623428)
			(xy 72.703434 -71.623428) (xy 72.707505 -71.567806) (xy 72.719631 -71.513369) (xy 72.739554 -71.461278)
			(xy 72.76685 -71.412643) (xy 72.800936 -71.3685) (xy 72.841085 -71.329791) (xy 72.886443 -71.29734)
			(xy 72.936043 -71.271839) (xy 72.988827 -71.253832) (xy 73.04367 -71.243702) (xy 73.099404 -71.241665)
			(xy 73.154841 -71.247765) (xy 73.208798 -71.261871) (xy 73.260127 -71.283683) (xy 73.307733 -71.312737)
			(xy 73.350601 -71.348412) (xy 73.387818 -71.389949) (xy 73.418591 -71.436462) (xy 73.442263 -71.486959)
			(xy 73.458331 -71.540366) (xy 73.466451 -71.595542) (xy 73.46696 -71.623428) (xy 73.466451 -71.651314)
			(xy 73.458331 -71.70649) (xy 73.442263 -71.759897) (xy 73.418591 -71.810394) (xy 73.387818 -71.856907)
			(xy 73.350601 -71.898444) (xy 73.307733 -71.934119) (xy 73.260127 -71.963173) (xy 73.208798 -71.984985)
			(xy 73.154841 -71.999091) (xy 73.099404 -72.005191) (xy 73.04367 -72.003154) (xy 72.988827 -71.993024)
			(xy 72.936043 -71.975017) (xy 72.886443 -71.949516) (xy 72.841085 -71.917065) (xy 72.800936 -71.878356)
			(xy 72.76685 -71.834213) (xy 72.739554 -71.785578) (xy 72.719631 -71.733487) (xy 72.707505 -71.67905)
			(xy 72.703434 -71.623428) (xy 71.951598 -71.623428) (xy 71.949317 -71.638926) (xy 71.933249 -71.692333)
			(xy 71.909577 -71.74283) (xy 71.878804 -71.789343) (xy 71.841587 -71.83088) (xy 71.798719 -71.866555)
			(xy 71.751113 -71.895609) (xy 71.699784 -71.917421) (xy 71.645827 -71.931527) (xy 71.59039 -71.937627)
			(xy 71.534656 -71.93559) (xy 71.479813 -71.92546) (xy 71.427029 -71.907453) (xy 71.377429 -71.881952)
			(xy 71.332071 -71.849501) (xy 71.291922 -71.810792) (xy 71.257836 -71.766649) (xy 71.23054 -71.718014)
			(xy 71.210617 -71.665923) (xy 71.198491 -71.611486) (xy 71.19442 -71.555864) (xy 65.548676 -71.555864)
			(xy 64.602316 -78.230476) (xy 65.148204 -78.230476) (xy 65.152275 -78.174854) (xy 65.164401 -78.120417)
			(xy 65.184324 -78.068326) (xy 65.21162 -78.019691) (xy 65.245706 -77.975548) (xy 65.285855 -77.936839)
			(xy 65.331213 -77.904388) (xy 65.380813 -77.878887) (xy 65.433597 -77.86088) (xy 65.48844 -77.85075)
			(xy 65.544174 -77.848713) (xy 65.599611 -77.854813) (xy 65.653568 -77.868919) (xy 65.704897 -77.890731)
			(xy 65.752503 -77.919785) (xy 65.795371 -77.95546) (xy 65.832588 -77.996997) (xy 65.863361 -78.04351)
			(xy 65.887033 -78.094007) (xy 65.903101 -78.147414) (xy 65.911221 -78.20259) (xy 65.91173 -78.230476)
			(xy 65.911221 -78.258362) (xy 65.903101 -78.313538) (xy 65.887033 -78.366945) (xy 65.863361 -78.417442)
			(xy 65.832588 -78.463955) (xy 65.795371 -78.505492) (xy 65.752503 -78.541167) (xy 65.704897 -78.570221)
			(xy 65.653568 -78.592033) (xy 65.599611 -78.606139) (xy 65.544174 -78.612239) (xy 65.48844 -78.610202)
			(xy 65.433597 -78.600072) (xy 65.380813 -78.582065) (xy 65.331213 -78.556564) (xy 65.285855 -78.524113)
			(xy 65.245706 -78.485404) (xy 65.21162 -78.441261) (xy 65.184324 -78.392626) (xy 65.164401 -78.340535)
			(xy 65.152275 -78.286098) (xy 65.148204 -78.230476) (xy 64.602316 -78.230476) (xy 64.32296 -80.200754)
			(xy 62.821312 -90.793824) (xy 62.820738 -90.798659) (xy 62.821249 -90.80838) (xy 62.822328 -90.813128)
			(xy 62.824228 -90.819815) (xy 62.831048 -90.831922) (xy 62.83579 -90.837004) (xy 63.347346 -91.34856)
			(xy 63.352848 -91.353541) (xy 63.366017 -91.360372) (xy 63.373254 -91.362022) (xy 63.382906 -91.363038)
			(xy 64.101726 -91.363038) (xy 64.113664 -91.361768) (xy 64.130174 -91.357704) (xy 64.132206 -91.356688)
			(xy 64.13672 -91.354061) (xy 64.144655 -91.347274) (xy 64.147954 -91.343226) (xy 72.598788 -80.336898)
			(xy 72.603909 -80.329715) (xy 72.609364 -80.312953) (xy 72.609456 -80.304132) (xy 72.608948 -80.295242)
			(xy 72.602344 -80.278732) (xy 72.596756 -80.272382) (xy 72.578855 -80.251364) (xy 72.548669 -80.205142)
			(xy 72.52546 -80.155051) (xy 72.509712 -80.102139) (xy 72.501754 -80.047509) (xy 72.501252 -80.019906)
			(xy 72.501737 -79.992653) (xy 72.509493 -79.938703) (xy 72.524847 -79.886405) (xy 72.547487 -79.836825)
			(xy 72.576953 -79.790971) (xy 72.612644 -79.749776) (xy 72.653834 -79.71408) (xy 72.699684 -79.684609)
			(xy 72.749262 -79.661963) (xy 72.801558 -79.646603) (xy 72.855507 -79.638841) (xy 72.88276 -79.638398)
			(xy 72.912127 -79.638933) (xy 72.970168 -79.647919) (xy 73.02615 -79.665686) (xy 73.052686 -79.678276)
			(xy 73.05294 -79.678276) (xy 73.063415 -79.682785) (xy 73.086188 -79.683146) (xy 73.106901 -79.673676)
			(xy 73.114662 -79.665322) (xy 84.12988 -65.318894) (xy 84.133724 -65.313517) (xy 84.138729 -65.301289)
			(xy 84.139786 -65.294764) (xy 84.141564 -65.28181) (xy 84.13623 -65.26911) (xy 84.127231 -65.246089)
			(xy 84.11457 -65.198311) (xy 84.108181 -65.149298) (xy 84.107782 -65.124584) (xy 84.107782 -65.115948)
			(xy 84.10881 -65.089077) (xy 84.117485 -65.036008) (xy 84.133529 -64.984683) (xy 84.156622 -64.936121)
			(xy 84.186308 -64.891284) (xy 84.221997 -64.851061) (xy 84.262981 -64.816249) (xy 84.30845 -64.78754)
			(xy 84.3575 -64.765501) (xy 84.409159 -64.750571) (xy 84.462403 -64.743044) (xy 84.48929 -64.742568)
			(xy 84.490306 -64.742568) (xy 84.50234 -64.742673) (xy 84.526361 -64.744199) (xy 84.538312 -64.745616)
			(xy 84.539074 -64.745616) (xy 84.545595 -64.74627) (xy 84.558588 -64.744604) (xy 84.564728 -64.742314)
			(xy 84.570062 -64.740028) (xy 84.580476 -64.732154) (xy 85.012784 -64.169036) (xy 85.119464 -64.030098)
			(xy 85.496146 -63.538862) (xy 85.50021 -63.53302) (xy 85.533738 -63.473584) (xy 85.750908 -63.088012)
			(xy 85.783166 -63.0301) (xy 85.787797 -63.019622) (xy 85.788064 -62.996739) (xy 85.783674 -62.986158)
			(xy 85.780118 -62.978538) (xy 85.773768 -62.972188) (xy 85.753591 -62.95069) (xy 85.719437 -62.902634)
			(xy 85.693084 -62.849895) (xy 85.675159 -62.793729) (xy 85.666089 -62.735474) (xy 85.665564 -62.705996)
			(xy 85.66605 -62.678744) (xy 85.673807 -62.624795) (xy 85.689162 -62.5725) (xy 85.711803 -62.522921)
			(xy 85.741269 -62.477069) (xy 85.77696 -62.435877) (xy 85.81815 -62.400183) (xy 85.864 -62.370715)
			(xy 85.913577 -62.34807) (xy 85.965872 -62.332712) (xy 86.01982 -62.324952) (xy 86.047072 -62.324488)
			(xy 86.068985 -62.324764) (xy 86.112528 -62.329728) (xy 86.13394 -62.334394) (xy 86.142911 -62.336073)
			(xy 86.160998 -62.33373) (xy 86.169246 -62.329822) (xy 86.173564 -62.327282) (xy 86.178287 -62.323982)
			(xy 86.18623 -62.315641) (xy 86.189312 -62.310772) (xy 86.18982 -62.309756) (xy 86.224872 -62.247526)
			(xy 86.244684 -62.211966) (xy 86.247383 -62.206754) (xy 86.250591 -62.195467) (xy 86.251034 -62.189614)
			(xy 86.251542 -62.179708) (xy 86.248494 -62.170818) (xy 86.23993 -62.143005) (xy 86.230361 -62.085605)
			(xy 86.229444 -62.056518) (xy 86.229444 -62.051438) (xy 86.229939 -62.023716) (xy 86.237962 -61.968857)
			(xy 86.253845 -61.915737) (xy 86.277252 -61.865477) (xy 86.307691 -61.819136) (xy 86.344519 -61.777692)
			(xy 86.38696 -61.742018) (xy 86.434121 -61.712865) (xy 86.485005 -61.690849) (xy 86.511638 -61.683138)
			(xy 86.511892 -61.683138) (xy 86.514686 -61.682376) (xy 86.523507 -61.678987) (xy 86.538102 -61.667006)
			(xy 86.543134 -61.659008) (xy 86.571328 -61.60262) (xy 86.574884 -61.592968) (xy 86.630764 -61.382148)
			(xy 86.64067 -61.34481) (xy 86.816438 -60.682124) (xy 86.815422 -60.672726) (xy 86.81339 -60.634118)
			(xy 86.81339 -60.632848) (xy 86.81397 -60.60321) (xy 86.823172 -60.544653) (xy 86.841315 -60.488222)
			(xy 86.867963 -60.435274) (xy 86.884764 -60.410852) (xy 86.890352 -60.403486) (xy 86.916006 -60.30595)
			(xy 86.98103 -60.060332) (xy 86.995762 -60.004706) (xy 86.99754 -59.991752) (xy 86.99754 -58.819288)
			(xy 86.997365 -58.813136) (xy 86.994401 -58.801195) (xy 86.991698 -58.795666) (xy 86.975696 -58.765186)
			(xy 86.971124 -58.761884) (xy 86.96833 -58.760106) (xy 86.966044 -58.758328) (xy 86.94553 -58.742874)
			(xy 86.908439 -58.707345) (xy 86.876449 -58.667163) (xy 86.850136 -58.623054) (xy 86.829977 -58.575814)
			(xy 86.816336 -58.526297) (xy 86.809458 -58.475399) (xy 86.809072 -58.449718) (xy 86.810596 -58.416698)
			(xy 86.811866 -58.405014) (xy 86.815495 -58.37836) (xy 86.82928 -58.326363) (xy 86.850231 -58.276819)
			(xy 86.877935 -58.230709) (xy 86.911841 -58.188948) (xy 86.931246 -58.170318) (xy 86.931754 -58.16981)
			(xy 86.932008 -58.169556) (xy 86.936031 -58.165527) (xy 86.942313 -58.156036) (xy 86.944454 -58.15076)
			(xy 86.946486 -58.145426) (xy 86.948264 -58.133742) (xy 86.659212 -55.372762) (xy 86.577678 -54.592474)
			(xy 86.576925 -54.586971) (xy 86.573333 -54.576463) (xy 86.570566 -54.571646) (xy 86.567625 -54.56696)
			(xy 86.560065 -54.558884) (xy 86.55558 -54.555644) (xy 86.555326 -54.555644) (xy 86.5334 -54.540388)
			(xy 86.493635 -54.504726) (xy 86.459232 -54.463866) (xy 86.430863 -54.418608) (xy 86.409082 -54.369836)
			(xy 86.394316 -54.318503) (xy 86.386852 -54.265613) (xy 86.386416 -54.238906) (xy 86.386494 -54.226168)
			(xy 86.388147 -54.200747) (xy 86.389718 -54.188106) (xy 86.394354 -54.158019) (xy 86.411938 -54.099742)
			(xy 86.438571 -54.045005) (xy 86.473573 -53.995203) (xy 86.494366 -53.972968) (xy 86.49843 -53.968904)
			(xy 86.504018 -53.959506) (xy 86.50605 -53.954172) (xy 86.507647 -53.948867) (xy 86.5088 -53.937849)
			(xy 86.508336 -53.932328) (xy 86.456012 -53.430424) (xy 86.279482 -51.744626) (xy 86.278259 -51.736174)
			(xy 86.270985 -51.720736) (xy 86.265258 -51.7144) (xy 86.259162 -51.708304) (xy 86.243668 -51.700684)
			(xy 86.234524 -51.699668) (xy 86.205946 -51.69598) (xy 86.150277 -51.681114) (xy 86.097473 -51.658054)
			(xy 86.048732 -51.627322) (xy 86.005162 -51.589616) (xy 85.967751 -51.545793) (xy 85.952076 -51.521614)
			(xy 85.94852 -51.515518) (xy 85.945726 -51.511454) (xy 85.936328 -51.505358) (xy 85.931249 -51.502344)
			(xy 85.920087 -51.498497) (xy 85.91423 -51.497738) (xy 85.904578 -51.496722) (xy 85.90407 -51.496722)
			(xy 85.840062 -51.490372) (xy 85.834474 -51.489864) (xy 85.828599 -51.489444) (xy 85.816926 -51.490985)
			(xy 85.81136 -51.492912) (xy 85.800438 -51.496976) (xy 85.79231 -51.505612) (xy 85.774247 -51.52415)
			(xy 85.733983 -51.556676) (xy 85.689694 -51.583464) (xy 85.642192 -51.604021) (xy 85.592347 -51.617972)
			(xy 85.541075 -51.625059) (xy 85.515196 -51.6255) (xy 85.514688 -51.6255) (xy 85.51418 -51.6255)
			(xy 85.497416 -51.625246) (xy 85.497162 -51.624992) (xy 85.470751 -51.623339) (xy 85.418726 -51.613653)
			(xy 85.368539 -51.596871) (xy 85.321153 -51.573316) (xy 85.277475 -51.543438) (xy 85.238346 -51.507812)
			(xy 85.204514 -51.467121) (xy 85.176629 -51.422146) (xy 85.155227 -51.373748) (xy 85.140717 -51.322858)
			(xy 85.133379 -51.270451) (xy 85.132926 -51.243992) (xy 85.133351 -51.218481) (xy 85.140147 -51.167913)
			(xy 85.153615 -51.118701) (xy 85.173517 -51.07172) (xy 85.199498 -51.027808) (xy 85.214968 -51.007518)
			(xy 85.217508 -51.00447) (xy 85.218524 -51.002946) (xy 85.221826 -50.996342) (xy 85.224169 -50.991119)
			(xy 85.226735 -50.979966) (xy 85.226906 -50.974244) (xy 85.226906 -50.94224) (xy 85.238082 -50.94224)
			(xy 85.238082 -50.89144) (xy 85.237747 -50.882836) (xy 85.232035 -50.866606) (xy 85.226906 -50.85969)
			(xy 85.225636 -50.858166) (xy 85.208243 -50.837289) (xy 85.178927 -50.791539) (xy 85.1564 -50.742091)
			(xy 85.141119 -50.689946) (xy 85.133394 -50.636161) (xy 85.132926 -50.608992) (xy 85.13339 -50.58174)
			(xy 85.141148 -50.527792) (xy 85.156505 -50.475497) (xy 85.179148 -50.42592) (xy 85.208617 -50.380071)
			(xy 85.244311 -50.338882) (xy 85.285504 -50.303192) (xy 85.331357 -50.273728) (xy 85.380937 -50.25109)
			(xy 85.433233 -50.235739) (xy 85.487182 -50.227987) (xy 85.514434 -50.227484) (xy 85.542474 -50.227982)
			(xy 85.59795 -50.236199) (xy 85.651624 -50.252451) (xy 85.70234 -50.276387) (xy 85.749004 -50.307491)
			(xy 85.790611 -50.345093) (xy 85.80882 -50.366422) (xy 85.809074 -50.366676) (xy 85.815932 -50.374804)
			(xy 85.839554 -50.386488) (xy 85.845904 -50.389536) (xy 85.850796 -50.39161) (xy 85.861168 -50.393904)
			(xy 85.866478 -50.394108) (xy 85.924136 -50.394108) (xy 85.93455 -50.393092) (xy 85.946234 -50.389028)
			(xy 85.965538 -50.379376) (xy 85.969717 -50.377214) (xy 85.977251 -50.371581) (xy 85.980524 -50.3682)
			(xy 85.982048 -50.366168) (xy 85.996542 -50.349113) (xy 86.028882 -50.318169) (xy 86.046564 -50.304446)
			(xy 86.057984 -50.295986) (xy 86.081886 -50.280604) (xy 86.094316 -50.273712) (xy 86.102698 -50.269394)
			(xy 86.107778 -50.2666) (xy 86.11489 -50.25263) (xy 86.118113 -50.245932) (xy 86.12094 -50.231347)
			(xy 86.120478 -50.223928) (xy 86.09584 -49.98847) (xy 86.09388 -49.976037) (xy 86.079756 -49.955241)
			(xy 86.068916 -49.948846) (xy 86.031578 -49.929288) (xy 85.993224 -49.908968) (xy 85.98196 -49.903965)
			(xy 85.957342 -49.904385) (xy 85.946234 -49.90973) (xy 85.918077 -49.924337) (xy 85.858123 -49.945036)
			(xy 85.795575 -49.955561) (xy 85.763862 -49.956212) (xy 85.738351 -49.955785) (xy 85.687785 -49.948987)
			(xy 85.638574 -49.935516) (xy 85.591595 -49.915613) (xy 85.547684 -49.889632) (xy 85.527388 -49.87417)
			(xy 85.52434 -49.87163) (xy 85.522816 -49.870614) (xy 85.516212 -49.867312) (xy 85.510989 -49.86497)
			(xy 85.499835 -49.86241) (xy 85.494114 -49.862232) (xy 85.46211 -49.862232) (xy 85.46211 -49.851056)
			(xy 85.41131 -49.851056) (xy 85.402709 -49.851396) (xy 85.386486 -49.857119) (xy 85.37956 -49.862232)
			(xy 85.378036 -49.863502) (xy 85.357159 -49.880896) (xy 85.31141 -49.910213) (xy 85.261962 -49.93274)
			(xy 85.209817 -49.948019) (xy 85.156031 -49.955741) (xy 85.128862 -49.956212) (xy 85.103351 -49.955785)
			(xy 85.052785 -49.948987) (xy 85.003574 -49.935516) (xy 84.956595 -49.915613) (xy 84.912684 -49.889632)
			(xy 84.892388 -49.87417) (xy 84.88934 -49.87163) (xy 84.887816 -49.870614) (xy 84.881212 -49.867312)
			(xy 84.875989 -49.86497) (xy 84.864835 -49.86241) (xy 84.859114 -49.862232) (xy 84.82711 -49.862232)
			(xy 84.82711 -49.851056) (xy 84.77631 -49.851056) (xy 84.767709 -49.851396) (xy 84.751486 -49.857119)
			(xy 84.74456 -49.862232) (xy 84.743036 -49.863502) (xy 84.722159 -49.880896) (xy 84.67641 -49.910213)
			(xy 84.626962 -49.93274) (xy 84.574817 -49.948019) (xy 84.521031 -49.955741) (xy 84.493862 -49.956212)
			(xy 84.466612 -49.955724) (xy 84.412668 -49.947963) (xy 84.360377 -49.932604) (xy 84.310804 -49.909961)
			(xy 84.264958 -49.880493) (xy 84.223772 -49.844801) (xy 84.188084 -49.803611) (xy 84.158621 -49.757762)
			(xy 84.135983 -49.708187) (xy 84.120629 -49.655895) (xy 84.112874 -49.60195) (xy 84.112874 -49.54745)
			(xy 84.120629 -49.493505) (xy 84.135983 -49.441213) (xy 84.158621 -49.391638) (xy 84.188084 -49.345789)
			(xy 84.223772 -49.304599) (xy 84.264958 -49.268907) (xy 84.310804 -49.239439) (xy 84.360377 -49.216796)
			(xy 84.412668 -49.201437) (xy 84.466612 -49.193676) (xy 84.493862 -49.193196) (xy 84.519372 -49.193625)
			(xy 84.569937 -49.200426) (xy 84.619146 -49.2139) (xy 84.666123 -49.233805) (xy 84.710031 -49.259788)
			(xy 84.730336 -49.275238) (xy 84.733384 -49.277778) (xy 84.734908 -49.278794) (xy 84.741512 -49.282096)
			(xy 84.746736 -49.284435) (xy 84.757889 -49.28699) (xy 84.76361 -49.287176) (xy 84.795614 -49.287176)
			(xy 84.795614 -49.298352) (xy 84.846414 -49.298352) (xy 84.85502 -49.298025) (xy 84.871259 -49.292321)
			(xy 84.878164 -49.287176) (xy 84.879688 -49.285906) (xy 84.900565 -49.268513) (xy 84.946315 -49.239198)
			(xy 84.995763 -49.216674) (xy 85.047908 -49.201398) (xy 85.101694 -49.193679) (xy 85.128862 -49.193196)
			(xy 85.154372 -49.193625) (xy 85.204937 -49.200426) (xy 85.254146 -49.2139) (xy 85.301123 -49.233805)
			(xy 85.345031 -49.259788) (xy 85.365336 -49.275238) (xy 85.368384 -49.277778) (xy 85.369908 -49.278794)
			(xy 85.376512 -49.282096) (xy 85.381736 -49.284435) (xy 85.392889 -49.28699) (xy 85.39861 -49.287176)
			(xy 85.430614 -49.287176) (xy 85.430614 -49.298352) (xy 85.481414 -49.298352) (xy 85.49002 -49.298025)
			(xy 85.506259 -49.292321) (xy 85.513164 -49.287176) (xy 85.514688 -49.285906) (xy 85.522054 -49.279302)
			(xy 85.52307 -49.278794) (xy 85.52434 -49.277778) (xy 85.524848 -49.27727) (xy 85.546946 -49.26076)
			(xy 85.57895 -49.240948) (xy 85.579204 -49.240948) (xy 85.579458 -49.240694) (xy 85.584256 -49.237838)
			(xy 85.592584 -49.230403) (xy 85.595968 -49.225962) (xy 85.599524 -49.221136) (xy 85.603842 -49.210468)
			(xy 85.61578 -49.13503) (xy 85.616398 -49.124369) (xy 85.609966 -49.104031) (xy 85.603334 -49.09566)
			(xy 79.777844 -42.736516) (xy 79.770654 -42.729954) (xy 79.752754 -42.72235) (xy 79.733309 -42.721989)
			(xy 79.715138 -42.728923) (xy 79.70774 -42.735246) (xy 79.704184 -42.738548) (xy 79.698088 -42.744136)
			(xy 79.689706 -42.768012) (xy 79.691738 -42.780712) (xy 79.693922 -42.79522) (xy 79.696338 -42.824462)
			(xy 79.696564 -42.839132) (xy 79.696564 -42.84091) (xy 79.696077 -42.868157) (xy 79.688321 -42.922097)
			(xy 79.672967 -42.974384) (xy 79.650328 -43.023953) (xy 79.620866 -43.069797) (xy 79.585179 -43.110981)
			(xy 79.543995 -43.146667) (xy 79.498152 -43.176129) (xy 79.448582 -43.198768) (xy 79.396295 -43.214121)
			(xy 79.342355 -43.221877) (xy 79.287861 -43.221878) (xy 79.233921 -43.214124) (xy 79.181633 -43.198773)
			(xy 79.132062 -43.176137) (xy 79.086218 -43.146677) (xy 79.045032 -43.110992) (xy 79.009344 -43.06981)
			(xy 78.979879 -43.023967) (xy 78.957239 -42.974399) (xy 78.941883 -42.922113) (xy 78.934124 -42.868173)
			(xy 78.93412 -42.813679) (xy 78.941872 -42.759738) (xy 78.957221 -42.70745) (xy 78.979854 -42.657878)
			(xy 79.009312 -42.612032) (xy 79.044995 -42.570845) (xy 79.086176 -42.535154) (xy 79.132017 -42.505688)
			(xy 79.181584 -42.483045) (xy 79.23387 -42.467687) (xy 79.287809 -42.459925) (xy 79.315056 -42.459402)
			(xy 79.33815 -42.459753) (xy 79.383998 -42.465354) (xy 79.406496 -42.470578) (xy 79.414116 -42.472356)
			(xy 79.429102 -42.471594) (xy 79.443072 -42.466514) (xy 79.45501 -42.45737) (xy 79.45755 -42.453814)
			(xy 79.497428 -42.39895) (xy 79.503015 -42.390616) (xy 79.507737 -42.371134) (xy 79.504583 -42.351336)
			(xy 79.499714 -42.342562) (xy 79.159862 -41.787064) (xy 78.899004 -41.360344) (xy 78.896432 -41.356346)
			(xy 78.890045 -41.349306) (xy 78.886304 -41.346374) (xy 78.878938 -41.340786) (xy 78.869032 -41.337992)
			(xy 78.842966 -41.3299) (xy 78.793288 -41.307299) (xy 78.747337 -41.277848) (xy 78.706053 -41.24215)
			(xy 78.670277 -41.200932) (xy 78.640742 -41.155036) (xy 78.618048 -41.1054) (xy 78.602661 -41.053036)
			(xy 78.594893 -40.999013) (xy 78.594458 -40.971724) (xy 78.594458 -40.969692) (xy 78.594733 -40.951928)
			(xy 78.598164 -40.916564) (xy 78.601316 -40.89908) (xy 78.601824 -40.896032) (xy 78.603094 -40.889936)
			(xy 78.60157 -40.881046) (xy 78.600597 -40.876409) (xy 78.597148 -40.867584) (xy 78.594712 -40.86352)
			(xy 78.297024 -40.37711) (xy 78.293647 -40.371994) (xy 78.284919 -40.363391) (xy 78.279752 -40.360092)
			(xy 78.269084 -40.353742) (xy 78.262226 -40.353234) (xy 78.256384 -40.35298) (xy 78.227868 -40.350874)
			(xy 78.171896 -40.339198) (xy 78.118293 -40.319301) (xy 78.068258 -40.291629) (xy 78.022912 -40.256801)
			(xy 77.98327 -40.215598) (xy 77.950219 -40.16894) (xy 77.924501 -40.117874) (xy 77.906689 -40.063542)
			(xy 77.897184 -40.00716) (xy 77.896212 -39.978584) (xy 77.896212 -39.971472) (xy 77.896647 -39.946615)
			(xy 77.903171 -39.89733) (xy 77.916041 -39.849309) (xy 77.925168 -39.826184) (xy 77.928978 -39.816786)
			(xy 77.931518 -39.811452) (xy 77.93355 -39.79926) (xy 77.933296 -39.793418) (xy 77.93265 -39.787443)
			(xy 77.928928 -39.77602) (xy 77.92593 -39.770812) (xy 77.568044 -39.186104) (xy 77.559408 -39.180008)
			(xy 77.52115 -39.152732) (xy 77.449397 -39.092058) (xy 77.383657 -39.024918) (xy 77.353668 -38.988746)
			(xy 77.35316 -38.988238) (xy 77.349858 -38.984174) (xy 77.341222 -38.977316) (xy 77.317346 -38.965886)
			(xy 77.31202 -38.963427) (xy 77.300604 -38.960738) (xy 77.29474 -38.960552) (xy 77.224382 -38.961314)
			(xy 77.213221 -38.962344) (xy 77.193335 -38.972626) (xy 77.186028 -38.981126) (xy 77.185774 -38.98138)
			(xy 77.167636 -39.004408) (xy 77.125484 -39.045141) (xy 77.077595 -39.078942) (xy 77.025096 -39.105016)
			(xy 76.969225 -39.122746) (xy 76.911298 -39.131716) (xy 76.88199 -39.132256) (xy 76.8713 -39.132212)
			(xy 76.849951 -39.13107) (xy 76.839318 -39.12997) (xy 76.839064 -39.12997) (xy 76.837286 -39.129716)
			(xy 76.809224 -39.125889) (xy 76.754578 -39.111013) (xy 76.702734 -39.088217) (xy 76.654833 -39.058002)
			(xy 76.611929 -39.021033) (xy 76.574966 -38.978124) (xy 76.55941 -38.954456) (xy 76.556616 -38.949884)
			(xy 76.556362 -38.949376) (xy 76.551536 -38.944804) (xy 76.543154 -38.938454) (xy 76.51242 -38.919658)
			(xy 76.498958 -38.918896) (xy 76.429616 -38.914324) (xy 76.418772 -38.914102) (xy 76.398486 -38.92172)
			(xy 76.3905 -38.929056) (xy 76.38669 -38.932866) (xy 76.384912 -38.935152) (xy 76.38415 -38.936168)
			(xy 76.365939 -38.958794) (xy 76.323832 -38.998798) (xy 76.276157 -39.031968) (xy 76.22401 -39.05754)
			(xy 76.168593 -39.074925) (xy 76.111184 -39.083722) (xy 76.082144 -39.08425) (xy 76.08189 -39.08425)
			(xy 76.054636 -39.083763) (xy 76.000684 -39.076005) (xy 75.948384 -39.060647) (xy 75.898803 -39.038003)
			(xy 75.852949 -39.008533) (xy 75.811755 -38.972838) (xy 75.776061 -38.931643) (xy 75.746592 -38.885788)
			(xy 75.723949 -38.836206) (xy 75.708593 -38.783907) (xy 75.700836 -38.729954) (xy 75.700836 -38.675446)
			(xy 75.708593 -38.621493) (xy 75.723949 -38.569194) (xy 75.746592 -38.519612) (xy 75.776061 -38.473757)
			(xy 75.811755 -38.432562) (xy 75.852949 -38.396867) (xy 75.898803 -38.367397) (xy 75.948384 -38.344753)
			(xy 76.000684 -38.329395) (xy 76.054636 -38.321637) (xy 76.08189 -38.321234) (xy 76.10936 -38.321712)
			(xy 76.163732 -38.32959) (xy 76.216413 -38.345185) (xy 76.266312 -38.368174) (xy 76.312398 -38.398082)
			(xy 76.353718 -38.43429) (xy 76.389418 -38.476051) (xy 76.40447 -38.499034) (xy 76.407772 -38.504368)
			(xy 76.411836 -38.508432) (xy 76.420726 -38.515036) (xy 76.440284 -38.527228) (xy 76.442062 -38.528244)
			(xy 76.446407 -38.530541) (xy 76.455745 -38.533603) (xy 76.460604 -38.53434) (xy 76.463906 -38.534594)
			(xy 76.467462 -38.534848) (xy 76.534518 -38.539166) (xy 76.538616 -38.539383) (xy 76.546788 -38.538618)
			(xy 76.550774 -38.537642) (xy 76.556616 -38.53561) (xy 76.558394 -38.534848) (xy 76.559664 -38.53434)
			(xy 76.565033 -38.531603) (xy 76.574407 -38.524032) (xy 76.578206 -38.519354) (xy 76.57846 -38.5191)
			(xy 76.580238 -38.51656) (xy 76.598727 -38.493707) (xy 76.641534 -38.453425) (xy 76.690013 -38.420186)
			(xy 76.743016 -38.394775) (xy 76.770992 -38.38575) (xy 76.795691 -38.37865) (xy 76.84641 -38.370372)
			(xy 76.872084 -38.36924) (xy 76.878434 -38.368986) (xy 76.888848 -38.363652) (xy 76.894226 -38.360678)
			(xy 76.903465 -38.352579) (xy 76.907136 -38.34765) (xy 76.92517 -38.321996) (xy 76.927964 -38.317678)
			(xy 76.932548 -38.308396) (xy 76.934637 -38.287819) (xy 76.932028 -38.2778) (xy 76.922365 -38.250424)
			(xy 76.905844 -38.194763) (xy 76.899008 -38.166548) (xy 76.897484 -38.159436) (xy 76.89723 -38.158674)
			(xy 76.880212 -38.130988) (xy 76.874116 -38.125654) (xy 76.841096 -38.096444) (xy 76.807975 -38.065096)
			(xy 76.74697 -37.997302) (xy 76.692396 -37.92423) (xy 76.668122 -37.885624) (xy 76.409296 -37.462968)
			(xy 76.393431 -37.436649) (xy 76.364581 -37.382382) (xy 76.351638 -37.35451) (xy 76.335382 -37.31641)
			(xy 76.333858 -37.3126) (xy 76.245212 -37.168328) (xy 76.22368 -37.132477) (xy 76.186039 -37.05779)
			(xy 76.154836 -36.980193) (xy 76.130292 -36.90024) (xy 76.121006 -36.859464) (xy 76.11237 -36.814252)
			(xy 76.110846 -36.8046) (xy 76.084176 -36.760912) (xy 76.07681 -36.755324) (xy 76.05667 -36.739192)
			(xy 76.020505 -36.702386) (xy 75.989641 -36.661033) (xy 75.964644 -36.615892) (xy 75.95489 -36.592002)
			(xy 75.95108 -36.582096) (xy 75.515978 -36.143438) (xy 75.508733 -36.13753) (xy 75.491281 -36.130877)
			(xy 75.481942 -36.130484) (xy 75.477624 -36.130484) (xy 75.467662 -36.130972) (xy 75.449239 -36.13856)
			(xy 75.44181 -36.145216) (xy 75.441556 -36.14547) (xy 75.419931 -36.166449) (xy 75.371297 -36.202007)
			(xy 75.317679 -36.229482) (xy 75.260412 -36.248192) (xy 75.200915 -36.257671) (xy 75.170792 -36.258246)
			(xy 75.143057 -36.257741) (xy 75.088174 -36.249695) (xy 75.035034 -36.233789) (xy 74.984756 -36.210358)
			(xy 74.9384 -36.179894) (xy 74.896943 -36.143041) (xy 74.861257 -36.100575) (xy 74.832095 -36.05339)
			(xy 74.810071 -36.00248) (xy 74.795648 -35.948918) (xy 74.791824 -35.921442) (xy 74.790046 -35.906202)
			(xy 74.78903 -35.87242) (xy 74.789538 -35.862006) (xy 74.789538 -35.861752) (xy 74.790941 -35.836528)
			(xy 74.799571 -35.786752) (xy 74.814689 -35.738548) (xy 74.836031 -35.692758) (xy 74.863225 -35.650182)
			(xy 74.8792 -35.630612) (xy 74.88501 -35.623135) (xy 74.891148 -35.605234) (xy 74.890392 -35.586326)
			(xy 74.882843 -35.568974) (xy 74.876406 -35.562032) (xy 74.840084 -35.525456) (xy 74.677778 -35.363404)
			(xy 74.64044 -35.32378) (xy 74.638408 -35.321494) (xy 74.632058 -35.314382) (xy 74.623676 -35.310064)
			(xy 74.619249 -35.307876) (xy 74.609783 -35.305071) (xy 74.60488 -35.304476) (xy 74.587862 -35.302952)
			(xy 74.583311 -35.30269) (xy 74.57424 -35.303584) (xy 74.569828 -35.30473) (xy 74.561192 -35.307016)
			(xy 74.553064 -35.313366) (xy 74.515803 -35.341176) (xy 74.436994 -35.390524) (xy 74.353933 -35.432321)
			(xy 74.267342 -35.466203) (xy 74.177972 -35.491876) (xy 74.0866 -35.509117) (xy 73.99402 -35.517777)
			(xy 73.947528 -35.518344) (xy 73.947274 -35.518344) (xy 73.904782 -35.5179) (xy 73.820106 -35.510666)
			(xy 73.736352 -35.496253) (xy 73.654129 -35.474765) (xy 73.574033 -35.446358) (xy 73.496644 -35.411239)
			(xy 73.422524 -35.369662) (xy 73.352212 -35.321929) (xy 73.286216 -35.268385) (xy 73.225015 -35.20942)
			(xy 73.196704 -35.17773) (xy 73.168632 -35.144917) (xy 73.117633 -35.075222) (xy 73.09485 -35.038538)
			(xy 73.09231 -35.034474) (xy 73.079864 -35.020758) (xy 73.076562 -35.018218) (xy 73.054423 -35.000023)
			(xy 73.015328 -34.958127) (xy 72.98293 -34.910862) (xy 72.957955 -34.859287) (xy 72.940963 -34.804561)
			(xy 72.932335 -34.747911) (xy 72.931782 -34.71926) (xy 72.931782 -34.718752) (xy 72.931782 -34.711894)
			(xy 72.932798 -34.689796) (xy 72.934576 -34.671762) (xy 72.936802 -34.655134) (xy 72.9438 -34.622321)
			(xy 72.948546 -34.60623) (xy 72.95007 -34.599118) (xy 72.951848 -34.588196) (xy 72.951848 -34.584386)
			(xy 72.951594 -34.581592) (xy 72.949816 -34.521902) (xy 72.949816 -34.520886) (xy 72.950248 -34.478939)
			(xy 72.957293 -34.39534) (xy 72.971332 -34.312628) (xy 72.992267 -34.231387) (xy 73.019948 -34.15219)
			(xy 73.036684 -34.113724) (xy 73.038462 -34.10966) (xy 73.043034 -34.089594) (xy 73.043034 -34.088578)
			(xy 73.039478 -34.073338) (xy 73.03643 -34.063686) (xy 73.01975 -34.025283) (xy 72.992142 -33.946233)
			(xy 72.971263 -33.865144) (xy 72.957262 -33.78259) (xy 72.950238 -33.699153) (xy 72.949816 -33.657286)
			(xy 72.951848 -33.595564) (xy 72.95261 -33.584134) (xy 72.95007 -33.576006) (xy 72.948118 -33.571242)
			(xy 72.942613 -33.562543) (xy 72.939148 -33.558734) (xy 72.91959 -33.53816) (xy 72.915526 -33.53435)
			(xy 72.909335 -33.529553) (xy 72.894853 -33.523611) (xy 72.887078 -33.522666) (xy 72.88276 -33.522412)
			(xy 72.432926 -33.522412) (xy 72.382866 -33.521054) (xy 72.28338 -33.509543) (xy 72.185549 -33.488119)
			(xy 72.090357 -33.456998) (xy 72.044306 -33.437322) (xy 72.03948 -33.43529) (xy 72.019414 -33.430718)
			(xy 72.018652 -33.430718) (xy 71.984616 -33.444434) (xy 71.977758 -33.450784) (xy 71.943365 -33.481469)
			(xy 71.869833 -33.537054) (xy 71.791484 -33.585615) (xy 71.708988 -33.626738) (xy 71.623048 -33.660072)
			(xy 71.5344 -33.685332) (xy 71.443798 -33.702303) (xy 71.352017 -33.71084) (xy 71.305928 -33.711388)
			(xy 71.305166 -33.711388) (xy 71.258694 -33.710848) (xy 71.166155 -33.702191) (xy 71.074823 -33.684963)
			(xy 70.985488 -33.659315) (xy 70.898927 -33.625468) (xy 70.815889 -33.583717) (xy 70.737095 -33.534422)
			(xy 70.663228 -33.478013) (xy 70.594928 -33.414977) (xy 70.532787 -33.345861) (xy 70.477344 -33.271265)
			(xy 70.452742 -33.231836) (xy 70.451218 -33.22955) (xy 70.450202 -33.227772) (xy 70.447685 -33.223792)
			(xy 70.441421 -33.216759) (xy 70.437756 -33.213802) (xy 70.415131 -33.19559) (xy 70.37513 -33.153484)
			(xy 70.341964 -33.105807) (xy 70.316397 -33.05366) (xy 70.299018 -32.998244) (xy 70.290227 -32.940835)
			(xy 70.289674 -32.911796) (xy 70.289674 -32.911034) (xy 70.290179 -32.882599) (xy 70.298597 -32.826357)
			(xy 70.306438 -32.79902) (xy 70.307962 -32.791908) (xy 70.30974 -32.780986) (xy 70.30974 -32.777176)
			(xy 70.309486 -32.774382) (xy 70.308601 -32.758586) (xy 70.307711 -32.726957) (xy 70.307708 -32.711136)
			(xy 70.307708 -32.710882) (xy 70.308285 -32.669349) (xy 70.315488 -32.586591) (xy 70.329544 -32.504719)
			(xy 70.350355 -32.424298) (xy 70.377777 -32.345884) (xy 70.394322 -32.307784) (xy 70.39737 -32.298132)
			(xy 70.400926 -32.282892) (xy 70.400926 -32.281876) (xy 70.39737 -32.266636) (xy 70.394322 -32.257238)
			(xy 70.379254 -32.222552) (xy 70.353796 -32.151334) (xy 70.3338 -32.078394) (xy 70.32625 -32.041338)
			(xy 70.317596 -31.994124) (xy 70.308312 -31.898581) (xy 70.307708 -31.850584) (xy 70.307708 -31.843472)
			(xy 70.309486 -31.789878) (xy 70.30974 -31.78683) (xy 70.30974 -31.78302) (xy 70.307962 -31.772098)
			(xy 70.306438 -31.76524) (xy 70.298609 -31.7379) (xy 70.290189 -31.68166) (xy 70.289674 -31.653226)
			(xy 70.289674 -31.652972) (xy 70.290219 -31.623902) (xy 70.299029 -31.566432) (xy 70.31644 -31.510959)
			(xy 70.342053 -31.458764) (xy 70.375274 -31.411049) (xy 70.415339 -31.368916) (xy 70.43801 -31.350712)
			(xy 70.44309 -31.34614) (xy 70.448932 -31.339028) (xy 70.471716 -31.30176) (xy 70.522874 -31.230949)
			(xy 70.580034 -31.164889) (xy 70.642758 -31.104087) (xy 70.710564 -31.049009) (xy 70.782932 -31.000079)
			(xy 70.859305 -30.957671) (xy 70.89902 -30.939486) (xy 70.937384 -30.92286) (xy 71.016345 -30.895343)
			(xy 71.097333 -30.874532) (xy 71.179778 -30.860575) (xy 71.263103 -30.853567) (xy 71.304912 -30.853126)
			(xy 71.305166 -30.853126) (xy 71.347747 -30.853575) (xy 71.432599 -30.86084) (xy 71.516522 -30.875312)
			(xy 71.598907 -30.896885) (xy 71.679152 -30.925402) (xy 71.756675 -30.960656) (xy 71.83091 -31.00239)
			(xy 71.901318 -31.050299) (xy 71.967385 -31.104037) (xy 71.998332 -31.133288) (xy 72.004597 -31.137828)
			(xy 72.019074 -31.143267) (xy 72.02678 -31.143956) (xy 72.876918 -31.143956) (xy 72.883776 -31.143448)
			(xy 72.892564 -31.141911) (xy 72.908335 -31.133592) (xy 72.920281 -31.120356) (xy 72.923908 -31.112206)
			(xy 72.932544 -31.09087) (xy 72.933306 -31.08325) (xy 72.933306 -31.082996) (xy 72.934068 -31.07563)
			(xy 72.936245 -31.057836) (xy 72.943495 -31.022726) (xy 72.948546 -31.005526) (xy 72.95007 -30.998414)
			(xy 72.951848 -30.987492) (xy 72.951848 -30.983682) (xy 72.951594 -30.980888) (xy 72.949816 -30.92069)
			(xy 72.950257 -30.878825) (xy 72.957296 -30.79539) (xy 72.971298 -30.712838) (xy 72.992165 -30.631748)
			(xy 73.019751 -30.552692) (xy 73.03643 -30.51429) (xy 73.039478 -30.504638) (xy 73.043034 -30.489398)
			(xy 73.043034 -30.488382) (xy 73.038462 -30.468316) (xy 73.036684 -30.464252) (xy 73.017126 -30.419035)
			(xy 72.985977 -30.325565) (xy 72.964182 -30.229482) (xy 72.951954 -30.13172) (xy 72.95007 -30.08249)
			(xy 72.949816 -30.058614) (xy 72.949816 -30.056836) (xy 72.95007 -30.034738) (xy 72.950324 -30.03042)
			(xy 72.950324 -30.029912) (xy 72.950578 -30.021784) (xy 72.950578 -30.019752) (xy 72.946768 -30.0101)
			(xy 72.944796 -30.005619) (xy 72.939428 -29.997434) (xy 72.9361 -29.993844) (xy 72.891904 -29.948632)
			(xy 72.884668 -29.942382) (xy 72.866912 -29.935329) (xy 72.85736 -29.934916) (xy 72.845676 -29.934916)
			(xy 72.798954 -29.934342) (xy 72.705933 -29.925458) (xy 72.614167 -29.90783) (xy 72.524476 -29.881614)
			(xy 72.437661 -29.847046) (xy 72.395842 -29.826204) (xy 72.390415 -29.823622) (xy 72.378735 -29.820802)
			(xy 72.372728 -29.820616) (xy 72.039226 -29.820616) (xy 72.034336 -29.820755) (xy 72.024745 -29.822677)
			(xy 72.020176 -29.824426) (xy 71.99503 -29.834586) (xy 71.987918 -29.84119) (xy 71.953424 -29.872858)
			(xy 71.87946 -29.930292) (xy 71.800439 -29.980544) (xy 71.717058 -30.023171) (xy 71.630049 -30.057798)
			(xy 71.540179 -30.08412) (xy 71.448238 -30.101906) (xy 71.355035 -30.110999) (xy 71.308214 -30.1117)
			(xy 71.298308 -30.1117) (xy 71.251479 -30.110838) (xy 71.158286 -30.101403) (xy 71.066389 -30.083274)
			(xy 70.976595 -30.05661) (xy 70.889697 -30.021646) (xy 70.806459 -29.978689) (xy 70.727615 -29.928118)
			(xy 70.653858 -29.870379) (xy 70.585839 -29.80598) (xy 70.554596 -29.771086) (xy 70.526525 -29.738272)
			(xy 70.47553 -29.668575) (xy 70.452742 -29.631894) (xy 70.450202 -29.62783) (xy 70.437756 -29.614114)
			(xy 70.434454 -29.611574) (xy 70.412313 -29.59338) (xy 70.373212 -29.551485) (xy 70.340808 -29.504221)
			(xy 70.315825 -29.452647) (xy 70.298826 -29.39792) (xy 70.290191 -29.341268) (xy 70.289674 -29.312616)
			(xy 70.289674 -29.312108) (xy 70.289674 -29.30525) (xy 70.29069 -29.283152) (xy 70.294754 -29.249116)
			(xy 70.296838 -29.237353) (xy 70.302302 -29.214094) (xy 70.305676 -29.202634) (xy 70.305676 -29.202126)
			(xy 70.307454 -29.196284) (xy 70.30974 -29.181552) (xy 70.30974 -29.177742) (xy 70.309486 -29.174948)
			(xy 70.307708 -29.114496) (xy 70.307708 -29.096208) (xy 70.307708 -29.094176) (xy 70.30847 -29.074364)
			(xy 70.30948 -29.051818) (xy 70.313291 -29.006842) (xy 70.31609 -28.984448) (xy 70.322945 -28.93685)
			(xy 70.344632 -28.843155) (xy 70.375236 -28.751982) (xy 70.394322 -28.707842) (xy 70.39737 -28.69819)
			(xy 70.400926 -28.68295) (xy 70.400926 -28.681934) (xy 70.39737 -28.666694) (xy 70.394322 -28.657042)
			(xy 70.377644 -28.618639) (xy 70.350039 -28.539588) (xy 70.329164 -28.458499) (xy 70.315167 -28.375945)
			(xy 70.308146 -28.292508) (xy 70.307708 -28.250642) (xy 70.307708 -28.24353) (xy 70.309486 -28.189936)
			(xy 70.30974 -28.187142) (xy 70.30974 -28.183332) (xy 70.307962 -28.17241) (xy 70.306438 -28.165298)
			(xy 70.298598 -28.137896) (xy 70.290184 -28.081527) (xy 70.289674 -28.05303) (xy 70.289674 -28.04668)
			(xy 70.289928 -28.038298) (xy 70.291198 -28.01874) (xy 70.291198 -28.018486) (xy 70.291706 -28.012898)
			(xy 70.295376 -27.983489) (xy 70.310636 -27.926223) (xy 70.334564 -27.872004) (xy 70.350126 -27.846782)
			(xy 70.353428 -27.841702) (xy 70.370635 -27.816869) (xy 70.411596 -27.772462) (xy 70.434962 -27.75331)
			(xy 70.440804 -27.747722) (xy 70.44563 -27.742388) (xy 70.451726 -27.73426) (xy 70.474727 -27.697232)
			(xy 70.526239 -27.626904) (xy 70.554596 -27.593798) (xy 70.582907 -27.562107) (xy 70.644103 -27.503135)
			(xy 70.710096 -27.449586) (xy 70.780407 -27.401848) (xy 70.854527 -27.360268) (xy 70.931917 -27.325148)
			(xy 71.012015 -27.296742) (xy 71.09424 -27.275256) (xy 71.177995 -27.260847) (xy 71.262673 -27.253619)
			(xy 71.305166 -27.253184) (xy 71.30542 -27.253184) (xy 71.352939 -27.25374) (xy 71.447544 -27.262801)
			(xy 71.540856 -27.280828) (xy 71.632028 -27.307658) (xy 71.720231 -27.343047) (xy 71.804663 -27.386674)
			(xy 71.844916 -27.411934) (xy 71.882853 -27.436961) (xy 71.95447 -27.492925) (xy 71.987918 -27.523694)
			(xy 71.993252 -27.528774) (xy 71.994522 -27.530044) (xy 71.994776 -27.530298) (xy 72.020176 -27.540458)
			(xy 72.024742 -27.542215) (xy 72.034335 -27.544139) (xy 72.039226 -27.544268) (xy 73.972928 -27.544268)
			(xy 74.021844 -27.544891) (xy 74.119201 -27.554519) (xy 74.215148 -27.573629) (xy 74.308765 -27.602038)
			(xy 74.354182 -27.620214) (xy 75.80122 -28.220924) (xy 75.810695 -28.223965) (xy 75.830563 -28.223319)
			(xy 75.848684 -28.215147) (xy 75.85583 -28.208224) (xy 75.856084 -28.20797) (xy 75.874209 -28.189322)
			(xy 75.914633 -28.156608) (xy 75.959122 -28.129682) (xy 76.006853 -28.109041) (xy 76.056943 -28.095068)
			(xy 76.108467 -28.088021) (xy 76.134468 -28.087574) (xy 76.161723 -28.088035) (xy 76.215678 -28.095788)
			(xy 76.267981 -28.111141) (xy 76.317566 -28.133781) (xy 76.3259 -28.139136) (xy 80.397856 -28.139136)
			(xy 80.401927 -28.083514) (xy 80.414053 -28.029077) (xy 80.433976 -27.976986) (xy 80.461272 -27.928351)
			(xy 80.495358 -27.884208) (xy 80.535507 -27.845499) (xy 80.580865 -27.813048) (xy 80.630465 -27.787547)
			(xy 80.683249 -27.76954) (xy 80.738092 -27.75941) (xy 80.793826 -27.757373) (xy 80.849263 -27.763473)
			(xy 80.90322 -27.777579) (xy 80.954549 -27.799391) (xy 81.002155 -27.828445) (xy 81.045023 -27.86412)
			(xy 81.08224 -27.905657) (xy 81.113013 -27.95217) (xy 81.136685 -28.002667) (xy 81.152753 -28.056074)
			(xy 81.160873 -28.11125) (xy 81.161382 -28.139136) (xy 81.667856 -28.139136) (xy 81.671927 -28.083514)
			(xy 81.684053 -28.029077) (xy 81.703976 -27.976986) (xy 81.731272 -27.928351) (xy 81.765358 -27.884208)
			(xy 81.805507 -27.845499) (xy 81.850865 -27.813048) (xy 81.900465 -27.787547) (xy 81.953249 -27.76954)
			(xy 82.008092 -27.75941) (xy 82.063826 -27.757373) (xy 82.119263 -27.763473) (xy 82.17322 -27.777579)
			(xy 82.224549 -27.799391) (xy 82.272155 -27.828445) (xy 82.315023 -27.86412) (xy 82.35224 -27.905657)
			(xy 82.383013 -27.95217) (xy 82.406685 -28.002667) (xy 82.422753 -28.056074) (xy 82.430873 -28.11125)
			(xy 82.431382 -28.139136) (xy 82.430873 -28.167022) (xy 82.422753 -28.222198) (xy 82.406685 -28.275605)
			(xy 82.383013 -28.326102) (xy 82.35224 -28.372615) (xy 82.315023 -28.414152) (xy 82.272155 -28.449827)
			(xy 82.224549 -28.478881) (xy 82.17322 -28.500693) (xy 82.119263 -28.514799) (xy 82.063826 -28.520899)
			(xy 82.008092 -28.518862) (xy 81.953249 -28.508732) (xy 81.900465 -28.490725) (xy 81.850865 -28.465224)
			(xy 81.805507 -28.432773) (xy 81.765358 -28.394064) (xy 81.731272 -28.349921) (xy 81.703976 -28.301286)
			(xy 81.684053 -28.249195) (xy 81.671927 -28.194758) (xy 81.667856 -28.139136) (xy 81.161382 -28.139136)
			(xy 81.160873 -28.167022) (xy 81.152753 -28.222198) (xy 81.136685 -28.275605) (xy 81.113013 -28.326102)
			(xy 81.08224 -28.372615) (xy 81.045023 -28.414152) (xy 81.002155 -28.449827) (xy 80.954549 -28.478881)
			(xy 80.90322 -28.500693) (xy 80.849263 -28.514799) (xy 80.793826 -28.520899) (xy 80.738092 -28.518862)
			(xy 80.683249 -28.508732) (xy 80.630465 -28.490725) (xy 80.580865 -28.465224) (xy 80.535507 -28.432773)
			(xy 80.495358 -28.394064) (xy 80.461272 -28.349921) (xy 80.433976 -28.301286) (xy 80.414053 -28.249195)
			(xy 80.401927 -28.194758) (xy 80.397856 -28.139136) (xy 76.3259 -28.139136) (xy 76.363425 -28.163248)
			(xy 76.404623 -28.198942) (xy 76.440322 -28.240135) (xy 76.469795 -28.28599) (xy 76.492442 -28.335572)
			(xy 76.507802 -28.387873) (xy 76.515562 -28.441827) (xy 76.515976 -28.469082) (xy 76.515976 -28.480004)
			(xy 76.514626 -28.508516) (xy 76.504523 -28.564692) (xy 76.486182 -28.618742) (xy 76.473558 -28.644342)
			(xy 76.471526 -28.648406) (xy 76.468191 -28.657795) (xy 76.46821 -28.677701) (xy 76.475794 -28.696105)
			(xy 76.482448 -28.703524) (xy 76.901294 -29.12237) (xy 86.606888 -29.12237) (xy 86.606888 -28.25877)
			(xy 86.607378 -28.228802) (xy 86.615201 -28.16938) (xy 86.630714 -28.111487) (xy 86.65365 -28.056114)
			(xy 86.683617 -28.004208) (xy 86.720104 -27.956658) (xy 86.762484 -27.914278) (xy 86.810034 -27.877791)
			(xy 86.86194 -27.847824) (xy 86.917313 -27.824888) (xy 86.975206 -27.809375) (xy 87.034628 -27.801552)
			(xy 87.094564 -27.801552) (xy 87.153986 -27.809375) (xy 87.211879 -27.824888) (xy 87.267252 -27.847824)
			(xy 87.319158 -27.877791) (xy 87.366708 -27.914278) (xy 87.409088 -27.956658) (xy 87.445575 -28.004208)
			(xy 87.475542 -28.056114) (xy 87.498478 -28.111487) (xy 87.513991 -28.16938) (xy 87.521814 -28.228802)
			(xy 87.522304 -28.25877) (xy 87.522304 -29.12237) (xy 87.521814 -29.152338) (xy 87.513991 -29.21176)
			(xy 87.498478 -29.269653) (xy 87.475542 -29.325026) (xy 87.445575 -29.376932) (xy 87.409088 -29.424482)
			(xy 87.366708 -29.466862) (xy 87.319158 -29.503349) (xy 87.267252 -29.533316) (xy 87.211879 -29.556252)
			(xy 87.153986 -29.571765) (xy 87.094564 -29.579588) (xy 87.034628 -29.579588) (xy 86.975206 -29.571765)
			(xy 86.917313 -29.556252) (xy 86.86194 -29.533316) (xy 86.810034 -29.503349) (xy 86.762484 -29.466862)
			(xy 86.720104 -29.424482) (xy 86.683617 -29.376932) (xy 86.65365 -29.325026) (xy 86.630714 -29.269653)
			(xy 86.615201 -29.21176) (xy 86.607378 -29.152338) (xy 86.606888 -29.12237) (xy 76.901294 -29.12237)
			(xy 77.18806 -29.409136) (xy 77.188568 -29.409644) (xy 77.18933 -29.410406) (xy 77.196198 -29.416281)
			(xy 77.212888 -29.423182) (xy 77.230936 -29.423826) (xy 77.239622 -29.421328) (xy 77.240638 -29.421074)
			(xy 77.241654 -29.420566) (xy 77.268219 -29.41266) (xy 77.322919 -29.403728) (xy 77.35062 -29.402786)
			(xy 77.364082 -29.402786) (xy 77.390727 -29.403689) (xy 77.443386 -29.41202) (xy 77.494372 -29.4276)
			(xy 77.542693 -29.450126) (xy 77.587408 -29.479159) (xy 77.627646 -29.514134) (xy 77.662624 -29.554369)
			(xy 77.69166 -29.599082) (xy 77.714189 -29.647401) (xy 77.729773 -29.698386) (xy 77.738108 -29.751044)
			(xy 77.738986 -29.77769) (xy 77.738986 -29.784802) (xy 77.738403 -29.814703) (xy 77.729089 -29.873775)
			(xy 77.720444 -29.902404) (xy 77.718412 -29.909008) (xy 77.71765 -29.922724) (xy 77.719428 -29.929836)
			(xy 77.721255 -29.936608) (xy 77.728095 -29.948846) (xy 77.73289 -29.953966) (xy 78.155712 -30.376876)
			(xy 78.888844 -30.376876) (xy 78.8894 -30.34796) (xy 78.898119 -30.29079) (xy 78.915369 -30.235591)
			(xy 78.940753 -30.183629) (xy 78.973691 -30.136094) (xy 79.013427 -30.094077) (xy 79.03591 -30.075886)
			(xy 79.044715 -30.068277) (xy 79.054899 -30.047378) (xy 79.055468 -30.035754) (xy 79.055468 -29.955998)
			(xy 79.054927 -29.944366) (xy 79.044741 -29.923456) (xy 79.03591 -29.915866) (xy 79.013412 -29.897692)
			(xy 78.973678 -29.855669) (xy 78.94074 -29.80813) (xy 78.915354 -29.756166) (xy 78.898101 -29.700965)
			(xy 78.889376 -29.643793) (xy 78.888844 -29.614876) (xy 78.88933 -29.587625) (xy 78.897086 -29.533677)
			(xy 78.912441 -29.481382) (xy 78.935083 -29.431805) (xy 78.964549 -29.385955) (xy 79.00024 -29.344764)
			(xy 79.041431 -29.309073) (xy 79.087281 -29.279607) (xy 79.136858 -29.256965) (xy 79.189153 -29.24161)
			(xy 79.243101 -29.233854) (xy 79.297603 -29.233854) (xy 79.351551 -29.24161) (xy 79.403846 -29.256965)
			(xy 79.453423 -29.279607) (xy 79.499273 -29.309073) (xy 79.540464 -29.344764) (xy 79.576155 -29.385955)
			(xy 79.605621 -29.431805) (xy 79.628263 -29.481382) (xy 79.643618 -29.533677) (xy 79.651374 -29.587625)
			(xy 79.65186 -29.614876) (xy 79.65134 -29.643793) (xy 79.642613 -29.700965) (xy 79.625357 -29.756164)
			(xy 79.599965 -29.808126) (xy 79.567022 -29.85566) (xy 79.52728 -29.897676) (xy 79.504794 -29.915866)
			(xy 79.496011 -29.923497) (xy 79.485815 -29.94438) (xy 79.485236 -29.955998) (xy 79.485236 -30.035754)
			(xy 79.485746 -30.04739) (xy 79.495954 -30.0683) (xy 79.504794 -30.075886) (xy 79.52727 -30.094086)
			(xy 79.567005 -30.136104) (xy 79.599946 -30.183637) (xy 79.625335 -30.235596) (xy 79.642593 -30.290792)
			(xy 79.651324 -30.347961) (xy 79.65186 -30.376876) (xy 81.92897 -30.376876) (xy 81.929517 -30.34796)
			(xy 81.938236 -30.290789) (xy 81.955487 -30.235589) (xy 81.980873 -30.183627) (xy 82.013813 -30.136093)
			(xy 82.053552 -30.094076) (xy 82.076036 -30.075886) (xy 82.084846 -30.068281) (xy 82.095026 -30.047379)
			(xy 82.095594 -30.035754) (xy 82.095594 -29.955998) (xy 82.095044 -29.944367) (xy 82.084863 -29.923458)
			(xy 82.076036 -29.915866) (xy 82.053544 -29.897685) (xy 82.013807 -29.855664) (xy 81.980868 -29.808128)
			(xy 81.955481 -29.756164) (xy 81.938227 -29.700964) (xy 81.929502 -29.643793) (xy 81.92897 -29.614876)
			(xy 81.929456 -29.587625) (xy 81.937212 -29.533677) (xy 81.952567 -29.481382) (xy 81.975209 -29.431805)
			(xy 82.004675 -29.385955) (xy 82.040366 -29.344764) (xy 82.081557 -29.309073) (xy 82.127407 -29.279607)
			(xy 82.176984 -29.256965) (xy 82.229279 -29.24161) (xy 82.283227 -29.233854) (xy 82.337729 -29.233854)
			(xy 82.391677 -29.24161) (xy 82.443972 -29.256965) (xy 82.493549 -29.279607) (xy 82.539399 -29.309073)
			(xy 82.58059 -29.344764) (xy 82.616281 -29.385955) (xy 82.645747 -29.431805) (xy 82.668389 -29.481382)
			(xy 82.683744 -29.533677) (xy 82.6915 -29.587625) (xy 82.691986 -29.614876) (xy 82.691456 -29.643793)
			(xy 82.68273 -29.700963) (xy 82.665475 -29.756162) (xy 82.640085 -29.808124) (xy 82.607144 -29.855658)
			(xy 82.567405 -29.897676) (xy 82.54492 -29.915866) (xy 82.536125 -29.923484) (xy 82.525938 -29.944377)
			(xy 82.525362 -29.955998) (xy 82.525362 -30.035754) (xy 82.525863 -30.047391) (xy 82.536076 -30.068302)
			(xy 82.54492 -30.075886) (xy 82.567401 -30.09408) (xy 82.607135 -30.1361) (xy 82.640074 -30.183634)
			(xy 82.665463 -30.235595) (xy 82.68272 -30.290791) (xy 82.69145 -30.34796) (xy 82.691986 -30.376876)
			(xy 82.6915 -30.404127) (xy 82.683744 -30.458075) (xy 82.668389 -30.51037) (xy 82.645747 -30.559947)
			(xy 82.616281 -30.605797) (xy 82.58059 -30.646988) (xy 82.539399 -30.682679) (xy 82.493549 -30.712145)
			(xy 82.443972 -30.734787) (xy 82.391677 -30.750142) (xy 82.337729 -30.757898) (xy 82.283227 -30.757898)
			(xy 82.229279 -30.750142) (xy 82.176984 -30.734787) (xy 82.127407 -30.712145) (xy 82.081557 -30.682679)
			(xy 82.040366 -30.646988) (xy 82.004675 -30.605797) (xy 81.975209 -30.559947) (xy 81.952567 -30.51037)
			(xy 81.937212 -30.458075) (xy 81.929456 -30.404127) (xy 81.92897 -30.376876) (xy 79.65186 -30.376876)
			(xy 79.651374 -30.404127) (xy 79.643618 -30.458075) (xy 79.628263 -30.51037) (xy 79.605621 -30.559947)
			(xy 79.576155 -30.605797) (xy 79.540464 -30.646988) (xy 79.499273 -30.682679) (xy 79.453423 -30.712145)
			(xy 79.403846 -30.734787) (xy 79.351551 -30.750142) (xy 79.297603 -30.757898) (xy 79.243101 -30.757898)
			(xy 79.189153 -30.750142) (xy 79.136858 -30.734787) (xy 79.087281 -30.712145) (xy 79.041431 -30.682679)
			(xy 79.00024 -30.646988) (xy 78.964549 -30.605797) (xy 78.935083 -30.559947) (xy 78.912441 -30.51037)
			(xy 78.897086 -30.458075) (xy 78.88933 -30.404127) (xy 78.888844 -30.376876) (xy 78.155712 -30.376876)
			(xy 78.701191 -30.922468) (xy 84.752688 -30.922468) (xy 84.752688 -30.058868) (xy 84.753178 -30.0289)
			(xy 84.761001 -29.969478) (xy 84.776514 -29.911585) (xy 84.79945 -29.856212) (xy 84.829417 -29.804306)
			(xy 84.865904 -29.756756) (xy 84.908284 -29.714376) (xy 84.955834 -29.677889) (xy 85.00774 -29.647922)
			(xy 85.063113 -29.624986) (xy 85.121006 -29.609473) (xy 85.180428 -29.60165) (xy 85.240364 -29.60165)
			(xy 85.299786 -29.609473) (xy 85.357679 -29.624986) (xy 85.413052 -29.647922) (xy 85.464958 -29.677889)
			(xy 85.512508 -29.714376) (xy 85.554888 -29.756756) (xy 85.591375 -29.804306) (xy 85.621342 -29.856212)
			(xy 85.644278 -29.911585) (xy 85.659791 -29.969478) (xy 85.667614 -30.0289) (xy 85.668104 -30.058868)
			(xy 85.668104 -30.922468) (xy 85.667614 -30.952436) (xy 85.659791 -31.011858) (xy 85.644278 -31.069751)
			(xy 85.621342 -31.125124) (xy 85.591375 -31.17703) (xy 85.554888 -31.22458) (xy 85.512508 -31.26696)
			(xy 85.464958 -31.303447) (xy 85.413052 -31.333414) (xy 85.357679 -31.35635) (xy 85.299786 -31.371863)
			(xy 85.240364 -31.379686) (xy 85.180428 -31.379686) (xy 85.121006 -31.371863) (xy 85.063113 -31.35635)
			(xy 85.00774 -31.333414) (xy 84.955834 -31.303447) (xy 84.908284 -31.26696) (xy 84.865904 -31.22458)
			(xy 84.829417 -31.17703) (xy 84.79945 -31.125124) (xy 84.776514 -31.069751) (xy 84.761001 -31.011858)
			(xy 84.753178 -30.952436) (xy 84.752688 -30.922468) (xy 78.701191 -30.922468) (xy 78.959202 -31.180532)
			(xy 78.973172 -31.194756) (xy 78.984509 -31.206691) (xy 79.006486 -31.231207) (xy 79.017114 -31.243778)
			(xy 79.023718 -31.251398) (xy 79.031338 -31.255462) (xy 79.035674 -31.257782) (xy 79.045014 -31.260853)
			(xy 79.04988 -31.261558) (xy 79.118968 -31.269432) (xy 79.123887 -31.26988) (xy 79.133734 -31.269109)
			(xy 79.138526 -31.267908) (xy 79.14259 -31.266892) (xy 79.150718 -31.263336) (xy 79.154782 -31.260288)
			(xy 79.179487 -31.242875) (xy 79.233243 -31.215249) (xy 79.290682 -31.196443) (xy 79.350368 -31.186928)
			(xy 79.380588 -31.186374) (xy 79.40784 -31.186859) (xy 79.46179 -31.194614) (xy 79.514087 -31.209968)
			(xy 79.563667 -31.232608) (xy 79.609521 -31.262074) (xy 79.650714 -31.297765) (xy 79.686408 -31.338955)
			(xy 79.715878 -31.384806) (xy 79.738522 -31.434384) (xy 79.75388 -31.48668) (xy 79.761639 -31.54063)
			(xy 79.762096 -31.567882) (xy 79.76235 -31.567882) (xy 79.761826 -31.596581) (xy 79.753219 -31.65333)
			(xy 79.73621 -31.708151) (xy 79.730825 -31.719266) (xy 80.285334 -31.719266) (xy 80.289405 -31.663644)
			(xy 80.301531 -31.609207) (xy 80.321454 -31.557116) (xy 80.34875 -31.508481) (xy 80.382836 -31.464338)
			(xy 80.422985 -31.425629) (xy 80.468343 -31.393178) (xy 80.517943 -31.367677) (xy 80.570727 -31.34967)
			(xy 80.62557 -31.33954) (xy 80.681304 -31.337503) (xy 80.736741 -31.343603) (xy 80.790698 -31.357709)
			(xy 80.842027 -31.379521) (xy 80.889633 -31.408575) (xy 80.932501 -31.44425) (xy 80.969718 -31.485787)
			(xy 81.000491 -31.5323) (xy 81.024163 -31.582797) (xy 81.040231 -31.636204) (xy 81.044381 -31.664402)
			(xy 81.560922 -31.664402) (xy 81.564993 -31.60878) (xy 81.577119 -31.554343) (xy 81.597042 -31.502252)
			(xy 81.624338 -31.453617) (xy 81.658424 -31.409474) (xy 81.698573 -31.370765) (xy 81.743931 -31.338314)
			(xy 81.793531 -31.312813) (xy 81.846315 -31.294806) (xy 81.901158 -31.284676) (xy 81.956892 -31.282639)
			(xy 82.012329 -31.288739) (xy 82.066286 -31.302845) (xy 82.117615 -31.324657) (xy 82.165221 -31.353711)
			(xy 82.208089 -31.389386) (xy 82.245306 -31.430923) (xy 82.276079 -31.477436) (xy 82.299751 -31.527933)
			(xy 82.315819 -31.58134) (xy 82.323939 -31.636516) (xy 82.324448 -31.664402) (xy 82.323939 -31.692288)
			(xy 82.315819 -31.747464) (xy 82.306879 -31.777178) (xy 82.826096 -31.777178) (xy 82.830167 -31.721556)
			(xy 82.842293 -31.667119) (xy 82.862216 -31.615028) (xy 82.889512 -31.566393) (xy 82.923598 -31.52225)
			(xy 82.963747 -31.483541) (xy 83.009105 -31.45109) (xy 83.058705 -31.425589) (xy 83.111489 -31.407582)
			(xy 83.166332 -31.397452) (xy 83.222066 -31.395415) (xy 83.277503 -31.401515) (xy 83.33146 -31.415621)
			(xy 83.382789 -31.437433) (xy 83.430395 -31.466487) (xy 83.473263 -31.502162) (xy 83.51048 -31.543699)
			(xy 83.541253 -31.590212) (xy 83.564925 -31.640709) (xy 83.580993 -31.694116) (xy 83.589113 -31.749292)
			(xy 83.589622 -31.777178) (xy 83.589113 -31.805064) (xy 83.580993 -31.86024) (xy 83.564925 -31.913647)
			(xy 83.541253 -31.964144) (xy 83.51048 -32.010657) (xy 83.473263 -32.052194) (xy 83.430395 -32.087869)
			(xy 83.382789 -32.116923) (xy 83.33146 -32.138735) (xy 83.277503 -32.152841) (xy 83.222066 -32.158941)
			(xy 83.166332 -32.156904) (xy 83.111489 -32.146774) (xy 83.058705 -32.128767) (xy 83.009105 -32.103266)
			(xy 82.963747 -32.070815) (xy 82.923598 -32.032106) (xy 82.889512 -31.987963) (xy 82.862216 -31.939328)
			(xy 82.842293 -31.887237) (xy 82.830167 -31.8328) (xy 82.826096 -31.777178) (xy 82.306879 -31.777178)
			(xy 82.299751 -31.800871) (xy 82.276079 -31.851368) (xy 82.245306 -31.897881) (xy 82.208089 -31.939418)
			(xy 82.165221 -31.975093) (xy 82.117615 -32.004147) (xy 82.066286 -32.025959) (xy 82.012329 -32.040065)
			(xy 81.956892 -32.046165) (xy 81.901158 -32.044128) (xy 81.846315 -32.033998) (xy 81.793531 -32.015991)
			(xy 81.743931 -31.99049) (xy 81.698573 -31.958039) (xy 81.658424 -31.91933) (xy 81.624338 -31.875187)
			(xy 81.597042 -31.826552) (xy 81.577119 -31.774461) (xy 81.564993 -31.720024) (xy 81.560922 -31.664402)
			(xy 81.044381 -31.664402) (xy 81.048351 -31.69138) (xy 81.04886 -31.719266) (xy 81.048351 -31.747152)
			(xy 81.040231 -31.802328) (xy 81.024163 -31.855735) (xy 81.000491 -31.906232) (xy 80.969718 -31.952745)
			(xy 80.932501 -31.994282) (xy 80.889633 -32.029957) (xy 80.842027 -32.059011) (xy 80.790698 -32.080823)
			(xy 80.736741 -32.094929) (xy 80.681304 -32.101029) (xy 80.62557 -32.098992) (xy 80.570727 -32.088862)
			(xy 80.517943 -32.070855) (xy 80.468343 -32.045354) (xy 80.422985 -32.012903) (xy 80.382836 -31.974194)
			(xy 80.34875 -31.930051) (xy 80.321454 -31.881416) (xy 80.301531 -31.829325) (xy 80.289405 -31.774888)
			(xy 80.285334 -31.719266) (xy 79.730825 -31.719266) (xy 79.711184 -31.759806) (xy 79.678704 -31.807131)
			(xy 79.639504 -31.849058) (xy 79.594467 -31.884642) (xy 79.569818 -31.899352) (xy 79.56042 -31.904686)
			(xy 79.554578 -31.912306) (xy 79.551658 -31.91641) (xy 79.547305 -31.925491) (xy 79.545942 -31.93034)
			(xy 79.527654 -32.002476) (xy 79.52618 -32.010995) (xy 79.528399 -32.02813) (xy 79.531972 -32.036004)
			(xy 79.968922 -32.722312) (xy 86.606888 -32.722312) (xy 86.606888 -31.858712) (xy 86.607378 -31.828744)
			(xy 86.615201 -31.769322) (xy 86.630714 -31.711429) (xy 86.65365 -31.656056) (xy 86.683617 -31.60415)
			(xy 86.720104 -31.5566) (xy 86.762484 -31.51422) (xy 86.810034 -31.477733) (xy 86.86194 -31.447766)
			(xy 86.917313 -31.42483) (xy 86.975206 -31.409317) (xy 87.034628 -31.401494) (xy 87.094564 -31.401494)
			(xy 87.153986 -31.409317) (xy 87.211879 -31.42483) (xy 87.267252 -31.447766) (xy 87.319158 -31.477733)
			(xy 87.366708 -31.51422) (xy 87.409088 -31.5566) (xy 87.445575 -31.60415) (xy 87.475542 -31.656056)
			(xy 87.498478 -31.711429) (xy 87.513991 -31.769322) (xy 87.521814 -31.828744) (xy 87.522304 -31.858712)
			(xy 87.522304 -32.722312) (xy 87.521814 -32.75228) (xy 87.513991 -32.811702) (xy 87.498478 -32.869595)
			(xy 87.475542 -32.924968) (xy 87.445575 -32.976874) (xy 87.409088 -33.024424) (xy 87.366708 -33.066804)
			(xy 87.319158 -33.103291) (xy 87.267252 -33.133258) (xy 87.211879 -33.156194) (xy 87.153986 -33.171707)
			(xy 87.094564 -33.17953) (xy 87.034628 -33.17953) (xy 86.975206 -33.171707) (xy 86.917313 -33.156194)
			(xy 86.86194 -33.133258) (xy 86.810034 -33.103291) (xy 86.762484 -33.066804) (xy 86.720104 -33.024424)
			(xy 86.683617 -32.976874) (xy 86.65365 -32.924968) (xy 86.630714 -32.869595) (xy 86.615201 -32.811702)
			(xy 86.607378 -32.75228) (xy 86.606888 -32.722312) (xy 79.968922 -32.722312) (xy 80.015334 -32.79521)
			(xy 80.05826 -32.86252) (xy 80.058768 -32.863282) (xy 80.063572 -32.869954) (xy 80.076525 -32.880065)
			(xy 80.084168 -32.883094) (xy 80.109893 -32.891426) (xy 80.158872 -32.914336) (xy 80.204124 -32.943934)
			(xy 80.244742 -32.979628) (xy 80.27991 -33.020701) (xy 80.308925 -33.06633) (xy 80.331204 -33.115599)
			(xy 80.3463 -33.167521) (xy 80.35391 -33.221056) (xy 80.354424 -33.248092) (xy 80.354424 -33.25622)
			(xy 80.353916 -33.268158) (xy 80.353916 -33.268666) (xy 80.353154 -33.280096) (xy 80.353154 -33.280604)
			(xy 80.350868 -33.299654) (xy 80.350868 -33.300416) (xy 80.35018 -33.309188) (xy 80.354068 -33.326336)
			(xy 80.358488 -33.333944) (xy 81.115178 -34.52241) (xy 84.752688 -34.52241) (xy 84.752688 -33.65881)
			(xy 84.753178 -33.628842) (xy 84.761001 -33.56942) (xy 84.776514 -33.511527) (xy 84.79945 -33.456154)
			(xy 84.829417 -33.404248) (xy 84.865904 -33.356698) (xy 84.908284 -33.314318) (xy 84.955834 -33.277831)
			(xy 85.00774 -33.247864) (xy 85.063113 -33.224928) (xy 85.121006 -33.209415) (xy 85.180428 -33.201592)
			(xy 85.240364 -33.201592) (xy 85.299786 -33.209415) (xy 85.357679 -33.224928) (xy 85.413052 -33.247864)
			(xy 85.464958 -33.277831) (xy 85.512508 -33.314318) (xy 85.554888 -33.356698) (xy 85.591375 -33.404248)
			(xy 85.621342 -33.456154) (xy 85.644278 -33.511527) (xy 85.659791 -33.56942) (xy 85.667614 -33.628842)
			(xy 85.668104 -33.65881) (xy 85.668104 -34.52241) (xy 85.667614 -34.552378) (xy 85.659791 -34.6118)
			(xy 85.644278 -34.669693) (xy 85.621342 -34.725066) (xy 85.591375 -34.776972) (xy 85.554888 -34.824522)
			(xy 85.512508 -34.866902) (xy 85.464958 -34.903389) (xy 85.413052 -34.933356) (xy 85.357679 -34.956292)
			(xy 85.299786 -34.971805) (xy 85.240364 -34.979628) (xy 85.180428 -34.979628) (xy 85.121006 -34.971805)
			(xy 85.063113 -34.956292) (xy 85.00774 -34.933356) (xy 84.955834 -34.903389) (xy 84.908284 -34.866902)
			(xy 84.865904 -34.824522) (xy 84.829417 -34.776972) (xy 84.79945 -34.725066) (xy 84.776514 -34.669693)
			(xy 84.761001 -34.6118) (xy 84.753178 -34.552378) (xy 84.752688 -34.52241) (xy 81.115178 -34.52241)
			(xy 81.587887 -35.264852) (xy 81.902298 -35.264852) (xy 81.906369 -35.20923) (xy 81.918495 -35.154793)
			(xy 81.938418 -35.102702) (xy 81.965714 -35.054067) (xy 81.9998 -35.009924) (xy 82.039949 -34.971215)
			(xy 82.085307 -34.938764) (xy 82.134907 -34.913263) (xy 82.187691 -34.895256) (xy 82.242534 -34.885126)
			(xy 82.298268 -34.883089) (xy 82.353705 -34.889189) (xy 82.407662 -34.903295) (xy 82.458991 -34.925107)
			(xy 82.506597 -34.954161) (xy 82.549465 -34.989836) (xy 82.586682 -35.031373) (xy 82.617455 -35.077886)
			(xy 82.641127 -35.128383) (xy 82.657195 -35.18179) (xy 82.665315 -35.236966) (xy 82.665824 -35.264852)
			(xy 82.665315 -35.292738) (xy 82.657195 -35.347914) (xy 82.641127 -35.401321) (xy 82.617455 -35.451818)
			(xy 82.586682 -35.498331) (xy 82.549465 -35.539868) (xy 82.506597 -35.575543) (xy 82.458991 -35.604597)
			(xy 82.407662 -35.626409) (xy 82.353705 -35.640515) (xy 82.298268 -35.646615) (xy 82.242534 -35.644578)
			(xy 82.187691 -35.634448) (xy 82.134907 -35.616441) (xy 82.085307 -35.59094) (xy 82.039949 -35.558489)
			(xy 81.9998 -35.51978) (xy 81.965714 -35.475637) (xy 81.938418 -35.427002) (xy 81.918495 -35.374911)
			(xy 81.906369 -35.320474) (xy 81.902298 -35.264852) (xy 81.587887 -35.264852) (xy 82.23865 -36.286948)
			(xy 83.200238 -36.286948) (xy 83.204309 -36.231326) (xy 83.216435 -36.176889) (xy 83.236358 -36.124798)
			(xy 83.263654 -36.076163) (xy 83.29774 -36.03202) (xy 83.337889 -35.993311) (xy 83.383247 -35.96086)
			(xy 83.432847 -35.935359) (xy 83.485631 -35.917352) (xy 83.540474 -35.907222) (xy 83.596208 -35.905185)
			(xy 83.651645 -35.911285) (xy 83.705602 -35.925391) (xy 83.756931 -35.947203) (xy 83.804537 -35.976257)
			(xy 83.847405 -36.011932) (xy 83.884622 -36.053469) (xy 83.915395 -36.099982) (xy 83.939067 -36.150479)
			(xy 83.955135 -36.203886) (xy 83.963255 -36.259062) (xy 83.963764 -36.286948) (xy 83.963255 -36.314834)
			(xy 83.955135 -36.37001) (xy 83.939067 -36.423417) (xy 83.915395 -36.473914) (xy 83.88785 -36.515548)
			(xy 85.014052 -36.515548) (xy 85.018123 -36.459926) (xy 85.030249 -36.405489) (xy 85.050172 -36.353398)
			(xy 85.077468 -36.304763) (xy 85.111554 -36.26062) (xy 85.151703 -36.221911) (xy 85.197061 -36.18946)
			(xy 85.246661 -36.163959) (xy 85.299445 -36.145952) (xy 85.354288 -36.135822) (xy 85.410022 -36.133785)
			(xy 85.465459 -36.139885) (xy 85.519416 -36.153991) (xy 85.570745 -36.175803) (xy 85.618351 -36.204857)
			(xy 85.661219 -36.240532) (xy 85.698436 -36.282069) (xy 85.729209 -36.328582) (xy 85.752881 -36.379079)
			(xy 85.768949 -36.432486) (xy 85.777069 -36.487662) (xy 85.777578 -36.515548) (xy 85.777069 -36.543434)
			(xy 85.768949 -36.59861) (xy 85.768492 -36.60013) (xy 89.998049 -36.60013) (xy 90.002054 -36.512222)
			(xy 90.014037 -36.425042) (xy 90.033897 -36.339313) (xy 90.061472 -36.255745) (xy 90.096531 -36.175031)
			(xy 90.138784 -36.097839) (xy 90.187882 -36.02481) (xy 90.243418 -35.956548) (xy 90.30493 -35.893618)
			(xy 90.371911 -35.836544) (xy 90.443804 -35.785796) (xy 90.520013 -35.741796) (xy 90.599908 -35.704909)
			(xy 90.682827 -35.67544) (xy 90.768082 -35.653633) (xy 90.854966 -35.639669) (xy 90.94276 -35.633663)
			(xy 91.030737 -35.635667) (xy 91.118167 -35.645662) (xy 91.204326 -35.663566) (xy 91.2885 -35.68923)
			(xy 91.369991 -35.722443) (xy 91.448125 -35.762929) (xy 91.522253 -35.810351) (xy 91.591761 -35.864318)
			(xy 91.656075 -35.924383) (xy 91.714659 -35.990047) (xy 91.76703 -36.060766) (xy 91.812753 -36.135954)
			(xy 91.85145 -36.214989) (xy 91.882799 -36.297215) (xy 91.906541 -36.381951) (xy 91.922479 -36.468495)
			(xy 91.930481 -36.55613) (xy 91.930982 -36.60013) (xy 91.930481 -36.64413) (xy 91.922479 -36.731765)
			(xy 91.906541 -36.818309) (xy 91.882799 -36.903045) (xy 91.85145 -36.985271) (xy 91.812753 -37.064306)
			(xy 91.76703 -37.139494) (xy 91.714659 -37.210213) (xy 91.656075 -37.275877) (xy 91.591761 -37.335942)
			(xy 91.522253 -37.389909) (xy 91.448125 -37.437331) (xy 91.369991 -37.477817) (xy 91.2885 -37.51103)
			(xy 91.204326 -37.536694) (xy 91.118167 -37.554598) (xy 91.030737 -37.564593) (xy 90.94276 -37.566597)
			(xy 90.854966 -37.560591) (xy 90.768082 -37.546627) (xy 90.682827 -37.52482) (xy 90.599908 -37.495351)
			(xy 90.520013 -37.458464) (xy 90.443804 -37.414464) (xy 90.371911 -37.363716) (xy 90.30493 -37.306642)
			(xy 90.243418 -37.243712) (xy 90.187882 -37.17545) (xy 90.138784 -37.102421) (xy 90.096531 -37.025229)
			(xy 90.061472 -36.944515) (xy 90.033897 -36.860947) (xy 90.014037 -36.775218) (xy 90.002054 -36.688038)
			(xy 89.998049 -36.60013) (xy 85.768492 -36.60013) (xy 85.752881 -36.652017) (xy 85.729209 -36.702514)
			(xy 85.698436 -36.749027) (xy 85.661219 -36.790564) (xy 85.618351 -36.826239) (xy 85.570745 -36.855293)
			(xy 85.519416 -36.877105) (xy 85.465459 -36.891211) (xy 85.410022 -36.897311) (xy 85.354288 -36.895274)
			(xy 85.299445 -36.885144) (xy 85.246661 -36.867137) (xy 85.197061 -36.841636) (xy 85.151703 -36.809185)
			(xy 85.111554 -36.770476) (xy 85.077468 -36.726333) (xy 85.050172 -36.677698) (xy 85.030249 -36.625607)
			(xy 85.018123 -36.57117) (xy 85.014052 -36.515548) (xy 83.88785 -36.515548) (xy 83.884622 -36.520427)
			(xy 83.847405 -36.561964) (xy 83.804537 -36.597639) (xy 83.756931 -36.626693) (xy 83.705602 -36.648505)
			(xy 83.651645 -36.662611) (xy 83.596208 -36.668711) (xy 83.540474 -36.666674) (xy 83.485631 -36.656544)
			(xy 83.432847 -36.638537) (xy 83.383247 -36.613036) (xy 83.337889 -36.580585) (xy 83.29774 -36.541876)
			(xy 83.263654 -36.497733) (xy 83.236358 -36.449098) (xy 83.216435 -36.397007) (xy 83.204309 -36.34257)
			(xy 83.200238 -36.286948) (xy 82.23865 -36.286948) (xy 83.185523 -37.774118) (xy 83.464652 -37.774118)
			(xy 83.468723 -37.718496) (xy 83.480849 -37.664059) (xy 83.500772 -37.611968) (xy 83.528068 -37.563333)
			(xy 83.562154 -37.51919) (xy 83.602303 -37.480481) (xy 83.647661 -37.44803) (xy 83.697261 -37.422529)
			(xy 83.750045 -37.404522) (xy 83.804888 -37.394392) (xy 83.860622 -37.392355) (xy 83.916059 -37.398455)
			(xy 83.970016 -37.412561) (xy 84.021345 -37.434373) (xy 84.068951 -37.463427) (xy 84.111819 -37.499102)
			(xy 84.149036 -37.540639) (xy 84.179809 -37.587152) (xy 84.203481 -37.637649) (xy 84.219549 -37.691056)
			(xy 84.227669 -37.746232) (xy 84.228178 -37.774118) (xy 84.227669 -37.802004) (xy 84.219549 -37.85718)
			(xy 84.203481 -37.910587) (xy 84.179809 -37.961084) (xy 84.149036 -38.007597) (xy 84.111819 -38.049134)
			(xy 84.068951 -38.084809) (xy 84.021345 -38.113863) (xy 83.970016 -38.135675) (xy 83.916059 -38.149781)
			(xy 83.860622 -38.155881) (xy 83.804888 -38.153844) (xy 83.750045 -38.143714) (xy 83.697261 -38.125707)
			(xy 83.647661 -38.100206) (xy 83.602303 -38.067755) (xy 83.562154 -38.029046) (xy 83.528068 -37.984903)
			(xy 83.500772 -37.936268) (xy 83.480849 -37.884177) (xy 83.468723 -37.82974) (xy 83.464652 -37.774118)
			(xy 83.185523 -37.774118) (xy 84.045552 -39.12489) (xy 84.050124 -39.130986) (xy 85.921892 -41.268751)
			(xy 93.84385 -41.268751) (xy 93.84385 -41.214249) (xy 93.851606 -41.160301) (xy 93.86696 -41.108006)
			(xy 93.889599 -41.058428) (xy 93.919064 -41.012576) (xy 93.954753 -40.971384) (xy 93.995941 -40.93569)
			(xy 94.041789 -40.90622) (xy 94.091365 -40.883575) (xy 94.143658 -40.868215) (xy 94.197605 -40.860453)
			(xy 94.224856 -40.859964) (xy 94.253596 -40.860463) (xy 94.310424 -40.869093) (xy 94.365314 -40.88615)
			(xy 94.417026 -40.911246) (xy 94.464387 -40.943816) (xy 94.485714 -40.963088) (xy 94.492572 -40.969692)
			(xy 94.510606 -40.976804) (xy 94.599506 -40.976804) (xy 94.61754 -40.969692) (xy 94.624398 -40.963088)
			(xy 94.645709 -40.943799) (xy 94.693075 -40.911233) (xy 94.74479 -40.886143) (xy 94.799685 -40.869097)
			(xy 94.856516 -40.860481) (xy 94.885256 -40.859964) (xy 94.912509 -40.86048) (xy 94.966461 -40.868232)
			(xy 95.01876 -40.883583) (xy 95.068342 -40.906221) (xy 95.114197 -40.935686) (xy 95.155392 -40.971377)
			(xy 95.191088 -41.012567) (xy 95.220558 -41.058419) (xy 95.243202 -41.107999) (xy 95.258559 -41.160296)
			(xy 95.266317 -41.214247) (xy 95.266317 -41.268753) (xy 95.258559 -41.322704) (xy 95.243202 -41.375001)
			(xy 95.220558 -41.424581) (xy 95.191088 -41.470433) (xy 95.155392 -41.511623) (xy 95.114197 -41.547314)
			(xy 95.068342 -41.576779) (xy 95.01876 -41.599417) (xy 94.966461 -41.614768) (xy 94.912509 -41.62252)
			(xy 94.885256 -41.62298) (xy 94.856517 -41.622462) (xy 94.79969 -41.613834) (xy 94.744801 -41.596782)
			(xy 94.693089 -41.57169) (xy 94.645726 -41.539126) (xy 94.624398 -41.519856) (xy 94.61754 -41.513252)
			(xy 94.599506 -41.50614) (xy 94.510606 -41.50614) (xy 94.492572 -41.513252) (xy 94.485714 -41.519856)
			(xy 94.464404 -41.539147) (xy 94.417038 -41.57171) (xy 94.365322 -41.596799) (xy 94.310427 -41.613845)
			(xy 94.253596 -41.622462) (xy 94.224856 -41.62298) (xy 94.197605 -41.622547) (xy 94.143658 -41.614785)
			(xy 94.091365 -41.599425) (xy 94.041789 -41.57678) (xy 93.995941 -41.54731) (xy 93.954753 -41.511616)
			(xy 93.919064 -41.470424) (xy 93.889599 -41.424572) (xy 93.86696 -41.374994) (xy 93.851606 -41.322699)
			(xy 93.84385 -41.268751) (xy 85.921892 -41.268751) (xy 87.70497 -43.305222) (xy 96.307148 -43.305222)
			(xy 96.307615 -43.277852) (xy 96.315431 -43.223672) (xy 96.330919 -43.171169) (xy 96.353761 -43.121422)
			(xy 96.383486 -43.075455) (xy 96.401128 -43.054524) (xy 96.401382 -43.05427) (xy 96.406943 -43.047166)
			(xy 96.413205 -43.030263) (xy 96.413574 -43.02125) (xy 96.413574 -42.954194) (xy 96.413226 -42.945176)
			(xy 96.406973 -42.928259) (xy 96.401382 -42.921174) (xy 96.401128 -42.921174) (xy 96.401128 -42.92092)
			(xy 96.383489 -42.899988) (xy 96.353776 -42.854015) (xy 96.33094 -42.804268) (xy 96.315449 -42.751767)
			(xy 96.307621 -42.697591) (xy 96.307148 -42.670222) (xy 96.307699 -42.641484) (xy 96.316317 -42.584659)
			(xy 96.333362 -42.529769) (xy 96.358447 -42.478057) (xy 96.391005 -42.430692) (xy 96.410272 -42.409364)
			(xy 96.416876 -42.402506) (xy 96.423988 -42.384472) (xy 96.423988 -42.295572) (xy 96.416876 -42.277538)
			(xy 96.410272 -42.27068) (xy 96.391025 -42.249333) (xy 96.358464 -42.201973) (xy 96.333374 -42.150264)
			(xy 96.316325 -42.095377) (xy 96.307702 -42.038553) (xy 96.307699 -41.981079) (xy 96.316318 -41.924255)
			(xy 96.333363 -41.869366) (xy 96.358448 -41.817655) (xy 96.391005 -41.770292) (xy 96.410272 -41.748964)
			(xy 96.416876 -41.742106) (xy 96.423988 -41.724072) (xy 96.423988 -41.635172) (xy 96.416876 -41.617138)
			(xy 96.410272 -41.61028) (xy 96.391017 -41.588939) (xy 96.358448 -41.541581) (xy 96.333351 -41.489873)
			(xy 96.316297 -41.434985) (xy 96.307671 -41.37816) (xy 96.307148 -41.349422) (xy 96.307634 -41.322171)
			(xy 96.31539 -41.268223) (xy 96.330745 -41.215928) (xy 96.353387 -41.166351) (xy 96.382853 -41.120501)
			(xy 96.418544 -41.07931) (xy 96.459735 -41.043619) (xy 96.505585 -41.014153) (xy 96.555162 -40.991511)
			(xy 96.607457 -40.976156) (xy 96.661405 -40.9684) (xy 96.715907 -40.9684) (xy 96.769855 -40.976156)
			(xy 96.82215 -40.991511) (xy 96.871727 -41.014153) (xy 96.917577 -41.043619) (xy 96.958768 -41.07931)
			(xy 96.994459 -41.120501) (xy 97.023925 -41.166351) (xy 97.046567 -41.215928) (xy 97.061922 -41.268223)
			(xy 97.069678 -41.322171) (xy 97.070164 -41.349422) (xy 97.069637 -41.378161) (xy 97.061012 -41.434987)
			(xy 97.043962 -41.489877) (xy 97.018872 -41.541589) (xy 96.986309 -41.588952) (xy 96.96704 -41.61028)
			(xy 96.960436 -41.617138) (xy 96.953324 -41.635172) (xy 96.953324 -41.724072) (xy 96.960436 -41.742106)
			(xy 96.96704 -41.748964) (xy 96.986334 -41.770271) (xy 97.018902 -41.817636) (xy 97.043995 -41.869351)
			(xy 97.061045 -41.924245) (xy 97.069666 -41.981076) (xy 97.069664 -42.038557) (xy 97.061037 -42.095387)
			(xy 97.043983 -42.150279) (xy 97.018886 -42.201992) (xy 96.986314 -42.249354) (xy 96.96704 -42.27068)
			(xy 96.960436 -42.277538) (xy 96.953324 -42.295572) (xy 96.953324 -42.384472) (xy 96.960436 -42.402506)
			(xy 96.96704 -42.409364) (xy 96.986318 -42.430685) (xy 97.018884 -42.478048) (xy 97.043975 -42.529761)
			(xy 97.061024 -42.584654) (xy 97.069645 -42.641483) (xy 97.070164 -42.670222) (xy 97.06972 -42.697593)
			(xy 97.061898 -42.751773) (xy 97.046404 -42.804277) (xy 97.025847 -42.849038) (xy 98.89185 -42.849038)
			(xy 98.895921 -42.793416) (xy 98.908047 -42.738979) (xy 98.92797 -42.686888) (xy 98.955266 -42.638253)
			(xy 98.989352 -42.59411) (xy 99.029501 -42.555401) (xy 99.074859 -42.52295) (xy 99.124459 -42.497449)
			(xy 99.177243 -42.479442) (xy 99.232086 -42.469312) (xy 99.28782 -42.467275) (xy 99.343257 -42.473375)
			(xy 99.397214 -42.487481) (xy 99.448543 -42.509293) (xy 99.496149 -42.538347) (xy 99.539017 -42.574022)
			(xy 99.576234 -42.615559) (xy 99.607007 -42.662072) (xy 99.630679 -42.712569) (xy 99.646747 -42.765976)
			(xy 99.654867 -42.821152) (xy 99.655376 -42.849038) (xy 99.654867 -42.876924) (xy 99.646747 -42.9321)
			(xy 99.630679 -42.985507) (xy 99.607007 -43.036004) (xy 99.576234 -43.082517) (xy 99.539017 -43.124054)
			(xy 99.496149 -43.159729) (xy 99.448543 -43.188783) (xy 99.397214 -43.210595) (xy 99.343257 -43.224701)
			(xy 99.28782 -43.230801) (xy 99.232086 -43.228764) (xy 99.177243 -43.218634) (xy 99.124459 -43.200627)
			(xy 99.074859 -43.175126) (xy 99.029501 -43.142675) (xy 98.989352 -43.103966) (xy 98.955266 -43.059823)
			(xy 98.92797 -43.011188) (xy 98.908047 -42.959097) (xy 98.895921 -42.90466) (xy 98.89185 -42.849038)
			(xy 97.025847 -42.849038) (xy 97.023557 -42.854024) (xy 96.993828 -42.899989) (xy 96.976184 -42.92092)
			(xy 96.97593 -42.921174) (xy 96.97034 -42.928258) (xy 96.964097 -42.945177) (xy 96.963738 -42.954194)
			(xy 96.963738 -43.02125) (xy 96.964111 -43.030265) (xy 96.970346 -43.047183) (xy 96.97593 -43.05427)
			(xy 96.976184 -43.05427) (xy 96.976184 -43.054524) (xy 96.993798 -43.075476) (xy 97.023515 -43.121443)
			(xy 97.046355 -43.171185) (xy 97.061852 -43.223682) (xy 97.069687 -43.277854) (xy 97.070164 -43.305222)
			(xy 97.069678 -43.332473) (xy 97.061922 -43.386421) (xy 97.046567 -43.438716) (xy 97.023925 -43.488293)
			(xy 96.994459 -43.534143) (xy 96.958768 -43.575334) (xy 96.917577 -43.611025) (xy 96.871727 -43.640491)
			(xy 96.82215 -43.663133) (xy 96.769855 -43.678488) (xy 96.715907 -43.686244) (xy 96.661405 -43.686244)
			(xy 96.607457 -43.678488) (xy 96.555162 -43.663133) (xy 96.505585 -43.640491) (xy 96.459735 -43.611025)
			(xy 96.418544 -43.575334) (xy 96.382853 -43.534143) (xy 96.353387 -43.488293) (xy 96.330745 -43.438716)
			(xy 96.31539 -43.386421) (xy 96.307634 -43.332473) (xy 96.307148 -43.305222) (xy 87.70497 -43.305222)
			(xy 88.082375 -43.73626) (xy 98.212908 -43.73626) (xy 98.216979 -43.680638) (xy 98.229105 -43.626201)
			(xy 98.249028 -43.57411) (xy 98.276324 -43.525475) (xy 98.31041 -43.481332) (xy 98.350559 -43.442623)
			(xy 98.395917 -43.410172) (xy 98.445517 -43.384671) (xy 98.498301 -43.366664) (xy 98.553144 -43.356534)
			(xy 98.608878 -43.354497) (xy 98.664315 -43.360597) (xy 98.718272 -43.374703) (xy 98.769601 -43.396515)
			(xy 98.817207 -43.425569) (xy 98.860075 -43.461244) (xy 98.897292 -43.502781) (xy 98.928065 -43.549294)
			(xy 98.951737 -43.599791) (xy 98.967805 -43.653198) (xy 98.975925 -43.708374) (xy 98.976434 -43.73626)
			(xy 98.975925 -43.764146) (xy 98.967805 -43.819322) (xy 98.956496 -43.85691) (xy 102.71963 -43.85691)
			(xy 102.723701 -43.801288) (xy 102.735827 -43.746851) (xy 102.75575 -43.69476) (xy 102.783046 -43.646125)
			(xy 102.817132 -43.601982) (xy 102.857281 -43.563273) (xy 102.902639 -43.530822) (xy 102.952239 -43.505321)
			(xy 103.005023 -43.487314) (xy 103.059866 -43.477184) (xy 103.1156 -43.475147) (xy 103.171037 -43.481247)
			(xy 103.224994 -43.495353) (xy 103.276323 -43.517165) (xy 103.323929 -43.546219) (xy 103.366797 -43.581894)
			(xy 103.404014 -43.623431) (xy 103.434787 -43.669944) (xy 103.458459 -43.720441) (xy 103.474527 -43.773848)
			(xy 103.482647 -43.829024) (xy 103.483156 -43.85691) (xy 103.482647 -43.884796) (xy 103.474527 -43.939972)
			(xy 103.458459 -43.993379) (xy 103.434787 -44.043876) (xy 103.404014 -44.090389) (xy 103.366797 -44.131926)
			(xy 103.323929 -44.167601) (xy 103.276323 -44.196655) (xy 103.224994 -44.218467) (xy 103.171037 -44.232573)
			(xy 103.1156 -44.238673) (xy 103.059866 -44.236636) (xy 103.005023 -44.226506) (xy 102.952239 -44.208499)
			(xy 102.902639 -44.182998) (xy 102.857281 -44.150547) (xy 102.817132 -44.111838) (xy 102.783046 -44.067695)
			(xy 102.75575 -44.01906) (xy 102.735827 -43.966969) (xy 102.723701 -43.912532) (xy 102.71963 -43.85691)
			(xy 98.956496 -43.85691) (xy 98.951737 -43.872729) (xy 98.928065 -43.923226) (xy 98.897292 -43.969739)
			(xy 98.860075 -44.011276) (xy 98.817207 -44.046951) (xy 98.769601 -44.076005) (xy 98.718272 -44.097817)
			(xy 98.664315 -44.111923) (xy 98.608878 -44.118023) (xy 98.553144 -44.115986) (xy 98.498301 -44.105856)
			(xy 98.445517 -44.087849) (xy 98.395917 -44.062348) (xy 98.350559 -44.029897) (xy 98.31041 -43.991188)
			(xy 98.276324 -43.947045) (xy 98.249028 -43.89841) (xy 98.229105 -43.846319) (xy 98.216979 -43.791882)
			(xy 98.212908 -43.73626) (xy 88.082375 -43.73626) (xy 89.289092 -45.114464) (xy 98.065334 -45.114464)
			(xy 98.069405 -45.058842) (xy 98.081531 -45.004405) (xy 98.101454 -44.952314) (xy 98.12875 -44.903679)
			(xy 98.162836 -44.859536) (xy 98.202985 -44.820827) (xy 98.248343 -44.788376) (xy 98.297943 -44.762875)
			(xy 98.350727 -44.744868) (xy 98.40557 -44.734738) (xy 98.461304 -44.732701) (xy 98.516741 -44.738801)
			(xy 98.570698 -44.752907) (xy 98.622027 -44.774719) (xy 98.669633 -44.803773) (xy 98.712501 -44.839448)
			(xy 98.749718 -44.880985) (xy 98.780491 -44.927498) (xy 98.804163 -44.977995) (xy 98.820231 -45.031402)
			(xy 98.828351 -45.086578) (xy 98.82886 -45.114464) (xy 98.828351 -45.14235) (xy 98.820231 -45.197526)
			(xy 98.804163 -45.250933) (xy 98.780491 -45.30143) (xy 98.749718 -45.347943) (xy 98.744076 -45.35424)
			(xy 102.703628 -45.35424) (xy 102.707699 -45.298618) (xy 102.719825 -45.244181) (xy 102.739748 -45.19209)
			(xy 102.767044 -45.143455) (xy 102.80113 -45.099312) (xy 102.841279 -45.060603) (xy 102.886637 -45.028152)
			(xy 102.936237 -45.002651) (xy 102.989021 -44.984644) (xy 103.043864 -44.974514) (xy 103.099598 -44.972477)
			(xy 103.155035 -44.978577) (xy 103.208992 -44.992683) (xy 103.260321 -45.014495) (xy 103.307927 -45.043549)
			(xy 103.350795 -45.079224) (xy 103.388012 -45.120761) (xy 103.418785 -45.167274) (xy 103.442457 -45.217771)
			(xy 103.458525 -45.271178) (xy 103.466645 -45.326354) (xy 103.467154 -45.35424) (xy 103.466645 -45.382126)
			(xy 103.458525 -45.437302) (xy 103.442457 -45.490709) (xy 103.418785 -45.541206) (xy 103.388012 -45.587719)
			(xy 103.350795 -45.629256) (xy 103.307927 -45.664931) (xy 103.260321 -45.693985) (xy 103.208992 -45.715797)
			(xy 103.155035 -45.729903) (xy 103.099598 -45.736003) (xy 103.043864 -45.733966) (xy 102.989021 -45.723836)
			(xy 102.936237 -45.705829) (xy 102.886637 -45.680328) (xy 102.841279 -45.647877) (xy 102.80113 -45.609168)
			(xy 102.767044 -45.565025) (xy 102.739748 -45.51639) (xy 102.719825 -45.464299) (xy 102.707699 -45.409862)
			(xy 102.703628 -45.35424) (xy 98.744076 -45.35424) (xy 98.712501 -45.38948) (xy 98.669633 -45.425155)
			(xy 98.622027 -45.454209) (xy 98.570698 -45.476021) (xy 98.516741 -45.490127) (xy 98.461304 -45.496227)
			(xy 98.40557 -45.49419) (xy 98.350727 -45.48406) (xy 98.297943 -45.466053) (xy 98.248343 -45.440552)
			(xy 98.202985 -45.408101) (xy 98.162836 -45.369392) (xy 98.12875 -45.325249) (xy 98.101454 -45.276614)
			(xy 98.081531 -45.224523) (xy 98.069405 -45.170086) (xy 98.065334 -45.114464) (xy 89.289092 -45.114464)
			(xy 90.136419 -46.082204) (xy 96.052386 -46.082204) (xy 96.052881 -46.054953) (xy 96.060637 -46.001006)
			(xy 96.075992 -45.948712) (xy 96.098632 -45.899135) (xy 96.128097 -45.853285) (xy 96.163788 -45.812095)
			(xy 96.204977 -45.776403) (xy 96.250826 -45.746937) (xy 96.300402 -45.724295) (xy 96.352696 -45.708939)
			(xy 96.406643 -45.701182) (xy 96.433894 -45.700696) (xy 96.460796 -45.701163) (xy 96.514066 -45.708734)
			(xy 96.565744 -45.723712) (xy 96.614806 -45.745802) (xy 96.660279 -45.774563) (xy 96.70126 -45.809427)
			(xy 96.736938 -45.849702) (xy 96.752156 -45.871892) (xy 96.759268 -45.882814) (xy 96.782128 -45.894752)
			(xy 96.894396 -45.89272) (xy 96.916748 -45.879766) (xy 96.923606 -45.86859) (xy 96.938537 -45.844995)
			(xy 96.974214 -45.802043) (xy 97.015771 -45.76475) (xy 97.06232 -45.733912) (xy 97.112865 -45.710187)
			(xy 97.166329 -45.694083) (xy 97.22157 -45.685943) (xy 97.249488 -45.685456) (xy 97.276481 -45.685924)
			(xy 97.329929 -45.693528) (xy 97.381772 -45.708587) (xy 97.430977 -45.730799) (xy 97.476561 -45.759723)
			(xy 97.497392 -45.776896) (xy 97.50552 -45.784008) (xy 97.526094 -45.790104) (xy 97.611438 -45.779182)
			(xy 97.621978 -45.777387) (xy 97.640263 -45.766348) (xy 97.646744 -45.757846) (xy 97.662076 -45.7366)
			(xy 97.697667 -45.698147) (xy 97.738188 -45.66493) (xy 97.782874 -45.637573) (xy 97.830886 -45.616592)
			(xy 97.881318 -45.602382) (xy 97.93322 -45.595211) (xy 97.959418 -45.594778) (xy 97.986667 -45.595293)
			(xy 98.040611 -45.603052) (xy 98.092902 -45.618408) (xy 98.142475 -45.641049) (xy 98.188321 -45.670515)
			(xy 98.229508 -45.706205) (xy 98.265196 -45.747393) (xy 98.294659 -45.793241) (xy 98.317298 -45.842815)
			(xy 98.332652 -45.895106) (xy 98.340408 -45.949051) (xy 98.340408 -46.003549) (xy 98.332652 -46.057493)
			(xy 98.317298 -46.109785) (xy 98.294659 -46.159359) (xy 98.265196 -46.205207) (xy 98.229508 -46.246395)
			(xy 98.188321 -46.282085) (xy 98.142475 -46.311551) (xy 98.092902 -46.334192) (xy 98.040611 -46.349548)
			(xy 97.986667 -46.357307) (xy 97.959418 -46.357794) (xy 97.932426 -46.357311) (xy 97.878979 -46.349708)
			(xy 97.827136 -46.334653) (xy 97.777931 -46.312444) (xy 97.732346 -46.283525) (xy 97.711514 -46.266354)
			(xy 97.703386 -46.259242) (xy 97.682812 -46.253146) (xy 97.597468 -46.264068) (xy 97.586922 -46.265834)
			(xy 97.568641 -46.276896) (xy 97.562162 -46.285404) (xy 97.544551 -46.309706) (xy 97.502954 -46.352964)
			(xy 97.479358 -46.37151) (xy 97.471484 -46.377352) (xy 97.46107 -46.394878) (xy 97.447862 -46.485302)
			(xy 97.452688 -46.504606) (xy 97.45853 -46.51248) (xy 97.45853 -46.512734) (xy 97.476028 -46.537482)
			(xy 97.503833 -46.591333) (xy 97.522771 -46.648904) (xy 97.529974 -46.693836) (xy 102.676198 -46.693836)
			(xy 102.676684 -46.666585) (xy 102.68444 -46.612637) (xy 102.699795 -46.560342) (xy 102.722437 -46.510765)
			(xy 102.751903 -46.464915) (xy 102.787594 -46.423724) (xy 102.828785 -46.388033) (xy 102.874635 -46.358567)
			(xy 102.924212 -46.335925) (xy 102.976507 -46.32057) (xy 103.030455 -46.312814) (xy 103.084957 -46.312814)
			(xy 103.138905 -46.32057) (xy 103.1912 -46.335925) (xy 103.240777 -46.358567) (xy 103.286627 -46.388033)
			(xy 103.327818 -46.423724) (xy 103.363509 -46.464915) (xy 103.392975 -46.510765) (xy 103.415617 -46.560342)
			(xy 103.430972 -46.612637) (xy 103.438728 -46.666585) (xy 103.439214 -46.693836) (xy 103.438739 -46.720263)
			(xy 103.43143 -46.772611) (xy 103.416957 -46.823446) (xy 103.395598 -46.871793) (xy 103.382064 -46.894496)
			(xy 103.38181 -46.89475) (xy 103.376473 -46.904768) (xy 103.374218 -46.927318) (xy 103.377492 -46.938184)
			(xy 103.403654 -47.01286) (xy 103.408037 -47.023376) (xy 103.424126 -47.039464) (xy 103.434642 -47.043848)
			(xy 103.434896 -47.043848) (xy 103.459415 -47.052889) (xy 103.505867 -47.076838) (xy 103.548617 -47.106899)
			(xy 103.586867 -47.14251) (xy 103.619902 -47.183006) (xy 103.647104 -47.22763) (xy 103.667965 -47.275548)
			(xy 103.682094 -47.325863) (xy 103.689227 -47.377635) (xy 103.689658 -47.403766) (xy 103.689172 -47.431017)
			(xy 103.681416 -47.484965) (xy 103.666061 -47.53726) (xy 103.643419 -47.586837) (xy 103.613953 -47.632687)
			(xy 103.578262 -47.673878) (xy 103.537071 -47.709569) (xy 103.491221 -47.739035) (xy 103.441644 -47.761677)
			(xy 103.389349 -47.777032) (xy 103.335401 -47.784788) (xy 103.280899 -47.784788) (xy 103.226951 -47.777032)
			(xy 103.174656 -47.761677) (xy 103.125079 -47.739035) (xy 103.079229 -47.709569) (xy 103.038038 -47.673878)
			(xy 103.002347 -47.632687) (xy 102.972881 -47.586837) (xy 102.950239 -47.53726) (xy 102.934884 -47.484965)
			(xy 102.927128 -47.431017) (xy 102.926642 -47.403766) (xy 102.92711 -47.377338) (xy 102.93442 -47.32499)
			(xy 102.948895 -47.274155) (xy 102.970256 -47.225809) (xy 102.983792 -47.203106) (xy 102.984046 -47.202852)
			(xy 102.989381 -47.192833) (xy 102.99164 -47.170284) (xy 102.988364 -47.159418) (xy 102.962202 -47.084742)
			(xy 102.957838 -47.074216) (xy 102.941736 -47.058132) (xy 102.931214 -47.053754) (xy 102.93096 -47.053754)
			(xy 102.906453 -47.044679) (xy 102.860001 -47.020738) (xy 102.817249 -46.990683) (xy 102.778996 -46.955076)
			(xy 102.74596 -46.914584) (xy 102.718756 -46.869963) (xy 102.697894 -46.822049) (xy 102.683763 -46.771736)
			(xy 102.676629 -46.719966) (xy 102.676198 -46.693836) (xy 97.529974 -46.693836) (xy 97.532364 -46.708745)
			(xy 97.532952 -46.739048) (xy 97.532467 -46.766298) (xy 97.524705 -46.820244) (xy 97.509346 -46.872536)
			(xy 97.486703 -46.92211) (xy 97.457235 -46.967958) (xy 97.421544 -47.009147) (xy 97.380355 -47.044838)
			(xy 97.334507 -47.074304) (xy 97.284932 -47.096947) (xy 97.23264 -47.112306) (xy 97.178694 -47.120067)
			(xy 97.151444 -47.120556) (xy 97.12541 -47.120133) (xy 97.073826 -47.113039) (xy 97.023684 -47.099004)
			(xy 96.975913 -47.078288) (xy 96.9314 -47.051275) (xy 96.910906 -47.035212) (xy 96.903154 -47.029462)
			(xy 96.884739 -47.023726) (xy 96.875092 -47.024036) (xy 96.795336 -47.030386) (xy 96.777556 -47.039022)
			(xy 96.771206 -47.046388) (xy 96.753045 -47.066053) (xy 96.712133 -47.100573) (xy 96.6668 -47.12904)
			(xy 96.617935 -47.150894) (xy 96.566495 -47.165708) (xy 96.513491 -47.173189) (xy 96.486726 -47.173642)
			(xy 96.459477 -47.173098) (xy 96.405533 -47.165346) (xy 96.353242 -47.149995) (xy 96.303667 -47.12736)
			(xy 96.257818 -47.0979) (xy 96.216628 -47.062214) (xy 96.180936 -47.02103) (xy 96.151469 -46.975186)
			(xy 96.128826 -46.925615) (xy 96.113467 -46.873326) (xy 96.105707 -46.819383) (xy 96.105218 -46.792134)
			(xy 96.105738 -46.76336) (xy 96.114389 -46.706465) (xy 96.131486 -46.651514) (xy 96.156641 -46.599754)
			(xy 96.189283 -46.552359) (xy 96.208596 -46.531022) (xy 96.215962 -46.523148) (xy 96.223074 -46.503336)
			(xy 96.215708 -46.40707) (xy 96.205802 -46.388274) (xy 96.19742 -46.38167) (xy 96.175235 -46.363445)
			(xy 96.136025 -46.32151) (xy 96.10354 -46.274174) (xy 96.078511 -46.222506) (xy 96.061505 -46.167672)
			(xy 96.052904 -46.110909) (xy 96.052386 -46.082204) (xy 90.136419 -46.082204) (xy 90.897456 -46.951392)
			(xy 90.925994 -46.984709) (xy 90.977763 -47.055537) (xy 91.023109 -47.13064) (xy 91.061681 -47.209437)
			(xy 91.093181 -47.291318) (xy 91.117365 -47.37565) (xy 91.134045 -47.46178) (xy 91.13901 -47.505366)
			(xy 91.160854 -47.713646) (xy 91.22258 -48.30699) (xy 102.553768 -48.30699) (xy 102.557839 -48.251368)
			(xy 102.569965 -48.196931) (xy 102.589888 -48.14484) (xy 102.617184 -48.096205) (xy 102.65127 -48.052062)
			(xy 102.691419 -48.013353) (xy 102.736777 -47.980902) (xy 102.786377 -47.955401) (xy 102.839161 -47.937394)
			(xy 102.894004 -47.927264) (xy 102.949738 -47.925227) (xy 103.005175 -47.931327) (xy 103.059132 -47.945433)
			(xy 103.110461 -47.967245) (xy 103.158067 -47.996299) (xy 103.200935 -48.031974) (xy 103.238152 -48.073511)
			(xy 103.268925 -48.120024) (xy 103.292597 -48.170521) (xy 103.308665 -48.223928) (xy 103.316785 -48.279104)
			(xy 103.317294 -48.30699) (xy 103.316785 -48.334876) (xy 103.308665 -48.390052) (xy 103.292597 -48.443459)
			(xy 103.268925 -48.493956) (xy 103.238152 -48.540469) (xy 103.200935 -48.582006) (xy 103.158067 -48.617681)
			(xy 103.110461 -48.646735) (xy 103.059132 -48.668547) (xy 103.005175 -48.682653) (xy 102.949738 -48.688753)
			(xy 102.894004 -48.686716) (xy 102.839161 -48.676586) (xy 102.786377 -48.658579) (xy 102.736777 -48.633078)
			(xy 102.691419 -48.600627) (xy 102.65127 -48.561918) (xy 102.617184 -48.517775) (xy 102.589888 -48.46914)
			(xy 102.569965 -48.417049) (xy 102.557839 -48.362612) (xy 102.553768 -48.30699) (xy 91.22258 -48.30699)
			(xy 91.250008 -48.570642) (xy 91.269031 -48.753014) (xy 99.168202 -48.753014) (xy 99.172273 -48.697392)
			(xy 99.184399 -48.642955) (xy 99.204322 -48.590864) (xy 99.231618 -48.542229) (xy 99.265704 -48.498086)
			(xy 99.305853 -48.459377) (xy 99.351211 -48.426926) (xy 99.400811 -48.401425) (xy 99.453595 -48.383418)
			(xy 99.508438 -48.373288) (xy 99.564172 -48.371251) (xy 99.619609 -48.377351) (xy 99.673566 -48.391457)
			(xy 99.724895 -48.413269) (xy 99.772501 -48.442323) (xy 99.815369 -48.477998) (xy 99.852586 -48.519535)
			(xy 99.883359 -48.566048) (xy 99.907031 -48.616545) (xy 99.923099 -48.669952) (xy 99.931219 -48.725128)
			(xy 99.931728 -48.753014) (xy 99.931219 -48.7809) (xy 99.923099 -48.836076) (xy 99.920655 -48.8442)
			(xy 100.18725 -48.8442) (xy 100.191321 -48.788578) (xy 100.203447 -48.734141) (xy 100.22337 -48.68205)
			(xy 100.250666 -48.633415) (xy 100.284752 -48.589272) (xy 100.324901 -48.550563) (xy 100.370259 -48.518112)
			(xy 100.419859 -48.492611) (xy 100.472643 -48.474604) (xy 100.527486 -48.464474) (xy 100.58322 -48.462437)
			(xy 100.638657 -48.468537) (xy 100.692614 -48.482643) (xy 100.743943 -48.504455) (xy 100.791549 -48.533509)
			(xy 100.834417 -48.569184) (xy 100.871634 -48.610721) (xy 100.902407 -48.657234) (xy 100.926079 -48.707731)
			(xy 100.942147 -48.761138) (xy 100.950267 -48.816314) (xy 100.950776 -48.8442) (xy 100.950267 -48.872086)
			(xy 100.947269 -48.89246) (xy 101.213918 -48.89246) (xy 101.217989 -48.836838) (xy 101.230115 -48.782401)
			(xy 101.250038 -48.73031) (xy 101.277334 -48.681675) (xy 101.31142 -48.637532) (xy 101.351569 -48.598823)
			(xy 101.396927 -48.566372) (xy 101.446527 -48.540871) (xy 101.499311 -48.522864) (xy 101.554154 -48.512734)
			(xy 101.609888 -48.510697) (xy 101.665325 -48.516797) (xy 101.719282 -48.530903) (xy 101.770611 -48.552715)
			(xy 101.818217 -48.581769) (xy 101.861085 -48.617444) (xy 101.898302 -48.658981) (xy 101.929075 -48.705494)
			(xy 101.952747 -48.755991) (xy 101.968815 -48.809398) (xy 101.976935 -48.864574) (xy 101.977444 -48.89246)
			(xy 101.976935 -48.920346) (xy 101.968815 -48.975522) (xy 101.952747 -49.028929) (xy 101.929075 -49.079426)
			(xy 101.898302 -49.125939) (xy 101.861085 -49.167476) (xy 101.818217 -49.203151) (xy 101.770611 -49.232205)
			(xy 101.719282 -49.254017) (xy 101.665325 -49.268123) (xy 101.609888 -49.274223) (xy 101.554154 -49.272186)
			(xy 101.499311 -49.262056) (xy 101.446527 -49.244049) (xy 101.396927 -49.218548) (xy 101.351569 -49.186097)
			(xy 101.31142 -49.147388) (xy 101.277334 -49.103245) (xy 101.250038 -49.05461) (xy 101.230115 -49.002519)
			(xy 101.217989 -48.948082) (xy 101.213918 -48.89246) (xy 100.947269 -48.89246) (xy 100.942147 -48.927262)
			(xy 100.926079 -48.980669) (xy 100.902407 -49.031166) (xy 100.871634 -49.077679) (xy 100.834417 -49.119216)
			(xy 100.791549 -49.154891) (xy 100.743943 -49.183945) (xy 100.692614 -49.205757) (xy 100.638657 -49.219863)
			(xy 100.58322 -49.225963) (xy 100.527486 -49.223926) (xy 100.472643 -49.213796) (xy 100.419859 -49.195789)
			(xy 100.370259 -49.170288) (xy 100.324901 -49.137837) (xy 100.284752 -49.099128) (xy 100.250666 -49.054985)
			(xy 100.22337 -49.00635) (xy 100.203447 -48.954259) (xy 100.191321 -48.899822) (xy 100.18725 -48.8442)
			(xy 99.920655 -48.8442) (xy 99.907031 -48.889483) (xy 99.883359 -48.93998) (xy 99.852586 -48.986493)
			(xy 99.815369 -49.02803) (xy 99.772501 -49.063705) (xy 99.724895 -49.092759) (xy 99.673566 -49.114571)
			(xy 99.619609 -49.128677) (xy 99.564172 -49.134777) (xy 99.508438 -49.13274) (xy 99.453595 -49.12261)
			(xy 99.400811 -49.104603) (xy 99.351211 -49.079102) (xy 99.305853 -49.046651) (xy 99.265704 -49.007942)
			(xy 99.231618 -48.963799) (xy 99.204322 -48.915164) (xy 99.184399 -48.863073) (xy 99.172273 -48.808636)
			(xy 99.168202 -48.753014) (xy 91.269031 -48.753014) (xy 91.317064 -49.213516) (xy 91.319604 -49.224946)
			(xy 91.522804 -49.81067) (xy 91.537028 -49.853106) (xy 91.558652 -49.939962) (xy 91.572324 -50.028418)
			(xy 91.575636 -50.073052) (xy 91.584272 -50.210212) (xy 91.635041 -51.019456) (xy 102.749348 -51.019456)
			(xy 102.753419 -50.963834) (xy 102.765545 -50.909397) (xy 102.785468 -50.857306) (xy 102.812764 -50.808671)
			(xy 102.84685 -50.764528) (xy 102.886999 -50.725819) (xy 102.932357 -50.693368) (xy 102.981957 -50.667867)
			(xy 103.034741 -50.64986) (xy 103.089584 -50.63973) (xy 103.145318 -50.637693) (xy 103.200755 -50.643793)
			(xy 103.254712 -50.657899) (xy 103.306041 -50.679711) (xy 103.353647 -50.708765) (xy 103.396515 -50.74444)
			(xy 103.433732 -50.785977) (xy 103.464505 -50.83249) (xy 103.488177 -50.882987) (xy 103.504245 -50.936394)
			(xy 103.512365 -50.99157) (xy 103.512874 -51.019456) (xy 103.512365 -51.047342) (xy 103.504245 -51.102518)
			(xy 103.488177 -51.155925) (xy 103.464505 -51.206422) (xy 103.433732 -51.252935) (xy 103.396515 -51.294472)
			(xy 103.353647 -51.330147) (xy 103.306041 -51.359201) (xy 103.254712 -51.381013) (xy 103.200755 -51.395119)
			(xy 103.145318 -51.401219) (xy 103.089584 -51.399182) (xy 103.034741 -51.389052) (xy 102.981957 -51.371045)
			(xy 102.932357 -51.345544) (xy 102.886999 -51.313093) (xy 102.84685 -51.274384) (xy 102.812764 -51.230241)
			(xy 102.785468 -51.181606) (xy 102.765545 -51.129515) (xy 102.753419 -51.075078) (xy 102.749348 -51.019456)
			(xy 91.635041 -51.019456) (xy 91.718892 -52.356004) (xy 91.720416 -52.36591) (xy 91.722872 -52.373763)
			(xy 91.731948 -52.387478) (xy 91.738196 -52.392834) (xy 91.759024 -52.409344) (xy 91.76893 -52.415694)
			(xy 91.776932 -52.419078) (xy 91.794211 -52.420783) (xy 91.802712 -52.418996) (xy 91.827098 -52.413426)
			(xy 91.876761 -52.407444) (xy 91.901772 -52.407058) (xy 91.902026 -52.407058) (xy 91.931979 -52.407594)
			(xy 91.991275 -52.416123) (xy 92.048754 -52.433004) (xy 92.103245 -52.457893) (xy 92.153639 -52.490283)
			(xy 92.198912 -52.529515) (xy 92.23814 -52.574791) (xy 92.270526 -52.625189) (xy 92.295409 -52.679682)
			(xy 92.312285 -52.737162) (xy 92.320809 -52.796459) (xy 92.32138 -52.826412) (xy 92.320932 -52.853854)
			(xy 92.313772 -52.908269) (xy 92.299577 -52.961286) (xy 92.278589 -53.011998) (xy 92.251166 -53.059541)
			(xy 92.217777 -53.1031) (xy 92.198698 -53.12283) (xy 92.193872 -53.12791) (xy 92.178378 -53.164232)
			(xy 92.178378 -53.178964) (xy 92.178744 -53.186999) (xy 92.183796 -53.20226) (xy 92.188284 -53.208936)
			(xy 92.190824 -53.211984) (xy 92.208225 -53.232856) (xy 92.237552 -53.2786) (xy 92.260078 -53.32805)
			(xy 92.275348 -53.380199) (xy 92.283049 -53.433989) (xy 92.283534 -53.461158) (xy 92.283534 -53.461412)
			(xy 92.283108 -53.486923) (xy 92.276312 -53.53749) (xy 92.262842 -53.586701) (xy 92.242938 -53.633681)
			(xy 92.216955 -53.677591) (xy 92.201492 -53.697886) (xy 92.198952 -53.700934) (xy 92.197936 -53.702458)
			(xy 92.194634 -53.709062) (xy 92.192289 -53.714284) (xy 92.189721 -53.725438) (xy 92.189554 -53.73116)
			(xy 92.189554 -53.763164) (xy 92.178378 -53.763164) (xy 92.178378 -53.813964) (xy 92.178712 -53.822568)
			(xy 92.184422 -53.838801) (xy 92.189554 -53.845714) (xy 92.190824 -53.847238) (xy 92.208218 -53.868115)
			(xy 92.237537 -53.913864) (xy 92.260066 -53.963312) (xy 92.275348 -54.015457) (xy 92.283073 -54.069243)
			(xy 92.283534 -54.096412) (xy 92.283108 -54.121923) (xy 92.276312 -54.17249) (xy 92.262842 -54.221701)
			(xy 92.242938 -54.268681) (xy 92.216955 -54.312591) (xy 92.201492 -54.332886) (xy 92.198952 -54.335934)
			(xy 92.197936 -54.337458) (xy 92.194634 -54.344062) (xy 92.192289 -54.349284) (xy 92.189721 -54.360438)
			(xy 92.189554 -54.36616) (xy 92.189554 -54.398164) (xy 92.178378 -54.398164) (xy 92.178378 -54.448964)
			(xy 92.178712 -54.457568) (xy 92.184422 -54.473801) (xy 92.189554 -54.480714) (xy 92.190824 -54.482238)
			(xy 92.208218 -54.503115) (xy 92.237537 -54.548864) (xy 92.260066 -54.598312) (xy 92.275348 -54.650457)
			(xy 92.283073 -54.704243) (xy 92.283534 -54.731412) (xy 92.282981 -54.760556) (xy 92.278278 -54.791102)
			(xy 94.176342 -54.791102) (xy 94.176799 -54.763731) (xy 94.184617 -54.709551) (xy 94.200108 -54.657048)
			(xy 94.222952 -54.607301) (xy 94.252679 -54.561335) (xy 94.270322 -54.540404) (xy 94.270576 -54.54015)
			(xy 94.276157 -54.53306) (xy 94.282405 -54.516146) (xy 94.282768 -54.50713) (xy 94.282768 -54.440074)
			(xy 94.28243 -54.431055) (xy 94.27617 -54.414138) (xy 94.270576 -54.407054) (xy 94.270322 -54.407054)
			(xy 94.270322 -54.4068) (xy 94.252683 -54.385866) (xy 94.222959 -54.339898) (xy 94.200114 -54.290152)
			(xy 94.184618 -54.23765) (xy 94.176789 -54.183472) (xy 94.176789 -54.128731) (xy 94.184617 -54.074553)
			(xy 94.200113 -54.022051) (xy 94.222958 -53.972305) (xy 94.252682 -53.926337) (xy 94.270322 -53.905404)
			(xy 94.270576 -53.90515) (xy 94.276157 -53.89806) (xy 94.282405 -53.881146) (xy 94.282768 -53.87213)
			(xy 94.282768 -53.805074) (xy 94.28243 -53.796055) (xy 94.27617 -53.779138) (xy 94.270576 -53.772054)
			(xy 94.270322 -53.772054) (xy 94.270322 -53.7718) (xy 94.252683 -53.750866) (xy 94.222959 -53.704898)
			(xy 94.200114 -53.655152) (xy 94.184618 -53.60265) (xy 94.176789 -53.548472) (xy 94.176789 -53.493731)
			(xy 94.184617 -53.439553) (xy 94.200113 -53.387051) (xy 94.222958 -53.337305) (xy 94.252682 -53.291337)
			(xy 94.270322 -53.270404) (xy 94.270576 -53.27015) (xy 94.276157 -53.26306) (xy 94.282405 -53.246146)
			(xy 94.282768 -53.23713) (xy 94.282768 -53.170074) (xy 94.28243 -53.161055) (xy 94.27617 -53.144138)
			(xy 94.270576 -53.137054) (xy 94.270322 -53.137054) (xy 94.270322 -53.1368) (xy 94.252673 -53.115876)
			(xy 94.222962 -53.069901) (xy 94.200127 -53.020152) (xy 94.184639 -52.967649) (xy 94.176814 -52.913472)
			(xy 94.176342 -52.886102) (xy 94.176828 -52.858851) (xy 94.184584 -52.804903) (xy 94.199939 -52.752608)
			(xy 94.222581 -52.703031) (xy 94.252047 -52.657181) (xy 94.287738 -52.61599) (xy 94.328929 -52.580299)
			(xy 94.374779 -52.550833) (xy 94.424356 -52.528191) (xy 94.476651 -52.512836) (xy 94.530599 -52.50508)
			(xy 94.585101 -52.50508) (xy 94.639049 -52.512836) (xy 94.691344 -52.528191) (xy 94.730453 -52.546052)
			(xy 99.679473 -52.546052) (xy 99.679473 -52.491548) (xy 99.68723 -52.437599) (xy 99.702586 -52.385303)
			(xy 99.725228 -52.335725) (xy 99.754695 -52.289874) (xy 99.790387 -52.248683) (xy 99.831579 -52.212991)
			(xy 99.87743 -52.183525) (xy 99.927009 -52.160884) (xy 99.979305 -52.145529) (xy 100.033254 -52.137773)
			(xy 100.060506 -52.13731) (xy 100.087876 -52.13777) (xy 100.142056 -52.145589) (xy 100.194559 -52.161079)
			(xy 100.244306 -52.183922) (xy 100.290273 -52.213648) (xy 100.311204 -52.23129) (xy 100.311458 -52.231544)
			(xy 100.318549 -52.237124) (xy 100.335462 -52.243374) (xy 100.344478 -52.243736) (xy 100.411534 -52.243736)
			(xy 100.420552 -52.243388) (xy 100.437468 -52.237133) (xy 100.444554 -52.231544) (xy 100.444554 -52.23129)
			(xy 100.444808 -52.23129) (xy 100.465741 -52.213649) (xy 100.511709 -52.183925) (xy 100.561455 -52.161079)
			(xy 100.613957 -52.145583) (xy 100.668135 -52.137754) (xy 100.722877 -52.137754) (xy 100.777055 -52.145583)
			(xy 100.829557 -52.161079) (xy 100.879303 -52.183925) (xy 100.925271 -52.213649) (xy 100.946204 -52.23129)
			(xy 100.946458 -52.231544) (xy 100.953549 -52.237124) (xy 100.970462 -52.243374) (xy 100.979478 -52.243736)
			(xy 101.046534 -52.243736) (xy 101.055552 -52.243388) (xy 101.072468 -52.237133) (xy 101.079554 -52.231544)
			(xy 101.079554 -52.23129) (xy 101.079808 -52.23129) (xy 101.100725 -52.213632) (xy 101.146702 -52.183923)
			(xy 101.196453 -52.161091) (xy 101.248957 -52.145605) (xy 101.303136 -52.137781) (xy 101.330506 -52.13731)
			(xy 101.357758 -52.13776) (xy 101.411708 -52.145518) (xy 101.464004 -52.160874) (xy 101.513583 -52.183517)
			(xy 101.559435 -52.212985) (xy 101.600626 -52.248678) (xy 101.636319 -52.28987) (xy 101.665786 -52.335722)
			(xy 101.688428 -52.385301) (xy 101.703783 -52.437598) (xy 101.71154 -52.491548) (xy 101.71154 -52.546052)
			(xy 101.705595 -52.587398) (xy 102.75519 -52.587398) (xy 102.759261 -52.531776) (xy 102.771387 -52.477339)
			(xy 102.79131 -52.425248) (xy 102.818606 -52.376613) (xy 102.852692 -52.33247) (xy 102.892841 -52.293761)
			(xy 102.938199 -52.26131) (xy 102.987799 -52.235809) (xy 103.040583 -52.217802) (xy 103.095426 -52.207672)
			(xy 103.15116 -52.205635) (xy 103.206597 -52.211735) (xy 103.260554 -52.225841) (xy 103.311883 -52.247653)
			(xy 103.359489 -52.276707) (xy 103.402357 -52.312382) (xy 103.439574 -52.353919) (xy 103.470347 -52.400432)
			(xy 103.494019 -52.450929) (xy 103.510087 -52.504336) (xy 103.518207 -52.559512) (xy 103.518716 -52.587398)
			(xy 103.518207 -52.615284) (xy 103.510087 -52.67046) (xy 103.494019 -52.723867) (xy 103.470347 -52.774364)
			(xy 103.439574 -52.820877) (xy 103.402357 -52.862414) (xy 103.359489 -52.898089) (xy 103.311883 -52.927143)
			(xy 103.260554 -52.948955) (xy 103.206597 -52.963061) (xy 103.15116 -52.969161) (xy 103.095426 -52.967124)
			(xy 103.040583 -52.956994) (xy 102.987799 -52.938987) (xy 102.938199 -52.913486) (xy 102.892841 -52.881035)
			(xy 102.852692 -52.842326) (xy 102.818606 -52.798183) (xy 102.79131 -52.749548) (xy 102.771387 -52.697457)
			(xy 102.759261 -52.64302) (xy 102.75519 -52.587398) (xy 101.705595 -52.587398) (xy 101.703783 -52.600002)
			(xy 101.688428 -52.652299) (xy 101.665786 -52.701878) (xy 101.636319 -52.74773) (xy 101.600626 -52.788922)
			(xy 101.559435 -52.824615) (xy 101.513583 -52.854083) (xy 101.464004 -52.876726) (xy 101.411708 -52.892082)
			(xy 101.357758 -52.89984) (xy 101.330506 -52.900326) (xy 101.303135 -52.899874) (xy 101.248955 -52.892056)
			(xy 101.196451 -52.876564) (xy 101.146704 -52.853719) (xy 101.100738 -52.82399) (xy 101.079808 -52.806346)
			(xy 101.079554 -52.806092) (xy 101.072457 -52.800521) (xy 101.055548 -52.794265) (xy 101.046534 -52.7939)
			(xy 100.979478 -52.7939) (xy 100.97046 -52.794247) (xy 100.953543 -52.800501) (xy 100.946458 -52.806092)
			(xy 100.946204 -52.806346) (xy 100.925271 -52.823987) (xy 100.879303 -52.853711) (xy 100.829557 -52.876557)
			(xy 100.777055 -52.892053) (xy 100.722877 -52.899882) (xy 100.668135 -52.899882) (xy 100.613957 -52.892053)
			(xy 100.561455 -52.876557) (xy 100.511709 -52.853711) (xy 100.465741 -52.823987) (xy 100.444808 -52.806346)
			(xy 100.444554 -52.806092) (xy 100.437457 -52.800521) (xy 100.420548 -52.794265) (xy 100.411534 -52.7939)
			(xy 100.344478 -52.7939) (xy 100.33546 -52.794247) (xy 100.318543 -52.800501) (xy 100.311458 -52.806092)
			(xy 100.311458 -52.806346) (xy 100.311204 -52.806346) (xy 100.290274 -52.823988) (xy 100.244302 -52.853701)
			(xy 100.194554 -52.876538) (xy 100.142052 -52.892028) (xy 100.087875 -52.899854) (xy 100.060506 -52.900326)
			(xy 100.033254 -52.899827) (xy 99.979305 -52.892071) (xy 99.927009 -52.876716) (xy 99.87743 -52.854075)
			(xy 99.831579 -52.824609) (xy 99.790387 -52.788917) (xy 99.754695 -52.747726) (xy 99.725228 -52.701875)
			(xy 99.702586 -52.652297) (xy 99.68723 -52.600001) (xy 99.679473 -52.546052) (xy 94.730453 -52.546052)
			(xy 94.740921 -52.550833) (xy 94.786771 -52.580299) (xy 94.827962 -52.61599) (xy 94.863653 -52.657181)
			(xy 94.893119 -52.703031) (xy 94.915761 -52.752608) (xy 94.931116 -52.804903) (xy 94.938872 -52.858851)
			(xy 94.939358 -52.886102) (xy 94.938903 -52.913473) (xy 94.931084 -52.967653) (xy 94.915593 -53.020156)
			(xy 94.892749 -53.069903) (xy 94.863021 -53.115869) (xy 94.845378 -53.1368) (xy 94.845124 -53.137054)
			(xy 94.839542 -53.144143) (xy 94.833294 -53.161058) (xy 94.832932 -53.170074) (xy 94.832932 -53.23713)
			(xy 94.833268 -53.246149) (xy 94.839529 -53.263066) (xy 94.845124 -53.27015) (xy 94.845378 -53.27015)
			(xy 94.845378 -53.270404) (xy 94.86302 -53.291335) (xy 94.892745 -53.337303) (xy 94.91559 -53.38705)
			(xy 94.931086 -53.439552) (xy 94.938914 -53.493731) (xy 94.938914 -53.548472) (xy 94.931085 -53.602651)
			(xy 94.915589 -53.655153) (xy 94.892743 -53.704899) (xy 94.863019 -53.750867) (xy 94.846448 -53.77053)
			(xy 95.21063 -53.77053) (xy 95.211158 -53.741613) (xy 95.219884 -53.684442) (xy 95.237139 -53.629243)
			(xy 95.262529 -53.577281) (xy 95.295471 -53.529747) (xy 95.335211 -53.48773) (xy 95.357696 -53.46954)
			(xy 95.366475 -53.461905) (xy 95.376674 -53.441026) (xy 95.377254 -53.429408) (xy 95.377254 -53.349652)
			(xy 95.376744 -53.338016) (xy 95.366536 -53.317106) (xy 95.357696 -53.30952) (xy 95.335221 -53.291319)
			(xy 95.295486 -53.249301) (xy 95.262546 -53.201768) (xy 95.237156 -53.149809) (xy 95.219898 -53.094613)
			(xy 95.211166 -53.037445) (xy 95.21063 -53.00853) (xy 95.211083 -52.981276) (xy 95.218837 -52.927323)
			(xy 95.234191 -52.875023) (xy 95.256833 -52.82544) (xy 95.286302 -52.779585) (xy 95.321997 -52.738391)
			(xy 95.363191 -52.702697) (xy 95.409047 -52.673229) (xy 95.45863 -52.650589) (xy 95.510931 -52.635236)
			(xy 95.564884 -52.627483) (xy 95.592138 -52.627022) (xy 95.618453 -52.627457) (xy 95.670583 -52.634698)
			(xy 95.721227 -52.649023) (xy 95.769426 -52.670161) (xy 95.814269 -52.697713) (xy 95.854907 -52.731158)
			(xy 95.873062 -52.750212) (xy 95.880594 -52.757601) (xy 95.899866 -52.766132) (xy 95.9104 -52.766722)
			(xy 95.985076 -52.766722) (xy 95.995625 -52.766187) (xy 96.01492 -52.757655) (xy 96.022414 -52.750212)
			(xy 96.040572 -52.731159) (xy 96.081201 -52.697701) (xy 96.126041 -52.670141) (xy 96.174241 -52.649002)
			(xy 96.224888 -52.634685) (xy 96.277022 -52.62746) (xy 96.303338 -52.627022) (xy 96.330592 -52.627443)
			(xy 96.384543 -52.635205) (xy 96.436841 -52.650566) (xy 96.48642 -52.673214) (xy 96.532272 -52.702687)
			(xy 96.573463 -52.738386) (xy 96.609154 -52.779583) (xy 96.638618 -52.825439) (xy 96.661257 -52.875023)
			(xy 96.676609 -52.927323) (xy 96.684362 -52.981276) (xy 96.684846 -53.00853) (xy 96.684382 -53.036197)
			(xy 96.676377 -53.09095) (xy 96.660554 -53.143973) (xy 96.637244 -53.194158) (xy 96.606934 -53.240454)
			(xy 96.570261 -53.28189) (xy 96.527991 -53.317599) (xy 96.50476 -53.332634) (xy 96.495071 -53.339256)
			(xy 96.482633 -53.359128) (xy 96.480884 -53.370734) (xy 96.47301 -53.450744) (xy 96.47237 -53.462382)
			(xy 96.480457 -53.484219) (xy 96.488504 -53.492654) (xy 96.488758 -53.492908) (xy 96.507317 -53.511011)
			(xy 96.5399 -53.551337) (xy 96.566716 -53.595706) (xy 96.587273 -53.643301) (xy 96.601191 -53.693242)
			(xy 96.608212 -53.744608) (xy 96.608646 -53.77053) (xy 96.60815 -53.79778) (xy 96.600391 -53.851726)
			(xy 96.585034 -53.904018) (xy 96.562392 -53.953593) (xy 96.532926 -53.999441) (xy 96.497236 -54.04063)
			(xy 96.456048 -54.076321) (xy 96.4102 -54.105788) (xy 96.360625 -54.128431) (xy 96.308333 -54.143789)
			(xy 96.254388 -54.15155) (xy 96.227138 -54.152038) (xy 96.199768 -54.151565) (xy 96.145588 -54.143751)
			(xy 96.093085 -54.128264) (xy 96.043338 -54.105424) (xy 95.997371 -54.075699) (xy 95.97644 -54.058058)
			(xy 95.976186 -54.057804) (xy 95.969107 -54.052206) (xy 95.952185 -54.045966) (xy 95.943166 -54.045612)
			(xy 95.87611 -54.045612) (xy 95.867093 -54.045971) (xy 95.850176 -54.052217) (xy 95.84309 -54.057804)
			(xy 95.84309 -54.058058) (xy 95.842836 -54.058058) (xy 95.821896 -54.075687) (xy 95.775926 -54.105402)
			(xy 95.726181 -54.12824) (xy 95.673681 -54.143734) (xy 95.619507 -54.151563) (xy 95.592138 -54.152038)
			(xy 95.564887 -54.151509) (xy 95.51094 -54.143758) (xy 95.458646 -54.128409) (xy 95.409068 -54.105773)
			(xy 95.363216 -54.076312) (xy 95.322023 -54.040625) (xy 95.286329 -53.999439) (xy 95.25686 -53.953592)
			(xy 95.234215 -53.904018) (xy 95.218856 -53.851726) (xy 95.211095 -53.79778) (xy 95.21063 -53.77053)
			(xy 94.846448 -53.77053) (xy 94.845378 -53.7718) (xy 94.845124 -53.772054) (xy 94.839542 -53.779143)
			(xy 94.833294 -53.796058) (xy 94.832932 -53.805074) (xy 94.832932 -53.87213) (xy 94.833268 -53.881149)
			(xy 94.839529 -53.898066) (xy 94.845124 -53.90515) (xy 94.845378 -53.90515) (xy 94.845378 -53.905404)
			(xy 94.86302 -53.926335) (xy 94.892745 -53.972303) (xy 94.91559 -54.02205) (xy 94.931086 -54.074552)
			(xy 94.938914 -54.128731) (xy 94.938914 -54.183472) (xy 94.931085 -54.237651) (xy 94.915589 -54.290153)
			(xy 94.901796 -54.320186) (xy 97.130362 -54.320186) (xy 97.130805 -54.292815) (xy 97.138626 -54.238634)
			(xy 97.15412 -54.18613) (xy 97.176967 -54.136384) (xy 97.206698 -54.090418) (xy 97.224342 -54.069488)
			(xy 97.224596 -54.069234) (xy 97.230174 -54.062142) (xy 97.236426 -54.045229) (xy 97.236788 -54.036214)
			(xy 97.236788 -53.969158) (xy 97.236406 -53.960144) (xy 97.230176 -53.943226) (xy 97.224596 -53.936138)
			(xy 97.224342 -53.936138) (xy 97.224342 -53.935884) (xy 97.206735 -53.914926) (xy 97.177017 -53.868961)
			(xy 97.154174 -53.81922) (xy 97.138676 -53.766725) (xy 97.13084 -53.712553) (xy 97.130362 -53.685186)
			(xy 97.130848 -53.657935) (xy 97.138604 -53.603987) (xy 97.153959 -53.551692) (xy 97.176601 -53.502115)
			(xy 97.206067 -53.456265) (xy 97.241758 -53.415074) (xy 97.282949 -53.379383) (xy 97.328799 -53.349917)
			(xy 97.378376 -53.327275) (xy 97.430671 -53.31192) (xy 97.484619 -53.304164) (xy 97.539121 -53.304164)
			(xy 97.593069 -53.31192) (xy 97.645364 -53.327275) (xy 97.694941 -53.349917) (xy 97.740791 -53.379383)
			(xy 97.781982 -53.415074) (xy 97.817673 -53.456265) (xy 97.847139 -53.502115) (xy 97.869781 -53.551692)
			(xy 97.885136 -53.603987) (xy 97.892892 -53.657935) (xy 97.893378 -53.685186) (xy 97.892909 -53.712556)
			(xy 97.885093 -53.766735) (xy 97.869605 -53.819239) (xy 97.846763 -53.868986) (xy 97.817039 -53.914952)
			(xy 97.799398 -53.935884) (xy 97.799144 -53.936138) (xy 97.793571 -53.943233) (xy 97.787317 -53.960144)
			(xy 97.786952 -53.969158) (xy 97.786952 -54.036214) (xy 97.787291 -54.045233) (xy 97.79355 -54.06215)
			(xy 97.799144 -54.069234) (xy 97.799398 -54.069234) (xy 97.799398 -54.069488) (xy 97.817045 -54.090414)
			(xy 97.846755 -54.136388) (xy 97.86959 -54.186137) (xy 97.885079 -54.23864) (xy 97.892905 -54.292816)
			(xy 97.893378 -54.320186) (xy 97.892892 -54.347437) (xy 97.885136 -54.401385) (xy 97.869781 -54.45368)
			(xy 97.847139 -54.503257) (xy 97.817673 -54.549107) (xy 97.781982 -54.590298) (xy 97.740791 -54.625989)
			(xy 97.694941 -54.655455) (xy 97.645364 -54.678097) (xy 97.593069 -54.693452) (xy 97.539121 -54.701208)
			(xy 97.484619 -54.701208) (xy 97.430671 -54.693452) (xy 97.378376 -54.678097) (xy 97.328799 -54.655455)
			(xy 97.282949 -54.625989) (xy 97.241758 -54.590298) (xy 97.206067 -54.549107) (xy 97.176601 -54.503257)
			(xy 97.153959 -54.45368) (xy 97.138604 -54.401385) (xy 97.130848 -54.347437) (xy 97.130362 -54.320186)
			(xy 94.901796 -54.320186) (xy 94.892743 -54.339899) (xy 94.863019 -54.385867) (xy 94.845378 -54.4068)
			(xy 94.845124 -54.407054) (xy 94.839542 -54.414143) (xy 94.833294 -54.431058) (xy 94.832932 -54.440074)
			(xy 94.832932 -54.50713) (xy 94.833268 -54.516149) (xy 94.839529 -54.533066) (xy 94.845124 -54.54015)
			(xy 94.845378 -54.54015) (xy 94.845378 -54.540404) (xy 94.863029 -54.561327) (xy 94.89274 -54.607302)
			(xy 94.915574 -54.657052) (xy 94.931062 -54.709554) (xy 94.938886 -54.763732) (xy 94.939003 -54.770528)
			(xy 98.070924 -54.770528) (xy 98.071401 -54.743158) (xy 98.079215 -54.688979) (xy 98.094701 -54.636476)
			(xy 98.117541 -54.586729) (xy 98.147264 -54.540762) (xy 98.164904 -54.51983) (xy 98.165158 -54.519576)
			(xy 98.170768 -54.512505) (xy 98.176999 -54.495576) (xy 98.17735 -54.486556) (xy 98.17735 -54.4195)
			(xy 98.177004 -54.410482) (xy 98.17075 -54.393564) (xy 98.165158 -54.38648) (xy 98.164904 -54.38648)
			(xy 98.164904 -54.386226) (xy 98.147264 -54.365294) (xy 98.117552 -54.319322) (xy 98.094716 -54.269574)
			(xy 98.079226 -54.217073) (xy 98.071398 -54.162897) (xy 98.070924 -54.135528) (xy 98.07141 -54.108277)
			(xy 98.079166 -54.054329) (xy 98.094521 -54.002034) (xy 98.117163 -53.952457) (xy 98.146629 -53.906607)
			(xy 98.18232 -53.865416) (xy 98.223511 -53.829725) (xy 98.269361 -53.800259) (xy 98.318938 -53.777617)
			(xy 98.371233 -53.762262) (xy 98.425181 -53.754506) (xy 98.479683 -53.754506) (xy 98.533631 -53.762262)
			(xy 98.585926 -53.777617) (xy 98.635503 -53.800259) (xy 98.681353 -53.829725) (xy 98.722544 -53.865416)
			(xy 98.758235 -53.906607) (xy 98.787701 -53.952457) (xy 98.792776 -53.96357) (xy 102.771954 -53.96357)
			(xy 102.776025 -53.907948) (xy 102.788151 -53.853511) (xy 102.808074 -53.80142) (xy 102.83537 -53.752785)
			(xy 102.869456 -53.708642) (xy 102.909605 -53.669933) (xy 102.954963 -53.637482) (xy 103.004563 -53.611981)
			(xy 103.057347 -53.593974) (xy 103.11219 -53.583844) (xy 103.167924 -53.581807) (xy 103.223361 -53.587907)
			(xy 103.277318 -53.602013) (xy 103.328647 -53.623825) (xy 103.376253 -53.652879) (xy 103.419121 -53.688554)
			(xy 103.456338 -53.730091) (xy 103.487111 -53.776604) (xy 103.510783 -53.827101) (xy 103.526851 -53.880508)
			(xy 103.534971 -53.935684) (xy 103.53548 -53.96357) (xy 103.534971 -53.991456) (xy 103.526851 -54.046632)
			(xy 103.510783 -54.100039) (xy 103.487111 -54.150536) (xy 103.456338 -54.197049) (xy 103.419121 -54.238586)
			(xy 103.376253 -54.274261) (xy 103.328647 -54.303315) (xy 103.277318 -54.325127) (xy 103.223361 -54.339233)
			(xy 103.167924 -54.345333) (xy 103.11219 -54.343296) (xy 103.057347 -54.333166) (xy 103.004563 -54.315159)
			(xy 102.954963 -54.289658) (xy 102.909605 -54.257207) (xy 102.869456 -54.218498) (xy 102.83537 -54.174355)
			(xy 102.808074 -54.12572) (xy 102.788151 -54.073629) (xy 102.776025 -54.019192) (xy 102.771954 -53.96357)
			(xy 98.792776 -53.96357) (xy 98.810343 -54.002034) (xy 98.825698 -54.054329) (xy 98.833454 -54.108277)
			(xy 98.83394 -54.135528) (xy 98.833505 -54.1629) (xy 98.825682 -54.217081) (xy 98.810186 -54.269585)
			(xy 98.787337 -54.319331) (xy 98.757605 -54.365296) (xy 98.73996 -54.386226) (xy 98.739706 -54.38648)
			(xy 98.734122 -54.393569) (xy 98.727874 -54.410484) (xy 98.727514 -54.4195) (xy 98.727514 -54.486556)
			(xy 98.727889 -54.495571) (xy 98.734124 -54.512488) (xy 98.739706 -54.519576) (xy 98.73996 -54.519576)
			(xy 98.73996 -54.51983) (xy 98.757574 -54.540783) (xy 98.787291 -54.586749) (xy 98.810132 -54.636491)
			(xy 98.825629 -54.688988) (xy 98.833463 -54.74316) (xy 98.83394 -54.770528) (xy 98.833454 -54.797779)
			(xy 98.825698 -54.851727) (xy 98.810343 -54.904022) (xy 98.787701 -54.953599) (xy 98.758235 -54.999449)
			(xy 98.722544 -55.04064) (xy 98.681353 -55.076331) (xy 98.635503 -55.105797) (xy 98.585926 -55.128439)
			(xy 98.533631 -55.143794) (xy 98.479683 -55.15155) (xy 98.425181 -55.15155) (xy 98.371233 -55.143794)
			(xy 98.318938 -55.128439) (xy 98.269361 -55.105797) (xy 98.223511 -55.076331) (xy 98.18232 -55.04064)
			(xy 98.146629 -54.999449) (xy 98.117163 -54.953599) (xy 98.094521 -54.904022) (xy 98.079166 -54.851727)
			(xy 98.07141 -54.797779) (xy 98.070924 -54.770528) (xy 94.939003 -54.770528) (xy 94.939358 -54.791102)
			(xy 94.938872 -54.818353) (xy 94.931116 -54.872301) (xy 94.915761 -54.924596) (xy 94.893119 -54.974173)
			(xy 94.863653 -55.020023) (xy 94.827962 -55.061214) (xy 94.786771 -55.096905) (xy 94.740921 -55.126371)
			(xy 94.691344 -55.149013) (xy 94.639049 -55.164368) (xy 94.585101 -55.172124) (xy 94.530599 -55.172124)
			(xy 94.476651 -55.164368) (xy 94.424356 -55.149013) (xy 94.374779 -55.126371) (xy 94.328929 -55.096905)
			(xy 94.287738 -55.061214) (xy 94.252047 -55.020023) (xy 94.222581 -54.974173) (xy 94.199939 -54.924596)
			(xy 94.184584 -54.872301) (xy 94.176828 -54.818353) (xy 94.176342 -54.791102) (xy 92.278278 -54.791102)
			(xy 92.274111 -54.818164) (xy 92.25658 -54.873752) (xy 92.230796 -54.926026) (xy 92.197359 -54.973769)
			(xy 92.157047 -55.015868) (xy 92.1108 -55.051345) (xy 92.059694 -55.079372) (xy 92.004918 -55.099298)
			(xy 91.976448 -55.105554) (xy 91.974162 -55.106062) (xy 91.965386 -55.108623) (xy 91.950311 -55.11894)
			(xy 91.9398 -55.133881) (xy 91.935181 -55.151555) (xy 91.935808 -55.160672) (xy 91.966542 -55.455058)
			(xy 91.994378 -55.722266) (xy 103.833928 -55.722266) (xy 103.837999 -55.666644) (xy 103.850125 -55.612207)
			(xy 103.870048 -55.560116) (xy 103.897344 -55.511481) (xy 103.93143 -55.467338) (xy 103.971579 -55.428629)
			(xy 104.016937 -55.396178) (xy 104.066537 -55.370677) (xy 104.119321 -55.35267) (xy 104.174164 -55.34254)
			(xy 104.229898 -55.340503) (xy 104.285335 -55.346603) (xy 104.339292 -55.360709) (xy 104.390621 -55.382521)
			(xy 104.438227 -55.411575) (xy 104.481095 -55.44725) (xy 104.518312 -55.488787) (xy 104.549085 -55.5353)
			(xy 104.572757 -55.585797) (xy 104.588825 -55.639204) (xy 104.596945 -55.69438) (xy 104.597454 -55.722266)
			(xy 104.596945 -55.750152) (xy 104.588825 -55.805328) (xy 104.572757 -55.858735) (xy 104.549085 -55.909232)
			(xy 104.518312 -55.955745) (xy 104.481095 -55.997282) (xy 104.438227 -56.032957) (xy 104.390621 -56.062011)
			(xy 104.339292 -56.083823) (xy 104.285335 -56.097929) (xy 104.229898 -56.104029) (xy 104.174164 -56.101992)
			(xy 104.119321 -56.091862) (xy 104.066537 -56.073855) (xy 104.016937 -56.048354) (xy 103.971579 -56.015903)
			(xy 103.93143 -55.977194) (xy 103.897344 -55.933051) (xy 103.870048 -55.884416) (xy 103.850125 -55.832325)
			(xy 103.837999 -55.777888) (xy 103.833928 -55.722266) (xy 91.994378 -55.722266) (xy 92.07119 -56.459628)
			(xy 92.071982 -56.465356) (xy 92.075842 -56.476254) (xy 92.07881 -56.481218) (xy 92.081604 -56.48579)
			(xy 92.090494 -56.494426) (xy 92.095828 -56.497474) (xy 92.119976 -56.51227) (xy 92.164012 -56.547879)
			(xy 92.202294 -56.589613) (xy 92.233978 -56.636552) (xy 92.258366 -56.687664) (xy 92.274922 -56.741822)
			(xy 92.283281 -56.797834) (xy 92.283788 -56.82615) (xy 92.283788 -56.826658) (xy 92.28328 -56.844438)
			(xy 92.282518 -56.85536) (xy 92.279852 -56.883703) (xy 92.26719 -56.939202) (xy 92.246432 -56.992208)
			(xy 92.240259 -57.002934) (xy 99.563428 -57.002934) (xy 99.563927 -56.974842) (xy 99.572151 -56.919264)
			(xy 99.58844 -56.865494) (xy 99.612441 -56.814696) (xy 99.643636 -56.767969) (xy 99.681348 -56.726324)
			(xy 99.724763 -56.690664) (xy 99.748594 -56.675782) (xy 99.757484 -56.670448) (xy 99.769676 -56.65343)
			(xy 99.789996 -56.560212) (xy 99.785678 -56.539638) (xy 99.779836 -56.531002) (xy 99.763839 -56.506936)
			(xy 99.738494 -56.455006) (xy 99.721268 -56.399848) (xy 99.712552 -56.342724) (xy 99.712018 -56.313832)
			(xy 99.712485 -56.286579) (xy 99.720238 -56.232627) (xy 99.735592 -56.180327) (xy 99.758232 -56.130746)
			(xy 99.787699 -56.084891) (xy 99.823393 -56.043697) (xy 99.864586 -56.008003) (xy 99.91044 -55.978535)
			(xy 99.960022 -55.955894) (xy 100.012321 -55.94054) (xy 100.066273 -55.932786) (xy 100.093526 -55.932324)
			(xy 100.120897 -55.932769) (xy 100.175077 -55.940591) (xy 100.227581 -55.956085) (xy 100.277327 -55.978931)
			(xy 100.323293 -56.00866) (xy 100.344224 -56.026304) (xy 100.344478 -56.026558) (xy 100.351562 -56.032148)
			(xy 100.368481 -56.038391) (xy 100.377498 -56.03875) (xy 100.444554 -56.03875) (xy 100.45357 -56.038382)
			(xy 100.470488 -56.032143) (xy 100.477574 -56.026558) (xy 100.477574 -56.026304) (xy 100.477828 -56.026304)
			(xy 100.498761 -56.008663) (xy 100.544729 -55.978939) (xy 100.594475 -55.956093) (xy 100.646977 -55.940597)
			(xy 100.701155 -55.932768) (xy 100.755897 -55.932768) (xy 100.810075 -55.940597) (xy 100.862577 -55.956093)
			(xy 100.912323 -55.978939) (xy 100.958291 -56.008663) (xy 100.979224 -56.026304) (xy 100.979478 -56.026558)
			(xy 100.986562 -56.032148) (xy 101.003481 -56.038391) (xy 101.012498 -56.03875) (xy 101.079554 -56.03875)
			(xy 101.08857 -56.038382) (xy 101.105488 -56.032143) (xy 101.112574 -56.026558) (xy 101.112574 -56.026304)
			(xy 101.112828 -56.026304) (xy 101.133777 -56.008686) (xy 101.179745 -55.978971) (xy 101.229488 -55.956131)
			(xy 101.281985 -55.940635) (xy 101.336158 -55.932801) (xy 101.363526 -55.932324) (xy 101.390778 -55.932748)
			(xy 101.444728 -55.940508) (xy 101.497024 -55.955866) (xy 101.546602 -55.978511) (xy 101.592453 -56.00798)
			(xy 101.633643 -56.043675) (xy 101.669335 -56.084868) (xy 101.698801 -56.130721) (xy 101.721443 -56.180301)
			(xy 101.736798 -56.232598) (xy 101.744554 -56.286548) (xy 101.744554 -56.297068) (xy 102.086408 -56.297068)
			(xy 102.090479 -56.241446) (xy 102.102605 -56.187009) (xy 102.122528 -56.134918) (xy 102.149824 -56.086283)
			(xy 102.18391 -56.04214) (xy 102.224059 -56.003431) (xy 102.269417 -55.97098) (xy 102.319017 -55.945479)
			(xy 102.371801 -55.927472) (xy 102.426644 -55.917342) (xy 102.482378 -55.915305) (xy 102.537815 -55.921405)
			(xy 102.591772 -55.935511) (xy 102.643101 -55.957323) (xy 102.690707 -55.986377) (xy 102.733575 -56.022052)
			(xy 102.770792 -56.063589) (xy 102.801565 -56.110102) (xy 102.825237 -56.160599) (xy 102.841305 -56.214006)
			(xy 102.849425 -56.269182) (xy 102.849934 -56.297068) (xy 102.849425 -56.324954) (xy 102.841305 -56.38013)
			(xy 102.825237 -56.433537) (xy 102.801565 -56.484034) (xy 102.770792 -56.530547) (xy 102.733575 -56.572084)
			(xy 102.690707 -56.607759) (xy 102.643101 -56.636813) (xy 102.591772 -56.658625) (xy 102.537815 -56.672731)
			(xy 102.482378 -56.678831) (xy 102.426644 -56.676794) (xy 102.371801 -56.666664) (xy 102.319017 -56.648657)
			(xy 102.269417 -56.623156) (xy 102.224059 -56.590705) (xy 102.18391 -56.551996) (xy 102.149824 -56.507853)
			(xy 102.122528 -56.459218) (xy 102.102605 -56.407127) (xy 102.090479 -56.35269) (xy 102.086408 -56.297068)
			(xy 101.744554 -56.297068) (xy 101.744554 -56.341052) (xy 101.736798 -56.395002) (xy 101.721443 -56.447299)
			(xy 101.698801 -56.496879) (xy 101.669335 -56.542732) (xy 101.633643 -56.583925) (xy 101.592453 -56.61962)
			(xy 101.546602 -56.649089) (xy 101.497024 -56.671734) (xy 101.444728 -56.687092) (xy 101.390778 -56.694852)
			(xy 101.363526 -56.69534) (xy 101.336156 -56.694873) (xy 101.281976 -56.687058) (xy 101.229472 -56.67157)
			(xy 101.179725 -56.648728) (xy 101.133759 -56.619002) (xy 101.112828 -56.60136) (xy 101.112574 -56.601106)
			(xy 101.10547 -56.595545) (xy 101.088567 -56.589283) (xy 101.079554 -56.588914) (xy 101.012498 -56.588914)
			(xy 101.003481 -56.589267) (xy 100.986564 -56.595517) (xy 100.979478 -56.601106) (xy 100.979478 -56.60136)
			(xy 100.979224 -56.60136) (xy 100.958291 -56.619001) (xy 100.912323 -56.648725) (xy 100.862577 -56.671571)
			(xy 100.810075 -56.687067) (xy 100.755897 -56.694896) (xy 100.701155 -56.694896) (xy 100.646977 -56.687067)
			(xy 100.594475 -56.671571) (xy 100.544729 -56.648725) (xy 100.498761 -56.619001) (xy 100.477828 -56.60136)
			(xy 100.477574 -56.601106) (xy 100.47047 -56.595545) (xy 100.453567 -56.589283) (xy 100.444554 -56.588914)
			(xy 100.377498 -56.588914) (xy 100.368481 -56.589267) (xy 100.351564 -56.595517) (xy 100.344478 -56.601106)
			(xy 100.34397 -56.60136) (xy 100.331235 -56.612303) (xy 100.304144 -56.632145) (xy 100.289868 -56.640984)
			(xy 100.280978 -56.646318) (xy 100.268786 -56.663336) (xy 100.248466 -56.756554) (xy 100.252784 -56.777128)
			(xy 100.258626 -56.785764) (xy 100.274616 -56.809834) (xy 100.29996 -56.861764) (xy 100.317188 -56.91692)
			(xy 100.325907 -56.974042) (xy 100.326444 -57.002934) (xy 100.325958 -57.030185) (xy 100.318202 -57.084133)
			(xy 100.302847 -57.136428) (xy 100.280205 -57.186005) (xy 100.250739 -57.231855) (xy 100.215048 -57.273046)
			(xy 100.173857 -57.308737) (xy 100.128007 -57.338203) (xy 100.07843 -57.360845) (xy 100.026135 -57.3762)
			(xy 99.972187 -57.383956) (xy 99.917685 -57.383956) (xy 99.863737 -57.3762) (xy 99.811442 -57.360845)
			(xy 99.761865 -57.338203) (xy 99.716015 -57.308737) (xy 99.674824 -57.273046) (xy 99.639133 -57.231855)
			(xy 99.609667 -57.186005) (xy 99.587025 -57.136428) (xy 99.57167 -57.084133) (xy 99.563914 -57.030185)
			(xy 99.563428 -57.002934) (xy 92.240259 -57.002934) (xy 92.218038 -57.041547) (xy 92.20073 -57.064148)
			(xy 92.195396 -57.070498) (xy 92.192602 -57.078372) (xy 92.191194 -57.082551) (xy 92.189664 -57.091235)
			(xy 92.189554 -57.095644) (xy 92.189554 -57.128156) (xy 92.178378 -57.128156) (xy 92.178378 -57.178956)
			(xy 92.178711 -57.18756) (xy 92.184419 -57.203795) (xy 92.189554 -57.210706) (xy 92.190824 -57.21223)
			(xy 92.208219 -57.233106) (xy 92.237539 -57.278856) (xy 92.260068 -57.328304) (xy 92.275351 -57.380449)
			(xy 92.283077 -57.434235) (xy 92.283534 -57.461404) (xy 92.282958 -57.491232) (xy 92.273675 -57.55016)
			(xy 92.255336 -57.606926) (xy 92.228388 -57.660148) (xy 92.211398 -57.68467) (xy 92.20581 -57.69229)
			(xy 92.203524 -57.70118) (xy 92.202374 -57.705721) (xy 92.201599 -57.715055) (xy 92.202 -57.719722)
			(xy 92.218256 -57.87517) (xy 92.219179 -57.880002) (xy 92.222624 -57.889216) (xy 92.225114 -57.893458)
			(xy 92.225368 -57.893966) (xy 92.23916 -57.916818) (xy 92.260914 -57.96556) (xy 92.275653 -58.01686)
			(xy 92.283088 -58.069716) (xy 92.283534 -58.096404) (xy 92.282802 -58.129944) (xy 92.271041 -58.195985)
			(xy 92.260166 -58.227722) (xy 92.256102 -58.238898) (xy 92.266008 -58.33491) (xy 92.270072 -58.383678)
			(xy 92.271596 -58.438034) (xy 92.271596 -58.636154) (xy 92.27185 -58.637678) (xy 92.27312 -58.64225)
			(xy 92.278032 -58.664209) (xy 92.279801 -58.679334) (xy 99.995228 -58.679334) (xy 99.995642 -58.653018)
			(xy 100.002887 -58.600887) (xy 100.017216 -58.550243) (xy 100.038358 -58.502044) (xy 100.065914 -58.457202)
			(xy 100.099362 -58.416565) (xy 100.118418 -58.39841) (xy 100.12582 -58.390889) (xy 100.134344 -58.371608)
			(xy 100.134928 -58.361072) (xy 100.134928 -58.286396) (xy 100.134406 -58.275846) (xy 100.125865 -58.256551)
			(xy 100.118418 -58.249058) (xy 100.099353 -58.230912) (xy 100.065896 -58.190281) (xy 100.038337 -58.145439)
			(xy 100.017201 -58.097236) (xy 100.002886 -58.046586) (xy 99.995664 -57.994451) (xy 99.995228 -57.968134)
			(xy 99.995714 -57.940883) (xy 100.00347 -57.886935) (xy 100.018825 -57.83464) (xy 100.041467 -57.785063)
			(xy 100.070933 -57.739213) (xy 100.106624 -57.698022) (xy 100.147815 -57.662331) (xy 100.193665 -57.632865)
			(xy 100.243242 -57.610223) (xy 100.295537 -57.594868) (xy 100.349485 -57.587112) (xy 100.403987 -57.587112)
			(xy 100.457935 -57.594868) (xy 100.51023 -57.610223) (xy 100.559807 -57.632865) (xy 100.605657 -57.662331)
			(xy 100.646848 -57.698022) (xy 100.682539 -57.739213) (xy 100.712005 -57.785063) (xy 100.734647 -57.83464)
			(xy 100.750002 -57.886935) (xy 100.757758 -57.940883) (xy 100.758244 -57.968134) (xy 100.757817 -57.99445)
			(xy 100.750577 -58.046581) (xy 100.743309 -58.072274) (xy 103.99344 -58.072274) (xy 103.997511 -58.016652)
			(xy 104.009637 -57.962215) (xy 104.02956 -57.910124) (xy 104.056856 -57.861489) (xy 104.090942 -57.817346)
			(xy 104.131091 -57.778637) (xy 104.176449 -57.746186) (xy 104.226049 -57.720685) (xy 104.278833 -57.702678)
			(xy 104.333676 -57.692548) (xy 104.38941 -57.690511) (xy 104.444847 -57.696611) (xy 104.498804 -57.710717)
			(xy 104.550133 -57.732529) (xy 104.597739 -57.761583) (xy 104.640607 -57.797258) (xy 104.677824 -57.838795)
			(xy 104.708597 -57.885308) (xy 104.732269 -57.935805) (xy 104.748337 -57.989212) (xy 104.756457 -58.044388)
			(xy 104.756966 -58.072274) (xy 104.756457 -58.10016) (xy 104.748337 -58.155336) (xy 104.732269 -58.208743)
			(xy 104.708597 -58.25924) (xy 104.677824 -58.305753) (xy 104.640607 -58.34729) (xy 104.597739 -58.382965)
			(xy 104.550133 -58.412019) (xy 104.498804 -58.433831) (xy 104.444847 -58.447937) (xy 104.38941 -58.454037)
			(xy 104.333676 -58.452) (xy 104.278833 -58.44187) (xy 104.226049 -58.423863) (xy 104.176449 -58.398362)
			(xy 104.131091 -58.365911) (xy 104.090942 -58.327202) (xy 104.056856 -58.283059) (xy 104.02956 -58.234424)
			(xy 104.009637 -58.182333) (xy 103.997511 -58.127896) (xy 103.99344 -58.072274) (xy 100.743309 -58.072274)
			(xy 100.736251 -58.097225) (xy 100.715111 -58.145424) (xy 100.687557 -58.190266) (xy 100.65411 -58.230903)
			(xy 100.635054 -58.249058) (xy 100.627677 -58.256601) (xy 100.619137 -58.275864) (xy 100.618544 -58.286396)
			(xy 100.618544 -58.361072) (xy 100.619062 -58.371623) (xy 100.627604 -58.390919) (xy 100.635054 -58.39841)
			(xy 100.654118 -58.416557) (xy 100.687572 -58.45719) (xy 100.715129 -58.502032) (xy 100.736265 -58.550234)
			(xy 100.750581 -58.600883) (xy 100.757806 -58.653018) (xy 100.758244 -58.679334) (xy 100.757758 -58.706585)
			(xy 100.750002 -58.760533) (xy 100.734647 -58.812828) (xy 100.712005 -58.862405) (xy 100.682539 -58.908255)
			(xy 100.646848 -58.949446) (xy 100.605657 -58.985137) (xy 100.559807 -59.014603) (xy 100.51023 -59.037245)
			(xy 100.457935 -59.0526) (xy 100.403987 -59.060356) (xy 100.349485 -59.060356) (xy 100.295537 -59.0526)
			(xy 100.243242 -59.037245) (xy 100.193665 -59.014603) (xy 100.147815 -58.985137) (xy 100.106624 -58.949446)
			(xy 100.070933 -58.908255) (xy 100.041467 -58.862405) (xy 100.018825 -58.812828) (xy 100.00347 -58.760533)
			(xy 99.995714 -58.706585) (xy 99.995228 -58.679334) (xy 92.279801 -58.679334) (xy 92.283258 -58.708904)
			(xy 92.283534 -58.731404) (xy 92.283235 -58.753903) (xy 92.278014 -58.798596) (xy 92.27312 -58.820558)
			(xy 92.27185 -58.82513) (xy 92.271596 -58.826654) (xy 92.271596 -60.01925) (xy 100.135684 -60.01925)
			(xy 100.135684 -59.96475) (xy 100.14344 -59.910804) (xy 100.158794 -59.85851) (xy 100.181434 -59.808935)
			(xy 100.210899 -59.763086) (xy 100.246589 -59.721896) (xy 100.287777 -59.686205) (xy 100.333626 -59.656739)
			(xy 100.383201 -59.634098) (xy 100.435494 -59.618742) (xy 100.48944 -59.610984) (xy 100.51669 -59.610498)
			(xy 100.54406 -59.61097) (xy 100.598239 -59.618787) (xy 100.650742 -59.634274) (xy 100.700489 -59.657115)
			(xy 100.746456 -59.686838) (xy 100.767388 -59.704478) (xy 100.767642 -59.704732) (xy 100.774738 -59.710304)
			(xy 100.791648 -59.716558) (xy 100.800662 -59.716924) (xy 100.867718 -59.716924) (xy 100.876735 -59.716571)
			(xy 100.893652 -59.71032) (xy 100.900738 -59.704732) (xy 100.900738 -59.704478) (xy 100.900992 -59.704478)
			(xy 100.921925 -59.686837) (xy 100.967893 -59.657113) (xy 101.017639 -59.634267) (xy 101.070141 -59.618771)
			(xy 101.124319 -59.610942) (xy 101.179061 -59.610942) (xy 101.233239 -59.618771) (xy 101.285741 -59.634267)
			(xy 101.335487 -59.657113) (xy 101.381455 -59.686837) (xy 101.402388 -59.704478) (xy 101.402642 -59.704732)
			(xy 101.409738 -59.710304) (xy 101.426648 -59.716558) (xy 101.435662 -59.716924) (xy 101.502718 -59.716924)
			(xy 101.511735 -59.716571) (xy 101.528652 -59.71032) (xy 101.535738 -59.704732) (xy 101.535738 -59.704478)
			(xy 101.535992 -59.704478) (xy 101.556913 -59.686826) (xy 101.60289 -59.657117) (xy 101.65264 -59.634284)
			(xy 101.705143 -59.618796) (xy 101.75932 -59.61097) (xy 101.78669 -59.610498) (xy 101.813944 -59.610949)
			(xy 101.867897 -59.618705) (xy 101.920196 -59.63406) (xy 101.969779 -59.656702) (xy 102.015634 -59.68617)
			(xy 102.056828 -59.721865) (xy 102.092524 -59.763058) (xy 102.121993 -59.808913) (xy 102.144636 -59.858494)
			(xy 102.159993 -59.910794) (xy 102.167751 -59.964746) (xy 102.167751 -60.019254) (xy 102.159993 -60.073206)
			(xy 102.144636 -60.125506) (xy 102.121993 -60.175087) (xy 102.092524 -60.220942) (xy 102.056828 -60.262135)
			(xy 102.015634 -60.29783) (xy 101.969779 -60.327298) (xy 101.920196 -60.34994) (xy 101.867897 -60.365295)
			(xy 101.813944 -60.373051) (xy 101.78669 -60.373514) (xy 101.75932 -60.37305) (xy 101.705141 -60.365231)
			(xy 101.652638 -60.349742) (xy 101.602891 -60.326899) (xy 101.556924 -60.297175) (xy 101.535992 -60.279534)
			(xy 101.535738 -60.27928) (xy 101.528646 -60.273701) (xy 101.511733 -60.26745) (xy 101.502718 -60.267088)
			(xy 101.435662 -60.267088) (xy 101.426644 -60.267429) (xy 101.409727 -60.273688) (xy 101.402642 -60.27928)
			(xy 101.402388 -60.279534) (xy 101.381455 -60.297175) (xy 101.335487 -60.326899) (xy 101.285741 -60.349745)
			(xy 101.233239 -60.365241) (xy 101.179061 -60.37307) (xy 101.124319 -60.37307) (xy 101.070141 -60.365241)
			(xy 101.017639 -60.349745) (xy 100.967893 -60.326899) (xy 100.921925 -60.297175) (xy 100.900992 -60.279534)
			(xy 100.900738 -60.27928) (xy 100.893646 -60.273701) (xy 100.876733 -60.26745) (xy 100.867718 -60.267088)
			(xy 100.800662 -60.267088) (xy 100.791644 -60.267429) (xy 100.774727 -60.273688) (xy 100.767642 -60.27928)
			(xy 100.767642 -60.279534) (xy 100.767388 -60.279534) (xy 100.746438 -60.297151) (xy 100.70047 -60.326865)
			(xy 100.650727 -60.349704) (xy 100.59823 -60.365201) (xy 100.544058 -60.373036) (xy 100.51669 -60.373514)
			(xy 100.48944 -60.373016) (xy 100.435494 -60.365258) (xy 100.383201 -60.349902) (xy 100.333626 -60.327261)
			(xy 100.287777 -60.297795) (xy 100.246589 -60.262104) (xy 100.210899 -60.220914) (xy 100.181434 -60.175065)
			(xy 100.158794 -60.12549) (xy 100.14344 -60.073196) (xy 100.135684 -60.01925) (xy 92.271596 -60.01925)
			(xy 92.271596 -60.59424) (xy 92.271107 -60.637887) (xy 92.263437 -60.724844) (xy 92.248203 -60.810798)
			(xy 92.237306 -60.853066) (xy 91.602673 -63.213552) (xy 100.120665 -63.213552) (xy 100.120665 -63.159048)
			(xy 100.128422 -63.105098) (xy 100.143778 -63.052801) (xy 100.16642 -63.003222) (xy 100.195888 -62.95737)
			(xy 100.231581 -62.916178) (xy 100.272773 -62.880485) (xy 100.318625 -62.851018) (xy 100.368205 -62.828377)
			(xy 100.420502 -62.813021) (xy 100.474452 -62.805265) (xy 100.501704 -62.804802) (xy 100.529074 -62.805265)
			(xy 100.583254 -62.813084) (xy 100.635757 -62.828573) (xy 100.685504 -62.851416) (xy 100.73147 -62.881141)
			(xy 100.752402 -62.898782) (xy 100.752656 -62.899036) (xy 100.759748 -62.904614) (xy 100.776661 -62.910865)
			(xy 100.785676 -62.911228) (xy 100.852732 -62.911228) (xy 100.86175 -62.91088) (xy 100.878666 -62.904626)
			(xy 100.885752 -62.899036) (xy 100.885752 -62.898782) (xy 100.886006 -62.898782) (xy 100.906939 -62.881141)
			(xy 100.952907 -62.851417) (xy 101.002653 -62.828571) (xy 101.055155 -62.813075) (xy 101.109333 -62.805246)
			(xy 101.164075 -62.805246) (xy 101.218253 -62.813075) (xy 101.270755 -62.828571) (xy 101.320501 -62.851417)
			(xy 101.366469 -62.881141) (xy 101.387402 -62.898782) (xy 101.387656 -62.899036) (xy 101.394748 -62.904614)
			(xy 101.411661 -62.910865) (xy 101.420676 -62.911228) (xy 101.487732 -62.911228) (xy 101.49675 -62.91088)
			(xy 101.513666 -62.904626) (xy 101.520752 -62.899036) (xy 101.520752 -62.898782) (xy 101.521006 -62.898782)
			(xy 101.541923 -62.881124) (xy 101.5879 -62.851415) (xy 101.637651 -62.828583) (xy 101.690155 -62.813097)
			(xy 101.744334 -62.805273) (xy 101.771704 -62.804802) (xy 101.798956 -62.805268) (xy 101.852904 -62.813025)
			(xy 101.9052 -62.828381) (xy 101.954778 -62.851023) (xy 102.000629 -62.88049) (xy 102.04182 -62.916183)
			(xy 102.077512 -62.957374) (xy 102.106979 -63.003225) (xy 102.12962 -63.052804) (xy 102.144976 -63.105099)
			(xy 102.152732 -63.159048) (xy 102.152732 -63.213552) (xy 102.144976 -63.267501) (xy 102.12962 -63.319796)
			(xy 102.106979 -63.369375) (xy 102.077512 -63.415226) (xy 102.04182 -63.456417) (xy 102.000629 -63.49211)
			(xy 101.954778 -63.521577) (xy 101.9052 -63.544219) (xy 101.852904 -63.559575) (xy 101.798956 -63.567332)
			(xy 101.771704 -63.567818) (xy 101.744333 -63.56737) (xy 101.690152 -63.559551) (xy 101.637648 -63.544058)
			(xy 101.587902 -63.521212) (xy 101.541936 -63.491482) (xy 101.521006 -63.473838) (xy 101.520752 -63.473584)
			(xy 101.513656 -63.468011) (xy 101.496746 -63.461757) (xy 101.487732 -63.461392) (xy 101.420676 -63.461392)
			(xy 101.411658 -63.461739) (xy 101.394741 -63.467994) (xy 101.387656 -63.473584) (xy 101.387402 -63.473838)
			(xy 101.366469 -63.491479) (xy 101.320501 -63.521203) (xy 101.270755 -63.544049) (xy 101.218253 -63.559545)
			(xy 101.164075 -63.567374) (xy 101.109333 -63.567374) (xy 101.055155 -63.559545) (xy 101.002653 -63.544049)
			(xy 100.952907 -63.521203) (xy 100.906939 -63.491479) (xy 100.886006 -63.473838) (xy 100.885752 -63.473584)
			(xy 100.878656 -63.468011) (xy 100.861746 -63.461757) (xy 100.852732 -63.461392) (xy 100.785676 -63.461392)
			(xy 100.776658 -63.461739) (xy 100.759741 -63.467994) (xy 100.752656 -63.473584) (xy 100.752656 -63.473838)
			(xy 100.752402 -63.473838) (xy 100.731485 -63.491496) (xy 100.685508 -63.521204) (xy 100.635756 -63.544036)
			(xy 100.583252 -63.559522) (xy 100.529074 -63.567346) (xy 100.501704 -63.567818) (xy 100.474452 -63.567335)
			(xy 100.420502 -63.559579) (xy 100.368205 -63.544223) (xy 100.318625 -63.521582) (xy 100.272773 -63.492115)
			(xy 100.231581 -63.456422) (xy 100.195888 -63.41523) (xy 100.16642 -63.369378) (xy 100.143778 -63.319799)
			(xy 100.128422 -63.267502) (xy 100.120665 -63.213552) (xy 91.602673 -63.213552) (xy 91.590876 -63.25743)
			(xy 91.577504 -63.304893) (xy 91.542647 -63.39714) (xy 91.52128 -63.44158) (xy 90.698521 -65.100962)
			(xy 98.13239 -65.100962) (xy 98.136461 -65.04534) (xy 98.148587 -64.990903) (xy 98.16851 -64.938812)
			(xy 98.195806 -64.890177) (xy 98.229892 -64.846034) (xy 98.270041 -64.807325) (xy 98.315399 -64.774874)
			(xy 98.364999 -64.749373) (xy 98.417783 -64.731366) (xy 98.472626 -64.721236) (xy 98.52836 -64.719199)
			(xy 98.583797 -64.725299) (xy 98.637754 -64.739405) (xy 98.689083 -64.761217) (xy 98.736689 -64.790271)
			(xy 98.779557 -64.825946) (xy 98.816774 -64.867483) (xy 98.847547 -64.913996) (xy 98.871219 -64.964493)
			(xy 98.887287 -65.0179) (xy 98.895407 -65.073076) (xy 98.895916 -65.100962) (xy 98.895407 -65.128848)
			(xy 98.887287 -65.184024) (xy 98.871219 -65.237431) (xy 98.847547 -65.287928) (xy 98.816774 -65.334441)
			(xy 98.779557 -65.375978) (xy 98.736689 -65.411653) (xy 98.689083 -65.440707) (xy 98.637754 -65.462519)
			(xy 98.583797 -65.476625) (xy 98.52836 -65.482725) (xy 98.472626 -65.480688) (xy 98.417783 -65.470558)
			(xy 98.364999 -65.452551) (xy 98.315399 -65.42705) (xy 98.270041 -65.394599) (xy 98.229892 -65.35589)
			(xy 98.195806 -65.311747) (xy 98.16851 -65.263112) (xy 98.148587 -65.211021) (xy 98.136461 -65.156584)
			(xy 98.13239 -65.100962) (xy 90.698521 -65.100962) (xy 90.526362 -65.44818) (xy 90.504461 -65.491088)
			(xy 90.453571 -65.572891) (xy 90.424762 -65.611502) (xy 90.314514 -65.75552) (xy 92.346524 -65.75552)
			(xy 92.350595 -65.699898) (xy 92.362721 -65.645461) (xy 92.382644 -65.59337) (xy 92.40994 -65.544735)
			(xy 92.444026 -65.500592) (xy 92.484175 -65.461883) (xy 92.529533 -65.429432) (xy 92.579133 -65.403931)
			(xy 92.631917 -65.385924) (xy 92.68676 -65.375794) (xy 92.742494 -65.373757) (xy 92.797931 -65.379857)
			(xy 92.851888 -65.393963) (xy 92.903217 -65.415775) (xy 92.950823 -65.444829) (xy 92.993691 -65.480504)
			(xy 93.030908 -65.522041) (xy 93.061681 -65.568554) (xy 93.085353 -65.619051) (xy 93.101421 -65.672458)
			(xy 93.109541 -65.727634) (xy 93.11005 -65.75552) (xy 93.109541 -65.783406) (xy 93.101421 -65.838582)
			(xy 93.085353 -65.891989) (xy 93.061681 -65.942486) (xy 93.030908 -65.988999) (xy 92.993691 -66.030536)
			(xy 92.950823 -66.066211) (xy 92.903217 -66.095265) (xy 92.851888 -66.117077) (xy 92.797931 -66.131183)
			(xy 92.742494 -66.137283) (xy 92.68676 -66.135246) (xy 92.631917 -66.125116) (xy 92.579133 -66.107109)
			(xy 92.529533 -66.081608) (xy 92.484175 -66.049157) (xy 92.444026 -66.010448) (xy 92.40994 -65.966305)
			(xy 92.382644 -65.91767) (xy 92.362721 -65.865579) (xy 92.350595 -65.811142) (xy 92.346524 -65.75552)
			(xy 90.314514 -65.75552) (xy 89.263131 -67.128949) (xy 92.366598 -67.128949) (xy 92.366598 -67.074451)
			(xy 92.374354 -67.020506) (xy 92.389708 -66.968215) (xy 92.412347 -66.918641) (xy 92.441811 -66.872794)
			(xy 92.4775 -66.831606) (xy 92.518687 -66.795916) (xy 92.564534 -66.766451) (xy 92.614108 -66.743811)
			(xy 92.666399 -66.728456) (xy 92.720343 -66.720699) (xy 92.747592 -66.720212) (xy 92.774962 -66.72068)
			(xy 92.829141 -66.728497) (xy 92.881645 -66.743985) (xy 92.931391 -66.766827) (xy 92.977358 -66.796551)
			(xy 92.99829 -66.814192) (xy 92.998544 -66.814446) (xy 93.005638 -66.820021) (xy 93.022549 -66.826273)
			(xy 93.031564 -66.826638) (xy 93.09862 -66.826638) (xy 93.107637 -66.826282) (xy 93.124553 -66.820033)
			(xy 93.13164 -66.814446) (xy 93.13164 -66.814192) (xy 93.131894 -66.814192) (xy 93.152816 -66.796541)
			(xy 93.198792 -66.766831) (xy 93.248542 -66.743998) (xy 93.301045 -66.728509) (xy 93.355222 -66.720684)
			(xy 93.382592 -66.720212) (xy 93.409847 -66.720634) (xy 93.463801 -66.728391) (xy 93.516103 -66.743747)
			(xy 93.565687 -66.76639) (xy 93.611543 -66.79586) (xy 93.652739 -66.831555) (xy 93.688436 -66.87275)
			(xy 93.717906 -66.918606) (xy 93.74055 -66.96819) (xy 93.755907 -67.020491) (xy 93.763665 -67.074445)
			(xy 93.763665 -67.128955) (xy 93.755907 -67.182909) (xy 93.74055 -67.23521) (xy 93.717906 -67.284794)
			(xy 93.688436 -67.33065) (xy 93.652739 -67.371845) (xy 93.611543 -67.40754) (xy 93.565687 -67.43701)
			(xy 93.516103 -67.459653) (xy 93.463801 -67.475009) (xy 93.409847 -67.482766) (xy 93.382592 -67.483228)
			(xy 93.355221 -67.482784) (xy 93.30104 -67.474964) (xy 93.248536 -67.45947) (xy 93.198789 -67.436623)
			(xy 93.152824 -67.406892) (xy 93.131894 -67.389248) (xy 93.13164 -67.388994) (xy 93.124547 -67.383417)
			(xy 93.107635 -67.377165) (xy 93.09862 -67.376802) (xy 93.031564 -67.376802) (xy 93.022545 -67.377142)
			(xy 93.005629 -67.383401) (xy 92.998544 -67.388994) (xy 92.998544 -67.389248) (xy 92.99829 -67.389248)
			(xy 92.977366 -67.406897) (xy 92.931392 -67.436609) (xy 92.881642 -67.459444) (xy 92.82914 -67.474933)
			(xy 92.774962 -67.482757) (xy 92.747592 -67.483228) (xy 92.720343 -67.482701) (xy 92.666399 -67.474944)
			(xy 92.614108 -67.459589) (xy 92.564534 -67.436949) (xy 92.518687 -67.407484) (xy 92.4775 -67.371794)
			(xy 92.441811 -67.330606) (xy 92.412347 -67.284759) (xy 92.389708 -67.235185) (xy 92.374354 -67.182894)
			(xy 92.366598 -67.128949) (xy 89.263131 -67.128949) (xy 88.98823 -67.488054) (xy 96.779078 -67.488054)
			(xy 96.783149 -67.432432) (xy 96.795275 -67.377995) (xy 96.815198 -67.325904) (xy 96.842494 -67.277269)
			(xy 96.87658 -67.233126) (xy 96.916729 -67.194417) (xy 96.962087 -67.161966) (xy 97.011687 -67.136465)
			(xy 97.064471 -67.118458) (xy 97.119314 -67.108328) (xy 97.175048 -67.106291) (xy 97.230485 -67.112391)
			(xy 97.284442 -67.126497) (xy 97.335771 -67.148309) (xy 97.383377 -67.177363) (xy 97.426245 -67.213038)
			(xy 97.463462 -67.254575) (xy 97.494235 -67.301088) (xy 97.517907 -67.351585) (xy 97.533975 -67.404992)
			(xy 97.542095 -67.460168) (xy 97.542604 -67.488054) (xy 97.542095 -67.51594) (xy 97.53891 -67.537584)
			(xy 98.071176 -67.537584) (xy 98.075247 -67.481962) (xy 98.087373 -67.427525) (xy 98.107296 -67.375434)
			(xy 98.134592 -67.326799) (xy 98.168678 -67.282656) (xy 98.208827 -67.243947) (xy 98.254185 -67.211496)
			(xy 98.303785 -67.185995) (xy 98.356569 -67.167988) (xy 98.411412 -67.157858) (xy 98.467146 -67.155821)
			(xy 98.522583 -67.161921) (xy 98.57654 -67.176027) (xy 98.627869 -67.197839) (xy 98.675475 -67.226893)
			(xy 98.718343 -67.262568) (xy 98.75556 -67.304105) (xy 98.786333 -67.350618) (xy 98.810005 -67.401115)
			(xy 98.826073 -67.454522) (xy 98.834193 -67.509698) (xy 98.834702 -67.537584) (xy 98.834193 -67.56547)
			(xy 98.830148 -67.592956) (xy 99.34524 -67.592956) (xy 99.349311 -67.537334) (xy 99.361437 -67.482897)
			(xy 99.38136 -67.430806) (xy 99.408656 -67.382171) (xy 99.442742 -67.338028) (xy 99.482891 -67.299319)
			(xy 99.528249 -67.266868) (xy 99.577849 -67.241367) (xy 99.630633 -67.22336) (xy 99.685476 -67.21323)
			(xy 99.74121 -67.211193) (xy 99.796647 -67.217293) (xy 99.850604 -67.231399) (xy 99.901933 -67.253211)
			(xy 99.949539 -67.282265) (xy 99.992407 -67.31794) (xy 100.029624 -67.359477) (xy 100.060397 -67.40599)
			(xy 100.084069 -67.456487) (xy 100.100137 -67.509894) (xy 100.108257 -67.56507) (xy 100.108766 -67.592956)
			(xy 100.108257 -67.620842) (xy 100.100137 -67.676018) (xy 100.084069 -67.729425) (xy 100.060397 -67.779922)
			(xy 100.029624 -67.826435) (xy 99.992407 -67.867972) (xy 99.949539 -67.903647) (xy 99.901933 -67.932701)
			(xy 99.850604 -67.954513) (xy 99.796647 -67.968619) (xy 99.74121 -67.974719) (xy 99.685476 -67.972682)
			(xy 99.630633 -67.962552) (xy 99.577849 -67.944545) (xy 99.528249 -67.919044) (xy 99.482891 -67.886593)
			(xy 99.442742 -67.847884) (xy 99.408656 -67.803741) (xy 99.38136 -67.755106) (xy 99.361437 -67.703015)
			(xy 99.349311 -67.648578) (xy 99.34524 -67.592956) (xy 98.830148 -67.592956) (xy 98.826073 -67.620646)
			(xy 98.810005 -67.674053) (xy 98.786333 -67.72455) (xy 98.75556 -67.771063) (xy 98.718343 -67.8126)
			(xy 98.675475 -67.848275) (xy 98.627869 -67.877329) (xy 98.57654 -67.899141) (xy 98.522583 -67.913247)
			(xy 98.467146 -67.919347) (xy 98.411412 -67.91731) (xy 98.356569 -67.90718) (xy 98.303785 -67.889173)
			(xy 98.254185 -67.863672) (xy 98.208827 -67.831221) (xy 98.168678 -67.792512) (xy 98.134592 -67.748369)
			(xy 98.107296 -67.699734) (xy 98.087373 -67.647643) (xy 98.075247 -67.593206) (xy 98.071176 -67.537584)
			(xy 97.53891 -67.537584) (xy 97.533975 -67.571116) (xy 97.517907 -67.624523) (xy 97.494235 -67.67502)
			(xy 97.463462 -67.721533) (xy 97.426245 -67.76307) (xy 97.383377 -67.798745) (xy 97.335771 -67.827799)
			(xy 97.284442 -67.849611) (xy 97.230485 -67.863717) (xy 97.175048 -67.869817) (xy 97.119314 -67.86778)
			(xy 97.064471 -67.85765) (xy 97.011687 -67.839643) (xy 96.962087 -67.814142) (xy 96.916729 -67.781691)
			(xy 96.87658 -67.742982) (xy 96.842494 -67.698839) (xy 96.815198 -67.650204) (xy 96.795275 -67.598113)
			(xy 96.783149 -67.543676) (xy 96.779078 -67.488054) (xy 88.98823 -67.488054) (xy 88.147272 -68.586604)
			(xy 94.62516 -68.586604) (xy 94.625614 -68.559233) (xy 94.633432 -68.505053) (xy 94.648923 -68.452549)
			(xy 94.671768 -68.402802) (xy 94.701497 -68.356837) (xy 94.71914 -68.335906) (xy 94.719394 -68.335652)
			(xy 94.724964 -68.328554) (xy 94.731221 -68.311646) (xy 94.731586 -68.302632) (xy 94.731586 -68.235576)
			(xy 94.731243 -68.226558) (xy 94.724986 -68.209641) (xy 94.719394 -68.202556) (xy 94.71914 -68.202556)
			(xy 94.71914 -68.202302) (xy 94.701495 -68.181375) (xy 94.671782 -68.135401) (xy 94.648947 -68.085653)
			(xy 94.633458 -68.033151) (xy 94.625632 -67.978974) (xy 94.62516 -67.951604) (xy 94.625681 -67.924354)
			(xy 94.633437 -67.87041) (xy 94.64879 -67.818117) (xy 94.671428 -67.768542) (xy 94.700891 -67.722693)
			(xy 94.736578 -67.681504) (xy 94.777765 -67.645812) (xy 94.823611 -67.616345) (xy 94.873184 -67.593702)
			(xy 94.925474 -67.578344) (xy 94.979418 -67.570584) (xy 95.006668 -67.570096) (xy 95.032983 -67.570519)
			(xy 95.085114 -67.577763) (xy 95.135757 -67.592091) (xy 95.183956 -67.613232) (xy 95.228799 -67.640786)
			(xy 95.269436 -67.674231) (xy 95.287592 -67.693286) (xy 95.295117 -67.700684) (xy 95.314394 -67.709211)
			(xy 95.32493 -67.709796) (xy 95.399606 -67.709796) (xy 95.410158 -67.709285) (xy 95.429453 -67.700737)
			(xy 95.436944 -67.693286) (xy 95.455082 -67.674213) (xy 95.495716 -67.640758) (xy 95.54056 -67.613202)
			(xy 95.588764 -67.592067) (xy 95.639415 -67.577753) (xy 95.691551 -67.570532) (xy 95.717868 -67.570096)
			(xy 95.745238 -67.570582) (xy 95.799416 -67.578395) (xy 95.851919 -67.59388) (xy 95.901666 -67.616717)
			(xy 95.947634 -67.646437) (xy 95.968566 -67.664076) (xy 95.96882 -67.66433) (xy 95.975894 -67.669934)
			(xy 95.992821 -67.676169) (xy 96.00184 -67.676522) (xy 96.068896 -67.676522) (xy 96.077912 -67.676158)
			(xy 96.094829 -67.669915) (xy 96.101916 -67.66433) (xy 96.101916 -67.664076) (xy 96.10217 -67.664076)
			(xy 96.123099 -67.646434) (xy 96.169073 -67.616723) (xy 96.218822 -67.593888) (xy 96.271323 -67.578398)
			(xy 96.325499 -67.57057) (xy 96.352868 -67.570096) (xy 96.38012 -67.570585) (xy 96.43407 -67.578338)
			(xy 96.486368 -67.59369) (xy 96.535948 -67.616329) (xy 96.581802 -67.645794) (xy 96.622995 -67.681485)
			(xy 96.658689 -67.722676) (xy 96.688158 -67.768527) (xy 96.7108 -67.818106) (xy 96.726156 -67.870402)
			(xy 96.733913 -67.924352) (xy 96.734376 -67.951604) (xy 96.733918 -67.978975) (xy 96.726099 -68.033154)
			(xy 96.710609 -68.085658) (xy 96.687765 -68.135404) (xy 96.658038 -68.181371) (xy 96.640396 -68.202302)
			(xy 96.640142 -68.202556) (xy 96.634561 -68.209646) (xy 96.628312 -68.22656) (xy 96.62795 -68.235576)
			(xy 96.62795 -68.302632) (xy 96.628281 -68.311652) (xy 96.634545 -68.328569) (xy 96.640142 -68.335652)
			(xy 96.640396 -68.335652) (xy 96.640396 -68.335906) (xy 96.658051 -68.356825) (xy 96.68776 -68.402802)
			(xy 96.710593 -68.452552) (xy 96.726081 -68.505056) (xy 96.733904 -68.559234) (xy 96.734376 -68.586604)
			(xy 96.733948 -68.613858) (xy 96.72619 -68.667812) (xy 96.710832 -68.720113) (xy 96.688186 -68.769695)
			(xy 96.658715 -68.81555) (xy 96.623018 -68.856743) (xy 96.581821 -68.892437) (xy 96.535963 -68.921904)
			(xy 96.486379 -68.944544) (xy 96.434077 -68.959898) (xy 96.380122 -68.967651) (xy 96.352868 -68.968112)
			(xy 96.325497 -68.967662) (xy 96.271318 -68.95984) (xy 96.218814 -68.944347) (xy 96.169068 -68.921502)
			(xy 96.123101 -68.891774) (xy 96.10217 -68.874132) (xy 96.101916 -68.873878) (xy 96.094831 -68.86829)
			(xy 96.077913 -68.862045) (xy 96.068896 -68.861686) (xy 96.00184 -68.861686) (xy 95.992825 -68.862065)
			(xy 95.975908 -68.868298) (xy 95.96882 -68.873878) (xy 95.96882 -68.874132) (xy 95.968566 -68.874132)
			(xy 95.947624 -68.891759) (xy 95.901653 -68.921471) (xy 95.851908 -68.944309) (xy 95.79941 -68.959803)
			(xy 95.745236 -68.967636) (xy 95.717868 -68.968112) (xy 95.691553 -68.967662) (xy 95.639424 -68.960423)
			(xy 95.588781 -68.9461) (xy 95.540583 -68.924965) (xy 95.49574 -68.897416) (xy 95.4551 -68.863975)
			(xy 95.436944 -68.844922) (xy 95.429405 -68.837541) (xy 95.410138 -68.829004) (xy 95.399606 -68.828412)
			(xy 95.32493 -68.828412) (xy 95.31438 -68.82894) (xy 95.295085 -68.837476) (xy 95.287592 -68.844922)
			(xy 95.269438 -68.863979) (xy 95.228807 -68.897435) (xy 95.183966 -68.924993) (xy 95.135766 -68.946131)
			(xy 95.085118 -68.960448) (xy 95.032984 -68.967673) (xy 95.006668 -68.968112) (xy 94.979416 -68.967652)
			(xy 94.925468 -68.959891) (xy 94.873173 -68.944532) (xy 94.823596 -68.921888) (xy 94.777746 -68.892418)
			(xy 94.736556 -68.856724) (xy 94.700865 -68.815532) (xy 94.671399 -68.76968) (xy 94.648758 -68.720101)
			(xy 94.633403 -68.667805) (xy 94.625646 -68.613856) (xy 94.62516 -68.586604) (xy 88.147272 -68.586604)
			(xy 85.874254 -71.555864) (xy 97.194368 -71.555864) (xy 97.198439 -71.500242) (xy 97.210565 -71.445805)
			(xy 97.230488 -71.393714) (xy 97.257784 -71.345079) (xy 97.29187 -71.300936) (xy 97.332019 -71.262227)
			(xy 97.377377 -71.229776) (xy 97.426977 -71.204275) (xy 97.479761 -71.186268) (xy 97.534604 -71.176138)
			(xy 97.590338 -71.174101) (xy 97.645775 -71.180201) (xy 97.699732 -71.194307) (xy 97.751061 -71.216119)
			(xy 97.798667 -71.245173) (xy 97.841535 -71.280848) (xy 97.878752 -71.322385) (xy 97.909525 -71.368898)
			(xy 97.933197 -71.419395) (xy 97.949265 -71.472802) (xy 97.957385 -71.527978) (xy 97.957894 -71.555864)
			(xy 97.957385 -71.58375) (xy 97.951546 -71.623428) (xy 98.703382 -71.623428) (xy 98.707453 -71.567806)
			(xy 98.719579 -71.513369) (xy 98.739502 -71.461278) (xy 98.766798 -71.412643) (xy 98.800884 -71.3685)
			(xy 98.841033 -71.329791) (xy 98.886391 -71.29734) (xy 98.935991 -71.271839) (xy 98.988775 -71.253832)
			(xy 99.043618 -71.243702) (xy 99.099352 -71.241665) (xy 99.154789 -71.247765) (xy 99.208746 -71.261871)
			(xy 99.260075 -71.283683) (xy 99.307681 -71.312737) (xy 99.350549 -71.348412) (xy 99.387766 -71.389949)
			(xy 99.418539 -71.436462) (xy 99.442211 -71.486959) (xy 99.458279 -71.540366) (xy 99.466399 -71.595542)
			(xy 99.466908 -71.623428) (xy 99.466399 -71.651314) (xy 99.458279 -71.70649) (xy 99.442211 -71.759897)
			(xy 99.418539 -71.810394) (xy 99.387766 -71.856907) (xy 99.350549 -71.898444) (xy 99.307681 -71.934119)
			(xy 99.260075 -71.963173) (xy 99.208746 -71.984985) (xy 99.154789 -71.999091) (xy 99.099352 -72.005191)
			(xy 99.043618 -72.003154) (xy 98.988775 -71.993024) (xy 98.935991 -71.975017) (xy 98.886391 -71.949516)
			(xy 98.841033 -71.917065) (xy 98.800884 -71.878356) (xy 98.766798 -71.834213) (xy 98.739502 -71.785578)
			(xy 98.719579 -71.733487) (xy 98.707453 -71.67905) (xy 98.703382 -71.623428) (xy 97.951546 -71.623428)
			(xy 97.949265 -71.638926) (xy 97.933197 -71.692333) (xy 97.909525 -71.74283) (xy 97.878752 -71.789343)
			(xy 97.841535 -71.83088) (xy 97.798667 -71.866555) (xy 97.751061 -71.895609) (xy 97.699732 -71.917421)
			(xy 97.645775 -71.931527) (xy 97.590338 -71.937627) (xy 97.534604 -71.93559) (xy 97.479761 -71.92546)
			(xy 97.426977 -71.907453) (xy 97.377377 -71.881952) (xy 97.332019 -71.849501) (xy 97.29187 -71.810792)
			(xy 97.257784 -71.766649) (xy 97.230488 -71.718014) (xy 97.210565 -71.665923) (xy 97.198439 -71.611486)
			(xy 97.194368 -71.555864) (xy 85.874254 -71.555864) (xy 84.148393 -73.810368) (xy 90.899486 -73.810368)
			(xy 90.903557 -73.754746) (xy 90.915683 -73.700309) (xy 90.935606 -73.648218) (xy 90.962902 -73.599583)
			(xy 90.996988 -73.55544) (xy 91.037137 -73.516731) (xy 91.082495 -73.48428) (xy 91.132095 -73.458779)
			(xy 91.184879 -73.440772) (xy 91.239722 -73.430642) (xy 91.295456 -73.428605) (xy 91.350893 -73.434705)
			(xy 91.40485 -73.448811) (xy 91.456179 -73.470623) (xy 91.503785 -73.499677) (xy 91.546653 -73.535352)
			(xy 91.58387 -73.576889) (xy 91.614643 -73.623402) (xy 91.638315 -73.673899) (xy 91.654383 -73.727306)
			(xy 91.662503 -73.782482) (xy 91.663012 -73.810368) (xy 91.662503 -73.838254) (xy 91.654383 -73.89343)
			(xy 91.638315 -73.946837) (xy 91.614643 -73.997334) (xy 91.58387 -74.043847) (xy 91.546653 -74.085384)
			(xy 91.503785 -74.121059) (xy 91.456179 -74.150113) (xy 91.40485 -74.171925) (xy 91.350893 -74.186031)
			(xy 91.295456 -74.192131) (xy 91.239722 -74.190094) (xy 91.184879 -74.179964) (xy 91.132095 -74.161957)
			(xy 91.082495 -74.136456) (xy 91.037137 -74.104005) (xy 90.996988 -74.065296) (xy 90.962902 -74.021153)
			(xy 90.935606 -73.972518) (xy 90.915683 -73.920427) (xy 90.903557 -73.86599) (xy 90.899486 -73.810368)
			(xy 84.148393 -73.810368) (xy 81.548714 -77.206348) (xy 82.68411 -77.206348) (xy 82.688181 -77.150726)
			(xy 82.700307 -77.096289) (xy 82.72023 -77.044198) (xy 82.747526 -76.995563) (xy 82.781612 -76.95142)
			(xy 82.821761 -76.912711) (xy 82.867119 -76.88026) (xy 82.916719 -76.854759) (xy 82.969503 -76.836752)
			(xy 83.024346 -76.826622) (xy 83.08008 -76.824585) (xy 83.135517 -76.830685) (xy 83.189474 -76.844791)
			(xy 83.240803 -76.866603) (xy 83.288409 -76.895657) (xy 83.331277 -76.931332) (xy 83.368494 -76.972869)
			(xy 83.399267 -77.019382) (xy 83.422939 -77.069879) (xy 83.439007 -77.123286) (xy 83.447127 -77.178462)
			(xy 83.447636 -77.206348) (xy 83.447127 -77.234234) (xy 83.439007 -77.28941) (xy 83.422939 -77.342817)
			(xy 83.399267 -77.393314) (xy 83.368494 -77.439827) (xy 83.331277 -77.481364) (xy 83.288409 -77.517039)
			(xy 83.240803 -77.546093) (xy 83.189474 -77.567905) (xy 83.135517 -77.582011) (xy 83.08008 -77.588111)
			(xy 83.024346 -77.586074) (xy 82.969503 -77.575944) (xy 82.916719 -77.557937) (xy 82.867119 -77.532436)
			(xy 82.821761 -77.499985) (xy 82.781612 -77.461276) (xy 82.747526 -77.417133) (xy 82.72023 -77.368498)
			(xy 82.700307 -77.316407) (xy 82.688181 -77.26197) (xy 82.68411 -77.206348) (xy 81.548714 -77.206348)
			(xy 80.268318 -78.878938) (xy 80.263482 -78.885893) (xy 80.258175 -78.901967) (xy 80.257904 -78.910434)
			(xy 80.257904 -78.918816) (xy 80.263746 -78.934564) (xy 80.269334 -78.941422) (xy 80.285395 -78.961916)
			(xy 80.312405 -79.006431) (xy 80.333118 -79.054202) (xy 80.34715 -79.104343) (xy 80.354241 -79.155926)
			(xy 80.354678 -79.18196) (xy 80.354158 -79.210634) (xy 80.345569 -79.267337) (xy 80.328593 -79.322116)
			(xy 80.303613 -79.373739) (xy 80.271191 -79.421043) (xy 80.232056 -79.462964) (xy 80.209898 -79.481172)
			(xy 80.207358 -79.483204) (xy 80.20304 -79.487522) (xy 80.196272 -79.494951) (xy 80.188696 -79.513547)
			(xy 80.188308 -79.52359) (xy 80.191864 -79.57312) (xy 80.194658 -79.613506) (xy 80.19652 -79.624266)
			(xy 80.207973 -79.642832) (xy 80.216756 -79.64932) (xy 80.219804 -79.651098) (xy 80.244388 -79.665786)
			(xy 80.289252 -79.701378) (xy 80.328293 -79.743274) (xy 80.360634 -79.790534) (xy 80.38555 -79.842097)
			(xy 80.40248 -79.896804) (xy 80.411044 -79.953427) (xy 80.411574 -79.98206) (xy 80.411113 -80.009314)
			(xy 80.403361 -80.063267) (xy 80.388008 -80.115568) (xy 80.386688 -80.118458) (xy 88.214706 -80.118458)
			(xy 88.218777 -80.062836) (xy 88.230903 -80.008399) (xy 88.250826 -79.956308) (xy 88.278122 -79.907673)
			(xy 88.312208 -79.86353) (xy 88.352357 -79.824821) (xy 88.397715 -79.79237) (xy 88.447315 -79.766869)
			(xy 88.500099 -79.748862) (xy 88.554942 -79.738732) (xy 88.610676 -79.736695) (xy 88.666113 -79.742795)
			(xy 88.72007 -79.756901) (xy 88.771399 -79.778713) (xy 88.819005 -79.807767) (xy 88.861873 -79.843442)
			(xy 88.89909 -79.884979) (xy 88.929863 -79.931492) (xy 88.953535 -79.981989) (xy 88.969603 -80.035396)
			(xy 88.977723 -80.090572) (xy 88.978232 -80.118458) (xy 88.977723 -80.146344) (xy 88.969603 -80.20152)
			(xy 88.953535 -80.254927) (xy 88.929863 -80.305424) (xy 88.89909 -80.351937) (xy 88.861873 -80.393474)
			(xy 88.819005 -80.429149) (xy 88.771399 -80.458203) (xy 88.72007 -80.480015) (xy 88.666113 -80.494121)
			(xy 88.610676 -80.500221) (xy 88.554942 -80.498184) (xy 88.500099 -80.488054) (xy 88.447315 -80.470047)
			(xy 88.397715 -80.444546) (xy 88.352357 -80.412095) (xy 88.312208 -80.373386) (xy 88.278122 -80.329243)
			(xy 88.250826 -80.280608) (xy 88.230903 -80.228517) (xy 88.218777 -80.17408) (xy 88.214706 -80.118458)
			(xy 80.386688 -80.118458) (xy 80.365367 -80.165151) (xy 80.3359 -80.211007) (xy 80.300206 -80.252201)
			(xy 80.259011 -80.287896) (xy 80.213156 -80.317364) (xy 80.163574 -80.340006) (xy 80.111273 -80.35536)
			(xy 80.05732 -80.363113) (xy 80.030066 -80.363568) (xy 80.003045 -80.363096) (xy 79.949545 -80.355467)
			(xy 79.897657 -80.340365) (xy 79.848419 -80.318093) (xy 79.802815 -80.289096) (xy 79.76176 -80.253956)
			(xy 79.726073 -80.213374) (xy 79.696468 -80.168162) (xy 79.67354 -80.119226) (xy 79.657745 -80.067545)
			(xy 79.6494 -80.014152) (xy 79.648558 -79.98714) (xy 79.648558 -79.986886) (xy 79.647874 -79.976393)
			(xy 79.63917 -79.957277) (xy 79.623549 -79.943235) (xy 79.61376 -79.939388) (xy 79.522574 -79.909416)
			(xy 79.512424 -79.906609) (xy 79.491477 -79.908548) (xy 79.473051 -79.918698) (xy 79.466186 -79.926688)
			(xy 79.455772 -79.940404) (xy 79.198724 -80.276192) (xy 79.131668 -80.363568) (xy 79.128745 -80.367671)
			(xy 79.124387 -80.376751) (xy 79.123032 -80.381602) (xy 79.120492 -80.391) (xy 79.121762 -80.400906)
			(xy 79.123217 -80.413045) (xy 79.124744 -80.437448) (xy 79.12481 -80.449674) (xy 79.124315 -80.477309)
			(xy 79.116333 -80.532001) (xy 79.100546 -80.58497) (xy 79.077285 -80.635108) (xy 79.047036 -80.681366)
			(xy 79.010431 -80.722779) (xy 78.968236 -80.758479) (xy 78.921334 -80.78772) (xy 78.870704 -80.809891)
			(xy 78.817407 -80.824528) (xy 78.790038 -80.828388) (xy 78.789784 -80.828388) (xy 78.784704 -80.82915)
			(xy 78.77683 -80.833722) (xy 78.772534 -80.836344) (xy 78.764986 -80.842998) (xy 78.761844 -80.84693)
			(xy 78.552441 -81.120488) (xy 88.099136 -81.120488) (xy 88.103207 -81.064866) (xy 88.115333 -81.010429)
			(xy 88.135256 -80.958338) (xy 88.162552 -80.909703) (xy 88.196638 -80.86556) (xy 88.236787 -80.826851)
			(xy 88.282145 -80.7944) (xy 88.331745 -80.768899) (xy 88.384529 -80.750892) (xy 88.439372 -80.740762)
			(xy 88.495106 -80.738725) (xy 88.550543 -80.744825) (xy 88.6045 -80.758931) (xy 88.655829 -80.780743)
			(xy 88.703435 -80.809797) (xy 88.746303 -80.845472) (xy 88.78352 -80.887009) (xy 88.814293 -80.933522)
			(xy 88.837965 -80.984019) (xy 88.854033 -81.037426) (xy 88.862153 -81.092602) (xy 88.862662 -81.120488)
			(xy 88.862153 -81.148374) (xy 88.854033 -81.20355) (xy 88.837965 -81.256957) (xy 88.814293 -81.307454)
			(xy 88.78352 -81.353967) (xy 88.746303 -81.395504) (xy 88.703435 -81.431179) (xy 88.655829 -81.460233)
			(xy 88.6045 -81.482045) (xy 88.550543 -81.496151) (xy 88.495106 -81.502251) (xy 88.439372 -81.500214)
			(xy 88.384529 -81.490084) (xy 88.331745 -81.472077) (xy 88.282145 -81.446576) (xy 88.236787 -81.414125)
			(xy 88.196638 -81.375416) (xy 88.162552 -81.331273) (xy 88.135256 -81.282638) (xy 88.115333 -81.230547)
			(xy 88.103207 -81.17611) (xy 88.099136 -81.120488) (xy 78.552441 -81.120488) (xy 78.002198 -81.839308)
			(xy 88.80551 -81.839308) (xy 88.809581 -81.783686) (xy 88.821707 -81.729249) (xy 88.84163 -81.677158)
			(xy 88.868926 -81.628523) (xy 88.903012 -81.58438) (xy 88.943161 -81.545671) (xy 88.988519 -81.51322)
			(xy 89.038119 -81.487719) (xy 89.090903 -81.469712) (xy 89.145746 -81.459582) (xy 89.20148 -81.457545)
			(xy 89.256917 -81.463645) (xy 89.310874 -81.477751) (xy 89.362203 -81.499563) (xy 89.409809 -81.528617)
			(xy 89.452677 -81.564292) (xy 89.489894 -81.605829) (xy 89.520667 -81.652342) (xy 89.544339 -81.702839)
			(xy 89.560407 -81.756246) (xy 89.568527 -81.811422) (xy 89.569036 -81.839308) (xy 89.568527 -81.867194)
			(xy 89.560407 -81.92237) (xy 89.544339 -81.975777) (xy 89.520667 -82.026274) (xy 89.489894 -82.072787)
			(xy 89.452677 -82.114324) (xy 89.409809 -82.149999) (xy 89.362203 -82.179053) (xy 89.310874 -82.200865)
			(xy 89.256917 -82.214971) (xy 89.20148 -82.221071) (xy 89.145746 -82.219034) (xy 89.090903 -82.208904)
			(xy 89.038119 -82.190897) (xy 88.988519 -82.165396) (xy 88.943161 -82.132945) (xy 88.903012 -82.094236)
			(xy 88.868926 -82.050093) (xy 88.84163 -82.001458) (xy 88.821707 -81.949367) (xy 88.809581 -81.89493)
			(xy 88.80551 -81.839308) (xy 78.002198 -81.839308) (xy 77.551894 -82.427572) (xy 78.932784 -82.427572)
			(xy 78.936855 -82.37195) (xy 78.948981 -82.317513) (xy 78.968904 -82.265422) (xy 78.9962 -82.216787)
			(xy 79.030286 -82.172644) (xy 79.070435 -82.133935) (xy 79.115793 -82.101484) (xy 79.165393 -82.075983)
			(xy 79.218177 -82.057976) (xy 79.27302 -82.047846) (xy 79.328754 -82.045809) (xy 79.384191 -82.051909)
			(xy 79.438148 -82.066015) (xy 79.489477 -82.087827) (xy 79.537083 -82.116881) (xy 79.579951 -82.152556)
			(xy 79.617168 -82.194093) (xy 79.647941 -82.240606) (xy 79.671613 -82.291103) (xy 79.687681 -82.34451)
			(xy 79.692578 -82.377788) (xy 80.519014 -82.377788) (xy 80.523085 -82.322166) (xy 80.535211 -82.267729)
			(xy 80.555134 -82.215638) (xy 80.58243 -82.167003) (xy 80.616516 -82.12286) (xy 80.656665 -82.084151)
			(xy 80.702023 -82.0517) (xy 80.751623 -82.026199) (xy 80.804407 -82.008192) (xy 80.85925 -81.998062)
			(xy 80.914984 -81.996025) (xy 80.970421 -82.002125) (xy 81.024378 -82.016231) (xy 81.075707 -82.038043)
			(xy 81.123313 -82.067097) (xy 81.166181 -82.102772) (xy 81.203398 -82.144309) (xy 81.234171 -82.190822)
			(xy 81.257843 -82.241319) (xy 81.273911 -82.294726) (xy 81.282031 -82.349902) (xy 81.28254 -82.377788)
			(xy 81.282031 -82.405674) (xy 81.273911 -82.46085) (xy 81.257843 -82.514257) (xy 81.234171 -82.564754)
			(xy 81.203398 -82.611267) (xy 81.166181 -82.652804) (xy 81.123313 -82.688479) (xy 81.075707 -82.717533)
			(xy 81.024378 -82.739345) (xy 80.970421 -82.753451) (xy 80.914984 -82.759551) (xy 80.85925 -82.757514)
			(xy 80.804407 -82.747384) (xy 80.751623 -82.729377) (xy 80.702023 -82.703876) (xy 80.656665 -82.671425)
			(xy 80.616516 -82.632716) (xy 80.58243 -82.588573) (xy 80.555134 -82.539938) (xy 80.535211 -82.487847)
			(xy 80.523085 -82.43341) (xy 80.519014 -82.377788) (xy 79.692578 -82.377788) (xy 79.695801 -82.399686)
			(xy 79.69631 -82.427572) (xy 79.695801 -82.455458) (xy 79.687681 -82.510634) (xy 79.671613 -82.564041)
			(xy 79.647941 -82.614538) (xy 79.617168 -82.661051) (xy 79.579951 -82.702588) (xy 79.537083 -82.738263)
			(xy 79.489477 -82.767317) (xy 79.438148 -82.789129) (xy 79.384191 -82.803235) (xy 79.328754 -82.809335)
			(xy 79.27302 -82.807298) (xy 79.218177 -82.797168) (xy 79.165393 -82.779161) (xy 79.115793 -82.75366)
			(xy 79.070435 -82.721209) (xy 79.030286 -82.6825) (xy 78.9962 -82.638357) (xy 78.968904 -82.589722)
			(xy 78.948981 -82.537631) (xy 78.936855 -82.483194) (xy 78.932784 -82.427572) (xy 77.551894 -82.427572)
			(xy 76.95946 -83.20151) (xy 76.955728 -83.207817) (xy 76.951601 -83.221872) (xy 76.951332 -83.229196)
			(xy 76.96581 -83.264756) (xy 76.97216 -83.271614) (xy 76.991391 -83.29293) (xy 77.023884 -83.340258)
			(xy 77.048919 -83.391921) (xy 77.065928 -83.446753) (xy 77.074528 -83.503514) (xy 77.07503 -83.532218)
			(xy 77.074531 -83.559959) (xy 77.066497 -83.614855) (xy 77.0506 -83.668011) (xy 77.027176 -83.718305)
			(xy 76.996717 -83.764678) (xy 76.959866 -83.806153) (xy 76.917399 -83.841857) (xy 76.870211 -83.871037)
			(xy 76.819296 -83.893078) (xy 76.765726 -83.907516) (xy 76.738226 -83.911186) (xy 76.723748 -83.91271)
			(xy 76.693522 -83.91398) (xy 76.669058 -83.913591) (xy 76.620531 -83.907344) (xy 76.573199 -83.89495)
			(xy 76.527837 -83.876612) (xy 76.506324 -83.864958) (xy 76.50607 -83.864958) (xy 76.497964 -83.860819)
			(xy 76.480005 -83.857939) (xy 76.471018 -83.85937) (xy 76.462128 -83.861148) (xy 76.446888 -83.8708)
			(xy 75.983358 -84.476336) (xy 79.867758 -84.476336) (xy 79.871829 -84.420714) (xy 79.883955 -84.366277)
			(xy 79.903878 -84.314186) (xy 79.931174 -84.265551) (xy 79.96526 -84.221408) (xy 80.005409 -84.182699)
			(xy 80.050767 -84.150248) (xy 80.100367 -84.124747) (xy 80.153151 -84.10674) (xy 80.207994 -84.09661)
			(xy 80.263728 -84.094573) (xy 80.319165 -84.100673) (xy 80.373122 -84.114779) (xy 80.424451 -84.136591)
			(xy 80.472057 -84.165645) (xy 80.514925 -84.20132) (xy 80.552142 -84.242857) (xy 80.582915 -84.28937)
			(xy 80.606587 -84.339867) (xy 80.622655 -84.393274) (xy 80.630775 -84.44845) (xy 80.631284 -84.476336)
			(xy 80.630775 -84.504222) (xy 80.622655 -84.559398) (xy 80.606587 -84.612805) (xy 80.582915 -84.663302)
			(xy 80.552142 -84.709815) (xy 80.514925 -84.751352) (xy 80.472057 -84.787027) (xy 80.424451 -84.816081)
			(xy 80.373122 -84.837893) (xy 80.319165 -84.851999) (xy 80.263728 -84.858099) (xy 80.207994 -84.856062)
			(xy 80.153151 -84.845932) (xy 80.100367 -84.827925) (xy 80.050767 -84.802424) (xy 80.005409 -84.769973)
			(xy 79.96526 -84.731264) (xy 79.931174 -84.687121) (xy 79.903878 -84.638486) (xy 79.883955 -84.586395)
			(xy 79.871829 -84.531958) (xy 79.867758 -84.476336) (xy 75.983358 -84.476336) (xy 74.627183 -86.247986)
			(xy 75.238608 -86.247986) (xy 75.242679 -86.192364) (xy 75.254805 -86.137927) (xy 75.274728 -86.085836)
			(xy 75.302024 -86.037201) (xy 75.33611 -85.993058) (xy 75.376259 -85.954349) (xy 75.421617 -85.921898)
			(xy 75.471217 -85.896397) (xy 75.524001 -85.87839) (xy 75.578844 -85.86826) (xy 75.634578 -85.866223)
			(xy 75.690015 -85.872323) (xy 75.743972 -85.886429) (xy 75.795301 -85.908241) (xy 75.842907 -85.937295)
			(xy 75.885775 -85.97297) (xy 75.922992 -86.014507) (xy 75.953765 -86.06102) (xy 75.977437 -86.111517)
			(xy 75.993505 -86.164924) (xy 76.001625 -86.2201) (xy 76.002134 -86.247986) (xy 76.001625 -86.275872)
			(xy 75.993505 -86.331048) (xy 75.977437 -86.384455) (xy 75.953765 -86.434952) (xy 75.922992 -86.481465)
			(xy 75.885775 -86.523002) (xy 75.842907 -86.558677) (xy 75.795301 -86.587731) (xy 75.743972 -86.609543)
			(xy 75.690015 -86.623649) (xy 75.634578 -86.629749) (xy 75.578844 -86.627712) (xy 75.524001 -86.617582)
			(xy 75.471217 -86.599575) (xy 75.421617 -86.574074) (xy 75.376259 -86.541623) (xy 75.33611 -86.502914)
			(xy 75.302024 -86.458771) (xy 75.274728 -86.410136) (xy 75.254805 -86.358045) (xy 75.242679 -86.303608)
			(xy 75.238608 -86.247986) (xy 74.627183 -86.247986) (xy 72.553743 -88.956642) (xy 73.632566 -88.956642)
			(xy 73.636637 -88.90102) (xy 73.648763 -88.846583) (xy 73.668686 -88.794492) (xy 73.695982 -88.745857)
			(xy 73.730068 -88.701714) (xy 73.770217 -88.663005) (xy 73.815575 -88.630554) (xy 73.865175 -88.605053)
			(xy 73.917959 -88.587046) (xy 73.972802 -88.576916) (xy 74.028536 -88.574879) (xy 74.083973 -88.580979)
			(xy 74.13793 -88.595085) (xy 74.189259 -88.616897) (xy 74.236865 -88.645951) (xy 74.279733 -88.681626)
			(xy 74.31695 -88.723163) (xy 74.347723 -88.769676) (xy 74.371395 -88.820173) (xy 74.387463 -88.87358)
			(xy 74.395583 -88.928756) (xy 74.396092 -88.956642) (xy 74.395583 -88.984528) (xy 74.387463 -89.039704)
			(xy 74.371395 -89.093111) (xy 74.347723 -89.143608) (xy 74.31695 -89.190121) (xy 74.279733 -89.231658)
			(xy 74.236865 -89.267333) (xy 74.189259 -89.296387) (xy 74.13793 -89.318199) (xy 74.083973 -89.332305)
			(xy 74.028536 -89.338405) (xy 73.972802 -89.336368) (xy 73.917959 -89.326238) (xy 73.865175 -89.308231)
			(xy 73.815575 -89.28273) (xy 73.770217 -89.250279) (xy 73.730068 -89.21157) (xy 73.695982 -89.167427)
			(xy 73.668686 -89.118792) (xy 73.648763 -89.066701) (xy 73.636637 -89.012264) (xy 73.632566 -88.956642)
			(xy 72.553743 -88.956642) (xy 68.377308 -94.412562) (xy 68.371974 -94.421198) (xy 68.368164 -94.431866)
			(xy 68.175886 -95.240094) (xy 68.011294 -95.932752) (xy 68.00977 -95.939102) (xy 68.00977 -95.939356)
			(xy 67.79355 -96.901) (xy 69.321932 -96.901) (xy 69.326003 -96.845378) (xy 69.338129 -96.790941)
			(xy 69.358052 -96.73885) (xy 69.385348 -96.690215) (xy 69.419434 -96.646072) (xy 69.459583 -96.607363)
			(xy 69.504941 -96.574912) (xy 69.554541 -96.549411) (xy 69.607325 -96.531404) (xy 69.662168 -96.521274)
			(xy 69.717902 -96.519237) (xy 69.773339 -96.525337) (xy 69.827296 -96.539443) (xy 69.878625 -96.561255)
			(xy 69.926231 -96.590309) (xy 69.969099 -96.625984) (xy 70.006316 -96.667521) (xy 70.037089 -96.714034)
			(xy 70.060761 -96.764531) (xy 70.076829 -96.817938) (xy 70.084949 -96.873114) (xy 70.085458 -96.901)
			(xy 70.084949 -96.928886) (xy 70.076829 -96.984062) (xy 70.060761 -97.037469) (xy 70.037089 -97.087966)
			(xy 70.006316 -97.134479) (xy 69.969099 -97.176016) (xy 69.926231 -97.211691) (xy 69.878625 -97.240745)
			(xy 69.827296 -97.262557) (xy 69.773339 -97.276663) (xy 69.717902 -97.282763) (xy 69.662168 -97.280726)
			(xy 69.607325 -97.270596) (xy 69.554541 -97.252589) (xy 69.504941 -97.227088) (xy 69.459583 -97.194637)
			(xy 69.419434 -97.155928) (xy 69.385348 -97.111785) (xy 69.358052 -97.06315) (xy 69.338129 -97.011059)
			(xy 69.326003 -96.956622) (xy 69.321932 -96.901) (xy 67.79355 -96.901) (xy 67.017762 -100.351336)
			(xy 70.122032 -100.351336) (xy 70.126103 -100.295714) (xy 70.138229 -100.241277) (xy 70.158152 -100.189186)
			(xy 70.185448 -100.140551) (xy 70.219534 -100.096408) (xy 70.259683 -100.057699) (xy 70.305041 -100.025248)
			(xy 70.354641 -99.999747) (xy 70.407425 -99.98174) (xy 70.462268 -99.97161) (xy 70.518002 -99.969573)
			(xy 70.573439 -99.975673) (xy 70.627396 -99.989779) (xy 70.678725 -100.011591) (xy 70.726331 -100.040645)
			(xy 70.769199 -100.07632) (xy 70.806416 -100.117857) (xy 70.837189 -100.16437) (xy 70.860861 -100.214867)
			(xy 70.876929 -100.268274) (xy 70.885049 -100.32345) (xy 70.885558 -100.351336) (xy 70.885049 -100.379222)
			(xy 70.876929 -100.434398) (xy 70.860861 -100.487805) (xy 70.837189 -100.538302) (xy 70.806416 -100.584815)
			(xy 70.769199 -100.626352) (xy 70.726331 -100.662027) (xy 70.678725 -100.691081) (xy 70.627396 -100.712893)
			(xy 70.573439 -100.726999) (xy 70.518002 -100.733099) (xy 70.462268 -100.731062) (xy 70.407425 -100.720932)
			(xy 70.354641 -100.702925) (xy 70.305041 -100.677424) (xy 70.259683 -100.644973) (xy 70.219534 -100.606264)
			(xy 70.185448 -100.562121) (xy 70.158152 -100.513486) (xy 70.138229 -100.461395) (xy 70.126103 -100.406958)
			(xy 70.122032 -100.351336) (xy 67.017762 -100.351336) (xy 65.509648 -107.058714) (xy 65.50914 -107.060746)
			(xy 65.506854 -107.073446) (xy 65.505584 -107.083098) (xy 65.50533 -107.085638) (xy 65.508632 -107.095798)
			(xy 65.516797 -107.123601) (xy 65.525597 -107.180872) (xy 65.526158 -107.209844) (xy 65.526158 -107.224322)
			(xy 65.524411 -107.255034) (xy 65.512327 -107.315347) (xy 65.490729 -107.372942) (xy 65.460177 -107.426329)
			(xy 65.441322 -107.450636) (xy 65.437004 -107.45597) (xy 65.43675 -107.456224) (xy 65.434464 -107.461304)
			(xy 65.430908 -107.472734) (xy 65.40754 -107.593892) (xy 65.06464 -109.39399) (xy 65.06591 -109.40669)
			(xy 65.066418 -109.408976) (xy 65.069689 -109.427085) (xy 65.073127 -109.463726) (xy 65.073276 -109.482128)
			(xy 65.073276 -109.50194) (xy 65.073022 -109.507782) (xy 65.072006 -109.516672) (xy 65.071752 -109.51845)
			(xy 65.071752 -109.518704) (xy 65.068737 -109.54473) (xy 65.056499 -109.595674) (xy 65.037425 -109.644473)
			(xy 65.025016 -109.667548) (xy 65.014856 -109.68482) (xy 65.01257 -109.68863) (xy 65.006982 -109.701838)
			(xy 65.00495 -109.706918) (xy 64.771524 -110.933484) (xy 64.770907 -110.941156) (xy 64.773756 -110.956275)
			(xy 64.777112 -110.963202) (xy 64.780922 -110.970314) (xy 64.793114 -110.981744) (xy 64.801242 -110.985554)
			(xy 64.826146 -110.99717) (xy 64.872618 -111.026498) (xy 64.914401 -111.06219) (xy 64.950632 -111.103506)
			(xy 64.980561 -111.149593) (xy 65.003569 -111.199496) (xy 65.019181 -111.252184) (xy 65.027072 -111.306566)
			(xy 65.027556 -111.334042) (xy 65.027097 -111.360567) (xy 65.019744 -111.413105) (xy 65.005186 -111.464118)
			(xy 64.983703 -111.512623) (xy 64.955709 -111.557686) (xy 64.921744 -111.598437) (xy 64.882463 -111.634092)
			(xy 64.838622 -111.663963) (xy 64.791067 -111.687474) (xy 64.740713 -111.704172) (xy 64.688533 -111.713736)
			(xy 64.66205 -111.715296) (xy 64.660526 -111.715296) (xy 64.65238 -111.716179) (xy 64.637232 -111.722402)
			(xy 64.630808 -111.727488) (xy 64.624458 -111.733076) (xy 64.62014 -111.740188) (xy 64.618071 -111.744007)
			(xy 64.615141 -111.752183) (xy 64.614298 -111.756444) (xy 64.545972 -112.114584) (xy 64.513206 -112.287304)
			(xy 64.51223 -112.292999) (xy 64.512621 -112.304545) (xy 64.513968 -112.310164) (xy 64.516508 -112.319562)
			(xy 64.520826 -112.330484) (xy 64.522096 -112.33277) (xy 64.535836 -112.360155) (xy 64.55536 -112.418225)
			(xy 64.565348 -112.47867) (xy 64.566038 -112.5093) (xy 64.566038 -112.51819) (xy 64.565055 -112.545585)
			(xy 64.556205 -112.599682) (xy 64.539706 -112.651956) (xy 64.515896 -112.701331) (xy 64.485267 -112.746792)
			(xy 64.448448 -112.787402) (xy 64.427608 -112.80521) (xy 64.425576 -112.806734) (xy 64.422274 -112.810036)
			(xy 64.413892 -112.821212) (xy 64.409066 -112.833658) (xy 64.408823 -112.834928) (xy 66.496946 -112.834928)
			(xy 66.497432 -112.807677) (xy 66.505188 -112.753729) (xy 66.520543 -112.701434) (xy 66.543185 -112.651857)
			(xy 66.572651 -112.606007) (xy 66.608342 -112.564816) (xy 66.649533 -112.529125) (xy 66.695383 -112.499659)
			(xy 66.74496 -112.477017) (xy 66.797255 -112.461662) (xy 66.851203 -112.453906) (xy 66.905705 -112.453906)
			(xy 66.959653 -112.461662) (xy 67.011948 -112.477017) (xy 67.061525 -112.499659) (xy 67.107375 -112.529125)
			(xy 67.148566 -112.564816) (xy 67.184257 -112.606007) (xy 67.213723 -112.651857) (xy 67.236365 -112.701434)
			(xy 67.25172 -112.753729) (xy 67.259476 -112.807677) (xy 67.259962 -112.834928) (xy 67.259592 -112.858546)
			(xy 67.253736 -112.905418) (xy 67.248278 -112.9284) (xy 67.245153 -112.942907) (xy 67.246479 -112.97254)
			(xy 67.256253 -113.000546) (xy 67.273654 -113.024568) (xy 67.297217 -113.042587) (xy 67.32496 -113.053085)
			(xy 67.339718 -113.054638) (xy 67.368241 -113.057167) (xy 67.424115 -113.069687) (xy 67.47749 -113.090418)
			(xy 67.527167 -113.118895) (xy 67.572028 -113.154479) (xy 67.611066 -113.196368) (xy 67.643403 -113.243623)
			(xy 67.668313 -113.295181) (xy 67.685236 -113.349883) (xy 67.693791 -113.4065) (xy 67.694302 -113.43513)
			(xy 67.693816 -113.462381) (xy 67.68606 -113.516329) (xy 67.670705 -113.568624) (xy 67.648063 -113.618201)
			(xy 67.618597 -113.664051) (xy 67.582906 -113.705242) (xy 67.541715 -113.740933) (xy 67.495865 -113.770399)
			(xy 67.446288 -113.793041) (xy 67.393993 -113.808396) (xy 67.340045 -113.816152) (xy 67.285543 -113.816152)
			(xy 67.231595 -113.808396) (xy 67.1793 -113.793041) (xy 67.129723 -113.770399) (xy 67.083873 -113.740933)
			(xy 67.042682 -113.705242) (xy 67.006991 -113.664051) (xy 66.977525 -113.618201) (xy 66.954883 -113.568624)
			(xy 66.939528 -113.516329) (xy 66.931772 -113.462381) (xy 66.931286 -113.43513) (xy 66.93165 -113.411512)
			(xy 66.93751 -113.364639) (xy 66.94297 -113.341658) (xy 66.946079 -113.327146) (xy 66.944768 -113.297511)
			(xy 66.935001 -113.269501) (xy 66.917602 -113.245475) (xy 66.894037 -113.227458) (xy 66.86629 -113.216967)
			(xy 66.85153 -113.21542) (xy 66.823006 -113.212891) (xy 66.767129 -113.200377) (xy 66.713751 -113.179649)
			(xy 66.664072 -113.151173) (xy 66.619209 -113.11559) (xy 66.58017 -113.073699) (xy 66.547833 -113.026443)
			(xy 66.522924 -112.974883) (xy 66.506005 -112.920178) (xy 66.497454 -112.863559) (xy 66.496946 -112.834928)
			(xy 64.408823 -112.834928) (xy 64.40043 -112.87887) (xy 64.399668 -112.883442) (xy 64.398685 -112.892503)
			(xy 64.402433 -112.910328) (xy 64.412157 -112.925728) (xy 64.426639 -112.936774) (xy 64.435228 -112.93983)
			(xy 64.445896 -112.941862) (xy 64.453509 -112.942152) (xy 64.468361 -112.938799) (xy 64.475106 -112.935258)
			(xy 64.4779 -112.93348) (xy 64.501416 -112.918533) (xy 64.551869 -112.894886) (xy 64.605226 -112.878836)
			(xy 64.660352 -112.870726) (xy 64.688212 -112.870234) (xy 64.71546 -112.870721) (xy 64.7694 -112.878478)
			(xy 64.821688 -112.893832) (xy 64.871258 -112.916472) (xy 64.917102 -112.945935) (xy 64.958286 -112.981623)
			(xy 64.993972 -113.022808) (xy 65.023434 -113.068653) (xy 65.046072 -113.118224) (xy 65.061425 -113.170512)
			(xy 65.06918 -113.224452) (xy 65.06918 -113.278948) (xy 65.061425 -113.332888) (xy 65.046072 -113.385176)
			(xy 65.023434 -113.434747) (xy 64.993972 -113.480592) (xy 64.958286 -113.521777) (xy 64.917102 -113.557465)
			(xy 64.871258 -113.586928) (xy 64.821688 -113.609568) (xy 64.7694 -113.624922) (xy 64.71546 -113.632679)
			(xy 64.688212 -113.63325) (xy 64.687704 -113.63325) (xy 64.658023 -113.632669) (xy 64.599381 -113.62344)
			(xy 64.542878 -113.605236) (xy 64.489878 -113.578496) (xy 64.465454 -113.561622) (xy 64.450722 -113.551208)
			(xy 64.446404 -113.547398) (xy 64.434974 -113.537238) (xy 64.432434 -113.534952) (xy 64.43218 -113.534698)
			(xy 64.427056 -113.530367) (xy 64.415082 -113.524328) (xy 64.408558 -113.52276) (xy 64.401954 -113.52149)
			(xy 64.388746 -113.522252) (xy 64.298322 -113.552732) (xy 64.290334 -113.555723) (xy 64.276816 -113.566111)
			(xy 64.267464 -113.580364) (xy 64.265048 -113.588546) (xy 64.192404 -113.970308) (xy 64.075963 -114.581432)
			(xy 66.300096 -114.581432) (xy 66.300582 -114.554181) (xy 66.308338 -114.500233) (xy 66.323693 -114.447938)
			(xy 66.346335 -114.398361) (xy 66.375801 -114.352511) (xy 66.411492 -114.31132) (xy 66.452683 -114.275629)
			(xy 66.498533 -114.246163) (xy 66.54811 -114.223521) (xy 66.600405 -114.208166) (xy 66.654353 -114.20041)
			(xy 66.708855 -114.20041) (xy 66.762803 -114.208166) (xy 66.815098 -114.223521) (xy 66.864675 -114.246163)
			(xy 66.910525 -114.275629) (xy 66.951716 -114.31132) (xy 66.987407 -114.352511) (xy 67.016873 -114.398361)
			(xy 67.039515 -114.447938) (xy 67.05487 -114.500233) (xy 67.062626 -114.554181) (xy 67.063112 -114.581432)
			(xy 67.062096 -114.607848) (xy 67.062096 -114.608102) (xy 67.061966 -114.619897) (xy 67.07109 -114.641615)
			(xy 67.079622 -114.649758) (xy 67.150742 -114.710718) (xy 67.173602 -114.71656) (xy 67.185286 -114.71402)
			(xy 67.185794 -114.71402) (xy 67.21713 -114.70742) (xy 67.280774 -114.700293) (xy 67.312794 -114.699796)
			(xy 67.617594 -114.699796) (xy 67.627667 -114.699395) (xy 67.646266 -114.69166) (xy 67.653662 -114.68481)
			(xy 68.295774 -114.042952) (xy 68.30258 -114.035525) (xy 68.31032 -114.016946) (xy 68.31076 -114.006884)
			(xy 68.31076 -111.06531) (xy 68.311256 -111.032458) (xy 68.318617 -110.967166) (xy 68.333236 -110.903109)
			(xy 68.35493 -110.841088) (xy 68.383427 -110.781885) (xy 68.418368 -110.726241) (xy 68.459316 -110.674856)
			(xy 68.48221 -110.65129) (xy 70.759574 -108.373926) (xy 70.783154 -108.351044) (xy 70.834528 -108.310078)
			(xy 70.890165 -108.275122) (xy 70.949366 -108.246615) (xy 71.011386 -108.224914) (xy 71.075446 -108.210293)
			(xy 71.14074 -108.202937) (xy 71.173594 -108.202476) (xy 72.152764 -108.202476) (xy 72.162832 -108.202038)
			(xy 72.18143 -108.194327) (xy 72.188832 -108.18749) (xy 72.526906 -107.849162) (xy 72.533756 -107.84177)
			(xy 72.54147 -107.823165) (xy 72.541892 -107.813094) (xy 72.541892 -106.413808) (xy 72.541464 -106.403739)
			(xy 72.533745 -106.385141) (xy 72.526906 -106.37774) (xy 71.792338 -105.643172) (xy 71.769432 -105.619615)
			(xy 71.728468 -105.568237) (xy 71.693514 -105.512596) (xy 71.66501 -105.453391) (xy 71.643313 -105.391367)
			(xy 71.628697 -105.327304) (xy 71.621346 -105.262007) (xy 71.620888 -105.229152) (xy 71.620888 -97.780602)
			(xy 71.62137 -97.747749) (xy 71.628733 -97.682457) (xy 71.643354 -97.618399) (xy 71.66505 -97.556378)
			(xy 71.693549 -97.497175) (xy 71.728492 -97.441531) (xy 71.769442 -97.390147) (xy 71.792338 -97.366582)
			(xy 72.705468 -96.453452) (xy 72.711981 -96.446214) (xy 72.719558 -96.4283) (xy 72.719935 -96.408853)
			(xy 72.716898 -96.399604) (xy 72.679052 -96.298766) (xy 72.654922 -96.28124) (xy 72.639936 -96.280224)
			(xy 72.593936 -96.276741) (xy 72.502713 -96.262977) (xy 72.413018 -96.241391) (xy 72.325521 -96.212144)
			(xy 72.240875 -96.175454) (xy 72.159712 -96.131595) (xy 72.082636 -96.080895) (xy 72.010224 -96.023732)
			(xy 71.943016 -95.960532) (xy 71.881514 -95.891768) (xy 71.826176 -95.817952) (xy 71.777416 -95.739635)
			(xy 71.735597 -95.657401) (xy 71.701032 -95.571866) (xy 71.673978 -95.483666) (xy 71.654638 -95.39346)
			(xy 71.643155 -95.301922) (xy 71.639616 -95.209734) (xy 71.644047 -95.117585) (xy 71.656415 -95.026162)
			(xy 71.676627 -94.936148) (xy 71.704532 -94.848214) (xy 71.739924 -94.763016) (xy 71.782536 -94.681192)
			(xy 71.832052 -94.60335) (xy 71.888101 -94.530073) (xy 71.950266 -94.461906) (xy 72.018082 -94.39936)
			(xy 72.091044 -94.3429) (xy 72.168606 -94.292948) (xy 72.25019 -94.249876) (xy 72.335187 -94.214007)
			(xy 72.422963 -94.185608) (xy 72.512863 -94.164891) (xy 72.604215 -94.15201) (xy 72.696338 -94.147062)
			(xy 72.788544 -94.150083) (xy 72.880145 -94.161052) (xy 72.970458 -94.179885) (xy 73.058808 -94.206443)
			(xy 73.144537 -94.240528) (xy 73.227004 -94.281884) (xy 73.266554 -94.305628) (xy 73.278238 -94.312994)
			(xy 73.305924 -94.313502) (xy 73.395332 -94.263464) (xy 73.402987 -94.25875) (xy 73.414666 -94.245102)
			(xy 73.420886 -94.22825) (xy 73.42124 -94.219268) (xy 73.42124 -91.064588) (xy 73.42166 -91.031706)
			(xy 73.42903 -90.966357) (xy 73.443674 -90.902245) (xy 73.465409 -90.840177) (xy 73.49396 -90.780935)
			(xy 73.52897 -90.725265) (xy 73.569995 -90.673867) (xy 73.592944 -90.650314) (xy 76.281534 -87.961724)
			(xy 76.305126 -87.938822) (xy 76.356535 -87.897826) (xy 76.412206 -87.862838) (xy 76.471442 -87.834296)
			(xy 76.533498 -87.812559) (xy 76.597596 -87.7979) (xy 76.662932 -87.790501) (xy 76.695808 -87.79002)
			(xy 80.281018 -87.79002) (xy 80.316669 -87.790518) (xy 80.387442 -87.799186) (xy 80.456639 -87.816381)
			(xy 80.523238 -87.841846) (xy 80.586254 -87.875207) (xy 80.644755 -87.91597) (xy 80.697876 -87.963531)
			(xy 80.744831 -88.017189) (xy 80.784927 -88.076149) (xy 80.81757 -88.139539) (xy 80.83042 -88.172798)
			(xy 80.834992 -88.18499) (xy 80.85455 -88.201754) (xy 80.950816 -88.22309) (xy 80.963457 -88.225092)
			(xy 80.987984 -88.217878) (xy 80.997552 -88.209374) (xy 81.22539 -87.981536) (xy 81.248959 -87.958609)
			(xy 81.300371 -87.917615) (xy 81.356047 -87.882629) (xy 81.415287 -87.854091) (xy 81.477347 -87.832358)
			(xy 81.541448 -87.817703) (xy 81.606787 -87.81031) (xy 81.639664 -87.809832) (xy 81.67507 -87.810423)
			(xy 81.745366 -87.818957) (xy 81.81412 -87.835903) (xy 81.88033 -87.861016) (xy 81.943029 -87.893928)
			(xy 82.001302 -87.93416) (xy 82.054299 -87.981124) (xy 82.101247 -88.034135) (xy 82.141462 -88.09242)
			(xy 82.174355 -88.155129) (xy 82.199448 -88.221346) (xy 82.216375 -88.290105) (xy 82.224887 -88.360404)
			(xy 82.225388 -88.39581) (xy 82.224969 -88.428683) (xy 82.217619 -88.494016) (xy 82.203002 -88.558115)
			(xy 82.181301 -88.620175) (xy 82.15279 -88.679417) (xy 82.117826 -88.735094) (xy 82.076849 -88.786507)
			(xy 82.053938 -88.810084) (xy 81.566766 -89.297256) (xy 81.54317 -89.320155) (xy 81.491763 -89.361151)
			(xy 81.436092 -89.39614) (xy 81.376857 -89.424682) (xy 81.314801 -89.44642) (xy 81.250704 -89.46108)
			(xy 81.185368 -89.468479) (xy 81.152492 -89.46896) (xy 81.037176 -89.46896) (xy 81.02856 -89.469284)
			(xy 81.012288 -89.474941) (xy 80.998835 -89.485702) (xy 80.993996 -89.492836) (xy 80.941418 -89.577164)
			(xy 80.939894 -89.602818) (xy 80.945736 -89.614756) (xy 80.957836 -89.640848) (xy 80.974931 -89.695763)
			(xy 80.98357 -89.752623) (xy 80.98409 -89.78138) (xy 80.983637 -89.806797) (xy 80.97689 -89.857181)
			(xy 80.963512 -89.906223) (xy 80.943741 -89.953054) (xy 80.917926 -89.996845) (xy 80.902556 -90.017092)
			(xy 80.902302 -90.017346) (xy 80.897279 -90.024457) (xy 80.891819 -90.040973) (xy 80.892186 -90.058363)
			(xy 80.894936 -90.066622) (xy 80.926178 -90.148156) (xy 80.929587 -90.156201) (xy 80.940885 -90.169514)
			(xy 80.956007 -90.178243) (xy 80.964532 -90.18016) (xy 80.964786 -90.18016) (xy 80.99097 -90.18522)
			(xy 81.041709 -90.201631) (xy 81.089668 -90.22495) (xy 81.133911 -90.254723) (xy 81.173575 -90.290368)
			(xy 81.207888 -90.331191) (xy 81.236179 -90.376396) (xy 81.257897 -90.425101) (xy 81.272619 -90.476356)
			(xy 81.280058 -90.529162) (xy 81.280508 -90.555826) (xy 81.280046 -90.583078) (xy 81.272286 -90.637026)
			(xy 81.256928 -90.689322) (xy 81.234284 -90.738899) (xy 81.204815 -90.784749) (xy 81.169121 -90.825939)
			(xy 81.127928 -90.86163) (xy 81.082076 -90.891096) (xy 81.032497 -90.913737) (xy 80.980201 -90.929092)
			(xy 80.926252 -90.936848) (xy 80.899 -90.937334) (xy 80.869194 -90.936769) (xy 80.81031 -90.927478)
			(xy 80.75359 -90.909137) (xy 80.700414 -90.882195) (xy 80.652078 -90.847306) (xy 80.609759 -90.805321)
			(xy 80.59166 -90.781632) (xy 80.59166 -90.781378) (xy 80.586379 -90.774786) (xy 80.572446 -90.765254)
			(xy 80.556161 -90.760808) (xy 80.547718 -90.761058) (xy 80.44942 -90.767154) (xy 80.427576 -90.78087)
			(xy 80.421226 -90.792046) (xy 80.406632 -90.816935) (xy 80.371059 -90.86236) (xy 80.329055 -90.901915)
			(xy 80.281578 -90.934698) (xy 80.229708 -90.959964) (xy 80.174626 -90.977136) (xy 80.117588 -90.985825)
			(xy 80.08874 -90.986356) (xy 80.060293 -90.985868) (xy 80.004031 -90.977405) (xy 79.949652 -90.960676)
			(xy 79.898362 -90.936053) (xy 79.8513 -90.904082) (xy 79.809511 -90.865473) (xy 79.791306 -90.843608)
			(xy 79.783641 -90.834926) (xy 79.762746 -90.824998) (xy 79.751174 -90.824558) (xy 79.659226 -90.825574)
			(xy 79.638398 -90.836242) (xy 79.631286 -90.84564) (xy 79.613109 -90.868485) (xy 79.57097 -90.908886)
			(xy 79.523169 -90.942399) (xy 79.470823 -90.968241) (xy 79.415151 -90.985809) (xy 79.357453 -90.994694)
			(xy 79.328264 -90.995246) (xy 79.299668 -90.994733) (xy 79.243117 -90.986204) (xy 79.188472 -90.969328)
			(xy 79.13696 -90.944483) (xy 79.089734 -90.912226) (xy 79.047853 -90.87328) (xy 79.012256 -90.828517)
			(xy 78.997556 -90.803984) (xy 78.990444 -90.791538) (xy 78.96606 -90.778076) (xy 78.847696 -90.782648)
			(xy 78.824074 -90.798142) (xy 78.817978 -90.810842) (xy 78.805968 -90.834838) (xy 78.776268 -90.879527)
			(xy 78.740599 -90.919614) (xy 78.699664 -90.954306) (xy 78.654271 -90.982919) (xy 78.605316 -91.004888)
			(xy 78.553766 -91.01978) (xy 78.500637 -91.027301) (xy 78.473808 -91.027758) (xy 78.446558 -91.027195)
			(xy 78.392614 -91.01944) (xy 78.340322 -91.004087) (xy 78.290747 -90.981448) (xy 78.244899 -90.951984)
			(xy 78.203711 -90.916295) (xy 78.168021 -90.875108) (xy 78.138556 -90.82926) (xy 78.115916 -90.779686)
			(xy 78.100561 -90.727394) (xy 78.092805 -90.67345) (xy 78.092805 -90.61895) (xy 78.100561 -90.565006)
			(xy 78.115916 -90.512714) (xy 78.138556 -90.46314) (xy 78.168021 -90.417292) (xy 78.203711 -90.376105)
			(xy 78.244899 -90.340416) (xy 78.290747 -90.310952) (xy 78.340322 -90.288313) (xy 78.392614 -90.27296)
			(xy 78.446558 -90.265205) (xy 78.473808 -90.264742) (xy 78.502403 -90.265284) (xy 78.558952 -90.273808)
			(xy 78.613596 -90.29068) (xy 78.665108 -90.31552) (xy 78.712334 -90.347773) (xy 78.754216 -90.386715)
			(xy 78.789815 -90.431473) (xy 78.804516 -90.456004) (xy 78.811628 -90.46845) (xy 78.836012 -90.481912)
			(xy 78.954376 -90.47734) (xy 78.977998 -90.461846) (xy 78.984094 -90.449146) (xy 78.99612 -90.425159)
			(xy 79.025818 -90.38047) (xy 79.061486 -90.340385) (xy 79.102419 -90.305692) (xy 79.147809 -90.277078)
			(xy 79.196761 -90.255107) (xy 79.248309 -90.240213) (xy 79.301436 -90.232689) (xy 79.328264 -90.23223)
			(xy 79.356708 -90.232791) (xy 79.412966 -90.24124) (xy 79.467344 -90.257954) (xy 79.518634 -90.282563)
			(xy 79.565698 -90.314521) (xy 79.607491 -90.353118) (xy 79.625698 -90.374978) (xy 79.633364 -90.383659)
			(xy 79.654258 -90.393588) (xy 79.66583 -90.394028) (xy 79.757778 -90.393012) (xy 79.778606 -90.382344)
			(xy 79.785718 -90.372946) (xy 79.803889 -90.350096) (xy 79.84603 -90.309696) (xy 79.893832 -90.276184)
			(xy 79.94618 -90.250343) (xy 80.001852 -90.232776) (xy 80.059551 -90.223892) (xy 80.08874 -90.22334)
			(xy 80.118546 -90.223887) (xy 80.17743 -90.233183) (xy 80.234151 -90.251528) (xy 80.287327 -90.278474)
			(xy 80.335662 -90.313366) (xy 80.377981 -90.355353) (xy 80.39608 -90.379042) (xy 80.39608 -90.379296)
			(xy 80.401344 -90.385904) (xy 80.415284 -90.395435) (xy 80.431577 -90.399872) (xy 80.440022 -90.399616)
			(xy 80.53832 -90.39352) (xy 80.560164 -90.379804) (xy 80.566514 -90.368628) (xy 80.573821 -90.355969)
			(xy 80.590095 -90.331685) (xy 80.599026 -90.320114) (xy 80.59928 -90.31986) (xy 80.604302 -90.31275)
			(xy 80.609756 -90.296233) (xy 80.609391 -90.278843) (xy 80.606646 -90.270584) (xy 80.575404 -90.18905)
			(xy 80.572004 -90.181) (xy 80.560703 -90.167687) (xy 80.545577 -90.158961) (xy 80.53705 -90.157046)
			(xy 80.536796 -90.157046) (xy 80.510611 -90.151994) (xy 80.459872 -90.135581) (xy 80.411913 -90.11226)
			(xy 80.367671 -90.082486) (xy 80.328007 -90.04684) (xy 80.293695 -90.006016) (xy 80.265404 -89.960811)
			(xy 80.243686 -89.912106) (xy 80.228964 -89.86085) (xy 80.221525 -89.808044) (xy 80.221074 -89.78138)
			(xy 80.221625 -89.752626) (xy 80.230274 -89.695771) (xy 80.247343 -89.640853) (xy 80.259428 -89.614756)
			(xy 80.26527 -89.602818) (xy 80.263746 -89.577164) (xy 80.211168 -89.492836) (xy 80.2063 -89.48573)
			(xy 80.192838 -89.475001) (xy 80.176594 -89.469304) (xy 80.167988 -89.46896) (xy 77.424788 -89.46896)
			(xy 77.414716 -89.469363) (xy 77.396117 -89.477098) (xy 77.38872 -89.483946) (xy 75.295506 -91.57716)
			(xy 75.288692 -91.58458) (xy 75.280957 -91.603164) (xy 75.28052 -91.613228) (xy 75.28052 -95.989648)
			(xy 75.563982 -95.989648) (xy 75.568053 -95.934026) (xy 75.580179 -95.879589) (xy 75.600102 -95.827498)
			(xy 75.627398 -95.778863) (xy 75.661484 -95.73472) (xy 75.701633 -95.696011) (xy 75.746991 -95.66356)
			(xy 75.796591 -95.638059) (xy 75.849375 -95.620052) (xy 75.904218 -95.609922) (xy 75.959952 -95.607885)
			(xy 76.015389 -95.613985) (xy 76.069346 -95.628091) (xy 76.120675 -95.649903) (xy 76.168281 -95.678957)
			(xy 76.211149 -95.714632) (xy 76.248366 -95.756169) (xy 76.279139 -95.802682) (xy 76.302811 -95.853179)
			(xy 76.318879 -95.906586) (xy 76.326999 -95.961762) (xy 76.327508 -95.989648) (xy 76.326999 -96.017534)
			(xy 76.318879 -96.07271) (xy 76.302811 -96.126117) (xy 76.279139 -96.176614) (xy 76.248366 -96.223127)
			(xy 76.211149 -96.264664) (xy 76.168281 -96.300339) (xy 76.120675 -96.329393) (xy 76.069346 -96.351205)
			(xy 76.015389 -96.365311) (xy 75.959952 -96.371411) (xy 75.904218 -96.369374) (xy 75.849375 -96.359244)
			(xy 75.796591 -96.341237) (xy 75.746991 -96.315736) (xy 75.701633 -96.283285) (xy 75.661484 -96.244576)
			(xy 75.627398 -96.200433) (xy 75.600102 -96.151798) (xy 75.580179 -96.099707) (xy 75.568053 -96.04527)
			(xy 75.563982 -95.989648) (xy 75.28052 -95.989648) (xy 75.28052 -96.264984) (xy 75.279907 -96.301735)
			(xy 75.270672 -96.374654) (xy 75.252382 -96.445844) (xy 75.225325 -96.514185) (xy 75.20813 -96.54667)
			(xy 75.207876 -96.546924) (xy 75.203338 -96.55644) (xy 75.201642 -96.577435) (xy 75.204574 -96.587564)
			(xy 75.229212 -96.658938) (xy 75.233125 -96.66891) (xy 75.247734 -96.684556) (xy 75.257406 -96.689164)
			(xy 75.282813 -96.700554) (xy 75.330298 -96.729626) (xy 75.373051 -96.765293) (xy 75.410163 -96.806799)
			(xy 75.440845 -96.853259) (xy 75.464444 -96.903688) (xy 75.48046 -96.957013) (xy 75.488551 -97.012099)
			(xy 75.489054 -97.039938) (xy 75.488558 -97.067188) (xy 75.480797 -97.121133) (xy 75.46544 -97.173425)
			(xy 75.442797 -97.222999) (xy 75.413331 -97.268847) (xy 75.377641 -97.310036) (xy 75.336453 -97.345727)
			(xy 75.290606 -97.375194) (xy 75.241032 -97.397837) (xy 75.188741 -97.413195) (xy 75.134796 -97.420957)
			(xy 75.107546 -97.421446) (xy 75.081147 -97.420985) (xy 75.028855 -97.413685) (xy 74.978068 -97.399247)
			(xy 74.929757 -97.377946) (xy 74.884843 -97.350189) (xy 74.844184 -97.316506) (xy 74.808556 -97.277539)
			(xy 74.77864 -97.234033) (xy 74.766424 -97.210626) (xy 74.760435 -97.200206) (xy 74.74108 -97.186019)
			(xy 74.72934 -97.183448) (xy 74.647806 -97.169986) (xy 74.635804 -97.168773) (xy 74.612885 -97.1762)
			(xy 74.603864 -97.18421) (xy 74.56551 -97.222564) (xy 74.558712 -97.230052) (xy 74.551114 -97.248778)
			(xy 74.550778 -97.258886) (xy 74.551032 -97.331022) (xy 74.551534 -97.341052) (xy 74.559395 -97.359517)
			(xy 74.566272 -97.366836) (xy 74.566526 -97.36709) (xy 74.584406 -97.385092) (xy 74.615701 -97.42503)
			(xy 74.641425 -97.468764) (xy 74.661125 -97.515522) (xy 74.674453 -97.564479) (xy 74.681174 -97.614771)
			(xy 74.681588 -97.64014) (xy 74.681159 -97.667393) (xy 74.673397 -97.721344) (xy 74.658036 -97.773641)
			(xy 74.635388 -97.82322) (xy 74.605916 -97.869071) (xy 74.570219 -97.910261) (xy 74.529023 -97.945952)
			(xy 74.483167 -97.975417) (xy 74.433585 -97.998057) (xy 74.381285 -98.01341) (xy 74.327333 -98.021164)
			(xy 74.30008 -98.021648) (xy 74.27471 -98.021264) (xy 74.224419 -98.014535) (xy 74.175463 -98.001199)
			(xy 74.128707 -97.981491) (xy 74.084977 -97.955758) (xy 74.045044 -97.924455) (xy 74.02703 -97.906586)
			(xy 74.026776 -97.906332) (xy 74.019405 -97.899532) (xy 74.000973 -97.891686) (xy 73.990962 -97.891092)
			(xy 73.918826 -97.890838) (xy 73.908716 -97.891173) (xy 73.889984 -97.898761) (xy 73.882504 -97.90557)
			(xy 73.6169 -98.171) (xy 75.563982 -98.171) (xy 75.568053 -98.115378) (xy 75.580179 -98.060941) (xy 75.600102 -98.00885)
			(xy 75.627398 -97.960215) (xy 75.661484 -97.916072) (xy 75.701633 -97.877363) (xy 75.746991 -97.844912)
			(xy 75.796591 -97.819411) (xy 75.849375 -97.801404) (xy 75.904218 -97.791274) (xy 75.959952 -97.789237)
			(xy 76.015389 -97.795337) (xy 76.069346 -97.809443) (xy 76.120675 -97.831255) (xy 76.168281 -97.860309)
			(xy 76.211149 -97.895984) (xy 76.248366 -97.937521) (xy 76.279139 -97.984034) (xy 76.302811 -98.034531)
			(xy 76.318879 -98.087938) (xy 76.326999 -98.143114) (xy 76.327508 -98.171) (xy 76.326999 -98.198886)
			(xy 76.318879 -98.254062) (xy 76.302811 -98.307469) (xy 76.279139 -98.357966) (xy 76.248366 -98.404479)
			(xy 76.211149 -98.446016) (xy 76.168281 -98.481691) (xy 76.120675 -98.510745) (xy 76.069346 -98.532557)
			(xy 76.015389 -98.546663) (xy 75.959952 -98.552763) (xy 75.904218 -98.550726) (xy 75.849375 -98.540596)
			(xy 75.796591 -98.522589) (xy 75.746991 -98.497088) (xy 75.701633 -98.464637) (xy 75.661484 -98.425928)
			(xy 75.627398 -98.381785) (xy 75.600102 -98.33315) (xy 75.580179 -98.281059) (xy 75.568053 -98.226622)
			(xy 75.563982 -98.171) (xy 73.6169 -98.171) (xy 73.494646 -98.293174) (xy 73.487831 -98.300594) (xy 73.480095 -98.319178)
			(xy 73.47966 -98.329242) (xy 73.47966 -99.439984) (xy 75.309982 -99.439984) (xy 75.314053 -99.384362)
			(xy 75.326179 -99.329925) (xy 75.346102 -99.277834) (xy 75.373398 -99.229199) (xy 75.407484 -99.185056)
			(xy 75.447633 -99.146347) (xy 75.492991 -99.113896) (xy 75.542591 -99.088395) (xy 75.595375 -99.070388)
			(xy 75.650218 -99.060258) (xy 75.705952 -99.058221) (xy 75.761389 -99.064321) (xy 75.815346 -99.078427)
			(xy 75.866675 -99.100239) (xy 75.914281 -99.129293) (xy 75.957149 -99.164968) (xy 75.994366 -99.206505)
			(xy 76.025139 -99.253018) (xy 76.048811 -99.303515) (xy 76.064879 -99.356922) (xy 76.072999 -99.412098)
			(xy 76.073508 -99.439984) (xy 76.072999 -99.46787) (xy 76.064879 -99.523046) (xy 76.048811 -99.576453)
			(xy 76.025139 -99.62695) (xy 75.994366 -99.673463) (xy 75.957149 -99.715) (xy 75.914281 -99.750675)
			(xy 75.866675 -99.779729) (xy 75.815346 -99.801541) (xy 75.761389 -99.815647) (xy 75.705952 -99.821747)
			(xy 75.650218 -99.81971) (xy 75.595375 -99.80958) (xy 75.542591 -99.791573) (xy 75.492991 -99.766072)
			(xy 75.447633 -99.733621) (xy 75.407484 -99.694912) (xy 75.373398 -99.650769) (xy 75.346102 -99.602134)
			(xy 75.326179 -99.550043) (xy 75.314053 -99.495606) (xy 75.309982 -99.439984) (xy 73.47966 -99.439984)
			(xy 73.47966 -100.039932) (xy 73.876914 -100.039932) (xy 73.880985 -99.98431) (xy 73.893111 -99.929873)
			(xy 73.913034 -99.877782) (xy 73.94033 -99.829147) (xy 73.974416 -99.785004) (xy 74.014565 -99.746295)
			(xy 74.059923 -99.713844) (xy 74.109523 -99.688343) (xy 74.162307 -99.670336) (xy 74.21715 -99.660206)
			(xy 74.272884 -99.658169) (xy 74.328321 -99.664269) (xy 74.382278 -99.678375) (xy 74.433607 -99.700187)
			(xy 74.481213 -99.729241) (xy 74.524081 -99.764916) (xy 74.561298 -99.806453) (xy 74.592071 -99.852966)
			(xy 74.615743 -99.903463) (xy 74.631811 -99.95687) (xy 74.639931 -100.012046) (xy 74.64044 -100.039932)
			(xy 74.639931 -100.067818) (xy 74.631811 -100.122994) (xy 74.615743 -100.176401) (xy 74.592071 -100.226898)
			(xy 74.561298 -100.273411) (xy 74.524081 -100.314948) (xy 74.481213 -100.350623) (xy 74.433607 -100.379677)
			(xy 74.382278 -100.401489) (xy 74.328321 -100.415595) (xy 74.272884 -100.421695) (xy 74.21715 -100.419658)
			(xy 74.162307 -100.409528) (xy 74.109523 -100.391521) (xy 74.059923 -100.36602) (xy 74.014565 -100.333569)
			(xy 73.974416 -100.29486) (xy 73.94033 -100.250717) (xy 73.913034 -100.202082) (xy 73.893111 -100.149991)
			(xy 73.880985 -100.095554) (xy 73.876914 -100.039932) (xy 73.47966 -100.039932) (xy 73.47966 -101.240082)
			(xy 74.293982 -101.240082) (xy 74.298053 -101.18446) (xy 74.310179 -101.130023) (xy 74.330102 -101.077932)
			(xy 74.357398 -101.029297) (xy 74.391484 -100.985154) (xy 74.431633 -100.946445) (xy 74.476991 -100.913994)
			(xy 74.526591 -100.888493) (xy 74.579375 -100.870486) (xy 74.634218 -100.860356) (xy 74.689952 -100.858319)
			(xy 74.745389 -100.864419) (xy 74.799346 -100.878525) (xy 74.850675 -100.900337) (xy 74.898281 -100.929391)
			(xy 74.941149 -100.965066) (xy 74.978366 -101.006603) (xy 75.009139 -101.053116) (xy 75.016889 -101.069648)
			(xy 75.586334 -101.069648) (xy 75.590405 -101.014026) (xy 75.602531 -100.959589) (xy 75.622454 -100.907498)
			(xy 75.64975 -100.858863) (xy 75.683836 -100.81472) (xy 75.723985 -100.776011) (xy 75.769343 -100.74356)
			(xy 75.818943 -100.718059) (xy 75.871727 -100.700052) (xy 75.92657 -100.689922) (xy 75.982304 -100.687885)
			(xy 76.037741 -100.693985) (xy 76.091698 -100.708091) (xy 76.143027 -100.729903) (xy 76.190633 -100.758957)
			(xy 76.233501 -100.794632) (xy 76.270718 -100.836169) (xy 76.301491 -100.882682) (xy 76.325163 -100.933179)
			(xy 76.341231 -100.986586) (xy 76.349351 -101.041762) (xy 76.34986 -101.069648) (xy 76.349351 -101.097534)
			(xy 76.341231 -101.15271) (xy 76.325163 -101.206117) (xy 76.301491 -101.256614) (xy 76.270718 -101.303127)
			(xy 76.233501 -101.344664) (xy 76.190633 -101.380339) (xy 76.143027 -101.409393) (xy 76.091698 -101.431205)
			(xy 76.037741 -101.445311) (xy 75.982304 -101.451411) (xy 75.92657 -101.449374) (xy 75.871727 -101.439244)
			(xy 75.818943 -101.421237) (xy 75.769343 -101.395736) (xy 75.723985 -101.363285) (xy 75.683836 -101.324576)
			(xy 75.64975 -101.280433) (xy 75.622454 -101.231798) (xy 75.602531 -101.179707) (xy 75.590405 -101.12527)
			(xy 75.586334 -101.069648) (xy 75.016889 -101.069648) (xy 75.032811 -101.103613) (xy 75.048879 -101.15702)
			(xy 75.056999 -101.212196) (xy 75.057508 -101.240082) (xy 75.056999 -101.267968) (xy 75.048879 -101.323144)
			(xy 75.032811 -101.376551) (xy 75.009139 -101.427048) (xy 74.978366 -101.473561) (xy 74.941149 -101.515098)
			(xy 74.898281 -101.550773) (xy 74.850675 -101.579827) (xy 74.799346 -101.601639) (xy 74.745389 -101.615745)
			(xy 74.689952 -101.621845) (xy 74.634218 -101.619808) (xy 74.579375 -101.609678) (xy 74.526591 -101.591671)
			(xy 74.476991 -101.56617) (xy 74.431633 -101.533719) (xy 74.391484 -101.49501) (xy 74.357398 -101.450867)
			(xy 74.330102 -101.402232) (xy 74.310179 -101.350141) (xy 74.298053 -101.295704) (xy 74.293982 -101.240082)
			(xy 73.47966 -101.240082) (xy 73.47966 -102.489) (xy 74.801982 -102.489) (xy 74.806053 -102.433378)
			(xy 74.818179 -102.378941) (xy 74.838102 -102.32685) (xy 74.865398 -102.278215) (xy 74.899484 -102.234072)
			(xy 74.939633 -102.195363) (xy 74.984991 -102.162912) (xy 75.034591 -102.137411) (xy 75.087375 -102.119404)
			(xy 75.142218 -102.109274) (xy 75.197952 -102.107237) (xy 75.253389 -102.113337) (xy 75.307346 -102.127443)
			(xy 75.358675 -102.149255) (xy 75.406281 -102.178309) (xy 75.449149 -102.213984) (xy 75.486366 -102.255521)
			(xy 75.517139 -102.302034) (xy 75.540811 -102.352531) (xy 75.556879 -102.405938) (xy 75.564999 -102.461114)
			(xy 75.565508 -102.489) (xy 75.564999 -102.516886) (xy 75.556879 -102.572062) (xy 75.540811 -102.625469)
			(xy 75.517139 -102.675966) (xy 75.486366 -102.722479) (xy 75.449149 -102.764016) (xy 75.406281 -102.799691)
			(xy 75.358675 -102.828745) (xy 75.307346 -102.850557) (xy 75.253389 -102.864663) (xy 75.197952 -102.870763)
			(xy 75.142218 -102.868726) (xy 75.087375 -102.858596) (xy 75.034591 -102.840589) (xy 74.984991 -102.815088)
			(xy 74.939633 -102.782637) (xy 74.899484 -102.743928) (xy 74.865398 -102.699785) (xy 74.838102 -102.65115)
			(xy 74.818179 -102.599059) (xy 74.806053 -102.544622) (xy 74.801982 -102.489) (xy 73.47966 -102.489)
			(xy 73.47966 -103.886) (xy 75.309982 -103.886) (xy 75.314053 -103.830378) (xy 75.326179 -103.775941)
			(xy 75.346102 -103.72385) (xy 75.373398 -103.675215) (xy 75.407484 -103.631072) (xy 75.447633 -103.592363)
			(xy 75.492991 -103.559912) (xy 75.542591 -103.534411) (xy 75.595375 -103.516404) (xy 75.650218 -103.506274)
			(xy 75.705952 -103.504237) (xy 75.761389 -103.510337) (xy 75.815346 -103.524443) (xy 75.866675 -103.546255)
			(xy 75.914281 -103.575309) (xy 75.957149 -103.610984) (xy 75.994366 -103.652521) (xy 76.025139 -103.699034)
			(xy 76.048811 -103.749531) (xy 76.064879 -103.802938) (xy 76.072999 -103.858114) (xy 76.073508 -103.886)
			(xy 76.072999 -103.913886) (xy 76.064879 -103.969062) (xy 76.048811 -104.022469) (xy 76.025139 -104.072966)
			(xy 75.994366 -104.119479) (xy 75.957149 -104.161016) (xy 75.914281 -104.196691) (xy 75.866675 -104.225745)
			(xy 75.815346 -104.247557) (xy 75.761389 -104.261663) (xy 75.705952 -104.267763) (xy 75.650218 -104.265726)
			(xy 75.595375 -104.255596) (xy 75.542591 -104.237589) (xy 75.492991 -104.212088) (xy 75.447633 -104.179637)
			(xy 75.407484 -104.140928) (xy 75.373398 -104.096785) (xy 75.346102 -104.04815) (xy 75.326179 -103.996059)
			(xy 75.314053 -103.941622) (xy 75.309982 -103.886) (xy 73.47966 -103.886) (xy 73.47966 -104.356154)
			(xy 73.480093 -104.366223) (xy 73.487807 -104.384822) (xy 73.494646 -104.392222) (xy 74.118216 -105.015538)
			(xy 74.141109 -105.039139) (xy 74.182107 -105.090545) (xy 74.217098 -105.146214) (xy 74.245641 -105.205448)
			(xy 74.26738 -105.267503) (xy 74.28204 -105.331601) (xy 74.289439 -105.396936) (xy 74.28992 -105.429812)
			(xy 74.28992 -108.929932) (xy 74.314812 -108.95838) (xy 74.333862 -108.96092) (xy 74.360058 -108.964867)
			(xy 74.411086 -108.979105) (xy 74.459652 -109.000267) (xy 74.504822 -109.027948) (xy 74.545726 -109.061614)
			(xy 74.563986 -109.080808) (xy 74.57151 -109.088206) (xy 74.590788 -109.096732) (xy 74.601324 -109.097318)
			(xy 74.676 -109.097318) (xy 74.686551 -109.096797) (xy 74.705845 -109.088256) (xy 74.713338 -109.080808)
			(xy 74.731484 -109.061743) (xy 74.772115 -109.028286) (xy 74.816958 -109.000728) (xy 74.86516 -108.979591)
			(xy 74.91581 -108.965276) (xy 74.967945 -108.958055) (xy 74.994262 -108.957618) (xy 75.021515 -108.958091)
			(xy 75.075467 -108.965843) (xy 75.127766 -108.981196) (xy 75.177348 -109.003836) (xy 75.223203 -109.033302)
			(xy 75.264396 -109.068995) (xy 75.300091 -109.110188) (xy 75.329559 -109.156041) (xy 75.3522 -109.205622)
			(xy 75.367554 -109.257921) (xy 75.375308 -109.311873) (xy 75.37577 -109.339126) (xy 75.375243 -109.367865)
			(xy 75.366619 -109.424691) (xy 75.349568 -109.479581) (xy 75.324478 -109.531293) (xy 75.291915 -109.578656)
			(xy 75.272646 -109.599984) (xy 75.266042 -109.606842) (xy 75.25893 -109.624876) (xy 75.25893 -109.713776)
			(xy 75.266042 -109.73181) (xy 75.272646 -109.738668) (xy 75.291944 -109.759972) (xy 75.324511 -109.807337)
			(xy 75.349603 -109.859053) (xy 75.366653 -109.913947) (xy 75.375273 -109.970778) (xy 75.375271 -110.02826)
			(xy 75.366644 -110.08509) (xy 75.349589 -110.139983) (xy 75.324492 -110.191696) (xy 75.29192 -110.239058)
			(xy 75.272646 -110.260384) (xy 75.266042 -110.267242) (xy 75.25893 -110.285276) (xy 75.25893 -110.374176)
			(xy 75.266042 -110.39221) (xy 75.272646 -110.399068) (xy 75.291944 -110.420372) (xy 75.324511 -110.467737)
			(xy 75.349603 -110.519453) (xy 75.366653 -110.574347) (xy 75.375273 -110.631178) (xy 75.375271 -110.68866)
			(xy 75.366644 -110.74549) (xy 75.349589 -110.800383) (xy 75.324492 -110.852096) (xy 75.29192 -110.899458)
			(xy 75.272646 -110.920784) (xy 75.266042 -110.927642) (xy 75.25893 -110.945676) (xy 75.25893 -111.034576)
			(xy 75.266042 -111.05261) (xy 75.272646 -111.059468) (xy 75.291944 -111.080772) (xy 75.324511 -111.128137)
			(xy 75.349603 -111.179853) (xy 75.366653 -111.234747) (xy 75.375273 -111.291578) (xy 75.375271 -111.34906)
			(xy 75.366644 -111.40589) (xy 75.349589 -111.460783) (xy 75.324492 -111.512496) (xy 75.29192 -111.559858)
			(xy 75.272646 -111.581184) (xy 75.266042 -111.588042) (xy 75.25893 -111.606076) (xy 75.25893 -111.694976)
			(xy 75.266042 -111.71301) (xy 75.272646 -111.719868) (xy 75.291926 -111.741187) (xy 75.324492 -111.788551)
			(xy 75.349583 -111.840264) (xy 75.366631 -111.895157) (xy 75.375251 -111.951986) (xy 75.37577 -111.980726)
			(xy 75.375369 -112.007981) (xy 75.367608 -112.061936) (xy 75.352246 -112.114238) (xy 75.329598 -112.163821)
			(xy 75.300124 -112.209676) (xy 75.264424 -112.250869) (xy 75.223224 -112.286562) (xy 75.177364 -112.316029)
			(xy 75.127778 -112.338669) (xy 75.075474 -112.354021) (xy 75.021517 -112.361774) (xy 74.994262 -112.362234)
			(xy 74.967948 -112.361781) (xy 74.915819 -112.354542) (xy 74.865176 -112.340219) (xy 74.816978 -112.319084)
			(xy 74.772135 -112.291536) (xy 74.731495 -112.258096) (xy 74.713338 -112.239044) (xy 74.705798 -112.231664)
			(xy 74.686532 -112.223126) (xy 74.676 -112.222534) (xy 74.601324 -112.222534) (xy 74.590773 -112.223052)
			(xy 74.571477 -112.231594) (xy 74.563986 -112.239044) (xy 74.545839 -112.258108) (xy 74.505206 -112.291562)
			(xy 74.460364 -112.319119) (xy 74.412162 -112.340256) (xy 74.361513 -112.354572) (xy 74.309378 -112.361796)
			(xy 74.283062 -112.362234) (xy 74.282046 -112.362234) (xy 74.272365 -112.362652) (xy 74.254373 -112.369811)
			(xy 74.24029 -112.383101) (xy 74.235818 -112.391698) (xy 74.220938 -112.422781) (xy 74.184911 -112.481529)
			(xy 74.142232 -112.53564) (xy 74.118216 -112.560354) (xy 72.703436 -113.975134) (xy 72.679901 -113.998065)
			(xy 72.62852 -114.03903) (xy 72.572876 -114.073984) (xy 72.513667 -114.102488) (xy 72.451639 -114.124183)
			(xy 72.387573 -114.138797) (xy 72.322272 -114.146145) (xy 72.289416 -114.146584) (xy 71.795894 -114.146584)
			(xy 71.785821 -114.146984) (xy 71.767223 -114.15472) (xy 71.759826 -114.16157) (xy 71.590154 -114.331496)
			(xy 71.566571 -114.354408) (xy 71.51516 -114.395402) (xy 71.459487 -114.430389) (xy 71.40025 -114.458929)
			(xy 71.338192 -114.480664) (xy 71.274093 -114.495322) (xy 71.208757 -114.502719) (xy 71.17588 -114.5032)
			(xy 71.14047 -114.502729) (xy 71.070167 -114.494188) (xy 71.001407 -114.477233) (xy 70.935193 -114.452111)
			(xy 70.872491 -114.419188) (xy 70.814216 -114.378946) (xy 70.761217 -114.331972) (xy 70.71427 -114.27895)
			(xy 70.674057 -114.220654) (xy 70.641167 -114.157935) (xy 70.616079 -114.091708) (xy 70.599158 -114.022939)
			(xy 70.590653 -113.952632) (xy 70.590156 -113.917222) (xy 70.590612 -113.884351) (xy 70.597958 -113.81902)
			(xy 70.61257 -113.754921) (xy 70.634265 -113.692862) (xy 70.66277 -113.63362) (xy 70.697728 -113.577942)
			(xy 70.738698 -113.526527) (xy 70.761606 -113.502948) (xy 70.809612 -113.454942) (xy 70.816263 -113.447506)
			(xy 70.823858 -113.429083) (xy 70.823866 -113.409156) (xy 70.816286 -113.390728) (xy 70.809612 -113.383314)
			(xy 70.803262 -113.376964) (xy 70.787768 -113.369598) (xy 70.779132 -113.368836) (xy 70.751536 -113.365188)
			(xy 70.697727 -113.35095) (xy 70.646557 -113.329045) (xy 70.599112 -113.299937) (xy 70.556401 -113.264244)
			(xy 70.519329 -113.222724) (xy 70.488684 -113.176258) (xy 70.465115 -113.125833) (xy 70.449124 -113.072518)
			(xy 70.441048 -113.017445) (xy 70.44055 -112.989614) (xy 70.441091 -112.962365) (xy 70.448845 -112.908422)
			(xy 70.464196 -112.85613) (xy 70.486832 -112.806556) (xy 70.516293 -112.760708) (xy 70.551979 -112.719518)
			(xy 70.593163 -112.683827) (xy 70.639007 -112.654359) (xy 70.688578 -112.631715) (xy 70.740867 -112.616357)
			(xy 70.794809 -112.608595) (xy 70.822058 -112.608106) (xy 70.849036 -112.608627) (xy 70.902452 -112.616245)
			(xy 70.954263 -112.631306) (xy 71.003439 -112.653511) (xy 71.048999 -112.682417) (xy 71.090036 -112.717448)
			(xy 71.125734 -112.757908) (xy 71.15538 -112.80299) (xy 71.178385 -112.851796) (xy 71.19429 -112.903355)
			(xy 71.198994 -112.929924) (xy 71.200772 -112.941354) (xy 71.213218 -112.959896) (xy 71.300594 -113.011458)
			(xy 71.322946 -113.01349) (xy 71.333614 -113.00968) (xy 71.365442 -112.998739) (xy 71.430969 -112.983369)
			(xy 71.497827 -112.97562) (xy 71.53148 -112.975136) (xy 72.02551 -112.975136) (xy 72.035582 -112.974733)
			(xy 72.054181 -112.966999) (xy 72.061578 -112.96015) (xy 73.102978 -111.918496) (xy 73.109809 -111.911089)
			(xy 73.117535 -111.892495) (xy 73.117964 -111.882428) (xy 73.117964 -109.02188) (xy 73.100946 -108.99648)
			(xy 73.086722 -108.990638) (xy 73.077296 -108.987172) (xy 73.057225 -108.987227) (xy 73.038712 -108.994981)
			(xy 73.03135 -109.001814) (xy 72.83069 -109.202474) (xy 72.807127 -109.225374) (xy 72.75575 -109.266338)
			(xy 72.700109 -109.301292) (xy 72.640906 -109.329797) (xy 72.578883 -109.351495) (xy 72.51482 -109.366112)
			(xy 72.449524 -109.373465) (xy 72.41667 -109.373924) (xy 71.4375 -109.373924) (xy 71.42743 -109.374343)
			(xy 71.408832 -109.382068) (xy 71.401432 -109.38891) (xy 70.81012 -109.980476) (xy 70.803824 -109.987423)
			(xy 70.796267 -110.004561) (xy 70.79538 -110.02327) (xy 70.797928 -110.032292) (xy 70.830694 -110.132114)
			(xy 70.852538 -110.150656) (xy 70.867016 -110.152688) (xy 70.893823 -110.157152) (xy 70.945903 -110.172673)
			(xy 70.995254 -110.195424) (xy 71.040879 -110.224946) (xy 71.081855 -110.260641) (xy 71.117354 -110.301788)
			(xy 71.146656 -110.347554) (xy 71.16917 -110.397014) (xy 71.184441 -110.449168) (xy 71.192159 -110.50296)
			(xy 71.192644 -110.530132) (xy 71.192152 -110.557382) (xy 71.184392 -110.611328) (xy 71.169035 -110.66362)
			(xy 71.146393 -110.713195) (xy 71.116926 -110.759044) (xy 71.081236 -110.800233) (xy 71.040047 -110.835924)
			(xy 70.994199 -110.865391) (xy 70.944624 -110.888033) (xy 70.892332 -110.903391) (xy 70.838386 -110.911152)
			(xy 70.811136 -110.91164) (xy 70.783962 -110.911142) (xy 70.730161 -110.903447) (xy 70.677998 -110.888192)
			(xy 70.628528 -110.865688) (xy 70.582754 -110.836389) (xy 70.541602 -110.80089) (xy 70.505906 -110.759908)
			(xy 70.476389 -110.714274) (xy 70.453648 -110.664913) (xy 70.438144 -110.612823) (xy 70.433692 -110.586012)
			(xy 70.43166 -110.571534) (xy 70.413118 -110.54969) (xy 70.313296 -110.516924) (xy 70.304271 -110.514391)
			(xy 70.285564 -110.515276) (xy 70.268422 -110.522818) (xy 70.26148 -110.529116) (xy 69.497194 -111.293148)
			(xy 69.490383 -111.300571) (xy 69.482647 -111.319153) (xy 69.482208 -111.329216) (xy 69.482208 -111.884206)
			(xy 70.364348 -111.884206) (xy 70.368419 -111.828584) (xy 70.380545 -111.774147) (xy 70.400468 -111.722056)
			(xy 70.427764 -111.673421) (xy 70.46185 -111.629278) (xy 70.501999 -111.590569) (xy 70.547357 -111.558118)
			(xy 70.596957 -111.532617) (xy 70.649741 -111.51461) (xy 70.704584 -111.50448) (xy 70.760318 -111.502443)
			(xy 70.815755 -111.508543) (xy 70.869712 -111.522649) (xy 70.921041 -111.544461) (xy 70.968647 -111.573515)
			(xy 71.011515 -111.60919) (xy 71.048732 -111.650727) (xy 71.079505 -111.69724) (xy 71.103177 -111.747737)
			(xy 71.119245 -111.801144) (xy 71.127365 -111.85632) (xy 71.127874 -111.884206) (xy 71.127365 -111.912092)
			(xy 71.119245 -111.967268) (xy 71.103177 -112.020675) (xy 71.079505 -112.071172) (xy 71.048732 -112.117685)
			(xy 71.011515 -112.159222) (xy 70.968647 -112.194897) (xy 70.921041 -112.223951) (xy 70.869712 -112.245763)
			(xy 70.815755 -112.259869) (xy 70.760318 -112.265969) (xy 70.704584 -112.263932) (xy 70.649741 -112.253802)
			(xy 70.596957 -112.235795) (xy 70.547357 -112.210294) (xy 70.501999 -112.177843) (xy 70.46185 -112.139134)
			(xy 70.427764 -112.094991) (xy 70.400468 -112.046356) (xy 70.380545 -111.994265) (xy 70.368419 -111.939828)
			(xy 70.364348 -111.884206) (xy 69.482208 -111.884206) (xy 69.482208 -112.010444) (xy 69.48256 -112.019422)
			(xy 69.488811 -112.036259) (xy 69.500467 -112.049923) (xy 69.508116 -112.05464) (xy 69.598032 -112.104932)
			(xy 69.62521 -112.104424) (xy 69.637148 -112.097058) (xy 69.659778 -112.083619) (xy 69.707957 -112.062431)
			(xy 69.758597 -112.048084) (xy 69.81073 -112.040851) (xy 69.837046 -112.040416) (xy 69.864297 -112.040857)
			(xy 69.918243 -112.048619) (xy 69.970535 -112.063979) (xy 70.02011 -112.086625) (xy 70.065958 -112.116094)
			(xy 70.107145 -112.151788) (xy 70.142834 -112.192979) (xy 70.172298 -112.23883) (xy 70.194937 -112.288408)
			(xy 70.21029 -112.340702) (xy 70.218046 -112.394649) (xy 70.218046 -112.449151) (xy 70.21029 -112.503098)
			(xy 70.194937 -112.555392) (xy 70.172298 -112.60497) (xy 70.142834 -112.650821) (xy 70.107145 -112.692012)
			(xy 70.065958 -112.727706) (xy 70.02011 -112.757175) (xy 69.970535 -112.779821) (xy 69.918243 -112.795181)
			(xy 69.864297 -112.802943) (xy 69.837046 -112.803432) (xy 69.810734 -112.802965) (xy 69.758612 -112.795699)
			(xy 69.707979 -112.781353) (xy 69.659793 -112.760198) (xy 69.637148 -112.74679) (xy 69.629283 -112.742401)
			(xy 69.611637 -112.738862) (xy 69.593861 -112.74168) (xy 69.58584 -112.745774) (xy 69.508116 -112.789208)
			(xy 69.500439 -112.793891) (xy 69.488759 -112.807551) (xy 69.482551 -112.824417) (xy 69.482208 -112.833404)
			(xy 69.482208 -113.014252) (xy 69.482544 -113.023046) (xy 69.48851 -113.039591) (xy 69.499721 -113.053142)
			(xy 69.5071 -113.05794) (xy 69.582792 -113.102644) (xy 69.590502 -113.106671) (xy 69.607583 -113.109876)
			(xy 69.624758 -113.107215) (xy 69.632576 -113.103406) (xy 69.633084 -113.103406) (xy 69.661285 -113.088649)
			(xy 69.721394 -113.067734) (xy 69.784143 -113.057092) (xy 69.815964 -113.056416) (xy 69.84322 -113.056828)
			(xy 69.897179 -113.064582) (xy 69.949484 -113.079936) (xy 69.999072 -113.102578) (xy 70.044932 -113.132046)
			(xy 70.086132 -113.167742) (xy 70.121832 -113.208939) (xy 70.151305 -113.254796) (xy 70.173952 -113.304382)
			(xy 70.189311 -113.356686) (xy 70.197069 -113.410644) (xy 70.197069 -113.465156) (xy 70.189311 -113.519114)
			(xy 70.173952 -113.571418) (xy 70.151305 -113.621004) (xy 70.121832 -113.666861) (xy 70.086132 -113.708058)
			(xy 70.044932 -113.743754) (xy 69.999072 -113.773222) (xy 69.949484 -113.795864) (xy 69.897179 -113.811218)
			(xy 69.84322 -113.818972) (xy 69.815964 -113.819432) (xy 69.784103 -113.818744) (xy 69.721272 -113.80811)
			(xy 69.66108 -113.787192) (xy 69.63283 -113.772442) (xy 69.632576 -113.772442) (xy 69.624781 -113.768555)
			(xy 69.607583 -113.765856) (xy 69.590479 -113.769105) (xy 69.582792 -113.773204) (xy 69.5071 -113.817908)
			(xy 69.499726 -113.822707) (xy 69.488528 -113.836262) (xy 69.482577 -113.852805) (xy 69.482208 -113.861596)
			(xy 69.482208 -114.27079) (xy 69.481721 -114.303643) (xy 69.47436 -114.368935) (xy 69.45974 -114.432993)
			(xy 69.438044 -114.495013) (xy 69.409546 -114.554217) (xy 69.374603 -114.60986) (xy 69.333654 -114.661245)
			(xy 69.310758 -114.68481) (xy 68.63461 -115.360958) (xy 74.11847 -115.360958) (xy 74.118953 -115.333588)
			(xy 74.126764 -115.279409) (xy 74.142248 -115.226906) (xy 74.165087 -115.177158) (xy 74.194809 -115.131191)
			(xy 74.21245 -115.11026) (xy 74.212704 -115.110006) (xy 74.218295 -115.102922) (xy 74.224539 -115.086003)
			(xy 74.224896 -115.076986) (xy 74.224896 -115.00993) (xy 74.224526 -115.000914) (xy 74.218288 -114.983997)
			(xy 74.212704 -114.97691) (xy 74.21245 -114.97691) (xy 74.21245 -114.976656) (xy 74.194831 -114.955707)
			(xy 74.165115 -114.90974) (xy 74.142274 -114.859997) (xy 74.126778 -114.807499) (xy 74.118946 -114.753326)
			(xy 74.11847 -114.725958) (xy 74.118939 -114.698707) (xy 74.1267 -114.64476) (xy 74.14206 -114.592466)
			(xy 74.164704 -114.54289) (xy 74.194173 -114.497041) (xy 74.229866 -114.455852) (xy 74.271057 -114.420161)
			(xy 74.316907 -114.390694) (xy 74.366485 -114.368053) (xy 74.418779 -114.352696) (xy 74.472727 -114.344937)
			(xy 74.499978 -114.34445) (xy 74.527348 -114.344917) (xy 74.581528 -114.352733) (xy 74.634031 -114.368221)
			(xy 74.683778 -114.391063) (xy 74.729745 -114.420788) (xy 74.750676 -114.43843) (xy 74.75093 -114.438684)
			(xy 74.758034 -114.444246) (xy 74.774937 -114.450508) (xy 74.78395 -114.450876) (xy 74.851006 -114.450876)
			(xy 74.860024 -114.450527) (xy 74.876941 -114.444275) (xy 74.884026 -114.438684) (xy 74.884026 -114.43843)
			(xy 74.88428 -114.43843) (xy 74.905213 -114.420791) (xy 74.951185 -114.391079) (xy 75.000932 -114.368242)
			(xy 75.053433 -114.352751) (xy 75.107609 -114.344923) (xy 75.134978 -114.34445) (xy 75.162227 -114.344999)
			(xy 75.21617 -114.352751) (xy 75.268461 -114.368101) (xy 75.318035 -114.390737) (xy 75.363884 -114.420197)
			(xy 75.405073 -114.455882) (xy 75.440765 -114.497065) (xy 75.470233 -114.542909) (xy 75.492876 -114.592479)
			(xy 75.508235 -114.644767) (xy 75.515997 -114.698709) (xy 75.516486 -114.725958) (xy 75.515999 -114.753328)
			(xy 75.508187 -114.807506) (xy 75.492703 -114.860009) (xy 75.469866 -114.909756) (xy 75.440145 -114.955724)
			(xy 75.422506 -114.976656) (xy 75.422252 -114.97691) (xy 75.416649 -114.983985) (xy 75.410413 -115.000911)
			(xy 75.41006 -115.00993) (xy 75.41006 -115.076986) (xy 75.410411 -115.086004) (xy 75.416661 -115.102921)
			(xy 75.422252 -115.110006) (xy 75.422506 -115.110006) (xy 75.422506 -115.11026) (xy 75.440141 -115.131196)
			(xy 75.469853 -115.177167) (xy 75.49269 -115.226914) (xy 75.508182 -115.279414) (xy 75.516011 -115.333589)
			(xy 75.516486 -115.360958) (xy 75.516006 -115.388211) (xy 75.508254 -115.442162) (xy 75.492902 -115.494461)
			(xy 75.470263 -115.544043) (xy 75.440797 -115.589897) (xy 75.405105 -115.631091) (xy 75.363913 -115.666785)
			(xy 75.31806 -115.696253) (xy 75.26848 -115.718895) (xy 75.216182 -115.734249) (xy 75.162231 -115.742004)
			(xy 75.134978 -115.742466) (xy 75.107607 -115.742021) (xy 75.053427 -115.734199) (xy 75.000923 -115.718706)
			(xy 74.951176 -115.695859) (xy 74.905211 -115.66613) (xy 74.88428 -115.648486) (xy 74.884026 -115.648232)
			(xy 74.876942 -115.642642) (xy 74.860023 -115.636399) (xy 74.851006 -115.63604) (xy 74.78395 -115.63604)
			(xy 74.774934 -115.636412) (xy 74.758017 -115.642648) (xy 74.75093 -115.648232) (xy 74.75093 -115.648486)
			(xy 74.750676 -115.648486) (xy 74.729724 -115.666101) (xy 74.683757 -115.695817) (xy 74.634015 -115.718658)
			(xy 74.581518 -115.734154) (xy 74.527346 -115.741989) (xy 74.499978 -115.742466) (xy 74.472723 -115.742065)
			(xy 74.418767 -115.734304) (xy 74.366466 -115.718943) (xy 74.316883 -115.696295) (xy 74.271027 -115.666821)
			(xy 74.229834 -115.631121) (xy 74.194141 -115.589921) (xy 74.164674 -115.544061) (xy 74.142034 -115.494474)
			(xy 74.126682 -115.44217) (xy 74.11893 -115.388213) (xy 74.11847 -115.360958) (xy 68.63461 -115.360958)
			(xy 68.29552 -115.700048) (xy 68.271944 -115.722967) (xy 68.220533 -115.763962) (xy 68.164859 -115.798949)
			(xy 68.10562 -115.827489) (xy 68.043561 -115.849223) (xy 67.979461 -115.863879) (xy 67.914123 -115.871273)
			(xy 67.881246 -115.871752) (xy 67.312794 -115.871752) (xy 67.277379 -115.87127) (xy 67.207065 -115.862732)
			(xy 67.138293 -115.84578) (xy 67.072066 -115.820662) (xy 67.009349 -115.787744) (xy 66.951058 -115.747506)
			(xy 66.898042 -115.700536) (xy 66.851074 -115.647517) (xy 66.810839 -115.589223) (xy 66.777925 -115.526505)
			(xy 66.75281 -115.460277) (xy 66.735862 -115.391504) (xy 66.727328 -115.321189) (xy 66.726816 -115.285774)
			(xy 66.727285 -115.253692) (xy 66.734357 -115.189918) (xy 66.748348 -115.127297) (xy 66.758312 -115.096798)
			(xy 66.761463 -115.085375) (xy 66.758156 -115.061941) (xy 66.751962 -115.05184) (xy 66.698876 -114.974624)
			(xy 66.678302 -114.963194) (xy 66.66611 -114.962686) (xy 66.639604 -114.961144) (xy 66.587367 -114.951641)
			(xy 66.536951 -114.934989) (xy 66.489331 -114.911509) (xy 66.445426 -114.881653) (xy 66.406083 -114.846)
			(xy 66.372063 -114.805236) (xy 66.344023 -114.76015) (xy 66.322503 -114.711613) (xy 66.30792 -114.66056)
			(xy 66.300556 -114.607979) (xy 66.300096 -114.581432) (xy 64.075963 -114.581432) (xy 63.881508 -115.602004)
			(xy 63.871602 -115.65382) (xy 63.871602 -115.668552) (xy 63.878206 -115.67668) (xy 63.878714 -115.677442)
			(xy 63.879984 -115.67922) (xy 63.896379 -115.699795) (xy 63.923954 -115.744596) (xy 63.94511 -115.792763)
			(xy 63.959447 -115.843379) (xy 63.966691 -115.895486) (xy 63.967106 -115.92179) (xy 63.967106 -115.922044)
			(xy 63.966597 -115.950694) (xy 63.958043 -116.007352) (xy 63.941118 -116.062095) (xy 63.916203 -116.113695)
			(xy 63.883856 -116.160992) (xy 63.844805 -116.202924) (xy 63.799927 -116.23855) (xy 63.775336 -116.25326)
			(xy 63.77178 -116.255292) (xy 63.768049 -116.257922) (xy 63.761532 -116.264315) (xy 63.758826 -116.267992)
			(xy 63.752984 -116.27612) (xy 63.720336 -116.44757) (xy 66.157092 -116.44757) (xy 66.161163 -116.391948)
			(xy 66.173289 -116.337511) (xy 66.193212 -116.28542) (xy 66.220508 -116.236785) (xy 66.254594 -116.192642)
			(xy 66.294743 -116.153933) (xy 66.340101 -116.121482) (xy 66.389701 -116.095981) (xy 66.442485 -116.077974)
			(xy 66.497328 -116.067844) (xy 66.553062 -116.065807) (xy 66.608499 -116.071907) (xy 66.662456 -116.086013)
			(xy 66.713785 -116.107825) (xy 66.761391 -116.136879) (xy 66.804259 -116.172554) (xy 66.841476 -116.214091)
			(xy 66.872249 -116.260604) (xy 66.895921 -116.311101) (xy 66.911989 -116.364508) (xy 66.920109 -116.419684)
			(xy 66.920618 -116.44757) (xy 66.920109 -116.475456) (xy 66.919839 -116.477288) (xy 71.304402 -116.477288)
			(xy 71.308473 -116.421666) (xy 71.320599 -116.367229) (xy 71.340522 -116.315138) (xy 71.367818 -116.266503)
			(xy 71.401904 -116.22236) (xy 71.442053 -116.183651) (xy 71.487411 -116.1512) (xy 71.537011 -116.125699)
			(xy 71.589795 -116.107692) (xy 71.644638 -116.097562) (xy 71.700372 -116.095525) (xy 71.755809 -116.101625)
			(xy 71.809766 -116.115731) (xy 71.861095 -116.137543) (xy 71.908701 -116.166597) (xy 71.951569 -116.202272)
			(xy 71.988786 -116.243809) (xy 72.019559 -116.290322) (xy 72.043231 -116.340819) (xy 72.059299 -116.394226)
			(xy 72.067419 -116.449402) (xy 72.067928 -116.477288) (xy 72.067419 -116.505174) (xy 72.059299 -116.56035)
			(xy 72.043231 -116.613757) (xy 72.019559 -116.664254) (xy 71.988786 -116.710767) (xy 71.951569 -116.752304)
			(xy 71.908701 -116.787979) (xy 71.861095 -116.817033) (xy 71.809766 -116.838845) (xy 71.755809 -116.852951)
			(xy 71.700372 -116.859051) (xy 71.644638 -116.857014) (xy 71.589795 -116.846884) (xy 71.537011 -116.828877)
			(xy 71.487411 -116.803376) (xy 71.442053 -116.770925) (xy 71.401904 -116.732216) (xy 71.367818 -116.688073)
			(xy 71.340522 -116.639438) (xy 71.320599 -116.587347) (xy 71.308473 -116.53291) (xy 71.304402 -116.477288)
			(xy 66.919839 -116.477288) (xy 66.911989 -116.530632) (xy 66.895921 -116.584039) (xy 66.872249 -116.634536)
			(xy 66.841476 -116.681049) (xy 66.804259 -116.722586) (xy 66.761391 -116.758261) (xy 66.713785 -116.787315)
			(xy 66.662456 -116.809127) (xy 66.608499 -116.823233) (xy 66.553062 -116.829333) (xy 66.497328 -116.827296)
			(xy 66.442485 -116.817166) (xy 66.389701 -116.799159) (xy 66.340101 -116.773658) (xy 66.294743 -116.741207)
			(xy 66.254594 -116.702498) (xy 66.220508 -116.658355) (xy 66.193212 -116.60972) (xy 66.173289 -116.557629)
			(xy 66.161163 -116.503192) (xy 66.157092 -116.44757) (xy 63.720336 -116.44757) (xy 63.669164 -116.716302)
			(xy 63.544196 -117.37213) (xy 63.544196 -117.372384) (xy 63.543942 -117.374162) (xy 63.501763 -117.723666)
			(xy 69.689724 -117.723666) (xy 69.693795 -117.668044) (xy 69.705921 -117.613607) (xy 69.725844 -117.561516)
			(xy 69.75314 -117.512881) (xy 69.787226 -117.468738) (xy 69.827375 -117.430029) (xy 69.872733 -117.397578)
			(xy 69.922333 -117.372077) (xy 69.975117 -117.35407) (xy 70.02996 -117.34394) (xy 70.085694 -117.341903)
			(xy 70.141131 -117.348003) (xy 70.195088 -117.362109) (xy 70.246417 -117.383921) (xy 70.294023 -117.412975)
			(xy 70.336891 -117.44865) (xy 70.374108 -117.490187) (xy 70.404881 -117.5367) (xy 70.428553 -117.587197)
			(xy 70.444621 -117.640604) (xy 70.452741 -117.69578) (xy 70.45325 -117.723666) (xy 70.452741 -117.751552)
			(xy 70.451686 -117.758718) (xy 74.474832 -117.758718) (xy 74.474832 -116.895118) (xy 74.475322 -116.865134)
			(xy 74.48315 -116.805678) (xy 74.498671 -116.747753) (xy 74.52162 -116.692349) (xy 74.551604 -116.640415)
			(xy 74.58811 -116.592839) (xy 74.630515 -116.550434) (xy 74.678091 -116.513928) (xy 74.730025 -116.483944)
			(xy 74.785429 -116.460995) (xy 74.843354 -116.445474) (xy 74.90281 -116.437646) (xy 74.962778 -116.437646)
			(xy 75.022234 -116.445474) (xy 75.080159 -116.460995) (xy 75.135563 -116.483944) (xy 75.187497 -116.513928)
			(xy 75.235073 -116.550434) (xy 75.277478 -116.592839) (xy 75.313984 -116.640415) (xy 75.343968 -116.692349)
			(xy 75.366917 -116.747753) (xy 75.382438 -116.805678) (xy 75.390266 -116.865134) (xy 75.390756 -116.895118)
			(xy 75.390756 -117.758718) (xy 75.390266 -117.788702) (xy 75.382438 -117.848158) (xy 75.366917 -117.906083)
			(xy 75.343968 -117.961487) (xy 75.313984 -118.013421) (xy 75.277478 -118.060997) (xy 75.235073 -118.103402)
			(xy 75.187497 -118.139908) (xy 75.135563 -118.169892) (xy 75.080159 -118.192841) (xy 75.022234 -118.208362)
			(xy 74.962778 -118.21619) (xy 74.90281 -118.21619) (xy 74.843354 -118.208362) (xy 74.785429 -118.192841)
			(xy 74.730025 -118.169892) (xy 74.678091 -118.139908) (xy 74.630515 -118.103402) (xy 74.58811 -118.060997)
			(xy 74.551604 -118.013421) (xy 74.52162 -117.961487) (xy 74.498671 -117.906083) (xy 74.48315 -117.848158)
			(xy 74.475322 -117.788702) (xy 74.474832 -117.758718) (xy 70.451686 -117.758718) (xy 70.444621 -117.806728)
			(xy 70.428553 -117.860135) (xy 70.404881 -117.910632) (xy 70.374108 -117.957145) (xy 70.336891 -117.998682)
			(xy 70.294023 -118.034357) (xy 70.246417 -118.063411) (xy 70.195088 -118.085223) (xy 70.141131 -118.099329)
			(xy 70.085694 -118.105429) (xy 70.02996 -118.103392) (xy 69.975117 -118.093262) (xy 69.922333 -118.075255)
			(xy 69.872733 -118.049754) (xy 69.827375 -118.017303) (xy 69.787226 -117.978594) (xy 69.75314 -117.934451)
			(xy 69.725844 -117.885816) (xy 69.705921 -117.833725) (xy 69.693795 -117.779288) (xy 69.689724 -117.723666)
			(xy 63.501763 -117.723666) (xy 63.47206 -117.969792) (xy 63.47146 -117.976672) (xy 63.473513 -117.990323)
			(xy 63.476124 -117.996716) (xy 63.481712 -118.009162) (xy 63.486792 -118.012718) (xy 63.49365 -118.017544)
			(xy 63.515185 -118.032856) (xy 63.554218 -118.06847) (xy 63.587959 -118.109135) (xy 63.615758 -118.15407)
			(xy 63.637085 -118.202415) (xy 63.651529 -118.253241) (xy 63.658815 -118.305576) (xy 63.659258 -118.331996)
			(xy 63.658729 -118.360849) (xy 63.650038 -118.417896) (xy 63.632853 -118.472983) (xy 63.607567 -118.524854)
			(xy 63.574757 -118.572324) (xy 63.53517 -118.614311) (xy 63.489712 -118.649856) (xy 63.439418 -118.678148)
			(xy 63.412624 -118.688866) (xy 63.409576 -118.689882) (xy 63.398665 -118.695558) (xy 63.383398 -118.714793)
			(xy 63.380366 -118.726712) (xy 63.278908 -119.567198) (xy 66.599308 -119.567198) (xy 66.599308 -118.703598)
			(xy 66.599798 -118.673614) (xy 66.607626 -118.614158) (xy 66.623147 -118.556233) (xy 66.646096 -118.500829)
			(xy 66.67608 -118.448895) (xy 66.712586 -118.401319) (xy 66.754991 -118.358914) (xy 66.802567 -118.322408)
			(xy 66.854501 -118.292424) (xy 66.909905 -118.269475) (xy 66.96783 -118.253954) (xy 67.027286 -118.246126)
			(xy 67.087254 -118.246126) (xy 67.14671 -118.253954) (xy 67.204635 -118.269475) (xy 67.260039 -118.292424)
			(xy 67.311973 -118.322408) (xy 67.359549 -118.358914) (xy 67.401954 -118.401319) (xy 67.43846 -118.448895)
			(xy 67.468444 -118.500829) (xy 67.491393 -118.556233) (xy 67.506914 -118.614158) (xy 67.514742 -118.673614)
			(xy 67.515232 -118.703598) (xy 67.515232 -118.711218) (xy 69.809358 -118.711218) (xy 69.813429 -118.655596)
			(xy 69.825555 -118.601159) (xy 69.845478 -118.549068) (xy 69.872774 -118.500433) (xy 69.90686 -118.45629)
			(xy 69.947009 -118.417581) (xy 69.992367 -118.38513) (xy 70.041967 -118.359629) (xy 70.094751 -118.341622)
			(xy 70.149594 -118.331492) (xy 70.205328 -118.329455) (xy 70.260765 -118.335555) (xy 70.314722 -118.349661)
			(xy 70.366051 -118.371473) (xy 70.413657 -118.400527) (xy 70.456525 -118.436202) (xy 70.493742 -118.477739)
			(xy 70.524515 -118.524252) (xy 70.548187 -118.574749) (xy 70.564255 -118.628156) (xy 70.572375 -118.683332)
			(xy 70.572884 -118.711218) (xy 70.572375 -118.739104) (xy 70.564255 -118.79428) (xy 70.548187 -118.847687)
			(xy 70.524515 -118.898184) (xy 70.493742 -118.944697) (xy 70.456525 -118.986234) (xy 70.413657 -119.021909)
			(xy 70.366051 -119.050963) (xy 70.314722 -119.072775) (xy 70.260765 -119.086881) (xy 70.205328 -119.092981)
			(xy 70.149594 -119.090944) (xy 70.094751 -119.080814) (xy 70.041967 -119.062807) (xy 69.992367 -119.037306)
			(xy 69.947009 -119.004855) (xy 69.90686 -118.966146) (xy 69.872774 -118.922003) (xy 69.845478 -118.873368)
			(xy 69.825555 -118.821277) (xy 69.813429 -118.76684) (xy 69.809358 -118.711218) (xy 67.515232 -118.711218)
			(xy 67.515232 -119.567198) (xy 67.514742 -119.597182) (xy 67.506914 -119.656638) (xy 67.491393 -119.714563)
			(xy 67.468444 -119.769967) (xy 67.43846 -119.821901) (xy 67.401954 -119.869477) (xy 67.359549 -119.911882)
			(xy 67.311973 -119.948388) (xy 67.260039 -119.978372) (xy 67.204635 -120.001321) (xy 67.14671 -120.016842)
			(xy 67.087254 -120.02467) (xy 67.027286 -120.02467) (xy 66.96783 -120.016842) (xy 66.909905 -120.001321)
			(xy 66.854501 -119.978372) (xy 66.802567 -119.948388) (xy 66.754991 -119.911882) (xy 66.712586 -119.869477)
			(xy 66.67608 -119.821901) (xy 66.646096 -119.769967) (xy 66.623147 -119.714563) (xy 66.607626 -119.656638)
			(xy 66.599798 -119.597182) (xy 66.599308 -119.567198) (xy 63.278908 -119.567198) (xy 63.22568 -120.008142)
			(xy 63.1317 -120.786652) (xy 63.10122 -121.041414) (xy 63.100966 -121.04497) (xy 63.083899 -121.367296)
			(xy 64.745108 -121.367296) (xy 64.745108 -120.503696) (xy 64.745598 -120.473712) (xy 64.753426 -120.414256)
			(xy 64.768947 -120.356331) (xy 64.791896 -120.300927) (xy 64.82188 -120.248993) (xy 64.858386 -120.201417)
			(xy 64.900791 -120.159012) (xy 64.948367 -120.122506) (xy 65.000301 -120.092522) (xy 65.055705 -120.069573)
			(xy 65.11363 -120.054052) (xy 65.173086 -120.046224) (xy 65.233054 -120.046224) (xy 65.29251 -120.054052)
			(xy 65.350435 -120.069573) (xy 65.405839 -120.092522) (xy 65.457773 -120.122506) (xy 65.505349 -120.159012)
			(xy 65.547754 -120.201417) (xy 65.58426 -120.248993) (xy 65.614244 -120.300927) (xy 65.637193 -120.356331)
			(xy 65.652714 -120.414256) (xy 65.660542 -120.473712) (xy 65.661032 -120.503696) (xy 65.661032 -121.367296)
			(xy 65.660542 -121.39728) (xy 65.652714 -121.456736) (xy 65.637193 -121.514661) (xy 65.614244 -121.570065)
			(xy 65.58426 -121.621999) (xy 65.547754 -121.669575) (xy 65.505349 -121.71198) (xy 65.457773 -121.748486)
			(xy 65.405839 -121.77847) (xy 65.350435 -121.801419) (xy 65.29251 -121.81694) (xy 65.233054 -121.824768)
			(xy 65.173086 -121.824768) (xy 65.11363 -121.81694) (xy 65.055705 -121.801419) (xy 65.000301 -121.77847)
			(xy 64.948367 -121.748486) (xy 64.900791 -121.71198) (xy 64.858386 -121.669575) (xy 64.82188 -121.621999)
			(xy 64.791896 -121.570065) (xy 64.768947 -121.514661) (xy 64.753426 -121.456736) (xy 64.745598 -121.39728)
			(xy 64.745108 -121.367296) (xy 63.083899 -121.367296) (xy 62.988601 -123.16714) (xy 66.599308 -123.16714)
			(xy 66.599308 -122.30354) (xy 66.599798 -122.273556) (xy 66.607626 -122.2141) (xy 66.623147 -122.156175)
			(xy 66.646096 -122.100771) (xy 66.67608 -122.048837) (xy 66.712586 -122.001261) (xy 66.754991 -121.958856)
			(xy 66.802567 -121.92235) (xy 66.854501 -121.892366) (xy 66.909905 -121.869417) (xy 66.96783 -121.853896)
			(xy 67.027286 -121.846068) (xy 67.087254 -121.846068) (xy 67.14671 -121.853896) (xy 67.204635 -121.869417)
			(xy 67.260039 -121.892366) (xy 67.311973 -121.92235) (xy 67.359549 -121.958856) (xy 67.401954 -122.001261)
			(xy 67.43846 -122.048837) (xy 67.468444 -122.100771) (xy 67.491393 -122.156175) (xy 67.506914 -122.2141)
			(xy 67.514742 -122.273556) (xy 67.515232 -122.30354) (xy 67.515232 -123.16714) (xy 67.514742 -123.197124)
			(xy 67.506914 -123.25658) (xy 67.491393 -123.314505) (xy 67.468444 -123.369909) (xy 67.43846 -123.421843)
			(xy 67.401954 -123.469419) (xy 67.359549 -123.511824) (xy 67.311973 -123.54833) (xy 67.260039 -123.578314)
			(xy 67.204635 -123.601263) (xy 67.14671 -123.616784) (xy 67.087254 -123.624612) (xy 67.027286 -123.624612)
			(xy 66.96783 -123.616784) (xy 66.909905 -123.601263) (xy 66.854501 -123.578314) (xy 66.802567 -123.54833)
			(xy 66.754991 -123.511824) (xy 66.712586 -123.469419) (xy 66.67608 -123.421843) (xy 66.646096 -123.369909)
			(xy 66.623147 -123.314505) (xy 66.607626 -123.25658) (xy 66.599798 -123.197124) (xy 66.599308 -123.16714)
			(xy 62.988601 -123.16714) (xy 62.893289 -124.967238) (xy 64.745108 -124.967238) (xy 64.745108 -124.103638)
			(xy 64.745598 -124.073654) (xy 64.753426 -124.014198) (xy 64.768947 -123.956273) (xy 64.791896 -123.900869)
			(xy 64.82188 -123.848935) (xy 64.858386 -123.801359) (xy 64.900791 -123.758954) (xy 64.948367 -123.722448)
			(xy 65.000301 -123.692464) (xy 65.055705 -123.669515) (xy 65.11363 -123.653994) (xy 65.173086 -123.646166)
			(xy 65.233054 -123.646166) (xy 65.29251 -123.653994) (xy 65.350435 -123.669515) (xy 65.405839 -123.692464)
			(xy 65.457773 -123.722448) (xy 65.505349 -123.758954) (xy 65.547754 -123.801359) (xy 65.58426 -123.848935)
			(xy 65.614244 -123.900869) (xy 65.637193 -123.956273) (xy 65.652714 -124.014198) (xy 65.660542 -124.073654)
			(xy 65.661032 -124.103638) (xy 65.661032 -124.967238) (xy 65.660542 -124.997222) (xy 65.652714 -125.056678)
			(xy 65.637193 -125.114603) (xy 65.614244 -125.170007) (xy 65.58426 -125.221941) (xy 65.547754 -125.269517)
			(xy 65.505349 -125.311922) (xy 65.457773 -125.348428) (xy 65.405839 -125.378412) (xy 65.350435 -125.401361)
			(xy 65.29251 -125.416882) (xy 65.233054 -125.42471) (xy 65.173086 -125.42471) (xy 65.11363 -125.416882)
			(xy 65.055705 -125.401361) (xy 65.000301 -125.378412) (xy 64.948367 -125.348428) (xy 64.900791 -125.311922)
			(xy 64.858386 -125.269517) (xy 64.82188 -125.221941) (xy 64.791896 -125.170007) (xy 64.768947 -125.114603)
			(xy 64.753426 -125.056678) (xy 64.745598 -124.997222) (xy 64.745108 -124.967238) (xy 62.893289 -124.967238)
			(xy 62.664848 -129.281682) (xy 62.585687 -130.777234) (xy 66.599308 -130.777234) (xy 66.599308 -129.913634)
			(xy 66.599798 -129.88365) (xy 66.607626 -129.824194) (xy 66.623147 -129.766269) (xy 66.646096 -129.710865)
			(xy 66.67608 -129.658931) (xy 66.712586 -129.611355) (xy 66.754991 -129.56895) (xy 66.802567 -129.532444)
			(xy 66.854501 -129.50246) (xy 66.909905 -129.479511) (xy 66.96783 -129.46399) (xy 67.027286 -129.456162)
			(xy 67.087254 -129.456162) (xy 67.14671 -129.46399) (xy 67.204635 -129.479511) (xy 67.260039 -129.50246)
			(xy 67.311973 -129.532444) (xy 67.359549 -129.56895) (xy 67.401954 -129.611355) (xy 67.43846 -129.658931)
			(xy 67.468444 -129.710865) (xy 67.491393 -129.766269) (xy 67.506914 -129.824194) (xy 67.514742 -129.88365)
			(xy 67.515232 -129.913634) (xy 67.515232 -130.777234) (xy 67.514742 -130.807218) (xy 67.506914 -130.866674)
			(xy 67.491393 -130.924599) (xy 67.468444 -130.980003) (xy 67.43846 -131.031937) (xy 67.401954 -131.079513)
			(xy 67.359549 -131.121918) (xy 67.311973 -131.158424) (xy 67.260039 -131.188408) (xy 67.204635 -131.211357)
			(xy 67.14671 -131.226878) (xy 67.087254 -131.234706) (xy 67.027286 -131.234706) (xy 66.96783 -131.226878)
			(xy 66.909905 -131.211357) (xy 66.854501 -131.188408) (xy 66.802567 -131.158424) (xy 66.754991 -131.121918)
			(xy 66.712586 -131.079513) (xy 66.67608 -131.031937) (xy 66.646096 -130.980003) (xy 66.623147 -130.924599)
			(xy 66.607626 -130.866674) (xy 66.599798 -130.807218) (xy 66.599308 -130.777234) (xy 62.585687 -130.777234)
			(xy 62.490407 -132.577332) (xy 64.745108 -132.577332) (xy 64.745108 -131.713732) (xy 64.745598 -131.683748)
			(xy 64.753426 -131.624292) (xy 64.768947 -131.566367) (xy 64.791896 -131.510963) (xy 64.82188 -131.459029)
			(xy 64.858386 -131.411453) (xy 64.900791 -131.369048) (xy 64.948367 -131.332542) (xy 65.000301 -131.302558)
			(xy 65.055705 -131.279609) (xy 65.11363 -131.264088) (xy 65.173086 -131.25626) (xy 65.233054 -131.25626)
			(xy 65.29251 -131.264088) (xy 65.350435 -131.279609) (xy 65.405839 -131.302558) (xy 65.457773 -131.332542)
			(xy 65.505349 -131.369048) (xy 65.547754 -131.411453) (xy 65.58426 -131.459029) (xy 65.614244 -131.510963)
			(xy 65.637193 -131.566367) (xy 65.652714 -131.624292) (xy 65.660542 -131.683748) (xy 65.661032 -131.713732)
			(xy 65.661032 -132.577332) (xy 65.660542 -132.607316) (xy 65.652714 -132.666772) (xy 65.637193 -132.724697)
			(xy 65.614244 -132.780101) (xy 65.58426 -132.832035) (xy 65.547754 -132.879611) (xy 65.505349 -132.922016)
			(xy 65.457773 -132.958522) (xy 65.405839 -132.988506) (xy 65.350435 -133.011455) (xy 65.29251 -133.026976)
			(xy 65.233054 -133.034804) (xy 65.173086 -133.034804) (xy 65.11363 -133.026976) (xy 65.055705 -133.011455)
			(xy 65.000301 -132.988506) (xy 64.948367 -132.958522) (xy 64.900791 -132.922016) (xy 64.858386 -132.879611)
			(xy 64.82188 -132.832035) (xy 64.791896 -132.780101) (xy 64.768947 -132.724697) (xy 64.753426 -132.666772)
			(xy 64.745598 -132.607316) (xy 64.745108 -132.577332) (xy 62.490407 -132.577332) (xy 62.39514 -134.377176)
			(xy 66.599308 -134.377176) (xy 66.599308 -133.513576) (xy 66.599798 -133.483592) (xy 66.607626 -133.424136)
			(xy 66.623147 -133.366211) (xy 66.646096 -133.310807) (xy 66.67608 -133.258873) (xy 66.712586 -133.211297)
			(xy 66.754991 -133.168892) (xy 66.802567 -133.132386) (xy 66.854501 -133.102402) (xy 66.909905 -133.079453)
			(xy 66.96783 -133.063932) (xy 67.027286 -133.056104) (xy 67.087254 -133.056104) (xy 67.14671 -133.063932)
			(xy 67.204635 -133.079453) (xy 67.260039 -133.102402) (xy 67.311973 -133.132386) (xy 67.359549 -133.168892)
			(xy 67.401954 -133.211297) (xy 67.43846 -133.258873) (xy 67.468444 -133.310807) (xy 67.491393 -133.366211)
			(xy 67.506914 -133.424136) (xy 67.514742 -133.483592) (xy 67.515232 -133.513576) (xy 67.515232 -134.377176)
			(xy 67.514742 -134.40716) (xy 67.506914 -134.466616) (xy 67.491393 -134.524541) (xy 67.468444 -134.579945)
			(xy 67.43846 -134.631879) (xy 67.401954 -134.679455) (xy 67.359549 -134.72186) (xy 67.311973 -134.758366)
			(xy 67.260039 -134.78835) (xy 67.204635 -134.811299) (xy 67.14671 -134.82682) (xy 67.087254 -134.834648)
			(xy 67.027286 -134.834648) (xy 66.96783 -134.82682) (xy 66.909905 -134.811299) (xy 66.854501 -134.78835)
			(xy 66.802567 -134.758366) (xy 66.754991 -134.72186) (xy 66.712586 -134.679455) (xy 66.67608 -134.631879)
			(xy 66.646096 -134.579945) (xy 66.623147 -134.524541) (xy 66.607626 -134.466616) (xy 66.599798 -134.40716)
			(xy 66.599308 -134.377176) (xy 62.39514 -134.377176) (xy 62.299859 -136.177274) (xy 64.745108 -136.177274)
			(xy 64.745108 -135.313674) (xy 64.745598 -135.28369) (xy 64.753426 -135.224234) (xy 64.768947 -135.166309)
			(xy 64.791896 -135.110905) (xy 64.82188 -135.058971) (xy 64.858386 -135.011395) (xy 64.900791 -134.96899)
			(xy 64.948367 -134.932484) (xy 65.000301 -134.9025) (xy 65.055705 -134.879551) (xy 65.11363 -134.86403)
			(xy 65.173086 -134.856202) (xy 65.233054 -134.856202) (xy 65.29251 -134.86403) (xy 65.350435 -134.879551)
			(xy 65.405839 -134.9025) (xy 65.457773 -134.932484) (xy 65.505349 -134.96899) (xy 65.547754 -135.011395)
			(xy 65.58426 -135.058971) (xy 65.614244 -135.110905) (xy 65.637193 -135.166309) (xy 65.652714 -135.224234)
			(xy 65.660542 -135.28369) (xy 65.661032 -135.313674) (xy 65.661032 -136.177274) (xy 65.660542 -136.207258)
			(xy 65.652714 -136.266714) (xy 65.637193 -136.324639) (xy 65.614244 -136.380043) (xy 65.58426 -136.431977)
			(xy 65.547754 -136.479553) (xy 65.505349 -136.521958) (xy 65.457773 -136.558464) (xy 65.405839 -136.588448)
			(xy 65.350435 -136.611397) (xy 65.29251 -136.626918) (xy 65.233054 -136.634746) (xy 65.173086 -136.634746)
			(xy 65.11363 -136.626918) (xy 65.055705 -136.611397) (xy 65.000301 -136.588448) (xy 64.948367 -136.558464)
			(xy 64.900791 -136.521958) (xy 64.858386 -136.479553) (xy 64.82188 -136.431977) (xy 64.791896 -136.380043)
			(xy 64.768947 -136.324639) (xy 64.753426 -136.266714) (xy 64.745598 -136.207258) (xy 64.745108 -136.177274)
			(xy 62.299859 -136.177274) (xy 62.234318 -137.415524) (xy 62.234235 -137.424972) (xy 62.240196 -137.442889)
			(xy 62.252231 -137.457439) (xy 62.268711 -137.466654) (xy 62.278006 -137.468356) (xy 62.28588 -137.468864)
			(xy 62.289182 -137.46861) (xy 62.321948 -137.46734) (xy 62.325758 -137.46734) (xy 62.352833 -137.468081)
			(xy 62.406371 -137.476269) (xy 62.458214 -137.491948) (xy 62.507318 -137.514801) (xy 62.552695 -137.54437)
			(xy 62.593434 -137.58006) (xy 62.628716 -137.621154) (xy 62.657831 -137.666824) (xy 62.680193 -137.716153)
			(xy 62.695354 -137.768149) (xy 62.703008 -137.821767) (xy 62.703456 -137.848848) (xy 62.702967 -137.876098)
			(xy 62.695205 -137.930043) (xy 62.679846 -137.982335) (xy 62.657203 -138.031909) (xy 62.627736 -138.077757)
			(xy 62.592046 -138.118946) (xy 62.550857 -138.154636) (xy 62.505009 -138.184103) (xy 62.455435 -138.206746)
			(xy 62.403143 -138.222105) (xy 62.349198 -138.229867) (xy 62.321948 -138.230356) (xy 62.294516 -138.22934)
			(xy 62.284356 -138.228578) (xy 62.275212 -138.231626) (xy 62.270423 -138.233388) (xy 62.2616 -138.238512)
			(xy 62.257686 -138.241786) (xy 62.201298 -138.291316) (xy 62.195297 -138.297686) (xy 62.187618 -138.313398)
			(xy 62.186312 -138.32205) (xy 62.183264 -138.37793) (xy 62.183215 -138.388755) (xy 62.191107 -138.408889)
			(xy 62.198504 -138.416792) (xy 62.253114 -138.470132) (xy 62.25709 -138.47385) (xy 62.266316 -138.479622)
			(xy 62.271402 -138.481562) (xy 62.281562 -138.485118) (xy 62.292484 -138.484356) (xy 62.319408 -138.48334)
			(xy 62.326774 -138.48334) (xy 62.353801 -138.484149) (xy 62.407231 -138.492453) (xy 62.458952 -138.508218)
			(xy 62.507929 -138.531129) (xy 62.553181 -138.560725) (xy 62.5938 -138.596414) (xy 62.628973 -138.637481)
			(xy 62.657995 -138.683103) (xy 62.680284 -138.732366) (xy 62.695394 -138.784283) (xy 62.703022 -138.837813)
			(xy 62.703456 -138.864848) (xy 62.702967 -138.892098) (xy 62.695205 -138.946043) (xy 62.679846 -138.998335)
			(xy 62.657203 -139.047909) (xy 62.627736 -139.093757) (xy 62.592046 -139.134946) (xy 62.550857 -139.170636)
			(xy 62.505009 -139.200103) (xy 62.455435 -139.222746) (xy 62.403143 -139.238105) (xy 62.349198 -139.245867)
			(xy 62.321948 -139.246356) (xy 62.304513 -139.24616) (xy 62.269788 -139.242976) (xy 62.252606 -139.240006)
			(xy 62.249558 -139.239498) (xy 62.243462 -139.238228) (xy 62.241938 -139.237974) (xy 62.231016 -139.240768)
			(xy 62.225779 -139.242162) (xy 62.216032 -139.246895) (xy 62.211712 -139.250166) (xy 62.151768 -139.29741)
			(xy 62.144027 -139.304118) (xy 62.134209 -139.322073) (xy 62.132718 -139.332208) (xy 61.912834 -143.48714)
			(xy 66.599308 -143.48714) (xy 66.599308 -142.62354) (xy 66.599798 -142.593556) (xy 66.607626 -142.5341)
			(xy 66.623147 -142.476175) (xy 66.646096 -142.420771) (xy 66.67608 -142.368837) (xy 66.712586 -142.321261)
			(xy 66.754991 -142.278856) (xy 66.802567 -142.24235) (xy 66.854501 -142.212366) (xy 66.909905 -142.189417)
			(xy 66.96783 -142.173896) (xy 67.027286 -142.166068) (xy 67.087254 -142.166068) (xy 67.14671 -142.173896)
			(xy 67.204635 -142.189417) (xy 67.260039 -142.212366) (xy 67.311973 -142.24235) (xy 67.359549 -142.278856)
			(xy 67.401954 -142.321261) (xy 67.43846 -142.368837) (xy 67.468444 -142.420771) (xy 67.491393 -142.476175)
			(xy 67.506914 -142.5341) (xy 67.514742 -142.593556) (xy 67.515232 -142.62354) (xy 67.515232 -143.48714)
			(xy 67.514742 -143.517124) (xy 67.506914 -143.57658) (xy 67.491393 -143.634505) (xy 67.468444 -143.689909)
			(xy 67.43846 -143.741843) (xy 67.401954 -143.789419) (xy 67.359549 -143.831824) (xy 67.311973 -143.86833)
			(xy 67.260039 -143.898314) (xy 67.204635 -143.921263) (xy 67.14671 -143.936784) (xy 67.087254 -143.944612)
			(xy 67.027286 -143.944612) (xy 66.96783 -143.936784) (xy 66.909905 -143.921263) (xy 66.854501 -143.898314)
			(xy 66.802567 -143.86833) (xy 66.754991 -143.831824) (xy 66.712586 -143.789419) (xy 66.67608 -143.741843)
			(xy 66.646096 -143.689909) (xy 66.623147 -143.634505) (xy 66.607626 -143.57658) (xy 66.599798 -143.517124)
			(xy 66.599308 -143.48714) (xy 61.912834 -143.48714) (xy 61.81757 -145.287238) (xy 64.745108 -145.287238)
			(xy 64.745108 -144.423638) (xy 64.745598 -144.393654) (xy 64.753426 -144.334198) (xy 64.768947 -144.276273)
			(xy 64.791896 -144.220869) (xy 64.82188 -144.168935) (xy 64.858386 -144.121359) (xy 64.900791 -144.078954)
			(xy 64.948367 -144.042448) (xy 65.000301 -144.012464) (xy 65.055705 -143.989515) (xy 65.11363 -143.973994)
			(xy 65.173086 -143.966166) (xy 65.233054 -143.966166) (xy 65.29251 -143.973994) (xy 65.350435 -143.989515)
			(xy 65.405839 -144.012464) (xy 65.457773 -144.042448) (xy 65.505349 -144.078954) (xy 65.547754 -144.121359)
			(xy 65.58426 -144.168935) (xy 65.614244 -144.220869) (xy 65.637193 -144.276273) (xy 65.652714 -144.334198)
			(xy 65.660542 -144.393654) (xy 65.661032 -144.423638) (xy 65.661032 -145.287238) (xy 65.660542 -145.317222)
			(xy 65.652714 -145.376678) (xy 65.637193 -145.434603) (xy 65.614244 -145.490007) (xy 65.58426 -145.541941)
			(xy 65.547754 -145.589517) (xy 65.505349 -145.631922) (xy 65.457773 -145.668428) (xy 65.405839 -145.698412)
			(xy 65.350435 -145.721361) (xy 65.29251 -145.736882) (xy 65.233054 -145.74471) (xy 65.173086 -145.74471)
			(xy 65.11363 -145.736882) (xy 65.055705 -145.721361) (xy 65.000301 -145.698412) (xy 64.948367 -145.668428)
			(xy 64.900791 -145.631922) (xy 64.858386 -145.589517) (xy 64.82188 -145.541941) (xy 64.791896 -145.490007)
			(xy 64.768947 -145.434603) (xy 64.753426 -145.376678) (xy 64.745598 -145.317222) (xy 64.745108 -145.287238)
			(xy 61.81757 -145.287238) (xy 61.722306 -147.087336) (xy 66.599308 -147.087336) (xy 66.599308 -146.223736)
			(xy 66.599798 -146.193752) (xy 66.607626 -146.134296) (xy 66.623147 -146.076371) (xy 66.646096 -146.020967)
			(xy 66.67608 -145.969033) (xy 66.712586 -145.921457) (xy 66.754991 -145.879052) (xy 66.802567 -145.842546)
			(xy 66.854501 -145.812562) (xy 66.909905 -145.789613) (xy 66.96783 -145.774092) (xy 67.027286 -145.766264)
			(xy 67.087254 -145.766264) (xy 67.14671 -145.774092) (xy 67.204635 -145.789613) (xy 67.260039 -145.812562)
			(xy 67.311973 -145.842546) (xy 67.359549 -145.879052) (xy 67.401954 -145.921457) (xy 67.43846 -145.969033)
			(xy 67.468444 -146.020967) (xy 67.491393 -146.076371) (xy 67.506914 -146.134296) (xy 67.514742 -146.193752)
			(xy 67.515232 -146.223736) (xy 67.515232 -147.087336) (xy 67.514742 -147.11732) (xy 67.506914 -147.176776)
			(xy 67.491393 -147.234701) (xy 67.468444 -147.290105) (xy 67.43846 -147.342039) (xy 67.401954 -147.389615)
			(xy 67.359549 -147.43202) (xy 67.311973 -147.468526) (xy 67.260039 -147.49851) (xy 67.204635 -147.521459)
			(xy 67.14671 -147.53698) (xy 67.087254 -147.544808) (xy 67.027286 -147.544808) (xy 66.96783 -147.53698)
			(xy 66.909905 -147.521459) (xy 66.854501 -147.49851) (xy 66.802567 -147.468526) (xy 66.754991 -147.43202)
			(xy 66.712586 -147.389615) (xy 66.67608 -147.342039) (xy 66.646096 -147.290105) (xy 66.623147 -147.234701)
			(xy 66.607626 -147.176776) (xy 66.599798 -147.11732) (xy 66.599308 -147.087336) (xy 61.722306 -147.087336)
			(xy 61.627043 -148.887434) (xy 64.745108 -148.887434) (xy 64.745108 -148.023834) (xy 64.745598 -147.99385)
			(xy 64.753426 -147.934394) (xy 64.768947 -147.876469) (xy 64.791896 -147.821065) (xy 64.82188 -147.769131)
			(xy 64.858386 -147.721555) (xy 64.900791 -147.67915) (xy 64.948367 -147.642644) (xy 65.000301 -147.61266)
			(xy 65.055705 -147.589711) (xy 65.11363 -147.57419) (xy 65.173086 -147.566362) (xy 65.233054 -147.566362)
			(xy 65.29251 -147.57419) (xy 65.350435 -147.589711) (xy 65.405839 -147.61266) (xy 65.457773 -147.642644)
			(xy 65.505349 -147.67915) (xy 65.547754 -147.721555) (xy 65.58426 -147.769131) (xy 65.614244 -147.821065)
			(xy 65.637193 -147.876469) (xy 65.652714 -147.934394) (xy 65.660542 -147.99385) (xy 65.661032 -148.023834)
			(xy 65.661032 -148.887434) (xy 65.660542 -148.917418) (xy 65.652714 -148.976874) (xy 65.637193 -149.034799)
			(xy 65.614244 -149.090203) (xy 65.58426 -149.142137) (xy 65.547754 -149.189713) (xy 65.505349 -149.232118)
			(xy 65.457773 -149.268624) (xy 65.405839 -149.298608) (xy 65.350435 -149.321557) (xy 65.29251 -149.337078)
			(xy 65.233054 -149.344906) (xy 65.173086 -149.344906) (xy 65.11363 -149.337078) (xy 65.055705 -149.321557)
			(xy 65.000301 -149.298608) (xy 64.948367 -149.268624) (xy 64.900791 -149.232118) (xy 64.858386 -149.189713)
			(xy 64.82188 -149.142137) (xy 64.791896 -149.090203) (xy 64.768947 -149.034799) (xy 64.753426 -148.976874)
			(xy 64.745598 -148.917418) (xy 64.745108 -148.887434) (xy 61.627043 -148.887434) (xy 61.531793 -150.687278)
			(xy 66.599308 -150.687278) (xy 66.599308 -149.823678) (xy 66.599798 -149.793694) (xy 66.607626 -149.734238)
			(xy 66.623147 -149.676313) (xy 66.646096 -149.620909) (xy 66.67608 -149.568975) (xy 66.712586 -149.521399)
			(xy 66.754991 -149.478994) (xy 66.802567 -149.442488) (xy 66.854501 -149.412504) (xy 66.909905 -149.389555)
			(xy 66.96783 -149.374034) (xy 67.027286 -149.366206) (xy 67.087254 -149.366206) (xy 67.14671 -149.374034)
			(xy 67.204635 -149.389555) (xy 67.260039 -149.412504) (xy 67.311973 -149.442488) (xy 67.359549 -149.478994)
			(xy 67.401954 -149.521399) (xy 67.43846 -149.568975) (xy 67.468444 -149.620909) (xy 67.491393 -149.676313)
			(xy 67.506914 -149.734238) (xy 67.514742 -149.793694) (xy 67.515232 -149.823678) (xy 67.515232 -150.687278)
			(xy 67.514742 -150.717262) (xy 67.506914 -150.776718) (xy 67.491393 -150.834643) (xy 67.468444 -150.890047)
			(xy 67.43846 -150.941981) (xy 67.401954 -150.989557) (xy 67.359549 -151.031962) (xy 67.311973 -151.068468)
			(xy 67.260039 -151.098452) (xy 67.204635 -151.121401) (xy 67.14671 -151.136922) (xy 67.087254 -151.14475)
			(xy 67.027286 -151.14475) (xy 66.96783 -151.136922) (xy 66.909905 -151.121401) (xy 66.854501 -151.098452)
			(xy 66.802567 -151.068468) (xy 66.754991 -151.031962) (xy 66.712586 -150.989557) (xy 66.67608 -150.941981)
			(xy 66.646096 -150.890047) (xy 66.623147 -150.834643) (xy 66.607626 -150.776718) (xy 66.599798 -150.717262)
			(xy 66.599308 -150.687278) (xy 61.531793 -150.687278) (xy 61.43653 -152.487376) (xy 64.745108 -152.487376)
			(xy 64.745108 -151.623776) (xy 64.745598 -151.593792) (xy 64.753426 -151.534336) (xy 64.768947 -151.476411)
			(xy 64.791896 -151.421007) (xy 64.82188 -151.369073) (xy 64.858386 -151.321497) (xy 64.900791 -151.279092)
			(xy 64.948367 -151.242586) (xy 65.000301 -151.212602) (xy 65.055705 -151.189653) (xy 65.11363 -151.174132)
			(xy 65.173086 -151.166304) (xy 65.233054 -151.166304) (xy 65.29251 -151.174132) (xy 65.350435 -151.189653)
			(xy 65.405839 -151.212602) (xy 65.457773 -151.242586) (xy 65.505349 -151.279092) (xy 65.547754 -151.321497)
			(xy 65.58426 -151.369073) (xy 65.614244 -151.421007) (xy 65.637193 -151.476411) (xy 65.652714 -151.534336)
			(xy 65.660542 -151.593792) (xy 65.661032 -151.623776) (xy 65.661032 -152.487376) (xy 65.660542 -152.51736)
			(xy 65.652714 -152.576816) (xy 65.637193 -152.634741) (xy 65.614244 -152.690145) (xy 65.58426 -152.742079)
			(xy 65.547754 -152.789655) (xy 65.505349 -152.83206) (xy 65.457773 -152.868566) (xy 65.405839 -152.89855)
			(xy 65.350435 -152.921499) (xy 65.29251 -152.93702) (xy 65.233054 -152.944848) (xy 65.173086 -152.944848)
			(xy 65.11363 -152.93702) (xy 65.055705 -152.921499) (xy 65.000301 -152.89855) (xy 64.948367 -152.868566)
			(xy 64.900791 -152.83206) (xy 64.858386 -152.789655) (xy 64.82188 -152.742079) (xy 64.791896 -152.690145)
			(xy 64.768947 -152.634741) (xy 64.753426 -152.576816) (xy 64.745598 -152.51736) (xy 64.745108 -152.487376)
			(xy 61.43653 -152.487376) (xy 61.405009 -153.083006) (xy 62.492126 -153.083006) (xy 62.496197 -153.027384)
			(xy 62.508323 -152.972947) (xy 62.528246 -152.920856) (xy 62.555542 -152.872221) (xy 62.589628 -152.828078)
			(xy 62.629777 -152.789369) (xy 62.675135 -152.756918) (xy 62.724735 -152.731417) (xy 62.777519 -152.71341)
			(xy 62.832362 -152.70328) (xy 62.888096 -152.701243) (xy 62.943533 -152.707343) (xy 62.99749 -152.721449)
			(xy 63.048819 -152.743261) (xy 63.096425 -152.772315) (xy 63.139293 -152.80799) (xy 63.17651 -152.849527)
			(xy 63.207283 -152.89604) (xy 63.230955 -152.946537) (xy 63.247023 -152.999944) (xy 63.255143 -153.05512)
			(xy 63.255652 -153.083006) (xy 63.255143 -153.110892) (xy 63.247023 -153.166068) (xy 63.230955 -153.219475)
			(xy 63.207283 -153.269972) (xy 63.17651 -153.316485) (xy 63.139293 -153.358022) (xy 63.096425 -153.393697)
			(xy 63.048819 -153.422751) (xy 62.99749 -153.444563) (xy 62.943533 -153.458669) (xy 62.888096 -153.464769)
			(xy 62.832362 -153.462732) (xy 62.777519 -153.452602) (xy 62.724735 -153.434595) (xy 62.675135 -153.409094)
			(xy 62.629777 -153.376643) (xy 62.589628 -153.337934) (xy 62.555542 -153.293791) (xy 62.528246 -153.245156)
			(xy 62.508323 -153.193065) (xy 62.496197 -153.138628) (xy 62.492126 -153.083006) (xy 61.405009 -153.083006)
			(xy 61.34128 -154.28722) (xy 66.599308 -154.28722) (xy 66.599308 -153.42362) (xy 66.599798 -153.393636)
			(xy 66.607626 -153.33418) (xy 66.623147 -153.276255) (xy 66.646096 -153.220851) (xy 66.67608 -153.168917)
			(xy 66.712586 -153.121341) (xy 66.754991 -153.078936) (xy 66.802567 -153.04243) (xy 66.854501 -153.012446)
			(xy 66.909905 -152.989497) (xy 66.96783 -152.973976) (xy 67.027286 -152.966148) (xy 67.087254 -152.966148)
			(xy 67.14671 -152.973976) (xy 67.204635 -152.989497) (xy 67.260039 -153.012446) (xy 67.311973 -153.04243)
			(xy 67.359549 -153.078936) (xy 67.401954 -153.121341) (xy 67.43846 -153.168917) (xy 67.468444 -153.220851)
			(xy 67.491393 -153.276255) (xy 67.506914 -153.33418) (xy 67.514742 -153.393636) (xy 67.515232 -153.42362)
			(xy 67.515232 -154.28722) (xy 67.514742 -154.317204) (xy 67.506914 -154.37666) (xy 67.491393 -154.434585)
			(xy 67.468444 -154.489989) (xy 67.43846 -154.541923) (xy 67.401954 -154.589499) (xy 67.359549 -154.631904)
			(xy 67.311973 -154.66841) (xy 67.260039 -154.698394) (xy 67.204635 -154.721343) (xy 67.14671 -154.736864)
			(xy 67.087254 -154.744692) (xy 67.027286 -154.744692) (xy 66.96783 -154.736864) (xy 66.909905 -154.721343)
			(xy 66.854501 -154.698394) (xy 66.802567 -154.66841) (xy 66.754991 -154.631904) (xy 66.712586 -154.589499)
			(xy 66.67608 -154.541923) (xy 66.646096 -154.489989) (xy 66.623147 -154.434585) (xy 66.607626 -154.37666)
			(xy 66.599798 -154.317204) (xy 66.599308 -154.28722) (xy 61.34128 -154.28722) (xy 61.246017 -156.087318)
			(xy 64.745108 -156.087318) (xy 64.745108 -155.223718) (xy 64.745598 -155.193734) (xy 64.753426 -155.134278)
			(xy 64.768947 -155.076353) (xy 64.791896 -155.020949) (xy 64.82188 -154.969015) (xy 64.858386 -154.921439)
			(xy 64.900791 -154.879034) (xy 64.948367 -154.842528) (xy 65.000301 -154.812544) (xy 65.055705 -154.789595)
			(xy 65.11363 -154.774074) (xy 65.173086 -154.766246) (xy 65.233054 -154.766246) (xy 65.29251 -154.774074)
			(xy 65.350435 -154.789595) (xy 65.405839 -154.812544) (xy 65.457773 -154.842528) (xy 65.505349 -154.879034)
			(xy 65.547754 -154.921439) (xy 65.58426 -154.969015) (xy 65.614244 -155.020949) (xy 65.637193 -155.076353)
			(xy 65.652714 -155.134278) (xy 65.660542 -155.193734) (xy 65.661032 -155.223718) (xy 65.661032 -156.087318)
			(xy 65.660542 -156.117302) (xy 65.652714 -156.176758) (xy 65.637193 -156.234683) (xy 65.614244 -156.290087)
			(xy 65.58426 -156.342021) (xy 65.547754 -156.389597) (xy 65.505349 -156.432002) (xy 65.457773 -156.468508)
			(xy 65.405839 -156.498492) (xy 65.350435 -156.521441) (xy 65.29251 -156.536962) (xy 65.233054 -156.54479)
			(xy 65.173086 -156.54479) (xy 65.11363 -156.536962) (xy 65.055705 -156.521441) (xy 65.000301 -156.498492)
			(xy 64.948367 -156.468508) (xy 64.900791 -156.432002) (xy 64.858386 -156.389597) (xy 64.82188 -156.342021)
			(xy 64.791896 -156.290087) (xy 64.768947 -156.234683) (xy 64.753426 -156.176758) (xy 64.745598 -156.117302)
			(xy 64.745108 -156.087318) (xy 61.246017 -156.087318) (xy 61.195327 -157.045152) (xy 61.410594 -157.045152)
			(xy 61.414665 -156.98953) (xy 61.426791 -156.935093) (xy 61.446714 -156.883002) (xy 61.47401 -156.834367)
			(xy 61.508096 -156.790224) (xy 61.548245 -156.751515) (xy 61.593603 -156.719064) (xy 61.643203 -156.693563)
			(xy 61.695987 -156.675556) (xy 61.75083 -156.665426) (xy 61.806564 -156.663389) (xy 61.862001 -156.669489)
			(xy 61.915958 -156.683595) (xy 61.967287 -156.705407) (xy 62.014893 -156.734461) (xy 62.057761 -156.770136)
			(xy 62.094978 -156.811673) (xy 62.125751 -156.858186) (xy 62.149423 -156.908683) (xy 62.165491 -156.96209)
			(xy 62.173611 -157.017266) (xy 62.17412 -157.045152) (xy 62.426594 -157.045152) (xy 62.430665 -156.98953)
			(xy 62.442791 -156.935093) (xy 62.462714 -156.883002) (xy 62.49001 -156.834367) (xy 62.524096 -156.790224)
			(xy 62.564245 -156.751515) (xy 62.609603 -156.719064) (xy 62.659203 -156.693563) (xy 62.711987 -156.675556)
			(xy 62.76683 -156.665426) (xy 62.822564 -156.663389) (xy 62.878001 -156.669489) (xy 62.931958 -156.683595)
			(xy 62.983287 -156.705407) (xy 63.030893 -156.734461) (xy 63.073761 -156.770136) (xy 63.110978 -156.811673)
			(xy 63.141751 -156.858186) (xy 63.165423 -156.908683) (xy 63.181491 -156.96209) (xy 63.189611 -157.017266)
			(xy 63.19012 -157.045152) (xy 63.189611 -157.073038) (xy 63.181491 -157.128214) (xy 63.165423 -157.181621)
			(xy 63.141751 -157.232118) (xy 63.110978 -157.278631) (xy 63.073761 -157.320168) (xy 63.030893 -157.355843)
			(xy 62.983287 -157.384897) (xy 62.931958 -157.406709) (xy 62.878001 -157.420815) (xy 62.822564 -157.426915)
			(xy 62.76683 -157.424878) (xy 62.711987 -157.414748) (xy 62.659203 -157.396741) (xy 62.609603 -157.37124)
			(xy 62.564245 -157.338789) (xy 62.524096 -157.30008) (xy 62.49001 -157.255937) (xy 62.462714 -157.207302)
			(xy 62.442791 -157.155211) (xy 62.430665 -157.100774) (xy 62.426594 -157.045152) (xy 62.17412 -157.045152)
			(xy 62.173611 -157.073038) (xy 62.165491 -157.128214) (xy 62.149423 -157.181621) (xy 62.125751 -157.232118)
			(xy 62.094978 -157.278631) (xy 62.057761 -157.320168) (xy 62.014893 -157.355843) (xy 61.967287 -157.384897)
			(xy 61.915958 -157.406709) (xy 61.862001 -157.420815) (xy 61.806564 -157.426915) (xy 61.75083 -157.424878)
			(xy 61.695987 -157.414748) (xy 61.643203 -157.396741) (xy 61.593603 -157.37124) (xy 61.548245 -157.338789)
			(xy 61.508096 -157.30008) (xy 61.47401 -157.255937) (xy 61.446714 -157.207302) (xy 61.426791 -157.155211)
			(xy 61.414665 -157.100774) (xy 61.410594 -157.045152) (xy 61.195327 -157.045152) (xy 61.082428 -159.178498)
			(xy 61.083129 -159.188647) (xy 61.091461 -159.207189) (xy 61.106312 -159.221069) (xy 61.115702 -159.22498)
			(xy 61.120274 -159.22625) (xy 61.147081 -159.233842) (xy 61.198317 -159.255726) (xy 61.245828 -159.284823)
			(xy 61.288608 -159.320515) (xy 61.325746 -159.362044) (xy 61.356456 -159.40853) (xy 61.380085 -159.458985)
			(xy 61.396131 -159.512337) (xy 61.404254 -159.567456) (xy 61.404754 -159.595312) (xy 61.404675 -159.60805)
			(xy 61.403021 -159.633471) (xy 61.401452 -159.646112) (xy 61.397361 -159.673074) (xy 61.382479 -159.725536)
			(xy 61.360278 -159.775345) (xy 61.331213 -159.821486) (xy 61.295875 -159.863019) (xy 61.254984 -159.899098)
			(xy 61.209372 -159.928988) (xy 61.15997 -159.95208) (xy 61.107784 -159.967903) (xy 61.080904 -159.972502)
			(xy 61.079126 -159.972756) (xy 61.068574 -159.975244) (xy 61.050815 -159.987644) (xy 61.039729 -160.006252)
			(xy 61.037978 -160.016952) (xy 61.029078 -160.1851) (xy 69.888875 -160.1851) (xy 69.892831 -160.093241)
			(xy 69.904668 -160.002062) (xy 69.9243 -159.912238) (xy 69.951581 -159.824435) (xy 69.986309 -159.739302)
			(xy 70.028227 -159.657469) (xy 70.077025 -159.579542) (xy 70.13234 -159.506099) (xy 70.193765 -159.437683)
			(xy 70.260844 -159.374801) (xy 70.333079 -159.317918) (xy 70.409938 -159.267455) (xy 70.49085 -159.223786)
			(xy 70.575216 -159.187234) (xy 70.662412 -159.15807) (xy 70.751793 -159.13651) (xy 70.842696 -159.122714)
			(xy 70.934449 -159.116782) (xy 71.026371 -159.118761) (xy 71.117784 -159.128634) (xy 71.208009 -159.146329)
			(xy 71.29638 -159.171714) (xy 71.38224 -159.204602) (xy 71.464956 -159.24475) (xy 71.543914 -159.291859)
			(xy 71.618531 -159.345582) (xy 71.688252 -159.40552) (xy 71.752563 -159.47123) (xy 71.810988 -159.542226)
			(xy 71.863093 -159.61798) (xy 71.908492 -159.697934) (xy 71.946851 -159.781494) (xy 71.977884 -159.868043)
			(xy 72.001362 -159.956939) (xy 72.017112 -160.047524) (xy 72.025016 -160.139128) (xy 72.02551 -160.1851)
			(xy 72.025016 -160.231072) (xy 72.017112 -160.322676) (xy 72.001362 -160.413261) (xy 71.977884 -160.502157)
			(xy 71.946851 -160.588706) (xy 71.908492 -160.672266) (xy 71.863093 -160.75222) (xy 71.810988 -160.827974)
			(xy 71.752563 -160.89897) (xy 71.688252 -160.96468) (xy 71.618531 -161.024618) (xy 71.543914 -161.078341)
			(xy 71.464956 -161.12545) (xy 71.38224 -161.165598) (xy 71.29638 -161.198486) (xy 71.208009 -161.223871)
			(xy 71.117784 -161.241566) (xy 71.026371 -161.251439) (xy 70.934449 -161.253418) (xy 70.842696 -161.247486)
			(xy 70.751793 -161.23369) (xy 70.662412 -161.21213) (xy 70.575216 -161.182966) (xy 70.49085 -161.146414)
			(xy 70.409938 -161.102745) (xy 70.333079 -161.052282) (xy 70.260844 -160.995399) (xy 70.193765 -160.932517)
			(xy 70.13234 -160.864101) (xy 70.077025 -160.790658) (xy 70.028227 -160.712731) (xy 69.986309 -160.630898)
			(xy 69.951581 -160.545765) (xy 69.9243 -160.457962) (xy 69.904668 -160.368138) (xy 69.892831 -160.276959)
			(xy 69.888875 -160.1851) (xy 61.029078 -160.1851) (xy 60.952262 -161.636456) (xy 63.800734 -161.636456)
			(xy 63.804805 -161.580834) (xy 63.816931 -161.526397) (xy 63.836854 -161.474306) (xy 63.86415 -161.425671)
			(xy 63.898236 -161.381528) (xy 63.938385 -161.342819) (xy 63.983743 -161.310368) (xy 64.033343 -161.284867)
			(xy 64.086127 -161.26686) (xy 64.14097 -161.25673) (xy 64.196704 -161.254693) (xy 64.252141 -161.260793)
			(xy 64.306098 -161.274899) (xy 64.357427 -161.296711) (xy 64.405033 -161.325765) (xy 64.447901 -161.36144)
			(xy 64.485118 -161.402977) (xy 64.515891 -161.44949) (xy 64.539563 -161.499987) (xy 64.555631 -161.553394)
			(xy 64.563751 -161.60857) (xy 64.56426 -161.636456) (xy 64.563751 -161.664342) (xy 64.555631 -161.719518)
			(xy 64.539563 -161.772925) (xy 64.515891 -161.823422) (xy 64.485118 -161.869935) (xy 64.447901 -161.911472)
			(xy 64.405033 -161.947147) (xy 64.357427 -161.976201) (xy 64.306098 -161.998013) (xy 64.252141 -162.012119)
			(xy 64.196704 -162.018219) (xy 64.14097 -162.016182) (xy 64.086127 -162.006052) (xy 64.033343 -161.988045)
			(xy 63.983743 -161.962544) (xy 63.938385 -161.930093) (xy 63.898236 -161.891384) (xy 63.86415 -161.847241)
			(xy 63.836854 -161.798606) (xy 63.816931 -161.746515) (xy 63.804805 -161.692078) (xy 63.800734 -161.636456)
			(xy 60.952262 -161.636456) (xy 60.887356 -162.862768) (xy 60.887305 -162.873375) (xy 60.894786 -162.893195)
			(xy 60.901834 -162.901122) (xy 60.941966 -162.941254) (xy 60.95492 -162.954462) (xy 60.958792 -162.958126)
			(xy 60.967759 -162.963889) (xy 60.9727 -162.965892) (xy 60.982098 -162.969702) (xy 60.99302 -162.969448)
			(xy 61.009022 -162.969194) (xy 61.00953 -162.969194) (xy 61.03677 -162.969695) (xy 61.090693 -162.977479)
			(xy 61.14296 -162.992854) (xy 61.192508 -163.015508) (xy 61.23833 -163.04498) (xy 61.279492 -163.080672)
			(xy 61.315159 -163.121856) (xy 61.344603 -163.167695) (xy 61.367228 -163.217257) (xy 61.382571 -163.269534)
			(xy 61.390321 -163.323461) (xy 61.390784 -163.350702) (xy 61.390319 -163.377655) (xy 61.382732 -163.431025)
			(xy 61.36771 -163.482796) (xy 61.34555 -163.531938) (xy 61.316695 -163.577471) (xy 61.281719 -163.618491)
			(xy 61.241318 -163.654179) (xy 61.196297 -163.683827) (xy 61.147551 -163.706843) (xy 61.09605 -163.722769)
			(xy 61.042821 -163.731289) (xy 61.01588 -163.73221) (xy 61.009022 -163.73221) (xy 60.994937 -163.732098)
			(xy 60.966842 -163.730064) (xy 60.952888 -163.728146) (xy 60.952634 -163.728146) (xy 60.942108 -163.727126)
			(xy 60.92175 -163.732759) (xy 60.913264 -163.739068) (xy 60.855098 -163.786566) (xy 60.847665 -163.793154)
			(xy 60.838103 -163.810539) (xy 60.836556 -163.820348) (xy 60.683846 -166.705534) (xy 61.11189 -166.705534)
			(xy 61.115961 -166.649912) (xy 61.128087 -166.595475) (xy 61.14801 -166.543384) (xy 61.175306 -166.494749)
			(xy 61.209392 -166.450606) (xy 61.249541 -166.411897) (xy 61.294899 -166.379446) (xy 61.344499 -166.353945)
			(xy 61.397283 -166.335938) (xy 61.452126 -166.325808) (xy 61.50786 -166.323771) (xy 61.563297 -166.329871)
			(xy 61.617254 -166.343977) (xy 61.668583 -166.365789) (xy 61.716189 -166.394843) (xy 61.759057 -166.430518)
			(xy 61.796274 -166.472055) (xy 61.827047 -166.518568) (xy 61.850719 -166.569065) (xy 61.866787 -166.622472)
			(xy 61.874907 -166.677648) (xy 61.875416 -166.705534) (xy 62.12789 -166.705534) (xy 62.131961 -166.649912)
			(xy 62.144087 -166.595475) (xy 62.16401 -166.543384) (xy 62.191306 -166.494749) (xy 62.225392 -166.450606)
			(xy 62.265541 -166.411897) (xy 62.310899 -166.379446) (xy 62.360499 -166.353945) (xy 62.413283 -166.335938)
			(xy 62.468126 -166.325808) (xy 62.52386 -166.323771) (xy 62.579297 -166.329871) (xy 62.633254 -166.343977)
			(xy 62.684583 -166.365789) (xy 62.732189 -166.394843) (xy 62.775057 -166.430518) (xy 62.812274 -166.472055)
			(xy 62.843047 -166.518568) (xy 62.866719 -166.569065) (xy 62.882787 -166.622472) (xy 62.890907 -166.677648)
			(xy 62.891416 -166.705534) (xy 63.14389 -166.705534) (xy 63.147961 -166.649912) (xy 63.160087 -166.595475)
			(xy 63.18001 -166.543384) (xy 63.207306 -166.494749) (xy 63.241392 -166.450606) (xy 63.281541 -166.411897)
			(xy 63.326899 -166.379446) (xy 63.376499 -166.353945) (xy 63.429283 -166.335938) (xy 63.484126 -166.325808)
			(xy 63.53986 -166.323771) (xy 63.595297 -166.329871) (xy 63.649254 -166.343977) (xy 63.700583 -166.365789)
			(xy 63.748189 -166.394843) (xy 63.791057 -166.430518) (xy 63.828274 -166.472055) (xy 63.859047 -166.518568)
			(xy 63.882719 -166.569065) (xy 63.898787 -166.622472) (xy 63.906907 -166.677648) (xy 63.907416 -166.705534)
			(xy 63.906907 -166.73342) (xy 63.898787 -166.788596) (xy 63.882719 -166.842003) (xy 63.859047 -166.8925)
			(xy 63.828274 -166.939013) (xy 63.791057 -166.98055) (xy 63.748189 -167.016225) (xy 63.700583 -167.045279)
			(xy 63.649254 -167.067091) (xy 63.595297 -167.081197) (xy 63.53986 -167.087297) (xy 63.484126 -167.08526)
			(xy 63.429283 -167.07513) (xy 63.376499 -167.057123) (xy 63.326899 -167.031622) (xy 63.281541 -166.999171)
			(xy 63.241392 -166.960462) (xy 63.207306 -166.916319) (xy 63.18001 -166.867684) (xy 63.160087 -166.815593)
			(xy 63.147961 -166.761156) (xy 63.14389 -166.705534) (xy 62.891416 -166.705534) (xy 62.890907 -166.73342)
			(xy 62.882787 -166.788596) (xy 62.866719 -166.842003) (xy 62.843047 -166.8925) (xy 62.812274 -166.939013)
			(xy 62.775057 -166.98055) (xy 62.732189 -167.016225) (xy 62.684583 -167.045279) (xy 62.633254 -167.067091)
			(xy 62.579297 -167.081197) (xy 62.52386 -167.087297) (xy 62.468126 -167.08526) (xy 62.413283 -167.07513)
			(xy 62.360499 -167.057123) (xy 62.310899 -167.031622) (xy 62.265541 -166.999171) (xy 62.225392 -166.960462)
			(xy 62.191306 -166.916319) (xy 62.16401 -166.867684) (xy 62.144087 -166.815593) (xy 62.131961 -166.761156)
			(xy 62.12789 -166.705534) (xy 61.875416 -166.705534) (xy 61.874907 -166.73342) (xy 61.866787 -166.788596)
			(xy 61.850719 -166.842003) (xy 61.827047 -166.8925) (xy 61.796274 -166.939013) (xy 61.759057 -166.98055)
			(xy 61.716189 -167.016225) (xy 61.668583 -167.045279) (xy 61.617254 -167.067091) (xy 61.563297 -167.081197)
			(xy 61.50786 -167.087297) (xy 61.452126 -167.08526) (xy 61.397283 -167.07513) (xy 61.344499 -167.057123)
			(xy 61.294899 -167.031622) (xy 61.249541 -166.999171) (xy 61.209392 -166.960462) (xy 61.175306 -166.916319)
			(xy 61.14801 -166.867684) (xy 61.128087 -166.815593) (xy 61.115961 -166.761156) (xy 61.11189 -166.705534)
			(xy 60.683846 -166.705534) (xy 60.386183 -172.329348) (xy 61.847982 -172.329348) (xy 61.852053 -172.273726)
			(xy 61.864179 -172.219289) (xy 61.884102 -172.167198) (xy 61.911398 -172.118563) (xy 61.945484 -172.07442)
			(xy 61.985633 -172.035711) (xy 62.030991 -172.00326) (xy 62.080591 -171.977759) (xy 62.133375 -171.959752)
			(xy 62.188218 -171.949622) (xy 62.243952 -171.947585) (xy 62.299389 -171.953685) (xy 62.353346 -171.967791)
			(xy 62.404675 -171.989603) (xy 62.452281 -172.018657) (xy 62.495149 -172.054332) (xy 62.532366 -172.095869)
			(xy 62.563139 -172.142382) (xy 62.586811 -172.192879) (xy 62.602879 -172.246286) (xy 62.610999 -172.301462)
			(xy 62.611508 -172.329348) (xy 62.611244 -172.343826) (xy 62.785242 -172.343826) (xy 62.789313 -172.288204)
			(xy 62.801439 -172.233767) (xy 62.821362 -172.181676) (xy 62.848658 -172.133041) (xy 62.882744 -172.088898)
			(xy 62.922893 -172.050189) (xy 62.968251 -172.017738) (xy 63.017851 -171.992237) (xy 63.070635 -171.97423)
			(xy 63.125478 -171.9641) (xy 63.181212 -171.962063) (xy 63.236649 -171.968163) (xy 63.290606 -171.982269)
			(xy 63.341935 -172.004081) (xy 63.389541 -172.033135) (xy 63.432409 -172.06881) (xy 63.469626 -172.110347)
			(xy 63.500399 -172.15686) (xy 63.524071 -172.207357) (xy 63.540139 -172.260764) (xy 63.548259 -172.31594)
			(xy 63.548768 -172.343826) (xy 63.548259 -172.371712) (xy 63.540139 -172.426888) (xy 63.524071 -172.480295)
			(xy 63.500399 -172.530792) (xy 63.469626 -172.577305) (xy 63.432409 -172.618842) (xy 63.389541 -172.654517)
			(xy 63.341935 -172.683571) (xy 63.290606 -172.705383) (xy 63.236649 -172.719489) (xy 63.181212 -172.725589)
			(xy 63.125478 -172.723552) (xy 63.070635 -172.713422) (xy 63.017851 -172.695415) (xy 62.968251 -172.669914)
			(xy 62.922893 -172.637463) (xy 62.882744 -172.598754) (xy 62.848658 -172.554611) (xy 62.821362 -172.505976)
			(xy 62.801439 -172.453885) (xy 62.789313 -172.399448) (xy 62.785242 -172.343826) (xy 62.611244 -172.343826)
			(xy 62.610999 -172.357234) (xy 62.602879 -172.41241) (xy 62.586811 -172.465817) (xy 62.563139 -172.516314)
			(xy 62.532366 -172.562827) (xy 62.495149 -172.604364) (xy 62.452281 -172.640039) (xy 62.404675 -172.669093)
			(xy 62.353346 -172.690905) (xy 62.299389 -172.705011) (xy 62.243952 -172.711111) (xy 62.188218 -172.709074)
			(xy 62.133375 -172.698944) (xy 62.080591 -172.680937) (xy 62.030991 -172.655436) (xy 61.985633 -172.622985)
			(xy 61.945484 -172.584276) (xy 61.911398 -172.540133) (xy 61.884102 -172.491498) (xy 61.864179 -172.439407)
			(xy 61.852053 -172.38497) (xy 61.847982 -172.329348) (xy 60.386183 -172.329348) (xy 60.21609 -175.542956)
			(xy 62.632842 -175.542956) (xy 62.636913 -175.487334) (xy 62.649039 -175.432897) (xy 62.668962 -175.380806)
			(xy 62.696258 -175.332171) (xy 62.730344 -175.288028) (xy 62.770493 -175.249319) (xy 62.815851 -175.216868)
			(xy 62.865451 -175.191367) (xy 62.918235 -175.17336) (xy 62.973078 -175.16323) (xy 63.028812 -175.161193)
			(xy 63.084249 -175.167293) (xy 63.138206 -175.181399) (xy 63.189535 -175.203211) (xy 63.237141 -175.232265)
			(xy 63.280009 -175.26794) (xy 63.317226 -175.309477) (xy 63.347999 -175.35599) (xy 63.371671 -175.406487)
			(xy 63.387739 -175.459894) (xy 63.395859 -175.51507) (xy 63.396368 -175.542956) (xy 63.395859 -175.570842)
			(xy 63.387739 -175.626018) (xy 63.371671 -175.679425) (xy 63.347999 -175.729922) (xy 63.317226 -175.776435)
			(xy 63.280009 -175.817972) (xy 63.237141 -175.853647) (xy 63.189535 -175.882701) (xy 63.138206 -175.904513)
			(xy 63.084249 -175.918619) (xy 63.028812 -175.924719) (xy 62.973078 -175.922682) (xy 62.918235 -175.912552)
			(xy 62.865451 -175.894545) (xy 62.815851 -175.869044) (xy 62.770493 -175.836593) (xy 62.730344 -175.797884)
			(xy 62.696258 -175.753741) (xy 62.668962 -175.705106) (xy 62.649039 -175.653015) (xy 62.636913 -175.598578)
			(xy 62.632842 -175.542956) (xy 60.21609 -175.542956) (xy 60.138156 -177.015394) (xy 61.6618 -177.015394)
			(xy 61.665871 -176.959772) (xy 61.677997 -176.905335) (xy 61.69792 -176.853244) (xy 61.725216 -176.804609)
			(xy 61.759302 -176.760466) (xy 61.799451 -176.721757) (xy 61.844809 -176.689306) (xy 61.894409 -176.663805)
			(xy 61.947193 -176.645798) (xy 62.002036 -176.635668) (xy 62.05777 -176.633631) (xy 62.113207 -176.639731)
			(xy 62.167164 -176.653837) (xy 62.218493 -176.675649) (xy 62.266099 -176.704703) (xy 62.308967 -176.740378)
			(xy 62.346184 -176.781915) (xy 62.376957 -176.828428) (xy 62.400629 -176.878925) (xy 62.416697 -176.932332)
			(xy 62.424817 -176.987508) (xy 62.425326 -177.015394) (xy 62.424817 -177.04328) (xy 62.416697 -177.098456)
			(xy 62.400629 -177.151863) (xy 62.376957 -177.20236) (xy 62.346184 -177.248873) (xy 62.308967 -177.29041)
			(xy 62.266099 -177.326085) (xy 62.221647 -177.353214) (xy 64.295018 -177.353214) (xy 64.299089 -177.297592)
			(xy 64.311215 -177.243155) (xy 64.331138 -177.191064) (xy 64.358434 -177.142429) (xy 64.39252 -177.098286)
			(xy 64.432669 -177.059577) (xy 64.478027 -177.027126) (xy 64.527627 -177.001625) (xy 64.580411 -176.983618)
			(xy 64.635254 -176.973488) (xy 64.690988 -176.971451) (xy 64.746425 -176.977551) (xy 64.800382 -176.991657)
			(xy 64.851711 -177.013469) (xy 64.899317 -177.042523) (xy 64.942185 -177.078198) (xy 64.979402 -177.119735)
			(xy 65.010175 -177.166248) (xy 65.033847 -177.216745) (xy 65.049915 -177.270152) (xy 65.058035 -177.325328)
			(xy 65.058544 -177.353214) (xy 65.058035 -177.3811) (xy 65.049915 -177.436276) (xy 65.033847 -177.489683)
			(xy 65.010175 -177.54018) (xy 64.979402 -177.586693) (xy 64.942185 -177.62823) (xy 64.899317 -177.663905)
			(xy 64.851711 -177.692959) (xy 64.800382 -177.714771) (xy 64.746425 -177.728877) (xy 64.690988 -177.734977)
			(xy 64.635254 -177.73294) (xy 64.580411 -177.72281) (xy 64.527627 -177.704803) (xy 64.478027 -177.679302)
			(xy 64.432669 -177.646851) (xy 64.39252 -177.608142) (xy 64.358434 -177.563999) (xy 64.331138 -177.515364)
			(xy 64.311215 -177.463273) (xy 64.299089 -177.408836) (xy 64.295018 -177.353214) (xy 62.221647 -177.353214)
			(xy 62.218493 -177.355139) (xy 62.167164 -177.376951) (xy 62.113207 -177.391057) (xy 62.05777 -177.397157)
			(xy 62.002036 -177.39512) (xy 61.947193 -177.38499) (xy 61.894409 -177.366983) (xy 61.844809 -177.341482)
			(xy 61.799451 -177.309031) (xy 61.759302 -177.270322) (xy 61.725216 -177.226179) (xy 61.69792 -177.177544)
			(xy 61.677997 -177.125453) (xy 61.665871 -177.071016) (xy 61.6618 -177.015394) (xy 60.138156 -177.015394)
			(xy 59.36619 -191.600328) (xy 59.508642 -191.600328) (xy 59.512713 -191.544706) (xy 59.524839 -191.490269)
			(xy 59.544762 -191.438178) (xy 59.572058 -191.389543) (xy 59.606144 -191.3454) (xy 59.646293 -191.306691)
			(xy 59.691651 -191.27424) (xy 59.741251 -191.248739) (xy 59.794035 -191.230732) (xy 59.848878 -191.220602)
			(xy 59.904612 -191.218565) (xy 59.960049 -191.224665) (xy 60.014006 -191.238771) (xy 60.065335 -191.260583)
			(xy 60.112941 -191.289637) (xy 60.155809 -191.325312) (xy 60.193026 -191.366849) (xy 60.223799 -191.413362)
			(xy 60.247471 -191.463859) (xy 60.263539 -191.517266) (xy 60.271659 -191.572442) (xy 60.272168 -191.600328)
			(xy 60.271659 -191.628214) (xy 60.263539 -191.68339) (xy 60.247471 -191.736797) (xy 60.223799 -191.787294)
			(xy 60.193026 -191.833807) (xy 60.155809 -191.875344) (xy 60.112941 -191.911019) (xy 60.065335 -191.940073)
			(xy 60.014006 -191.961885) (xy 59.960049 -191.975991) (xy 59.904612 -191.982091) (xy 59.848878 -191.980054)
			(xy 59.794035 -191.969924) (xy 59.741251 -191.951917) (xy 59.691651 -191.926416) (xy 59.646293 -191.893965)
			(xy 59.606144 -191.855256) (xy 59.572058 -191.811113) (xy 59.544762 -191.762478) (xy 59.524839 -191.710387)
			(xy 59.512713 -191.65595) (xy 59.508642 -191.600328) (xy 59.36619 -191.600328) (xy 58.590338 -206.258668)
			(xy 62.738506 -206.258668) (xy 62.742577 -206.203046) (xy 62.754703 -206.148609) (xy 62.774626 -206.096518)
			(xy 62.801922 -206.047883) (xy 62.836008 -206.00374) (xy 62.876157 -205.965031) (xy 62.921515 -205.93258)
			(xy 62.971115 -205.907079) (xy 63.023899 -205.889072) (xy 63.078742 -205.878942) (xy 63.134476 -205.876905)
			(xy 63.189913 -205.883005) (xy 63.24387 -205.897111) (xy 63.295199 -205.918923) (xy 63.342805 -205.947977)
			(xy 63.385673 -205.983652) (xy 63.42289 -206.025189) (xy 63.453663 -206.071702) (xy 63.477335 -206.122199)
			(xy 63.493403 -206.175606) (xy 63.501523 -206.230782) (xy 63.502032 -206.258668) (xy 63.501523 -206.286554)
			(xy 63.493403 -206.34173) (xy 63.477335 -206.395137) (xy 63.453663 -206.445634) (xy 63.42289 -206.492147)
			(xy 63.385673 -206.533684) (xy 63.342805 -206.569359) (xy 63.295199 -206.598413) (xy 63.24387 -206.620225)
			(xy 63.189913 -206.634331) (xy 63.134476 -206.640431) (xy 63.078742 -206.638394) (xy 63.023899 -206.628264)
			(xy 62.971115 -206.610257) (xy 62.921515 -206.584756) (xy 62.876157 -206.552305) (xy 62.836008 -206.513596)
			(xy 62.801922 -206.469453) (xy 62.774626 -206.420818) (xy 62.754703 -206.368727) (xy 62.742577 -206.31429)
			(xy 62.738506 -206.258668) (xy 58.590338 -206.258668) (xy 58.546995 -207.077564) (xy 59.966096 -207.077564)
			(xy 59.970167 -207.021942) (xy 59.982293 -206.967505) (xy 60.002216 -206.915414) (xy 60.029512 -206.866779)
			(xy 60.063598 -206.822636) (xy 60.103747 -206.783927) (xy 60.149105 -206.751476) (xy 60.198705 -206.725975)
			(xy 60.251489 -206.707968) (xy 60.306332 -206.697838) (xy 60.362066 -206.695801) (xy 60.417503 -206.701901)
			(xy 60.47146 -206.716007) (xy 60.522789 -206.737819) (xy 60.570395 -206.766873) (xy 60.613263 -206.802548)
			(xy 60.65048 -206.844085) (xy 60.681253 -206.890598) (xy 60.704925 -206.941095) (xy 60.713505 -206.969614)
			(xy 60.883798 -206.969614) (xy 60.887869 -206.913992) (xy 60.899995 -206.859555) (xy 60.919918 -206.807464)
			(xy 60.947214 -206.758829) (xy 60.9813 -206.714686) (xy 61.021449 -206.675977) (xy 61.066807 -206.643526)
			(xy 61.116407 -206.618025) (xy 61.169191 -206.600018) (xy 61.224034 -206.589888) (xy 61.279768 -206.587851)
			(xy 61.335205 -206.593951) (xy 61.389162 -206.608057) (xy 61.440491 -206.629869) (xy 61.488097 -206.658923)
			(xy 61.530965 -206.694598) (xy 61.568182 -206.736135) (xy 61.598955 -206.782648) (xy 61.622627 -206.833145)
			(xy 61.638695 -206.886552) (xy 61.646815 -206.941728) (xy 61.647324 -206.969614) (xy 61.646815 -206.9975)
			(xy 61.638695 -207.052676) (xy 61.622627 -207.106083) (xy 61.598955 -207.15658) (xy 61.568182 -207.203093)
			(xy 61.530965 -207.24463) (xy 61.488097 -207.280305) (xy 61.440491 -207.309359) (xy 61.389162 -207.331171)
			(xy 61.335205 -207.345277) (xy 61.279768 -207.351377) (xy 61.224034 -207.34934) (xy 61.169191 -207.33921)
			(xy 61.116407 -207.321203) (xy 61.066807 -207.295702) (xy 61.021449 -207.263251) (xy 60.9813 -207.224542)
			(xy 60.947214 -207.180399) (xy 60.919918 -207.131764) (xy 60.899995 -207.079673) (xy 60.887869 -207.025236)
			(xy 60.883798 -206.969614) (xy 60.713505 -206.969614) (xy 60.720993 -206.994502) (xy 60.729113 -207.049678)
			(xy 60.729622 -207.077564) (xy 60.729113 -207.10545) (xy 60.720993 -207.160626) (xy 60.704925 -207.214033)
			(xy 60.681253 -207.26453) (xy 60.65048 -207.311043) (xy 60.613263 -207.35258) (xy 60.570395 -207.388255)
			(xy 60.522789 -207.417309) (xy 60.47146 -207.439121) (xy 60.417503 -207.453227) (xy 60.362066 -207.459327)
			(xy 60.306332 -207.45729) (xy 60.251489 -207.44716) (xy 60.198705 -207.429153) (xy 60.149105 -207.403652)
			(xy 60.103747 -207.371201) (xy 60.063598 -207.332492) (xy 60.029512 -207.288349) (xy 60.002216 -207.239714)
			(xy 59.982293 -207.187623) (xy 59.970167 -207.133186) (xy 59.966096 -207.077564) (xy 58.546995 -207.077564)
			(xy 58.496795 -208.026) (xy 62.180976 -208.026) (xy 62.185047 -207.970378) (xy 62.197173 -207.915941)
			(xy 62.217096 -207.86385) (xy 62.244392 -207.815215) (xy 62.278478 -207.771072) (xy 62.318627 -207.732363)
			(xy 62.363985 -207.699912) (xy 62.413585 -207.674411) (xy 62.466369 -207.656404) (xy 62.521212 -207.646274)
			(xy 62.576946 -207.644237) (xy 62.632383 -207.650337) (xy 62.68634 -207.664443) (xy 62.737669 -207.686255)
			(xy 62.785275 -207.715309) (xy 62.828143 -207.750984) (xy 62.86536 -207.792521) (xy 62.896133 -207.839034)
			(xy 62.919805 -207.889531) (xy 62.935873 -207.942938) (xy 62.943993 -207.998114) (xy 62.944502 -208.026)
			(xy 62.943993 -208.053886) (xy 62.935873 -208.109062) (xy 62.919805 -208.162469) (xy 62.896133 -208.212966)
			(xy 62.86536 -208.259479) (xy 62.828143 -208.301016) (xy 62.785275 -208.336691) (xy 62.737669 -208.365745)
			(xy 62.68634 -208.387557) (xy 62.632383 -208.401663) (xy 62.576946 -208.407763) (xy 62.521212 -208.405726)
			(xy 62.466369 -208.395596) (xy 62.413585 -208.377589) (xy 62.363985 -208.352088) (xy 62.318627 -208.319637)
			(xy 62.278478 -208.280928) (xy 62.244392 -208.236785) (xy 62.217096 -208.18815) (xy 62.197173 -208.136059)
			(xy 62.185047 -208.081622) (xy 62.180976 -208.026) (xy 58.496795 -208.026) (xy 58.429535 -209.296762)
			(xy 62.751206 -209.296762) (xy 62.755277 -209.24114) (xy 62.767403 -209.186703) (xy 62.787326 -209.134612)
			(xy 62.814622 -209.085977) (xy 62.848708 -209.041834) (xy 62.888857 -209.003125) (xy 62.934215 -208.970674)
			(xy 62.983815 -208.945173) (xy 63.036599 -208.927166) (xy 63.091442 -208.917036) (xy 63.147176 -208.914999)
			(xy 63.202613 -208.921099) (xy 63.25657 -208.935205) (xy 63.307899 -208.957017) (xy 63.355505 -208.986071)
			(xy 63.398373 -209.021746) (xy 63.43559 -209.063283) (xy 63.466363 -209.109796) (xy 63.490035 -209.160293)
			(xy 63.506103 -209.2137) (xy 63.514223 -209.268876) (xy 63.514732 -209.296762) (xy 63.514223 -209.324648)
			(xy 63.506103 -209.379824) (xy 63.490035 -209.433231) (xy 63.466363 -209.483728) (xy 63.43559 -209.530241)
			(xy 63.398373 -209.571778) (xy 63.355505 -209.607453) (xy 63.307899 -209.636507) (xy 63.25657 -209.658319)
			(xy 63.202613 -209.672425) (xy 63.147176 -209.678525) (xy 63.091442 -209.676488) (xy 63.036599 -209.666358)
			(xy 62.983815 -209.648351) (xy 62.934215 -209.62285) (xy 62.888857 -209.590399) (xy 62.848708 -209.55169)
			(xy 62.814622 -209.507547) (xy 62.787326 -209.458912) (xy 62.767403 -209.406821) (xy 62.755277 -209.352384)
			(xy 62.751206 -209.296762) (xy 58.429535 -209.296762) (xy 58.256148 -212.5726) (xy 60.171582 -212.5726)
			(xy 60.175653 -212.516978) (xy 60.187779 -212.462541) (xy 60.207702 -212.41045) (xy 60.234998 -212.361815)
			(xy 60.269084 -212.317672) (xy 60.309233 -212.278963) (xy 60.354591 -212.246512) (xy 60.404191 -212.221011)
			(xy 60.456975 -212.203004) (xy 60.511818 -212.192874) (xy 60.567552 -212.190837) (xy 60.622989 -212.196937)
			(xy 60.676946 -212.211043) (xy 60.728275 -212.232855) (xy 60.775881 -212.261909) (xy 60.818749 -212.297584)
			(xy 60.855966 -212.339121) (xy 60.886739 -212.385634) (xy 60.910411 -212.436131) (xy 60.926479 -212.489538)
			(xy 60.934599 -212.544714) (xy 60.935108 -212.5726) (xy 60.934599 -212.600486) (xy 60.926479 -212.655662)
			(xy 60.910411 -212.709069) (xy 60.886739 -212.759566) (xy 60.855966 -212.806079) (xy 60.818749 -212.847616)
			(xy 60.775881 -212.883291) (xy 60.728275 -212.912345) (xy 60.676946 -212.934157) (xy 60.622989 -212.948263)
			(xy 60.567552 -212.954363) (xy 60.511818 -212.952326) (xy 60.456975 -212.942196) (xy 60.404191 -212.924189)
			(xy 60.354591 -212.898688) (xy 60.309233 -212.866237) (xy 60.269084 -212.827528) (xy 60.234998 -212.783385)
			(xy 60.207702 -212.73475) (xy 60.187779 -212.682659) (xy 60.175653 -212.628222) (xy 60.171582 -212.5726)
			(xy 58.256148 -212.5726) (xy 57.681876 -223.422464) (xy 57.682372 -223.434294) (xy 57.69274 -223.45555)
			(xy 57.711529 -223.46991) (xy 57.723024 -223.472756) (xy 58.944764 -223.709992) (xy 61.74486 -224.253298)
			(xy 61.754088 -224.254072) (xy 61.772076 -224.249738) (xy 61.787346 -224.239287) (xy 61.797898 -224.224088)
			(xy 61.800486 -224.215198) (xy 63.874142 -212.934804) (xy 63.87535 -212.926859) (xy 63.873283 -212.910931)
			(xy 63.870078 -212.903562) (xy 63.86322 -212.889338) (xy 63.856108 -212.885274) (xy 63.852298 -212.883242)
			(xy 63.826701 -212.868832) (xy 63.779874 -212.833371) (xy 63.739029 -212.791157) (xy 63.70513 -212.743188)
			(xy 63.678977 -212.690593) (xy 63.661185 -212.634613) (xy 63.652175 -212.576569) (xy 63.651638 -212.5472)
			(xy 63.652088 -212.520648) (xy 63.659435 -212.468055) (xy 63.673999 -212.416987) (xy 63.695501 -212.368431)
			(xy 63.723525 -212.323324) (xy 63.75753 -212.282536) (xy 63.796861 -212.246854) (xy 63.840757 -212.216969)
			(xy 63.888371 -212.193455) (xy 63.938785 -212.176767) (xy 63.96482 -212.171534) (xy 63.971932 -212.170264)
			(xy 63.985394 -212.16366) (xy 64.01054 -212.13953) (xy 64.016124 -212.133771) (xy 64.023746 -212.119667)
			(xy 64.025526 -212.111844) (xy 64.123824 -211.576412) (xy 64.125262 -211.566079) (xy 64.120678 -211.545749)
			(xy 64.114934 -211.537042) (xy 64.101472 -211.518754) (xy 64.070992 -211.477352) (xy 64.067878 -211.473289)
			(xy 64.060331 -211.466374) (xy 64.056006 -211.463636) (xy 64.047624 -211.45881) (xy 64.036702 -211.457286)
			(xy 64.009432 -211.45329) (xy 63.956348 -211.43847) (xy 63.905948 -211.41617) (xy 63.859279 -211.386853)
			(xy 63.817311 -211.351128) (xy 63.780918 -211.30974) (xy 63.750855 -211.263547) (xy 63.727748 -211.213511)
			(xy 63.712078 -211.160672) (xy 63.70417 -211.106129) (xy 63.703708 -211.078572) (xy 63.704196 -211.051303)
			(xy 63.711961 -210.997321) (xy 63.727329 -210.944993) (xy 63.749986 -210.895385) (xy 63.779472 -210.849505)
			(xy 63.815187 -210.808288) (xy 63.856403 -210.772573) (xy 63.902283 -210.743087) (xy 63.951891 -210.720429)
			(xy 64.004219 -210.705061) (xy 64.058201 -210.697296) (xy 64.08547 -210.69681) (xy 64.107976 -210.697169)
			(xy 64.152669 -210.702519) (xy 64.174624 -210.707478) (xy 64.180974 -210.709002) (xy 64.181482 -210.709002)
			(xy 64.184276 -210.709764) (xy 64.185038 -210.710018) (xy 64.194944 -210.70824) (xy 64.199924 -210.707215)
			(xy 64.209385 -210.703499) (xy 64.21374 -210.700874) (xy 64.278764 -210.65871) (xy 64.287908 -210.64982)
			(xy 64.289686 -210.64728) (xy 64.29235 -210.643313) (xy 64.296316 -210.634621) (xy 64.29756 -210.630008)
			(xy 64.298322 -210.62696) (xy 64.412622 -210.00466) (xy 64.495934 -209.551778) (xy 64.49441 -209.538316)
			(xy 64.491362 -209.530696) (xy 64.481948 -209.507202) (xy 64.468706 -209.45835) (xy 64.462049 -209.408175)
			(xy 64.461644 -209.382868) (xy 64.461644 -209.38236) (xy 64.462165 -209.353251) (xy 64.470955 -209.2957)
			(xy 64.488386 -209.240153) (xy 64.514052 -209.187898) (xy 64.547359 -209.140149) (xy 64.567054 -209.118708)
			(xy 64.572134 -209.113374) (xy 64.575182 -209.107786) (xy 64.577034 -209.104244) (xy 64.579721 -209.096717)
			(xy 64.580516 -209.0928) (xy 64.644778 -208.742534) (xy 64.645894 -208.732237) (xy 64.640768 -208.71219)
			(xy 64.634872 -208.703672) (xy 64.581278 -208.641188) (xy 64.577494 -208.637077) (xy 64.568524 -208.630421)
			(xy 64.563498 -208.62798) (xy 64.553592 -208.623408) (xy 64.545972 -208.623408) (xy 64.530986 -208.623916)
			(xy 64.530732 -208.623916) (xy 64.505466 -208.623529) (xy 64.455371 -208.616905) (xy 64.406588 -208.60373)
			(xy 64.35997 -208.584234) (xy 64.337946 -208.571846) (xy 64.332104 -208.568798) (xy 64.308678 -208.558527)
			(xy 64.264574 -208.532618) (xy 64.224326 -208.50105) (xy 64.188656 -208.464389) (xy 64.1731 -208.444084)
			(xy 64.164238 -208.432931) (xy 64.14162 -208.415633) (xy 64.115106 -208.405252) (xy 64.086756 -208.402597)
			(xy 64.058774 -208.407872) (xy 64.033338 -208.420669) (xy 64.012424 -208.439993) (xy 64.004698 -208.451958)
			(xy 63.989771 -208.475699) (xy 63.954059 -208.518935) (xy 63.91241 -208.556487) (xy 63.86572 -208.587548)
			(xy 63.814991 -208.611451) (xy 63.761313 -208.627683) (xy 63.705839 -208.635894) (xy 63.6778 -208.636362)
			(xy 63.650531 -208.635876) (xy 63.596547 -208.628114) (xy 63.544217 -208.612749) (xy 63.494607 -208.590092)
			(xy 63.448726 -208.560606) (xy 63.407509 -208.524891) (xy 63.371794 -208.483674) (xy 63.342308 -208.437793)
			(xy 63.319651 -208.388183) (xy 63.304286 -208.335853) (xy 63.296524 -208.281869) (xy 63.296524 -208.227331)
			(xy 63.304286 -208.173347) (xy 63.319651 -208.121017) (xy 63.342308 -208.071407) (xy 63.371794 -208.025526)
			(xy 63.407509 -207.984309) (xy 63.448726 -207.948594) (xy 63.494607 -207.919108) (xy 63.544217 -207.896451)
			(xy 63.596547 -207.881086) (xy 63.650531 -207.873324) (xy 63.6778 -207.872838) (xy 63.707506 -207.873402)
			(xy 63.766202 -207.882599) (xy 63.822766 -207.900771) (xy 63.875836 -207.927479) (xy 63.924132 -207.96208)
			(xy 63.96649 -208.003741) (xy 63.984632 -208.02727) (xy 63.993492 -208.038422) (xy 64.016104 -208.055719)
			(xy 64.042615 -208.066097) (xy 64.070961 -208.068749) (xy 64.098937 -208.063467) (xy 64.124365 -208.050664)
			(xy 64.145267 -208.031334) (xy 64.153034 -208.019396) (xy 64.167963 -207.995659) (xy 64.203679 -207.952431)
			(xy 64.24533 -207.914886) (xy 64.29202 -207.883833) (xy 64.342748 -207.859937) (xy 64.396424 -207.843712)
			(xy 64.451895 -207.835507) (xy 64.479932 -207.834992) (xy 64.505133 -207.835417) (xy 64.555091 -207.842085)
			(xy 64.60374 -207.855262) (xy 64.650235 -207.874718) (xy 64.67221 -207.887062) (xy 64.678052 -207.89011)
			(xy 64.69205 -207.896141) (xy 64.719132 -207.910129) (xy 64.732154 -207.91805) (xy 64.734948 -207.919574)
			(xy 64.758824 -207.924146) (xy 64.765673 -207.925184) (xy 64.77946 -207.923887) (xy 64.786002 -207.921606)
			(xy 64.796162 -207.917796) (xy 64.872362 -207.50403) (xy 64.984884 -206.89189) (xy 65.021968 -206.68996)
			(xy 65.018158 -206.68742) (xy 64.980312 -206.67472) (xy 64.955308 -206.66591) (xy 64.907816 -206.642356)
			(xy 64.864039 -206.612457) (xy 64.824819 -206.57679) (xy 64.790911 -206.53604) (xy 64.762967 -206.49099)
			(xy 64.741524 -206.442508) (xy 64.726995 -206.391525) (xy 64.719658 -206.339022) (xy 64.7192 -206.312516)
			(xy 64.719685 -206.285245) (xy 64.727445 -206.231258) (xy 64.742808 -206.178924) (xy 64.765463 -206.129309)
			(xy 64.794948 -206.083424) (xy 64.830663 -206.042201) (xy 64.87188 -206.00648) (xy 64.917762 -205.976989)
			(xy 64.967373 -205.954327) (xy 65.019705 -205.938956) (xy 65.073691 -205.931189) (xy 65.100962 -205.930754)
			(xy 65.116964 -205.931008) (xy 65.156334 -205.932786) (xy 65.161414 -205.931516) (xy 69.259958 -183.635904)
			(xy 73.358756 -161.340038) (xy 73.359264 -161.33699) (xy 73.906888 -156.7434) (xy 73.907227 -156.739715)
			(xy 73.90697 -156.732321) (xy 73.90638 -156.728668) (xy 73.905364 -156.722826) (xy 73.902316 -156.715968)
			(xy 73.890041 -156.688177) (xy 73.873456 -156.629732) (xy 73.869296 -156.599636) (xy 73.868788 -156.595064)
			(xy 73.867814 -156.58506) (xy 73.866797 -156.564983) (xy 73.866756 -156.554932) (xy 73.867171 -156.529256)
			(xy 73.874049 -156.478368) (xy 73.887685 -156.42886) (xy 73.907833 -156.381627) (xy 73.93413 -156.33752)
			(xy 73.949814 -156.317188) (xy 73.950068 -156.316934) (xy 73.953972 -156.31176) (xy 73.959249 -156.299928)
			(xy 73.960482 -156.293566) (xy 73.997566 -155.981908) (xy 74.093832 -155.172918) (xy 74.097388 -155.143708)
			(xy 74.098163 -155.133538) (xy 74.09255 -155.113949) (xy 74.079756 -155.098088) (xy 74.070972 -155.092908)
			(xy 74.070718 -155.092654) (xy 74.047973 -155.080219) (xy 74.005767 -155.050124) (xy 73.96803 -155.014586)
			(xy 73.935457 -154.974262) (xy 73.90865 -154.929894) (xy 73.888104 -154.882304) (xy 73.874197 -154.832367)
			(xy 73.867187 -154.781007) (xy 73.866756 -154.755088) (xy 73.866835 -154.74235) (xy 73.868489 -154.716929)
			(xy 73.870058 -154.704288) (xy 73.874272 -154.676619) (xy 73.889743 -154.622832) (xy 73.912896 -154.571879)
			(xy 73.943235 -154.524848) (xy 73.980111 -154.482746) (xy 74.001122 -154.464258) (xy 74.022294 -154.446921)
			(xy 74.06865 -154.417843) (xy 74.118674 -154.395663) (xy 74.144886 -154.387804) (xy 74.1553 -154.384502)
			(xy 74.182224 -154.354022) (xy 74.187164 -154.348075) (xy 74.193486 -154.333977) (xy 74.19467 -154.326336)
			(xy 74.757026 -149.60981) (xy 74.769726 -149.503384) (xy 74.811128 -149.156166) (xy 74.811382 -149.152102)
			(xy 74.986896 -144.881092) (xy 75.01128 -144.287494) (xy 75.116944 -141.71676) (xy 75.119339 -141.670421)
			(xy 75.131675 -141.578449) (xy 75.141582 -141.533118) (xy 75.265026 -140.998702) (xy 75.266296 -140.989812)
			(xy 75.473814 -136.095232) (xy 75.553316 -134.218934) (xy 75.553316 -131.097782) (xy 75.553824 -131.068826)
			(xy 75.553824 -131.068318) (xy 75.554332 -131.056888) (xy 76.083922 -118.147084) (xy 76.084936 -118.125431)
			(xy 76.088621 -118.082236) (xy 76.091288 -118.060724) (xy 76.66355 -113.613438) (xy 76.664295 -113.60586)
			(xy 76.661717 -113.590861) (xy 76.65847 -113.583974) (xy 76.655422 -113.577878) (xy 76.645262 -113.56721)
			(xy 76.637896 -113.563146) (xy 76.620116 -113.552224) (xy 76.619608 -113.552224) (xy 76.596027 -113.536645)
			(xy 76.553305 -113.499646) (xy 76.516504 -113.456753) (xy 76.486427 -113.408905) (xy 76.463732 -113.357146)
			(xy 76.448914 -113.302607) (xy 76.44511 -113.274602) (xy 76.444094 -113.264442) (xy 76.442316 -113.230152)
			(xy 76.442316 -113.229644) (xy 76.442801 -113.20306) (xy 76.450229 -113.150412) (xy 76.464894 -113.099305)
			(xy 76.486509 -113.050727) (xy 76.514658 -113.00562) (xy 76.548795 -112.964857) (xy 76.588259 -112.929226)
			(xy 76.632287 -112.899418) (xy 76.65593 -112.887252) (xy 76.673389 -112.878912) (xy 76.709654 -112.865419)
			(xy 76.72832 -112.860328) (xy 76.728828 -112.860074) (xy 76.736002 -112.857962) (xy 76.748794 -112.850227)
			(xy 76.753974 -112.844834) (xy 76.758546 -112.8395) (xy 76.764896 -112.825784) (xy 77.04963 -110.612428)
			(xy 77.566266 -106.598974) (xy 77.566718 -106.594849) (xy 77.566462 -106.586554) (xy 77.565758 -106.582464)
			(xy 77.564234 -106.575352) (xy 77.56017 -106.567986) (xy 77.545466 -106.539725) (xy 77.524635 -106.479525)
			(xy 77.514077 -106.416703) (xy 77.513434 -106.384852) (xy 77.513434 -106.383328) (xy 77.513434 -106.369358)
			(xy 77.513688 -106.364786) (xy 77.514958 -106.349292) (xy 77.516736 -106.334052) (xy 77.521447 -106.303679)
			(xy 77.539293 -106.244867) (xy 77.566319 -106.189668) (xy 77.601827 -106.139504) (xy 77.622908 -106.117136)
			(xy 77.629004 -106.110786) (xy 77.794612 -104.823006) (xy 77.794612 -104.822498) (xy 77.799262 -104.78136)
			(xy 77.814518 -104.699983) (xy 77.836459 -104.620149) (xy 77.864936 -104.542405) (xy 77.899752 -104.467287)
			(xy 77.919834 -104.431084) (xy 88.490044 -85.816948) (xy 88.494414 -85.808504) (xy 88.497172 -85.789707)
			(xy 88.495378 -85.780372) (xy 88.477852 -85.704172) (xy 88.467438 -85.688678) (xy 88.460834 -85.684106)
			(xy 88.439275 -85.668785) (xy 88.400195 -85.633148) (xy 88.366412 -85.592453) (xy 88.338574 -85.547483)
			(xy 88.317215 -85.499098) (xy 88.302744 -85.448227) (xy 88.295438 -85.395845) (xy 88.294972 -85.3694)
			(xy 88.295476 -85.341663) (xy 88.303521 -85.286775) (xy 88.319425 -85.23363) (xy 88.342854 -85.183346)
			(xy 88.373315 -85.136983) (xy 88.410166 -85.095518) (xy 88.452631 -85.059824) (xy 88.499816 -85.030652)
			(xy 88.550726 -85.008617) (xy 88.604289 -84.994183) (xy 88.631776 -84.990432) (xy 88.645492 -84.988908)
			(xy 88.67648 -84.987638) (xy 88.676734 -84.987638) (xy 88.703936 -84.988125) (xy 88.757791 -84.995848)
			(xy 88.810009 -85.011118) (xy 88.834976 -85.021928) (xy 88.843866 -85.025992) (xy 88.852756 -85.0265)
			(xy 88.857645 -85.026758) (xy 88.867368 -85.025612) (xy 88.87206 -85.024214) (xy 88.8873 -85.019134)
			(xy 88.936576 -85.003132) (xy 88.945373 -84.999801) (xy 88.959959 -84.987945) (xy 88.965024 -84.980018)
			(xy 92.095066 -79.468218) (xy 92.119132 -79.426967) (xy 92.174004 -79.348795) (xy 92.236085 -79.276216)
			(xy 92.270072 -79.242666) (xy 92.27058 -79.242158) (xy 94.44736 -77.060298) (xy 94.447614 -77.060044)
			(xy 94.46006 -77.047344) (xy 94.461584 -77.046074) (xy 94.473522 -77.034136) (xy 94.494233 -77.013669)
			(xy 94.537694 -76.974907) (xy 94.56039 -76.956666) (xy 98.740468 -73.655428) (xy 98.740976 -73.65492)
			(xy 98.976434 -73.461626) (xy 98.976688 -73.461372) (xy 98.981768 -73.457308) (xy 101.85019 -69.279262)
			(xy 101.856468 -69.268898) (xy 101.859516 -69.244894) (xy 101.856032 -69.233288) (xy 101.832156 -69.166486)
			(xy 101.829926 -69.160895) (xy 101.823253 -69.150881) (xy 101.818948 -69.146674) (xy 101.818694 -69.14642)
			(xy 101.794564 -69.124068) (xy 101.786944 -69.121528) (xy 101.783388 -69.120512) (xy 101.768402 -69.115432)
			(xy 101.744018 -69.10578) (xy 101.728753 -69.098849) (xy 101.699372 -69.082701) (xy 101.685344 -69.073522)
			(xy 101.654864 -69.050662) (xy 101.646706 -69.043873) (xy 101.631075 -69.029515) (xy 101.623622 -69.02196)
			(xy 101.616764 -69.014848) (xy 101.589586 -69.002656) (xy 101.581966 -69.000116) (xy 101.569012 -68.998338)
			(xy 101.515926 -68.998338) (xy 101.510084 -68.998592) (xy 101.49713 -69.001894) (xy 101.46792 -69.014594)
			(xy 101.461062 -69.02196) (xy 101.442995 -69.03997) (xy 101.402915 -69.071531) (xy 101.358995 -69.097484)
			(xy 101.312015 -69.117368) (xy 101.262808 -69.130829) (xy 101.212249 -69.13763) (xy 101.186742 -69.138038)
			(xy 101.161232 -69.137609) (xy 101.110668 -69.130808) (xy 101.06146 -69.117333) (xy 101.014484 -69.097425)
			(xy 100.970578 -69.071438) (xy 100.950268 -69.055996) (xy 100.94722 -69.053456) (xy 100.945696 -69.05244)
			(xy 100.939092 -69.049138) (xy 100.933869 -69.046797) (xy 100.922715 -69.04424) (xy 100.916994 -69.044058)
			(xy 100.88499 -69.044058) (xy 100.88499 -69.032882) (xy 100.83419 -69.032882) (xy 100.825589 -69.033224)
			(xy 100.809366 -69.038945) (xy 100.80244 -69.044058) (xy 100.800916 -69.045328) (xy 100.780039 -69.062719)
			(xy 100.734288 -69.092033) (xy 100.684839 -69.114555) (xy 100.632695 -69.12983) (xy 100.57891 -69.137549)
			(xy 100.551742 -69.138038) (xy 100.524486 -69.137578) (xy 100.470529 -69.129826) (xy 100.418225 -69.114474)
			(xy 100.368637 -69.091834) (xy 100.322777 -69.062368) (xy 100.281576 -69.026675) (xy 100.245875 -68.985481)
			(xy 100.2164 -68.939626) (xy 100.193751 -68.890043) (xy 100.178389 -68.837741) (xy 100.170627 -68.783786)
			(xy 100.170234 -68.75653) (xy 100.170657 -68.731018) (xy 100.177448 -68.680448) (xy 100.190912 -68.631233)
			(xy 100.210811 -68.584249) (xy 100.23679 -68.540334) (xy 100.252276 -68.520056) (xy 100.254816 -68.517008)
			(xy 100.255832 -68.515484) (xy 100.259134 -68.50888) (xy 100.261471 -68.503656) (xy 100.264022 -68.492502)
			(xy 100.264214 -68.486782) (xy 100.264214 -68.454778) (xy 100.27539 -68.454778) (xy 100.27539 -68.403978)
			(xy 100.275062 -68.395372) (xy 100.26936 -68.379133) (xy 100.264214 -68.372228) (xy 100.262944 -68.370704)
			(xy 100.245554 -68.349826) (xy 100.216245 -68.304074) (xy 100.193726 -68.254626) (xy 100.178453 -68.202481)
			(xy 100.170737 -68.148697) (xy 100.170234 -68.12153) (xy 100.170695 -68.094277) (xy 100.178449 -68.040325)
			(xy 100.193803 -67.988026) (xy 100.216444 -67.938445) (xy 100.245912 -67.892591) (xy 100.281606 -67.851398)
			(xy 100.3228 -67.815705) (xy 100.368655 -67.786239) (xy 100.418237 -67.763599) (xy 100.470537 -67.748246)
			(xy 100.524489 -67.740494) (xy 100.551742 -67.740022) (xy 100.577252 -67.740449) (xy 100.627818 -67.747249)
			(xy 100.677028 -67.760721) (xy 100.724006 -67.780626) (xy 100.767915 -67.806609) (xy 100.788216 -67.822064)
			(xy 100.791264 -67.824604) (xy 100.792788 -67.82562) (xy 100.799392 -67.828922) (xy 100.804615 -67.831262)
			(xy 100.815769 -67.83382) (xy 100.82149 -67.834002) (xy 100.853494 -67.834002) (xy 100.853494 -67.845178)
			(xy 100.904294 -67.845178) (xy 100.912895 -67.844838) (xy 100.929119 -67.839117) (xy 100.936044 -67.834002)
			(xy 100.937568 -67.832732) (xy 100.958446 -67.815341) (xy 101.004197 -67.786029) (xy 101.053645 -67.763507)
			(xy 101.10579 -67.748231) (xy 101.159574 -67.740511) (xy 101.186742 -67.740022) (xy 101.21225 -67.740442)
			(xy 101.262814 -67.747224) (xy 101.312026 -67.760674) (xy 101.35901 -67.780553) (xy 101.40293 -67.806508)
			(xy 101.443006 -67.838077) (xy 101.461062 -67.8561) (xy 101.46792 -67.863466) (xy 101.49713 -67.876166)
			(xy 101.510084 -67.879468) (xy 101.515926 -67.879722) (xy 101.568758 -67.879722) (xy 101.5746 -67.879468)
			(xy 101.587554 -67.876166) (xy 101.616764 -67.863466) (xy 101.623622 -67.8561) (xy 101.64169 -67.838091)
			(xy 101.68177 -67.806535) (xy 101.72569 -67.780587) (xy 101.772671 -67.760711) (xy 101.821877 -67.747258)
			(xy 101.872436 -67.740467) (xy 101.897942 -67.740022) (xy 101.92519 -67.740511) (xy 101.979132 -67.748273)
			(xy 102.03142 -67.763632) (xy 102.08099 -67.786276) (xy 102.126833 -67.815744) (xy 102.168016 -67.851435)
			(xy 102.2037 -67.892625) (xy 102.233159 -67.938473) (xy 102.255793 -67.988048) (xy 102.271143 -68.040338)
			(xy 102.278894 -68.094281) (xy 102.27945 -68.12153) (xy 102.279023 -68.147041) (xy 102.272225 -68.197607)
			(xy 102.258753 -68.246817) (xy 102.238848 -68.293795) (xy 102.212865 -68.337704) (xy 102.197408 -68.358004)
			(xy 102.194868 -68.361052) (xy 102.193852 -68.362576) (xy 102.19055 -68.36918) (xy 102.188206 -68.374402)
			(xy 102.185641 -68.385556) (xy 102.18547 -68.391278) (xy 102.18547 -68.423282) (xy 102.174294 -68.423282)
			(xy 102.174294 -68.474082) (xy 102.174631 -68.482685) (xy 102.180347 -68.498913) (xy 102.18547 -68.505832)
			(xy 102.18674 -68.507356) (xy 102.191312 -68.51269) (xy 102.191566 -68.512944) (xy 102.192836 -68.514468)
			(xy 102.203504 -68.527676) (xy 102.203504 -68.528184) (xy 102.204012 -68.528438) (xy 102.207673 -68.532977)
			(xy 102.216653 -68.540413) (xy 102.221792 -68.54317) (xy 102.227126 -68.54571) (xy 102.23881 -68.54825)
			(xy 102.268274 -68.547742) (xy 102.327456 -68.546218) (xy 102.339482 -68.545308) (xy 102.360685 -68.533891)
			(xy 102.368096 -68.524374) (xy 102.568756 -68.231766) (xy 102.705916 -68.032122) (xy 102.708856 -68.027591)
			(xy 102.712964 -68.017602) (xy 102.714044 -68.01231) (xy 102.715822 -68.001642) (xy 102.6922 -67.914012)
			(xy 102.68966 -67.907662) (xy 102.665276 -67.883278) (xy 102.657656 -67.879468) (xy 102.634165 -67.867279)
			(xy 102.590495 -67.837385) (xy 102.551378 -67.801741) (xy 102.517564 -67.76103) (xy 102.489704 -67.716035)
			(xy 102.468333 -67.66762) (xy 102.45386 -67.616716) (xy 102.446566 -67.564299) (xy 102.446074 -67.537838)
			(xy 102.446534 -67.510583) (xy 102.454287 -67.456627) (xy 102.469639 -67.404323) (xy 102.492279 -67.354737)
			(xy 102.521746 -67.308878) (xy 102.55744 -67.267679) (xy 102.598633 -67.23198) (xy 102.644488 -67.202506)
			(xy 102.694071 -67.179859) (xy 102.746372 -67.164499) (xy 102.800327 -67.156738) (xy 102.827582 -67.15633)
			(xy 102.853867 -67.156779) (xy 102.905935 -67.164026) (xy 102.95651 -67.17837) (xy 103.004629 -67.199539)
			(xy 103.027226 -67.212972) (xy 103.027734 -67.212972) (xy 103.027988 -67.213226) (xy 103.033205 -67.216172)
			(xy 103.04463 -67.219763) (xy 103.050594 -67.220338) (xy 103.062786 -67.221354) (xy 103.150924 -67.182492)
			(xy 103.161565 -67.177143) (xy 103.176795 -67.158871) (xy 103.180134 -67.14744) (xy 104.497886 -60.311792)
			(xy 105.182924 -56.758332) (xy 105.184302 -56.748781) (xy 105.180656 -56.729847) (xy 105.175812 -56.721502)
			(xy 105.172764 -56.716676) (xy 105.1687 -56.710326) (xy 105.16108 -56.701436) (xy 105.160572 -56.700928)
			(xy 105.155492 -56.696356) (xy 105.131777 -56.684234) (xy 105.087659 -56.654397) (xy 105.048118 -56.618718)
			(xy 105.01392 -56.577887) (xy 104.98573 -56.5327) (xy 104.964096 -56.484032) (xy 104.949438 -56.432829)
			(xy 104.94204 -56.380086) (xy 104.941624 -56.353456) (xy 104.942095 -56.326362) (xy 104.949756 -56.272718)
			(xy 104.96493 -56.220697) (xy 104.987313 -56.171348) (xy 105.016455 -56.125662) (xy 105.051768 -56.084561)
			(xy 105.092542 -56.04887) (xy 105.137957 -56.019308) (xy 105.16235 -56.007508) (xy 105.162604 -56.007508)
			(xy 105.170997 -56.003147) (xy 105.184038 -55.989465) (xy 105.191242 -55.971991) (xy 105.191814 -55.96255)
			(xy 105.18394 -55.485284) (xy 105.183609 -55.478298) (xy 105.179605 -55.464902) (xy 105.176066 -55.458868)
			(xy 105.155492 -55.42661) (xy 105.148888 -55.423054) (xy 105.145078 -55.421276) (xy 105.143808 -55.420514)
			(xy 105.118034 -55.406142) (xy 105.07086 -55.370689) (xy 105.029699 -55.328402) (xy 104.995531 -55.280289)
			(xy 104.96917 -55.227494) (xy 104.951241 -55.171272) (xy 104.942172 -55.112962) (xy 104.941624 -55.083456)
			(xy 104.942172 -55.053952) (xy 104.951254 -54.995648) (xy 104.96921 -54.939439) (xy 104.995612 -54.886668)
			(xy 105.029828 -54.838594) (xy 105.071042 -54.796365) (xy 105.11827 -54.76099) (xy 105.144062 -54.746652)
			(xy 105.14711 -54.744874) (xy 105.154151 -54.740119) (xy 105.164829 -54.726918) (xy 105.170581 -54.710942)
			(xy 105.170986 -54.702456) (xy 105.169208 -54.597046) (xy 105.166922 -54.443884) (xy 105.166099 -54.435369)
			(xy 105.159527 -54.419585) (xy 105.148109 -54.40686) (xy 105.14076 -54.402482) (xy 105.140506 -54.402482)
			(xy 105.115113 -54.388008) (xy 105.068661 -54.352538) (xy 105.028164 -54.310396) (xy 104.994571 -54.262569)
			(xy 104.968669 -54.210176) (xy 104.951064 -54.154444) (xy 104.942168 -54.096679) (xy 104.941624 -54.067456)
			(xy 104.942143 -54.039142) (xy 104.950521 -53.983137) (xy 104.967086 -53.928985) (xy 104.991474 -53.877878)
			(xy 105.023149 -53.830937) (xy 105.061416 -53.789194) (xy 105.105433 -53.753568) (xy 105.129584 -53.73878)
			(xy 105.135443 -53.73509) (xy 105.145102 -53.725177) (xy 105.148634 -53.719222) (xy 105.151428 -53.714142)
			(xy 105.154476 -53.701188) (xy 105.154222 -53.683154) (xy 105.149904 -53.4162) (xy 105.149163 -53.410634)
			(xy 105.145568 -53.399999) (xy 105.142792 -53.395118) (xy 105.125774 -53.3781) (xy 105.123234 -53.376576)
			(xy 105.09905 -53.361103) (xy 105.055197 -53.324049) (xy 105.017394 -53.280841) (xy 104.986496 -53.232453)
			(xy 104.963201 -53.17998) (xy 104.948035 -53.124608) (xy 104.944164 -53.09616) (xy 104.943148 -53.08727)
			(xy 104.943148 -53.086762) (xy 104.94264 -53.082698) (xy 104.94137 -53.05171) (xy 104.94137 -53.051456)
			(xy 104.941841 -53.024339) (xy 104.949505 -52.970649) (xy 104.964687 -52.918584) (xy 104.987081 -52.86919)
			(xy 105.016238 -52.82346) (xy 105.051571 -52.782315) (xy 105.092368 -52.746582) (xy 105.114852 -52.731416)
			(xy 105.1179 -52.729384) (xy 105.127019 -52.721646) (xy 105.137505 -52.700185) (xy 105.137966 -52.688236)
			(xy 105.13695 -52.616862) (xy 105.136696 -52.60848) (xy 105.136188 -52.58181) (xy 105.13441 -52.463954)
			(xy 105.134085 -52.457634) (xy 105.130735 -52.445434) (xy 105.127806 -52.439824) (xy 105.108502 -52.42052)
			(xy 105.106216 -52.418996) (xy 105.081099 -52.40428) (xy 105.034614 -52.369238) (xy 104.993149 -52.32838)
			(xy 104.957425 -52.282417) (xy 104.928065 -52.23215) (xy 104.90558 -52.178455) (xy 104.890362 -52.122266)
			(xy 104.882675 -52.064562) (xy 104.882188 -52.035456) (xy 104.882624 -52.007063) (xy 104.889897 -51.950744)
			(xy 104.904332 -51.895823) (xy 104.925689 -51.843206) (xy 104.953616 -51.793762) (xy 104.987652 -51.748306)
			(xy 105.027235 -51.70759) (xy 105.071712 -51.672284) (xy 105.095802 -51.65725) (xy 105.096056 -51.656996)
			(xy 105.10156 -51.653442) (xy 105.110694 -51.644056) (xy 105.11409 -51.638454) (xy 105.117392 -51.632612)
			(xy 105.120694 -51.619658) (xy 105.116122 -51.363118) (xy 105.114792 -51.352329) (xy 105.104398 -51.333259)
			(xy 105.096056 -51.326288) (xy 105.095802 -51.326034) (xy 105.072322 -51.307882) (xy 105.030737 -51.265541)
			(xy 104.996196 -51.217281) (xy 104.969531 -51.164263) (xy 104.951381 -51.107759) (xy 104.942184 -51.049129)
			(xy 104.941624 -51.019456) (xy 104.942048 -50.992909) (xy 104.949337 -50.940317) (xy 104.963836 -50.889242)
			(xy 104.974136 -50.86477) (xy 104.987146 -50.836956) (xy 105.020693 -50.785528) (xy 105.062017 -50.740114)
			(xy 105.085642 -50.720498) (xy 105.088436 -50.718212) (xy 105.095982 -50.710479) (xy 105.10451 -50.690655)
			(xy 105.104946 -50.679858) (xy 105.102406 -50.519838) (xy 105.102406 -50.518314) (xy 105.098596 -50.288698)
			(xy 105.097202 -50.278372) (xy 105.087368 -50.260023) (xy 105.079546 -50.253138) (xy 105.079292 -50.252884)
			(xy 105.056985 -50.234691) (xy 105.017581 -50.192732) (xy 104.984927 -50.14533) (xy 104.959765 -50.09356)
			(xy 104.942665 -50.038598) (xy 104.934016 -49.98169) (xy 104.933496 -49.95291) (xy 104.933994 -49.925172)
			(xy 104.942032 -49.87028) (xy 104.95794 -49.817133) (xy 104.981381 -49.766852) (xy 105.011861 -49.720499)
			(xy 105.048737 -49.679052) (xy 105.06964 -49.66081) (xy 105.073958 -49.657254) (xy 105.080816 -49.64811)
			(xy 105.083356 -49.64303) (xy 105.08549 -49.637831) (xy 105.08766 -49.626807) (xy 105.087674 -49.621186)
			(xy 105.086658 -49.558448) (xy 105.081324 -49.258474) (xy 105.080115 -49.248846) (xy 105.071495 -49.231479)
			(xy 105.06456 -49.224692) (xy 105.064306 -49.224438) (xy 105.04416 -49.206231) (xy 105.00871 -49.165097)
			(xy 104.979448 -49.119355) (xy 104.956964 -49.069927) (xy 104.941712 -49.017812) (xy 104.934001 -48.964061)
			(xy 104.933496 -48.93691) (xy 104.933943 -48.910797) (xy 104.941101 -48.859062) (xy 104.955244 -48.808786)
			(xy 104.976108 -48.760906) (xy 105.003304 -48.716318) (xy 105.036323 -48.675853) (xy 105.055162 -48.657764)
			(xy 105.05567 -48.657256) (xy 105.062359 -48.650309) (xy 105.070445 -48.632816) (xy 105.071418 -48.62322)
			(xy 105.059226 -47.891954) (xy 105.05694 -47.750476) (xy 105.056432 -47.709836) (xy 105.056234 -47.705545)
			(xy 105.054571 -47.697119) (xy 105.05313 -47.693072) (xy 105.05059 -47.686214) (xy 105.045256 -47.679356)
			(xy 105.029591 -47.659009) (xy 105.003282 -47.614909) (xy 104.983122 -47.56768) (xy 104.969476 -47.518175)
			(xy 104.96259 -47.467288) (xy 104.962198 -47.441612) (xy 104.962797 -47.411077) (xy 104.972517 -47.350785)
			(xy 104.99171 -47.292809) (xy 105.019887 -47.238628) (xy 105.037636 -47.213774) (xy 105.042716 -47.206916)
			(xy 105.045256 -47.199296) (xy 105.04644 -47.195276) (xy 105.047596 -47.186976) (xy 105.047542 -47.182786)
			(xy 105.030778 -46.161198) (xy 105.030419 -46.153367) (xy 105.025506 -46.138489) (xy 105.021126 -46.131988)
			(xy 105.019348 -46.129956) (xy 105.003174 -46.10946) (xy 104.975993 -46.064881) (xy 104.955153 -46.017009)
			(xy 104.941043 -45.96674) (xy 104.933927 -45.915016) (xy 104.933496 -45.88891) (xy 104.933531 -45.878732)
			(xy 104.93455 -45.858401) (xy 104.935528 -45.84827) (xy 104.936036 -45.843952) (xy 104.939472 -45.818719)
			(xy 104.952181 -45.769406) (xy 104.971341 -45.722223) (xy 104.996613 -45.678011) (xy 105.011728 -45.657516)
			(xy 105.017062 -45.650404) (xy 105.019602 -45.642784) (xy 105.020784 -45.638764) (xy 105.021937 -45.630464)
			(xy 105.021888 -45.626274) (xy 105.014014 -45.123862) (xy 105.013854 -45.119848) (xy 105.012453 -45.111937)
			(xy 105.01122 -45.108114) (xy 105.00868 -45.101002) (xy 105.004362 -45.094906) (xy 104.987679 -45.070608)
			(xy 104.961197 -45.017953) (xy 104.943118 -44.961856) (xy 104.933869 -44.903647) (xy 104.933242 -44.87418)
			(xy 104.933242 -44.872656) (xy 104.93502 -44.835318) (xy 104.936036 -44.828206) (xy 104.936036 -44.827952)
			(xy 104.938068 -44.813728) (xy 104.939914 -44.802688) (xy 104.944744 -44.78083) (xy 104.94772 -44.77004)
			(xy 104.956317 -44.741348) (xy 104.981192 -44.686865) (xy 104.99725 -44.661582) (xy 105.001568 -44.655232)
			(xy 105.003854 -44.647612) (xy 105.004851 -44.643948) (xy 105.005875 -44.636423) (xy 105.005886 -44.632626)
			(xy 104.996488 -44.080938) (xy 104.99471 -44.067984) (xy 104.992932 -44.061634) (xy 104.991916 -44.06011)
			(xy 104.989122 -44.055538) (xy 104.975945 -44.032985) (xy 104.955155 -43.985069) (xy 104.941072 -43.934771)
			(xy 104.933957 -43.883026) (xy 104.933496 -43.85691) (xy 104.933496 -43.841924) (xy 104.935274 -43.811596)
			(xy 104.947254 -43.752042) (xy 104.968538 -43.695145) (xy 104.983026 -43.668442) (xy 104.986328 -43.6626)
			(xy 104.987852 -43.657012) (xy 104.988815 -43.653471) (xy 104.989831 -43.646203) (xy 104.989884 -43.642534)
			(xy 104.986074 -43.422316) (xy 104.97947 -43.02887) (xy 104.976676 -43.017694) (xy 104.974136 -43.012614)
			(xy 104.961914 -42.987182) (xy 104.944251 -42.933594) (xy 104.934652 -42.877993) (xy 104.933496 -42.8498)
			(xy 104.933242 -42.837608) (xy 102.172262 -37.702744) (xy 102.172262 -37.70249) (xy 102.162102 -37.683694)
			(xy 101.65588 -36.755324) (xy 101.59365 -36.641024) (xy 101.579426 -36.614862) (xy 101.572822 -36.605464)
			(xy 101.561646 -36.592764) (xy 101.557074 -36.589462) (xy 101.528992 -36.568773) (xy 101.475474 -36.52403)
			(xy 101.45014 -36.500054) (xy 101.413286 -36.463694) (xy 101.346507 -36.384574) (xy 101.288295 -36.298955)
			(xy 101.263196 -36.253674) (xy 101.243638 -36.217098) (xy 101.240082 -36.21278) (xy 101.239828 -36.212526)
			(xy 101.206957 -36.173034) (xy 101.148676 -36.088405) (xy 101.123496 -36.043616) (xy 100.967794 -35.757866)
			(xy 100.911914 -35.655504) (xy 100.888712 -35.61169) (xy 100.850201 -35.520327) (xy 100.821039 -35.425564)
			(xy 100.801522 -35.328355) (xy 100.79609 -35.279076) (xy 100.795836 -35.277044) (xy 100.794334 -35.268348)
			(xy 100.786153 -35.252722) (xy 100.779834 -35.246564) (xy 100.778564 -35.245548) (xy 100.774246 -35.24123)
			(xy 100.77119 -35.238673) (xy 100.764428 -35.234459) (xy 100.760784 -35.232848) (xy 100.752656 -35.229546)
			(xy 100.744782 -35.22726) (xy 100.671884 -35.22726) (xy 100.667006 -35.227353) (xy 100.657414 -35.229136)
			(xy 100.652834 -35.230816) (xy 100.644198 -35.234372) (xy 100.636832 -35.241484) (xy 100.60596 -35.270421)
			(xy 100.540096 -35.323552) (xy 100.469966 -35.37091) (xy 100.396074 -35.412152) (xy 100.318953 -35.446984)
			(xy 100.239156 -35.475153) (xy 100.15726 -35.496458) (xy 100.073852 -35.510745) (xy 99.989533 -35.51791)
			(xy 99.947222 -35.518344) (xy 99.900741 -35.51781) (xy 99.808183 -35.509159) (xy 99.716833 -35.49193)
			(xy 99.627482 -35.466272) (xy 99.540908 -35.432408) (xy 99.457862 -35.390633) (xy 99.379066 -35.341309)
			(xy 99.305202 -35.284864) (xy 99.236914 -35.221789) (xy 99.174793 -35.152631) (xy 99.11938 -35.07799)
			(xy 99.094798 -35.038538) (xy 99.092258 -35.034474) (xy 99.079812 -35.020758) (xy 99.07651 -35.018218)
			(xy 99.054374 -35.000021) (xy 99.015284 -34.958123) (xy 98.98289 -34.910857) (xy 98.957918 -34.859283)
			(xy 98.940929 -34.804559) (xy 98.932303 -34.74791) (xy 98.93173 -34.71926) (xy 98.93173 -34.718752)
			(xy 98.93173 -34.711894) (xy 98.932746 -34.689796) (xy 98.934524 -34.671762) (xy 98.93675 -34.655134)
			(xy 98.943749 -34.622321) (xy 98.948494 -34.60623) (xy 98.950018 -34.599118) (xy 98.951796 -34.588196)
			(xy 98.951796 -34.584386) (xy 98.951542 -34.581592) (xy 98.949764 -34.521902) (xy 98.949764 -34.520886)
			(xy 98.950196 -34.478939) (xy 98.957242 -34.39534) (xy 98.971281 -34.312629) (xy 98.992217 -34.231388)
			(xy 99.019899 -34.152192) (xy 99.036632 -34.113724) (xy 99.03841 -34.10966) (xy 99.042982 -34.089594)
			(xy 99.042982 -34.088578) (xy 99.039426 -34.073338) (xy 99.036378 -34.063686) (xy 99.019698 -34.025283)
			(xy 98.992088 -33.946233) (xy 98.971208 -33.865145) (xy 98.957206 -33.782591) (xy 98.950181 -33.699153)
			(xy 98.949764 -33.657286) (xy 98.951796 -33.595564) (xy 98.952558 -33.585404) (xy 98.952558 -33.58388)
			(xy 98.951796 -33.581594) (xy 98.951288 -33.58007) (xy 98.950526 -33.578038) (xy 98.94189 -33.563814)
			(xy 98.935286 -33.554924) (xy 98.89363 -33.510982) (xy 98.886363 -33.504633) (xy 98.868472 -33.497441)
			(xy 98.858832 -33.497012) (xy 98.69424 -33.497012) (xy 98.646677 -33.49643) (xy 98.551993 -33.487265)
			(xy 98.458626 -33.469053) (xy 98.367439 -33.441964) (xy 98.323146 -33.424622) (xy 98.319844 -33.423352)
			(xy 98.313494 -33.420812) (xy 98.029522 -33.420812) (xy 98.027998 -33.420812) (xy 98.019464 -33.421389)
			(xy 98.003491 -33.427479) (xy 97.996756 -33.43275) (xy 97.96586 -33.461864) (xy 97.899899 -33.515316)
			(xy 97.829632 -33.562966) (xy 97.755569 -33.604472) (xy 97.678247 -33.639532) (xy 97.598224 -33.667892)
			(xy 97.51608 -33.689348) (xy 97.432409 -33.703743) (xy 97.347818 -33.710974) (xy 97.305368 -33.711388)
			(xy 97.305114 -33.711388) (xy 97.258641 -33.710851) (xy 97.1661 -33.702197) (xy 97.074764 -33.684973)
			(xy 96.985427 -33.659328) (xy 96.898862 -33.625484) (xy 96.815821 -33.583734) (xy 96.737024 -33.534442)
			(xy 96.663153 -33.478033) (xy 96.594849 -33.414998) (xy 96.532705 -33.345883) (xy 96.477259 -33.271286)
			(xy 96.45269 -33.231836) (xy 96.451166 -33.22955) (xy 96.45015 -33.227772) (xy 96.447635 -33.22379)
			(xy 96.441375 -33.216753) (xy 96.437704 -33.213802) (xy 96.415082 -33.195589) (xy 96.375086 -33.15348)
			(xy 96.341924 -33.105803) (xy 96.316361 -33.053656) (xy 96.298984 -32.998241) (xy 96.290195 -32.940834)
			(xy 96.289622 -32.911796) (xy 96.289622 -32.911034) (xy 96.290126 -32.882599) (xy 96.298544 -32.826357)
			(xy 96.306386 -32.79902) (xy 96.30791 -32.791908) (xy 96.309688 -32.780986) (xy 96.309688 -32.777176)
			(xy 96.309434 -32.774382) (xy 96.308549 -32.758586) (xy 96.307659 -32.726957) (xy 96.307656 -32.711136)
			(xy 96.307656 -32.710882) (xy 96.308233 -32.669349) (xy 96.315436 -32.586592) (xy 96.329493 -32.504719)
			(xy 96.350305 -32.424298) (xy 96.377729 -32.345885) (xy 96.39427 -32.307784) (xy 96.397318 -32.298132)
			(xy 96.400874 -32.282892) (xy 96.400874 -32.281876) (xy 96.397318 -32.266636) (xy 96.39427 -32.257238)
			(xy 96.379203 -32.222552) (xy 96.353746 -32.151334) (xy 96.333751 -32.078393) (xy 96.326198 -32.041338)
			(xy 96.317544 -31.994124) (xy 96.308259 -31.898581) (xy 96.307656 -31.850584) (xy 96.307656 -31.843472)
			(xy 96.309434 -31.789878) (xy 96.309688 -31.78683) (xy 96.309688 -31.78302) (xy 96.30791 -31.772098)
			(xy 96.306386 -31.76524) (xy 96.298558 -31.7379) (xy 96.290139 -31.68166) (xy 96.289622 -31.653226)
			(xy 96.289622 -31.652972) (xy 96.290167 -31.623902) (xy 96.298978 -31.566434) (xy 96.316391 -31.510963)
			(xy 96.342005 -31.458769) (xy 96.375229 -31.411057) (xy 96.415297 -31.368929) (xy 96.437958 -31.350712)
			(xy 96.443038 -31.34614) (xy 96.44888 -31.339028) (xy 96.471665 -31.301761) (xy 96.522824 -31.230953)
			(xy 96.579986 -31.164895) (xy 96.642711 -31.104095) (xy 96.710519 -31.04902) (xy 96.782887 -31.000093)
			(xy 96.859261 -30.957689) (xy 96.898968 -30.939486) (xy 96.937331 -30.922858) (xy 97.016292 -30.895337)
			(xy 97.09728 -30.874522) (xy 97.179725 -30.86056) (xy 97.26305 -30.853548) (xy 97.30486 -30.853126)
			(xy 97.305114 -30.853126) (xy 97.347696 -30.853573) (xy 97.432549 -30.860834) (xy 97.516475 -30.875302)
			(xy 97.598862 -30.896871) (xy 97.679111 -30.925385) (xy 97.756636 -30.960636) (xy 97.830875 -31.002368)
			(xy 97.901286 -31.050276) (xy 97.967356 -31.104011) (xy 97.99828 -31.133288) (xy 98.004547 -31.137822)
			(xy 98.019025 -31.143247) (xy 98.026728 -31.143956) (xy 98.876866 -31.143956) (xy 98.883724 -31.143448)
			(xy 98.892507 -31.141904) (xy 98.908265 -31.133577) (xy 98.920199 -31.12034) (xy 98.923856 -31.112206)
			(xy 98.932492 -31.09087) (xy 98.933254 -31.08325) (xy 98.933254 -31.082996) (xy 98.934016 -31.07563)
			(xy 98.936193 -31.057836) (xy 98.943442 -31.022726) (xy 98.948494 -31.005526) (xy 98.950018 -30.998414)
			(xy 98.951796 -30.987492) (xy 98.951796 -30.983682) (xy 98.951542 -30.980888) (xy 98.949764 -30.92069)
			(xy 98.950205 -30.878824) (xy 98.957243 -30.79539) (xy 98.971245 -30.712837) (xy 98.992111 -30.631747)
			(xy 99.019695 -30.55269) (xy 99.036378 -30.51429) (xy 99.039426 -30.504638) (xy 99.042982 -30.489398)
			(xy 99.042982 -30.488382) (xy 99.03841 -30.468316) (xy 99.036632 -30.464252) (xy 99.017073 -30.419035)
			(xy 98.985923 -30.325565) (xy 98.964127 -30.229482) (xy 98.951898 -30.13172) (xy 98.950018 -30.08249)
			(xy 98.949764 -30.058614) (xy 98.949764 -30.056836) (xy 98.950018 -30.034738) (xy 98.950272 -30.03042)
			(xy 98.950272 -30.029912) (xy 98.950526 -30.021784) (xy 98.950526 -30.019752) (xy 98.946716 -30.0101)
			(xy 98.944743 -30.00562) (xy 98.939371 -29.997439) (xy 98.936048 -29.993844) (xy 98.891852 -29.948632)
			(xy 98.885608 -29.943209) (xy 98.870575 -29.93634) (xy 98.862388 -29.93517) (xy 98.857054 -29.934916)
			(xy 98.780346 -29.934916) (xy 98.7336 -29.934348) (xy 98.640529 -29.925472) (xy 98.548714 -29.907841)
			(xy 98.458975 -29.881614) (xy 98.372116 -29.847025) (xy 98.330258 -29.826204) (xy 98.324831 -29.823621)
			(xy 98.313152 -29.820796) (xy 98.307144 -29.820616) (xy 98.039174 -29.820616) (xy 98.034283 -29.82075)
			(xy 98.024689 -29.822664) (xy 98.020124 -29.824426) (xy 97.994978 -29.834586) (xy 97.987866 -29.84119)
			(xy 97.953373 -29.872859) (xy 97.879409 -29.930298) (xy 97.800389 -29.980553) (xy 97.717008 -30.023184)
			(xy 97.63 -30.057815) (xy 97.540129 -30.084141) (xy 97.448188 -30.101932) (xy 97.354983 -30.111029)
			(xy 97.308162 -30.1117) (xy 97.298256 -30.1117) (xy 97.251426 -30.11084) (xy 97.158231 -30.10141)
			(xy 97.066331 -30.083284) (xy 96.976535 -30.056624) (xy 96.889633 -30.021662) (xy 96.806392 -29.978708)
			(xy 96.727544 -29.928139) (xy 96.653784 -29.870401) (xy 96.585762 -29.806003) (xy 96.554544 -29.771086)
			(xy 96.526472 -29.738273) (xy 96.475475 -29.668577) (xy 96.45269 -29.631894) (xy 96.45015 -29.62783)
			(xy 96.437704 -29.614114) (xy 96.434402 -29.611574) (xy 96.412263 -29.593378) (xy 96.373168 -29.551482)
			(xy 96.340768 -29.504216) (xy 96.315789 -29.452643) (xy 96.298792 -29.397917) (xy 96.290158 -29.341267)
			(xy 96.289622 -29.312616) (xy 96.289622 -29.312108) (xy 96.289622 -29.30525) (xy 96.290638 -29.283152)
			(xy 96.294702 -29.249116) (xy 96.296786 -29.237353) (xy 96.302249 -29.214094) (xy 96.305624 -29.202634)
			(xy 96.305624 -29.202126) (xy 96.307402 -29.196284) (xy 96.309688 -29.181552) (xy 96.309688 -29.177742)
			(xy 96.309434 -29.174948) (xy 96.307656 -29.114496) (xy 96.307656 -29.096208) (xy 96.307656 -29.094176)
			(xy 96.308418 -29.074364) (xy 96.309428 -29.051818) (xy 96.313238 -29.006842) (xy 96.316038 -28.984448)
			(xy 96.322894 -28.93685) (xy 96.344581 -28.843155) (xy 96.375187 -28.751983) (xy 96.39427 -28.707842)
			(xy 96.397318 -28.69819) (xy 96.400874 -28.68295) (xy 96.400874 -28.681934) (xy 96.397318 -28.666694)
			(xy 96.39427 -28.657042) (xy 96.377591 -28.618639) (xy 96.349985 -28.539588) (xy 96.329109 -28.4585)
			(xy 96.315112 -28.375946) (xy 96.30809 -28.292508) (xy 96.307656 -28.250642) (xy 96.307656 -28.24353)
			(xy 96.309434 -28.189936) (xy 96.309688 -28.187142) (xy 96.309688 -28.183332) (xy 96.30791 -28.17241)
			(xy 96.306386 -28.165298) (xy 96.298547 -28.137896) (xy 96.290134 -28.081527) (xy 96.289622 -28.05303)
			(xy 96.289622 -28.04668) (xy 96.289876 -28.038298) (xy 96.291146 -28.01874) (xy 96.291146 -28.018486)
			(xy 96.291654 -28.012898) (xy 96.295325 -27.983489) (xy 96.310587 -27.926224) (xy 96.334517 -27.872007)
			(xy 96.350074 -27.846782) (xy 96.353376 -27.841702) (xy 96.370581 -27.816867) (xy 96.411538 -27.772455)
			(xy 96.43491 -27.75331) (xy 96.440752 -27.747722) (xy 96.445578 -27.742388) (xy 96.451674 -27.73426)
			(xy 96.474674 -27.697232) (xy 96.526184 -27.626901) (xy 96.554544 -27.593798) (xy 96.582856 -27.562108)
			(xy 96.644052 -27.50314) (xy 96.710046 -27.449594) (xy 96.780358 -27.401859) (xy 96.854478 -27.360283)
			(xy 96.931868 -27.325166) (xy 97.011966 -27.296764) (xy 97.09419 -27.275282) (xy 97.177945 -27.260877)
			(xy 97.262622 -27.253653) (xy 97.305114 -27.253184) (xy 97.305368 -27.253184) (xy 97.352887 -27.253738)
			(xy 97.447494 -27.262794) (xy 97.540809 -27.280816) (xy 97.631983 -27.307642) (xy 97.720189 -27.343028)
			(xy 97.804625 -27.386651) (xy 97.844864 -27.411934) (xy 97.8828 -27.436962) (xy 97.954415 -27.492928)
			(xy 97.987866 -27.523694) (xy 97.9932 -27.528774) (xy 97.99447 -27.530044) (xy 97.994724 -27.530298)
			(xy 98.020124 -27.540458) (xy 98.024691 -27.542211) (xy 98.034284 -27.544126) (xy 98.039174 -27.544268)
			(xy 99.413822 -27.544268) (xy 99.452848 -27.544648) (xy 99.530661 -27.550755) (xy 99.56927 -27.55646)
			(xy 99.573334 -27.556968) (xy 99.871784 -27.556968) (xy 99.916177 -27.557491) (xy 100.004601 -27.565498)
			(xy 100.091953 -27.581394) (xy 100.177529 -27.605053) (xy 100.219256 -27.620214) (xy 100.249482 -27.632152)
			(xy 101.766116 -28.260802) (xy 101.775466 -28.264174) (xy 101.795325 -28.264293) (xy 101.804724 -28.261056)
			(xy 101.811158 -28.258222) (xy 101.822239 -28.249578) (xy 101.826568 -28.244038) (xy 101.826568 -28.243784)
			(xy 101.844677 -28.220026) (xy 101.88704 -28.177912) (xy 101.935447 -28.142913) (xy 101.988716 -28.115884)
			(xy 102.045546 -28.097485) (xy 102.104549 -28.088164) (xy 102.134416 -28.087574) (xy 102.161404 -28.088042)
			(xy 102.214842 -28.09565) (xy 102.266675 -28.110711) (xy 102.315868 -28.132926) (xy 102.325652 -28.139136)
			(xy 118.49811 -28.139136) (xy 118.502181 -28.083514) (xy 118.514307 -28.029077) (xy 118.53423 -27.976986)
			(xy 118.561526 -27.928351) (xy 118.595612 -27.884208) (xy 118.635761 -27.845499) (xy 118.681119 -27.813048)
			(xy 118.730719 -27.787547) (xy 118.783503 -27.76954) (xy 118.838346 -27.75941) (xy 118.89408 -27.757373)
			(xy 118.949517 -27.763473) (xy 119.003474 -27.777579) (xy 119.054803 -27.799391) (xy 119.102409 -27.828445)
			(xy 119.145277 -27.86412) (xy 119.182494 -27.905657) (xy 119.213267 -27.95217) (xy 119.236939 -28.002667)
			(xy 119.253007 -28.056074) (xy 119.261127 -28.11125) (xy 119.261636 -28.139136) (xy 119.76811 -28.139136)
			(xy 119.772181 -28.083514) (xy 119.784307 -28.029077) (xy 119.80423 -27.976986) (xy 119.831526 -27.928351)
			(xy 119.865612 -27.884208) (xy 119.905761 -27.845499) (xy 119.951119 -27.813048) (xy 120.000719 -27.787547)
			(xy 120.053503 -27.76954) (xy 120.108346 -27.75941) (xy 120.16408 -27.757373) (xy 120.219517 -27.763473)
			(xy 120.273474 -27.777579) (xy 120.324803 -27.799391) (xy 120.372409 -27.828445) (xy 120.415277 -27.86412)
			(xy 120.452494 -27.905657) (xy 120.483267 -27.95217) (xy 120.506939 -28.002667) (xy 120.523007 -28.056074)
			(xy 120.531127 -28.11125) (xy 120.531636 -28.139136) (xy 120.531127 -28.167022) (xy 120.523007 -28.222198)
			(xy 120.506939 -28.275605) (xy 120.483267 -28.326102) (xy 120.452494 -28.372615) (xy 120.415277 -28.414152)
			(xy 120.372409 -28.449827) (xy 120.324803 -28.478881) (xy 120.273474 -28.500693) (xy 120.219517 -28.514799)
			(xy 120.16408 -28.520899) (xy 120.108346 -28.518862) (xy 120.053503 -28.508732) (xy 120.000719 -28.490725)
			(xy 119.951119 -28.465224) (xy 119.905761 -28.432773) (xy 119.865612 -28.394064) (xy 119.831526 -28.349921)
			(xy 119.80423 -28.301286) (xy 119.784307 -28.249195) (xy 119.772181 -28.194758) (xy 119.76811 -28.139136)
			(xy 119.261636 -28.139136) (xy 119.261127 -28.167022) (xy 119.253007 -28.222198) (xy 119.236939 -28.275605)
			(xy 119.213267 -28.326102) (xy 119.182494 -28.372615) (xy 119.145277 -28.414152) (xy 119.102409 -28.449827)
			(xy 119.054803 -28.478881) (xy 119.003474 -28.500693) (xy 118.949517 -28.514799) (xy 118.89408 -28.520899)
			(xy 118.838346 -28.518862) (xy 118.783503 -28.508732) (xy 118.730719 -28.490725) (xy 118.681119 -28.465224)
			(xy 118.635761 -28.432773) (xy 118.595612 -28.394064) (xy 118.561526 -28.349921) (xy 118.53423 -28.301286)
			(xy 118.514307 -28.249195) (xy 118.502181 -28.194758) (xy 118.49811 -28.139136) (xy 102.325652 -28.139136)
			(xy 102.36144 -28.161851) (xy 102.402482 -28.196909) (xy 102.438175 -28.237399) (xy 102.467806 -28.282516)
			(xy 102.490785 -28.331357) (xy 102.506652 -28.382949) (xy 102.515091 -28.436261) (xy 102.515924 -28.46324)
			(xy 102.515924 -28.46959) (xy 102.515447 -28.49613) (xy 102.508051 -28.548693) (xy 102.493441 -28.599724)
			(xy 102.471901 -28.648237) (xy 102.458266 -28.671012) (xy 102.454202 -28.677108) (xy 102.450646 -28.690316)
			(xy 102.449 -28.697213) (xy 102.449139 -28.711387) (xy 102.4509 -28.718256) (xy 102.453186 -28.725114)
			(xy 102.460806 -28.737052) (xy 102.466394 -28.741878) (xy 102.479656 -28.75354) (xy 102.505443 -28.777675)
			(xy 102.517956 -28.790138) (xy 102.849376 -29.12237) (xy 124.706888 -29.12237) (xy 124.706888 -28.25877)
			(xy 124.707378 -28.228786) (xy 124.715206 -28.16933) (xy 124.730727 -28.111405) (xy 124.753676 -28.056001)
			(xy 124.78366 -28.004067) (xy 124.820166 -27.956491) (xy 124.862571 -27.914086) (xy 124.910147 -27.87758)
			(xy 124.962081 -27.847596) (xy 125.017485 -27.824647) (xy 125.07541 -27.809126) (xy 125.134866 -27.801298)
			(xy 125.194834 -27.801298) (xy 125.25429 -27.809126) (xy 125.312215 -27.824647) (xy 125.367619 -27.847596)
			(xy 125.419553 -27.87758) (xy 125.467129 -27.914086) (xy 125.509534 -27.956491) (xy 125.54604 -28.004067)
			(xy 125.576024 -28.056001) (xy 125.598973 -28.111405) (xy 125.614494 -28.16933) (xy 125.622322 -28.228786)
			(xy 125.622812 -28.25877) (xy 125.622812 -29.12237) (xy 125.622322 -29.152354) (xy 125.614494 -29.21181)
			(xy 125.598973 -29.269735) (xy 125.576024 -29.325139) (xy 125.54604 -29.377073) (xy 125.509534 -29.424649)
			(xy 125.467129 -29.467054) (xy 125.419553 -29.50356) (xy 125.367619 -29.533544) (xy 125.312215 -29.556493)
			(xy 125.25429 -29.572014) (xy 125.194834 -29.579842) (xy 125.134866 -29.579842) (xy 125.07541 -29.572014)
			(xy 125.017485 -29.556493) (xy 124.962081 -29.533544) (xy 124.910147 -29.50356) (xy 124.862571 -29.467054)
			(xy 124.820166 -29.424649) (xy 124.78366 -29.377073) (xy 124.753676 -29.325139) (xy 124.730727 -29.269735)
			(xy 124.715206 -29.21181) (xy 124.707378 -29.152354) (xy 124.706888 -29.12237) (xy 102.849376 -29.12237)
			(xy 104.100814 -30.376876) (xy 116.989098 -30.376876) (xy 116.989672 -30.347961) (xy 116.998389 -30.290793)
			(xy 117.015636 -30.235595) (xy 117.041017 -30.183633) (xy 117.073951 -30.136098) (xy 117.113683 -30.094078)
			(xy 117.136164 -30.075886) (xy 117.144978 -30.068286) (xy 117.155155 -30.047379) (xy 117.155722 -30.035754)
			(xy 117.155722 -29.955998) (xy 117.155162 -29.944369) (xy 117.144987 -29.92346) (xy 117.136164 -29.915866)
			(xy 117.113657 -29.897703) (xy 117.073925 -29.855677) (xy 117.04099 -29.808135) (xy 117.015606 -29.756169)
			(xy 116.998354 -29.700967) (xy 116.98963 -29.643794) (xy 116.989098 -29.614876) (xy 116.989584 -29.587625)
			(xy 116.99734 -29.533677) (xy 117.012695 -29.481382) (xy 117.035337 -29.431805) (xy 117.064803 -29.385955)
			(xy 117.100494 -29.344764) (xy 117.141685 -29.309073) (xy 117.187535 -29.279607) (xy 117.237112 -29.256965)
			(xy 117.289407 -29.24161) (xy 117.343355 -29.233854) (xy 117.397857 -29.233854) (xy 117.451805 -29.24161)
			(xy 117.5041 -29.256965) (xy 117.553677 -29.279607) (xy 117.599527 -29.309073) (xy 117.640718 -29.344764)
			(xy 117.676409 -29.385955) (xy 117.705875 -29.431805) (xy 117.728517 -29.481382) (xy 117.743872 -29.533677)
			(xy 117.751628 -29.587625) (xy 117.752114 -29.614876) (xy 117.751611 -29.643794) (xy 117.742884 -29.700967)
			(xy 117.725625 -29.756168) (xy 117.70023 -29.80813) (xy 117.667282 -29.855663) (xy 117.627536 -29.897678)
			(xy 117.605048 -29.915866) (xy 117.596257 -29.923489) (xy 117.586067 -29.944378) (xy 117.58549 -29.955998)
			(xy 117.58549 -30.035754) (xy 117.586016 -30.047387) (xy 117.596215 -30.068296) (xy 117.605048 -30.075886)
			(xy 117.627535 -30.094073) (xy 117.667268 -30.136095) (xy 117.700205 -30.183631) (xy 117.725592 -30.235593)
			(xy 117.742848 -30.290791) (xy 117.751578 -30.34796) (xy 117.752114 -30.376876) (xy 120.029224 -30.376876)
			(xy 120.029788 -30.347961) (xy 120.038506 -30.290791) (xy 120.055754 -30.235593) (xy 120.081137 -30.183631)
			(xy 120.114073 -30.136096) (xy 120.153808 -30.094077) (xy 120.17629 -30.075886) (xy 120.185092 -30.068274)
			(xy 120.195279 -30.047377) (xy 120.195848 -30.035754) (xy 120.195848 -29.955998) (xy 120.195314 -29.944365)
			(xy 120.185123 -29.923454) (xy 120.17629 -29.915866) (xy 120.153788 -29.897697) (xy 120.114055 -29.855672)
			(xy 120.081118 -29.808133) (xy 120.055733 -29.756167) (xy 120.038481 -29.700966) (xy 120.029756 -29.643793)
			(xy 120.029224 -29.614876) (xy 120.02971 -29.587625) (xy 120.037466 -29.533677) (xy 120.052821 -29.481382)
			(xy 120.075463 -29.431805) (xy 120.104929 -29.385955) (xy 120.14062 -29.344764) (xy 120.181811 -29.309073)
			(xy 120.227661 -29.279607) (xy 120.277238 -29.256965) (xy 120.329533 -29.24161) (xy 120.383481 -29.233854)
			(xy 120.437983 -29.233854) (xy 120.491931 -29.24161) (xy 120.544226 -29.256965) (xy 120.593803 -29.279607)
			(xy 120.639653 -29.309073) (xy 120.680844 -29.344764) (xy 120.716535 -29.385955) (xy 120.746001 -29.431805)
			(xy 120.768643 -29.481382) (xy 120.783998 -29.533677) (xy 120.791754 -29.587625) (xy 120.79224 -29.614876)
			(xy 120.791727 -29.643793) (xy 120.783 -29.700966) (xy 120.765743 -29.756166) (xy 120.74035 -29.808128)
			(xy 120.707405 -29.855662) (xy 120.667661 -29.897677) (xy 120.645174 -29.915866) (xy 120.636388 -29.923493)
			(xy 120.626194 -29.944379) (xy 120.625616 -29.955998) (xy 120.625616 -30.035754) (xy 120.626133 -30.047389)
			(xy 120.636337 -30.068298) (xy 120.645174 -30.075886) (xy 120.667645 -30.094092) (xy 120.707382 -30.136107)
			(xy 120.740324 -30.183639) (xy 120.765714 -30.235598) (xy 120.782973 -30.290793) (xy 120.791704 -30.347961)
			(xy 120.79224 -30.376876) (xy 120.791754 -30.404127) (xy 120.783998 -30.458075) (xy 120.768643 -30.51037)
			(xy 120.746001 -30.559947) (xy 120.716535 -30.605797) (xy 120.680844 -30.646988) (xy 120.639653 -30.682679)
			(xy 120.593803 -30.712145) (xy 120.544226 -30.734787) (xy 120.491931 -30.750142) (xy 120.437983 -30.757898)
			(xy 120.383481 -30.757898) (xy 120.329533 -30.750142) (xy 120.277238 -30.734787) (xy 120.227661 -30.712145)
			(xy 120.181811 -30.682679) (xy 120.14062 -30.646988) (xy 120.104929 -30.605797) (xy 120.075463 -30.559947)
			(xy 120.052821 -30.51037) (xy 120.037466 -30.458075) (xy 120.02971 -30.404127) (xy 120.029224 -30.376876)
			(xy 117.752114 -30.376876) (xy 117.751628 -30.404127) (xy 117.743872 -30.458075) (xy 117.728517 -30.51037)
			(xy 117.705875 -30.559947) (xy 117.676409 -30.605797) (xy 117.640718 -30.646988) (xy 117.599527 -30.682679)
			(xy 117.553677 -30.712145) (xy 117.5041 -30.734787) (xy 117.451805 -30.750142) (xy 117.397857 -30.757898)
			(xy 117.343355 -30.757898) (xy 117.289407 -30.750142) (xy 117.237112 -30.734787) (xy 117.187535 -30.712145)
			(xy 117.141685 -30.682679) (xy 117.100494 -30.646988) (xy 117.064803 -30.605797) (xy 117.035337 -30.559947)
			(xy 117.012695 -30.51037) (xy 116.99734 -30.458075) (xy 116.989584 -30.404127) (xy 116.989098 -30.376876)
			(xy 104.100814 -30.376876) (xy 104.645072 -30.922468) (xy 122.852688 -30.922468) (xy 122.852688 -30.058868)
			(xy 122.853178 -30.028884) (xy 122.861006 -29.969428) (xy 122.876527 -29.911503) (xy 122.899476 -29.856099)
			(xy 122.92946 -29.804165) (xy 122.965966 -29.756589) (xy 123.008371 -29.714184) (xy 123.055947 -29.677678)
			(xy 123.107881 -29.647694) (xy 123.163285 -29.624745) (xy 123.22121 -29.609224) (xy 123.280666 -29.601396)
			(xy 123.340634 -29.601396) (xy 123.40009 -29.609224) (xy 123.458015 -29.624745) (xy 123.513419 -29.647694)
			(xy 123.565353 -29.677678) (xy 123.612929 -29.714184) (xy 123.655334 -29.756589) (xy 123.69184 -29.804165)
			(xy 123.721824 -29.856099) (xy 123.744773 -29.911503) (xy 123.760294 -29.969428) (xy 123.768122 -30.028884)
			(xy 123.768612 -30.058868) (xy 123.768612 -30.922468) (xy 123.768122 -30.952452) (xy 123.760294 -31.011908)
			(xy 123.744773 -31.069833) (xy 123.721824 -31.125237) (xy 123.69184 -31.177171) (xy 123.655334 -31.224747)
			(xy 123.612929 -31.267152) (xy 123.565353 -31.303658) (xy 123.513419 -31.333642) (xy 123.458015 -31.356591)
			(xy 123.40009 -31.372112) (xy 123.340634 -31.37994) (xy 123.280666 -31.37994) (xy 123.22121 -31.372112)
			(xy 123.163285 -31.356591) (xy 123.107881 -31.333642) (xy 123.055947 -31.303658) (xy 123.008371 -31.267152)
			(xy 122.965966 -31.224747) (xy 122.92946 -31.177171) (xy 122.899476 -31.125237) (xy 122.876527 -31.069833)
			(xy 122.861006 -31.011908) (xy 122.853178 -30.952452) (xy 122.852688 -30.922468) (xy 104.645072 -30.922468)
			(xy 104.693974 -30.97149) (xy 104.726897 -31.005316) (xy 104.786909 -31.078183) (xy 104.839775 -31.156391)
			(xy 104.862884 -31.19755) (xy 105.065294 -31.567882) (xy 117.098824 -31.567882) (xy 117.102895 -31.51226)
			(xy 117.115021 -31.457823) (xy 117.134944 -31.405732) (xy 117.16224 -31.357097) (xy 117.196326 -31.312954)
			(xy 117.236475 -31.274245) (xy 117.281833 -31.241794) (xy 117.331433 -31.216293) (xy 117.384217 -31.198286)
			(xy 117.43906 -31.188156) (xy 117.494794 -31.186119) (xy 117.550231 -31.192219) (xy 117.604188 -31.206325)
			(xy 117.655517 -31.228137) (xy 117.703123 -31.257191) (xy 117.745991 -31.292866) (xy 117.783208 -31.334403)
			(xy 117.813981 -31.380916) (xy 117.837653 -31.431413) (xy 117.853721 -31.48482) (xy 117.861841 -31.539996)
			(xy 117.86235 -31.567882) (xy 117.861841 -31.595768) (xy 117.853721 -31.650944) (xy 117.837653 -31.704351)
			(xy 117.830661 -31.719266) (xy 118.385588 -31.719266) (xy 118.389659 -31.663644) (xy 118.401785 -31.609207)
			(xy 118.421708 -31.557116) (xy 118.449004 -31.508481) (xy 118.48309 -31.464338) (xy 118.523239 -31.425629)
			(xy 118.568597 -31.393178) (xy 118.618197 -31.367677) (xy 118.670981 -31.34967) (xy 118.725824 -31.33954)
			(xy 118.781558 -31.337503) (xy 118.836995 -31.343603) (xy 118.890952 -31.357709) (xy 118.942281 -31.379521)
			(xy 118.989887 -31.408575) (xy 119.032755 -31.44425) (xy 119.069972 -31.485787) (xy 119.100745 -31.5323)
			(xy 119.124417 -31.582797) (xy 119.140485 -31.636204) (xy 119.144635 -31.664402) (xy 119.661176 -31.664402)
			(xy 119.665247 -31.60878) (xy 119.677373 -31.554343) (xy 119.697296 -31.502252) (xy 119.724592 -31.453617)
			(xy 119.758678 -31.409474) (xy 119.798827 -31.370765) (xy 119.844185 -31.338314) (xy 119.893785 -31.312813)
			(xy 119.946569 -31.294806) (xy 120.001412 -31.284676) (xy 120.057146 -31.282639) (xy 120.112583 -31.288739)
			(xy 120.16654 -31.302845) (xy 120.217869 -31.324657) (xy 120.265475 -31.353711) (xy 120.308343 -31.389386)
			(xy 120.34556 -31.430923) (xy 120.376333 -31.477436) (xy 120.400005 -31.527933) (xy 120.416073 -31.58134)
			(xy 120.424193 -31.636516) (xy 120.424702 -31.664402) (xy 120.424193 -31.692288) (xy 120.416073 -31.747464)
			(xy 120.407133 -31.777178) (xy 120.92635 -31.777178) (xy 120.930421 -31.721556) (xy 120.942547 -31.667119)
			(xy 120.96247 -31.615028) (xy 120.989766 -31.566393) (xy 121.023852 -31.52225) (xy 121.064001 -31.483541)
			(xy 121.109359 -31.45109) (xy 121.158959 -31.425589) (xy 121.211743 -31.407582) (xy 121.266586 -31.397452)
			(xy 121.32232 -31.395415) (xy 121.377757 -31.401515) (xy 121.431714 -31.415621) (xy 121.483043 -31.437433)
			(xy 121.530649 -31.466487) (xy 121.573517 -31.502162) (xy 121.610734 -31.543699) (xy 121.641507 -31.590212)
			(xy 121.665179 -31.640709) (xy 121.681247 -31.694116) (xy 121.689367 -31.749292) (xy 121.689876 -31.777178)
			(xy 121.689367 -31.805064) (xy 121.681247 -31.86024) (xy 121.665179 -31.913647) (xy 121.641507 -31.964144)
			(xy 121.610734 -32.010657) (xy 121.573517 -32.052194) (xy 121.530649 -32.087869) (xy 121.483043 -32.116923)
			(xy 121.431714 -32.138735) (xy 121.377757 -32.152841) (xy 121.32232 -32.158941) (xy 121.266586 -32.156904)
			(xy 121.211743 -32.146774) (xy 121.158959 -32.128767) (xy 121.109359 -32.103266) (xy 121.064001 -32.070815)
			(xy 121.023852 -32.032106) (xy 120.989766 -31.987963) (xy 120.96247 -31.939328) (xy 120.942547 -31.887237)
			(xy 120.930421 -31.8328) (xy 120.92635 -31.777178) (xy 120.407133 -31.777178) (xy 120.400005 -31.800871)
			(xy 120.376333 -31.851368) (xy 120.34556 -31.897881) (xy 120.308343 -31.939418) (xy 120.265475 -31.975093)
			(xy 120.217869 -32.004147) (xy 120.16654 -32.025959) (xy 120.112583 -32.040065) (xy 120.057146 -32.046165)
			(xy 120.001412 -32.044128) (xy 119.946569 -32.033998) (xy 119.893785 -32.015991) (xy 119.844185 -31.99049)
			(xy 119.798827 -31.958039) (xy 119.758678 -31.91933) (xy 119.724592 -31.875187) (xy 119.697296 -31.826552)
			(xy 119.677373 -31.774461) (xy 119.665247 -31.720024) (xy 119.661176 -31.664402) (xy 119.144635 -31.664402)
			(xy 119.148605 -31.69138) (xy 119.149114 -31.719266) (xy 119.148605 -31.747152) (xy 119.140485 -31.802328)
			(xy 119.124417 -31.855735) (xy 119.100745 -31.906232) (xy 119.069972 -31.952745) (xy 119.032755 -31.994282)
			(xy 118.989887 -32.029957) (xy 118.942281 -32.059011) (xy 118.890952 -32.080823) (xy 118.836995 -32.094929)
			(xy 118.781558 -32.101029) (xy 118.725824 -32.098992) (xy 118.670981 -32.088862) (xy 118.618197 -32.070855)
			(xy 118.568597 -32.045354) (xy 118.523239 -32.012903) (xy 118.48309 -31.974194) (xy 118.449004 -31.930051)
			(xy 118.421708 -31.881416) (xy 118.401785 -31.829325) (xy 118.389659 -31.774888) (xy 118.385588 -31.719266)
			(xy 117.830661 -31.719266) (xy 117.813981 -31.754848) (xy 117.783208 -31.801361) (xy 117.745991 -31.842898)
			(xy 117.703123 -31.878573) (xy 117.655517 -31.907627) (xy 117.604188 -31.929439) (xy 117.550231 -31.943545)
			(xy 117.494794 -31.949645) (xy 117.43906 -31.947608) (xy 117.384217 -31.937478) (xy 117.331433 -31.919471)
			(xy 117.281833 -31.89397) (xy 117.236475 -31.861519) (xy 117.196326 -31.82281) (xy 117.16224 -31.778667)
			(xy 117.134944 -31.730032) (xy 117.115021 -31.677941) (xy 117.102895 -31.623504) (xy 117.098824 -31.567882)
			(xy 105.065294 -31.567882) (xy 105.696265 -32.722312) (xy 124.706888 -32.722312) (xy 124.706888 -31.858712)
			(xy 124.707378 -31.828728) (xy 124.715206 -31.769272) (xy 124.730727 -31.711347) (xy 124.753676 -31.655943)
			(xy 124.78366 -31.604009) (xy 124.820166 -31.556433) (xy 124.862571 -31.514028) (xy 124.910147 -31.477522)
			(xy 124.962081 -31.447538) (xy 125.017485 -31.424589) (xy 125.07541 -31.409068) (xy 125.134866 -31.40124)
			(xy 125.194834 -31.40124) (xy 125.25429 -31.409068) (xy 125.312215 -31.424589) (xy 125.367619 -31.447538)
			(xy 125.419553 -31.477522) (xy 125.467129 -31.514028) (xy 125.509534 -31.556433) (xy 125.54604 -31.604009)
			(xy 125.576024 -31.655943) (xy 125.598973 -31.711347) (xy 125.614494 -31.769272) (xy 125.622322 -31.828728)
			(xy 125.622812 -31.858712) (xy 125.622812 -32.722312) (xy 125.622322 -32.752296) (xy 125.614494 -32.811752)
			(xy 125.598973 -32.869677) (xy 125.576024 -32.925081) (xy 125.54604 -32.977015) (xy 125.509534 -33.024591)
			(xy 125.467129 -33.066996) (xy 125.419553 -33.103502) (xy 125.367619 -33.133486) (xy 125.312215 -33.156435)
			(xy 125.25429 -33.171956) (xy 125.194834 -33.179784) (xy 125.134866 -33.179784) (xy 125.07541 -33.171956)
			(xy 125.017485 -33.156435) (xy 124.962081 -33.133486) (xy 124.910147 -33.103502) (xy 124.862571 -33.066996)
			(xy 124.820166 -33.024591) (xy 124.78366 -32.977015) (xy 124.753676 -32.925081) (xy 124.730727 -32.869677)
			(xy 124.715206 -32.811752) (xy 124.707378 -32.752296) (xy 124.706888 -32.722312) (xy 105.696265 -32.722312)
			(xy 106.680136 -34.52241) (xy 122.852688 -34.52241) (xy 122.852688 -33.65881) (xy 122.853178 -33.628826)
			(xy 122.861006 -33.56937) (xy 122.876527 -33.511445) (xy 122.899476 -33.456041) (xy 122.92946 -33.404107)
			(xy 122.965966 -33.356531) (xy 123.008371 -33.314126) (xy 123.055947 -33.27762) (xy 123.107881 -33.247636)
			(xy 123.163285 -33.224687) (xy 123.22121 -33.209166) (xy 123.280666 -33.201338) (xy 123.340634 -33.201338)
			(xy 123.40009 -33.209166) (xy 123.458015 -33.224687) (xy 123.513419 -33.247636) (xy 123.565353 -33.27762)
			(xy 123.612929 -33.314126) (xy 123.655334 -33.356531) (xy 123.69184 -33.404107) (xy 123.721824 -33.456041)
			(xy 123.744773 -33.511445) (xy 123.760294 -33.56937) (xy 123.768122 -33.628826) (xy 123.768612 -33.65881)
			(xy 123.768612 -34.52241) (xy 123.768122 -34.552394) (xy 123.760294 -34.61185) (xy 123.744773 -34.669775)
			(xy 123.721824 -34.725179) (xy 123.69184 -34.777113) (xy 123.655334 -34.824689) (xy 123.612929 -34.867094)
			(xy 123.565353 -34.9036) (xy 123.513419 -34.933584) (xy 123.458015 -34.956533) (xy 123.40009 -34.972054)
			(xy 123.340634 -34.979882) (xy 123.280666 -34.979882) (xy 123.22121 -34.972054) (xy 123.163285 -34.956533)
			(xy 123.107881 -34.933584) (xy 123.055947 -34.9036) (xy 123.008371 -34.867094) (xy 122.965966 -34.824689)
			(xy 122.92946 -34.777113) (xy 122.899476 -34.725179) (xy 122.876527 -34.669775) (xy 122.861006 -34.61185)
			(xy 122.853178 -34.552394) (xy 122.852688 -34.52241) (xy 106.680136 -34.52241) (xy 107.085929 -35.264852)
			(xy 120.002552 -35.264852) (xy 120.006623 -35.20923) (xy 120.018749 -35.154793) (xy 120.038672 -35.102702)
			(xy 120.065968 -35.054067) (xy 120.100054 -35.009924) (xy 120.140203 -34.971215) (xy 120.185561 -34.938764)
			(xy 120.235161 -34.913263) (xy 120.287945 -34.895256) (xy 120.342788 -34.885126) (xy 120.398522 -34.883089)
			(xy 120.453959 -34.889189) (xy 120.507916 -34.903295) (xy 120.559245 -34.925107) (xy 120.606851 -34.954161)
			(xy 120.649719 -34.989836) (xy 120.686936 -35.031373) (xy 120.717709 -35.077886) (xy 120.741381 -35.128383)
			(xy 120.757449 -35.18179) (xy 120.765569 -35.236966) (xy 120.766078 -35.264852) (xy 120.765569 -35.292738)
			(xy 120.757449 -35.347914) (xy 120.741381 -35.401321) (xy 120.717709 -35.451818) (xy 120.686936 -35.498331)
			(xy 120.649719 -35.539868) (xy 120.606851 -35.575543) (xy 120.559245 -35.604597) (xy 120.507916 -35.626409)
			(xy 120.453959 -35.640515) (xy 120.398522 -35.646615) (xy 120.342788 -35.644578) (xy 120.287945 -35.634448)
			(xy 120.235161 -35.616441) (xy 120.185561 -35.59094) (xy 120.140203 -35.558489) (xy 120.100054 -35.51978)
			(xy 120.065968 -35.475637) (xy 120.038672 -35.427002) (xy 120.018749 -35.374911) (xy 120.006623 -35.320474)
			(xy 120.002552 -35.264852) (xy 107.085929 -35.264852) (xy 107.420364 -35.876738) (xy 108.817408 -35.876738)
			(xy 108.821479 -35.821116) (xy 108.833605 -35.766679) (xy 108.853528 -35.714588) (xy 108.880824 -35.665953)
			(xy 108.91491 -35.62181) (xy 108.955059 -35.583101) (xy 109.000417 -35.55065) (xy 109.050017 -35.525149)
			(xy 109.102801 -35.507142) (xy 109.157644 -35.497012) (xy 109.213378 -35.494975) (xy 109.268815 -35.501075)
			(xy 109.322772 -35.515181) (xy 109.374101 -35.536993) (xy 109.421707 -35.566047) (xy 109.464575 -35.601722)
			(xy 109.501792 -35.643259) (xy 109.532565 -35.689772) (xy 109.556237 -35.740269) (xy 109.572305 -35.793676)
			(xy 109.580425 -35.848852) (xy 109.580934 -35.876738) (xy 112.889028 -35.876738) (xy 112.893099 -35.821116)
			(xy 112.905225 -35.766679) (xy 112.925148 -35.714588) (xy 112.952444 -35.665953) (xy 112.98653 -35.62181)
			(xy 113.026679 -35.583101) (xy 113.072037 -35.55065) (xy 113.121637 -35.525149) (xy 113.174421 -35.507142)
			(xy 113.229264 -35.497012) (xy 113.284998 -35.494975) (xy 113.340435 -35.501075) (xy 113.394392 -35.515181)
			(xy 113.445721 -35.536993) (xy 113.493327 -35.566047) (xy 113.536195 -35.601722) (xy 113.573412 -35.643259)
			(xy 113.604185 -35.689772) (xy 113.627857 -35.740269) (xy 113.643925 -35.793676) (xy 113.652045 -35.848852)
			(xy 113.652554 -35.876738) (xy 113.652045 -35.904624) (xy 113.643925 -35.9598) (xy 113.627857 -36.013207)
			(xy 113.604185 -36.063704) (xy 113.573412 -36.110217) (xy 113.536195 -36.151754) (xy 113.493327 -36.187429)
			(xy 113.445721 -36.216483) (xy 113.394392 -36.238295) (xy 113.340435 -36.252401) (xy 113.284998 -36.258501)
			(xy 113.229264 -36.256464) (xy 113.174421 -36.246334) (xy 113.121637 -36.228327) (xy 113.072037 -36.202826)
			(xy 113.026679 -36.170375) (xy 112.98653 -36.131666) (xy 112.952444 -36.087523) (xy 112.925148 -36.038888)
			(xy 112.905225 -35.986797) (xy 112.893099 -35.93236) (xy 112.889028 -35.876738) (xy 109.580934 -35.876738)
			(xy 109.580425 -35.904624) (xy 109.572305 -35.9598) (xy 109.556237 -36.013207) (xy 109.532565 -36.063704)
			(xy 109.501792 -36.110217) (xy 109.464575 -36.151754) (xy 109.421707 -36.187429) (xy 109.374101 -36.216483)
			(xy 109.322772 -36.238295) (xy 109.268815 -36.252401) (xy 109.213378 -36.258501) (xy 109.157644 -36.256464)
			(xy 109.102801 -36.246334) (xy 109.050017 -36.228327) (xy 109.000417 -36.202826) (xy 108.955059 -36.170375)
			(xy 108.91491 -36.131666) (xy 108.880824 -36.087523) (xy 108.853528 -36.038888) (xy 108.833605 -35.986797)
			(xy 108.821479 -35.93236) (xy 108.817408 -35.876738) (xy 107.420364 -35.876738) (xy 107.766461 -36.50996)
			(xy 110.714026 -36.50996) (xy 110.718097 -36.454338) (xy 110.730223 -36.399901) (xy 110.750146 -36.34781)
			(xy 110.777442 -36.299175) (xy 110.811528 -36.255032) (xy 110.851677 -36.216323) (xy 110.897035 -36.183872)
			(xy 110.946635 -36.158371) (xy 110.999419 -36.140364) (xy 111.054262 -36.130234) (xy 111.109996 -36.128197)
			(xy 111.165433 -36.134297) (xy 111.21939 -36.148403) (xy 111.270719 -36.170215) (xy 111.318325 -36.199269)
			(xy 111.361193 -36.234944) (xy 111.39841 -36.276481) (xy 111.429183 -36.322994) (xy 111.452855 -36.373491)
			(xy 111.468923 -36.426898) (xy 111.472848 -36.453572) (xy 114.028726 -36.453572) (xy 114.032797 -36.39795)
			(xy 114.044923 -36.343513) (xy 114.064846 -36.291422) (xy 114.092142 -36.242787) (xy 114.126228 -36.198644)
			(xy 114.166377 -36.159935) (xy 114.211735 -36.127484) (xy 114.261335 -36.101983) (xy 114.314119 -36.083976)
			(xy 114.368962 -36.073846) (xy 114.424696 -36.071809) (xy 114.480133 -36.077909) (xy 114.53409 -36.092015)
			(xy 114.585419 -36.113827) (xy 114.633025 -36.142881) (xy 114.675893 -36.178556) (xy 114.71311 -36.220093)
			(xy 114.743883 -36.266606) (xy 114.753419 -36.286948) (xy 121.300492 -36.286948) (xy 121.304563 -36.231326)
			(xy 121.316689 -36.176889) (xy 121.336612 -36.124798) (xy 121.363908 -36.076163) (xy 121.397994 -36.03202)
			(xy 121.438143 -35.993311) (xy 121.483501 -35.96086) (xy 121.533101 -35.935359) (xy 121.585885 -35.917352)
			(xy 121.640728 -35.907222) (xy 121.696462 -35.905185) (xy 121.751899 -35.911285) (xy 121.805856 -35.925391)
			(xy 121.857185 -35.947203) (xy 121.904791 -35.976257) (xy 121.947659 -36.011932) (xy 121.984876 -36.053469)
			(xy 122.015649 -36.099982) (xy 122.039321 -36.150479) (xy 122.055389 -36.203886) (xy 122.063509 -36.259062)
			(xy 122.064018 -36.286948) (xy 122.063509 -36.314834) (xy 122.055389 -36.37001) (xy 122.039321 -36.423417)
			(xy 122.015649 -36.473914) (xy 121.988104 -36.515548) (xy 123.114306 -36.515548) (xy 123.118377 -36.459926)
			(xy 123.130503 -36.405489) (xy 123.150426 -36.353398) (xy 123.177722 -36.304763) (xy 123.211808 -36.26062)
			(xy 123.251957 -36.221911) (xy 123.297315 -36.18946) (xy 123.346915 -36.163959) (xy 123.399699 -36.145952)
			(xy 123.454542 -36.135822) (xy 123.510276 -36.133785) (xy 123.565713 -36.139885) (xy 123.61967 -36.153991)
			(xy 123.670999 -36.175803) (xy 123.718605 -36.204857) (xy 123.761473 -36.240532) (xy 123.79869 -36.282069)
			(xy 123.829463 -36.328582) (xy 123.853135 -36.379079) (xy 123.869203 -36.432486) (xy 123.877323 -36.487662)
			(xy 123.877832 -36.515548) (xy 123.877323 -36.543434) (xy 123.869203 -36.59861) (xy 123.868746 -36.60013)
			(xy 128.098303 -36.60013) (xy 128.102308 -36.512222) (xy 128.114291 -36.425042) (xy 128.134151 -36.339313)
			(xy 128.161726 -36.255745) (xy 128.196785 -36.175031) (xy 128.239038 -36.097839) (xy 128.288136 -36.02481)
			(xy 128.343672 -35.956548) (xy 128.405184 -35.893618) (xy 128.472165 -35.836544) (xy 128.544058 -35.785796)
			(xy 128.620267 -35.741796) (xy 128.700162 -35.704909) (xy 128.783081 -35.67544) (xy 128.868336 -35.653633)
			(xy 128.95522 -35.639669) (xy 129.043014 -35.633663) (xy 129.130991 -35.635667) (xy 129.218421 -35.645662)
			(xy 129.30458 -35.663566) (xy 129.388754 -35.68923) (xy 129.470245 -35.722443) (xy 129.548379 -35.762929)
			(xy 129.622507 -35.810351) (xy 129.692015 -35.864318) (xy 129.705314 -35.876738) (xy 134.817356 -35.876738)
			(xy 134.821427 -35.821116) (xy 134.833553 -35.766679) (xy 134.853476 -35.714588) (xy 134.880772 -35.665953)
			(xy 134.914858 -35.62181) (xy 134.955007 -35.583101) (xy 135.000365 -35.55065) (xy 135.049965 -35.525149)
			(xy 135.102749 -35.507142) (xy 135.157592 -35.497012) (xy 135.213326 -35.494975) (xy 135.268763 -35.501075)
			(xy 135.32272 -35.515181) (xy 135.374049 -35.536993) (xy 135.421655 -35.566047) (xy 135.464523 -35.601722)
			(xy 135.50174 -35.643259) (xy 135.532513 -35.689772) (xy 135.556185 -35.740269) (xy 135.572253 -35.793676)
			(xy 135.580373 -35.848852) (xy 135.580882 -35.876738) (xy 135.580373 -35.904624) (xy 135.572253 -35.9598)
			(xy 135.556185 -36.013207) (xy 135.532513 -36.063704) (xy 135.50174 -36.110217) (xy 135.464523 -36.151754)
			(xy 135.421655 -36.187429) (xy 135.374049 -36.216483) (xy 135.32272 -36.238295) (xy 135.268763 -36.252401)
			(xy 135.213326 -36.258501) (xy 135.157592 -36.256464) (xy 135.102749 -36.246334) (xy 135.049965 -36.228327)
			(xy 135.000365 -36.202826) (xy 134.955007 -36.170375) (xy 134.914858 -36.131666) (xy 134.880772 -36.087523)
			(xy 134.853476 -36.038888) (xy 134.833553 -35.986797) (xy 134.821427 -35.93236) (xy 134.817356 -35.876738)
			(xy 129.705314 -35.876738) (xy 129.756329 -35.924383) (xy 129.814913 -35.990047) (xy 129.867284 -36.060766)
			(xy 129.913007 -36.135954) (xy 129.951704 -36.214989) (xy 129.983053 -36.297215) (xy 130.006795 -36.381951)
			(xy 130.022733 -36.468495) (xy 130.026519 -36.50996) (xy 136.713974 -36.50996) (xy 136.718045 -36.454338)
			(xy 136.730171 -36.399901) (xy 136.750094 -36.34781) (xy 136.77739 -36.299175) (xy 136.811476 -36.255032)
			(xy 136.851625 -36.216323) (xy 136.896983 -36.183872) (xy 136.946583 -36.158371) (xy 136.999367 -36.140364)
			(xy 137.05421 -36.130234) (xy 137.109944 -36.128197) (xy 137.165381 -36.134297) (xy 137.219338 -36.148403)
			(xy 137.270667 -36.170215) (xy 137.318273 -36.199269) (xy 137.361141 -36.234944) (xy 137.398358 -36.276481)
			(xy 137.429131 -36.322994) (xy 137.452803 -36.373491) (xy 137.468871 -36.426898) (xy 137.476991 -36.482074)
			(xy 137.4775 -36.50996) (xy 137.476991 -36.537846) (xy 137.468871 -36.593022) (xy 137.452803 -36.646429)
			(xy 137.429131 -36.696926) (xy 137.398358 -36.743439) (xy 137.361141 -36.784976) (xy 137.318273 -36.820651)
			(xy 137.270667 -36.849705) (xy 137.219338 -36.871517) (xy 137.165381 -36.885623) (xy 137.109944 -36.891723)
			(xy 137.05421 -36.889686) (xy 136.999367 -36.879556) (xy 136.946583 -36.861549) (xy 136.896983 -36.836048)
			(xy 136.851625 -36.803597) (xy 136.811476 -36.764888) (xy 136.77739 -36.720745) (xy 136.750094 -36.67211)
			(xy 136.730171 -36.620019) (xy 136.718045 -36.565582) (xy 136.713974 -36.50996) (xy 130.026519 -36.50996)
			(xy 130.030735 -36.55613) (xy 130.031236 -36.60013) (xy 130.030735 -36.64413) (xy 130.022733 -36.731765)
			(xy 130.006795 -36.818309) (xy 129.983053 -36.903045) (xy 129.951704 -36.985271) (xy 129.913007 -37.064306)
			(xy 129.867284 -37.139494) (xy 129.814913 -37.210213) (xy 129.756329 -37.275877) (xy 129.692015 -37.335942)
			(xy 129.622507 -37.389909) (xy 129.548379 -37.437331) (xy 129.475373 -37.47516) (xy 133.859268 -37.47516)
			(xy 133.863339 -37.419538) (xy 133.875465 -37.365101) (xy 133.895388 -37.31301) (xy 133.922684 -37.264375)
			(xy 133.95677 -37.220232) (xy 133.996919 -37.181523) (xy 134.042277 -37.149072) (xy 134.091877 -37.123571)
			(xy 134.144661 -37.105564) (xy 134.199504 -37.095434) (xy 134.255238 -37.093397) (xy 134.310675 -37.099497)
			(xy 134.364632 -37.113603) (xy 134.415961 -37.135415) (xy 134.463567 -37.164469) (xy 134.506435 -37.200144)
			(xy 134.543652 -37.241681) (xy 134.574425 -37.288194) (xy 134.598097 -37.338691) (xy 134.614165 -37.392098)
			(xy 134.622285 -37.447274) (xy 134.622794 -37.47516) (xy 134.622285 -37.503046) (xy 134.614165 -37.558222)
			(xy 134.598097 -37.611629) (xy 134.574425 -37.662126) (xy 134.574272 -37.662358) (xy 136.048494 -37.662358)
			(xy 136.052565 -37.606736) (xy 136.064691 -37.552299) (xy 136.084614 -37.500208) (xy 136.11191 -37.451573)
			(xy 136.145996 -37.40743) (xy 136.186145 -37.368721) (xy 136.231503 -37.33627) (xy 136.281103 -37.310769)
			(xy 136.333887 -37.292762) (xy 136.38873 -37.282632) (xy 136.444464 -37.280595) (xy 136.499901 -37.286695)
			(xy 136.553858 -37.300801) (xy 136.605187 -37.322613) (xy 136.652793 -37.351667) (xy 136.695661 -37.387342)
			(xy 136.732878 -37.428879) (xy 136.763651 -37.475392) (xy 136.787323 -37.525889) (xy 136.803391 -37.579296)
			(xy 136.811511 -37.634472) (xy 136.81202 -37.662358) (xy 136.811511 -37.690244) (xy 136.803391 -37.74542)
			(xy 136.787323 -37.798827) (xy 136.763651 -37.849324) (xy 136.732878 -37.895837) (xy 136.695661 -37.937374)
			(xy 136.652793 -37.973049) (xy 136.605187 -38.002103) (xy 136.553858 -38.023915) (xy 136.499901 -38.038021)
			(xy 136.444464 -38.044121) (xy 136.38873 -38.042084) (xy 136.333887 -38.031954) (xy 136.281103 -38.013947)
			(xy 136.231503 -37.988446) (xy 136.186145 -37.955995) (xy 136.145996 -37.917286) (xy 136.11191 -37.873143)
			(xy 136.084614 -37.824508) (xy 136.064691 -37.772417) (xy 136.052565 -37.71798) (xy 136.048494 -37.662358)
			(xy 134.574272 -37.662358) (xy 134.543652 -37.708639) (xy 134.506435 -37.750176) (xy 134.463567 -37.785851)
			(xy 134.415961 -37.814905) (xy 134.364632 -37.836717) (xy 134.310675 -37.850823) (xy 134.255238 -37.856923)
			(xy 134.199504 -37.854886) (xy 134.144661 -37.844756) (xy 134.091877 -37.826749) (xy 134.042277 -37.801248)
			(xy 133.996919 -37.768797) (xy 133.95677 -37.730088) (xy 133.922684 -37.685945) (xy 133.895388 -37.63731)
			(xy 133.875465 -37.585219) (xy 133.863339 -37.530782) (xy 133.859268 -37.47516) (xy 129.475373 -37.47516)
			(xy 129.470245 -37.477817) (xy 129.388754 -37.51103) (xy 129.30458 -37.536694) (xy 129.218421 -37.554598)
			(xy 129.130991 -37.564593) (xy 129.043014 -37.566597) (xy 128.95522 -37.560591) (xy 128.868336 -37.546627)
			(xy 128.783081 -37.52482) (xy 128.700162 -37.495351) (xy 128.620267 -37.458464) (xy 128.544058 -37.414464)
			(xy 128.472165 -37.363716) (xy 128.405184 -37.306642) (xy 128.343672 -37.243712) (xy 128.288136 -37.17545)
			(xy 128.239038 -37.102421) (xy 128.196785 -37.025229) (xy 128.161726 -36.944515) (xy 128.134151 -36.860947)
			(xy 128.114291 -36.775218) (xy 128.102308 -36.688038) (xy 128.098303 -36.60013) (xy 123.868746 -36.60013)
			(xy 123.853135 -36.652017) (xy 123.829463 -36.702514) (xy 123.79869 -36.749027) (xy 123.761473 -36.790564)
			(xy 123.718605 -36.826239) (xy 123.670999 -36.855293) (xy 123.61967 -36.877105) (xy 123.565713 -36.891211)
			(xy 123.510276 -36.897311) (xy 123.454542 -36.895274) (xy 123.399699 -36.885144) (xy 123.346915 -36.867137)
			(xy 123.297315 -36.841636) (xy 123.251957 -36.809185) (xy 123.211808 -36.770476) (xy 123.177722 -36.726333)
			(xy 123.150426 -36.677698) (xy 123.130503 -36.625607) (xy 123.118377 -36.57117) (xy 123.114306 -36.515548)
			(xy 121.988104 -36.515548) (xy 121.984876 -36.520427) (xy 121.947659 -36.561964) (xy 121.904791 -36.597639)
			(xy 121.857185 -36.626693) (xy 121.805856 -36.648505) (xy 121.751899 -36.662611) (xy 121.696462 -36.668711)
			(xy 121.640728 -36.666674) (xy 121.585885 -36.656544) (xy 121.533101 -36.638537) (xy 121.483501 -36.613036)
			(xy 121.438143 -36.580585) (xy 121.397994 -36.541876) (xy 121.363908 -36.497733) (xy 121.336612 -36.449098)
			(xy 121.316689 -36.397007) (xy 121.304563 -36.34257) (xy 121.300492 -36.286948) (xy 114.753419 -36.286948)
			(xy 114.767555 -36.317103) (xy 114.783623 -36.37051) (xy 114.791743 -36.425686) (xy 114.792252 -36.453572)
			(xy 114.791743 -36.481458) (xy 114.783623 -36.536634) (xy 114.767555 -36.590041) (xy 114.743883 -36.640538)
			(xy 114.71311 -36.687051) (xy 114.675893 -36.728588) (xy 114.633025 -36.764263) (xy 114.585419 -36.793317)
			(xy 114.53409 -36.815129) (xy 114.480133 -36.829235) (xy 114.424696 -36.835335) (xy 114.368962 -36.833298)
			(xy 114.314119 -36.823168) (xy 114.261335 -36.805161) (xy 114.211735 -36.77966) (xy 114.166377 -36.747209)
			(xy 114.126228 -36.7085) (xy 114.092142 -36.664357) (xy 114.064846 -36.615722) (xy 114.044923 -36.563631)
			(xy 114.032797 -36.509194) (xy 114.028726 -36.453572) (xy 111.472848 -36.453572) (xy 111.477043 -36.482074)
			(xy 111.477552 -36.50996) (xy 111.477043 -36.537846) (xy 111.468923 -36.593022) (xy 111.452855 -36.646429)
			(xy 111.429183 -36.696926) (xy 111.39841 -36.743439) (xy 111.361193 -36.784976) (xy 111.318325 -36.820651)
			(xy 111.270719 -36.849705) (xy 111.21939 -36.871517) (xy 111.165433 -36.885623) (xy 111.109996 -36.891723)
			(xy 111.054262 -36.889686) (xy 110.999419 -36.879556) (xy 110.946635 -36.861549) (xy 110.897035 -36.836048)
			(xy 110.851677 -36.803597) (xy 110.811528 -36.764888) (xy 110.777442 -36.720745) (xy 110.750146 -36.67211)
			(xy 110.730223 -36.620019) (xy 110.718097 -36.565582) (xy 110.714026 -36.50996) (xy 107.766461 -36.50996)
			(xy 108.079794 -37.083238) (xy 108.084231 -37.090663) (xy 108.097088 -37.102215) (xy 108.10494 -37.105844)
			(xy 108.113068 -37.109146) (xy 108.129832 -37.110162) (xy 108.138214 -37.107876) (xy 108.163479 -37.101248)
			(xy 108.215222 -37.094107) (xy 108.241338 -37.093652) (xy 108.269076 -37.094152) (xy 108.323967 -37.10219)
			(xy 108.377115 -37.118089) (xy 108.427402 -37.141517) (xy 108.473767 -37.171978) (xy 108.515233 -37.208831)
			(xy 108.550926 -37.251299) (xy 108.580095 -37.298487) (xy 108.602125 -37.349401) (xy 108.616551 -37.402969)
			(xy 108.620306 -37.430456) (xy 108.62183 -37.444934) (xy 108.6231 -37.47516) (xy 108.622639 -37.502014)
			(xy 108.615104 -37.555191) (xy 108.600191 -37.606786) (xy 108.578194 -37.655783) (xy 108.574048 -37.662358)
			(xy 110.048546 -37.662358) (xy 110.052617 -37.606736) (xy 110.064743 -37.552299) (xy 110.084666 -37.500208)
			(xy 110.111962 -37.451573) (xy 110.146048 -37.40743) (xy 110.186197 -37.368721) (xy 110.231555 -37.33627)
			(xy 110.281155 -37.310769) (xy 110.333939 -37.292762) (xy 110.388782 -37.282632) (xy 110.444516 -37.280595)
			(xy 110.499953 -37.286695) (xy 110.55391 -37.300801) (xy 110.605239 -37.322613) (xy 110.652845 -37.351667)
			(xy 110.695713 -37.387342) (xy 110.73293 -37.428879) (xy 110.763703 -37.475392) (xy 110.787375 -37.525889)
			(xy 110.803443 -37.579296) (xy 110.811563 -37.634472) (xy 110.812072 -37.662358) (xy 110.811563 -37.690244)
			(xy 110.803443 -37.74542) (xy 110.794809 -37.774118) (xy 121.564906 -37.774118) (xy 121.568977 -37.718496)
			(xy 121.581103 -37.664059) (xy 121.601026 -37.611968) (xy 121.628322 -37.563333) (xy 121.662408 -37.51919)
			(xy 121.702557 -37.480481) (xy 121.747915 -37.44803) (xy 121.797515 -37.422529) (xy 121.850299 -37.404522)
			(xy 121.905142 -37.394392) (xy 121.960876 -37.392355) (xy 122.016313 -37.398455) (xy 122.07027 -37.412561)
			(xy 122.121599 -37.434373) (xy 122.169205 -37.463427) (xy 122.212073 -37.499102) (xy 122.24929 -37.540639)
			(xy 122.280063 -37.587152) (xy 122.303735 -37.637649) (xy 122.319803 -37.691056) (xy 122.327923 -37.746232)
			(xy 122.328432 -37.774118) (xy 122.327923 -37.802004) (xy 122.319803 -37.85718) (xy 122.303735 -37.910587)
			(xy 122.280063 -37.961084) (xy 122.24929 -38.007597) (xy 122.212073 -38.049134) (xy 122.169205 -38.084809)
			(xy 122.121599 -38.113863) (xy 122.07027 -38.135675) (xy 122.016313 -38.149781) (xy 121.960876 -38.155881)
			(xy 121.905142 -38.153844) (xy 121.850299 -38.143714) (xy 121.797515 -38.125707) (xy 121.747915 -38.100206)
			(xy 121.702557 -38.067755) (xy 121.662408 -38.029046) (xy 121.628322 -37.984903) (xy 121.601026 -37.936268)
			(xy 121.581103 -37.884177) (xy 121.568977 -37.82974) (xy 121.564906 -37.774118) (xy 110.794809 -37.774118)
			(xy 110.787375 -37.798827) (xy 110.763703 -37.849324) (xy 110.73293 -37.895837) (xy 110.695713 -37.937374)
			(xy 110.652845 -37.973049) (xy 110.605239 -38.002103) (xy 110.55391 -38.023915) (xy 110.499953 -38.038021)
			(xy 110.444516 -38.044121) (xy 110.388782 -38.042084) (xy 110.333939 -38.031954) (xy 110.281155 -38.013947)
			(xy 110.231555 -37.988446) (xy 110.186197 -37.955995) (xy 110.146048 -37.917286) (xy 110.111962 -37.873143)
			(xy 110.084666 -37.824508) (xy 110.064743 -37.772417) (xy 110.052617 -37.71798) (xy 110.048546 -37.662358)
			(xy 108.574048 -37.662358) (xy 108.549547 -37.701214) (xy 108.514817 -37.742181) (xy 108.495084 -37.760402)
			(xy 108.49483 -37.760656) (xy 108.488681 -37.766589) (xy 108.480376 -37.781513) (xy 108.478574 -37.789866)
			(xy 108.47705 -37.797994) (xy 108.479844 -37.815012) (xy 108.816394 -38.430454) (xy 108.979995 -38.729952)
			(xy 113.801097 -38.729952) (xy 113.801097 -38.675448) (xy 113.808855 -38.621499) (xy 113.824211 -38.569204)
			(xy 113.846854 -38.519626) (xy 113.876323 -38.473776) (xy 113.912018 -38.432587) (xy 113.953211 -38.396897)
			(xy 113.999065 -38.367433) (xy 114.048645 -38.344796) (xy 114.100942 -38.329445) (xy 114.154892 -38.321694)
			(xy 114.182144 -38.321234) (xy 114.210447 -38.321752) (xy 114.266435 -38.330097) (xy 114.320575 -38.346626)
			(xy 114.371676 -38.370976) (xy 114.418616 -38.402613) (xy 114.460364 -38.440841) (xy 114.496003 -38.48482)
			(xy 114.51082 -38.50894) (xy 114.518425 -38.520969) (xy 114.539042 -38.540571) (xy 114.564273 -38.553713)
			(xy 114.592152 -38.559374) (xy 114.62051 -38.557111) (xy 114.647139 -38.547101) (xy 114.669966 -38.530123)
			(xy 114.678968 -38.5191) (xy 114.697178 -38.496243) (xy 114.739336 -38.455778) (xy 114.787167 -38.422209)
			(xy 114.839554 -38.396318) (xy 114.895274 -38.378712) (xy 114.953026 -38.3698) (xy 114.982244 -38.36924)
			(xy 115.009497 -38.369633) (xy 115.063446 -38.377395) (xy 115.115742 -38.392756) (xy 115.16532 -38.415403)
			(xy 115.211171 -38.444874) (xy 115.252361 -38.48057) (xy 115.288052 -38.521764) (xy 115.317518 -38.567618)
			(xy 115.340159 -38.617199) (xy 115.355514 -38.669497) (xy 115.36327 -38.723447) (xy 115.36327 -38.777953)
			(xy 115.355514 -38.831903) (xy 115.340159 -38.884201) (xy 115.317518 -38.933782) (xy 115.288052 -38.979636)
			(xy 115.252361 -39.02083) (xy 115.211171 -39.056526) (xy 115.16532 -39.085997) (xy 115.115742 -39.108644)
			(xy 115.063446 -39.124005) (xy 115.009497 -39.131767) (xy 114.982244 -39.132256) (xy 114.95394 -39.131752)
			(xy 114.897951 -39.123406) (xy 114.843811 -39.106874) (xy 114.79271 -39.082522) (xy 114.74577 -39.050883)
			(xy 114.704022 -39.012653) (xy 114.668385 -38.968671) (xy 114.653568 -38.94455) (xy 114.645978 -38.93251)
			(xy 114.625357 -38.91291) (xy 114.600124 -38.899769) (xy 114.572242 -38.89411) (xy 114.543882 -38.896375)
			(xy 114.517251 -38.906387) (xy 114.494423 -38.923366) (xy 114.48542 -38.93439) (xy 114.467215 -38.95725)
			(xy 114.425056 -38.997716) (xy 114.377224 -39.031285) (xy 114.324836 -39.057175) (xy 114.269115 -39.074781)
			(xy 114.211362 -39.083691) (xy 114.182144 -39.08425) (xy 114.154892 -39.083706) (xy 114.100942 -39.075955)
			(xy 114.048645 -39.060604) (xy 113.999065 -39.037967) (xy 113.953211 -39.008503) (xy 113.912018 -38.972813)
			(xy 113.876323 -38.931624) (xy 113.846854 -38.885774) (xy 113.824211 -38.836196) (xy 113.808855 -38.783901)
			(xy 113.801097 -38.729952) (xy 108.979995 -38.729952) (xy 109.306868 -39.328344) (xy 109.323239 -39.358805)
			(xy 109.352221 -39.4216) (xy 109.36478 -39.45382) (xy 109.373601 -39.477592) (xy 109.389105 -39.525875)
			(xy 109.395768 -39.55034) (xy 109.507896 -39.97198) (xy 115.995956 -39.97198) (xy 116.000027 -39.916358)
			(xy 116.012153 -39.861921) (xy 116.032076 -39.80983) (xy 116.059372 -39.761195) (xy 116.093458 -39.717052)
			(xy 116.133607 -39.678343) (xy 116.178965 -39.645892) (xy 116.228565 -39.620391) (xy 116.281349 -39.602384)
			(xy 116.336192 -39.592254) (xy 116.391926 -39.590217) (xy 116.447363 -39.596317) (xy 116.50132 -39.610423)
			(xy 116.552649 -39.632235) (xy 116.600255 -39.661289) (xy 116.643123 -39.696964) (xy 116.68034 -39.738501)
			(xy 116.711113 -39.785014) (xy 116.734785 -39.835511) (xy 116.750853 -39.888918) (xy 116.758973 -39.944094)
			(xy 116.759482 -39.97198) (xy 116.758973 -39.999866) (xy 116.750853 -40.055042) (xy 116.734785 -40.108449)
			(xy 116.711113 -40.158946) (xy 116.68034 -40.205459) (xy 116.643123 -40.246996) (xy 116.600255 -40.282671)
			(xy 116.552649 -40.311725) (xy 116.50132 -40.333537) (xy 116.447363 -40.347643) (xy 116.391926 -40.353743)
			(xy 116.336192 -40.351706) (xy 116.281349 -40.341576) (xy 116.228565 -40.323569) (xy 116.178965 -40.298068)
			(xy 116.133607 -40.265617) (xy 116.093458 -40.226908) (xy 116.059372 -40.182765) (xy 116.032076 -40.13413)
			(xy 116.012153 -40.082039) (xy 116.000027 -40.027602) (xy 115.995956 -39.97198) (xy 109.507896 -39.97198)
			(xy 109.610906 -40.35933) (xy 109.710982 -40.736012) (xy 109.715046 -40.745664) (xy 109.838245 -40.971724)
			(xy 116.694202 -40.971724) (xy 116.698273 -40.916102) (xy 116.710399 -40.861665) (xy 116.730322 -40.809574)
			(xy 116.757618 -40.760939) (xy 116.791704 -40.716796) (xy 116.831853 -40.678087) (xy 116.877211 -40.645636)
			(xy 116.926811 -40.620135) (xy 116.979595 -40.602128) (xy 117.034438 -40.591998) (xy 117.090172 -40.589961)
			(xy 117.145609 -40.596061) (xy 117.199566 -40.610167) (xy 117.250895 -40.631979) (xy 117.298501 -40.661033)
			(xy 117.341369 -40.696708) (xy 117.378586 -40.738245) (xy 117.409359 -40.784758) (xy 117.433031 -40.835255)
			(xy 117.449099 -40.888662) (xy 117.457219 -40.943838) (xy 117.457728 -40.971724) (xy 117.457219 -40.99961)
			(xy 117.449099 -41.054786) (xy 117.433031 -41.108193) (xy 117.409359 -41.15869) (xy 117.378586 -41.205203)
			(xy 117.341369 -41.24674) (xy 117.314915 -41.268755) (xy 131.944027 -41.268755) (xy 131.944027 -41.214245)
			(xy 131.951785 -41.160289) (xy 131.967142 -41.107986) (xy 131.989787 -41.058402) (xy 132.019258 -41.012545)
			(xy 132.054956 -40.971349) (xy 132.096153 -40.935652) (xy 132.142011 -40.906183) (xy 132.191596 -40.883539)
			(xy 132.243899 -40.868183) (xy 132.297855 -40.860426) (xy 132.32511 -40.859964) (xy 132.353849 -40.860491)
			(xy 132.410675 -40.869114) (xy 132.465566 -40.886164) (xy 132.517278 -40.911255) (xy 132.564641 -40.943818)
			(xy 132.585968 -40.963088) (xy 132.592826 -40.969692) (xy 132.61086 -40.976804) (xy 132.69976 -40.976804)
			(xy 132.717794 -40.969692) (xy 132.724652 -40.963088) (xy 132.745982 -40.943821) (xy 132.793343 -40.911252)
			(xy 132.845053 -40.886158) (xy 132.899944 -40.869107) (xy 132.956771 -40.860484) (xy 132.98551 -40.859964)
			(xy 133.012759 -40.860507) (xy 133.066701 -40.868264) (xy 133.118991 -40.883619) (xy 133.168563 -40.906259)
			(xy 133.214409 -40.935723) (xy 133.255595 -40.971412) (xy 133.291283 -41.012599) (xy 133.320746 -41.058445)
			(xy 133.343385 -41.108018) (xy 133.358738 -41.160308) (xy 133.366494 -41.214251) (xy 133.366494 -41.268749)
			(xy 133.358738 -41.322692) (xy 133.343385 -41.374982) (xy 133.320746 -41.424555) (xy 133.291283 -41.470401)
			(xy 133.255595 -41.511588) (xy 133.214409 -41.547277) (xy 133.168563 -41.576741) (xy 133.118991 -41.599381)
			(xy 133.066701 -41.614736) (xy 133.012759 -41.622493) (xy 132.98551 -41.62298) (xy 132.956772 -41.622429)
			(xy 132.899947 -41.61381) (xy 132.845058 -41.596765) (xy 132.793345 -41.57168) (xy 132.745981 -41.539123)
			(xy 132.724652 -41.519856) (xy 132.717794 -41.513252) (xy 132.69976 -41.50614) (xy 132.61086 -41.50614)
			(xy 132.592826 -41.513252) (xy 132.585968 -41.519856) (xy 132.564636 -41.539121) (xy 132.517275 -41.571688)
			(xy 132.465565 -41.596782) (xy 132.410675 -41.613834) (xy 132.353849 -41.622458) (xy 132.32511 -41.62298)
			(xy 132.297855 -41.622574) (xy 132.243899 -41.614817) (xy 132.191596 -41.599461) (xy 132.142011 -41.576817)
			(xy 132.096153 -41.547348) (xy 132.054956 -41.511651) (xy 132.019258 -41.470455) (xy 131.989787 -41.424598)
			(xy 131.967142 -41.375014) (xy 131.951785 -41.322711) (xy 131.944027 -41.268755) (xy 117.314915 -41.268755)
			(xy 117.298501 -41.282415) (xy 117.250895 -41.311469) (xy 117.199566 -41.333281) (xy 117.145609 -41.347387)
			(xy 117.090172 -41.353487) (xy 117.034438 -41.35145) (xy 116.979595 -41.34132) (xy 116.926811 -41.323313)
			(xy 116.877211 -41.297812) (xy 116.831853 -41.265361) (xy 116.791704 -41.226652) (xy 116.757618 -41.182509)
			(xy 116.730322 -41.133874) (xy 116.710399 -41.081783) (xy 116.698273 -41.027346) (xy 116.694202 -40.971724)
			(xy 109.838245 -40.971724) (xy 109.955076 -41.1861) (xy 109.977848 -41.229089) (xy 110.015802 -41.318668)
			(xy 110.044782 -41.41154) (xy 110.064508 -41.506808) (xy 110.07479 -41.603552) (xy 110.075726 -41.65219)
			(xy 110.075726 -41.652698) (xy 110.085632 -42.142918) (xy 110.08614 -42.146728) (xy 110.092744 -42.171874)
			(xy 110.09757 -42.189908) (xy 110.107443 -42.228571) (xy 110.121714 -42.307088) (xy 110.129658 -42.386496)
			(xy 110.130844 -42.426382) (xy 110.148349 -43.305222) (xy 134.407402 -43.305222) (xy 134.40788 -43.277852)
			(xy 134.415695 -43.223674) (xy 134.431181 -43.171171) (xy 134.45402 -43.121424) (xy 134.483742 -43.075456)
			(xy 134.501382 -43.054524) (xy 134.501636 -43.05427) (xy 134.507203 -43.047171) (xy 134.513461 -43.030263)
			(xy 134.513828 -43.02125) (xy 134.513828 -42.954194) (xy 134.513468 -42.945178) (xy 134.507222 -42.928261)
			(xy 134.501636 -42.921174) (xy 134.501382 -42.921174) (xy 134.501382 -42.92092) (xy 134.483736 -42.899994)
			(xy 134.454026 -42.854019) (xy 134.431192 -42.80427) (xy 134.415702 -42.751768) (xy 134.407875 -42.697592)
			(xy 134.407402 -42.670222) (xy 134.407939 -42.641484) (xy 134.416558 -42.584657) (xy 134.433605 -42.529766)
			(xy 134.458694 -42.478054) (xy 134.491256 -42.430691) (xy 134.510526 -42.409364) (xy 134.51713 -42.402506)
			(xy 134.524242 -42.384472) (xy 134.524242 -42.295572) (xy 134.51713 -42.277538) (xy 134.510526 -42.27068)
			(xy 134.491277 -42.249334) (xy 134.458711 -42.201975) (xy 134.433618 -42.150267) (xy 134.416566 -42.095379)
			(xy 134.407941 -42.038554) (xy 134.407939 -41.981078) (xy 134.416559 -41.924253) (xy 134.433606 -41.869363)
			(xy 134.458695 -41.817653) (xy 134.491257 -41.770291) (xy 134.510526 -41.748964) (xy 134.51713 -41.742106)
			(xy 134.524242 -41.724072) (xy 134.524242 -41.635172) (xy 134.51713 -41.617138) (xy 134.510526 -41.61028)
			(xy 134.491264 -41.588946) (xy 134.458697 -41.541585) (xy 134.433603 -41.489876) (xy 134.41655 -41.434987)
			(xy 134.407925 -41.37816) (xy 134.407402 -41.349422) (xy 134.407888 -41.322171) (xy 134.415644 -41.268223)
			(xy 134.430999 -41.215928) (xy 134.453641 -41.166351) (xy 134.483107 -41.120501) (xy 134.518798 -41.07931)
			(xy 134.559989 -41.043619) (xy 134.605839 -41.014153) (xy 134.655416 -40.991511) (xy 134.707711 -40.976156)
			(xy 134.761659 -40.9684) (xy 134.816161 -40.9684) (xy 134.870109 -40.976156) (xy 134.922404 -40.991511)
			(xy 134.971981 -41.014153) (xy 135.017831 -41.043619) (xy 135.059022 -41.07931) (xy 135.094713 -41.120501)
			(xy 135.124179 -41.166351) (xy 135.146821 -41.215928) (xy 135.162176 -41.268223) (xy 135.169932 -41.322171)
			(xy 135.170418 -41.349422) (xy 135.169903 -41.378161) (xy 135.161277 -41.434989) (xy 135.144225 -41.489879)
			(xy 135.119132 -41.541591) (xy 135.086565 -41.588953) (xy 135.067294 -41.61028) (xy 135.06069 -41.617138)
			(xy 135.053578 -41.635172) (xy 135.053578 -41.724072) (xy 135.06069 -41.742106) (xy 135.067294 -41.748964)
			(xy 135.086586 -41.770272) (xy 135.119149 -41.817638) (xy 135.144238 -41.869353) (xy 135.161286 -41.924247)
			(xy 135.169906 -41.981076) (xy 135.169903 -42.038556) (xy 135.161278 -42.095385) (xy 135.144226 -42.150277)
			(xy 135.119133 -42.201989) (xy 135.086566 -42.249353) (xy 135.067294 -42.27068) (xy 135.06069 -42.277538)
			(xy 135.053578 -42.295572) (xy 135.053578 -42.384472) (xy 135.06069 -42.402506) (xy 135.067294 -42.409364)
			(xy 135.086564 -42.430692) (xy 135.119132 -42.478053) (xy 135.144226 -42.529764) (xy 135.161277 -42.584655)
			(xy 135.169898 -42.641483) (xy 135.170418 -42.670222) (xy 135.169985 -42.697594) (xy 135.162162 -42.751775)
			(xy 135.146666 -42.804279) (xy 135.126108 -42.849038) (xy 136.992104 -42.849038) (xy 136.996175 -42.793416)
			(xy 137.008301 -42.738979) (xy 137.028224 -42.686888) (xy 137.05552 -42.638253) (xy 137.089606 -42.59411)
			(xy 137.129755 -42.555401) (xy 137.175113 -42.52295) (xy 137.224713 -42.497449) (xy 137.277497 -42.479442)
			(xy 137.33234 -42.469312) (xy 137.388074 -42.467275) (xy 137.443511 -42.473375) (xy 137.497468 -42.487481)
			(xy 137.548797 -42.509293) (xy 137.596403 -42.538347) (xy 137.639271 -42.574022) (xy 137.676488 -42.615559)
			(xy 137.707261 -42.662072) (xy 137.730933 -42.712569) (xy 137.747001 -42.765976) (xy 137.755121 -42.821152)
			(xy 137.75563 -42.849038) (xy 137.755121 -42.876924) (xy 137.747001 -42.9321) (xy 137.730933 -42.985507)
			(xy 137.707261 -43.036004) (xy 137.676488 -43.082517) (xy 137.639271 -43.124054) (xy 137.596403 -43.159729)
			(xy 137.548797 -43.188783) (xy 137.497468 -43.210595) (xy 137.443511 -43.224701) (xy 137.388074 -43.230801)
			(xy 137.33234 -43.228764) (xy 137.277497 -43.218634) (xy 137.224713 -43.200627) (xy 137.175113 -43.175126)
			(xy 137.129755 -43.142675) (xy 137.089606 -43.103966) (xy 137.05552 -43.059823) (xy 137.028224 -43.011188)
			(xy 137.008301 -42.959097) (xy 136.996175 -42.90466) (xy 136.992104 -42.849038) (xy 135.126108 -42.849038)
			(xy 135.123817 -42.854026) (xy 135.094084 -42.89999) (xy 135.076438 -42.92092) (xy 135.076184 -42.921174)
			(xy 135.0706 -42.928263) (xy 135.064352 -42.945178) (xy 135.063992 -42.954194) (xy 135.063992 -43.02125)
			(xy 135.064374 -43.030264) (xy 135.070604 -43.047181) (xy 135.076184 -43.05427) (xy 135.076438 -43.05427)
			(xy 135.076438 -43.054524) (xy 135.094061 -43.075469) (xy 135.123774 -43.121439) (xy 135.146613 -43.171183)
			(xy 135.162108 -43.223681) (xy 135.169941 -43.277854) (xy 135.170418 -43.305222) (xy 135.169932 -43.332473)
			(xy 135.162176 -43.386421) (xy 135.146821 -43.438716) (xy 135.124179 -43.488293) (xy 135.094713 -43.534143)
			(xy 135.059022 -43.575334) (xy 135.017831 -43.611025) (xy 134.971981 -43.640491) (xy 134.922404 -43.663133)
			(xy 134.870109 -43.678488) (xy 134.816161 -43.686244) (xy 134.761659 -43.686244) (xy 134.707711 -43.678488)
			(xy 134.655416 -43.663133) (xy 134.605839 -43.640491) (xy 134.559989 -43.611025) (xy 134.518798 -43.575334)
			(xy 134.483107 -43.534143) (xy 134.453641 -43.488293) (xy 134.430999 -43.438716) (xy 134.415644 -43.386421)
			(xy 134.407888 -43.332473) (xy 134.407402 -43.305222) (xy 110.148349 -43.305222) (xy 110.156934 -43.73626)
			(xy 136.313162 -43.73626) (xy 136.317233 -43.680638) (xy 136.329359 -43.626201) (xy 136.349282 -43.57411)
			(xy 136.376578 -43.525475) (xy 136.410664 -43.481332) (xy 136.450813 -43.442623) (xy 136.496171 -43.410172)
			(xy 136.545771 -43.384671) (xy 136.598555 -43.366664) (xy 136.653398 -43.356534) (xy 136.709132 -43.354497)
			(xy 136.764569 -43.360597) (xy 136.818526 -43.374703) (xy 136.869855 -43.396515) (xy 136.917461 -43.425569)
			(xy 136.960329 -43.461244) (xy 136.997546 -43.502781) (xy 137.028319 -43.549294) (xy 137.051991 -43.599791)
			(xy 137.068059 -43.653198) (xy 137.076179 -43.708374) (xy 137.076688 -43.73626) (xy 137.076179 -43.764146)
			(xy 137.068059 -43.819322) (xy 137.05675 -43.85691) (xy 140.819884 -43.85691) (xy 140.823955 -43.801288)
			(xy 140.836081 -43.746851) (xy 140.856004 -43.69476) (xy 140.8833 -43.646125) (xy 140.917386 -43.601982)
			(xy 140.957535 -43.563273) (xy 141.002893 -43.530822) (xy 141.052493 -43.505321) (xy 141.105277 -43.487314)
			(xy 141.16012 -43.477184) (xy 141.215854 -43.475147) (xy 141.271291 -43.481247) (xy 141.325248 -43.495353)
			(xy 141.376577 -43.517165) (xy 141.424183 -43.546219) (xy 141.467051 -43.581894) (xy 141.504268 -43.623431)
			(xy 141.535041 -43.669944) (xy 141.558713 -43.720441) (xy 141.574781 -43.773848) (xy 141.582901 -43.829024)
			(xy 141.58341 -43.85691) (xy 141.582901 -43.884796) (xy 141.574781 -43.939972) (xy 141.558713 -43.993379)
			(xy 141.535041 -44.043876) (xy 141.504268 -44.090389) (xy 141.467051 -44.131926) (xy 141.424183 -44.167601)
			(xy 141.376577 -44.196655) (xy 141.325248 -44.218467) (xy 141.271291 -44.232573) (xy 141.215854 -44.238673)
			(xy 141.16012 -44.236636) (xy 141.105277 -44.226506) (xy 141.052493 -44.208499) (xy 141.002893 -44.182998)
			(xy 140.957535 -44.150547) (xy 140.917386 -44.111838) (xy 140.8833 -44.067695) (xy 140.856004 -44.01906)
			(xy 140.836081 -43.966969) (xy 140.823955 -43.912532) (xy 140.819884 -43.85691) (xy 137.05675 -43.85691)
			(xy 137.051991 -43.872729) (xy 137.028319 -43.923226) (xy 136.997546 -43.969739) (xy 136.960329 -44.011276)
			(xy 136.917461 -44.046951) (xy 136.869855 -44.076005) (xy 136.818526 -44.097817) (xy 136.764569 -44.111923)
			(xy 136.709132 -44.118023) (xy 136.653398 -44.115986) (xy 136.598555 -44.105856) (xy 136.545771 -44.087849)
			(xy 136.496171 -44.062348) (xy 136.450813 -44.029897) (xy 136.410664 -43.991188) (xy 136.376578 -43.947045)
			(xy 136.349282 -43.89841) (xy 136.329359 -43.846319) (xy 136.317233 -43.791882) (xy 136.313162 -43.73626)
			(xy 110.156934 -43.73626) (xy 110.184385 -45.114464) (xy 136.165588 -45.114464) (xy 136.169659 -45.058842)
			(xy 136.181785 -45.004405) (xy 136.201708 -44.952314) (xy 136.229004 -44.903679) (xy 136.26309 -44.859536)
			(xy 136.303239 -44.820827) (xy 136.348597 -44.788376) (xy 136.398197 -44.762875) (xy 136.450981 -44.744868)
			(xy 136.505824 -44.734738) (xy 136.561558 -44.732701) (xy 136.616995 -44.738801) (xy 136.670952 -44.752907)
			(xy 136.722281 -44.774719) (xy 136.769887 -44.803773) (xy 136.812755 -44.839448) (xy 136.842737 -44.87291)
			(xy 143.03324 -44.87291) (xy 143.037311 -44.817288) (xy 143.049437 -44.762851) (xy 143.06936 -44.71076)
			(xy 143.096656 -44.662125) (xy 143.130742 -44.617982) (xy 143.170891 -44.579273) (xy 143.216249 -44.546822)
			(xy 143.265849 -44.521321) (xy 143.318633 -44.503314) (xy 143.373476 -44.493184) (xy 143.42921 -44.491147)
			(xy 143.484647 -44.497247) (xy 143.538604 -44.511353) (xy 143.589933 -44.533165) (xy 143.637539 -44.562219)
			(xy 143.680407 -44.597894) (xy 143.717624 -44.639431) (xy 143.748397 -44.685944) (xy 143.772069 -44.736441)
			(xy 143.788137 -44.789848) (xy 143.796257 -44.845024) (xy 143.796766 -44.87291) (xy 143.796257 -44.900796)
			(xy 143.788137 -44.955972) (xy 143.772069 -45.009379) (xy 143.748397 -45.059876) (xy 143.717624 -45.106389)
			(xy 143.680407 -45.147926) (xy 143.637539 -45.183601) (xy 143.589933 -45.212655) (xy 143.538604 -45.234467)
			(xy 143.484647 -45.248573) (xy 143.42921 -45.254673) (xy 143.373476 -45.252636) (xy 143.318633 -45.242506)
			(xy 143.265849 -45.224499) (xy 143.216249 -45.198998) (xy 143.170891 -45.166547) (xy 143.130742 -45.127838)
			(xy 143.096656 -45.083695) (xy 143.06936 -45.03506) (xy 143.049437 -44.982969) (xy 143.037311 -44.928532)
			(xy 143.03324 -44.87291) (xy 136.842737 -44.87291) (xy 136.849972 -44.880985) (xy 136.880745 -44.927498)
			(xy 136.904417 -44.977995) (xy 136.920485 -45.031402) (xy 136.928605 -45.086578) (xy 136.929114 -45.114464)
			(xy 136.928605 -45.14235) (xy 136.920485 -45.197526) (xy 136.904417 -45.250933) (xy 136.880745 -45.30143)
			(xy 136.849972 -45.347943) (xy 136.84433 -45.35424) (xy 140.803882 -45.35424) (xy 140.807953 -45.298618)
			(xy 140.820079 -45.244181) (xy 140.840002 -45.19209) (xy 140.867298 -45.143455) (xy 140.901384 -45.099312)
			(xy 140.941533 -45.060603) (xy 140.986891 -45.028152) (xy 141.036491 -45.002651) (xy 141.089275 -44.984644)
			(xy 141.144118 -44.974514) (xy 141.199852 -44.972477) (xy 141.255289 -44.978577) (xy 141.309246 -44.992683)
			(xy 141.360575 -45.014495) (xy 141.408181 -45.043549) (xy 141.451049 -45.079224) (xy 141.488266 -45.120761)
			(xy 141.519039 -45.167274) (xy 141.542711 -45.217771) (xy 141.558779 -45.271178) (xy 141.566899 -45.326354)
			(xy 141.567408 -45.35424) (xy 141.566899 -45.382126) (xy 141.558779 -45.437302) (xy 141.542711 -45.490709)
			(xy 141.519039 -45.541206) (xy 141.488266 -45.587719) (xy 141.451049 -45.629256) (xy 141.408181 -45.664931)
			(xy 141.360575 -45.693985) (xy 141.309246 -45.715797) (xy 141.255289 -45.729903) (xy 141.199852 -45.736003)
			(xy 141.144118 -45.733966) (xy 141.089275 -45.723836) (xy 141.036491 -45.705829) (xy 140.986891 -45.680328)
			(xy 140.941533 -45.647877) (xy 140.901384 -45.609168) (xy 140.867298 -45.565025) (xy 140.840002 -45.51639)
			(xy 140.820079 -45.464299) (xy 140.807953 -45.409862) (xy 140.803882 -45.35424) (xy 136.84433 -45.35424)
			(xy 136.812755 -45.38948) (xy 136.769887 -45.425155) (xy 136.722281 -45.454209) (xy 136.670952 -45.476021)
			(xy 136.616995 -45.490127) (xy 136.561558 -45.496227) (xy 136.505824 -45.49419) (xy 136.450981 -45.48406)
			(xy 136.398197 -45.466053) (xy 136.348597 -45.440552) (xy 136.303239 -45.408101) (xy 136.26309 -45.369392)
			(xy 136.229004 -45.325249) (xy 136.201708 -45.276614) (xy 136.181785 -45.224523) (xy 136.169659 -45.170086)
			(xy 136.165588 -45.114464) (xy 110.184385 -45.114464) (xy 110.20366 -46.082204) (xy 134.15264 -46.082204)
			(xy 134.153059 -46.054949) (xy 134.160817 -46.000994) (xy 134.176175 -45.948692) (xy 134.19882 -45.899109)
			(xy 134.228292 -45.853254) (xy 134.263991 -45.81206) (xy 134.305189 -45.776366) (xy 134.351048 -45.746899)
			(xy 134.400634 -45.724259) (xy 134.452937 -45.708908) (xy 134.506893 -45.701156) (xy 134.534148 -45.700696)
			(xy 134.561052 -45.701122) (xy 134.614323 -45.7087) (xy 134.666003 -45.723686) (xy 134.715064 -45.745782)
			(xy 134.760536 -45.77455) (xy 134.801517 -45.80942) (xy 134.837193 -45.8497) (xy 134.85241 -45.871892)
			(xy 134.859522 -45.882814) (xy 134.882382 -45.894752) (xy 134.99465 -45.89272) (xy 135.017002 -45.879766)
			(xy 135.02386 -45.86859) (xy 135.038754 -45.84497) (xy 135.074438 -45.802019) (xy 135.116001 -45.764727)
			(xy 135.162555 -45.733892) (xy 135.213107 -45.710171) (xy 135.266577 -45.694073) (xy 135.321822 -45.685939)
			(xy 135.349742 -45.685456) (xy 135.376736 -45.685893) (xy 135.430185 -45.693505) (xy 135.482029 -45.70857)
			(xy 135.531233 -45.73079) (xy 135.576816 -45.75972) (xy 135.597646 -45.776896) (xy 135.605774 -45.784008)
			(xy 135.626348 -45.790104) (xy 135.711692 -45.779182) (xy 135.722238 -45.777414) (xy 135.74052 -45.766355)
			(xy 135.746998 -45.757846) (xy 135.762359 -45.736621) (xy 135.797945 -45.698168) (xy 135.838461 -45.664949)
			(xy 135.883142 -45.63759) (xy 135.931149 -45.616605) (xy 135.981577 -45.602391) (xy 136.033476 -45.595214)
			(xy 136.059672 -45.594778) (xy 136.086925 -45.595267) (xy 136.140877 -45.603021) (xy 136.193176 -45.618374)
			(xy 136.242758 -45.641014) (xy 136.288613 -45.67048) (xy 136.329808 -45.706172) (xy 136.365503 -45.747364)
			(xy 136.394973 -45.793217) (xy 136.417616 -45.842797) (xy 136.432973 -45.895095) (xy 136.440731 -45.949047)
			(xy 136.440731 -46.003553) (xy 136.432973 -46.057505) (xy 136.417616 -46.109803) (xy 136.394973 -46.159383)
			(xy 136.365503 -46.205236) (xy 136.329808 -46.246428) (xy 136.288613 -46.28212) (xy 136.242758 -46.311586)
			(xy 136.193176 -46.334226) (xy 136.140877 -46.349579) (xy 136.086925 -46.357333) (xy 136.059672 -46.357794)
			(xy 136.032679 -46.357337) (xy 135.979231 -46.349728) (xy 135.927388 -46.334667) (xy 135.878183 -46.312452)
			(xy 135.832599 -46.283528) (xy 135.811768 -46.266354) (xy 135.80364 -46.259242) (xy 135.783066 -46.253146)
			(xy 135.697722 -46.264068) (xy 135.687182 -46.265861) (xy 135.668899 -46.276903) (xy 135.662416 -46.285404)
			(xy 135.644798 -46.3097) (xy 135.603206 -46.352962) (xy 135.579612 -46.37151) (xy 135.571738 -46.377352)
			(xy 135.561324 -46.394878) (xy 135.548116 -46.485302) (xy 135.552942 -46.504606) (xy 135.558784 -46.51248)
			(xy 135.558784 -46.512734) (xy 135.576288 -46.537477) (xy 135.60409 -46.591331) (xy 135.623026 -46.648903)
			(xy 135.630229 -46.693836) (xy 140.776452 -46.693836) (xy 140.776938 -46.666585) (xy 140.784694 -46.612637)
			(xy 140.800049 -46.560342) (xy 140.822691 -46.510765) (xy 140.852157 -46.464915) (xy 140.887848 -46.423724)
			(xy 140.929039 -46.388033) (xy 140.974889 -46.358567) (xy 141.024466 -46.335925) (xy 141.076761 -46.32057)
			(xy 141.130709 -46.312814) (xy 141.185211 -46.312814) (xy 141.239159 -46.32057) (xy 141.291454 -46.335925)
			(xy 141.341031 -46.358567) (xy 141.386881 -46.388033) (xy 141.428072 -46.423724) (xy 141.463763 -46.464915)
			(xy 141.493229 -46.510765) (xy 141.515871 -46.560342) (xy 141.531226 -46.612637) (xy 141.538982 -46.666585)
			(xy 141.539468 -46.693836) (xy 141.539 -46.720264) (xy 141.53169 -46.772611) (xy 141.517215 -46.823446)
			(xy 141.495853 -46.871793) (xy 141.482318 -46.894496) (xy 141.482064 -46.89475) (xy 141.476728 -46.904768)
			(xy 141.47447 -46.927318) (xy 141.477746 -46.938184) (xy 141.503908 -47.01286) (xy 141.508267 -47.023389)
			(xy 141.524373 -47.039472) (xy 141.534896 -47.043848) (xy 141.53515 -47.043848) (xy 141.55966 -47.052915)
			(xy 141.606112 -47.076858) (xy 141.648864 -47.106915) (xy 141.687116 -47.142522) (xy 141.720152 -47.183015)
			(xy 141.747356 -47.227637) (xy 141.768217 -47.275552) (xy 141.782347 -47.325865) (xy 141.789481 -47.377636)
			(xy 141.789912 -47.403766) (xy 141.789426 -47.431017) (xy 141.787903 -47.441612) (xy 143.061942 -47.441612)
			(xy 143.066013 -47.38599) (xy 143.078139 -47.331553) (xy 143.098062 -47.279462) (xy 143.125358 -47.230827)
			(xy 143.159444 -47.186684) (xy 143.199593 -47.147975) (xy 143.244951 -47.115524) (xy 143.294551 -47.090023)
			(xy 143.347335 -47.072016) (xy 143.402178 -47.061886) (xy 143.457912 -47.059849) (xy 143.513349 -47.065949)
			(xy 143.567306 -47.080055) (xy 143.618635 -47.101867) (xy 143.666241 -47.130921) (xy 143.709109 -47.166596)
			(xy 143.746326 -47.208133) (xy 143.777099 -47.254646) (xy 143.800771 -47.305143) (xy 143.816839 -47.35855)
			(xy 143.824959 -47.413726) (xy 143.825468 -47.441612) (xy 143.824959 -47.469498) (xy 143.816839 -47.524674)
			(xy 143.800771 -47.578081) (xy 143.777099 -47.628578) (xy 143.746326 -47.675091) (xy 143.709109 -47.716628)
			(xy 143.666241 -47.752303) (xy 143.618635 -47.781357) (xy 143.567306 -47.803169) (xy 143.513349 -47.817275)
			(xy 143.457912 -47.823375) (xy 143.402178 -47.821338) (xy 143.347335 -47.811208) (xy 143.294551 -47.793201)
			(xy 143.244951 -47.7677) (xy 143.199593 -47.735249) (xy 143.159444 -47.69654) (xy 143.125358 -47.652397)
			(xy 143.098062 -47.603762) (xy 143.078139 -47.551671) (xy 143.066013 -47.497234) (xy 143.061942 -47.441612)
			(xy 141.787903 -47.441612) (xy 141.78167 -47.484965) (xy 141.766315 -47.53726) (xy 141.743673 -47.586837)
			(xy 141.714207 -47.632687) (xy 141.678516 -47.673878) (xy 141.637325 -47.709569) (xy 141.591475 -47.739035)
			(xy 141.541898 -47.761677) (xy 141.489603 -47.777032) (xy 141.435655 -47.784788) (xy 141.381153 -47.784788)
			(xy 141.327205 -47.777032) (xy 141.27491 -47.761677) (xy 141.225333 -47.739035) (xy 141.179483 -47.709569)
			(xy 141.138292 -47.673878) (xy 141.102601 -47.632687) (xy 141.073135 -47.586837) (xy 141.050493 -47.53726)
			(xy 141.035138 -47.484965) (xy 141.027382 -47.431017) (xy 141.026896 -47.403766) (xy 141.02737 -47.377338)
			(xy 141.034679 -47.324991) (xy 141.049152 -47.274156) (xy 141.070511 -47.225809) (xy 141.084046 -47.203106)
			(xy 141.0843 -47.202852) (xy 141.089635 -47.192833) (xy 141.091896 -47.170283) (xy 141.088618 -47.159418)
			(xy 141.062456 -47.084742) (xy 141.058067 -47.074229) (xy 141.041982 -47.058139) (xy 141.031468 -47.053754)
			(xy 141.031214 -47.053754) (xy 141.006697 -47.044705) (xy 140.960246 -47.020758) (xy 140.917495 -46.990699)
			(xy 140.879245 -46.955088) (xy 140.846209 -46.914593) (xy 140.819007 -46.86997) (xy 140.798146 -46.822053)
			(xy 140.784017 -46.771738) (xy 140.776883 -46.719966) (xy 140.776452 -46.693836) (xy 135.630229 -46.693836)
			(xy 135.632619 -46.708745) (xy 135.633206 -46.739048) (xy 135.632767 -46.766301) (xy 135.625004 -46.82025)
			(xy 135.609642 -46.872546) (xy 135.586996 -46.922123) (xy 135.557524 -46.967974) (xy 135.521828 -47.009163)
			(xy 135.480633 -47.044854) (xy 135.434779 -47.07432) (xy 135.385199 -47.09696) (xy 135.332901 -47.112314)
			(xy 135.278951 -47.12007) (xy 135.251698 -47.120556) (xy 135.225665 -47.120102) (xy 135.174082 -47.113016)
			(xy 135.123941 -47.098988) (xy 135.07617 -47.078278) (xy 135.031655 -47.051271) (xy 135.01116 -47.035212)
			(xy 135.003392 -47.029487) (xy 134.98499 -47.023736) (xy 134.975346 -47.024036) (xy 134.89559 -47.030386)
			(xy 134.87781 -47.039022) (xy 134.87146 -47.046388) (xy 134.853272 -47.066027) (xy 134.812366 -47.10055)
			(xy 134.767038 -47.12902) (xy 134.718178 -47.150878) (xy 134.666744 -47.165697) (xy 134.613743 -47.173186)
			(xy 134.58698 -47.173642) (xy 134.55973 -47.173141) (xy 134.505784 -47.165383) (xy 134.453492 -47.150027)
			(xy 134.403917 -47.127386) (xy 134.358068 -47.09792) (xy 134.316879 -47.062231) (xy 134.281188 -47.021043)
			(xy 134.251721 -46.975195) (xy 134.229078 -46.925621) (xy 134.21372 -46.873329) (xy 134.20596 -46.819384)
			(xy 134.205472 -46.792134) (xy 134.206004 -46.76336) (xy 134.214654 -46.706467) (xy 134.231749 -46.651517)
			(xy 134.256901 -46.599757) (xy 134.289539 -46.55236) (xy 134.30885 -46.531022) (xy 134.316216 -46.523148)
			(xy 134.323328 -46.503336) (xy 134.315962 -46.40707) (xy 134.306056 -46.388274) (xy 134.297674 -46.38167)
			(xy 134.27548 -46.363457) (xy 134.236273 -46.321518) (xy 134.203789 -46.274179) (xy 134.178763 -46.222509)
			(xy 134.161758 -46.167674) (xy 134.153158 -46.11091) (xy 134.15264 -46.082204) (xy 110.20366 -46.082204)
			(xy 110.247973 -48.30699) (xy 140.654022 -48.30699) (xy 140.658093 -48.251368) (xy 140.670219 -48.196931)
			(xy 140.690142 -48.14484) (xy 140.717438 -48.096205) (xy 140.751524 -48.052062) (xy 140.791673 -48.013353)
			(xy 140.837031 -47.980902) (xy 140.886631 -47.955401) (xy 140.939415 -47.937394) (xy 140.994258 -47.927264)
			(xy 141.049992 -47.925227) (xy 141.105429 -47.931327) (xy 141.159386 -47.945433) (xy 141.210715 -47.967245)
			(xy 141.258321 -47.996299) (xy 141.301189 -48.031974) (xy 141.338406 -48.073511) (xy 141.369179 -48.120024)
			(xy 141.392851 -48.170521) (xy 141.408919 -48.223928) (xy 141.417039 -48.279104) (xy 141.417548 -48.30699)
			(xy 141.417039 -48.334876) (xy 141.408919 -48.390052) (xy 141.392851 -48.443459) (xy 141.369179 -48.493956)
			(xy 141.338406 -48.540469) (xy 141.301189 -48.582006) (xy 141.258321 -48.617681) (xy 141.210715 -48.646735)
			(xy 141.159386 -48.668547) (xy 141.105429 -48.682653) (xy 141.049992 -48.688753) (xy 140.994258 -48.686716)
			(xy 140.939415 -48.676586) (xy 140.886631 -48.658579) (xy 140.837031 -48.633078) (xy 140.791673 -48.600627)
			(xy 140.751524 -48.561918) (xy 140.717438 -48.517775) (xy 140.690142 -48.46914) (xy 140.670219 -48.417049)
			(xy 140.658093 -48.362612) (xy 140.654022 -48.30699) (xy 110.247973 -48.30699) (xy 110.256857 -48.753014)
			(xy 137.268456 -48.753014) (xy 137.272527 -48.697392) (xy 137.284653 -48.642955) (xy 137.304576 -48.590864)
			(xy 137.331872 -48.542229) (xy 137.365958 -48.498086) (xy 137.406107 -48.459377) (xy 137.451465 -48.426926)
			(xy 137.501065 -48.401425) (xy 137.553849 -48.383418) (xy 137.608692 -48.373288) (xy 137.664426 -48.371251)
			(xy 137.719863 -48.377351) (xy 137.77382 -48.391457) (xy 137.825149 -48.413269) (xy 137.872755 -48.442323)
			(xy 137.915623 -48.477998) (xy 137.95284 -48.519535) (xy 137.983613 -48.566048) (xy 138.007285 -48.616545)
			(xy 138.023353 -48.669952) (xy 138.031473 -48.725128) (xy 138.031982 -48.753014) (xy 138.031473 -48.7809)
			(xy 138.023353 -48.836076) (xy 138.007285 -48.889483) (xy 138.005889 -48.89246) (xy 139.314172 -48.89246)
			(xy 139.318243 -48.836838) (xy 139.330369 -48.782401) (xy 139.350292 -48.73031) (xy 139.377588 -48.681675)
			(xy 139.411674 -48.637532) (xy 139.451823 -48.598823) (xy 139.497181 -48.566372) (xy 139.546781 -48.540871)
			(xy 139.599565 -48.522864) (xy 139.654408 -48.512734) (xy 139.710142 -48.510697) (xy 139.765579 -48.516797)
			(xy 139.819536 -48.530903) (xy 139.870865 -48.552715) (xy 139.918471 -48.581769) (xy 139.961339 -48.617444)
			(xy 139.998556 -48.658981) (xy 140.029329 -48.705494) (xy 140.053001 -48.755991) (xy 140.069069 -48.809398)
			(xy 140.077189 -48.864574) (xy 140.077698 -48.89246) (xy 140.077189 -48.920346) (xy 140.074751 -48.93691)
			(xy 143.03324 -48.93691) (xy 143.037311 -48.881288) (xy 143.049437 -48.826851) (xy 143.06936 -48.77476)
			(xy 143.096656 -48.726125) (xy 143.130742 -48.681982) (xy 143.170891 -48.643273) (xy 143.216249 -48.610822)
			(xy 143.265849 -48.585321) (xy 143.318633 -48.567314) (xy 143.373476 -48.557184) (xy 143.42921 -48.555147)
			(xy 143.484647 -48.561247) (xy 143.538604 -48.575353) (xy 143.589933 -48.597165) (xy 143.637539 -48.626219)
			(xy 143.680407 -48.661894) (xy 143.717624 -48.703431) (xy 143.748397 -48.749944) (xy 143.772069 -48.800441)
			(xy 143.788137 -48.853848) (xy 143.796257 -48.909024) (xy 143.796766 -48.93691) (xy 143.796257 -48.964796)
			(xy 143.788137 -49.019972) (xy 143.772069 -49.073379) (xy 143.748397 -49.123876) (xy 143.717624 -49.170389)
			(xy 143.680407 -49.211926) (xy 143.637539 -49.247601) (xy 143.589933 -49.276655) (xy 143.538604 -49.298467)
			(xy 143.484647 -49.312573) (xy 143.42921 -49.318673) (xy 143.373476 -49.316636) (xy 143.318633 -49.306506)
			(xy 143.265849 -49.288499) (xy 143.216249 -49.262998) (xy 143.170891 -49.230547) (xy 143.130742 -49.191838)
			(xy 143.096656 -49.147695) (xy 143.06936 -49.09906) (xy 143.049437 -49.046969) (xy 143.037311 -48.992532)
			(xy 143.03324 -48.93691) (xy 140.074751 -48.93691) (xy 140.069069 -48.975522) (xy 140.053001 -49.028929)
			(xy 140.029329 -49.079426) (xy 139.998556 -49.125939) (xy 139.961339 -49.167476) (xy 139.918471 -49.203151)
			(xy 139.870865 -49.232205) (xy 139.819536 -49.254017) (xy 139.765579 -49.268123) (xy 139.710142 -49.274223)
			(xy 139.654408 -49.272186) (xy 139.599565 -49.262056) (xy 139.546781 -49.244049) (xy 139.497181 -49.218548)
			(xy 139.451823 -49.186097) (xy 139.411674 -49.147388) (xy 139.377588 -49.103245) (xy 139.350292 -49.05461)
			(xy 139.330369 -49.002519) (xy 139.318243 -48.948082) (xy 139.314172 -48.89246) (xy 138.005889 -48.89246)
			(xy 137.983613 -48.93998) (xy 137.95284 -48.986493) (xy 137.915623 -49.02803) (xy 137.872755 -49.063705)
			(xy 137.825149 -49.092759) (xy 137.77382 -49.114571) (xy 137.719863 -49.128677) (xy 137.664426 -49.134777)
			(xy 137.608692 -49.13274) (xy 137.553849 -49.12261) (xy 137.501065 -49.104603) (xy 137.451465 -49.079102)
			(xy 137.406107 -49.046651) (xy 137.365958 -49.007942) (xy 137.331872 -48.963799) (xy 137.304576 -48.915164)
			(xy 137.284653 -48.863073) (xy 137.272527 -48.808636) (xy 137.268456 -48.753014) (xy 110.256857 -48.753014)
			(xy 110.273766 -49.601953) (xy 122.213059 -49.601953) (xy 122.213059 -49.547447) (xy 122.220817 -49.493495)
			(xy 122.236173 -49.441196) (xy 122.258817 -49.391616) (xy 122.288286 -49.345762) (xy 122.323981 -49.30457)
			(xy 122.365175 -49.268876) (xy 122.41103 -49.239409) (xy 122.460611 -49.216768) (xy 122.512911 -49.201413)
			(xy 122.566863 -49.193658) (xy 122.594116 -49.193196) (xy 122.621487 -49.193654) (xy 122.675666 -49.201474)
			(xy 122.728169 -49.216965) (xy 122.777916 -49.239808) (xy 122.823882 -49.269534) (xy 122.844814 -49.287176)
			(xy 122.845068 -49.28743) (xy 122.852157 -49.293013) (xy 122.869072 -49.299261) (xy 122.878088 -49.299622)
			(xy 122.945144 -49.299622) (xy 122.954158 -49.299234) (xy 122.971075 -49.293007) (xy 122.978164 -49.28743)
			(xy 122.978164 -49.287176) (xy 122.978418 -49.287176) (xy 122.999351 -49.269535) (xy 123.045319 -49.239811)
			(xy 123.095065 -49.216965) (xy 123.147567 -49.201469) (xy 123.201745 -49.19364) (xy 123.256487 -49.19364)
			(xy 123.310665 -49.201469) (xy 123.363167 -49.216965) (xy 123.412913 -49.239811) (xy 123.458881 -49.269535)
			(xy 123.479814 -49.287176) (xy 123.480068 -49.28743) (xy 123.487157 -49.293013) (xy 123.504072 -49.299261)
			(xy 123.513088 -49.299622) (xy 123.580144 -49.299622) (xy 123.589158 -49.299234) (xy 123.606075 -49.293007)
			(xy 123.613164 -49.28743) (xy 123.613164 -49.287176) (xy 123.613418 -49.287176) (xy 123.634351 -49.269535)
			(xy 123.680319 -49.239811) (xy 123.730065 -49.216965) (xy 123.782567 -49.201469) (xy 123.836745 -49.19364)
			(xy 123.891487 -49.19364) (xy 123.945665 -49.201469) (xy 123.998167 -49.216965) (xy 124.047913 -49.239811)
			(xy 124.093881 -49.269535) (xy 124.114814 -49.287176) (xy 124.115068 -49.28743) (xy 124.122157 -49.293013)
			(xy 124.139072 -49.299261) (xy 124.148088 -49.299622) (xy 124.215144 -49.299622) (xy 124.224158 -49.299234)
			(xy 124.241075 -49.293007) (xy 124.248164 -49.28743) (xy 124.248164 -49.287176) (xy 124.248418 -49.287176)
			(xy 124.269367 -49.269558) (xy 124.315336 -49.239844) (xy 124.365079 -49.217004) (xy 124.417576 -49.201508)
			(xy 124.471748 -49.193674) (xy 124.499116 -49.193196) (xy 124.526367 -49.193675) (xy 124.580313 -49.201433)
			(xy 124.632607 -49.21679) (xy 124.682182 -49.239432) (xy 124.728031 -49.268899) (xy 124.76922 -49.304591)
			(xy 124.80491 -49.345781) (xy 124.834375 -49.391632) (xy 124.857016 -49.441208) (xy 124.87237 -49.493502)
			(xy 124.880126 -49.547449) (xy 124.880126 -49.601951) (xy 124.87237 -49.655898) (xy 124.857016 -49.708192)
			(xy 124.834375 -49.757768) (xy 124.80491 -49.803619) (xy 124.76922 -49.844809) (xy 124.728031 -49.880501)
			(xy 124.682182 -49.909968) (xy 124.632607 -49.93261) (xy 124.580313 -49.947967) (xy 124.545941 -49.95291)
			(xy 143.03324 -49.95291) (xy 143.037311 -49.897288) (xy 143.049437 -49.842851) (xy 143.06936 -49.79076)
			(xy 143.096656 -49.742125) (xy 143.130742 -49.697982) (xy 143.170891 -49.659273) (xy 143.216249 -49.626822)
			(xy 143.265849 -49.601321) (xy 143.318633 -49.583314) (xy 143.373476 -49.573184) (xy 143.42921 -49.571147)
			(xy 143.484647 -49.577247) (xy 143.538604 -49.591353) (xy 143.589933 -49.613165) (xy 143.637539 -49.642219)
			(xy 143.680407 -49.677894) (xy 143.717624 -49.719431) (xy 143.748397 -49.765944) (xy 143.772069 -49.816441)
			(xy 143.788137 -49.869848) (xy 143.796257 -49.925024) (xy 143.796766 -49.95291) (xy 143.796257 -49.980796)
			(xy 143.788137 -50.035972) (xy 143.772069 -50.089379) (xy 143.748397 -50.139876) (xy 143.717624 -50.186389)
			(xy 143.680407 -50.227926) (xy 143.637539 -50.263601) (xy 143.589933 -50.292655) (xy 143.538604 -50.314467)
			(xy 143.484647 -50.328573) (xy 143.42921 -50.334673) (xy 143.373476 -50.332636) (xy 143.318633 -50.322506)
			(xy 143.265849 -50.304499) (xy 143.216249 -50.278998) (xy 143.170891 -50.246547) (xy 143.130742 -50.207838)
			(xy 143.096656 -50.163695) (xy 143.06936 -50.11506) (xy 143.049437 -50.062969) (xy 143.037311 -50.008532)
			(xy 143.03324 -49.95291) (xy 124.545941 -49.95291) (xy 124.526367 -49.955725) (xy 124.499116 -49.956212)
			(xy 124.471746 -49.955734) (xy 124.417568 -49.947918) (xy 124.365065 -49.932432) (xy 124.315318 -49.909593)
			(xy 124.26935 -49.879872) (xy 124.248418 -49.862232) (xy 124.248164 -49.861978) (xy 124.241065 -49.85641)
			(xy 124.224158 -49.850153) (xy 124.215144 -49.849786) (xy 124.148088 -49.849786) (xy 124.139071 -49.85014)
			(xy 124.122154 -49.85639) (xy 124.115068 -49.861978) (xy 124.114814 -49.862232) (xy 124.093881 -49.879873)
			(xy 124.047913 -49.909597) (xy 123.998167 -49.932443) (xy 123.945665 -49.947939) (xy 123.891487 -49.955768)
			(xy 123.836745 -49.955768) (xy 123.782567 -49.947939) (xy 123.730065 -49.932443) (xy 123.680319 -49.909597)
			(xy 123.634351 -49.879873) (xy 123.613418 -49.862232) (xy 123.613164 -49.861978) (xy 123.606065 -49.85641)
			(xy 123.589158 -49.850153) (xy 123.580144 -49.849786) (xy 123.513088 -49.849786) (xy 123.504071 -49.85014)
			(xy 123.487154 -49.85639) (xy 123.480068 -49.861978) (xy 123.480068 -49.862232) (xy 123.479814 -49.862232)
			(xy 123.458881 -49.879873) (xy 123.412913 -49.909597) (xy 123.363167 -49.932443) (xy 123.310665 -49.947939)
			(xy 123.256487 -49.955768) (xy 123.201745 -49.955768) (xy 123.147567 -49.947939) (xy 123.095065 -49.932443)
			(xy 123.045319 -49.909597) (xy 122.999351 -49.879873) (xy 122.978418 -49.862232) (xy 122.978164 -49.861978)
			(xy 122.971065 -49.85641) (xy 122.954158 -49.850153) (xy 122.945144 -49.849786) (xy 122.878088 -49.849786)
			(xy 122.869071 -49.85014) (xy 122.852154 -49.85639) (xy 122.845068 -49.861978) (xy 122.845068 -49.862232)
			(xy 122.844814 -49.862232) (xy 122.823892 -49.879883) (xy 122.777916 -49.909592) (xy 122.728166 -49.932425)
			(xy 122.675663 -49.947913) (xy 122.621486 -49.955739) (xy 122.594116 -49.956212) (xy 122.566863 -49.955742)
			(xy 122.512911 -49.947987) (xy 122.460611 -49.932632) (xy 122.41103 -49.909991) (xy 122.365175 -49.880524)
			(xy 122.323981 -49.84483) (xy 122.288286 -49.803638) (xy 122.258817 -49.757784) (xy 122.236173 -49.708204)
			(xy 122.220817 -49.655905) (xy 122.213059 -49.601953) (xy 110.273766 -49.601953) (xy 110.306472 -51.243992)
			(xy 123.23318 -51.243992) (xy 123.233622 -51.216621) (xy 123.241443 -51.16244) (xy 123.256936 -51.109936)
			(xy 123.279784 -51.060189) (xy 123.309515 -51.014224) (xy 123.32716 -50.993294) (xy 123.327414 -50.99304)
			(xy 123.332992 -50.985947) (xy 123.339243 -50.969035) (xy 123.339606 -50.96002) (xy 123.339606 -50.892964)
			(xy 123.339265 -50.883946) (xy 123.333006 -50.867029) (xy 123.327414 -50.859944) (xy 123.32716 -50.859944)
			(xy 123.32716 -50.85969) (xy 123.309496 -50.838778) (xy 123.279789 -50.792799) (xy 123.256959 -50.743046)
			(xy 123.241473 -50.690542) (xy 123.233651 -50.636362) (xy 123.23318 -50.608992) (xy 123.23367 -50.581741)
			(xy 123.241428 -50.527794) (xy 123.256783 -50.4755) (xy 123.279424 -50.425924) (xy 123.30889 -50.380074)
			(xy 123.344581 -50.338884) (xy 123.385771 -50.303193) (xy 123.43162 -50.273726) (xy 123.481196 -50.251085)
			(xy 123.53349 -50.235728) (xy 123.587437 -50.227971) (xy 123.614688 -50.227484) (xy 123.643606 -50.227979)
			(xy 123.70078 -50.236708) (xy 123.755981 -50.253969) (xy 123.807943 -50.279365) (xy 123.855476 -50.312314)
			(xy 123.89749 -50.352061) (xy 123.915678 -50.37455) (xy 123.923296 -50.383346) (xy 123.944189 -50.393534)
			(xy 123.95581 -50.394108) (xy 124.035566 -50.394108) (xy 124.047193 -50.393532) (xy 124.068103 -50.383369)
			(xy 124.075698 -50.37455) (xy 124.093877 -50.352057) (xy 124.135901 -50.312325) (xy 124.183439 -50.279388)
			(xy 124.235402 -50.254002) (xy 124.290601 -50.236747) (xy 124.347772 -50.228019) (xy 124.376688 -50.227484)
			(xy 124.40394 -50.227966) (xy 124.45789 -50.235722) (xy 124.510187 -50.251076) (xy 124.559767 -50.273716)
			(xy 124.605619 -50.303182) (xy 124.646812 -50.338874) (xy 124.682506 -50.380065) (xy 124.711974 -50.425916)
			(xy 124.734617 -50.475494) (xy 124.749974 -50.52779) (xy 124.757732 -50.58174) (xy 124.758196 -50.608992)
			(xy 124.757725 -50.635306) (xy 124.750491 -50.687434) (xy 124.736172 -50.738077) (xy 124.715041 -50.786276)
			(xy 124.687495 -50.83112) (xy 124.654057 -50.871759) (xy 124.635006 -50.889916) (xy 124.627596 -50.897431)
			(xy 124.619076 -50.916716) (xy 124.618496 -50.927254) (xy 124.618496 -51.00193) (xy 124.619051 -51.012477)
			(xy 124.622132 -51.019456) (xy 140.849602 -51.019456) (xy 140.853673 -50.963834) (xy 140.865799 -50.909397)
			(xy 140.885722 -50.857306) (xy 140.913018 -50.808671) (xy 140.947104 -50.764528) (xy 140.987253 -50.725819)
			(xy 141.032611 -50.693368) (xy 141.082211 -50.667867) (xy 141.134995 -50.64986) (xy 141.189838 -50.63973)
			(xy 141.245572 -50.637693) (xy 141.301009 -50.643793) (xy 141.354966 -50.657899) (xy 141.406295 -50.679711)
			(xy 141.453901 -50.708765) (xy 141.496769 -50.74444) (xy 141.533986 -50.785977) (xy 141.564759 -50.83249)
			(xy 141.588431 -50.882987) (xy 141.604499 -50.936394) (xy 141.612619 -50.99157) (xy 141.613128 -51.019456)
			(xy 141.612619 -51.047342) (xy 141.604499 -51.102518) (xy 141.588431 -51.155925) (xy 141.564759 -51.206422)
			(xy 141.533986 -51.252935) (xy 141.496769 -51.294472) (xy 141.453901 -51.330147) (xy 141.406295 -51.359201)
			(xy 141.354966 -51.381013) (xy 141.301009 -51.395119) (xy 141.245572 -51.401219) (xy 141.189838 -51.399182)
			(xy 141.134995 -51.389052) (xy 141.082211 -51.371045) (xy 141.032611 -51.345544) (xy 140.987253 -51.313093)
			(xy 140.947104 -51.274384) (xy 140.913018 -51.230241) (xy 140.885722 -51.181606) (xy 140.865799 -51.129515)
			(xy 140.853673 -51.075078) (xy 140.849602 -51.019456) (xy 124.622132 -51.019456) (xy 124.627568 -51.031772)
			(xy 124.635006 -51.039268) (xy 124.654089 -51.057396) (xy 124.687543 -51.098032) (xy 124.715098 -51.142878)
			(xy 124.736232 -51.191084) (xy 124.750544 -51.241736) (xy 124.757761 -51.293874) (xy 124.758196 -51.320192)
			(xy 124.757737 -51.347445) (xy 124.749981 -51.401397) (xy 124.734625 -51.453696) (xy 124.711983 -51.503276)
			(xy 124.682515 -51.54913) (xy 124.64682 -51.590323) (xy 124.605627 -51.626017) (xy 124.559773 -51.655485)
			(xy 124.510192 -51.678127) (xy 124.457893 -51.693482) (xy 124.403941 -51.701237) (xy 124.376688 -51.7017)
			(xy 124.349023 -51.701197) (xy 124.294273 -51.693196) (xy 124.241251 -51.677378) (xy 124.191067 -51.654073)
			(xy 124.144771 -51.623771) (xy 124.103334 -51.587104) (xy 124.067621 -51.544842) (xy 124.052584 -51.521614)
			(xy 124.045965 -51.511923) (xy 124.02609 -51.499487) (xy 124.014484 -51.497738) (xy 123.934474 -51.489864)
			(xy 123.922835 -51.48922) (xy 123.900997 -51.497308) (xy 123.892564 -51.505358) (xy 123.89231 -51.505612)
			(xy 123.874209 -51.524173) (xy 123.833881 -51.556753) (xy 123.789511 -51.583568) (xy 123.741917 -51.604124)
			(xy 123.691976 -51.618042) (xy 123.64061 -51.625065) (xy 123.614688 -51.6255) (xy 123.587436 -51.625033)
			(xy 123.533487 -51.617275) (xy 123.481192 -51.601918) (xy 123.431614 -51.579275) (xy 123.385763 -51.549807)
			(xy 123.344573 -51.514113) (xy 123.308881 -51.472921) (xy 123.279416 -51.427069) (xy 123.256775 -51.37749)
			(xy 123.241421 -51.325193) (xy 123.233665 -51.271244) (xy 123.23318 -51.243992) (xy 110.306472 -51.243992)
			(xy 110.322236 -52.035456) (xy 143.041368 -52.035456) (xy 143.045439 -51.979834) (xy 143.057565 -51.925397)
			(xy 143.077488 -51.873306) (xy 143.104784 -51.824671) (xy 143.13887 -51.780528) (xy 143.179019 -51.741819)
			(xy 143.224377 -51.709368) (xy 143.273977 -51.683867) (xy 143.326761 -51.66586) (xy 143.381604 -51.65573)
			(xy 143.437338 -51.653693) (xy 143.492775 -51.659793) (xy 143.546732 -51.673899) (xy 143.598061 -51.695711)
			(xy 143.645667 -51.724765) (xy 143.688535 -51.76044) (xy 143.725752 -51.801977) (xy 143.756525 -51.84849)
			(xy 143.780197 -51.898987) (xy 143.796265 -51.952394) (xy 143.804385 -52.00757) (xy 143.804894 -52.035456)
			(xy 143.804385 -52.063342) (xy 143.796265 -52.118518) (xy 143.780197 -52.171925) (xy 143.756525 -52.222422)
			(xy 143.725752 -52.268935) (xy 143.688535 -52.310472) (xy 143.645667 -52.346147) (xy 143.598061 -52.375201)
			(xy 143.546732 -52.397013) (xy 143.492775 -52.411119) (xy 143.437338 -52.417219) (xy 143.381604 -52.415182)
			(xy 143.326761 -52.405052) (xy 143.273977 -52.387045) (xy 143.224377 -52.361544) (xy 143.179019 -52.329093)
			(xy 143.13887 -52.290384) (xy 143.104784 -52.246241) (xy 143.077488 -52.197606) (xy 143.057565 -52.145515)
			(xy 143.045439 -52.091078) (xy 143.041368 -52.035456) (xy 110.322236 -52.035456) (xy 110.332603 -52.555953)
			(xy 122.683979 -52.555953) (xy 122.683979 -52.501447) (xy 122.691737 -52.447497) (xy 122.707093 -52.3952)
			(xy 122.729737 -52.345621) (xy 122.759206 -52.299769) (xy 122.794901 -52.258578) (xy 122.836095 -52.222887)
			(xy 122.881949 -52.193421) (xy 122.93153 -52.170782) (xy 122.983828 -52.15543) (xy 123.037779 -52.147677)
			(xy 123.065032 -52.147216) (xy 123.092403 -52.147659) (xy 123.146583 -52.155482) (xy 123.199087 -52.170976)
			(xy 123.248833 -52.193823) (xy 123.294799 -52.223552) (xy 123.31573 -52.241196) (xy 123.315984 -52.24145)
			(xy 123.323067 -52.247042) (xy 123.339987 -52.253284) (xy 123.349004 -52.253642) (xy 123.41606 -52.253642)
			(xy 123.425076 -52.253278) (xy 123.441994 -52.247037) (xy 123.44908 -52.24145) (xy 123.44908 -52.241196)
			(xy 123.449334 -52.241196) (xy 123.47028 -52.223574) (xy 123.516249 -52.19386) (xy 123.565993 -52.17102)
			(xy 123.61849 -52.155525) (xy 123.672664 -52.147693) (xy 123.700032 -52.147216) (xy 123.727283 -52.147656)
			(xy 123.781231 -52.155417) (xy 123.833525 -52.170776) (xy 123.883102 -52.19342) (xy 123.928951 -52.222889)
			(xy 123.97014 -52.258583) (xy 124.00583 -52.299775) (xy 124.035295 -52.345626) (xy 124.057936 -52.395205)
			(xy 124.07329 -52.4475) (xy 124.081046 -52.501448) (xy 124.081046 -52.555952) (xy 124.07329 -52.6099)
			(xy 124.057936 -52.662195) (xy 124.035295 -52.711774) (xy 124.00583 -52.757625) (xy 123.97014 -52.798817)
			(xy 123.928951 -52.834511) (xy 123.883102 -52.86398) (xy 123.833525 -52.886624) (xy 123.781231 -52.901983)
			(xy 123.727283 -52.909744) (xy 123.700032 -52.910232) (xy 123.672662 -52.909764) (xy 123.618482 -52.901949)
			(xy 123.565978 -52.886461) (xy 123.516231 -52.86362) (xy 123.470265 -52.833894) (xy 123.449334 -52.816252)
			(xy 123.44908 -52.815998) (xy 123.442004 -52.810397) (xy 123.425079 -52.804159) (xy 123.41606 -52.803806)
			(xy 123.349004 -52.803806) (xy 123.339987 -52.804164) (xy 123.32307 -52.810411) (xy 123.315984 -52.815998)
			(xy 123.315984 -52.816252) (xy 123.31573 -52.816252) (xy 123.294791 -52.833883) (xy 123.248821 -52.863598)
			(xy 123.199075 -52.886436) (xy 123.146576 -52.901929) (xy 123.092401 -52.909758) (xy 123.065032 -52.910232)
			(xy 123.037779 -52.909723) (xy 122.983828 -52.90197) (xy 122.93153 -52.886618) (xy 122.881949 -52.863979)
			(xy 122.836095 -52.834513) (xy 122.794901 -52.798822) (xy 122.759206 -52.757631) (xy 122.729737 -52.711779)
			(xy 122.707093 -52.6622) (xy 122.691737 -52.609903) (xy 122.683979 -52.555953) (xy 110.332603 -52.555953)
			(xy 110.351338 -53.496552) (xy 122.233664 -53.496552) (xy 122.233664 -53.442048) (xy 122.24142 -53.388099)
			(xy 122.256776 -53.335803) (xy 122.279417 -53.286225) (xy 122.308883 -53.240374) (xy 122.344575 -53.199182)
			(xy 122.385766 -53.163489) (xy 122.431616 -53.134022) (xy 122.481194 -53.111379) (xy 122.53349 -53.096022)
			(xy 122.587438 -53.088264) (xy 122.61469 -53.087778) (xy 122.642061 -53.088231) (xy 122.696241 -53.096049)
			(xy 122.748745 -53.11154) (xy 122.798492 -53.134385) (xy 122.844458 -53.164114) (xy 122.865388 -53.181758)
			(xy 122.865642 -53.182012) (xy 122.87274 -53.187582) (xy 122.889648 -53.193838) (xy 122.898662 -53.194204)
			(xy 122.965718 -53.194204) (xy 122.974736 -53.193855) (xy 122.991652 -53.187602) (xy 122.998738 -53.182012)
			(xy 122.998738 -53.181758) (xy 122.998992 -53.181758) (xy 123.019911 -53.164102) (xy 123.065888 -53.134394)
			(xy 123.115639 -53.111562) (xy 123.168142 -53.096075) (xy 123.22232 -53.08825) (xy 123.24969 -53.087778)
			(xy 123.276942 -53.088269) (xy 123.330892 -53.096024) (xy 123.383189 -53.111379) (xy 123.432769 -53.13402)
			(xy 123.478622 -53.163486) (xy 123.519814 -53.199179) (xy 123.555508 -53.24037) (xy 123.584975 -53.286222)
			(xy 123.607618 -53.335801) (xy 123.622974 -53.388098) (xy 123.630731 -53.442048) (xy 123.630731 -53.496552)
			(xy 123.622974 -53.550502) (xy 123.607618 -53.602799) (xy 123.584975 -53.652378) (xy 123.555508 -53.69823)
			(xy 123.519814 -53.739421) (xy 123.478622 -53.775114) (xy 123.432769 -53.80458) (xy 123.383189 -53.827221)
			(xy 123.330892 -53.842576) (xy 123.276942 -53.850331) (xy 123.24969 -53.850794) (xy 123.222319 -53.850335)
			(xy 123.16814 -53.842516) (xy 123.115637 -53.827025) (xy 123.06589 -53.804182) (xy 123.019924 -53.774456)
			(xy 122.998992 -53.756814) (xy 122.998738 -53.75656) (xy 122.991648 -53.750978) (xy 122.974734 -53.74473)
			(xy 122.965718 -53.744368) (xy 122.898662 -53.744368) (xy 122.889644 -53.744714) (xy 122.872728 -53.75097)
			(xy 122.865642 -53.75656) (xy 122.865642 -53.756814) (xy 122.865388 -53.756814) (xy 122.844435 -53.774427)
			(xy 122.798468 -53.804143) (xy 122.748726 -53.826983) (xy 122.69623 -53.84248) (xy 122.642058 -53.850316)
			(xy 122.61469 -53.850794) (xy 122.587438 -53.850336) (xy 122.53349 -53.842578) (xy 122.481194 -53.827221)
			(xy 122.431616 -53.804578) (xy 122.385766 -53.775111) (xy 122.344575 -53.739418) (xy 122.308883 -53.698226)
			(xy 122.279417 -53.652375) (xy 122.256776 -53.602797) (xy 122.24142 -53.550501) (xy 122.233664 -53.496552)
			(xy 110.351338 -53.496552) (xy 110.381065 -54.989051) (xy 120.001268 -54.989051) (xy 120.001268 -54.934549)
			(xy 120.009024 -54.880601) (xy 120.024379 -54.828306) (xy 120.047019 -54.778729) (xy 120.076485 -54.732878)
			(xy 120.112176 -54.691687) (xy 120.153365 -54.655995) (xy 120.199215 -54.626527) (xy 120.248791 -54.603884)
			(xy 120.301085 -54.588527) (xy 120.355033 -54.580769) (xy 120.382284 -54.580282) (xy 120.410375 -54.58079)
			(xy 120.465952 -54.589014) (xy 120.51972 -54.605303) (xy 120.570518 -54.629304) (xy 120.617245 -54.660497)
			(xy 120.65889 -54.698207) (xy 120.694553 -54.741618) (xy 120.709436 -54.765448) (xy 120.71477 -54.774338)
			(xy 120.731788 -54.78653) (xy 120.825006 -54.80685) (xy 120.84558 -54.802532) (xy 120.854216 -54.79669)
			(xy 120.878273 -54.78068) (xy 120.930207 -54.75534) (xy 120.985367 -54.738117) (xy 121.042493 -54.729405)
			(xy 121.071386 -54.728872) (xy 121.098636 -54.729391) (xy 121.112696 -54.731412) (xy 129.620772 -54.731412)
			(xy 129.621228 -54.704041) (xy 129.629045 -54.649861) (xy 129.644536 -54.597357) (xy 129.66738 -54.54761)
			(xy 129.697109 -54.501645) (xy 129.714752 -54.480714) (xy 129.715006 -54.48046) (xy 129.720574 -54.473361)
			(xy 129.726832 -54.456454) (xy 129.727198 -54.44744) (xy 129.727198 -54.380384) (xy 129.726849 -54.371366)
			(xy 129.720596 -54.354449) (xy 129.715006 -54.347364) (xy 129.714752 -54.347364) (xy 129.714752 -54.34711)
			(xy 129.697122 -54.326168) (xy 129.667395 -54.280203) (xy 129.644547 -54.230458) (xy 129.629049 -54.177957)
			(xy 129.621219 -54.123779) (xy 129.621217 -54.069039) (xy 129.629045 -54.014861) (xy 129.644541 -53.962359)
			(xy 129.667386 -53.912613) (xy 129.697111 -53.866646) (xy 129.714752 -53.845714) (xy 129.715006 -53.84546)
			(xy 129.720574 -53.838361) (xy 129.726832 -53.821454) (xy 129.727198 -53.81244) (xy 129.727198 -53.745384)
			(xy 129.726849 -53.736366) (xy 129.720596 -53.719449) (xy 129.715006 -53.712364) (xy 129.714752 -53.712364)
			(xy 129.714752 -53.71211) (xy 129.697122 -53.691168) (xy 129.667395 -53.645203) (xy 129.644547 -53.595458)
			(xy 129.629049 -53.542957) (xy 129.621219 -53.488779) (xy 129.621217 -53.434039) (xy 129.629045 -53.379861)
			(xy 129.644541 -53.327359) (xy 129.667386 -53.277613) (xy 129.697111 -53.231646) (xy 129.714752 -53.210714)
			(xy 129.715006 -53.21046) (xy 129.720574 -53.203361) (xy 129.726832 -53.186454) (xy 129.727198 -53.17744)
			(xy 129.727198 -53.110384) (xy 129.726849 -53.101366) (xy 129.720596 -53.084449) (xy 129.715006 -53.077364)
			(xy 129.714752 -53.077364) (xy 129.714752 -53.07711) (xy 129.697112 -53.056178) (xy 129.667399 -53.010206)
			(xy 129.644562 -52.960459) (xy 129.629071 -52.907958) (xy 129.621245 -52.853781) (xy 129.620772 -52.826412)
			(xy 129.621258 -52.799161) (xy 129.629014 -52.745213) (xy 129.644369 -52.692918) (xy 129.667011 -52.643341)
			(xy 129.696477 -52.597491) (xy 129.732168 -52.5563) (xy 129.773359 -52.520609) (xy 129.819209 -52.491143)
			(xy 129.868786 -52.468501) (xy 129.921081 -52.453146) (xy 129.975029 -52.44539) (xy 130.029531 -52.44539)
			(xy 130.083479 -52.453146) (xy 130.135774 -52.468501) (xy 130.185351 -52.491143) (xy 130.231201 -52.520609)
			(xy 130.272392 -52.5563) (xy 130.308083 -52.597491) (xy 130.337549 -52.643341) (xy 130.360191 -52.692918)
			(xy 130.375546 -52.745213) (xy 130.383302 -52.799161) (xy 130.383788 -52.826412) (xy 130.383332 -52.853783)
			(xy 130.375512 -52.907962) (xy 130.360021 -52.960466) (xy 130.337177 -53.010212) (xy 130.30745 -53.056179)
			(xy 130.289808 -53.07711) (xy 130.289554 -53.077364) (xy 130.283971 -53.084453) (xy 130.277723 -53.101368)
			(xy 130.277362 -53.110384) (xy 130.277362 -53.17744) (xy 130.277708 -53.186458) (xy 130.283964 -53.203374)
			(xy 130.289554 -53.21046) (xy 130.289808 -53.21046) (xy 130.289808 -53.210714) (xy 130.307459 -53.231638)
			(xy 130.337181 -53.277608) (xy 130.360023 -53.327356) (xy 130.375517 -53.379859) (xy 130.383344 -53.434038)
			(xy 130.383342 -53.48878) (xy 130.375513 -53.542959) (xy 130.360017 -53.595461) (xy 130.337172 -53.645208)
			(xy 130.307448 -53.691177) (xy 130.289808 -53.71211) (xy 130.289554 -53.712364) (xy 130.283971 -53.719453)
			(xy 130.277723 -53.736368) (xy 130.277362 -53.745384) (xy 130.277362 -53.81244) (xy 130.277708 -53.821458)
			(xy 130.283964 -53.838374) (xy 130.289554 -53.84546) (xy 130.289808 -53.84546) (xy 130.289808 -53.845714)
			(xy 130.307459 -53.866638) (xy 130.337181 -53.912608) (xy 130.360023 -53.962356) (xy 130.375517 -54.014859)
			(xy 130.383344 -54.069038) (xy 130.383342 -54.12378) (xy 130.375513 -54.177959) (xy 130.360017 -54.230461)
			(xy 130.337172 -54.280208) (xy 130.307448 -54.326177) (xy 130.289808 -54.34711) (xy 130.289554 -54.347364)
			(xy 130.283971 -54.354453) (xy 130.277723 -54.371368) (xy 130.277362 -54.380384) (xy 130.277362 -54.44744)
			(xy 130.277708 -54.456458) (xy 130.283964 -54.473374) (xy 130.289554 -54.48046) (xy 130.289808 -54.48046)
			(xy 130.289808 -54.480714) (xy 130.307421 -54.501667) (xy 130.337137 -54.547634) (xy 130.359978 -54.597376)
			(xy 130.375475 -54.649872) (xy 130.38331 -54.704044) (xy 130.383788 -54.731412) (xy 130.383302 -54.758663)
			(xy 130.378638 -54.791102) (xy 132.276596 -54.791102) (xy 132.277064 -54.763732) (xy 132.284882 -54.709553)
			(xy 132.30037 -54.65705) (xy 132.323212 -54.607303) (xy 132.352935 -54.561336) (xy 132.370576 -54.540404)
			(xy 132.37083 -54.54015) (xy 132.376405 -54.533056) (xy 132.382658 -54.516145) (xy 132.383022 -54.50713)
			(xy 132.383022 -54.440074) (xy 132.382673 -54.431056) (xy 132.376419 -54.41414) (xy 132.37083 -54.407054)
			(xy 132.370576 -54.407054) (xy 132.370576 -54.4068) (xy 132.352935 -54.385867) (xy 132.323207 -54.3399)
			(xy 132.300358 -54.290154) (xy 132.28486 -54.237652) (xy 132.27703 -54.183473) (xy 132.27703 -54.12873)
			(xy 132.284859 -54.074551) (xy 132.300357 -54.022049) (xy 132.323205 -53.972302) (xy 132.352933 -53.926336)
			(xy 132.370576 -53.905404) (xy 132.37083 -53.90515) (xy 132.376405 -53.898056) (xy 132.382658 -53.881145)
			(xy 132.383022 -53.87213) (xy 132.383022 -53.805074) (xy 132.382673 -53.796056) (xy 132.376419 -53.77914)
			(xy 132.37083 -53.772054) (xy 132.370576 -53.772054) (xy 132.370576 -53.7718) (xy 132.352935 -53.750867)
			(xy 132.323207 -53.7049) (xy 132.300358 -53.655154) (xy 132.28486 -53.602652) (xy 132.27703 -53.548473)
			(xy 132.27703 -53.49373) (xy 132.284859 -53.439551) (xy 132.300357 -53.387049) (xy 132.323205 -53.337302)
			(xy 132.352933 -53.291336) (xy 132.370576 -53.270404) (xy 132.37083 -53.27015) (xy 132.376405 -53.263056)
			(xy 132.382658 -53.246145) (xy 132.383022 -53.23713) (xy 132.383022 -53.170074) (xy 132.382673 -53.161056)
			(xy 132.376419 -53.14414) (xy 132.37083 -53.137054) (xy 132.370576 -53.137054) (xy 132.370576 -53.1368)
			(xy 132.35292 -53.115882) (xy 132.323211 -53.069905) (xy 132.300379 -53.020154) (xy 132.284892 -52.96765)
			(xy 132.277068 -52.913472) (xy 132.276596 -52.886102) (xy 132.277082 -52.858851) (xy 132.284838 -52.804903)
			(xy 132.300193 -52.752608) (xy 132.322835 -52.703031) (xy 132.352301 -52.657181) (xy 132.387992 -52.61599)
			(xy 132.429183 -52.580299) (xy 132.475033 -52.550833) (xy 132.52461 -52.528191) (xy 132.576905 -52.512836)
			(xy 132.630853 -52.50508) (xy 132.685355 -52.50508) (xy 132.739303 -52.512836) (xy 132.791598 -52.528191)
			(xy 132.830698 -52.546048) (xy 137.779796 -52.546048) (xy 137.779796 -52.491552) (xy 137.787551 -52.43761)
			(xy 137.802904 -52.385321) (xy 137.825541 -52.335749) (xy 137.855002 -52.289903) (xy 137.890687 -52.248716)
			(xy 137.931871 -52.213026) (xy 137.977714 -52.18356) (xy 138.027284 -52.160918) (xy 138.079571 -52.14556)
			(xy 138.133512 -52.137799) (xy 138.16076 -52.13731) (xy 138.18813 -52.137797) (xy 138.242308 -52.145609)
			(xy 138.294811 -52.161093) (xy 138.344558 -52.183931) (xy 138.390526 -52.213651) (xy 138.411458 -52.23129)
			(xy 138.411712 -52.231544) (xy 138.418787 -52.237147) (xy 138.435713 -52.243383) (xy 138.444732 -52.243736)
			(xy 138.511788 -52.243736) (xy 138.520803 -52.243365) (xy 138.53772 -52.237126) (xy 138.544808 -52.231544)
			(xy 138.544808 -52.23129) (xy 138.545062 -52.23129) (xy 138.565995 -52.213649) (xy 138.611963 -52.183925)
			(xy 138.661709 -52.161079) (xy 138.714211 -52.145583) (xy 138.768389 -52.137754) (xy 138.823131 -52.137754)
			(xy 138.877309 -52.145583) (xy 138.929811 -52.161079) (xy 138.979557 -52.183925) (xy 139.025525 -52.213649)
			(xy 139.046458 -52.23129) (xy 139.046712 -52.231544) (xy 139.053787 -52.237147) (xy 139.070713 -52.243383)
			(xy 139.079732 -52.243736) (xy 139.146788 -52.243736) (xy 139.155803 -52.243365) (xy 139.17272 -52.237126)
			(xy 139.179808 -52.231544) (xy 139.179808 -52.23129) (xy 139.180062 -52.23129) (xy 139.200996 -52.213654)
			(xy 139.246969 -52.183942) (xy 139.296716 -52.161105) (xy 139.349216 -52.145614) (xy 139.403391 -52.137785)
			(xy 139.43076 -52.13731) (xy 139.458016 -52.137734) (xy 139.511974 -52.145487) (xy 139.564279 -52.16084)
			(xy 139.613867 -52.183482) (xy 139.659727 -52.21295) (xy 139.700926 -52.248645) (xy 139.736626 -52.289841)
			(xy 139.766099 -52.335698) (xy 139.788746 -52.385283) (xy 139.804105 -52.437587) (xy 139.811863 -52.491544)
			(xy 139.811863 -52.546056) (xy 139.805919 -52.587398) (xy 140.855444 -52.587398) (xy 140.859515 -52.531776)
			(xy 140.871641 -52.477339) (xy 140.891564 -52.425248) (xy 140.91886 -52.376613) (xy 140.952946 -52.33247)
			(xy 140.993095 -52.293761) (xy 141.038453 -52.26131) (xy 141.088053 -52.235809) (xy 141.140837 -52.217802)
			(xy 141.19568 -52.207672) (xy 141.251414 -52.205635) (xy 141.306851 -52.211735) (xy 141.360808 -52.225841)
			(xy 141.412137 -52.247653) (xy 141.459743 -52.276707) (xy 141.502611 -52.312382) (xy 141.539828 -52.353919)
			(xy 141.570601 -52.400432) (xy 141.594273 -52.450929) (xy 141.610341 -52.504336) (xy 141.617937 -52.555949)
			(xy 148.684002 -52.555949) (xy 148.684002 -52.501451) (xy 148.691758 -52.447509) (xy 148.707111 -52.395219)
			(xy 148.729749 -52.345646) (xy 148.759212 -52.2998) (xy 148.794899 -52.258613) (xy 148.836084 -52.222924)
			(xy 148.881929 -52.193459) (xy 148.9315 -52.170818) (xy 148.983789 -52.155462) (xy 149.037731 -52.147704)
			(xy 149.06498 -52.147216) (xy 149.09235 -52.14769) (xy 149.146529 -52.155505) (xy 149.199032 -52.170992)
			(xy 149.248779 -52.193832) (xy 149.294746 -52.223555) (xy 149.315678 -52.241196) (xy 149.315932 -52.24145)
			(xy 149.32303 -52.24702) (xy 149.339938 -52.253276) (xy 149.348952 -52.253642) (xy 149.416008 -52.253642)
			(xy 149.425027 -52.253301) (xy 149.441944 -52.247044) (xy 149.449028 -52.24145) (xy 149.449028 -52.241196)
			(xy 149.449282 -52.241196) (xy 149.47021 -52.223551) (xy 149.516184 -52.19384) (xy 149.565932 -52.171006)
			(xy 149.618434 -52.155516) (xy 149.672611 -52.147689) (xy 149.69998 -52.147216) (xy 149.727236 -52.14763)
			(xy 149.781192 -52.155385) (xy 149.833496 -52.17074) (xy 149.883081 -52.193383) (xy 149.92894 -52.222852)
			(xy 149.970138 -52.258548) (xy 150.005836 -52.299744) (xy 150.035308 -52.345601) (xy 150.057953 -52.395186)
			(xy 150.073311 -52.447488) (xy 150.081069 -52.501444) (xy 150.081069 -52.555956) (xy 150.073311 -52.609912)
			(xy 150.057953 -52.662214) (xy 150.035308 -52.711799) (xy 150.005836 -52.757656) (xy 149.970138 -52.798852)
			(xy 149.92894 -52.834548) (xy 149.883081 -52.864017) (xy 149.833496 -52.88666) (xy 149.781192 -52.902015)
			(xy 149.727236 -52.90977) (xy 149.69998 -52.910232) (xy 149.672609 -52.909794) (xy 149.618428 -52.901972)
			(xy 149.565924 -52.886477) (xy 149.516177 -52.863629) (xy 149.470212 -52.833897) (xy 149.449282 -52.816252)
			(xy 149.449028 -52.815998) (xy 149.441938 -52.810417) (xy 149.425024 -52.804167) (xy 149.416008 -52.803806)
			(xy 149.348952 -52.803806) (xy 149.339938 -52.804187) (xy 149.32302 -52.810418) (xy 149.315932 -52.815998)
			(xy 149.315932 -52.816252) (xy 149.315678 -52.816252) (xy 149.294721 -52.833861) (xy 149.248756 -52.863579)
			(xy 149.199015 -52.886421) (xy 149.146519 -52.901919) (xy 149.092348 -52.909754) (xy 149.06498 -52.910232)
			(xy 149.037731 -52.909696) (xy 148.983789 -52.901938) (xy 148.9315 -52.886582) (xy 148.881929 -52.863941)
			(xy 148.836084 -52.834476) (xy 148.794899 -52.798787) (xy 148.759212 -52.7576) (xy 148.729749 -52.711754)
			(xy 148.707111 -52.662181) (xy 148.691758 -52.609891) (xy 148.684002 -52.555949) (xy 141.617937 -52.555949)
			(xy 141.618461 -52.559512) (xy 141.61897 -52.587398) (xy 141.618461 -52.615284) (xy 141.610341 -52.67046)
			(xy 141.594273 -52.723867) (xy 141.570601 -52.774364) (xy 141.539828 -52.820877) (xy 141.502611 -52.862414)
			(xy 141.459743 -52.898089) (xy 141.412137 -52.927143) (xy 141.360808 -52.948955) (xy 141.306851 -52.963061)
			(xy 141.251414 -52.969161) (xy 141.19568 -52.967124) (xy 141.140837 -52.956994) (xy 141.088053 -52.938987)
			(xy 141.038453 -52.913486) (xy 140.993095 -52.881035) (xy 140.952946 -52.842326) (xy 140.91886 -52.798183)
			(xy 140.891564 -52.749548) (xy 140.871641 -52.697457) (xy 140.859515 -52.64302) (xy 140.855444 -52.587398)
			(xy 139.805919 -52.587398) (xy 139.804105 -52.600013) (xy 139.788746 -52.652317) (xy 139.766099 -52.701902)
			(xy 139.736626 -52.747759) (xy 139.700926 -52.788955) (xy 139.659727 -52.82465) (xy 139.613867 -52.854118)
			(xy 139.564279 -52.87676) (xy 139.511974 -52.892113) (xy 139.458016 -52.899866) (xy 139.43076 -52.900326)
			(xy 139.40339 -52.899843) (xy 139.349211 -52.892032) (xy 139.296707 -52.876548) (xy 139.24696 -52.853709)
			(xy 139.200993 -52.823987) (xy 139.180062 -52.806346) (xy 139.179808 -52.806092) (xy 139.172724 -52.800502)
			(xy 139.155805 -52.794258) (xy 139.146788 -52.7939) (xy 139.079732 -52.7939) (xy 139.070717 -52.794272)
			(xy 139.0538 -52.800509) (xy 139.046712 -52.806092) (xy 139.046458 -52.806346) (xy 139.025525 -52.823987)
			(xy 138.979557 -52.853711) (xy 138.929811 -52.876557) (xy 138.877309 -52.892053) (xy 138.823131 -52.899882)
			(xy 138.768389 -52.899882) (xy 138.714211 -52.892053) (xy 138.661709 -52.876557) (xy 138.611963 -52.853711)
			(xy 138.565995 -52.823987) (xy 138.545062 -52.806346) (xy 138.544808 -52.806092) (xy 138.537724 -52.800502)
			(xy 138.520805 -52.794258) (xy 138.511788 -52.7939) (xy 138.444732 -52.7939) (xy 138.435717 -52.794272)
			(xy 138.4188 -52.800509) (xy 138.411712 -52.806092) (xy 138.411712 -52.806346) (xy 138.411458 -52.806346)
			(xy 138.390508 -52.823963) (xy 138.344541 -52.85368) (xy 138.294798 -52.876521) (xy 138.242301 -52.892017)
			(xy 138.188128 -52.89985) (xy 138.16076 -52.900326) (xy 138.133512 -52.899801) (xy 138.079571 -52.89204)
			(xy 138.027284 -52.876682) (xy 137.977714 -52.85404) (xy 137.931871 -52.824574) (xy 137.890687 -52.788884)
			(xy 137.855002 -52.747697) (xy 137.825541 -52.701851) (xy 137.802904 -52.652279) (xy 137.787551 -52.59999)
			(xy 137.779796 -52.546048) (xy 132.830698 -52.546048) (xy 132.841175 -52.550833) (xy 132.887025 -52.580299)
			(xy 132.928216 -52.61599) (xy 132.963907 -52.657181) (xy 132.993373 -52.703031) (xy 133.016015 -52.752608)
			(xy 133.03137 -52.804903) (xy 133.039126 -52.858851) (xy 133.039612 -52.886102) (xy 133.039144 -52.913472)
			(xy 133.031326 -52.967651) (xy 133.015837 -53.020154) (xy 132.992996 -53.069901) (xy 132.963273 -53.115868)
			(xy 132.945632 -53.1368) (xy 132.945378 -53.137054) (xy 132.939802 -53.144148) (xy 132.93355 -53.161059)
			(xy 132.933186 -53.170074) (xy 132.933186 -53.23713) (xy 132.933531 -53.246148) (xy 132.939787 -53.263065)
			(xy 132.945378 -53.27015) (xy 132.945632 -53.27015) (xy 132.945632 -53.270404) (xy 132.963276 -53.291334)
			(xy 132.993004 -53.337302) (xy 133.015852 -53.387048) (xy 133.03135 -53.439551) (xy 133.039179 -53.49373)
			(xy 133.039179 -53.548473) (xy 133.031349 -53.602652) (xy 133.015851 -53.655155) (xy 132.993003 -53.704901)
			(xy 132.963275 -53.750868) (xy 132.946702 -53.77053) (xy 133.310884 -53.77053) (xy 133.311392 -53.741612)
			(xy 133.320119 -53.684439) (xy 133.337376 -53.629239) (xy 133.36277 -53.577276) (xy 133.395717 -53.529743)
			(xy 133.435462 -53.487728) (xy 133.45795 -53.46954) (xy 133.466738 -53.461914) (xy 133.47693 -53.441027)
			(xy 133.477508 -53.429408) (xy 133.477508 -53.349652) (xy 133.476979 -53.338019) (xy 133.466783 -53.31711)
			(xy 133.45795 -53.30952) (xy 133.435466 -53.29133) (xy 133.395733 -53.249309) (xy 133.362795 -53.201773)
			(xy 133.337408 -53.149812) (xy 133.320151 -53.094615) (xy 133.31142 -53.037446) (xy 133.310884 -53.00853)
			(xy 133.311383 -52.981278) (xy 133.319136 -52.927329) (xy 133.334488 -52.875032) (xy 133.357126 -52.825453)
			(xy 133.38659 -52.7796) (xy 133.42228 -52.738407) (xy 133.463469 -52.702713) (xy 133.509319 -52.673244)
			(xy 133.558897 -52.650601) (xy 133.611192 -52.635244) (xy 133.66514 -52.627486) (xy 133.692392 -52.627022)
			(xy 133.718706 -52.627488) (xy 133.770835 -52.634722) (xy 133.821478 -52.649041) (xy 133.869677 -52.670174)
			(xy 133.914521 -52.69772) (xy 133.95516 -52.73116) (xy 133.973316 -52.750212) (xy 133.980828 -52.757625)
			(xy 134.000115 -52.766142) (xy 134.010654 -52.766722) (xy 134.08533 -52.766722) (xy 134.095876 -52.766162)
			(xy 134.115171 -52.757648) (xy 134.122668 -52.750212) (xy 134.1408 -52.731133) (xy 134.181434 -52.697677)
			(xy 134.22628 -52.670121) (xy 134.274485 -52.648987) (xy 134.325137 -52.634675) (xy 134.377274 -52.627457)
			(xy 134.403592 -52.627022) (xy 134.430846 -52.627463) (xy 134.484799 -52.63522) (xy 134.537099 -52.650576)
			(xy 134.586682 -52.67322) (xy 134.632536 -52.70269) (xy 134.67373 -52.738386) (xy 134.709423 -52.779582)
			(xy 134.738891 -52.825438) (xy 134.761532 -52.875021) (xy 134.776885 -52.927322) (xy 134.784639 -52.981276)
			(xy 134.7851 -53.00853) (xy 134.784611 -53.036196) (xy 134.78238 -53.051456) (xy 143.041368 -53.051456)
			(xy 143.045439 -52.995834) (xy 143.057565 -52.941397) (xy 143.077488 -52.889306) (xy 143.104784 -52.840671)
			(xy 143.13887 -52.796528) (xy 143.179019 -52.757819) (xy 143.224377 -52.725368) (xy 143.273977 -52.699867)
			(xy 143.326761 -52.68186) (xy 143.381604 -52.67173) (xy 143.437338 -52.669693) (xy 143.492775 -52.675793)
			(xy 143.546732 -52.689899) (xy 143.598061 -52.711711) (xy 143.645667 -52.740765) (xy 143.688535 -52.77644)
			(xy 143.725752 -52.817977) (xy 143.756525 -52.86449) (xy 143.780197 -52.914987) (xy 143.796265 -52.968394)
			(xy 143.804385 -53.02357) (xy 143.804894 -53.051456) (xy 143.804385 -53.079342) (xy 143.796265 -53.134518)
			(xy 143.780197 -53.187925) (xy 143.756525 -53.238422) (xy 143.725752 -53.284935) (xy 143.688535 -53.326472)
			(xy 143.645667 -53.362147) (xy 143.598061 -53.391201) (xy 143.546732 -53.413013) (xy 143.492775 -53.427119)
			(xy 143.437338 -53.433219) (xy 143.381604 -53.431182) (xy 143.326761 -53.421052) (xy 143.273977 -53.403045)
			(xy 143.224377 -53.377544) (xy 143.179019 -53.345093) (xy 143.13887 -53.306384) (xy 143.104784 -53.262241)
			(xy 143.077488 -53.213606) (xy 143.057565 -53.161515) (xy 143.045439 -53.107078) (xy 143.041368 -53.051456)
			(xy 134.78238 -53.051456) (xy 134.776608 -53.090946) (xy 134.760787 -53.143968) (xy 134.73748 -53.194152)
			(xy 134.707175 -53.240448) (xy 134.670507 -53.281885) (xy 134.628242 -53.317597) (xy 134.605014 -53.332634)
			(xy 134.595316 -53.339245) (xy 134.582884 -53.359125) (xy 134.581138 -53.370734) (xy 134.573264 -53.450744)
			(xy 134.572608 -53.462383) (xy 134.580704 -53.484222) (xy 134.588758 -53.492654) (xy 134.589012 -53.492908)
			(xy 134.607581 -53.511) (xy 134.640161 -53.55133) (xy 134.666975 -53.595702) (xy 134.68753 -53.643298)
			(xy 134.701446 -53.69324) (xy 134.708466 -53.744608) (xy 134.7089 -53.77053) (xy 134.70845 -53.797782)
			(xy 134.700689 -53.851732) (xy 134.68533 -53.904028) (xy 134.662685 -53.953606) (xy 134.633215 -53.999456)
			(xy 134.597519 -54.040646) (xy 134.556326 -54.076337) (xy 134.510472 -54.105803) (xy 134.460892 -54.128443)
			(xy 134.408595 -54.143797) (xy 134.354644 -54.151553) (xy 134.327392 -54.152038) (xy 134.300021 -54.151592)
			(xy 134.24584 -54.143771) (xy 134.193336 -54.128279) (xy 134.14359 -54.105432) (xy 134.097624 -54.075702)
			(xy 134.076694 -54.058058) (xy 134.07644 -54.057804) (xy 134.069346 -54.052228) (xy 134.052435 -54.045975)
			(xy 134.04342 -54.045612) (xy 133.976364 -54.045612) (xy 133.967345 -54.045949) (xy 133.950428 -54.05221)
			(xy 133.943344 -54.057804) (xy 133.943344 -54.058058) (xy 133.94309 -54.058058) (xy 133.922167 -54.075709)
			(xy 133.876192 -54.10542) (xy 133.826443 -54.128255) (xy 133.77394 -54.143743) (xy 133.719762 -54.151567)
			(xy 133.692392 -54.152038) (xy 133.665142 -54.15153) (xy 133.611197 -54.143773) (xy 133.558904 -54.128418)
			(xy 133.509329 -54.105778) (xy 133.46348 -54.076314) (xy 133.422291 -54.040625) (xy 133.386599 -53.999438)
			(xy 133.357132 -53.953591) (xy 133.334489 -53.904017) (xy 133.319132 -53.851725) (xy 133.311372 -53.79778)
			(xy 133.310884 -53.77053) (xy 132.946702 -53.77053) (xy 132.945632 -53.7718) (xy 132.945378 -53.772054)
			(xy 132.939802 -53.779148) (xy 132.93355 -53.796059) (xy 132.933186 -53.805074) (xy 132.933186 -53.87213)
			(xy 132.933531 -53.881148) (xy 132.939787 -53.898065) (xy 132.945378 -53.90515) (xy 132.945632 -53.90515)
			(xy 132.945632 -53.905404) (xy 132.963276 -53.926334) (xy 132.993004 -53.972302) (xy 133.015852 -54.022048)
			(xy 133.03135 -54.074551) (xy 133.039179 -54.12873) (xy 133.039179 -54.183473) (xy 133.031349 -54.237652)
			(xy 133.015851 -54.290155) (xy 133.002058 -54.320186) (xy 135.230616 -54.320186) (xy 135.23107 -54.292815)
			(xy 135.23889 -54.238636) (xy 135.254382 -54.186132) (xy 135.277226 -54.136385) (xy 135.306954 -54.090419)
			(xy 135.324596 -54.069488) (xy 135.32485 -54.069234) (xy 135.330434 -54.062146) (xy 135.336681 -54.04523)
			(xy 135.337042 -54.036214) (xy 135.337042 -53.969158) (xy 135.33667 -53.960142) (xy 135.330434 -53.943225)
			(xy 135.32485 -53.936138) (xy 135.324596 -53.936138) (xy 135.324596 -53.935884) (xy 135.306982 -53.914932)
			(xy 135.277267 -53.868964) (xy 135.254426 -53.819222) (xy 135.238929 -53.766726) (xy 135.231094 -53.712554)
			(xy 135.230616 -53.685186) (xy 135.231102 -53.657935) (xy 135.238858 -53.603987) (xy 135.254213 -53.551692)
			(xy 135.276855 -53.502115) (xy 135.306321 -53.456265) (xy 135.342012 -53.415074) (xy 135.383203 -53.379383)
			(xy 135.429053 -53.349917) (xy 135.47863 -53.327275) (xy 135.530925 -53.31192) (xy 135.584873 -53.304164)
			(xy 135.639375 -53.304164) (xy 135.693323 -53.31192) (xy 135.745618 -53.327275) (xy 135.795195 -53.349917)
			(xy 135.841045 -53.379383) (xy 135.882236 -53.415074) (xy 135.917927 -53.456265) (xy 135.94382 -53.496556)
			(xy 148.233541 -53.496556) (xy 148.233541 -53.442044) (xy 148.241299 -53.388088) (xy 148.256658 -53.335785)
			(xy 148.279304 -53.286201) (xy 148.308777 -53.240344) (xy 148.344476 -53.199149) (xy 148.385674 -53.163454)
			(xy 148.431534 -53.133986) (xy 148.481121 -53.111344) (xy 148.533425 -53.095991) (xy 148.587382 -53.088238)
			(xy 148.614638 -53.087778) (xy 148.642008 -53.088261) (xy 148.696187 -53.096072) (xy 148.748691 -53.111556)
			(xy 148.798438 -53.134394) (xy 148.844405 -53.164117) (xy 148.865336 -53.181758) (xy 148.86559 -53.182012)
			(xy 148.872674 -53.187602) (xy 148.889593 -53.193846) (xy 148.89861 -53.194204) (xy 148.965666 -53.194204)
			(xy 148.974681 -53.19383) (xy 148.991598 -53.187594) (xy 148.998686 -53.182012) (xy 148.998686 -53.181758)
			(xy 148.99894 -53.181758) (xy 149.019878 -53.164127) (xy 149.06585 -53.134415) (xy 149.115596 -53.111578)
			(xy 149.168095 -53.096085) (xy 149.222269 -53.088254) (xy 149.249638 -53.087778) (xy 149.276886 -53.088295)
			(xy 149.330828 -53.096055) (xy 149.383116 -53.111413) (xy 149.432687 -53.134056) (xy 149.478531 -53.163522)
			(xy 149.519715 -53.199212) (xy 149.555401 -53.2404) (xy 149.584863 -53.286247) (xy 149.6075 -53.335819)
			(xy 149.622853 -53.388109) (xy 149.630608 -53.442052) (xy 149.630608 -53.496548) (xy 149.622853 -53.550491)
			(xy 149.6075 -53.602781) (xy 149.584863 -53.652353) (xy 149.555401 -53.6982) (xy 149.519715 -53.739388)
			(xy 149.478531 -53.775078) (xy 149.432687 -53.804544) (xy 149.383116 -53.827187) (xy 149.330828 -53.842545)
			(xy 149.276886 -53.850305) (xy 149.249638 -53.850794) (xy 149.222269 -53.850307) (xy 149.16809 -53.842495)
			(xy 149.115587 -53.82701) (xy 149.06584 -53.804173) (xy 149.019872 -53.774453) (xy 148.99894 -53.756814)
			(xy 148.998686 -53.75656) (xy 148.991611 -53.750957) (xy 148.974685 -53.744721) (xy 148.965666 -53.744368)
			(xy 148.89861 -53.744368) (xy 148.889594 -53.744737) (xy 148.872678 -53.750977) (xy 148.86559 -53.75656)
			(xy 148.86559 -53.756814) (xy 148.865336 -53.756814) (xy 148.844403 -53.774452) (xy 148.79843 -53.804163)
			(xy 148.748683 -53.826999) (xy 148.696183 -53.842491) (xy 148.642007 -53.85032) (xy 148.614638 -53.850794)
			(xy 148.587382 -53.850362) (xy 148.533425 -53.842609) (xy 148.481121 -53.827256) (xy 148.431534 -53.804614)
			(xy 148.385674 -53.775146) (xy 148.344476 -53.739451) (xy 148.308777 -53.698256) (xy 148.279304 -53.652399)
			(xy 148.256658 -53.602815) (xy 148.241299 -53.550512) (xy 148.233541 -53.496556) (xy 135.94382 -53.496556)
			(xy 135.947393 -53.502115) (xy 135.970035 -53.551692) (xy 135.98539 -53.603987) (xy 135.993146 -53.657935)
			(xy 135.993632 -53.685186) (xy 135.993174 -53.712557) (xy 135.985357 -53.766737) (xy 135.969867 -53.819241)
			(xy 135.947023 -53.868987) (xy 135.917295 -53.914953) (xy 135.899652 -53.935884) (xy 135.899398 -53.936138)
			(xy 135.893831 -53.943238) (xy 135.887573 -53.960144) (xy 135.887206 -53.969158) (xy 135.887206 -54.036214)
			(xy 135.887555 -54.045232) (xy 135.893808 -54.062149) (xy 135.899398 -54.069234) (xy 135.899652 -54.069234)
			(xy 135.899652 -54.069488) (xy 135.917291 -54.09042) (xy 135.947005 -54.136392) (xy 135.969842 -54.186139)
			(xy 135.985332 -54.23864) (xy 135.993159 -54.292817) (xy 135.993632 -54.320186) (xy 135.993146 -54.347437)
			(xy 135.98539 -54.401385) (xy 135.970035 -54.45368) (xy 135.947393 -54.503257) (xy 135.917927 -54.549107)
			(xy 135.882236 -54.590298) (xy 135.841045 -54.625989) (xy 135.795195 -54.655455) (xy 135.745618 -54.678097)
			(xy 135.693323 -54.693452) (xy 135.639375 -54.701208) (xy 135.584873 -54.701208) (xy 135.530925 -54.693452)
			(xy 135.47863 -54.678097) (xy 135.429053 -54.655455) (xy 135.383203 -54.625989) (xy 135.342012 -54.590298)
			(xy 135.306321 -54.549107) (xy 135.276855 -54.503257) (xy 135.254213 -54.45368) (xy 135.238858 -54.401385)
			(xy 135.231102 -54.347437) (xy 135.230616 -54.320186) (xy 133.002058 -54.320186) (xy 132.993003 -54.339901)
			(xy 132.963275 -54.385868) (xy 132.945632 -54.4068) (xy 132.945378 -54.407054) (xy 132.939802 -54.414148)
			(xy 132.93355 -54.431059) (xy 132.933186 -54.440074) (xy 132.933186 -54.50713) (xy 132.933531 -54.516148)
			(xy 132.939787 -54.533065) (xy 132.945378 -54.54015) (xy 132.945632 -54.54015) (xy 132.945632 -54.540404)
			(xy 132.963291 -54.56132) (xy 132.992999 -54.607297) (xy 133.015831 -54.657049) (xy 133.031317 -54.709553)
			(xy 133.03914 -54.763732) (xy 133.039257 -54.770528) (xy 136.171178 -54.770528) (xy 136.171641 -54.743157)
			(xy 136.179457 -54.688977) (xy 136.194946 -54.636474) (xy 136.217788 -54.586727) (xy 136.247515 -54.540761)
			(xy 136.265158 -54.51983) (xy 136.265412 -54.519576) (xy 136.271016 -54.512501) (xy 136.277252 -54.495575)
			(xy 136.277604 -54.486556) (xy 136.277604 -54.4195) (xy 136.277246 -54.410483) (xy 136.270999 -54.393566)
			(xy 136.265412 -54.38648) (xy 136.265158 -54.38648) (xy 136.265158 -54.386226) (xy 136.247511 -54.365301)
			(xy 136.217801 -54.319325) (xy 136.194968 -54.269576) (xy 136.179478 -54.217074) (xy 136.171651 -54.162898)
			(xy 136.171178 -54.135528) (xy 136.171664 -54.108277) (xy 136.17942 -54.054329) (xy 136.194775 -54.002034)
			(xy 136.217417 -53.952457) (xy 136.246883 -53.906607) (xy 136.282574 -53.865416) (xy 136.323765 -53.829725)
			(xy 136.369615 -53.800259) (xy 136.419192 -53.777617) (xy 136.471487 -53.762262) (xy 136.525435 -53.754506)
			(xy 136.579937 -53.754506) (xy 136.633885 -53.762262) (xy 136.68618 -53.777617) (xy 136.735757 -53.800259)
			(xy 136.781607 -53.829725) (xy 136.822798 -53.865416) (xy 136.858489 -53.906607) (xy 136.887955 -53.952457)
			(xy 136.89303 -53.96357) (xy 140.872208 -53.96357) (xy 140.876279 -53.907948) (xy 140.888405 -53.853511)
			(xy 140.908328 -53.80142) (xy 140.935624 -53.752785) (xy 140.96971 -53.708642) (xy 141.009859 -53.669933)
			(xy 141.055217 -53.637482) (xy 141.104817 -53.611981) (xy 141.157601 -53.593974) (xy 141.212444 -53.583844)
			(xy 141.268178 -53.581807) (xy 141.323615 -53.587907) (xy 141.377572 -53.602013) (xy 141.428901 -53.623825)
			(xy 141.476507 -53.652879) (xy 141.519375 -53.688554) (xy 141.556592 -53.730091) (xy 141.587365 -53.776604)
			(xy 141.611037 -53.827101) (xy 141.627105 -53.880508) (xy 141.635225 -53.935684) (xy 141.635734 -53.96357)
			(xy 141.635225 -53.991456) (xy 141.627105 -54.046632) (xy 141.611037 -54.100039) (xy 141.587365 -54.150536)
			(xy 141.556592 -54.197049) (xy 141.519375 -54.238586) (xy 141.476507 -54.274261) (xy 141.428901 -54.303315)
			(xy 141.377572 -54.325127) (xy 141.323615 -54.339233) (xy 141.268178 -54.345333) (xy 141.212444 -54.343296)
			(xy 141.157601 -54.333166) (xy 141.104817 -54.315159) (xy 141.055217 -54.289658) (xy 141.009859 -54.257207)
			(xy 140.96971 -54.218498) (xy 140.935624 -54.174355) (xy 140.908328 -54.12572) (xy 140.888405 -54.073629)
			(xy 140.876279 -54.019192) (xy 140.872208 -53.96357) (xy 136.89303 -53.96357) (xy 136.910597 -54.002034)
			(xy 136.925952 -54.054329) (xy 136.933708 -54.108277) (xy 136.934194 -54.135528) (xy 136.933746 -54.162899)
			(xy 136.925924 -54.217079) (xy 136.910431 -54.269582) (xy 136.887585 -54.319329) (xy 136.857857 -54.365295)
			(xy 136.840214 -54.386226) (xy 136.83996 -54.38648) (xy 136.834371 -54.393565) (xy 136.828127 -54.410483)
			(xy 136.827768 -54.4195) (xy 136.827768 -54.486556) (xy 136.828153 -54.49557) (xy 136.834382 -54.512487)
			(xy 136.83996 -54.519576) (xy 136.840214 -54.519576) (xy 136.840214 -54.51983) (xy 136.857836 -54.540776)
			(xy 136.88755 -54.586745) (xy 136.910389 -54.636489) (xy 136.925884 -54.688987) (xy 136.933717 -54.74316)
			(xy 136.934194 -54.770528) (xy 136.933708 -54.797779) (xy 136.925952 -54.851727) (xy 136.910597 -54.904022)
			(xy 136.887955 -54.953599) (xy 136.865169 -54.989055) (xy 146.001145 -54.989055) (xy 146.001145 -54.934545)
			(xy 146.008903 -54.88059) (xy 146.024261 -54.828288) (xy 146.046906 -54.778704) (xy 146.076378 -54.732848)
			(xy 146.112076 -54.691654) (xy 146.153274 -54.655959) (xy 146.199132 -54.626491) (xy 146.248718 -54.60385)
			(xy 146.301021 -54.588496) (xy 146.354977 -54.580743) (xy 146.382232 -54.580282) (xy 146.410324 -54.580751)
			(xy 146.465903 -54.588983) (xy 146.519672 -54.605279) (xy 146.57047 -54.629286) (xy 146.617196 -54.660484)
			(xy 146.658841 -54.6982) (xy 146.694502 -54.741616) (xy 146.709384 -54.765448) (xy 146.714718 -54.774338)
			(xy 146.731736 -54.78653) (xy 146.824954 -54.80685) (xy 146.845528 -54.802532) (xy 146.854164 -54.79669)
			(xy 146.878235 -54.780702) (xy 146.930164 -54.755357) (xy 146.98532 -54.738128) (xy 147.042442 -54.729409)
			(xy 147.071334 -54.728872) (xy 147.098585 -54.729346) (xy 147.152532 -54.737107) (xy 147.204826 -54.752465)
			(xy 147.254402 -54.775109) (xy 147.300251 -54.804577) (xy 147.341441 -54.840269) (xy 147.377132 -54.88146)
			(xy 147.406598 -54.92731) (xy 147.42924 -54.976887) (xy 147.444596 -55.029181) (xy 147.452355 -55.083129)
			(xy 147.452842 -55.11038) (xy 147.452378 -55.13775) (xy 147.444562 -55.19193) (xy 147.429073 -55.244434)
			(xy 147.406231 -55.294181) (xy 147.376504 -55.340147) (xy 147.358862 -55.361078) (xy 147.358608 -55.361332)
			(xy 147.353045 -55.368435) (xy 147.346784 -55.385339) (xy 147.346416 -55.394352) (xy 147.346416 -55.461408)
			(xy 147.346766 -55.470426) (xy 147.353018 -55.487343) (xy 147.358608 -55.494428) (xy 147.358862 -55.494428)
			(xy 147.358862 -55.494682) (xy 147.376484 -55.51563) (xy 147.40621 -55.561595) (xy 147.429057 -55.611339)
			(xy 147.444555 -55.663839) (xy 147.452386 -55.718015) (xy 147.452388 -55.772755) (xy 147.444562 -55.826932)
			(xy 147.429068 -55.879433) (xy 147.406225 -55.929178) (xy 147.376502 -55.975146) (xy 147.358862 -55.996078)
			(xy 147.358608 -55.996332) (xy 147.353045 -56.003435) (xy 147.346784 -56.020339) (xy 147.346416 -56.029352)
			(xy 147.346416 -56.096408) (xy 147.346766 -56.105426) (xy 147.353018 -56.122343) (xy 147.358608 -56.129428)
			(xy 147.358862 -56.129428) (xy 147.358862 -56.129682) (xy 147.3765 -56.150615) (xy 147.406213 -56.196587)
			(xy 147.42905 -56.246334) (xy 147.444541 -56.298835) (xy 147.452369 -56.353011) (xy 147.452842 -56.38038)
			(xy 147.452356 -56.407631) (xy 147.4446 -56.461579) (xy 147.429245 -56.513874) (xy 147.406603 -56.563451)
			(xy 147.377137 -56.609301) (xy 147.341446 -56.650492) (xy 147.300255 -56.686183) (xy 147.254405 -56.715649)
			(xy 147.204828 -56.738291) (xy 147.152533 -56.753646) (xy 147.098585 -56.761402) (xy 147.044083 -56.761402)
			(xy 146.990135 -56.753646) (xy 146.93784 -56.738291) (xy 146.888263 -56.715649) (xy 146.842413 -56.686183)
			(xy 146.801222 -56.650492) (xy 146.765531 -56.609301) (xy 146.736065 -56.563451) (xy 146.713423 -56.513874)
			(xy 146.698068 -56.461579) (xy 146.690312 -56.407631) (xy 146.689826 -56.38038) (xy 146.690274 -56.353009)
			(xy 146.698095 -56.298829) (xy 146.713588 -56.246325) (xy 146.736434 -56.196579) (xy 146.766163 -56.150613)
			(xy 146.783806 -56.129682) (xy 146.78406 -56.129428) (xy 146.789648 -56.122343) (xy 146.795892 -56.105425)
			(xy 146.796252 -56.096408) (xy 146.796252 -56.029352) (xy 146.795881 -56.020336) (xy 146.789644 -56.003419)
			(xy 146.78406 -55.996332) (xy 146.783806 -55.996332) (xy 146.783806 -55.996078) (xy 146.766147 -55.975161)
			(xy 146.736424 -55.92919) (xy 146.713581 -55.879441) (xy 146.698087 -55.826937) (xy 146.690261 -55.772756)
			(xy 146.690263 -55.718014) (xy 146.698094 -55.663834) (xy 146.713592 -55.611331) (xy 146.736439 -55.561584)
			(xy 146.766165 -55.515615) (xy 146.783806 -55.494682) (xy 146.78406 -55.494428) (xy 146.789648 -55.487343)
			(xy 146.795892 -55.470425) (xy 146.796252 -55.461408) (xy 146.796252 -55.394352) (xy 146.795881 -55.385336)
			(xy 146.789644 -55.368419) (xy 146.78406 -55.361332) (xy 146.783806 -55.360824) (xy 146.772863 -55.348089)
			(xy 146.753021 -55.320998) (xy 146.744182 -55.306722) (xy 146.738848 -55.297832) (xy 146.72183 -55.28564)
			(xy 146.628612 -55.26532) (xy 146.608038 -55.269638) (xy 146.599402 -55.27548) (xy 146.575338 -55.291479)
			(xy 146.523407 -55.316823) (xy 146.468249 -55.334049) (xy 146.411125 -55.342764) (xy 146.382232 -55.343298)
			(xy 146.354977 -55.342857) (xy 146.301021 -55.335104) (xy 146.248718 -55.31975) (xy 146.199132 -55.297109)
			(xy 146.153274 -55.267641) (xy 146.112076 -55.231946) (xy 146.076378 -55.190752) (xy 146.046906 -55.144896)
			(xy 146.024261 -55.095312) (xy 146.008903 -55.04301) (xy 146.001145 -54.989055) (xy 136.865169 -54.989055)
			(xy 136.858489 -54.999449) (xy 136.822798 -55.04064) (xy 136.781607 -55.076331) (xy 136.735757 -55.105797)
			(xy 136.68618 -55.128439) (xy 136.633885 -55.143794) (xy 136.579937 -55.15155) (xy 136.525435 -55.15155)
			(xy 136.471487 -55.143794) (xy 136.419192 -55.128439) (xy 136.369615 -55.105797) (xy 136.323765 -55.076331)
			(xy 136.282574 -55.04064) (xy 136.246883 -54.999449) (xy 136.217417 -54.953599) (xy 136.194775 -54.904022)
			(xy 136.17942 -54.851727) (xy 136.171664 -54.797779) (xy 136.171178 -54.770528) (xy 133.039257 -54.770528)
			(xy 133.039612 -54.791102) (xy 133.039126 -54.818353) (xy 133.03137 -54.872301) (xy 133.016015 -54.924596)
			(xy 132.993373 -54.974173) (xy 132.963907 -55.020023) (xy 132.928216 -55.061214) (xy 132.887025 -55.096905)
			(xy 132.841175 -55.126371) (xy 132.791598 -55.149013) (xy 132.739303 -55.164368) (xy 132.685355 -55.172124)
			(xy 132.630853 -55.172124) (xy 132.576905 -55.164368) (xy 132.52461 -55.149013) (xy 132.475033 -55.126371)
			(xy 132.429183 -55.096905) (xy 132.387992 -55.061214) (xy 132.352301 -55.020023) (xy 132.322835 -54.974173)
			(xy 132.300193 -54.924596) (xy 132.284838 -54.872301) (xy 132.277082 -54.818353) (xy 132.276596 -54.791102)
			(xy 130.378638 -54.791102) (xy 130.375546 -54.812611) (xy 130.360191 -54.864906) (xy 130.337549 -54.914483)
			(xy 130.308083 -54.960333) (xy 130.272392 -55.001524) (xy 130.231201 -55.037215) (xy 130.185351 -55.066681)
			(xy 130.135774 -55.089323) (xy 130.083479 -55.104678) (xy 130.029531 -55.112434) (xy 129.975029 -55.112434)
			(xy 129.921081 -55.104678) (xy 129.868786 -55.089323) (xy 129.819209 -55.066681) (xy 129.773359 -55.037215)
			(xy 129.732168 -55.001524) (xy 129.696477 -54.960333) (xy 129.667011 -54.914483) (xy 129.644369 -54.864906)
			(xy 129.629014 -54.812611) (xy 129.621258 -54.758663) (xy 129.620772 -54.731412) (xy 121.112696 -54.731412)
			(xy 121.152581 -54.737145) (xy 121.204874 -54.752498) (xy 121.25445 -54.775136) (xy 121.300299 -54.804599)
			(xy 121.341489 -54.840287) (xy 121.377181 -54.881473) (xy 121.406648 -54.92732) (xy 121.42929 -54.976894)
			(xy 121.444647 -55.029185) (xy 121.452406 -55.08313) (xy 121.452894 -55.11038) (xy 121.452418 -55.13775)
			(xy 121.444603 -55.191929) (xy 121.429116 -55.244432) (xy 121.406276 -55.294179) (xy 121.376554 -55.340146)
			(xy 121.358914 -55.361078) (xy 121.35866 -55.361332) (xy 121.353091 -55.36843) (xy 121.346835 -55.385338)
			(xy 121.346468 -55.394352) (xy 121.346468 -55.461408) (xy 121.346828 -55.470424) (xy 121.353074 -55.487341)
			(xy 121.35866 -55.494428) (xy 121.358914 -55.494428) (xy 121.358914 -55.494682) (xy 121.376533 -55.515631)
			(xy 121.406256 -55.561597) (xy 121.4291 -55.611341) (xy 121.444596 -55.66384) (xy 121.452426 -55.718016)
			(xy 121.452426 -55.722266) (xy 141.934182 -55.722266) (xy 141.938253 -55.666644) (xy 141.950379 -55.612207)
			(xy 141.970302 -55.560116) (xy 141.997598 -55.511481) (xy 142.031684 -55.467338) (xy 142.071833 -55.428629)
			(xy 142.117191 -55.396178) (xy 142.166791 -55.370677) (xy 142.219575 -55.35267) (xy 142.274418 -55.34254)
			(xy 142.330152 -55.340503) (xy 142.385589 -55.346603) (xy 142.439546 -55.360709) (xy 142.490875 -55.382521)
			(xy 142.538481 -55.411575) (xy 142.549632 -55.420855) (xy 144.324745 -55.420855) (xy 144.324745 -55.366345)
			(xy 144.332503 -55.31239) (xy 144.347861 -55.260088) (xy 144.370506 -55.210504) (xy 144.399978 -55.164648)
			(xy 144.435676 -55.123454) (xy 144.476874 -55.087759) (xy 144.522732 -55.058291) (xy 144.572318 -55.03565)
			(xy 144.624621 -55.020296) (xy 144.678577 -55.012543) (xy 144.705832 -55.012082) (xy 144.732146 -55.012534)
			(xy 144.784275 -55.019773) (xy 144.834918 -55.034095) (xy 144.883117 -55.055231) (xy 144.92796 -55.082779)
			(xy 144.968599 -55.11622) (xy 144.986756 -55.135272) (xy 144.994296 -55.142652) (xy 145.013562 -55.15119)
			(xy 145.024094 -55.151782) (xy 145.09877 -55.151782) (xy 145.10932 -55.151256) (xy 145.128616 -55.142719)
			(xy 145.136108 -55.135272) (xy 145.154261 -55.116214) (xy 145.194892 -55.082758) (xy 145.239733 -55.0552)
			(xy 145.287934 -55.034062) (xy 145.338582 -55.019745) (xy 145.390716 -55.012521) (xy 145.417032 -55.012082)
			(xy 145.444281 -55.01259) (xy 145.498224 -55.02035) (xy 145.550513 -55.035708) (xy 145.600085 -55.05835)
			(xy 145.64593 -55.087817) (xy 145.687116 -55.123507) (xy 145.722803 -55.164695) (xy 145.752265 -55.210543)
			(xy 145.774903 -55.260117) (xy 145.790256 -55.312408) (xy 145.798012 -55.366351) (xy 145.798012 -55.420849)
			(xy 145.790256 -55.474792) (xy 145.774903 -55.527083) (xy 145.752265 -55.576657) (xy 145.722803 -55.622505)
			(xy 145.687116 -55.663693) (xy 145.64593 -55.699383) (xy 145.600085 -55.72885) (xy 145.550513 -55.751492)
			(xy 145.498224 -55.76685) (xy 145.444281 -55.77461) (xy 145.417032 -55.775098) (xy 145.390716 -55.774677)
			(xy 145.338586 -55.767432) (xy 145.287942 -55.753104) (xy 145.239744 -55.731963) (xy 145.194901 -55.704409)
			(xy 145.154263 -55.670963) (xy 145.136108 -55.651908) (xy 145.128584 -55.644509) (xy 145.109306 -55.635983)
			(xy 145.09877 -55.635398) (xy 145.024094 -55.635398) (xy 145.013542 -55.635911) (xy 144.994247 -55.644457)
			(xy 144.986756 -55.651908) (xy 144.968616 -55.670979) (xy 144.927983 -55.704435) (xy 144.883139 -55.731992)
			(xy 144.834936 -55.753127) (xy 144.784285 -55.767441) (xy 144.732149 -55.774662) (xy 144.705832 -55.775098)
			(xy 144.678577 -55.774657) (xy 144.624621 -55.766904) (xy 144.572318 -55.75155) (xy 144.522732 -55.728909)
			(xy 144.476874 -55.699441) (xy 144.435676 -55.663746) (xy 144.399978 -55.622552) (xy 144.370506 -55.576696)
			(xy 144.347861 -55.527112) (xy 144.332503 -55.47481) (xy 144.324745 -55.420855) (xy 142.549632 -55.420855)
			(xy 142.581349 -55.44725) (xy 142.618566 -55.488787) (xy 142.649339 -55.5353) (xy 142.673011 -55.585797)
			(xy 142.689079 -55.639204) (xy 142.697199 -55.69438) (xy 142.697708 -55.722266) (xy 142.697199 -55.750152)
			(xy 142.689079 -55.805328) (xy 142.673011 -55.858735) (xy 142.649339 -55.909232) (xy 142.618566 -55.955745)
			(xy 142.581349 -55.997282) (xy 142.538481 -56.032957) (xy 142.490875 -56.062011) (xy 142.439546 -56.083823)
			(xy 142.385589 -56.097929) (xy 142.330152 -56.104029) (xy 142.274418 -56.101992) (xy 142.219575 -56.091862)
			(xy 142.166791 -56.073855) (xy 142.117191 -56.048354) (xy 142.071833 -56.015903) (xy 142.031684 -55.977194)
			(xy 141.997598 -55.933051) (xy 141.970302 -55.884416) (xy 141.950379 -55.832325) (xy 141.938253 -55.777888)
			(xy 141.934182 -55.722266) (xy 121.452426 -55.722266) (xy 121.452428 -55.772754) (xy 121.444602 -55.82693)
			(xy 121.42911 -55.879431) (xy 121.40627 -55.929176) (xy 121.376552 -55.975144) (xy 121.358914 -55.996078)
			(xy 121.35866 -55.996332) (xy 121.353091 -56.00343) (xy 121.346835 -56.020338) (xy 121.346468 -56.029352)
			(xy 121.346468 -56.096408) (xy 121.346828 -56.105424) (xy 121.353074 -56.122341) (xy 121.35866 -56.129428)
			(xy 121.358914 -56.129428) (xy 121.358914 -56.129682) (xy 121.37656 -56.150608) (xy 121.406271 -56.196583)
			(xy 121.429105 -56.246332) (xy 121.444594 -56.298834) (xy 121.452421 -56.35301) (xy 121.452894 -56.38038)
			(xy 121.452408 -56.407631) (xy 121.444652 -56.461579) (xy 121.429297 -56.513874) (xy 121.406655 -56.563451)
			(xy 121.377189 -56.609301) (xy 121.341498 -56.650492) (xy 121.300307 -56.686183) (xy 121.254457 -56.715649)
			(xy 121.20488 -56.738291) (xy 121.152585 -56.753646) (xy 121.098637 -56.761402) (xy 121.044135 -56.761402)
			(xy 120.990187 -56.753646) (xy 120.937892 -56.738291) (xy 120.888315 -56.715649) (xy 120.842465 -56.686183)
			(xy 120.801274 -56.650492) (xy 120.765583 -56.609301) (xy 120.736117 -56.563451) (xy 120.713475 -56.513874)
			(xy 120.69812 -56.461579) (xy 120.690364 -56.407631) (xy 120.689878 -56.38038) (xy 120.690313 -56.353008)
			(xy 120.698136 -56.298827) (xy 120.713631 -56.246323) (xy 120.73648 -56.196577) (xy 120.766213 -56.150612)
			(xy 120.783858 -56.129682) (xy 120.784112 -56.129428) (xy 120.789694 -56.122339) (xy 120.795943 -56.105424)
			(xy 120.796304 -56.096408) (xy 120.796304 -56.029352) (xy 120.795921 -56.020338) (xy 120.789691 -56.003421)
			(xy 120.784112 -55.996332) (xy 120.783858 -55.996332) (xy 120.783858 -55.996078) (xy 120.766196 -55.975162)
			(xy 120.73647 -55.929192) (xy 120.713624 -55.879443) (xy 120.698128 -55.826938) (xy 120.690301 -55.772757)
			(xy 120.690303 -55.718013) (xy 120.698134 -55.663832) (xy 120.713635 -55.611329) (xy 120.736485 -55.561582)
			(xy 120.766215 -55.515614) (xy 120.783858 -55.494682) (xy 120.784112 -55.494428) (xy 120.789694 -55.487339)
			(xy 120.795943 -55.470424) (xy 120.796304 -55.461408) (xy 120.796304 -55.394352) (xy 120.795921 -55.385338)
			(xy 120.789691 -55.368421) (xy 120.784112 -55.361332) (xy 120.783858 -55.360824) (xy 120.772912 -55.348091)
			(xy 120.753072 -55.320999) (xy 120.744234 -55.306722) (xy 120.7389 -55.297832) (xy 120.721882 -55.28564)
			(xy 120.628664 -55.26532) (xy 120.60809 -55.269638) (xy 120.599454 -55.27548) (xy 120.575403 -55.2915)
			(xy 120.523467 -55.316838) (xy 120.468305 -55.334059) (xy 120.411178 -55.342767) (xy 120.382284 -55.343298)
			(xy 120.355033 -55.342831) (xy 120.301085 -55.335073) (xy 120.248791 -55.319716) (xy 120.199215 -55.297073)
			(xy 120.153365 -55.267605) (xy 120.112176 -55.231913) (xy 120.076485 -55.190722) (xy 120.047019 -55.144871)
			(xy 120.024379 -55.095294) (xy 120.009024 -55.042999) (xy 120.001268 -54.989051) (xy 110.381065 -54.989051)
			(xy 110.389665 -55.420851) (xy 118.324868 -55.420851) (xy 118.324868 -55.366349) (xy 118.332624 -55.312401)
			(xy 118.347979 -55.260106) (xy 118.370619 -55.210529) (xy 118.400085 -55.164678) (xy 118.435776 -55.123487)
			(xy 118.476965 -55.087795) (xy 118.522815 -55.058327) (xy 118.572391 -55.035684) (xy 118.624685 -55.020327)
			(xy 118.678633 -55.012569) (xy 118.705884 -55.012082) (xy 118.732197 -55.012566) (xy 118.784325 -55.019798)
			(xy 118.834967 -55.034114) (xy 118.883166 -55.055244) (xy 118.92801 -55.082787) (xy 118.968651 -55.116222)
			(xy 118.986808 -55.135272) (xy 118.994328 -55.142675) (xy 119.013609 -55.1512) (xy 119.024146 -55.151782)
			(xy 119.098822 -55.151782) (xy 119.109369 -55.15123) (xy 119.128665 -55.142711) (xy 119.13616 -55.135272)
			(xy 119.154288 -55.116189) (xy 119.194924 -55.082735) (xy 119.23977 -55.055181) (xy 119.287977 -55.034047)
			(xy 119.338629 -55.019736) (xy 119.390766 -55.012517) (xy 119.417084 -55.012082) (xy 119.444337 -55.012564)
			(xy 119.498288 -55.020319) (xy 119.550587 -55.035673) (xy 119.600167 -55.058314) (xy 119.646021 -55.087781)
			(xy 119.687215 -55.123474) (xy 119.722909 -55.164666) (xy 119.752378 -55.210519) (xy 119.775021 -55.260098)
			(xy 119.790377 -55.312396) (xy 119.798135 -55.366347) (xy 119.798135 -55.420853) (xy 119.790377 -55.474804)
			(xy 119.775021 -55.527102) (xy 119.752378 -55.576681) (xy 119.722909 -55.622534) (xy 119.687215 -55.663726)
			(xy 119.646021 -55.699419) (xy 119.600167 -55.728886) (xy 119.550587 -55.751527) (xy 119.498288 -55.766881)
			(xy 119.444337 -55.774636) (xy 119.417084 -55.775098) (xy 119.39077 -55.774642) (xy 119.338641 -55.767405)
			(xy 119.287998 -55.753084) (xy 119.239799 -55.731949) (xy 119.194955 -55.704401) (xy 119.154316 -55.67096)
			(xy 119.13616 -55.651908) (xy 119.128654 -55.644488) (xy 119.109362 -55.635974) (xy 119.098822 -55.635398)
			(xy 119.024146 -55.635398) (xy 119.013598 -55.635939) (xy 118.994302 -55.644466) (xy 118.986808 -55.651908)
			(xy 118.968643 -55.670954) (xy 118.928015 -55.704412) (xy 118.883177 -55.731972) (xy 118.834978 -55.753112)
			(xy 118.784332 -55.767431) (xy 118.7322 -55.774658) (xy 118.705884 -55.775098) (xy 118.678633 -55.774631)
			(xy 118.624685 -55.766873) (xy 118.572391 -55.751516) (xy 118.522815 -55.728873) (xy 118.476965 -55.699405)
			(xy 118.435776 -55.663713) (xy 118.400085 -55.622522) (xy 118.370619 -55.576671) (xy 118.347979 -55.527094)
			(xy 118.332624 -55.474799) (xy 118.324868 -55.420851) (xy 110.389665 -55.420851) (xy 110.42015 -56.951372)
			(xy 110.420404 -56.971184) (xy 110.420135 -57.002934) (xy 137.663682 -57.002934) (xy 137.664204 -56.974843)
			(xy 137.672426 -56.919268) (xy 137.688712 -56.865499) (xy 137.712711 -56.814702) (xy 137.743901 -56.767975)
			(xy 137.78161 -56.726329) (xy 137.825019 -56.690665) (xy 137.848848 -56.675782) (xy 137.857738 -56.670448)
			(xy 137.86993 -56.65343) (xy 137.89025 -56.560212) (xy 137.885932 -56.539638) (xy 137.88009 -56.531002)
			(xy 137.864087 -56.50694) (xy 137.838746 -56.455008) (xy 137.821521 -56.399849) (xy 137.812806 -56.342725)
			(xy 137.812272 -56.313832) (xy 137.812785 -56.286581) (xy 137.820537 -56.232633) (xy 137.835888 -56.180337)
			(xy 137.858525 -56.130758) (xy 137.887988 -56.084906) (xy 137.923677 -56.043714) (xy 137.964864 -56.008019)
			(xy 138.010713 -55.97855) (xy 138.060288 -55.955906) (xy 138.112582 -55.940548) (xy 138.166529 -55.932789)
			(xy 138.19378 -55.932324) (xy 138.22115 -55.932796) (xy 138.275329 -55.940611) (xy 138.327832 -55.956099)
			(xy 138.377579 -55.978939) (xy 138.423546 -56.008663) (xy 138.444478 -56.026304) (xy 138.444732 -56.026558)
			(xy 138.451829 -56.032129) (xy 138.468738 -56.038384) (xy 138.477752 -56.03875) (xy 138.544808 -56.03875)
			(xy 138.553827 -56.038407) (xy 138.570744 -56.032151) (xy 138.577828 -56.026558) (xy 138.577828 -56.026304)
			(xy 138.578082 -56.026304) (xy 138.599015 -56.008663) (xy 138.644983 -55.978939) (xy 138.694729 -55.956093)
			(xy 138.747231 -55.940597) (xy 138.801409 -55.932768) (xy 138.856151 -55.932768) (xy 138.910329 -55.940597)
			(xy 138.962831 -55.956093) (xy 139.012577 -55.978939) (xy 139.058545 -56.008663) (xy 139.079478 -56.026304)
			(xy 139.079732 -56.026558) (xy 139.086829 -56.032129) (xy 139.103738 -56.038384) (xy 139.112752 -56.03875)
			(xy 139.179808 -56.03875) (xy 139.188827 -56.038407) (xy 139.205744 -56.032151) (xy 139.212828 -56.026558)
			(xy 139.212828 -56.026304) (xy 139.213082 -56.026304) (xy 139.234011 -56.008661) (xy 139.279984 -55.978949)
			(xy 139.329733 -55.956114) (xy 139.382234 -55.940624) (xy 139.436411 -55.932797) (xy 139.46378 -55.932324)
			(xy 139.491036 -55.932722) (xy 139.544994 -55.940477) (xy 139.597298 -55.955832) (xy 139.646885 -55.978476)
			(xy 139.692745 -56.007946) (xy 139.733943 -56.043642) (xy 139.769642 -56.084839) (xy 139.799115 -56.130697)
			(xy 139.821761 -56.180283) (xy 139.837119 -56.232587) (xy 139.844877 -56.286544) (xy 139.844877 -56.297068)
			(xy 140.186662 -56.297068) (xy 140.190733 -56.241446) (xy 140.202859 -56.187009) (xy 140.222782 -56.134918)
			(xy 140.250078 -56.086283) (xy 140.284164 -56.04214) (xy 140.324313 -56.003431) (xy 140.369671 -55.97098)
			(xy 140.419271 -55.945479) (xy 140.472055 -55.927472) (xy 140.526898 -55.917342) (xy 140.582632 -55.915305)
			(xy 140.638069 -55.921405) (xy 140.692026 -55.935511) (xy 140.743355 -55.957323) (xy 140.790961 -55.986377)
			(xy 140.833829 -56.022052) (xy 140.871046 -56.063589) (xy 140.901819 -56.110102) (xy 140.925491 -56.160599)
			(xy 140.941559 -56.214006) (xy 140.949679 -56.269182) (xy 140.950188 -56.297068) (xy 140.949679 -56.324954)
			(xy 140.941559 -56.38013) (xy 140.925491 -56.433537) (xy 140.901819 -56.484034) (xy 140.871046 -56.530547)
			(xy 140.833829 -56.572084) (xy 140.790961 -56.607759) (xy 140.743355 -56.636813) (xy 140.692026 -56.658625)
			(xy 140.638069 -56.672731) (xy 140.582632 -56.678831) (xy 140.526898 -56.676794) (xy 140.472055 -56.666664)
			(xy 140.419271 -56.648657) (xy 140.369671 -56.623156) (xy 140.324313 -56.590705) (xy 140.284164 -56.551996)
			(xy 140.250078 -56.507853) (xy 140.222782 -56.459218) (xy 140.202859 -56.407127) (xy 140.190733 -56.35269)
			(xy 140.186662 -56.297068) (xy 139.844877 -56.297068) (xy 139.844877 -56.341056) (xy 139.837119 -56.395013)
			(xy 139.821761 -56.447317) (xy 139.799115 -56.496903) (xy 139.769642 -56.542761) (xy 139.733943 -56.583958)
			(xy 139.692745 -56.619654) (xy 139.646885 -56.649124) (xy 139.597298 -56.671768) (xy 139.544994 -56.687123)
			(xy 139.491036 -56.694878) (xy 139.46378 -56.69534) (xy 139.436409 -56.6949) (xy 139.382228 -56.687078)
			(xy 139.329724 -56.671584) (xy 139.279977 -56.648736) (xy 139.234012 -56.619005) (xy 139.213082 -56.60136)
			(xy 139.212828 -56.601106) (xy 139.205737 -56.595526) (xy 139.188824 -56.589275) (xy 139.179808 -56.588914)
			(xy 139.112752 -56.588914) (xy 139.103737 -56.589293) (xy 139.08682 -56.595525) (xy 139.079732 -56.601106)
			(xy 139.079732 -56.60136) (xy 139.079478 -56.60136) (xy 139.058545 -56.619001) (xy 139.012577 -56.648725)
			(xy 138.962831 -56.671571) (xy 138.910329 -56.687067) (xy 138.856151 -56.694896) (xy 138.801409 -56.694896)
			(xy 138.747231 -56.687067) (xy 138.694729 -56.671571) (xy 138.644983 -56.648725) (xy 138.599015 -56.619001)
			(xy 138.578082 -56.60136) (xy 138.577828 -56.601106) (xy 138.570737 -56.595526) (xy 138.553824 -56.589275)
			(xy 138.544808 -56.588914) (xy 138.477752 -56.588914) (xy 138.468737 -56.589293) (xy 138.45182 -56.595525)
			(xy 138.444732 -56.601106) (xy 138.444224 -56.60136) (xy 138.431492 -56.612307) (xy 138.404399 -56.632146)
			(xy 138.390122 -56.640984) (xy 138.381232 -56.646318) (xy 138.36904 -56.663336) (xy 138.34872 -56.756554)
			(xy 138.353038 -56.777128) (xy 138.35888 -56.785764) (xy 138.374865 -56.809838) (xy 138.400211 -56.861765)
			(xy 138.417441 -56.91692) (xy 138.426161 -56.974042) (xy 138.426698 -57.002934) (xy 138.426212 -57.030185)
			(xy 138.418456 -57.084133) (xy 138.403101 -57.136428) (xy 138.380459 -57.186005) (xy 138.350993 -57.231855)
			(xy 138.315302 -57.273046) (xy 138.274111 -57.308737) (xy 138.228261 -57.338203) (xy 138.178684 -57.360845)
			(xy 138.126389 -57.3762) (xy 138.072441 -57.383956) (xy 138.017939 -57.383956) (xy 137.963991 -57.3762)
			(xy 137.911696 -57.360845) (xy 137.862119 -57.338203) (xy 137.816269 -57.308737) (xy 137.775078 -57.273046)
			(xy 137.739387 -57.231855) (xy 137.709921 -57.186005) (xy 137.687279 -57.136428) (xy 137.671924 -57.084133)
			(xy 137.664168 -57.030185) (xy 137.663682 -57.002934) (xy 110.420135 -57.002934) (xy 110.420122 -57.004433)
			(xy 110.415675 -57.070783) (xy 110.411514 -57.103772) (xy 110.401608 -57.162954) (xy 110.338491 -57.48528)
			(xy 120.706132 -57.48528) (xy 120.710203 -57.429658) (xy 120.722329 -57.375221) (xy 120.742252 -57.32313)
			(xy 120.769548 -57.274495) (xy 120.803634 -57.230352) (xy 120.843783 -57.191643) (xy 120.889141 -57.159192)
			(xy 120.938741 -57.133691) (xy 120.991525 -57.115684) (xy 121.046368 -57.105554) (xy 121.102102 -57.103517)
			(xy 121.157539 -57.109617) (xy 121.211496 -57.123723) (xy 121.262825 -57.145535) (xy 121.310431 -57.174589)
			(xy 121.353299 -57.210264) (xy 121.390516 -57.251801) (xy 121.421289 -57.298314) (xy 121.444961 -57.348811)
			(xy 121.461029 -57.402218) (xy 121.469149 -57.457394) (xy 121.469658 -57.48528) (xy 146.70608 -57.48528)
			(xy 146.710151 -57.429658) (xy 146.722277 -57.375221) (xy 146.7422 -57.32313) (xy 146.769496 -57.274495)
			(xy 146.803582 -57.230352) (xy 146.843731 -57.191643) (xy 146.889089 -57.159192) (xy 146.938689 -57.133691)
			(xy 146.991473 -57.115684) (xy 147.046316 -57.105554) (xy 147.10205 -57.103517) (xy 147.157487 -57.109617)
			(xy 147.211444 -57.123723) (xy 147.262773 -57.145535) (xy 147.310379 -57.174589) (xy 147.353247 -57.210264)
			(xy 147.390464 -57.251801) (xy 147.421237 -57.298314) (xy 147.444909 -57.348811) (xy 147.460977 -57.402218)
			(xy 147.469097 -57.457394) (xy 147.469606 -57.48528) (xy 147.469097 -57.513166) (xy 147.460977 -57.568342)
			(xy 147.444909 -57.621749) (xy 147.421237 -57.672246) (xy 147.390464 -57.718759) (xy 147.353247 -57.760296)
			(xy 147.310379 -57.795971) (xy 147.262773 -57.825025) (xy 147.211444 -57.846837) (xy 147.157487 -57.860943)
			(xy 147.10205 -57.867043) (xy 147.046316 -57.865006) (xy 146.991473 -57.854876) (xy 146.938689 -57.836869)
			(xy 146.889089 -57.811368) (xy 146.843731 -57.778917) (xy 146.803582 -57.740208) (xy 146.769496 -57.696065)
			(xy 146.7422 -57.64743) (xy 146.722277 -57.595339) (xy 146.710151 -57.540902) (xy 146.70608 -57.48528)
			(xy 121.469658 -57.48528) (xy 121.469149 -57.513166) (xy 121.461029 -57.568342) (xy 121.444961 -57.621749)
			(xy 121.421289 -57.672246) (xy 121.390516 -57.718759) (xy 121.353299 -57.760296) (xy 121.310431 -57.795971)
			(xy 121.262825 -57.825025) (xy 121.211496 -57.846837) (xy 121.157539 -57.860943) (xy 121.102102 -57.867043)
			(xy 121.046368 -57.865006) (xy 120.991525 -57.854876) (xy 120.938741 -57.836869) (xy 120.889141 -57.811368)
			(xy 120.843783 -57.778917) (xy 120.803634 -57.740208) (xy 120.769548 -57.696065) (xy 120.742252 -57.64743)
			(xy 120.722329 -57.595339) (xy 120.710203 -57.540902) (xy 120.706132 -57.48528) (xy 110.338491 -57.48528)
			(xy 110.222801 -58.076084) (xy 121.458226 -58.076084) (xy 121.462297 -58.020462) (xy 121.474423 -57.966025)
			(xy 121.494346 -57.913934) (xy 121.521642 -57.865299) (xy 121.555728 -57.821156) (xy 121.595877 -57.782447)
			(xy 121.641235 -57.749996) (xy 121.690835 -57.724495) (xy 121.743619 -57.706488) (xy 121.798462 -57.696358)
			(xy 121.854196 -57.694321) (xy 121.909633 -57.700421) (xy 121.96359 -57.714527) (xy 122.014919 -57.736339)
			(xy 122.062525 -57.765393) (xy 122.105393 -57.801068) (xy 122.14261 -57.842605) (xy 122.158946 -57.867296)
			(xy 123.74321 -57.867296) (xy 123.747281 -57.811674) (xy 123.759407 -57.757237) (xy 123.77933 -57.705146)
			(xy 123.806626 -57.656511) (xy 123.840712 -57.612368) (xy 123.880861 -57.573659) (xy 123.926219 -57.541208)
			(xy 123.975819 -57.515707) (xy 124.028603 -57.4977) (xy 124.083446 -57.48757) (xy 124.13918 -57.485533)
			(xy 124.194617 -57.491633) (xy 124.248574 -57.505739) (xy 124.299903 -57.527551) (xy 124.347509 -57.556605)
			(xy 124.390377 -57.59228) (xy 124.427594 -57.633817) (xy 124.458367 -57.68033) (xy 124.482039 -57.730827)
			(xy 124.498107 -57.784234) (xy 124.506227 -57.83941) (xy 124.506736 -57.867296) (xy 124.506227 -57.895182)
			(xy 124.498107 -57.950358) (xy 124.482039 -58.003765) (xy 124.458367 -58.054262) (xy 124.427594 -58.100775)
			(xy 124.390377 -58.142312) (xy 124.347509 -58.177987) (xy 124.299903 -58.207041) (xy 124.248574 -58.228853)
			(xy 124.194617 -58.242959) (xy 124.13918 -58.249059) (xy 124.083446 -58.247022) (xy 124.028603 -58.236892)
			(xy 123.975819 -58.218885) (xy 123.926219 -58.193384) (xy 123.880861 -58.160933) (xy 123.840712 -58.122224)
			(xy 123.806626 -58.078081) (xy 123.77933 -58.029446) (xy 123.759407 -57.977355) (xy 123.747281 -57.922918)
			(xy 123.74321 -57.867296) (xy 122.158946 -57.867296) (xy 122.173383 -57.889118) (xy 122.197055 -57.939615)
			(xy 122.213123 -57.993022) (xy 122.221243 -58.048198) (xy 122.221752 -58.076084) (xy 122.221243 -58.10397)
			(xy 122.213123 -58.159146) (xy 122.197055 -58.212553) (xy 122.173383 -58.26305) (xy 122.14261 -58.309563)
			(xy 122.105393 -58.3511) (xy 122.062525 -58.386775) (xy 122.014919 -58.415829) (xy 121.96359 -58.437641)
			(xy 121.909633 -58.451747) (xy 121.854196 -58.457847) (xy 121.798462 -58.45581) (xy 121.743619 -58.44568)
			(xy 121.690835 -58.427673) (xy 121.641235 -58.402172) (xy 121.595877 -58.369721) (xy 121.555728 -58.331012)
			(xy 121.521642 -58.286869) (xy 121.494346 -58.238234) (xy 121.474423 -58.186143) (xy 121.462297 -58.131706)
			(xy 121.458226 -58.076084) (xy 110.222801 -58.076084) (xy 110.127802 -58.561224) (xy 122.66244 -58.561224)
			(xy 122.666511 -58.505602) (xy 122.678637 -58.451165) (xy 122.69856 -58.399074) (xy 122.725856 -58.350439)
			(xy 122.759942 -58.306296) (xy 122.800091 -58.267587) (xy 122.845449 -58.235136) (xy 122.895049 -58.209635)
			(xy 122.947833 -58.191628) (xy 123.002676 -58.181498) (xy 123.05841 -58.179461) (xy 123.113847 -58.185561)
			(xy 123.167804 -58.199667) (xy 123.219133 -58.221479) (xy 123.266739 -58.250533) (xy 123.309607 -58.286208)
			(xy 123.346824 -58.327745) (xy 123.377597 -58.374258) (xy 123.401269 -58.424755) (xy 123.408779 -58.449718)
			(xy 124.90907 -58.449718) (xy 124.913141 -58.394096) (xy 124.925267 -58.339659) (xy 124.94519 -58.287568)
			(xy 124.972486 -58.238933) (xy 125.006572 -58.19479) (xy 125.046721 -58.156081) (xy 125.092079 -58.12363)
			(xy 125.141679 -58.098129) (xy 125.194463 -58.080122) (xy 125.249306 -58.069992) (xy 125.30504 -58.067955)
			(xy 125.360477 -58.074055) (xy 125.414434 -58.088161) (xy 125.465763 -58.109973) (xy 125.513369 -58.139027)
			(xy 125.556237 -58.174702) (xy 125.593454 -58.216239) (xy 125.624227 -58.262752) (xy 125.647899 -58.313249)
			(xy 125.663967 -58.366656) (xy 125.672087 -58.421832) (xy 125.672596 -58.449718) (xy 125.672087 -58.477604)
			(xy 125.663967 -58.53278) (xy 125.647899 -58.586187) (xy 125.624227 -58.636684) (xy 125.59601 -58.679334)
			(xy 138.095482 -58.679334) (xy 138.095911 -58.653019) (xy 138.103155 -58.600889) (xy 138.117482 -58.550246)
			(xy 138.138621 -58.502047) (xy 138.166174 -58.457204) (xy 138.199618 -58.416566) (xy 138.218672 -58.39841)
			(xy 138.226067 -58.390883) (xy 138.234596 -58.371607) (xy 138.235182 -58.361072) (xy 138.235182 -58.286396)
			(xy 138.234674 -58.275844) (xy 138.226124 -58.256548) (xy 138.218672 -58.249058) (xy 138.199598 -58.230921)
			(xy 138.166143 -58.190287) (xy 138.138588 -58.145443) (xy 138.117453 -58.097238) (xy 138.103139 -58.046588)
			(xy 138.095918 -57.994451) (xy 138.095482 -57.968134) (xy 138.095968 -57.940883) (xy 138.103724 -57.886935)
			(xy 138.119079 -57.83464) (xy 138.141721 -57.785063) (xy 138.171187 -57.739213) (xy 138.206878 -57.698022)
			(xy 138.248069 -57.662331) (xy 138.293919 -57.632865) (xy 138.343496 -57.610223) (xy 138.395791 -57.594868)
			(xy 138.449739 -57.587112) (xy 138.504241 -57.587112) (xy 138.558189 -57.594868) (xy 138.610484 -57.610223)
			(xy 138.660061 -57.632865) (xy 138.705911 -57.662331) (xy 138.747102 -57.698022) (xy 138.782793 -57.739213)
			(xy 138.812259 -57.785063) (xy 138.834901 -57.83464) (xy 138.850256 -57.886935) (xy 138.858012 -57.940883)
			(xy 138.858498 -57.968134) (xy 138.858054 -57.994449) (xy 138.850814 -58.046578) (xy 138.843547 -58.072274)
			(xy 142.093694 -58.072274) (xy 142.097765 -58.016652) (xy 142.109891 -57.962215) (xy 142.129814 -57.910124)
			(xy 142.15711 -57.861489) (xy 142.191196 -57.817346) (xy 142.231345 -57.778637) (xy 142.276703 -57.746186)
			(xy 142.326303 -57.720685) (xy 142.379087 -57.702678) (xy 142.43393 -57.692548) (xy 142.489664 -57.690511)
			(xy 142.545101 -57.696611) (xy 142.599058 -57.710717) (xy 142.650387 -57.732529) (xy 142.697993 -57.761583)
			(xy 142.740861 -57.797258) (xy 142.778078 -57.838795) (xy 142.808851 -57.885308) (xy 142.832523 -57.935805)
			(xy 142.848591 -57.989212) (xy 142.856711 -58.044388) (xy 142.85722 -58.072274) (xy 142.85715 -58.076084)
			(xy 147.458174 -58.076084) (xy 147.462245 -58.020462) (xy 147.474371 -57.966025) (xy 147.494294 -57.913934)
			(xy 147.52159 -57.865299) (xy 147.555676 -57.821156) (xy 147.595825 -57.782447) (xy 147.641183 -57.749996)
			(xy 147.690783 -57.724495) (xy 147.743567 -57.706488) (xy 147.79841 -57.696358) (xy 147.854144 -57.694321)
			(xy 147.909581 -57.700421) (xy 147.963538 -57.714527) (xy 148.014867 -57.736339) (xy 148.062473 -57.765393)
			(xy 148.105341 -57.801068) (xy 148.142558 -57.842605) (xy 148.158894 -57.867296) (xy 149.743158 -57.867296)
			(xy 149.747229 -57.811674) (xy 149.759355 -57.757237) (xy 149.779278 -57.705146) (xy 149.806574 -57.656511)
			(xy 149.84066 -57.612368) (xy 149.880809 -57.573659) (xy 149.926167 -57.541208) (xy 149.975767 -57.515707)
			(xy 150.028551 -57.4977) (xy 150.083394 -57.48757) (xy 150.139128 -57.485533) (xy 150.194565 -57.491633)
			(xy 150.248522 -57.505739) (xy 150.299851 -57.527551) (xy 150.347457 -57.556605) (xy 150.390325 -57.59228)
			(xy 150.427542 -57.633817) (xy 150.458315 -57.68033) (xy 150.481987 -57.730827) (xy 150.498055 -57.784234)
			(xy 150.506175 -57.83941) (xy 150.506684 -57.867296) (xy 150.506175 -57.895182) (xy 150.498055 -57.950358)
			(xy 150.481987 -58.003765) (xy 150.458315 -58.054262) (xy 150.427542 -58.100775) (xy 150.390325 -58.142312)
			(xy 150.347457 -58.177987) (xy 150.299851 -58.207041) (xy 150.248522 -58.228853) (xy 150.194565 -58.242959)
			(xy 150.139128 -58.249059) (xy 150.083394 -58.247022) (xy 150.028551 -58.236892) (xy 149.975767 -58.218885)
			(xy 149.926167 -58.193384) (xy 149.880809 -58.160933) (xy 149.84066 -58.122224) (xy 149.806574 -58.078081)
			(xy 149.779278 -58.029446) (xy 149.759355 -57.977355) (xy 149.747229 -57.922918) (xy 149.743158 -57.867296)
			(xy 148.158894 -57.867296) (xy 148.173331 -57.889118) (xy 148.197003 -57.939615) (xy 148.213071 -57.993022)
			(xy 148.221191 -58.048198) (xy 148.2217 -58.076084) (xy 148.221191 -58.10397) (xy 148.213071 -58.159146)
			(xy 148.197003 -58.212553) (xy 148.173331 -58.26305) (xy 148.142558 -58.309563) (xy 148.105341 -58.3511)
			(xy 148.062473 -58.386775) (xy 148.014867 -58.415829) (xy 147.963538 -58.437641) (xy 147.909581 -58.451747)
			(xy 147.854144 -58.457847) (xy 147.79841 -58.45581) (xy 147.743567 -58.44568) (xy 147.690783 -58.427673)
			(xy 147.641183 -58.402172) (xy 147.595825 -58.369721) (xy 147.555676 -58.331012) (xy 147.52159 -58.286869)
			(xy 147.494294 -58.238234) (xy 147.474371 -58.186143) (xy 147.462245 -58.131706) (xy 147.458174 -58.076084)
			(xy 142.85715 -58.076084) (xy 142.856711 -58.10016) (xy 142.848591 -58.155336) (xy 142.832523 -58.208743)
			(xy 142.808851 -58.25924) (xy 142.778078 -58.305753) (xy 142.740861 -58.34729) (xy 142.697993 -58.382965)
			(xy 142.650387 -58.412019) (xy 142.599058 -58.433831) (xy 142.545101 -58.447937) (xy 142.489664 -58.454037)
			(xy 142.43393 -58.452) (xy 142.379087 -58.44187) (xy 142.326303 -58.423863) (xy 142.276703 -58.398362)
			(xy 142.231345 -58.365911) (xy 142.191196 -58.327202) (xy 142.15711 -58.283059) (xy 142.129814 -58.234424)
			(xy 142.109891 -58.182333) (xy 142.097765 -58.127896) (xy 142.093694 -58.072274) (xy 138.843547 -58.072274)
			(xy 138.836491 -58.097221) (xy 138.815354 -58.14542) (xy 138.787804 -58.190263) (xy 138.754361 -58.230902)
			(xy 138.735308 -58.249058) (xy 138.727924 -58.256594) (xy 138.719389 -58.275863) (xy 138.718798 -58.286396)
			(xy 138.718798 -58.361072) (xy 138.719329 -58.371621) (xy 138.727863 -58.390917) (xy 138.735308 -58.39841)
			(xy 138.754363 -58.416566) (xy 138.78782 -58.457196) (xy 138.815379 -58.502036) (xy 138.836517 -58.550237)
			(xy 138.839623 -58.561224) (xy 148.662388 -58.561224) (xy 148.666459 -58.505602) (xy 148.678585 -58.451165)
			(xy 148.698508 -58.399074) (xy 148.725804 -58.350439) (xy 148.75989 -58.306296) (xy 148.800039 -58.267587)
			(xy 148.845397 -58.235136) (xy 148.894997 -58.209635) (xy 148.947781 -58.191628) (xy 149.002624 -58.181498)
			(xy 149.058358 -58.179461) (xy 149.113795 -58.185561) (xy 149.167752 -58.199667) (xy 149.219081 -58.221479)
			(xy 149.266687 -58.250533) (xy 149.309555 -58.286208) (xy 149.346772 -58.327745) (xy 149.377545 -58.374258)
			(xy 149.401217 -58.424755) (xy 149.417285 -58.478162) (xy 149.425405 -58.533338) (xy 149.425914 -58.561224)
			(xy 149.425405 -58.58911) (xy 149.417285 -58.644286) (xy 149.401217 -58.697693) (xy 149.377545 -58.74819)
			(xy 149.346772 -58.794703) (xy 149.309555 -58.83624) (xy 149.266687 -58.871915) (xy 149.219081 -58.900969)
			(xy 149.167752 -58.922781) (xy 149.113795 -58.936887) (xy 149.058358 -58.942987) (xy 149.002624 -58.94095)
			(xy 148.947781 -58.93082) (xy 148.894997 -58.912813) (xy 148.845397 -58.887312) (xy 148.800039 -58.854861)
			(xy 148.75989 -58.816152) (xy 148.725804 -58.772009) (xy 148.698508 -58.723374) (xy 148.678585 -58.671283)
			(xy 148.666459 -58.616846) (xy 148.662388 -58.561224) (xy 138.839623 -58.561224) (xy 138.850835 -58.600884)
			(xy 138.858059 -58.653018) (xy 138.858498 -58.679334) (xy 138.858012 -58.706585) (xy 138.850256 -58.760533)
			(xy 138.834901 -58.812828) (xy 138.812259 -58.862405) (xy 138.782793 -58.908255) (xy 138.747102 -58.949446)
			(xy 138.705911 -58.985137) (xy 138.660061 -59.014603) (xy 138.610484 -59.037245) (xy 138.558189 -59.0526)
			(xy 138.504241 -59.060356) (xy 138.449739 -59.060356) (xy 138.395791 -59.0526) (xy 138.343496 -59.037245)
			(xy 138.293919 -59.014603) (xy 138.248069 -58.985137) (xy 138.206878 -58.949446) (xy 138.171187 -58.908255)
			(xy 138.141721 -58.862405) (xy 138.119079 -58.812828) (xy 138.103724 -58.760533) (xy 138.095968 -58.706585)
			(xy 138.095482 -58.679334) (xy 125.59601 -58.679334) (xy 125.593454 -58.683197) (xy 125.556237 -58.724734)
			(xy 125.513369 -58.760409) (xy 125.465763 -58.789463) (xy 125.414434 -58.811275) (xy 125.360477 -58.825381)
			(xy 125.30504 -58.831481) (xy 125.249306 -58.829444) (xy 125.194463 -58.819314) (xy 125.141679 -58.801307)
			(xy 125.092079 -58.775806) (xy 125.046721 -58.743355) (xy 125.006572 -58.704646) (xy 124.972486 -58.660503)
			(xy 124.94519 -58.611868) (xy 124.925267 -58.559777) (xy 124.913141 -58.50534) (xy 124.90907 -58.449718)
			(xy 123.408779 -58.449718) (xy 123.417337 -58.478162) (xy 123.425457 -58.533338) (xy 123.425966 -58.561224)
			(xy 123.425457 -58.58911) (xy 123.417337 -58.644286) (xy 123.401269 -58.697693) (xy 123.377597 -58.74819)
			(xy 123.346824 -58.794703) (xy 123.309607 -58.83624) (xy 123.266739 -58.871915) (xy 123.219133 -58.900969)
			(xy 123.167804 -58.922781) (xy 123.113847 -58.936887) (xy 123.05841 -58.942987) (xy 123.002676 -58.94095)
			(xy 122.947833 -58.93082) (xy 122.895049 -58.912813) (xy 122.845449 -58.887312) (xy 122.800091 -58.854861)
			(xy 122.759942 -58.816152) (xy 122.725856 -58.772009) (xy 122.69856 -58.723374) (xy 122.678637 -58.671283)
			(xy 122.666511 -58.616846) (xy 122.66244 -58.561224) (xy 110.127802 -58.561224) (xy 110.007685 -59.174634)
			(xy 121.193304 -59.174634) (xy 121.197375 -59.119012) (xy 121.209501 -59.064575) (xy 121.229424 -59.012484)
			(xy 121.25672 -58.963849) (xy 121.290806 -58.919706) (xy 121.330955 -58.880997) (xy 121.376313 -58.848546)
			(xy 121.425913 -58.823045) (xy 121.478697 -58.805038) (xy 121.53354 -58.794908) (xy 121.589274 -58.792871)
			(xy 121.644711 -58.798971) (xy 121.698668 -58.813077) (xy 121.749997 -58.834889) (xy 121.797603 -58.863943)
			(xy 121.840471 -58.899618) (xy 121.877688 -58.941155) (xy 121.908461 -58.987668) (xy 121.932133 -59.038165)
			(xy 121.948201 -59.091572) (xy 121.956321 -59.146748) (xy 121.95683 -59.174634) (xy 147.193252 -59.174634)
			(xy 147.197323 -59.119012) (xy 147.209449 -59.064575) (xy 147.229372 -59.012484) (xy 147.256668 -58.963849)
			(xy 147.290754 -58.919706) (xy 147.330903 -58.880997) (xy 147.376261 -58.848546) (xy 147.425861 -58.823045)
			(xy 147.478645 -58.805038) (xy 147.533488 -58.794908) (xy 147.589222 -58.792871) (xy 147.644659 -58.798971)
			(xy 147.698616 -58.813077) (xy 147.749945 -58.834889) (xy 147.797551 -58.863943) (xy 147.840419 -58.899618)
			(xy 147.877636 -58.941155) (xy 147.908409 -58.987668) (xy 147.932081 -59.038165) (xy 147.948149 -59.091572)
			(xy 147.956269 -59.146748) (xy 147.956778 -59.174634) (xy 147.956269 -59.20252) (xy 147.948149 -59.257696)
			(xy 147.932081 -59.311103) (xy 147.908409 -59.3616) (xy 147.877636 -59.408113) (xy 147.840419 -59.44965)
			(xy 147.797551 -59.485325) (xy 147.749945 -59.514379) (xy 147.698616 -59.536191) (xy 147.644659 -59.550297)
			(xy 147.589222 -59.556397) (xy 147.533488 -59.55436) (xy 147.478645 -59.54423) (xy 147.425861 -59.526223)
			(xy 147.376261 -59.500722) (xy 147.330903 -59.468271) (xy 147.290754 -59.429562) (xy 147.256668 -59.385419)
			(xy 147.229372 -59.336784) (xy 147.209449 -59.284693) (xy 147.197323 -59.230256) (xy 147.193252 -59.174634)
			(xy 121.95683 -59.174634) (xy 121.956321 -59.20252) (xy 121.948201 -59.257696) (xy 121.932133 -59.311103)
			(xy 121.908461 -59.3616) (xy 121.877688 -59.408113) (xy 121.840471 -59.44965) (xy 121.797603 -59.485325)
			(xy 121.749997 -59.514379) (xy 121.698668 -59.536191) (xy 121.644711 -59.550297) (xy 121.589274 -59.556397)
			(xy 121.53354 -59.55436) (xy 121.478697 -59.54423) (xy 121.425913 -59.526223) (xy 121.376313 -59.500722)
			(xy 121.330955 -59.468271) (xy 121.290806 -59.429562) (xy 121.25672 -59.385419) (xy 121.229424 -59.336784)
			(xy 121.209501 -59.284693) (xy 121.197375 -59.230256) (xy 121.193304 -59.174634) (xy 110.007685 -59.174634)
			(xy 109.842293 -60.019254) (xy 138.235861 -60.019254) (xy 138.235861 -59.964746) (xy 138.243619 -59.910792)
			(xy 138.258977 -59.858491) (xy 138.281623 -59.808909) (xy 138.311094 -59.763054) (xy 138.346792 -59.721861)
			(xy 138.38799 -59.686168) (xy 138.433848 -59.656702) (xy 138.483432 -59.634062) (xy 138.535735 -59.61871)
			(xy 138.58969 -59.610958) (xy 138.616944 -59.610498) (xy 138.644313 -59.610997) (xy 138.698491 -59.618807)
			(xy 138.750993 -59.634289) (xy 138.800741 -59.657123) (xy 138.846709 -59.68684) (xy 138.867642 -59.704478)
			(xy 138.867896 -59.704732) (xy 138.874977 -59.710327) (xy 138.891898 -59.716567) (xy 138.900916 -59.716924)
			(xy 138.967972 -59.716924) (xy 138.976987 -59.716548) (xy 138.993904 -59.710313) (xy 139.000992 -59.704732)
			(xy 139.000992 -59.704478) (xy 139.001246 -59.704478) (xy 139.022179 -59.686837) (xy 139.068147 -59.657113)
			(xy 139.117893 -59.634267) (xy 139.170395 -59.618771) (xy 139.224573 -59.610942) (xy 139.279315 -59.610942)
			(xy 139.333493 -59.618771) (xy 139.385995 -59.634267) (xy 139.435741 -59.657113) (xy 139.481709 -59.686837)
			(xy 139.502642 -59.704478) (xy 139.502896 -59.704732) (xy 139.509977 -59.710327) (xy 139.526898 -59.716567)
			(xy 139.535916 -59.716924) (xy 139.602972 -59.716924) (xy 139.611987 -59.716548) (xy 139.628904 -59.710313)
			(xy 139.635992 -59.704732) (xy 139.635992 -59.704478) (xy 139.636246 -59.704478) (xy 139.657185 -59.686847)
			(xy 139.703156 -59.657135) (xy 139.752902 -59.634298) (xy 139.805401 -59.618805) (xy 139.859575 -59.610974)
			(xy 139.886944 -59.610498) (xy 139.914194 -59.610975) (xy 139.968137 -59.618737) (xy 140.020428 -59.634096)
			(xy 140.07 -59.65674) (xy 140.115846 -59.686208) (xy 140.157031 -59.7219) (xy 140.192719 -59.763089)
			(xy 140.222181 -59.808938) (xy 140.24482 -59.858514) (xy 140.260173 -59.910806) (xy 140.267928 -59.96475)
			(xy 140.267928 -60.01925) (xy 140.260173 -60.073194) (xy 140.24482 -60.125486) (xy 140.222181 -60.175062)
			(xy 140.192719 -60.220911) (xy 140.157031 -60.2621) (xy 140.115846 -60.297792) (xy 140.07 -60.32726)
			(xy 140.020428 -60.349904) (xy 139.968137 -60.365263) (xy 139.914194 -60.373025) (xy 139.886944 -60.373514)
			(xy 139.859575 -60.373019) (xy 139.805397 -60.365207) (xy 139.752894 -60.349725) (xy 139.703147 -60.32689)
			(xy 139.657179 -60.297172) (xy 139.636246 -60.279534) (xy 139.635992 -60.27928) (xy 139.628914 -60.273682)
			(xy 139.61199 -60.267443) (xy 139.602972 -60.267088) (xy 139.535916 -60.267088) (xy 139.5269 -60.267455)
			(xy 139.509983 -60.273696) (xy 139.502896 -60.27928) (xy 139.502642 -60.279534) (xy 139.481709 -60.297175)
			(xy 139.435741 -60.326899) (xy 139.385995 -60.349745) (xy 139.333493 -60.365241) (xy 139.279315 -60.37307)
			(xy 139.224573 -60.37307) (xy 139.170395 -60.365241) (xy 139.117893 -60.349745) (xy 139.068147 -60.326899)
			(xy 139.022179 -60.297175) (xy 139.001246 -60.279534) (xy 139.000992 -60.27928) (xy 138.993914 -60.273682)
			(xy 138.97699 -60.267443) (xy 138.967972 -60.267088) (xy 138.900916 -60.267088) (xy 138.8919 -60.267455)
			(xy 138.874983 -60.273696) (xy 138.867896 -60.27928) (xy 138.867896 -60.279534) (xy 138.867642 -60.279534)
			(xy 138.846709 -60.297172) (xy 138.800736 -60.326883) (xy 138.750989 -60.349719) (xy 138.698488 -60.36521)
			(xy 138.644313 -60.373039) (xy 138.616944 -60.373514) (xy 138.58969 -60.373042) (xy 138.535735 -60.36529)
			(xy 138.483432 -60.349938) (xy 138.433847 -60.327298) (xy 138.38799 -60.297832) (xy 138.346792 -60.262139)
			(xy 138.311094 -60.220946) (xy 138.281623 -60.175091) (xy 138.258977 -60.125509) (xy 138.243619 -60.073208)
			(xy 138.235861 -60.019254) (xy 109.842293 -60.019254) (xy 109.722041 -60.633356) (xy 123.897134 -60.633356)
			(xy 123.901205 -60.577734) (xy 123.913331 -60.523297) (xy 123.933254 -60.471206) (xy 123.96055 -60.422571)
			(xy 123.994636 -60.378428) (xy 124.034785 -60.339719) (xy 124.080143 -60.307268) (xy 124.129743 -60.281767)
			(xy 124.182527 -60.26376) (xy 124.23737 -60.25363) (xy 124.293104 -60.251593) (xy 124.348541 -60.257693)
			(xy 124.402498 -60.271799) (xy 124.453827 -60.293611) (xy 124.501433 -60.322665) (xy 124.544301 -60.35834)
			(xy 124.581518 -60.399877) (xy 124.612291 -60.44639) (xy 124.635963 -60.496887) (xy 124.652031 -60.550294)
			(xy 124.660151 -60.60547) (xy 124.66066 -60.633356) (xy 149.897082 -60.633356) (xy 149.901153 -60.577734)
			(xy 149.913279 -60.523297) (xy 149.933202 -60.471206) (xy 149.960498 -60.422571) (xy 149.994584 -60.378428)
			(xy 150.034733 -60.339719) (xy 150.080091 -60.307268) (xy 150.129691 -60.281767) (xy 150.182475 -60.26376)
			(xy 150.237318 -60.25363) (xy 150.293052 -60.251593) (xy 150.348489 -60.257693) (xy 150.402446 -60.271799)
			(xy 150.453775 -60.293611) (xy 150.501381 -60.322665) (xy 150.544249 -60.35834) (xy 150.581466 -60.399877)
			(xy 150.612239 -60.44639) (xy 150.635911 -60.496887) (xy 150.651979 -60.550294) (xy 150.660099 -60.60547)
			(xy 150.660608 -60.633356) (xy 150.660099 -60.661242) (xy 150.651979 -60.716418) (xy 150.635911 -60.769825)
			(xy 150.612239 -60.820322) (xy 150.581466 -60.866835) (xy 150.544249 -60.908372) (xy 150.501381 -60.944047)
			(xy 150.453775 -60.973101) (xy 150.402446 -60.994913) (xy 150.348489 -61.009019) (xy 150.293052 -61.015119)
			(xy 150.237318 -61.013082) (xy 150.182475 -61.002952) (xy 150.129691 -60.984945) (xy 150.080091 -60.959444)
			(xy 150.034733 -60.926993) (xy 149.994584 -60.888284) (xy 149.960498 -60.844141) (xy 149.933202 -60.795506)
			(xy 149.913279 -60.743415) (xy 149.901153 -60.688978) (xy 149.897082 -60.633356) (xy 124.66066 -60.633356)
			(xy 124.660151 -60.661242) (xy 124.652031 -60.716418) (xy 124.635963 -60.769825) (xy 124.612291 -60.820322)
			(xy 124.581518 -60.866835) (xy 124.544301 -60.908372) (xy 124.501433 -60.944047) (xy 124.453827 -60.973101)
			(xy 124.402498 -60.994913) (xy 124.348541 -61.009019) (xy 124.293104 -61.015119) (xy 124.23737 -61.013082)
			(xy 124.182527 -61.002952) (xy 124.129743 -60.984945) (xy 124.080143 -60.959444) (xy 124.034785 -60.926993)
			(xy 123.994636 -60.888284) (xy 123.96055 -60.844141) (xy 123.933254 -60.795506) (xy 123.913331 -60.743415)
			(xy 123.901205 -60.688978) (xy 123.897134 -60.633356) (xy 109.722041 -60.633356) (xy 109.554723 -61.487812)
			(xy 122.40463 -61.487812) (xy 122.408701 -61.43219) (xy 122.420827 -61.377753) (xy 122.44075 -61.325662)
			(xy 122.468046 -61.277027) (xy 122.502132 -61.232884) (xy 122.542281 -61.194175) (xy 122.587639 -61.161724)
			(xy 122.637239 -61.136223) (xy 122.690023 -61.118216) (xy 122.744866 -61.108086) (xy 122.8006 -61.106049)
			(xy 122.856037 -61.112149) (xy 122.909994 -61.126255) (xy 122.961323 -61.148067) (xy 123.008929 -61.177121)
			(xy 123.051797 -61.212796) (xy 123.089014 -61.254333) (xy 123.119787 -61.300846) (xy 123.143459 -61.351343)
			(xy 123.159527 -61.40475) (xy 123.167647 -61.459926) (xy 123.168156 -61.487812) (xy 148.404578 -61.487812)
			(xy 148.408649 -61.43219) (xy 148.420775 -61.377753) (xy 148.440698 -61.325662) (xy 148.467994 -61.277027)
			(xy 148.50208 -61.232884) (xy 148.542229 -61.194175) (xy 148.587587 -61.161724) (xy 148.637187 -61.136223)
			(xy 148.689971 -61.118216) (xy 148.744814 -61.108086) (xy 148.800548 -61.106049) (xy 148.855985 -61.112149)
			(xy 148.909942 -61.126255) (xy 148.961271 -61.148067) (xy 149.008877 -61.177121) (xy 149.051745 -61.212796)
			(xy 149.088962 -61.254333) (xy 149.119735 -61.300846) (xy 149.143407 -61.351343) (xy 149.159475 -61.40475)
			(xy 149.167595 -61.459926) (xy 149.168104 -61.487812) (xy 149.167595 -61.515698) (xy 149.159475 -61.570874)
			(xy 149.143407 -61.624281) (xy 149.119735 -61.674778) (xy 149.088962 -61.721291) (xy 149.051745 -61.762828)
			(xy 149.008877 -61.798503) (xy 148.961271 -61.827557) (xy 148.909942 -61.849369) (xy 148.855985 -61.863475)
			(xy 148.800548 -61.869575) (xy 148.744814 -61.867538) (xy 148.689971 -61.857408) (xy 148.637187 -61.839401)
			(xy 148.587587 -61.8139) (xy 148.542229 -61.781449) (xy 148.50208 -61.74274) (xy 148.467994 -61.698597)
			(xy 148.440698 -61.649962) (xy 148.420775 -61.597871) (xy 148.408649 -61.543434) (xy 148.404578 -61.487812)
			(xy 123.168156 -61.487812) (xy 123.167647 -61.515698) (xy 123.159527 -61.570874) (xy 123.143459 -61.624281)
			(xy 123.119787 -61.674778) (xy 123.089014 -61.721291) (xy 123.051797 -61.762828) (xy 123.008929 -61.798503)
			(xy 122.961323 -61.827557) (xy 122.909994 -61.849369) (xy 122.856037 -61.863475) (xy 122.8006 -61.869575)
			(xy 122.744866 -61.867538) (xy 122.690023 -61.857408) (xy 122.637239 -61.839401) (xy 122.587639 -61.8139)
			(xy 122.542281 -61.781449) (xy 122.502132 -61.74274) (xy 122.468046 -61.698597) (xy 122.44075 -61.649962)
			(xy 122.420827 -61.597871) (xy 122.408701 -61.543434) (xy 122.40463 -61.487812) (xy 109.554723 -61.487812)
			(xy 109.430727 -62.121034) (xy 120.342404 -62.121034) (xy 120.346475 -62.065412) (xy 120.358601 -62.010975)
			(xy 120.378524 -61.958884) (xy 120.40582 -61.910249) (xy 120.439906 -61.866106) (xy 120.480055 -61.827397)
			(xy 120.525413 -61.794946) (xy 120.575013 -61.769445) (xy 120.627797 -61.751438) (xy 120.68264 -61.741308)
			(xy 120.738374 -61.739271) (xy 120.793811 -61.745371) (xy 120.847768 -61.759477) (xy 120.899097 -61.781289)
			(xy 120.946703 -61.810343) (xy 120.989571 -61.846018) (xy 121.026788 -61.887555) (xy 121.057561 -61.934068)
			(xy 121.081233 -61.984565) (xy 121.097301 -62.037972) (xy 121.105421 -62.093148) (xy 121.10593 -62.121034)
			(xy 121.105421 -62.14892) (xy 121.097301 -62.204096) (xy 121.081233 -62.257503) (xy 121.057561 -62.308)
			(xy 121.026788 -62.354513) (xy 120.989571 -62.39605) (xy 120.946703 -62.431725) (xy 120.899097 -62.460779)
			(xy 120.847768 -62.482591) (xy 120.793811 -62.496697) (xy 120.738374 -62.502797) (xy 120.68264 -62.50076)
			(xy 120.627797 -62.49063) (xy 120.575013 -62.472623) (xy 120.525413 -62.447122) (xy 120.480055 -62.414671)
			(xy 120.439906 -62.375962) (xy 120.40582 -62.331819) (xy 120.378524 -62.283184) (xy 120.358601 -62.231093)
			(xy 120.346475 -62.176656) (xy 120.342404 -62.121034) (xy 109.430727 -62.121034) (xy 109.241724 -63.086234)
			(xy 117.487698 -63.086234) (xy 117.491769 -63.030612) (xy 117.503895 -62.976175) (xy 117.523818 -62.924084)
			(xy 117.551114 -62.875449) (xy 117.5852 -62.831306) (xy 117.625349 -62.792597) (xy 117.670707 -62.760146)
			(xy 117.720307 -62.734645) (xy 117.773091 -62.716638) (xy 117.827934 -62.706508) (xy 117.883668 -62.704471)
			(xy 117.939105 -62.710571) (xy 117.993062 -62.724677) (xy 118.013208 -62.733238) (xy 123.76625 -62.733238)
			(xy 123.766253 -62.67873) (xy 123.774012 -62.624778) (xy 123.789371 -62.57248) (xy 123.812017 -62.522899)
			(xy 123.841488 -62.477047) (xy 123.877185 -62.435855) (xy 123.91838 -62.400162) (xy 123.964236 -62.370696)
			(xy 124.013819 -62.348056) (xy 124.066119 -62.332703) (xy 124.120072 -62.32495) (xy 124.147326 -62.324488)
			(xy 124.170881 -62.324863) (xy 124.217625 -62.330724) (xy 124.240544 -62.336172) (xy 124.2543 -62.339208)
			(xy 124.28245 -62.338353) (xy 124.309298 -62.329846) (xy 124.332804 -62.314336) (xy 124.351185 -62.292998)
			(xy 124.363044 -62.267454) (xy 124.367481 -62.239643) (xy 124.364159 -62.211677) (xy 124.359162 -62.198504)
			(xy 124.349851 -62.175114) (xy 124.336726 -62.126514) (xy 124.330103 -62.076609) (xy 124.329698 -62.051438)
			(xy 124.330114 -62.024182) (xy 124.337867 -61.970224) (xy 124.35322 -61.917918) (xy 124.37586 -61.86833)
			(xy 124.405328 -61.822469) (xy 124.441022 -61.781268) (xy 124.482217 -61.745567) (xy 124.528073 -61.716092)
			(xy 124.577657 -61.693443) (xy 124.62996 -61.678081) (xy 124.683917 -61.670319) (xy 124.738429 -61.670315)
			(xy 124.792387 -61.678069) (xy 124.844692 -61.693424) (xy 124.894279 -61.716066) (xy 124.94014 -61.745534)
			(xy 124.981339 -61.78123) (xy 125.017039 -61.822425) (xy 125.046513 -61.868282) (xy 125.069161 -61.917867)
			(xy 125.084521 -61.97017) (xy 125.092282 -62.024127) (xy 125.092284 -62.078639) (xy 125.086191 -62.121034)
			(xy 146.342352 -62.121034) (xy 146.346423 -62.065412) (xy 146.358549 -62.010975) (xy 146.378472 -61.958884)
			(xy 146.405768 -61.910249) (xy 146.439854 -61.866106) (xy 146.480003 -61.827397) (xy 146.525361 -61.794946)
			(xy 146.574961 -61.769445) (xy 146.627745 -61.751438) (xy 146.682588 -61.741308) (xy 146.738322 -61.739271)
			(xy 146.793759 -61.745371) (xy 146.847716 -61.759477) (xy 146.899045 -61.781289) (xy 146.946651 -61.810343)
			(xy 146.989519 -61.846018) (xy 147.026736 -61.887555) (xy 147.057509 -61.934068) (xy 147.081181 -61.984565)
			(xy 147.097249 -62.037972) (xy 147.105369 -62.093148) (xy 147.105878 -62.121034) (xy 147.105369 -62.14892)
			(xy 147.097249 -62.204096) (xy 147.081181 -62.257503) (xy 147.057509 -62.308) (xy 147.026736 -62.354513)
			(xy 146.989519 -62.39605) (xy 146.946651 -62.431725) (xy 146.899045 -62.460779) (xy 146.847716 -62.482591)
			(xy 146.793759 -62.496697) (xy 146.738322 -62.502797) (xy 146.682588 -62.50076) (xy 146.627745 -62.49063)
			(xy 146.574961 -62.472623) (xy 146.525361 -62.447122) (xy 146.480003 -62.414671) (xy 146.439854 -62.375962)
			(xy 146.405768 -62.331819) (xy 146.378472 -62.283184) (xy 146.358549 -62.231093) (xy 146.346423 -62.176656)
			(xy 146.342352 -62.121034) (xy 125.086191 -62.121034) (xy 125.084529 -62.132597) (xy 125.069173 -62.184902)
			(xy 125.046529 -62.234489) (xy 125.017059 -62.280348) (xy 124.981363 -62.321547) (xy 124.940166 -62.357246)
			(xy 124.894308 -62.386718) (xy 124.844723 -62.409365) (xy 124.792419 -62.424724) (xy 124.738462 -62.432483)
			(xy 124.711206 -62.432946) (xy 124.687652 -62.432564) (xy 124.640907 -62.426708) (xy 124.617988 -62.421262)
			(xy 124.604232 -62.418212) (xy 124.576076 -62.41906) (xy 124.549222 -62.427563) (xy 124.525709 -62.443075)
			(xy 124.507325 -62.464417) (xy 124.495467 -62.489968) (xy 124.491035 -62.517786) (xy 124.494367 -62.545757)
			(xy 124.49937 -62.55893) (xy 124.508692 -62.582315) (xy 124.521813 -62.630918) (xy 124.528158 -62.678767)
			(xy 149.766272 -62.678767) (xy 149.774026 -62.624819) (xy 149.789379 -62.572524) (xy 149.812017 -62.522946)
			(xy 149.841481 -62.477094) (xy 149.87717 -62.435901) (xy 149.918358 -62.400207) (xy 149.964206 -62.370738)
			(xy 150.013782 -62.348094) (xy 150.066076 -62.332736) (xy 150.120023 -62.324976) (xy 150.147274 -62.324488)
			(xy 150.170828 -62.324873) (xy 150.217573 -62.330727) (xy 150.240492 -62.336172) (xy 150.254259 -62.339155)
			(xy 150.282405 -62.338311) (xy 150.309251 -62.329815) (xy 150.332757 -62.314312) (xy 150.351138 -62.292981)
			(xy 150.362997 -62.267442) (xy 150.367433 -62.239635) (xy 150.364108 -62.211674) (xy 150.35911 -62.198504)
			(xy 150.349797 -62.175115) (xy 150.336673 -62.126514) (xy 150.330051 -62.076609) (xy 150.329646 -62.051438)
			(xy 150.330114 -62.024181) (xy 150.337867 -61.970221) (xy 150.353221 -61.917915) (xy 150.375863 -61.868325)
			(xy 150.405332 -61.822463) (xy 150.441028 -61.781262) (xy 150.482225 -61.745561) (xy 150.528083 -61.716086)
			(xy 150.57767 -61.693438) (xy 150.629975 -61.678078) (xy 150.683933 -61.670318) (xy 150.738447 -61.670316)
			(xy 150.792406 -61.678073) (xy 150.844712 -61.693431) (xy 150.894299 -61.716077) (xy 150.940159 -61.745549)
			(xy 150.981358 -61.781248) (xy 151.017056 -61.822447) (xy 151.046527 -61.868308) (xy 151.069172 -61.917896)
			(xy 151.084528 -61.970202) (xy 151.092284 -62.024161) (xy 151.092282 -62.078675) (xy 151.084521 -62.132633)
			(xy 151.069159 -62.184938) (xy 151.04651 -62.234524) (xy 151.017034 -62.280382) (xy 150.981332 -62.321577)
			(xy 150.94013 -62.357273) (xy 150.894268 -62.386741) (xy 150.844678 -62.409382) (xy 150.792371 -62.424734)
			(xy 150.738411 -62.432486) (xy 150.711154 -62.432946) (xy 150.687599 -62.432573) (xy 150.640855 -62.426711)
			(xy 150.617936 -62.421262) (xy 150.60417 -62.418261) (xy 150.576018 -62.419098) (xy 150.549165 -62.427592)
			(xy 150.525652 -62.443096) (xy 150.507268 -62.464433) (xy 150.49541 -62.489979) (xy 150.490979 -62.517793)
			(xy 150.494313 -62.545759) (xy 150.499318 -62.55893) (xy 150.508643 -62.582314) (xy 150.521762 -62.630918)
			(xy 150.528379 -62.680824) (xy 150.528782 -62.705996) (xy 150.528327 -62.733247) (xy 150.520571 -62.787195)
			(xy 150.505216 -62.83949) (xy 150.482576 -62.889067) (xy 150.453111 -62.934918) (xy 150.41742 -62.976109)
			(xy 150.37623 -63.011801) (xy 150.330381 -63.041269) (xy 150.280804 -63.063911) (xy 150.22851 -63.079267)
			(xy 150.174563 -63.087025) (xy 150.12006 -63.087027) (xy 150.066112 -63.079272) (xy 150.013817 -63.063919)
			(xy 149.964239 -63.041279) (xy 149.918388 -63.011815) (xy 149.877196 -62.976125) (xy 149.841503 -62.934936)
			(xy 149.812035 -62.889087) (xy 149.789392 -62.839511) (xy 149.774034 -62.787217) (xy 149.766275 -62.73327)
			(xy 149.766272 -62.678767) (xy 124.528158 -62.678767) (xy 124.528431 -62.680824) (xy 124.528834 -62.705996)
			(xy 124.528349 -62.73325) (xy 124.520592 -62.787202) (xy 124.505236 -62.839501) (xy 124.482593 -62.889083)
			(xy 124.453124 -62.934937) (xy 124.41743 -62.976131) (xy 124.376236 -63.011826) (xy 124.330381 -63.041294)
			(xy 124.2808 -63.063937) (xy 124.2285 -63.079293) (xy 124.174548 -63.087049) (xy 124.12004 -63.087048)
			(xy 124.066088 -63.07929) (xy 124.013789 -63.063933) (xy 123.964208 -63.041288) (xy 123.918355 -63.011818)
			(xy 123.877162 -62.976123) (xy 123.841468 -62.934928) (xy 123.812001 -62.889072) (xy 123.78936 -62.83949)
			(xy 123.774005 -62.78719) (xy 123.76625 -62.733238) (xy 118.013208 -62.733238) (xy 118.044391 -62.746489)
			(xy 118.091997 -62.775543) (xy 118.134865 -62.811218) (xy 118.172082 -62.852755) (xy 118.202855 -62.899268)
			(xy 118.226527 -62.949765) (xy 118.242595 -63.003172) (xy 118.250715 -63.058348) (xy 118.251224 -63.086234)
			(xy 118.250715 -63.11412) (xy 118.242595 -63.169296) (xy 118.226527 -63.222703) (xy 118.202855 -63.2732)
			(xy 118.202702 -63.273432) (xy 119.676924 -63.273432) (xy 119.680995 -63.21781) (xy 119.693121 -63.163373)
			(xy 119.713044 -63.111282) (xy 119.74034 -63.062647) (xy 119.774426 -63.018504) (xy 119.814575 -62.979795)
			(xy 119.859933 -62.947344) (xy 119.909533 -62.921843) (xy 119.962317 -62.903836) (xy 120.01716 -62.893706)
			(xy 120.072894 -62.891669) (xy 120.128331 -62.897769) (xy 120.182288 -62.911875) (xy 120.233617 -62.933687)
			(xy 120.281223 -62.962741) (xy 120.324091 -62.998416) (xy 120.361308 -63.039953) (xy 120.392081 -63.086466)
			(xy 120.415753 -63.136963) (xy 120.431821 -63.19037) (xy 120.435232 -63.213549) (xy 138.220988 -63.213549)
			(xy 138.220988 -63.159051) (xy 138.228743 -63.105109) (xy 138.244096 -63.052819) (xy 138.266733 -63.003246)
			(xy 138.296195 -62.957399) (xy 138.331881 -62.916211) (xy 138.373065 -62.88052) (xy 138.418909 -62.851054)
			(xy 138.468479 -62.828411) (xy 138.520768 -62.813052) (xy 138.574709 -62.805291) (xy 138.601958 -62.804802)
			(xy 138.629327 -62.805292) (xy 138.683505 -62.813104) (xy 138.736008 -62.828588) (xy 138.785756 -62.851424)
			(xy 138.831723 -62.881143) (xy 138.852656 -62.898782) (xy 138.85291 -62.899036) (xy 138.859987 -62.904637)
			(xy 138.876911 -62.910874) (xy 138.88593 -62.911228) (xy 138.952986 -62.911228) (xy 138.962001 -62.910858)
			(xy 138.978918 -62.904619) (xy 138.986006 -62.899036) (xy 138.986006 -62.898782) (xy 138.98626 -62.898782)
			(xy 139.007193 -62.881141) (xy 139.053161 -62.851417) (xy 139.102907 -62.828571) (xy 139.155409 -62.813075)
			(xy 139.209587 -62.805246) (xy 139.264329 -62.805246) (xy 139.318507 -62.813075) (xy 139.371009 -62.828571)
			(xy 139.420755 -62.851417) (xy 139.466723 -62.881141) (xy 139.487656 -62.898782) (xy 139.48791 -62.899036)
			(xy 139.494987 -62.904637) (xy 139.511911 -62.910874) (xy 139.52093 -62.911228) (xy 139.587986 -62.911228)
			(xy 139.597001 -62.910858) (xy 139.613918 -62.904619) (xy 139.621006 -62.899036) (xy 139.621006 -62.898782)
			(xy 139.62126 -62.898782) (xy 139.642194 -62.881145) (xy 139.688167 -62.851434) (xy 139.737914 -62.828598)
			(xy 139.790414 -62.813106) (xy 139.844589 -62.805277) (xy 139.871958 -62.804802) (xy 139.899214 -62.805242)
			(xy 139.953171 -62.812994) (xy 140.005475 -62.828347) (xy 140.055062 -62.850988) (xy 140.100921 -62.880456)
			(xy 140.14212 -62.91615) (xy 140.177819 -62.957345) (xy 140.207292 -63.003201) (xy 140.229938 -63.052786)
			(xy 140.23976 -63.086234) (xy 143.487646 -63.086234) (xy 143.491717 -63.030612) (xy 143.503843 -62.976175)
			(xy 143.523766 -62.924084) (xy 143.551062 -62.875449) (xy 143.585148 -62.831306) (xy 143.625297 -62.792597)
			(xy 143.670655 -62.760146) (xy 143.720255 -62.734645) (xy 143.773039 -62.716638) (xy 143.827882 -62.706508)
			(xy 143.883616 -62.704471) (xy 143.939053 -62.710571) (xy 143.99301 -62.724677) (xy 144.044339 -62.746489)
			(xy 144.091945 -62.775543) (xy 144.134813 -62.811218) (xy 144.17203 -62.852755) (xy 144.202803 -62.899268)
			(xy 144.226475 -62.949765) (xy 144.242543 -63.003172) (xy 144.250663 -63.058348) (xy 144.251172 -63.086234)
			(xy 144.250663 -63.11412) (xy 144.242543 -63.169296) (xy 144.226475 -63.222703) (xy 144.202803 -63.2732)
			(xy 144.20265 -63.273432) (xy 145.676872 -63.273432) (xy 145.680943 -63.21781) (xy 145.693069 -63.163373)
			(xy 145.712992 -63.111282) (xy 145.740288 -63.062647) (xy 145.774374 -63.018504) (xy 145.814523 -62.979795)
			(xy 145.859881 -62.947344) (xy 145.909481 -62.921843) (xy 145.962265 -62.903836) (xy 146.017108 -62.893706)
			(xy 146.072842 -62.891669) (xy 146.128279 -62.897769) (xy 146.182236 -62.911875) (xy 146.233565 -62.933687)
			(xy 146.281171 -62.962741) (xy 146.324039 -62.998416) (xy 146.361256 -63.039953) (xy 146.392029 -63.086466)
			(xy 146.415701 -63.136963) (xy 146.431769 -63.19037) (xy 146.439889 -63.245546) (xy 146.440398 -63.273432)
			(xy 146.439889 -63.301318) (xy 146.431769 -63.356494) (xy 146.415701 -63.409901) (xy 146.392029 -63.460398)
			(xy 146.361256 -63.506911) (xy 146.324039 -63.548448) (xy 146.281171 -63.584123) (xy 146.233565 -63.613177)
			(xy 146.182236 -63.634989) (xy 146.128279 -63.649095) (xy 146.072842 -63.655195) (xy 146.017108 -63.653158)
			(xy 145.962265 -63.643028) (xy 145.909481 -63.625021) (xy 145.859881 -63.59952) (xy 145.814523 -63.567069)
			(xy 145.774374 -63.52836) (xy 145.740288 -63.484217) (xy 145.712992 -63.435582) (xy 145.693069 -63.383491)
			(xy 145.680943 -63.329054) (xy 145.676872 -63.273432) (xy 144.20265 -63.273432) (xy 144.17203 -63.319713)
			(xy 144.134813 -63.36125) (xy 144.091945 -63.396925) (xy 144.044339 -63.425979) (xy 143.99301 -63.447791)
			(xy 143.939053 -63.461897) (xy 143.883616 -63.467997) (xy 143.827882 -63.46596) (xy 143.773039 -63.45583)
			(xy 143.720255 -63.437823) (xy 143.670655 -63.412322) (xy 143.625297 -63.379871) (xy 143.585148 -63.341162)
			(xy 143.551062 -63.297019) (xy 143.523766 -63.248384) (xy 143.503843 -63.196293) (xy 143.491717 -63.141856)
			(xy 143.487646 -63.086234) (xy 140.23976 -63.086234) (xy 140.245297 -63.105088) (xy 140.253055 -63.159044)
			(xy 140.253055 -63.213556) (xy 140.245297 -63.267512) (xy 140.229938 -63.319814) (xy 140.207292 -63.369399)
			(xy 140.177819 -63.415255) (xy 140.14212 -63.45645) (xy 140.100921 -63.492144) (xy 140.055062 -63.521612)
			(xy 140.005475 -63.544253) (xy 139.953171 -63.559606) (xy 139.899214 -63.567358) (xy 139.871958 -63.567818)
			(xy 139.844588 -63.567338) (xy 139.790409 -63.559527) (xy 139.737905 -63.544042) (xy 139.688158 -63.521203)
			(xy 139.642191 -63.491479) (xy 139.62126 -63.473838) (xy 139.621006 -63.473584) (xy 139.613923 -63.467992)
			(xy 139.597003 -63.461749) (xy 139.587986 -63.461392) (xy 139.52093 -63.461392) (xy 139.511915 -63.461765)
			(xy 139.494998 -63.468002) (xy 139.48791 -63.473584) (xy 139.487656 -63.473838) (xy 139.466723 -63.491479)
			(xy 139.420755 -63.521203) (xy 139.371009 -63.544049) (xy 139.318507 -63.559545) (xy 139.264329 -63.567374)
			(xy 139.209587 -63.567374) (xy 139.155409 -63.559545) (xy 139.102907 -63.544049) (xy 139.053161 -63.521203)
			(xy 139.007193 -63.491479) (xy 138.98626 -63.473838) (xy 138.986006 -63.473584) (xy 138.978923 -63.467992)
			(xy 138.962003 -63.461749) (xy 138.952986 -63.461392) (xy 138.88593 -63.461392) (xy 138.876915 -63.461765)
			(xy 138.859998 -63.468002) (xy 138.85291 -63.473584) (xy 138.85291 -63.473838) (xy 138.852656 -63.473838)
			(xy 138.831719 -63.491471) (xy 138.785747 -63.521182) (xy 138.736001 -63.544019) (xy 138.683501 -63.559512)
			(xy 138.629327 -63.567343) (xy 138.601958 -63.567818) (xy 138.574709 -63.567309) (xy 138.520768 -63.559548)
			(xy 138.468479 -63.544189) (xy 138.418909 -63.521546) (xy 138.373065 -63.49208) (xy 138.331881 -63.456389)
			(xy 138.296195 -63.415201) (xy 138.266733 -63.369354) (xy 138.244096 -63.319781) (xy 138.228743 -63.267491)
			(xy 138.220988 -63.213549) (xy 120.435232 -63.213549) (xy 120.439941 -63.245546) (xy 120.44045 -63.273432)
			(xy 120.439941 -63.301318) (xy 120.431821 -63.356494) (xy 120.415753 -63.409901) (xy 120.392081 -63.460398)
			(xy 120.361308 -63.506911) (xy 120.324091 -63.548448) (xy 120.281223 -63.584123) (xy 120.233617 -63.613177)
			(xy 120.182288 -63.634989) (xy 120.128331 -63.649095) (xy 120.072894 -63.655195) (xy 120.01716 -63.653158)
			(xy 119.962317 -63.643028) (xy 119.909533 -63.625021) (xy 119.859933 -63.59952) (xy 119.814575 -63.567069)
			(xy 119.774426 -63.52836) (xy 119.74034 -63.484217) (xy 119.713044 -63.435582) (xy 119.693121 -63.383491)
			(xy 119.680995 -63.329054) (xy 119.676924 -63.273432) (xy 118.202702 -63.273432) (xy 118.172082 -63.319713)
			(xy 118.134865 -63.36125) (xy 118.091997 -63.396925) (xy 118.044391 -63.425979) (xy 117.993062 -63.447791)
			(xy 117.939105 -63.461897) (xy 117.883668 -63.467997) (xy 117.827934 -63.46596) (xy 117.773091 -63.45583)
			(xy 117.720307 -63.437823) (xy 117.670707 -63.412322) (xy 117.625349 -63.379871) (xy 117.5852 -63.341162)
			(xy 117.551114 -63.297019) (xy 117.523818 -63.248384) (xy 117.503895 -63.196293) (xy 117.491769 -63.141856)
			(xy 117.487698 -63.086234) (xy 109.241724 -63.086234) (xy 108.842678 -65.124076) (xy 122.207526 -65.124076)
			(xy 122.211597 -65.068454) (xy 122.223723 -65.014017) (xy 122.243646 -64.961926) (xy 122.270942 -64.913291)
			(xy 122.305028 -64.869148) (xy 122.345177 -64.830439) (xy 122.390535 -64.797988) (xy 122.440135 -64.772487)
			(xy 122.492919 -64.75448) (xy 122.547762 -64.74435) (xy 122.603496 -64.742313) (xy 122.658933 -64.748413)
			(xy 122.71289 -64.762519) (xy 122.764219 -64.784331) (xy 122.811825 -64.813385) (xy 122.854693 -64.84906)
			(xy 122.89191 -64.890597) (xy 122.922683 -64.93711) (xy 122.946355 -64.987607) (xy 122.962423 -65.041014)
			(xy 122.970543 -65.09619) (xy 122.97063 -65.100962) (xy 136.232644 -65.100962) (xy 136.236715 -65.04534)
			(xy 136.248841 -64.990903) (xy 136.268764 -64.938812) (xy 136.29606 -64.890177) (xy 136.330146 -64.846034)
			(xy 136.370295 -64.807325) (xy 136.415653 -64.774874) (xy 136.465253 -64.749373) (xy 136.518037 -64.731366)
			(xy 136.57288 -64.721236) (xy 136.628614 -64.719199) (xy 136.684051 -64.725299) (xy 136.738008 -64.739405)
			(xy 136.789337 -64.761217) (xy 136.836943 -64.790271) (xy 136.879811 -64.825946) (xy 136.917028 -64.867483)
			(xy 136.947801 -64.913996) (xy 136.971473 -64.964493) (xy 136.987541 -65.0179) (xy 136.995661 -65.073076)
			(xy 136.99617 -65.100962) (xy 136.995748 -65.124076) (xy 148.207474 -65.124076) (xy 148.211545 -65.068454)
			(xy 148.223671 -65.014017) (xy 148.243594 -64.961926) (xy 148.27089 -64.913291) (xy 148.304976 -64.869148)
			(xy 148.345125 -64.830439) (xy 148.390483 -64.797988) (xy 148.440083 -64.772487) (xy 148.492867 -64.75448)
			(xy 148.54771 -64.74435) (xy 148.603444 -64.742313) (xy 148.658881 -64.748413) (xy 148.712838 -64.762519)
			(xy 148.764167 -64.784331) (xy 148.811773 -64.813385) (xy 148.854641 -64.84906) (xy 148.891858 -64.890597)
			(xy 148.922631 -64.93711) (xy 148.946303 -64.987607) (xy 148.962371 -65.041014) (xy 148.970491 -65.09619)
			(xy 148.971 -65.124076) (xy 148.970491 -65.151962) (xy 148.962371 -65.207138) (xy 148.946303 -65.260545)
			(xy 148.922631 -65.311042) (xy 148.891858 -65.357555) (xy 148.854641 -65.399092) (xy 148.811773 -65.434767)
			(xy 148.764167 -65.463821) (xy 148.712838 -65.485633) (xy 148.658881 -65.499739) (xy 148.603444 -65.505839)
			(xy 148.54771 -65.503802) (xy 148.492867 -65.493672) (xy 148.440083 -65.475665) (xy 148.390483 -65.450164)
			(xy 148.345125 -65.417713) (xy 148.304976 -65.379004) (xy 148.27089 -65.334861) (xy 148.243594 -65.286226)
			(xy 148.223671 -65.234135) (xy 148.211545 -65.179698) (xy 148.207474 -65.124076) (xy 136.995748 -65.124076)
			(xy 136.995661 -65.128848) (xy 136.987541 -65.184024) (xy 136.971473 -65.237431) (xy 136.947801 -65.287928)
			(xy 136.917028 -65.334441) (xy 136.879811 -65.375978) (xy 136.836943 -65.411653) (xy 136.789337 -65.440707)
			(xy 136.738008 -65.462519) (xy 136.684051 -65.476625) (xy 136.628614 -65.482725) (xy 136.57288 -65.480688)
			(xy 136.518037 -65.470558) (xy 136.465253 -65.452551) (xy 136.415653 -65.42705) (xy 136.370295 -65.394599)
			(xy 136.330146 -65.35589) (xy 136.29606 -65.311747) (xy 136.268764 -65.263112) (xy 136.248841 -65.211021)
			(xy 136.236715 -65.156584) (xy 136.232644 -65.100962) (xy 122.97063 -65.100962) (xy 122.971052 -65.124076)
			(xy 122.970543 -65.151962) (xy 122.962423 -65.207138) (xy 122.946355 -65.260545) (xy 122.922683 -65.311042)
			(xy 122.89191 -65.357555) (xy 122.854693 -65.399092) (xy 122.811825 -65.434767) (xy 122.764219 -65.463821)
			(xy 122.71289 -65.485633) (xy 122.658933 -65.499739) (xy 122.603496 -65.505839) (xy 122.547762 -65.503802)
			(xy 122.492919 -65.493672) (xy 122.440135 -65.475665) (xy 122.390535 -65.450164) (xy 122.345177 -65.417713)
			(xy 122.305028 -65.379004) (xy 122.270942 -65.334861) (xy 122.243646 -65.286226) (xy 122.223723 -65.234135)
			(xy 122.211597 -65.179698) (xy 122.207526 -65.124076) (xy 108.842678 -65.124076) (xy 108.71903 -65.75552)
			(xy 130.446778 -65.75552) (xy 130.450849 -65.699898) (xy 130.462975 -65.645461) (xy 130.482898 -65.59337)
			(xy 130.510194 -65.544735) (xy 130.54428 -65.500592) (xy 130.584429 -65.461883) (xy 130.629787 -65.429432)
			(xy 130.679387 -65.403931) (xy 130.732171 -65.385924) (xy 130.787014 -65.375794) (xy 130.842748 -65.373757)
			(xy 130.898185 -65.379857) (xy 130.952142 -65.393963) (xy 131.003471 -65.415775) (xy 131.051077 -65.444829)
			(xy 131.093945 -65.480504) (xy 131.131162 -65.522041) (xy 131.161935 -65.568554) (xy 131.185607 -65.619051)
			(xy 131.201675 -65.672458) (xy 131.209795 -65.727634) (xy 131.210304 -65.75552) (xy 131.209795 -65.783406)
			(xy 131.201675 -65.838582) (xy 131.185607 -65.891989) (xy 131.161935 -65.942486) (xy 131.131162 -65.988999)
			(xy 131.093945 -66.030536) (xy 131.051077 -66.066211) (xy 131.003471 -66.095265) (xy 130.952142 -66.117077)
			(xy 130.898185 -66.131183) (xy 130.842748 -66.137283) (xy 130.787014 -66.135246) (xy 130.732171 -66.125116)
			(xy 130.679387 -66.107109) (xy 130.629787 -66.081608) (xy 130.584429 -66.049157) (xy 130.54428 -66.010448)
			(xy 130.510194 -65.966305) (xy 130.482898 -65.91767) (xy 130.462975 -65.865579) (xy 130.450849 -65.811142)
			(xy 130.446778 -65.75552) (xy 108.71903 -65.75552) (xy 108.450087 -67.128954) (xy 130.466775 -67.128954)
			(xy 130.466775 -67.074446) (xy 130.474533 -67.020494) (xy 130.489891 -66.968196) (xy 130.512535 -66.918615)
			(xy 130.542006 -66.872762) (xy 130.577703 -66.83157) (xy 130.618899 -66.795879) (xy 130.664755 -66.766413)
			(xy 130.714339 -66.743775) (xy 130.766639 -66.728423) (xy 130.820592 -66.720672) (xy 130.847846 -66.720212)
			(xy 130.875215 -66.720707) (xy 130.929393 -66.728517) (xy 130.981896 -66.743999) (xy 131.031643 -66.766835)
			(xy 131.077611 -66.796553) (xy 131.098544 -66.814192) (xy 131.098798 -66.814446) (xy 131.105877 -66.820043)
			(xy 131.1228 -66.826282) (xy 131.131818 -66.826638) (xy 131.198874 -66.826638) (xy 131.207889 -66.82626)
			(xy 131.224805 -66.820026) (xy 131.231894 -66.814446) (xy 131.231894 -66.814192) (xy 131.232148 -66.814192)
			(xy 131.253088 -66.796563) (xy 131.299059 -66.76685) (xy 131.348804 -66.744012) (xy 131.401303 -66.728519)
			(xy 131.455477 -66.720688) (xy 131.482846 -66.720212) (xy 131.510097 -66.720661) (xy 131.564042 -66.728423)
			(xy 131.616334 -66.743783) (xy 131.665908 -66.766428) (xy 131.711755 -66.795897) (xy 131.752942 -66.831591)
			(xy 131.78863 -66.872782) (xy 131.818094 -66.918632) (xy 131.840733 -66.968209) (xy 131.856087 -67.020503)
			(xy 131.863842 -67.074449) (xy 131.863842 -67.128951) (xy 131.856087 -67.182897) (xy 131.840733 -67.235191)
			(xy 131.818094 -67.284768) (xy 131.78863 -67.330618) (xy 131.752942 -67.371809) (xy 131.711755 -67.407503)
			(xy 131.665908 -67.436972) (xy 131.616334 -67.459617) (xy 131.564042 -67.474977) (xy 131.510097 -67.482739)
			(xy 131.482846 -67.483228) (xy 131.455476 -67.482753) (xy 131.401297 -67.47494) (xy 131.348793 -67.459454)
			(xy 131.299046 -67.436614) (xy 131.253079 -67.406889) (xy 131.232148 -67.389248) (xy 131.231894 -67.388994)
			(xy 131.224814 -67.383398) (xy 131.207892 -67.377157) (xy 131.198874 -67.376802) (xy 131.131818 -67.376802)
			(xy 131.122802 -67.377167) (xy 131.105885 -67.383409) (xy 131.098798 -67.388994) (xy 131.098798 -67.389248)
			(xy 131.098544 -67.389248) (xy 131.077599 -67.406872) (xy 131.031631 -67.436588) (xy 130.981887 -67.459427)
			(xy 130.929388 -67.474922) (xy 130.875214 -67.482753) (xy 130.847846 -67.483228) (xy 130.820592 -67.482728)
			(xy 130.766639 -67.474977) (xy 130.714339 -67.459625) (xy 130.664755 -67.436987) (xy 130.618899 -67.407521)
			(xy 130.577703 -67.37183) (xy 130.542006 -67.330638) (xy 130.512535 -67.284785) (xy 130.489891 -67.235204)
			(xy 130.474533 -67.182906) (xy 130.466775 -67.128954) (xy 108.450087 -67.128954) (xy 108.379769 -67.488054)
			(xy 134.879332 -67.488054) (xy 134.883403 -67.432432) (xy 134.895529 -67.377995) (xy 134.915452 -67.325904)
			(xy 134.942748 -67.277269) (xy 134.976834 -67.233126) (xy 135.016983 -67.194417) (xy 135.062341 -67.161966)
			(xy 135.111941 -67.136465) (xy 135.164725 -67.118458) (xy 135.219568 -67.108328) (xy 135.275302 -67.106291)
			(xy 135.330739 -67.112391) (xy 135.384696 -67.126497) (xy 135.436025 -67.148309) (xy 135.483631 -67.177363)
			(xy 135.526499 -67.213038) (xy 135.563716 -67.254575) (xy 135.594489 -67.301088) (xy 135.618161 -67.351585)
			(xy 135.634229 -67.404992) (xy 135.642349 -67.460168) (xy 135.642858 -67.488054) (xy 135.642349 -67.51594)
			(xy 135.639164 -67.537584) (xy 136.17143 -67.537584) (xy 136.175501 -67.481962) (xy 136.187627 -67.427525)
			(xy 136.20755 -67.375434) (xy 136.234846 -67.326799) (xy 136.268932 -67.282656) (xy 136.309081 -67.243947)
			(xy 136.354439 -67.211496) (xy 136.404039 -67.185995) (xy 136.456823 -67.167988) (xy 136.511666 -67.157858)
			(xy 136.5674 -67.155821) (xy 136.622837 -67.161921) (xy 136.676794 -67.176027) (xy 136.728123 -67.197839)
			(xy 136.775729 -67.226893) (xy 136.818597 -67.262568) (xy 136.855814 -67.304105) (xy 136.886587 -67.350618)
			(xy 136.910259 -67.401115) (xy 136.926327 -67.454522) (xy 136.934447 -67.509698) (xy 136.934956 -67.537584)
			(xy 136.934447 -67.56547) (xy 136.930402 -67.592956) (xy 137.445494 -67.592956) (xy 137.449565 -67.537334)
			(xy 137.461691 -67.482897) (xy 137.481614 -67.430806) (xy 137.50891 -67.382171) (xy 137.542996 -67.338028)
			(xy 137.583145 -67.299319) (xy 137.628503 -67.266868) (xy 137.678103 -67.241367) (xy 137.730887 -67.22336)
			(xy 137.78573 -67.21323) (xy 137.841464 -67.211193) (xy 137.896901 -67.217293) (xy 137.950858 -67.231399)
			(xy 138.002187 -67.253211) (xy 138.049793 -67.282265) (xy 138.092661 -67.31794) (xy 138.129878 -67.359477)
			(xy 138.160651 -67.40599) (xy 138.184323 -67.456487) (xy 138.200391 -67.509894) (xy 138.208508 -67.565052)
			(xy 140.546793 -67.565052) (xy 140.546793 -67.510548) (xy 140.55455 -67.4566) (xy 140.569907 -67.404304)
			(xy 140.59255 -67.354726) (xy 140.622018 -67.308876) (xy 140.657712 -67.267687) (xy 140.698905 -67.231996)
			(xy 140.744758 -67.202532) (xy 140.794338 -67.179894) (xy 140.846635 -67.164543) (xy 140.900584 -67.156791)
			(xy 140.927836 -67.15633) (xy 140.955207 -67.156768) (xy 141.009388 -67.164591) (xy 141.061892 -67.180087)
			(xy 141.111638 -67.202935) (xy 141.157603 -67.232666) (xy 141.178534 -67.25031) (xy 141.178788 -67.250564)
			(xy 141.185868 -67.256159) (xy 141.20279 -67.262399) (xy 141.211808 -67.262756) (xy 141.278864 -67.262756)
			(xy 141.28788 -67.262391) (xy 141.304798 -67.25615) (xy 141.311884 -67.250564) (xy 141.311884 -67.25031)
			(xy 141.312138 -67.25031) (xy 141.333084 -67.232688) (xy 141.379053 -67.202973) (xy 141.428797 -67.180134)
			(xy 141.481294 -67.164639) (xy 141.535468 -67.156806) (xy 141.562836 -67.15633) (xy 141.590088 -67.156742)
			(xy 141.644037 -67.164504) (xy 141.696333 -67.179864) (xy 141.745911 -67.202509) (xy 141.791761 -67.231979)
			(xy 141.832951 -67.267674) (xy 141.868642 -67.308868) (xy 141.898108 -67.354721) (xy 141.920749 -67.404301)
			(xy 141.936104 -67.456598) (xy 141.94386 -67.510548) (xy 141.94386 -67.565052) (xy 141.936104 -67.619002)
			(xy 141.920749 -67.671299) (xy 141.898108 -67.720879) (xy 141.868642 -67.766732) (xy 141.832951 -67.807926)
			(xy 141.791761 -67.843621) (xy 141.745911 -67.873091) (xy 141.696333 -67.895736) (xy 141.644037 -67.911096)
			(xy 141.590088 -67.918858) (xy 141.562836 -67.919346) (xy 141.535466 -67.918872) (xy 141.481287 -67.911058)
			(xy 141.428783 -67.895572) (xy 141.379036 -67.872731) (xy 141.333069 -67.843007) (xy 141.312138 -67.825366)
			(xy 141.311884 -67.825112) (xy 141.304805 -67.819514) (xy 141.287883 -67.813274) (xy 141.278864 -67.81292)
			(xy 141.211808 -67.81292) (xy 141.202791 -67.813276) (xy 141.185874 -67.819524) (xy 141.178788 -67.825112)
			(xy 141.178788 -67.825366) (xy 141.178534 -67.825366) (xy 141.157596 -67.842997) (xy 141.111625 -67.872711)
			(xy 141.061879 -67.895549) (xy 141.00938 -67.911042) (xy 140.955205 -67.918872) (xy 140.927836 -67.919346)
			(xy 140.900584 -67.918809) (xy 140.846635 -67.911057) (xy 140.794338 -67.895706) (xy 140.744758 -67.873068)
			(xy 140.698905 -67.843604) (xy 140.657712 -67.807913) (xy 140.622018 -67.766724) (xy 140.59255 -67.720874)
			(xy 140.569907 -67.671296) (xy 140.55455 -67.619) (xy 140.546793 -67.565052) (xy 138.208508 -67.565052)
			(xy 138.208511 -67.56507) (xy 138.20902 -67.592956) (xy 138.208511 -67.620842) (xy 138.200391 -67.676018)
			(xy 138.184323 -67.729425) (xy 138.160651 -67.779922) (xy 138.129878 -67.826435) (xy 138.092661 -67.867972)
			(xy 138.049793 -67.903647) (xy 138.002187 -67.932701) (xy 137.950858 -67.954513) (xy 137.896901 -67.968619)
			(xy 137.841464 -67.974719) (xy 137.78573 -67.972682) (xy 137.730887 -67.962552) (xy 137.678103 -67.944545)
			(xy 137.628503 -67.919044) (xy 137.583145 -67.886593) (xy 137.542996 -67.847884) (xy 137.50891 -67.803741)
			(xy 137.481614 -67.755106) (xy 137.461691 -67.703015) (xy 137.449565 -67.648578) (xy 137.445494 -67.592956)
			(xy 136.930402 -67.592956) (xy 136.926327 -67.620646) (xy 136.910259 -67.674053) (xy 136.886587 -67.72455)
			(xy 136.855814 -67.771063) (xy 136.818597 -67.8126) (xy 136.775729 -67.848275) (xy 136.728123 -67.877329)
			(xy 136.676794 -67.899141) (xy 136.622837 -67.913247) (xy 136.5674 -67.919347) (xy 136.511666 -67.91731)
			(xy 136.456823 -67.90718) (xy 136.404039 -67.889173) (xy 136.354439 -67.863672) (xy 136.309081 -67.831221)
			(xy 136.268932 -67.792512) (xy 136.234846 -67.748369) (xy 136.20755 -67.699734) (xy 136.187627 -67.647643)
			(xy 136.175501 -67.593206) (xy 136.17143 -67.537584) (xy 135.639164 -67.537584) (xy 135.634229 -67.571116)
			(xy 135.618161 -67.624523) (xy 135.594489 -67.67502) (xy 135.563716 -67.721533) (xy 135.526499 -67.76307)
			(xy 135.483631 -67.798745) (xy 135.436025 -67.827799) (xy 135.384696 -67.849611) (xy 135.330739 -67.863717)
			(xy 135.275302 -67.869817) (xy 135.219568 -67.86778) (xy 135.164725 -67.85765) (xy 135.111941 -67.839643)
			(xy 135.062341 -67.814142) (xy 135.016983 -67.781691) (xy 134.976834 -67.742982) (xy 134.942748 -67.698839)
			(xy 134.915452 -67.650204) (xy 134.895529 -67.598113) (xy 134.883403 -67.543676) (xy 134.879332 -67.488054)
			(xy 108.379769 -67.488054) (xy 108.164653 -68.586604) (xy 132.725414 -68.586604) (xy 132.725879 -68.559234)
			(xy 132.733697 -68.505054) (xy 132.749186 -68.452551) (xy 132.772028 -68.402804) (xy 132.801753 -68.356838)
			(xy 132.819394 -68.335906) (xy 132.819648 -68.335652) (xy 132.825225 -68.328559) (xy 132.831476 -68.311647)
			(xy 132.83184 -68.302632) (xy 132.83184 -68.235576) (xy 132.831507 -68.226556) (xy 132.825244 -68.209639)
			(xy 132.819648 -68.202556) (xy 132.819394 -68.202556) (xy 132.819394 -68.202302) (xy 132.801741 -68.181381)
			(xy 132.772032 -68.135405) (xy 132.749199 -68.085655) (xy 132.733711 -68.033152) (xy 132.725886 -67.978974)
			(xy 132.725414 -67.951604) (xy 132.725859 -67.92435) (xy 132.733616 -67.870398) (xy 132.748973 -67.818098)
			(xy 132.771616 -67.768516) (xy 132.801086 -67.722662) (xy 132.836782 -67.681469) (xy 132.877977 -67.645775)
			(xy 132.923832 -67.616308) (xy 132.973415 -67.593666) (xy 133.025715 -67.578312) (xy 133.079668 -67.570558)
			(xy 133.106922 -67.570096) (xy 133.133236 -67.57055) (xy 133.185365 -67.577788) (xy 133.236008 -67.59211)
			(xy 133.284207 -67.613245) (xy 133.32905 -67.640793) (xy 133.36969 -67.674234) (xy 133.387846 -67.693286)
			(xy 133.39535 -67.700708) (xy 133.414643 -67.709221) (xy 133.425184 -67.709796) (xy 133.49986 -67.709796)
			(xy 133.510409 -67.70926) (xy 133.529704 -67.70073) (xy 133.537198 -67.693286) (xy 133.555359 -67.674236)
			(xy 133.595988 -67.640779) (xy 133.640827 -67.613219) (xy 133.689027 -67.59208) (xy 133.739673 -67.577762)
			(xy 133.791806 -67.570535) (xy 133.818122 -67.570096) (xy 133.845493 -67.57055) (xy 133.899672 -67.578371)
			(xy 133.952175 -67.593863) (xy 134.001922 -67.616707) (xy 134.047889 -67.646434) (xy 134.06882 -67.664076)
			(xy 134.069074 -67.66433) (xy 134.076161 -67.669915) (xy 134.093078 -67.676162) (xy 134.102094 -67.676522)
			(xy 134.16915 -67.676522) (xy 134.178164 -67.676136) (xy 134.195081 -67.669908) (xy 134.20217 -67.66433)
			(xy 134.20217 -67.664076) (xy 134.202424 -67.664076) (xy 134.223371 -67.646455) (xy 134.26934 -67.616742)
			(xy 134.319084 -67.593902) (xy 134.371581 -67.578407) (xy 134.425754 -67.570573) (xy 134.453122 -67.570096)
			(xy 134.480374 -67.570557) (xy 134.534323 -67.578317) (xy 134.586618 -67.593675) (xy 134.636196 -67.616319)
			(xy 134.682046 -67.645788) (xy 134.723236 -67.681482) (xy 134.758928 -67.722675) (xy 134.788393 -67.768527)
			(xy 134.811034 -67.818106) (xy 134.826389 -67.870403) (xy 134.834145 -67.924352) (xy 134.83463 -67.951604)
			(xy 134.834183 -67.978975) (xy 134.826363 -68.033156) (xy 134.810871 -68.08566) (xy 134.788024 -68.135406)
			(xy 134.758294 -68.181372) (xy 134.74065 -68.202302) (xy 134.740396 -68.202556) (xy 134.734821 -68.209651)
			(xy 134.728568 -68.226561) (xy 134.728204 -68.235576) (xy 134.728204 -68.302632) (xy 134.728545 -68.311651)
			(xy 134.734804 -68.328567) (xy 134.740396 -68.335652) (xy 134.74065 -68.335652) (xy 134.74065 -68.335906)
			(xy 134.758298 -68.356831) (xy 134.78801 -68.402805) (xy 134.810845 -68.452554) (xy 134.826334 -68.505057)
			(xy 134.834158 -68.559234) (xy 134.83463 -68.586604) (xy 134.834126 -68.613854) (xy 134.82637 -68.6678)
			(xy 134.811015 -68.720093) (xy 134.794375 -68.75653) (xy 138.270488 -68.75653) (xy 138.270975 -68.729161)
			(xy 138.278788 -68.674982) (xy 138.294272 -68.62248) (xy 138.317109 -68.572733) (xy 138.346829 -68.526765)
			(xy 138.364468 -68.505832) (xy 138.364722 -68.505578) (xy 138.370326 -68.498504) (xy 138.376562 -68.481577)
			(xy 138.376914 -68.472558) (xy 138.376914 -68.405502) (xy 138.376553 -68.396486) (xy 138.370308 -68.379569)
			(xy 138.364722 -68.372482) (xy 138.364468 -68.372482) (xy 138.364468 -68.372228) (xy 138.346824 -68.3513)
			(xy 138.317114 -68.305326) (xy 138.294279 -68.255577) (xy 138.278789 -68.203076) (xy 138.270962 -68.148899)
			(xy 138.270488 -68.12153) (xy 138.270983 -68.094278) (xy 138.278736 -68.040328) (xy 138.294088 -67.988031)
			(xy 138.316727 -67.938452) (xy 138.346191 -67.892599) (xy 138.381882 -67.851406) (xy 138.423071 -67.815712)
			(xy 138.468922 -67.786243) (xy 138.5185 -67.7636) (xy 138.570795 -67.748243) (xy 138.624744 -67.740486)
			(xy 138.651996 -67.740022) (xy 138.679366 -67.740485) (xy 138.733546 -67.748303) (xy 138.786049 -67.763792)
			(xy 138.835796 -67.786635) (xy 138.881763 -67.81636) (xy 138.902694 -67.834002) (xy 138.902948 -67.834256)
			(xy 138.91004 -67.839834) (xy 138.926953 -67.846084) (xy 138.935968 -67.846448) (xy 139.003024 -67.846448)
			(xy 139.012043 -67.846114) (xy 139.028961 -67.839852) (xy 139.036044 -67.834256) (xy 139.036044 -67.834002)
			(xy 139.036298 -67.834002) (xy 139.05722 -67.816351) (xy 139.103196 -67.786641) (xy 139.152946 -67.763807)
			(xy 139.205449 -67.748319) (xy 139.259626 -67.740494) (xy 139.286996 -67.740022) (xy 139.31331 -67.740485)
			(xy 139.365439 -67.74772) (xy 139.416082 -67.762039) (xy 139.464281 -67.783173) (xy 139.509125 -67.81072)
			(xy 139.549764 -67.84416) (xy 139.56792 -67.863212) (xy 139.575431 -67.870626) (xy 139.594719 -67.879143)
			(xy 139.605258 -67.879722) (xy 139.679934 -67.879722) (xy 139.69048 -67.879164) (xy 139.709776 -67.870649)
			(xy 139.717272 -67.863212) (xy 139.735451 -67.844179) (xy 139.776075 -67.81072) (xy 139.82091 -67.783157)
			(xy 139.869107 -67.762015) (xy 139.91975 -67.747693) (xy 139.971881 -67.740463) (xy 139.998196 -67.740022)
			(xy 140.02545 -67.740459) (xy 140.079404 -67.748216) (xy 140.131704 -67.763573) (xy 140.181286 -67.786218)
			(xy 140.22714 -67.815688) (xy 140.268334 -67.851385) (xy 140.304028 -67.89258) (xy 140.333495 -67.938437)
			(xy 140.356136 -67.988021) (xy 140.371489 -68.040322) (xy 140.379243 -68.094276) (xy 140.379704 -68.12153)
			(xy 140.379255 -68.148901) (xy 140.371433 -68.203081) (xy 140.35594 -68.255584) (xy 140.333094 -68.30533)
			(xy 140.303367 -68.351297) (xy 140.285724 -68.372228) (xy 140.28547 -68.372482) (xy 140.279881 -68.379567)
			(xy 140.273637 -68.396485) (xy 140.273278 -68.405502) (xy 140.273278 -68.472558) (xy 140.27366 -68.481572)
			(xy 140.279891 -68.498489) (xy 140.28547 -68.505578) (xy 140.285724 -68.505578) (xy 140.285724 -68.505832)
			(xy 140.303348 -68.526776) (xy 140.333062 -68.572746) (xy 140.3559 -68.62249) (xy 140.371395 -68.674988)
			(xy 140.379227 -68.729162) (xy 140.379704 -68.75653) (xy 140.37925 -68.783782) (xy 140.371489 -68.837731)
			(xy 140.35613 -68.890027) (xy 140.333485 -68.939604) (xy 140.304016 -68.985455) (xy 140.268321 -69.026645)
			(xy 140.227128 -69.062336) (xy 140.181275 -69.091802) (xy 140.131695 -69.114442) (xy 140.079398 -69.129797)
			(xy 140.025448 -69.137553) (xy 139.998196 -69.138038) (xy 139.971881 -69.137593) (xy 139.919751 -69.130356)
			(xy 139.869107 -69.116034) (xy 139.820907 -69.094898) (xy 139.776065 -69.067347) (xy 139.735427 -69.033902)
			(xy 139.717272 -69.014848) (xy 139.709756 -69.007439) (xy 139.690472 -68.998917) (xy 139.679934 -68.998338)
			(xy 139.605258 -68.998338) (xy 139.594709 -68.998874) (xy 139.575413 -69.007403) (xy 139.56792 -69.014848)
			(xy 139.549757 -69.033896) (xy 139.509128 -69.067352) (xy 139.464289 -69.094911) (xy 139.41609 -69.11605)
			(xy 139.365444 -69.13037) (xy 139.313312 -69.137597) (xy 139.286996 -69.138038) (xy 139.259625 -69.137589)
			(xy 139.205445 -69.12977) (xy 139.152941 -69.114277) (xy 139.103194 -69.091431) (xy 139.057229 -69.061702)
			(xy 139.036298 -69.044058) (xy 139.036044 -69.043804) (xy 139.028949 -69.03823) (xy 139.012039 -69.031976)
			(xy 139.003024 -69.031612) (xy 138.935968 -69.031612) (xy 138.926949 -69.031951) (xy 138.910032 -69.038211)
			(xy 138.902948 -69.043804) (xy 138.902948 -69.044058) (xy 138.902694 -69.044058) (xy 138.88177 -69.061707)
			(xy 138.835795 -69.091419) (xy 138.786046 -69.114253) (xy 138.733543 -69.129742) (xy 138.679366 -69.137566)
			(xy 138.651996 -69.138038) (xy 138.624746 -69.137526) (xy 138.570801 -69.12977) (xy 138.518508 -69.114416)
			(xy 138.468933 -69.091776) (xy 138.423084 -69.062312) (xy 138.381895 -69.026624) (xy 138.346203 -68.985437)
			(xy 138.316736 -68.93959) (xy 138.294093 -68.890016) (xy 138.278736 -68.837725) (xy 138.270976 -68.78378)
			(xy 138.270488 -68.75653) (xy 134.794375 -68.75653) (xy 134.788375 -68.769669) (xy 134.75891 -68.815518)
			(xy 134.723221 -68.856708) (xy 134.682033 -68.8924) (xy 134.636185 -68.921866) (xy 134.58661 -68.944509)
			(xy 134.534318 -68.959866) (xy 134.480372 -68.967625) (xy 134.453122 -68.968112) (xy 134.425752 -68.96763)
			(xy 134.371574 -68.959816) (xy 134.319071 -68.94433) (xy 134.269324 -68.921492) (xy 134.223356 -68.891771)
			(xy 134.202424 -68.874132) (xy 134.20217 -68.873878) (xy 134.195069 -68.868312) (xy 134.178163 -68.862054)
			(xy 134.16915 -68.861686) (xy 134.102094 -68.861686) (xy 134.093077 -68.862043) (xy 134.07616 -68.868291)
			(xy 134.069074 -68.873878) (xy 134.069074 -68.874132) (xy 134.06882 -68.874132) (xy 134.047895 -68.89178)
			(xy 134.00192 -68.92149) (xy 133.952171 -68.944323) (xy 133.899668 -68.959812) (xy 133.845492 -68.967639)
			(xy 133.818122 -68.968112) (xy 133.791809 -68.967626) (xy 133.739681 -68.960394) (xy 133.689039 -68.946079)
			(xy 133.64084 -68.92495) (xy 133.595996 -68.897407) (xy 133.555355 -68.863972) (xy 133.537198 -68.844922)
			(xy 133.529676 -68.837521) (xy 133.510396 -68.828995) (xy 133.49986 -68.828412) (xy 133.425184 -68.828412)
			(xy 133.414631 -68.828915) (xy 133.395336 -68.837468) (xy 133.387846 -68.844922) (xy 133.369714 -68.864001)
			(xy 133.329079 -68.897455) (xy 133.284233 -68.925011) (xy 133.236028 -68.946145) (xy 133.185377 -68.960457)
			(xy 133.133239 -68.967676) (xy 133.106922 -68.968112) (xy 133.07967 -68.967624) (xy 133.02572 -68.95987)
			(xy 132.973423 -68.944517) (xy 132.923843 -68.921878) (xy 132.87799 -68.892412) (xy 132.836797 -68.856721)
			(xy 132.801103 -68.815531) (xy 132.771635 -68.76968) (xy 132.748992 -68.720102) (xy 132.733635 -68.667805)
			(xy 132.725878 -68.613856) (xy 132.725414 -68.586604) (xy 108.164653 -68.586604) (xy 108.091986 -68.957698)
			(xy 108.084413 -68.994512) (xy 108.06445 -69.066978) (xy 108.052108 -69.102478) (xy 107.17235 -71.555864)
			(xy 135.294622 -71.555864) (xy 135.298693 -71.500242) (xy 135.310819 -71.445805) (xy 135.330742 -71.393714)
			(xy 135.358038 -71.345079) (xy 135.392124 -71.300936) (xy 135.432273 -71.262227) (xy 135.477631 -71.229776)
			(xy 135.527231 -71.204275) (xy 135.580015 -71.186268) (xy 135.634858 -71.176138) (xy 135.690592 -71.174101)
			(xy 135.746029 -71.180201) (xy 135.799986 -71.194307) (xy 135.851315 -71.216119) (xy 135.898921 -71.245173)
			(xy 135.941789 -71.280848) (xy 135.979006 -71.322385) (xy 136.009779 -71.368898) (xy 136.033451 -71.419395)
			(xy 136.049519 -71.472802) (xy 136.057639 -71.527978) (xy 136.058148 -71.555864) (xy 136.057639 -71.58375)
			(xy 136.0518 -71.623428) (xy 136.803636 -71.623428) (xy 136.807707 -71.567806) (xy 136.819833 -71.513369)
			(xy 136.839756 -71.461278) (xy 136.867052 -71.412643) (xy 136.901138 -71.3685) (xy 136.941287 -71.329791)
			(xy 136.986645 -71.29734) (xy 137.036245 -71.271839) (xy 137.089029 -71.253832) (xy 137.143872 -71.243702)
			(xy 137.199606 -71.241665) (xy 137.255043 -71.247765) (xy 137.309 -71.261871) (xy 137.360329 -71.283683)
			(xy 137.407935 -71.312737) (xy 137.450803 -71.348412) (xy 137.48802 -71.389949) (xy 137.518793 -71.436462)
			(xy 137.542465 -71.486959) (xy 137.558533 -71.540366) (xy 137.566653 -71.595542) (xy 137.567162 -71.623428)
			(xy 137.566653 -71.651314) (xy 137.558533 -71.70649) (xy 137.542465 -71.759897) (xy 137.518793 -71.810394)
			(xy 137.48802 -71.856907) (xy 137.450803 -71.898444) (xy 137.407935 -71.934119) (xy 137.360329 -71.963173)
			(xy 137.309 -71.984985) (xy 137.255043 -71.999091) (xy 137.199606 -72.005191) (xy 137.143872 -72.003154)
			(xy 137.089029 -71.993024) (xy 137.036245 -71.975017) (xy 136.986645 -71.949516) (xy 136.941287 -71.917065)
			(xy 136.901138 -71.878356) (xy 136.867052 -71.834213) (xy 136.839756 -71.785578) (xy 136.819833 -71.733487)
			(xy 136.807707 -71.67905) (xy 136.803636 -71.623428) (xy 136.0518 -71.623428) (xy 136.049519 -71.638926)
			(xy 136.033451 -71.692333) (xy 136.009779 -71.74283) (xy 135.979006 -71.789343) (xy 135.941789 -71.83088)
			(xy 135.898921 -71.866555) (xy 135.851315 -71.895609) (xy 135.799986 -71.917421) (xy 135.746029 -71.931527)
			(xy 135.690592 -71.937627) (xy 135.634858 -71.93559) (xy 135.580015 -71.92546) (xy 135.527231 -71.907453)
			(xy 135.477631 -71.881952) (xy 135.432273 -71.849501) (xy 135.392124 -71.810792) (xy 135.358038 -71.766649)
			(xy 135.330742 -71.718014) (xy 135.310819 -71.665923) (xy 135.298693 -71.611486) (xy 135.294622 -71.555864)
			(xy 107.17235 -71.555864) (xy 105.63225 -75.85075) (xy 105.618623 -75.887629) (xy 105.586346 -75.959328)
			(xy 105.548532 -76.028267) (xy 105.505416 -76.09402) (xy 105.481628 -76.125324) (xy 104.519915 -77.365367)
			(xy 105.150162 -77.365367) (xy 105.150162 -77.305433) (xy 105.157985 -77.246011) (xy 105.173496 -77.188119)
			(xy 105.19643 -77.132746) (xy 105.226396 -77.08084) (xy 105.26288 -77.03329) (xy 105.305258 -76.990908)
			(xy 105.352805 -76.954419) (xy 105.404708 -76.924449) (xy 105.460079 -76.901509) (xy 105.51797 -76.885993)
			(xy 105.577391 -76.878165) (xy 105.607358 -76.877672) (xy 106.470958 -76.877672) (xy 106.500928 -76.878178)
			(xy 106.560354 -76.885997) (xy 106.618252 -76.901506) (xy 106.67363 -76.92444) (xy 106.72554 -76.954406)
			(xy 106.773095 -76.990892) (xy 106.81548 -77.033273) (xy 106.851971 -77.080825) (xy 106.881942 -77.132732)
			(xy 106.904881 -77.188108) (xy 106.920395 -77.246004) (xy 106.928219 -77.305431) (xy 106.928219 -77.365367)
			(xy 109.150162 -77.365367) (xy 109.150162 -77.305433) (xy 109.157984 -77.246012) (xy 109.173495 -77.18812)
			(xy 109.196429 -77.132748) (xy 109.226394 -77.080843) (xy 109.262878 -77.033292) (xy 109.305255 -76.990911)
			(xy 109.352801 -76.954422) (xy 109.404703 -76.924452) (xy 109.460073 -76.901511) (xy 109.517963 -76.885994)
			(xy 109.577383 -76.878165) (xy 109.60735 -76.877672) (xy 110.47095 -76.877672) (xy 110.50092 -76.878178)
			(xy 110.560347 -76.885996) (xy 110.618246 -76.901504) (xy 110.673625 -76.924437) (xy 110.725536 -76.954403)
			(xy 110.773092 -76.990889) (xy 110.815478 -77.03327) (xy 110.851969 -77.080822) (xy 110.881941 -77.13273)
			(xy 110.90488 -77.188107) (xy 110.920395 -77.246003) (xy 110.928219 -77.30543) (xy 110.928219 -77.36537)
			(xy 110.920395 -77.424797) (xy 110.90488 -77.482693) (xy 110.881941 -77.53807) (xy 110.851969 -77.589978)
			(xy 110.815478 -77.63753) (xy 110.773092 -77.679911) (xy 110.725536 -77.716397) (xy 110.673625 -77.746363)
			(xy 110.618246 -77.769296) (xy 110.560347 -77.784804) (xy 110.50092 -77.792622) (xy 110.47095 -77.793088)
			(xy 109.60735 -77.793088) (xy 109.577383 -77.792635) (xy 109.517963 -77.784806) (xy 109.460073 -77.769289)
			(xy 109.404703 -77.746348) (xy 109.352801 -77.716378) (xy 109.305255 -77.679889) (xy 109.262878 -77.637508)
			(xy 109.226394 -77.589957) (xy 109.196429 -77.538052) (xy 109.173495 -77.48268) (xy 109.157984 -77.424788)
			(xy 109.150162 -77.365367) (xy 106.928219 -77.365367) (xy 106.928219 -77.365369) (xy 106.920395 -77.424796)
			(xy 106.904881 -77.482692) (xy 106.881942 -77.538068) (xy 106.851971 -77.589975) (xy 106.81548 -77.637527)
			(xy 106.773095 -77.679908) (xy 106.72554 -77.716394) (xy 106.67363 -77.74636) (xy 106.618252 -77.769294)
			(xy 106.560354 -77.784803) (xy 106.500928 -77.792622) (xy 106.470958 -77.793088) (xy 105.607358 -77.793088)
			(xy 105.577391 -77.792635) (xy 105.51797 -77.784807) (xy 105.460079 -77.769291) (xy 105.404708 -77.746351)
			(xy 105.352805 -77.716381) (xy 105.305258 -77.679892) (xy 105.26288 -77.63751) (xy 105.226396 -77.58996)
			(xy 105.19643 -77.538054) (xy 105.173496 -77.482681) (xy 105.157985 -77.424789) (xy 105.150162 -77.365367)
			(xy 104.519915 -77.365367) (xy 104.51973 -77.365606) (xy 104.494072 -77.397991) (xy 104.43819 -77.45886)
			(xy 104.377465 -77.5149) (xy 104.312315 -77.565726) (xy 104.243185 -77.610991) (xy 104.207056 -77.631036)
			(xy 103.292186 -78.127367) (xy 107.150162 -78.127367) (xy 107.150162 -78.067433) (xy 107.157984 -78.008012)
			(xy 107.173496 -77.950119) (xy 107.19643 -77.894747) (xy 107.226395 -77.842842) (xy 107.262879 -77.795291)
			(xy 107.305256 -77.752909) (xy 107.352803 -77.716421) (xy 107.404706 -77.68645) (xy 107.460076 -77.66351)
			(xy 107.517966 -77.647993) (xy 107.577387 -77.640165) (xy 107.607354 -77.639672) (xy 108.470954 -77.639672)
			(xy 108.500924 -77.640178) (xy 108.560351 -77.647996) (xy 108.618249 -77.663505) (xy 108.673627 -77.686438)
			(xy 108.725538 -77.716405) (xy 108.773094 -77.752891) (xy 108.815479 -77.795272) (xy 108.85197 -77.842823)
			(xy 108.881941 -77.894731) (xy 108.90488 -77.950107) (xy 108.920395 -78.008004) (xy 108.928219 -78.06743)
			(xy 108.928219 -78.12737) (xy 108.920395 -78.186796) (xy 108.90488 -78.244693) (xy 108.881941 -78.300069)
			(xy 108.85197 -78.351977) (xy 108.815479 -78.399528) (xy 108.773093 -78.441909) (xy 108.725538 -78.478395)
			(xy 108.673627 -78.508362) (xy 108.618249 -78.531295) (xy 108.560351 -78.546804) (xy 108.500924 -78.554622)
			(xy 108.470954 -78.555088) (xy 107.607354 -78.555088) (xy 107.577387 -78.554635) (xy 107.517966 -78.546807)
			(xy 107.460076 -78.53129) (xy 107.404706 -78.50835) (xy 107.352803 -78.478379) (xy 107.305256 -78.441891)
			(xy 107.262879 -78.399509) (xy 107.226395 -78.351958) (xy 107.19643 -78.300053) (xy 107.173496 -78.244681)
			(xy 107.157984 -78.186788) (xy 107.150162 -78.127367) (xy 103.292186 -78.127367) (xy 99.697843 -80.077352)
			(xy 102.068087 -80.077352) (xy 102.068087 -80.022848) (xy 102.075844 -79.9689) (xy 102.0912 -79.916605)
			(xy 102.113842 -79.867027) (xy 102.14331 -79.821177) (xy 102.179003 -79.779987) (xy 102.220195 -79.744297)
			(xy 102.266047 -79.714832) (xy 102.315626 -79.692192) (xy 102.367922 -79.67684) (xy 102.42187 -79.669086)
			(xy 102.449122 -79.668624) (xy 102.476493 -79.669071) (xy 102.530673 -79.676893) (xy 102.583177 -79.692386)
			(xy 102.632923 -79.715232) (xy 102.678889 -79.744961) (xy 102.69982 -79.762604) (xy 102.700074 -79.762858)
			(xy 102.707159 -79.768447) (xy 102.724077 -79.774691) (xy 102.733094 -79.77505) (xy 102.80015 -79.77505)
			(xy 102.809166 -79.77468) (xy 102.826083 -79.768443) (xy 102.83317 -79.762858) (xy 102.83317 -79.762604)
			(xy 102.833424 -79.762604) (xy 102.854374 -79.744988) (xy 102.900342 -79.715272) (xy 102.950085 -79.692432)
			(xy 103.002582 -79.676935) (xy 103.056754 -79.669101) (xy 103.084122 -79.668624) (xy 103.111375 -79.669047)
			(xy 103.165324 -79.676807) (xy 103.217621 -79.692165) (xy 103.267199 -79.71481) (xy 103.296199 -79.733448)
			(xy 129.613694 -79.733448) (xy 129.613694 -79.678952) (xy 129.621449 -79.62501) (xy 129.636802 -79.572721)
			(xy 129.659439 -79.523148) (xy 129.6889 -79.477302) (xy 129.724586 -79.436114) (xy 129.76577 -79.400424)
			(xy 129.811613 -79.370958) (xy 129.861183 -79.348316) (xy 129.913471 -79.332958) (xy 129.967412 -79.325197)
			(xy 129.99466 -79.324708) (xy 130.020371 -79.325106) (xy 130.071326 -79.332009) (xy 130.120892 -79.345696)
			(xy 130.16817 -79.365918) (xy 130.212302 -79.392309) (xy 130.232658 -79.40802) (xy 130.243716 -79.416334)
			(xy 130.269185 -79.427123) (xy 130.296614 -79.430678) (xy 130.323992 -79.426739) (xy 130.349307 -79.415595)
			(xy 130.370701 -79.398064) (xy 130.386603 -79.375434) (xy 130.391662 -79.362554) (xy 130.402017 -79.335086)
			(xy 130.429878 -79.283422) (xy 130.465323 -79.236634) (xy 130.507515 -79.195826) (xy 130.55546 -79.161962)
			(xy 130.608025 -79.13584) (xy 130.663971 -79.118076) (xy 130.721977 -79.109091) (xy 130.751326 -79.108554)
			(xy 130.778573 -79.109118) (xy 130.832513 -79.116877) (xy 130.884799 -79.132233) (xy 130.934368 -79.154873)
			(xy 130.980211 -79.184337) (xy 131.021394 -79.220025) (xy 131.057079 -79.26121) (xy 131.08654 -79.307055)
			(xy 131.109177 -79.356625) (xy 131.124529 -79.408913) (xy 131.132284 -79.462853) (xy 131.132284 -79.517347)
			(xy 131.124529 -79.571287) (xy 131.109177 -79.623575) (xy 131.08654 -79.673145) (xy 131.057079 -79.71899)
			(xy 131.021394 -79.760175) (xy 130.980211 -79.795863) (xy 130.934368 -79.825327) (xy 130.893738 -79.843884)
			(xy 131.606034 -79.843884) (xy 131.610105 -79.788262) (xy 131.622231 -79.733825) (xy 131.642154 -79.681734)
			(xy 131.66945 -79.633099) (xy 131.703536 -79.588956) (xy 131.743685 -79.550247) (xy 131.789043 -79.517796)
			(xy 131.838643 -79.492295) (xy 131.891427 -79.474288) (xy 131.94627 -79.464158) (xy 132.002004 -79.462121)
			(xy 132.057441 -79.468221) (xy 132.111398 -79.482327) (xy 132.162727 -79.504139) (xy 132.210333 -79.533193)
			(xy 132.253201 -79.568868) (xy 132.290418 -79.610405) (xy 132.321191 -79.656918) (xy 132.344863 -79.707415)
			(xy 132.360931 -79.760822) (xy 132.369051 -79.815998) (xy 132.36956 -79.843884) (xy 132.369051 -79.87177)
			(xy 132.360931 -79.926946) (xy 132.344863 -79.980353) (xy 132.321191 -80.03085) (xy 132.290418 -80.077363)
			(xy 132.253201 -80.1189) (xy 132.210333 -80.154575) (xy 132.162727 -80.183629) (xy 132.111398 -80.205441)
			(xy 132.057441 -80.219547) (xy 132.002004 -80.225647) (xy 131.94627 -80.22361) (xy 131.891427 -80.21348)
			(xy 131.838643 -80.195473) (xy 131.789043 -80.169972) (xy 131.743685 -80.137521) (xy 131.703536 -80.098812)
			(xy 131.66945 -80.054669) (xy 131.642154 -80.006034) (xy 131.622231 -79.953943) (xy 131.610105 -79.899506)
			(xy 131.606034 -79.843884) (xy 130.893738 -79.843884) (xy 130.884799 -79.847967) (xy 130.832513 -79.863323)
			(xy 130.778573 -79.871082) (xy 130.751326 -79.87157) (xy 130.725617 -79.871129) (xy 130.674663 -79.864237)
			(xy 130.625097 -79.850561) (xy 130.577819 -79.830348) (xy 130.533685 -79.803966) (xy 130.513328 -79.788258)
			(xy 130.502192 -79.780056) (xy 130.476747 -79.769262) (xy 130.449338 -79.765695) (xy 130.421978 -79.769617)
			(xy 130.396675 -79.780741) (xy 130.375287 -79.798249) (xy 130.359385 -79.820856) (xy 130.354324 -79.833724)
			(xy 130.343969 -79.861192) (xy 130.316109 -79.912857) (xy 130.280665 -79.959647) (xy 130.238473 -80.000455)
			(xy 130.190528 -80.03432) (xy 130.137962 -80.060441) (xy 130.082016 -80.078204) (xy 130.024009 -80.087188)
			(xy 129.99466 -80.087724) (xy 129.967412 -80.087203) (xy 129.913471 -80.079442) (xy 129.861183 -80.064084)
			(xy 129.811613 -80.041442) (xy 129.76577 -80.011976) (xy 129.724586 -79.976286) (xy 129.6889 -79.935098)
			(xy 129.659439 -79.889252) (xy 129.636802 -79.839679) (xy 129.621449 -79.78739) (xy 129.613694 -79.733448)
			(xy 103.296199 -79.733448) (xy 103.313051 -79.744279) (xy 103.354242 -79.779974) (xy 103.389934 -79.821167)
			(xy 103.419401 -79.86702) (xy 103.442042 -79.9166) (xy 103.457398 -79.968897) (xy 103.465154 -80.022847)
			(xy 103.465154 -80.077353) (xy 103.457398 -80.131303) (xy 103.442042 -80.1836) (xy 103.419401 -80.23318)
			(xy 103.389934 -80.279033) (xy 103.354242 -80.320226) (xy 103.313051 -80.355921) (xy 103.267199 -80.38539)
			(xy 103.217621 -80.408035) (xy 103.165324 -80.423393) (xy 103.111375 -80.431153) (xy 103.084122 -80.43164)
			(xy 103.056752 -80.431176) (xy 103.002572 -80.42336) (xy 102.950068 -80.407871) (xy 102.900321 -80.385028)
			(xy 102.854355 -80.355302) (xy 102.833424 -80.33766) (xy 102.83317 -80.337406) (xy 102.826067 -80.331843)
			(xy 102.809163 -80.325582) (xy 102.80015 -80.325214) (xy 102.733094 -80.325214) (xy 102.724076 -80.325565)
			(xy 102.707159 -80.331816) (xy 102.700074 -80.337406) (xy 102.700074 -80.33766) (xy 102.69982 -80.33766)
			(xy 102.678886 -80.355297) (xy 102.632914 -80.38501) (xy 102.583167 -80.407847) (xy 102.530667 -80.423339)
			(xy 102.476491 -80.431167) (xy 102.449122 -80.43164) (xy 102.42187 -80.431114) (xy 102.367922 -80.42336)
			(xy 102.315626 -80.408008) (xy 102.266047 -80.385368) (xy 102.220195 -80.355903) (xy 102.179003 -80.320213)
			(xy 102.14331 -80.279023) (xy 102.113842 -80.233173) (xy 102.0912 -80.183595) (xy 102.075844 -80.1313)
			(xy 102.068087 -80.077352) (xy 99.697843 -80.077352) (xy 97.695004 -81.163922) (xy 97.69175 -81.165758)
			(xy 97.685756 -81.170219) (xy 97.683066 -81.172812) (xy 97.049526 -81.806352) (xy 108.258065 -81.806352)
			(xy 108.258065 -81.751848) (xy 108.265822 -81.697898) (xy 108.281178 -81.645601) (xy 108.30382 -81.596022)
			(xy 108.333287 -81.55017) (xy 108.36898 -81.508979) (xy 108.410172 -81.473286) (xy 108.456024 -81.443819)
			(xy 108.505603 -81.421177) (xy 108.5579 -81.405822) (xy 108.61185 -81.398065) (xy 108.639102 -81.397602)
			(xy 108.666802 -81.398114) (xy 108.721622 -81.406101) (xy 108.77471 -81.421936) (xy 108.824948 -81.445285)
			(xy 108.87128 -81.475658) (xy 108.912729 -81.512415) (xy 108.948423 -81.554782) (xy 108.977612 -81.601868)
			(xy 108.999681 -81.652682) (xy 109.007402 -81.679288) (xy 109.010196 -81.69021) (xy 109.024674 -81.707482)
			(xy 109.1057 -81.74482) (xy 109.116051 -81.748972) (xy 109.138326 -81.748843) (xy 109.148626 -81.744566)
			(xy 109.14888 -81.744566) (xy 109.174458 -81.733036) (xy 109.228148 -81.716757) (xy 109.283642 -81.708507)
			(xy 109.311694 -81.70799) (xy 109.338947 -81.708457) (xy 109.392898 -81.716213) (xy 109.445197 -81.731569)
			(xy 109.494777 -81.754211) (xy 109.540631 -81.783678) (xy 109.581824 -81.819372) (xy 109.617518 -81.860564)
			(xy 109.646987 -81.906418) (xy 109.660534 -81.936082) (xy 110.531146 -81.936082) (xy 110.535217 -81.88046)
			(xy 110.547343 -81.826023) (xy 110.567266 -81.773932) (xy 110.594562 -81.725297) (xy 110.628648 -81.681154)
			(xy 110.668797 -81.642445) (xy 110.714155 -81.609994) (xy 110.763755 -81.584493) (xy 110.816539 -81.566486)
			(xy 110.871382 -81.556356) (xy 110.927116 -81.554319) (xy 110.982553 -81.560419) (xy 111.03651 -81.574525)
			(xy 111.087839 -81.596337) (xy 111.135445 -81.625391) (xy 111.178313 -81.661066) (xy 111.21553 -81.702603)
			(xy 111.246303 -81.749116) (xy 111.269975 -81.799613) (xy 111.286043 -81.85302) (xy 111.294163 -81.908196)
			(xy 111.294672 -81.936082) (xy 111.294163 -81.963968) (xy 111.286043 -82.019144) (xy 111.269975 -82.072551)
			(xy 111.246303 -82.123048) (xy 111.21553 -82.169561) (xy 111.178313 -82.211098) (xy 111.135445 -82.246773)
			(xy 111.087839 -82.275827) (xy 111.03651 -82.297639) (xy 110.982553 -82.311745) (xy 110.927116 -82.317845)
			(xy 110.871382 -82.315808) (xy 110.816539 -82.305678) (xy 110.763755 -82.287671) (xy 110.714155 -82.26217)
			(xy 110.668797 -82.229719) (xy 110.628648 -82.19101) (xy 110.594562 -82.146867) (xy 110.567266 -82.098232)
			(xy 110.547343 -82.046141) (xy 110.535217 -81.991704) (xy 110.531146 -81.936082) (xy 109.660534 -81.936082)
			(xy 109.669629 -81.955998) (xy 109.684986 -82.008296) (xy 109.692743 -82.062247) (xy 109.692743 -82.116753)
			(xy 109.684986 -82.170704) (xy 109.669629 -82.223002) (xy 109.646987 -82.272582) (xy 109.617518 -82.318436)
			(xy 109.581824 -82.359628) (xy 109.540631 -82.395322) (xy 109.494777 -82.424789) (xy 109.445197 -82.447431)
			(xy 109.392898 -82.462787) (xy 109.338947 -82.470543) (xy 109.311694 -82.471006) (xy 109.283994 -82.470492)
			(xy 109.229174 -82.462505) (xy 109.176087 -82.446669) (xy 109.125849 -82.42332) (xy 109.079518 -82.392947)
			(xy 109.038069 -82.356191) (xy 109.002374 -82.313825) (xy 108.973185 -82.266739) (xy 108.951115 -82.215926)
			(xy 108.943394 -82.18932) (xy 108.9406 -82.178398) (xy 108.926122 -82.161126) (xy 108.845096 -82.123788)
			(xy 108.834746 -82.119633) (xy 108.81247 -82.119764) (xy 108.80217 -82.124042) (xy 108.801916 -82.124042)
			(xy 108.776339 -82.135574) (xy 108.722648 -82.151852) (xy 108.667154 -82.160101) (xy 108.639102 -82.160618)
			(xy 108.61185 -82.160135) (xy 108.5579 -82.152378) (xy 108.505603 -82.137023) (xy 108.456024 -82.114381)
			(xy 108.410172 -82.084914) (xy 108.36898 -82.049221) (xy 108.333287 -82.00803) (xy 108.30382 -81.962178)
			(xy 108.281178 -81.912599) (xy 108.265822 -81.860302) (xy 108.258065 -81.806352) (xy 97.049526 -81.806352)
			(xy 96.933512 -81.922366) (xy 96.654734 -82.201258) (xy 107.056934 -82.201258) (xy 107.061005 -82.145636)
			(xy 107.073131 -82.091199) (xy 107.093054 -82.039108) (xy 107.12035 -81.990473) (xy 107.154436 -81.94633)
			(xy 107.194585 -81.907621) (xy 107.239943 -81.87517) (xy 107.289543 -81.849669) (xy 107.342327 -81.831662)
			(xy 107.39717 -81.821532) (xy 107.452904 -81.819495) (xy 107.508341 -81.825595) (xy 107.562298 -81.839701)
			(xy 107.613627 -81.861513) (xy 107.661233 -81.890567) (xy 107.704101 -81.926242) (xy 107.741318 -81.967779)
			(xy 107.772091 -82.014292) (xy 107.795763 -82.064789) (xy 107.811831 -82.118196) (xy 107.819951 -82.173372)
			(xy 107.82046 -82.201258) (xy 107.819951 -82.229144) (xy 107.811831 -82.28432) (xy 107.795763 -82.337727)
			(xy 107.772091 -82.388224) (xy 107.741318 -82.434737) (xy 107.704101 -82.476274) (xy 107.661233 -82.511949)
			(xy 107.613627 -82.541003) (xy 107.562298 -82.562815) (xy 107.552051 -82.565494) (xy 111.707166 -82.565494)
			(xy 111.711237 -82.509872) (xy 111.723363 -82.455435) (xy 111.743286 -82.403344) (xy 111.770582 -82.354709)
			(xy 111.804668 -82.310566) (xy 111.844817 -82.271857) (xy 111.890175 -82.239406) (xy 111.939775 -82.213905)
			(xy 111.992559 -82.195898) (xy 112.047402 -82.185768) (xy 112.103136 -82.183731) (xy 112.158573 -82.189831)
			(xy 112.21253 -82.203937) (xy 112.263859 -82.225749) (xy 112.311465 -82.254803) (xy 112.354333 -82.290478)
			(xy 112.39155 -82.332015) (xy 112.422323 -82.378528) (xy 112.445995 -82.429025) (xy 112.462063 -82.482432)
			(xy 112.470183 -82.537608) (xy 112.470692 -82.565494) (xy 112.470183 -82.59338) (xy 112.462063 -82.648556)
			(xy 112.445995 -82.701963) (xy 112.422323 -82.75246) (xy 112.39155 -82.798973) (xy 112.354333 -82.84051)
			(xy 112.311465 -82.876185) (xy 112.263859 -82.905239) (xy 112.21253 -82.927051) (xy 112.158573 -82.941157)
			(xy 112.103136 -82.947257) (xy 112.047402 -82.94522) (xy 111.992559 -82.93509) (xy 111.939775 -82.917083)
			(xy 111.890175 -82.891582) (xy 111.844817 -82.859131) (xy 111.804668 -82.820422) (xy 111.770582 -82.776279)
			(xy 111.743286 -82.727644) (xy 111.723363 -82.675553) (xy 111.711237 -82.621116) (xy 111.707166 -82.565494)
			(xy 107.552051 -82.565494) (xy 107.508341 -82.576921) (xy 107.452904 -82.583021) (xy 107.39717 -82.580984)
			(xy 107.342327 -82.570854) (xy 107.289543 -82.552847) (xy 107.239943 -82.527346) (xy 107.194585 -82.494895)
			(xy 107.154436 -82.456186) (xy 107.12035 -82.412043) (xy 107.093054 -82.363408) (xy 107.073131 -82.311317)
			(xy 107.061005 -82.25688) (xy 107.056934 -82.201258) (xy 96.654734 -82.201258) (xy 96.313752 -82.54238)
			(xy 96.311974 -82.544158) (xy 96.31045 -82.54619) (xy 96.309688 -82.546952) (xy 96.30918 -82.54746)
			(xy 96.304608 -82.554318) (xy 96.281974 -82.595974) (xy 105.060748 -82.595974) (xy 105.064819 -82.540352)
			(xy 105.076945 -82.485915) (xy 105.096868 -82.433824) (xy 105.124164 -82.385189) (xy 105.15825 -82.341046)
			(xy 105.198399 -82.302337) (xy 105.243757 -82.269886) (xy 105.293357 -82.244385) (xy 105.346141 -82.226378)
			(xy 105.400984 -82.216248) (xy 105.456718 -82.214211) (xy 105.512155 -82.220311) (xy 105.566112 -82.234417)
			(xy 105.617441 -82.256229) (xy 105.665047 -82.285283) (xy 105.707915 -82.320958) (xy 105.745132 -82.362495)
			(xy 105.775905 -82.409008) (xy 105.799577 -82.459505) (xy 105.815645 -82.512912) (xy 105.823765 -82.568088)
			(xy 105.824274 -82.595974) (xy 105.823765 -82.62386) (xy 105.815645 -82.679036) (xy 105.799577 -82.732443)
			(xy 105.775905 -82.78294) (xy 105.745132 -82.829453) (xy 105.707915 -82.87099) (xy 105.665047 -82.906665)
			(xy 105.617441 -82.935719) (xy 105.566112 -82.957531) (xy 105.512155 -82.971637) (xy 105.456718 -82.977737)
			(xy 105.400984 -82.9757) (xy 105.346141 -82.96557) (xy 105.293357 -82.947563) (xy 105.243757 -82.922062)
			(xy 105.198399 -82.889611) (xy 105.15825 -82.850902) (xy 105.124164 -82.806759) (xy 105.096868 -82.758124)
			(xy 105.076945 -82.706033) (xy 105.064819 -82.651596) (xy 105.060748 -82.595974) (xy 96.281974 -82.595974)
			(xy 95.867393 -83.35899) (xy 116.623592 -83.35899) (xy 116.623592 -82.49539) (xy 116.624082 -82.465422)
			(xy 116.631905 -82.406) (xy 116.647418 -82.348107) (xy 116.670354 -82.292734) (xy 116.700321 -82.240828)
			(xy 116.736808 -82.193278) (xy 116.779188 -82.150898) (xy 116.826738 -82.114411) (xy 116.878644 -82.084444)
			(xy 116.934017 -82.061508) (xy 116.99191 -82.045995) (xy 117.051332 -82.038172) (xy 117.111268 -82.038172)
			(xy 117.17069 -82.045995) (xy 117.228583 -82.061508) (xy 117.283956 -82.084444) (xy 117.335862 -82.114411)
			(xy 117.383412 -82.150898) (xy 117.425792 -82.193278) (xy 117.462279 -82.240828) (xy 117.492246 -82.292734)
			(xy 117.515182 -82.348107) (xy 117.530695 -82.406) (xy 117.538518 -82.465422) (xy 117.539008 -82.49539)
			(xy 117.539008 -83.35899) (xy 117.538518 -83.388958) (xy 117.530695 -83.44838) (xy 117.515182 -83.506273)
			(xy 117.492246 -83.561646) (xy 117.462279 -83.613552) (xy 117.425792 -83.661102) (xy 117.383412 -83.703482)
			(xy 117.335862 -83.739969) (xy 117.283956 -83.769936) (xy 117.228583 -83.792872) (xy 117.17069 -83.808385)
			(xy 117.111268 -83.816208) (xy 117.051332 -83.816208) (xy 116.99191 -83.808385) (xy 116.934017 -83.792872)
			(xy 116.878644 -83.769936) (xy 116.826738 -83.739969) (xy 116.779188 -83.703482) (xy 116.736808 -83.661102)
			(xy 116.700321 -83.613552) (xy 116.670354 -83.561646) (xy 116.647418 -83.506273) (xy 116.631905 -83.44838)
			(xy 116.624082 -83.388958) (xy 116.623592 -83.35899) (xy 95.867393 -83.35899) (xy 95.397609 -84.223606)
			(xy 101.470204 -84.223606) (xy 101.474275 -84.167984) (xy 101.486401 -84.113547) (xy 101.506324 -84.061456)
			(xy 101.53362 -84.012821) (xy 101.567706 -83.968678) (xy 101.607855 -83.929969) (xy 101.653213 -83.897518)
			(xy 101.702813 -83.872017) (xy 101.755597 -83.85401) (xy 101.81044 -83.84388) (xy 101.866174 -83.841843)
			(xy 101.921611 -83.847943) (xy 101.975568 -83.862049) (xy 102.026897 -83.883861) (xy 102.074503 -83.912915)
			(xy 102.117371 -83.94859) (xy 102.154588 -83.990127) (xy 102.185361 -84.03664) (xy 102.209033 -84.087137)
			(xy 102.225101 -84.140544) (xy 102.233221 -84.19572) (xy 102.233233 -84.196368) (xy 103.671382 -84.196368)
			(xy 103.679136 -84.142422) (xy 103.694488 -84.090128) (xy 103.717125 -84.040551) (xy 103.746588 -83.994701)
			(xy 103.782276 -83.95351) (xy 103.823462 -83.917817) (xy 103.869309 -83.888348) (xy 103.918883 -83.865705)
			(xy 103.971175 -83.850346) (xy 104.02512 -83.842586) (xy 104.05237 -83.842098) (xy 104.081108 -83.842641)
			(xy 104.137935 -83.851259) (xy 104.192825 -83.868304) (xy 104.244537 -83.893392) (xy 104.291901 -83.925953)
			(xy 104.313228 -83.945222) (xy 104.320034 -83.951039) (xy 104.336475 -83.958086) (xy 104.354334 -83.959104)
			(xy 104.363012 -83.956906) (xy 104.460548 -83.92668) (xy 104.478836 -83.906614) (xy 104.481884 -83.893406)
			(xy 104.488623 -83.865561) (xy 104.509369 -83.812161) (xy 104.537863 -83.762461) (xy 104.573465 -83.717578)
			(xy 104.615375 -83.678519) (xy 104.662651 -83.646163) (xy 104.714232 -83.621235) (xy 104.76896 -83.604297)
			(xy 104.825604 -83.595727) (xy 104.854248 -83.59521) (xy 104.881501 -83.595633) (xy 104.935452 -83.603397)
			(xy 104.987749 -83.618759) (xy 105.037328 -83.641407) (xy 105.083179 -83.67088) (xy 105.124369 -83.706578)
			(xy 105.16006 -83.747774) (xy 105.189525 -83.79363) (xy 105.212164 -83.843213) (xy 105.227517 -83.895512)
			(xy 105.235271 -83.949465) (xy 105.235756 -83.976718) (xy 105.235297 -84.004687) (xy 105.227138 -84.060028)
			(xy 105.210982 -84.113583) (xy 105.187177 -84.164203) (xy 105.156233 -84.210804) (xy 105.118813 -84.252384)
			(xy 105.09758 -84.270596) (xy 105.089452 -84.277454) (xy 105.0798 -84.296504) (xy 105.075228 -84.381848)
			(xy 105.075269 -84.392474) (xy 105.082871 -84.412288) (xy 105.08996 -84.420202) (xy 105.110456 -84.441743)
			(xy 105.145155 -84.490025) (xy 105.17194 -84.543108) (xy 105.18348 -84.578952) (xy 112.247678 -84.578952)
			(xy 112.251749 -84.52333) (xy 112.263875 -84.468893) (xy 112.283798 -84.416802) (xy 112.311094 -84.368167)
			(xy 112.34518 -84.324024) (xy 112.385329 -84.285315) (xy 112.430687 -84.252864) (xy 112.480287 -84.227363)
			(xy 112.533071 -84.209356) (xy 112.587914 -84.199226) (xy 112.643648 -84.197189) (xy 112.699085 -84.203289)
			(xy 112.753042 -84.217395) (xy 112.804371 -84.239207) (xy 112.851977 -84.268261) (xy 112.894845 -84.303936)
			(xy 112.932062 -84.345473) (xy 112.962835 -84.391986) (xy 112.986507 -84.442483) (xy 113.002575 -84.49589)
			(xy 113.010695 -84.551066) (xy 113.011204 -84.578952) (xy 113.010695 -84.606838) (xy 113.002575 -84.662014)
			(xy 112.986507 -84.715421) (xy 112.962835 -84.765918) (xy 112.932062 -84.812431) (xy 112.894845 -84.853968)
			(xy 112.851977 -84.889643) (xy 112.804371 -84.918697) (xy 112.753042 -84.940509) (xy 112.699085 -84.954615)
			(xy 112.643648 -84.960715) (xy 112.587914 -84.958678) (xy 112.533071 -84.948548) (xy 112.480287 -84.930541)
			(xy 112.430687 -84.90504) (xy 112.385329 -84.872589) (xy 112.34518 -84.83388) (xy 112.311094 -84.789737)
			(xy 112.283798 -84.741102) (xy 112.263875 -84.689011) (xy 112.251749 -84.634574) (xy 112.247678 -84.578952)
			(xy 105.18348 -84.578952) (xy 105.190161 -84.599704) (xy 105.199378 -84.658443) (xy 105.199942 -84.688172)
			(xy 105.199456 -84.715423) (xy 105.1917 -84.769371) (xy 105.176345 -84.821666) (xy 105.153703 -84.871243)
			(xy 105.124237 -84.917093) (xy 105.088546 -84.958284) (xy 105.047355 -84.993975) (xy 105.001505 -85.023441)
			(xy 104.951928 -85.046083) (xy 104.899633 -85.061438) (xy 104.845685 -85.069194) (xy 104.791183 -85.069194)
			(xy 104.737235 -85.061438) (xy 104.68494 -85.046083) (xy 104.635363 -85.023441) (xy 104.589513 -84.993975)
			(xy 104.548322 -84.958284) (xy 104.512631 -84.917093) (xy 104.483165 -84.871243) (xy 104.460523 -84.821666)
			(xy 104.445168 -84.769371) (xy 104.437412 -84.715423) (xy 104.436926 -84.688172) (xy 104.437384 -84.660203)
			(xy 104.445544 -84.604862) (xy 104.461701 -84.551308) (xy 104.485506 -84.500687) (xy 104.51645 -84.454087)
			(xy 104.553869 -84.412507) (xy 104.575102 -84.394294) (xy 104.58323 -84.387436) (xy 104.592882 -84.368386)
			(xy 104.597454 -84.283042) (xy 104.597423 -84.272416) (xy 104.589815 -84.2526) (xy 104.582722 -84.244688)
			(xy 104.567139 -84.22845) (xy 104.539509 -84.192921) (xy 104.527604 -84.173822) (xy 104.522338 -84.165688)
			(xy 104.506932 -84.153951) (xy 104.488273 -84.148761) (xy 104.469019 -84.150857) (xy 104.451913 -84.159942)
			(xy 104.439395 -84.17472) (xy 104.433245 -84.193086) (xy 104.43337 -84.202778) (xy 104.433878 -84.223606)
			(xy 104.433416 -84.250856) (xy 104.425659 -84.304802) (xy 104.410304 -84.357095) (xy 104.387663 -84.40667)
			(xy 104.358198 -84.452519) (xy 104.322507 -84.493707) (xy 104.281319 -84.529398) (xy 104.23547 -84.558863)
			(xy 104.185895 -84.581504) (xy 104.133602 -84.596859) (xy 104.079656 -84.604616) (xy 104.025156 -84.604617)
			(xy 103.97121 -84.596861) (xy 103.918917 -84.581508) (xy 103.869341 -84.558869) (xy 103.823491 -84.529405)
			(xy 103.782301 -84.493716) (xy 103.74661 -84.452528) (xy 103.717143 -84.406681) (xy 103.6945 -84.357106)
			(xy 103.679144 -84.304814) (xy 103.671385 -84.250868) (xy 103.671382 -84.196368) (xy 102.233233 -84.196368)
			(xy 102.23373 -84.223606) (xy 102.233221 -84.251492) (xy 102.225101 -84.306668) (xy 102.209033 -84.360075)
			(xy 102.185361 -84.410572) (xy 102.154588 -84.457085) (xy 102.117371 -84.498622) (xy 102.074503 -84.534297)
			(xy 102.026897 -84.563351) (xy 101.975568 -84.585163) (xy 101.921611 -84.599269) (xy 101.866174 -84.605369)
			(xy 101.81044 -84.603332) (xy 101.755597 -84.593202) (xy 101.702813 -84.575195) (xy 101.653213 -84.549694)
			(xy 101.607855 -84.517243) (xy 101.567706 -84.478534) (xy 101.53362 -84.434391) (xy 101.506324 -84.385756)
			(xy 101.486401 -84.333665) (xy 101.474275 -84.279228) (xy 101.470204 -84.223606) (xy 95.397609 -84.223606)
			(xy 94.84557 -85.239606) (xy 101.470204 -85.239606) (xy 101.474275 -85.183984) (xy 101.486401 -85.129547)
			(xy 101.506324 -85.077456) (xy 101.53362 -85.028821) (xy 101.567706 -84.984678) (xy 101.607855 -84.945969)
			(xy 101.653213 -84.913518) (xy 101.702813 -84.888017) (xy 101.755597 -84.87001) (xy 101.81044 -84.85988)
			(xy 101.866174 -84.857843) (xy 101.921611 -84.863943) (xy 101.975568 -84.878049) (xy 102.026897 -84.899861)
			(xy 102.074503 -84.928915) (xy 102.117371 -84.96459) (xy 102.154588 -85.006127) (xy 102.185361 -85.05264)
			(xy 102.209033 -85.103137) (xy 102.225101 -85.156544) (xy 102.233221 -85.21172) (xy 102.23373 -85.239606)
			(xy 102.233221 -85.267492) (xy 102.225101 -85.322668) (xy 102.209033 -85.376075) (xy 102.185361 -85.426572)
			(xy 102.154588 -85.473085) (xy 102.117371 -85.514622) (xy 102.07975 -85.54593) (xy 103.779826 -85.54593)
			(xy 103.783897 -85.490308) (xy 103.796023 -85.435871) (xy 103.815946 -85.38378) (xy 103.843242 -85.335145)
			(xy 103.877328 -85.291002) (xy 103.917477 -85.252293) (xy 103.962835 -85.219842) (xy 104.012435 -85.194341)
			(xy 104.065219 -85.176334) (xy 104.120062 -85.166204) (xy 104.175796 -85.164167) (xy 104.231233 -85.170267)
			(xy 104.28519 -85.184373) (xy 104.336519 -85.206185) (xy 104.384125 -85.235239) (xy 104.426993 -85.270914)
			(xy 104.46421 -85.312451) (xy 104.494983 -85.358964) (xy 104.494993 -85.358986) (xy 117.385592 -85.358986)
			(xy 117.385592 -84.495386) (xy 117.386082 -84.465418) (xy 117.393905 -84.405996) (xy 117.409418 -84.348103)
			(xy 117.432354 -84.29273) (xy 117.462321 -84.240824) (xy 117.498808 -84.193274) (xy 117.541188 -84.150894)
			(xy 117.588738 -84.114407) (xy 117.640644 -84.08444) (xy 117.696017 -84.061504) (xy 117.75391 -84.045991)
			(xy 117.813332 -84.038168) (xy 117.873268 -84.038168) (xy 117.93269 -84.045991) (xy 117.990583 -84.061504)
			(xy 118.045956 -84.08444) (xy 118.097862 -84.114407) (xy 118.145412 -84.150894) (xy 118.187792 -84.193274)
			(xy 118.224279 -84.240824) (xy 118.254246 -84.29273) (xy 118.277182 -84.348103) (xy 118.292695 -84.405996)
			(xy 118.300518 -84.465418) (xy 118.301008 -84.495386) (xy 118.301008 -85.358986) (xy 118.300518 -85.388954)
			(xy 118.293361 -85.443314) (xy 146.479004 -85.443314) (xy 146.483075 -85.387692) (xy 146.495201 -85.333255)
			(xy 146.515124 -85.281164) (xy 146.54242 -85.232529) (xy 146.576506 -85.188386) (xy 146.616655 -85.149677)
			(xy 146.662013 -85.117226) (xy 146.711613 -85.091725) (xy 146.764397 -85.073718) (xy 146.81924 -85.063588)
			(xy 146.874974 -85.061551) (xy 146.930411 -85.067651) (xy 146.984368 -85.081757) (xy 147.035697 -85.103569)
			(xy 147.083303 -85.132623) (xy 147.126171 -85.168298) (xy 147.163388 -85.209835) (xy 147.194161 -85.256348)
			(xy 147.217833 -85.306845) (xy 147.233901 -85.360252) (xy 147.242021 -85.415428) (xy 147.242039 -85.41639)
			(xy 148.126448 -85.41639) (xy 148.130519 -85.360768) (xy 148.142645 -85.306331) (xy 148.162568 -85.25424)
			(xy 148.189864 -85.205605) (xy 148.22395 -85.161462) (xy 148.264099 -85.122753) (xy 148.309457 -85.090302)
			(xy 148.359057 -85.064801) (xy 148.411841 -85.046794) (xy 148.466684 -85.036664) (xy 148.522418 -85.034627)
			(xy 148.577855 -85.040727) (xy 148.631812 -85.054833) (xy 148.683141 -85.076645) (xy 148.730747 -85.105699)
			(xy 148.773615 -85.141374) (xy 148.810832 -85.182911) (xy 148.841605 -85.229424) (xy 148.865277 -85.279921)
			(xy 148.881345 -85.333328) (xy 148.889465 -85.388504) (xy 148.889974 -85.41639) (xy 148.889465 -85.444276)
			(xy 148.881345 -85.499452) (xy 148.865277 -85.552859) (xy 148.841605 -85.603356) (xy 148.810832 -85.649869)
			(xy 148.773615 -85.691406) (xy 148.730747 -85.727081) (xy 148.683141 -85.756135) (xy 148.631812 -85.777947)
			(xy 148.577855 -85.792053) (xy 148.522418 -85.798153) (xy 148.466684 -85.796116) (xy 148.411841 -85.785986)
			(xy 148.359057 -85.767979) (xy 148.309457 -85.742478) (xy 148.264099 -85.710027) (xy 148.22395 -85.671318)
			(xy 148.189864 -85.627175) (xy 148.162568 -85.57854) (xy 148.142645 -85.526449) (xy 148.130519 -85.472012)
			(xy 148.126448 -85.41639) (xy 147.242039 -85.41639) (xy 147.24253 -85.443314) (xy 147.242021 -85.4712)
			(xy 147.233901 -85.526376) (xy 147.217833 -85.579783) (xy 147.194161 -85.63028) (xy 147.163388 -85.676793)
			(xy 147.126171 -85.71833) (xy 147.083303 -85.754005) (xy 147.035697 -85.783059) (xy 146.984368 -85.804871)
			(xy 146.930411 -85.818977) (xy 146.874974 -85.825077) (xy 146.81924 -85.82304) (xy 146.764397 -85.81291)
			(xy 146.711613 -85.794903) (xy 146.662013 -85.769402) (xy 146.616655 -85.736951) (xy 146.576506 -85.698242)
			(xy 146.54242 -85.654099) (xy 146.515124 -85.605464) (xy 146.495201 -85.553373) (xy 146.483075 -85.498936)
			(xy 146.479004 -85.443314) (xy 118.293361 -85.443314) (xy 118.292695 -85.448376) (xy 118.277182 -85.506269)
			(xy 118.254246 -85.561642) (xy 118.224279 -85.613548) (xy 118.187792 -85.661098) (xy 118.145412 -85.703478)
			(xy 118.097862 -85.739965) (xy 118.045956 -85.769932) (xy 117.990583 -85.792868) (xy 117.93269 -85.808381)
			(xy 117.873268 -85.816204) (xy 117.813332 -85.816204) (xy 117.75391 -85.808381) (xy 117.696017 -85.792868)
			(xy 117.640644 -85.769932) (xy 117.588738 -85.739965) (xy 117.541188 -85.703478) (xy 117.498808 -85.661098)
			(xy 117.462321 -85.613548) (xy 117.432354 -85.561642) (xy 117.409418 -85.506269) (xy 117.393905 -85.448376)
			(xy 117.386082 -85.388954) (xy 117.385592 -85.358986) (xy 104.494993 -85.358986) (xy 104.518655 -85.409461)
			(xy 104.534723 -85.462868) (xy 104.542843 -85.518044) (xy 104.543352 -85.54593) (xy 104.542843 -85.573816)
			(xy 104.534723 -85.628992) (xy 104.518655 -85.682399) (xy 104.494983 -85.732896) (xy 104.46421 -85.779409)
			(xy 104.440067 -85.806354) (xy 112.269957 -85.806354) (xy 112.269957 -85.751846) (xy 112.277715 -85.697892)
			(xy 112.293073 -85.645592) (xy 112.315717 -85.59601) (xy 112.345188 -85.550156) (xy 112.380885 -85.508963)
			(xy 112.422082 -85.473269) (xy 112.467938 -85.443802) (xy 112.517522 -85.421162) (xy 112.569824 -85.405808)
			(xy 112.623778 -85.398055) (xy 112.651032 -85.397594) (xy 112.678396 -85.398103) (xy 112.732566 -85.405903)
			(xy 112.785065 -85.421366) (xy 112.834814 -85.444174) (xy 112.880791 -85.473861) (xy 112.922053 -85.509815)
			(xy 112.957751 -85.551297) (xy 112.97285 -85.574124) (xy 112.980505 -85.585403) (xy 113.000689 -85.603712)
			(xy 113.025001 -85.616022) (xy 113.051705 -85.621454) (xy 113.078894 -85.619621) (xy 113.104626 -85.610653)
			(xy 113.127066 -85.595191) (xy 113.136172 -85.585046) (xy 113.154392 -85.564206) (xy 113.195801 -85.527471)
			(xy 113.242087 -85.497111) (xy 113.292276 -85.473762) (xy 113.345315 -85.457917) (xy 113.400087 -85.449907)
			(xy 113.427764 -85.44941) (xy 113.45502 -85.449834) (xy 113.508977 -85.457588) (xy 113.561282 -85.472941)
			(xy 113.610869 -85.495583) (xy 113.656729 -85.525051) (xy 113.697928 -85.560747) (xy 113.733627 -85.601942)
			(xy 113.7631 -85.647799) (xy 113.785746 -85.697384) (xy 113.801105 -85.749687) (xy 113.808863 -85.803644)
			(xy 113.808863 -85.858156) (xy 113.801105 -85.912113) (xy 113.785746 -85.964416) (xy 113.7631 -86.014001)
			(xy 113.733627 -86.059858) (xy 113.697928 -86.101053) (xy 113.656729 -86.136749) (xy 113.610869 -86.166217)
			(xy 113.561282 -86.188859) (xy 113.508977 -86.204212) (xy 113.45502 -86.211966) (xy 113.427764 -86.212426)
			(xy 113.400398 -86.211957) (xy 113.346225 -86.204155) (xy 113.293723 -86.188688) (xy 113.243973 -86.165873)
			(xy 113.197996 -86.13618) (xy 113.156736 -86.100218) (xy 113.121042 -86.058727) (xy 113.105946 -86.035896)
			(xy 113.098295 -86.024613) (xy 113.078112 -86.006301) (xy 113.053799 -85.993988) (xy 113.027093 -85.988555)
			(xy 112.999902 -85.99039) (xy 112.974168 -85.999361) (xy 112.951729 -86.014827) (xy 112.942624 -86.024974)
			(xy 112.924388 -86.0458) (xy 112.882984 -86.082539) (xy 112.836703 -86.112904) (xy 112.786516 -86.136255)
			(xy 112.733479 -86.152103) (xy 112.678709 -86.160113) (xy 112.651032 -86.16061) (xy 112.623778 -86.160145)
			(xy 112.569824 -86.152392) (xy 112.517522 -86.137038) (xy 112.467938 -86.114398) (xy 112.422081 -86.084931)
			(xy 112.380885 -86.049237) (xy 112.345188 -86.008044) (xy 112.315717 -85.96219) (xy 112.293073 -85.912608)
			(xy 112.277715 -85.860308) (xy 112.269957 -85.806354) (xy 104.440067 -85.806354) (xy 104.426993 -85.820946)
			(xy 104.384125 -85.856621) (xy 104.336519 -85.885675) (xy 104.28519 -85.907487) (xy 104.231233 -85.921593)
			(xy 104.175796 -85.927693) (xy 104.120062 -85.925656) (xy 104.065219 -85.915526) (xy 104.012435 -85.897519)
			(xy 103.962835 -85.872018) (xy 103.917477 -85.839567) (xy 103.877328 -85.800858) (xy 103.843242 -85.756715)
			(xy 103.815946 -85.70808) (xy 103.796023 -85.655989) (xy 103.783897 -85.601552) (xy 103.779826 -85.54593)
			(xy 102.07975 -85.54593) (xy 102.074503 -85.550297) (xy 102.026897 -85.579351) (xy 101.975568 -85.601163)
			(xy 101.921611 -85.615269) (xy 101.866174 -85.621369) (xy 101.81044 -85.619332) (xy 101.755597 -85.609202)
			(xy 101.702813 -85.591195) (xy 101.653213 -85.565694) (xy 101.607855 -85.533243) (xy 101.567706 -85.494534)
			(xy 101.53362 -85.450391) (xy 101.506324 -85.401756) (xy 101.486401 -85.349665) (xy 101.474275 -85.295228)
			(xy 101.470204 -85.239606) (xy 94.84557 -85.239606) (xy 93.991567 -86.811358) (xy 99.84232 -86.811358)
			(xy 99.84232 -85.947758) (xy 99.84281 -85.917774) (xy 99.850638 -85.858318) (xy 99.866159 -85.800393)
			(xy 99.889108 -85.744989) (xy 99.919092 -85.693055) (xy 99.955598 -85.645479) (xy 99.998003 -85.603074)
			(xy 100.045579 -85.566568) (xy 100.097513 -85.536584) (xy 100.152917 -85.513635) (xy 100.210842 -85.498114)
			(xy 100.270298 -85.490286) (xy 100.330266 -85.490286) (xy 100.389722 -85.498114) (xy 100.447647 -85.513635)
			(xy 100.503051 -85.536584) (xy 100.554985 -85.566568) (xy 100.602561 -85.603074) (xy 100.644966 -85.645479)
			(xy 100.681472 -85.693055) (xy 100.711456 -85.744989) (xy 100.734405 -85.800393) (xy 100.749926 -85.858318)
			(xy 100.757754 -85.917774) (xy 100.758244 -85.947758) (xy 100.758244 -86.811358) (xy 100.757754 -86.841342)
			(xy 100.749926 -86.900798) (xy 100.734405 -86.958723) (xy 100.711456 -87.014127) (xy 100.681472 -87.066061)
			(xy 100.644966 -87.113637) (xy 100.602561 -87.156042) (xy 100.554985 -87.192548) (xy 100.503051 -87.222532)
			(xy 100.447647 -87.245481) (xy 100.389722 -87.261002) (xy 100.330266 -87.26883) (xy 100.270298 -87.26883)
			(xy 100.210842 -87.261002) (xy 100.152917 -87.245481) (xy 100.097513 -87.222532) (xy 100.045579 -87.192548)
			(xy 99.998003 -87.156042) (xy 99.955598 -87.113637) (xy 99.919092 -87.066061) (xy 99.889108 -87.014127)
			(xy 99.866159 -86.958723) (xy 99.850638 -86.900798) (xy 99.84281 -86.841342) (xy 99.84232 -86.811358)
			(xy 93.991567 -86.811358) (xy 93.583196 -87.562944) (xy 103.932734 -87.562944) (xy 103.936805 -87.507322)
			(xy 103.948931 -87.452885) (xy 103.968854 -87.400794) (xy 103.99615 -87.352159) (xy 104.030236 -87.308016)
			(xy 104.070385 -87.269307) (xy 104.115743 -87.236856) (xy 104.165343 -87.211355) (xy 104.218127 -87.193348)
			(xy 104.27297 -87.183218) (xy 104.328704 -87.181181) (xy 104.384141 -87.187281) (xy 104.438098 -87.201387)
			(xy 104.489427 -87.223199) (xy 104.537033 -87.252253) (xy 104.579901 -87.287928) (xy 104.617118 -87.329465)
			(xy 104.647891 -87.375978) (xy 104.649568 -87.379556) (xy 112.261902 -87.379556) (xy 112.265973 -87.323934)
			(xy 112.278099 -87.269497) (xy 112.298022 -87.217406) (xy 112.325318 -87.168771) (xy 112.359404 -87.124628)
			(xy 112.399553 -87.085919) (xy 112.444911 -87.053468) (xy 112.494511 -87.027967) (xy 112.547295 -87.00996)
			(xy 112.602138 -86.99983) (xy 112.657872 -86.997793) (xy 112.713309 -87.003893) (xy 112.767266 -87.017999)
			(xy 112.818595 -87.039811) (xy 112.866201 -87.068865) (xy 112.909069 -87.10454) (xy 112.946286 -87.146077)
			(xy 112.977059 -87.19259) (xy 113.000731 -87.243087) (xy 113.016799 -87.296494) (xy 113.024919 -87.35167)
			(xy 113.025052 -87.358982) (xy 116.623592 -87.358982) (xy 116.623592 -86.495382) (xy 116.624082 -86.465414)
			(xy 116.631905 -86.405992) (xy 116.647418 -86.348099) (xy 116.670354 -86.292726) (xy 116.700321 -86.24082)
			(xy 116.736808 -86.19327) (xy 116.779188 -86.15089) (xy 116.826738 -86.114403) (xy 116.878644 -86.084436)
			(xy 116.934017 -86.0615) (xy 116.99191 -86.045987) (xy 117.051332 -86.038164) (xy 117.111268 -86.038164)
			(xy 117.17069 -86.045987) (xy 117.228583 -86.0615) (xy 117.283956 -86.084436) (xy 117.335862 -86.114403)
			(xy 117.383412 -86.15089) (xy 117.425792 -86.19327) (xy 117.462279 -86.24082) (xy 117.492246 -86.292726)
			(xy 117.515182 -86.348099) (xy 117.530695 -86.405992) (xy 117.538518 -86.465414) (xy 117.539008 -86.495382)
			(xy 117.539008 -87.358982) (xy 117.538518 -87.38895) (xy 117.530695 -87.448372) (xy 117.515182 -87.506265)
			(xy 117.492246 -87.561638) (xy 117.462279 -87.613544) (xy 117.425792 -87.661094) (xy 117.383412 -87.703474)
			(xy 117.335862 -87.739961) (xy 117.283956 -87.769928) (xy 117.228583 -87.792864) (xy 117.17069 -87.808377)
			(xy 117.130698 -87.813642) (xy 139.708126 -87.813642) (xy 139.712197 -87.75802) (xy 139.724323 -87.703583)
			(xy 139.744246 -87.651492) (xy 139.771542 -87.602857) (xy 139.805628 -87.558714) (xy 139.845777 -87.520005)
			(xy 139.891135 -87.487554) (xy 139.940735 -87.462053) (xy 139.993519 -87.444046) (xy 140.048362 -87.433916)
			(xy 140.104096 -87.431879) (xy 140.159533 -87.437979) (xy 140.21349 -87.452085) (xy 140.264819 -87.473897)
			(xy 140.312425 -87.502951) (xy 140.355293 -87.538626) (xy 140.39251 -87.580163) (xy 140.423283 -87.626676)
			(xy 140.446955 -87.677173) (xy 140.463023 -87.73058) (xy 140.471143 -87.785756) (xy 140.471652 -87.813642)
			(xy 140.471143 -87.841528) (xy 140.463023 -87.896704) (xy 140.446955 -87.950111) (xy 140.423283 -88.000608)
			(xy 140.39251 -88.047121) (xy 140.355293 -88.088658) (xy 140.312425 -88.124333) (xy 140.264819 -88.153387)
			(xy 140.21349 -88.175199) (xy 140.159533 -88.189305) (xy 140.104096 -88.195405) (xy 140.048362 -88.193368)
			(xy 139.993519 -88.183238) (xy 139.940735 -88.165231) (xy 139.891135 -88.13973) (xy 139.845777 -88.107279)
			(xy 139.805628 -88.06857) (xy 139.771542 -88.024427) (xy 139.744246 -87.975792) (xy 139.724323 -87.923701)
			(xy 139.712197 -87.869264) (xy 139.708126 -87.813642) (xy 117.130698 -87.813642) (xy 117.111268 -87.8162)
			(xy 117.051332 -87.8162) (xy 116.99191 -87.808377) (xy 116.934017 -87.792864) (xy 116.878644 -87.769928)
			(xy 116.826738 -87.739961) (xy 116.779188 -87.703474) (xy 116.736808 -87.661094) (xy 116.700321 -87.613544)
			(xy 116.670354 -87.561638) (xy 116.647418 -87.506265) (xy 116.631905 -87.448372) (xy 116.624082 -87.38895)
			(xy 116.623592 -87.358982) (xy 113.025052 -87.358982) (xy 113.025428 -87.379556) (xy 113.024919 -87.407442)
			(xy 113.016799 -87.462618) (xy 113.000731 -87.516025) (xy 112.977059 -87.566522) (xy 112.946286 -87.613035)
			(xy 112.909069 -87.654572) (xy 112.866201 -87.690247) (xy 112.818595 -87.719301) (xy 112.767266 -87.741113)
			(xy 112.713309 -87.755219) (xy 112.657872 -87.761319) (xy 112.602138 -87.759282) (xy 112.547295 -87.749152)
			(xy 112.494511 -87.731145) (xy 112.444911 -87.705644) (xy 112.399553 -87.673193) (xy 112.359404 -87.634484)
			(xy 112.325318 -87.590341) (xy 112.298022 -87.541706) (xy 112.278099 -87.489615) (xy 112.265973 -87.435178)
			(xy 112.261902 -87.379556) (xy 104.649568 -87.379556) (xy 104.671563 -87.426475) (xy 104.687631 -87.479882)
			(xy 104.695751 -87.535058) (xy 104.69626 -87.562944) (xy 104.695751 -87.59083) (xy 104.687631 -87.646006)
			(xy 104.671563 -87.699413) (xy 104.647891 -87.74991) (xy 104.617118 -87.796423) (xy 104.579901 -87.83796)
			(xy 104.537033 -87.873635) (xy 104.489427 -87.902689) (xy 104.438098 -87.924501) (xy 104.384141 -87.938607)
			(xy 104.328704 -87.944707) (xy 104.27297 -87.94267) (xy 104.218127 -87.93254) (xy 104.165343 -87.914533)
			(xy 104.115743 -87.889032) (xy 104.070385 -87.856581) (xy 104.030236 -87.817872) (xy 103.99615 -87.773729)
			(xy 103.968854 -87.725094) (xy 103.948931 -87.673003) (xy 103.936805 -87.618566) (xy 103.932734 -87.562944)
			(xy 93.583196 -87.562944) (xy 92.263272 -89.9922) (xy 92.469968 -89.9922) (xy 92.474039 -89.936578)
			(xy 92.486165 -89.882141) (xy 92.506088 -89.83005) (xy 92.533384 -89.781415) (xy 92.56747 -89.737272)
			(xy 92.607619 -89.698563) (xy 92.652977 -89.666112) (xy 92.702577 -89.640611) (xy 92.755361 -89.622604)
			(xy 92.810204 -89.612474) (xy 92.865938 -89.610437) (xy 92.921375 -89.616537) (xy 92.975332 -89.630643)
			(xy 93.026661 -89.652455) (xy 93.074267 -89.681509) (xy 93.117135 -89.717184) (xy 93.154352 -89.758721)
			(xy 93.185125 -89.805234) (xy 93.208797 -89.855731) (xy 93.213174 -89.87028) (xy 93.9579 -89.87028)
			(xy 93.961971 -89.814658) (xy 93.974097 -89.760221) (xy 93.99402 -89.70813) (xy 94.021316 -89.659495)
			(xy 94.055402 -89.615352) (xy 94.095551 -89.576643) (xy 94.140909 -89.544192) (xy 94.190509 -89.518691)
			(xy 94.243293 -89.500684) (xy 94.298136 -89.490554) (xy 94.35387 -89.488517) (xy 94.409307 -89.494617)
			(xy 94.463264 -89.508723) (xy 94.514593 -89.530535) (xy 94.562199 -89.559589) (xy 94.605067 -89.595264)
			(xy 94.642284 -89.636801) (xy 94.673057 -89.683314) (xy 94.681164 -89.700608) (xy 101.402894 -89.700608)
			(xy 101.406965 -89.644986) (xy 101.419091 -89.590549) (xy 101.439014 -89.538458) (xy 101.46631 -89.489823)
			(xy 101.500396 -89.44568) (xy 101.540545 -89.406971) (xy 101.585903 -89.37452) (xy 101.635503 -89.349019)
			(xy 101.688287 -89.331012) (xy 101.74313 -89.320882) (xy 101.798864 -89.318845) (xy 101.854301 -89.324945)
			(xy 101.908258 -89.339051) (xy 101.955151 -89.358978) (xy 117.385592 -89.358978) (xy 117.385592 -88.495378)
			(xy 117.386082 -88.46541) (xy 117.393905 -88.405988) (xy 117.409418 -88.348095) (xy 117.432354 -88.292722)
			(xy 117.462321 -88.240816) (xy 117.498808 -88.193266) (xy 117.541188 -88.150886) (xy 117.588738 -88.114399)
			(xy 117.640644 -88.084432) (xy 117.696017 -88.061496) (xy 117.75391 -88.045983) (xy 117.813332 -88.03816)
			(xy 117.873268 -88.03816) (xy 117.93269 -88.045983) (xy 117.990583 -88.061496) (xy 118.045956 -88.084432)
			(xy 118.097862 -88.114399) (xy 118.145412 -88.150886) (xy 118.187792 -88.193266) (xy 118.224279 -88.240816)
			(xy 118.254246 -88.292722) (xy 118.277182 -88.348095) (xy 118.288606 -88.39073) (xy 119.711722 -88.39073)
			(xy 119.715793 -88.335108) (xy 119.727919 -88.280671) (xy 119.747842 -88.22858) (xy 119.775138 -88.179945)
			(xy 119.809224 -88.135802) (xy 119.849373 -88.097093) (xy 119.894731 -88.064642) (xy 119.944331 -88.039141)
			(xy 119.997115 -88.021134) (xy 120.051958 -88.011004) (xy 120.107692 -88.008967) (xy 120.163129 -88.015067)
			(xy 120.217086 -88.029173) (xy 120.268415 -88.050985) (xy 120.316021 -88.080039) (xy 120.358889 -88.115714)
			(xy 120.396106 -88.157251) (xy 120.426879 -88.203764) (xy 120.450551 -88.254261) (xy 120.466619 -88.307668)
			(xy 120.474739 -88.362844) (xy 120.475248 -88.39073) (xy 120.474739 -88.418616) (xy 120.466619 -88.473792)
			(xy 120.450551 -88.527199) (xy 120.426879 -88.577696) (xy 120.396106 -88.624209) (xy 120.363609 -88.660478)
			(xy 134.653526 -88.660478) (xy 134.657597 -88.604856) (xy 134.669723 -88.550419) (xy 134.689646 -88.498328)
			(xy 134.716942 -88.449693) (xy 134.751028 -88.40555) (xy 134.791177 -88.366841) (xy 134.836535 -88.33439)
			(xy 134.886135 -88.308889) (xy 134.938919 -88.290882) (xy 134.993762 -88.280752) (xy 135.049496 -88.278715)
			(xy 135.104933 -88.284815) (xy 135.15889 -88.298921) (xy 135.210219 -88.320733) (xy 135.257825 -88.349787)
			(xy 135.300693 -88.385462) (xy 135.33791 -88.426999) (xy 135.368683 -88.473512) (xy 135.392355 -88.524009)
			(xy 135.408423 -88.577416) (xy 135.416543 -88.632592) (xy 135.417052 -88.660478) (xy 135.416543 -88.688364)
			(xy 135.408423 -88.74354) (xy 135.392355 -88.796947) (xy 135.368683 -88.847444) (xy 135.33791 -88.893957)
			(xy 135.300693 -88.935494) (xy 135.275281 -88.956642) (xy 139.708126 -88.956642) (xy 139.712197 -88.90102)
			(xy 139.724323 -88.846583) (xy 139.744246 -88.794492) (xy 139.771542 -88.745857) (xy 139.805628 -88.701714)
			(xy 139.845777 -88.663005) (xy 139.891135 -88.630554) (xy 139.940735 -88.605053) (xy 139.993519 -88.587046)
			(xy 140.048362 -88.576916) (xy 140.104096 -88.574879) (xy 140.159533 -88.580979) (xy 140.21349 -88.595085)
			(xy 140.264819 -88.616897) (xy 140.312425 -88.645951) (xy 140.355293 -88.681626) (xy 140.39251 -88.723163)
			(xy 140.423283 -88.769676) (xy 140.446955 -88.820173) (xy 140.463023 -88.87358) (xy 140.471143 -88.928756)
			(xy 140.471652 -88.956642) (xy 140.471143 -88.984528) (xy 140.463023 -89.039704) (xy 140.446955 -89.093111)
			(xy 140.423283 -89.143608) (xy 140.39251 -89.190121) (xy 140.355293 -89.231658) (xy 140.312425 -89.267333)
			(xy 140.264819 -89.296387) (xy 140.21349 -89.318199) (xy 140.159533 -89.332305) (xy 140.104096 -89.338405)
			(xy 140.048362 -89.336368) (xy 139.993519 -89.326238) (xy 139.940735 -89.308231) (xy 139.891135 -89.28273)
			(xy 139.845777 -89.250279) (xy 139.805628 -89.21157) (xy 139.771542 -89.167427) (xy 139.744246 -89.118792)
			(xy 139.724323 -89.066701) (xy 139.712197 -89.012264) (xy 139.708126 -88.956642) (xy 135.275281 -88.956642)
			(xy 135.257825 -88.971169) (xy 135.210219 -89.000223) (xy 135.15889 -89.022035) (xy 135.104933 -89.036141)
			(xy 135.049496 -89.042241) (xy 134.993762 -89.040204) (xy 134.938919 -89.030074) (xy 134.886135 -89.012067)
			(xy 134.836535 -88.986566) (xy 134.791177 -88.954115) (xy 134.751028 -88.915406) (xy 134.716942 -88.871263)
			(xy 134.689646 -88.822628) (xy 134.669723 -88.770537) (xy 134.657597 -88.7161) (xy 134.653526 -88.660478)
			(xy 120.363609 -88.660478) (xy 120.358889 -88.665746) (xy 120.316021 -88.701421) (xy 120.268415 -88.730475)
			(xy 120.217086 -88.752287) (xy 120.163129 -88.766393) (xy 120.107692 -88.772493) (xy 120.051958 -88.770456)
			(xy 119.997115 -88.760326) (xy 119.944331 -88.742319) (xy 119.894731 -88.716818) (xy 119.849373 -88.684367)
			(xy 119.809224 -88.645658) (xy 119.775138 -88.601515) (xy 119.747842 -88.55288) (xy 119.727919 -88.500789)
			(xy 119.715793 -88.446352) (xy 119.711722 -88.39073) (xy 118.288606 -88.39073) (xy 118.292695 -88.405988)
			(xy 118.300518 -88.46541) (xy 118.301008 -88.495378) (xy 118.301008 -89.358978) (xy 118.300518 -89.388946)
			(xy 118.292695 -89.448368) (xy 118.277182 -89.506261) (xy 118.265804 -89.53373) (xy 119.660414 -89.53373)
			(xy 119.664485 -89.478108) (xy 119.676611 -89.423671) (xy 119.696534 -89.37158) (xy 119.72383 -89.322945)
			(xy 119.757916 -89.278802) (xy 119.798065 -89.240093) (xy 119.843423 -89.207642) (xy 119.893023 -89.182141)
			(xy 119.945807 -89.164134) (xy 120.00065 -89.154004) (xy 120.056384 -89.151967) (xy 120.111821 -89.158067)
			(xy 120.165778 -89.172173) (xy 120.17621 -89.176606) (xy 124.546104 -89.176606) (xy 124.550175 -89.120984)
			(xy 124.562301 -89.066547) (xy 124.582224 -89.014456) (xy 124.60952 -88.965821) (xy 124.643606 -88.921678)
			(xy 124.683755 -88.882969) (xy 124.729113 -88.850518) (xy 124.778713 -88.825017) (xy 124.831497 -88.80701)
			(xy 124.88634 -88.79688) (xy 124.942074 -88.794843) (xy 124.997511 -88.800943) (xy 125.051468 -88.815049)
			(xy 125.102797 -88.836861) (xy 125.150403 -88.865915) (xy 125.193271 -88.90159) (xy 125.230488 -88.943127)
			(xy 125.261261 -88.98964) (xy 125.284933 -89.040137) (xy 125.301001 -89.093544) (xy 125.309121 -89.14872)
			(xy 125.30963 -89.176606) (xy 125.309121 -89.204492) (xy 125.3053 -89.230454) (xy 133.320534 -89.230454)
			(xy 133.324605 -89.174832) (xy 133.336731 -89.120395) (xy 133.356654 -89.068304) (xy 133.38395 -89.019669)
			(xy 133.418036 -88.975526) (xy 133.458185 -88.936817) (xy 133.503543 -88.904366) (xy 133.553143 -88.878865)
			(xy 133.605927 -88.860858) (xy 133.66077 -88.850728) (xy 133.716504 -88.848691) (xy 133.771941 -88.854791)
			(xy 133.825898 -88.868897) (xy 133.877227 -88.890709) (xy 133.924833 -88.919763) (xy 133.967701 -88.955438)
			(xy 134.004918 -88.996975) (xy 134.035691 -89.043488) (xy 134.059363 -89.093985) (xy 134.075431 -89.147392)
			(xy 134.083551 -89.202568) (xy 134.08406 -89.230454) (xy 134.083551 -89.25834) (xy 134.075431 -89.313516)
			(xy 134.059363 -89.366923) (xy 134.035691 -89.41742) (xy 134.004918 -89.463933) (xy 133.967701 -89.50547)
			(xy 133.924833 -89.541145) (xy 133.877227 -89.570199) (xy 133.825898 -89.592011) (xy 133.771941 -89.606117)
			(xy 133.716504 -89.612217) (xy 133.66077 -89.61018) (xy 133.605927 -89.60005) (xy 133.553143 -89.582043)
			(xy 133.503543 -89.556542) (xy 133.458185 -89.524091) (xy 133.418036 -89.485382) (xy 133.38395 -89.441239)
			(xy 133.356654 -89.392604) (xy 133.336731 -89.340513) (xy 133.324605 -89.286076) (xy 133.320534 -89.230454)
			(xy 125.3053 -89.230454) (xy 125.301001 -89.259668) (xy 125.284933 -89.313075) (xy 125.261261 -89.363572)
			(xy 125.230488 -89.410085) (xy 125.193271 -89.451622) (xy 125.150403 -89.487297) (xy 125.102797 -89.516351)
			(xy 125.051468 -89.538163) (xy 124.997511 -89.552269) (xy 124.942074 -89.558369) (xy 124.88634 -89.556332)
			(xy 124.831497 -89.546202) (xy 124.778713 -89.528195) (xy 124.729113 -89.502694) (xy 124.683755 -89.470243)
			(xy 124.643606 -89.431534) (xy 124.60952 -89.387391) (xy 124.582224 -89.338756) (xy 124.562301 -89.286665)
			(xy 124.550175 -89.232228) (xy 124.546104 -89.176606) (xy 120.17621 -89.176606) (xy 120.217107 -89.193985)
			(xy 120.264713 -89.223039) (xy 120.307581 -89.258714) (xy 120.344798 -89.300251) (xy 120.375571 -89.346764)
			(xy 120.399243 -89.397261) (xy 120.415311 -89.450668) (xy 120.423431 -89.505844) (xy 120.42394 -89.53373)
			(xy 120.423431 -89.561616) (xy 120.415311 -89.616792) (xy 120.399243 -89.670199) (xy 120.375571 -89.720696)
			(xy 120.344798 -89.767209) (xy 120.307581 -89.808746) (xy 120.264713 -89.844421) (xy 120.217107 -89.873475)
			(xy 120.165778 -89.895287) (xy 120.111821 -89.909393) (xy 120.056384 -89.915493) (xy 120.00065 -89.913456)
			(xy 119.945807 -89.903326) (xy 119.893023 -89.885319) (xy 119.843423 -89.859818) (xy 119.798065 -89.827367)
			(xy 119.757916 -89.788658) (xy 119.72383 -89.744515) (xy 119.696534 -89.69588) (xy 119.676611 -89.643789)
			(xy 119.664485 -89.589352) (xy 119.660414 -89.53373) (xy 118.265804 -89.53373) (xy 118.254246 -89.561634)
			(xy 118.224279 -89.61354) (xy 118.187792 -89.66109) (xy 118.145412 -89.70347) (xy 118.097862 -89.739957)
			(xy 118.045956 -89.769924) (xy 117.990583 -89.79286) (xy 117.93269 -89.808373) (xy 117.873268 -89.816196)
			(xy 117.813332 -89.816196) (xy 117.75391 -89.808373) (xy 117.696017 -89.79286) (xy 117.640644 -89.769924)
			(xy 117.588738 -89.739957) (xy 117.541188 -89.70347) (xy 117.498808 -89.66109) (xy 117.462321 -89.61354)
			(xy 117.432354 -89.561634) (xy 117.409418 -89.506261) (xy 117.393905 -89.448368) (xy 117.386082 -89.388946)
			(xy 117.385592 -89.358978) (xy 101.955151 -89.358978) (xy 101.959587 -89.360863) (xy 102.007193 -89.389917)
			(xy 102.050061 -89.425592) (xy 102.087278 -89.467129) (xy 102.118051 -89.513642) (xy 102.141723 -89.564139)
			(xy 102.157791 -89.617546) (xy 102.165911 -89.672722) (xy 102.16642 -89.700608) (xy 102.165911 -89.728494)
			(xy 102.157791 -89.78367) (xy 102.141723 -89.837077) (xy 102.118051 -89.887574) (xy 102.087278 -89.934087)
			(xy 102.050061 -89.975624) (xy 102.007193 -90.011299) (xy 101.959587 -90.040353) (xy 101.908258 -90.062165)
			(xy 101.854301 -90.076271) (xy 101.798864 -90.082371) (xy 101.74313 -90.080334) (xy 101.688287 -90.070204)
			(xy 101.635503 -90.052197) (xy 101.585903 -90.026696) (xy 101.540545 -89.994245) (xy 101.500396 -89.955536)
			(xy 101.46631 -89.911393) (xy 101.439014 -89.862758) (xy 101.419091 -89.810667) (xy 101.406965 -89.75623)
			(xy 101.402894 -89.700608) (xy 94.681164 -89.700608) (xy 94.696729 -89.733811) (xy 94.712797 -89.787218)
			(xy 94.720917 -89.842394) (xy 94.721426 -89.87028) (xy 94.720917 -89.898166) (xy 94.712797 -89.953342)
			(xy 94.696729 -90.006749) (xy 94.673057 -90.057246) (xy 94.642284 -90.103759) (xy 94.605067 -90.145296)
			(xy 94.562199 -90.180971) (xy 94.514593 -90.210025) (xy 94.497353 -90.217351) (xy 107.858044 -90.217351)
			(xy 107.858044 -90.162849) (xy 107.8658 -90.1089) (xy 107.881154 -90.056605) (xy 107.903793 -90.007026)
			(xy 107.933258 -89.961174) (xy 107.968947 -89.919981) (xy 108.010136 -89.884287) (xy 108.055984 -89.854816)
			(xy 108.10556 -89.832171) (xy 108.157853 -89.81681) (xy 108.211801 -89.809047) (xy 108.239052 -89.808558)
			(xy 108.259989 -89.808846) (xy 108.301612 -89.813425) (xy 108.32211 -89.817702) (xy 108.33227 -89.819988)
			(xy 108.352082 -89.816178) (xy 108.430568 -89.764616) (xy 108.441998 -89.747598) (xy 108.443776 -89.737438)
			(xy 108.449137 -89.711594) (xy 108.466074 -89.661602) (xy 108.489739 -89.614422) (xy 108.51968 -89.570954)
			(xy 108.555326 -89.532027) (xy 108.595998 -89.498385) (xy 108.640917 -89.470669) (xy 108.689228 -89.449408)
			(xy 108.740009 -89.435009) (xy 108.792289 -89.427745) (xy 108.81868 -89.427304) (xy 108.845935 -89.427742)
			(xy 108.89989 -89.435496) (xy 108.952191 -89.450851) (xy 109.001776 -89.473493) (xy 109.047633 -89.502962)
			(xy 109.088829 -89.538657) (xy 109.124526 -89.579851) (xy 109.153997 -89.625707) (xy 109.176642 -89.67529)
			(xy 109.191999 -89.727591) (xy 109.199757 -89.781545) (xy 109.199757 -89.836055) (xy 109.193119 -89.882218)
			(xy 110.333026 -89.882218) (xy 110.337097 -89.826596) (xy 110.349223 -89.772159) (xy 110.369146 -89.720068)
			(xy 110.396442 -89.671433) (xy 110.430528 -89.62729) (xy 110.470677 -89.588581) (xy 110.516035 -89.55613)
			(xy 110.565635 -89.530629) (xy 110.618419 -89.512622) (xy 110.673262 -89.502492) (xy 110.728996 -89.500455)
			(xy 110.784433 -89.506555) (xy 110.83839 -89.520661) (xy 110.889719 -89.542473) (xy 110.937325 -89.571527)
			(xy 110.980193 -89.607202) (xy 111.01741 -89.648739) (xy 111.048183 -89.695252) (xy 111.071855 -89.745749)
			(xy 111.087923 -89.799156) (xy 111.096043 -89.854332) (xy 111.096552 -89.882218) (xy 111.096043 -89.910104)
			(xy 111.087923 -89.96528) (xy 111.071855 -90.018687) (xy 111.048183 -90.069184) (xy 111.01741 -90.115697)
			(xy 110.980193 -90.157234) (xy 110.937325 -90.192909) (xy 110.889719 -90.221963) (xy 110.83839 -90.243775)
			(xy 110.784433 -90.257881) (xy 110.728996 -90.263981) (xy 110.673262 -90.261944) (xy 110.618419 -90.251814)
			(xy 110.565635 -90.233807) (xy 110.516035 -90.208306) (xy 110.470677 -90.175855) (xy 110.430528 -90.137146)
			(xy 110.396442 -90.093003) (xy 110.369146 -90.044368) (xy 110.349223 -89.992277) (xy 110.337097 -89.93784)
			(xy 110.333026 -89.882218) (xy 109.193119 -89.882218) (xy 109.191999 -89.890009) (xy 109.176642 -89.94231)
			(xy 109.153997 -89.991893) (xy 109.124526 -90.037749) (xy 109.088829 -90.078943) (xy 109.047633 -90.114638)
			(xy 109.001776 -90.144107) (xy 108.952191 -90.166749) (xy 108.89989 -90.182104) (xy 108.845935 -90.189858)
			(xy 108.81868 -90.19032) (xy 108.797742 -90.190043) (xy 108.756119 -90.185456) (xy 108.735622 -90.181176)
			(xy 108.725462 -90.17889) (xy 108.70565 -90.1827) (xy 108.627164 -90.234262) (xy 108.615734 -90.25128)
			(xy 108.613956 -90.26144) (xy 108.613318 -90.264488) (xy 111.514634 -90.264488) (xy 111.518705 -90.208866)
			(xy 111.530831 -90.154429) (xy 111.550754 -90.102338) (xy 111.57805 -90.053703) (xy 111.612136 -90.00956)
			(xy 111.652285 -89.970851) (xy 111.697643 -89.9384) (xy 111.747243 -89.912899) (xy 111.800027 -89.894892)
			(xy 111.85487 -89.884762) (xy 111.910604 -89.882725) (xy 111.966041 -89.888825) (xy 112.019998 -89.902931)
			(xy 112.071327 -89.924743) (xy 112.118933 -89.953797) (xy 112.156533 -89.985088) (xy 134.64743 -89.985088)
			(xy 134.651501 -89.929466) (xy 134.663627 -89.875029) (xy 134.68355 -89.822938) (xy 134.710846 -89.774303)
			(xy 134.744932 -89.73016) (xy 134.785081 -89.691451) (xy 134.830439 -89.659) (xy 134.880039 -89.633499)
			(xy 134.932823 -89.615492) (xy 134.987666 -89.605362) (xy 135.0434 -89.603325) (xy 135.098837 -89.609425)
			(xy 135.152794 -89.623531) (xy 135.204123 -89.645343) (xy 135.251729 -89.674397) (xy 135.294597 -89.710072)
			(xy 135.331814 -89.751609) (xy 135.362587 -89.798122) (xy 135.386259 -89.848619) (xy 135.402327 -89.902026)
			(xy 135.410447 -89.957202) (xy 135.410956 -89.985088) (xy 135.410447 -90.012974) (xy 135.402327 -90.06815)
			(xy 135.392852 -90.099642) (xy 139.708126 -90.099642) (xy 139.712197 -90.04402) (xy 139.724323 -89.989583)
			(xy 139.744246 -89.937492) (xy 139.771542 -89.888857) (xy 139.805628 -89.844714) (xy 139.845777 -89.806005)
			(xy 139.891135 -89.773554) (xy 139.940735 -89.748053) (xy 139.993519 -89.730046) (xy 140.048362 -89.719916)
			(xy 140.104096 -89.717879) (xy 140.159533 -89.723979) (xy 140.21349 -89.738085) (xy 140.264819 -89.759897)
			(xy 140.312425 -89.788951) (xy 140.355293 -89.824626) (xy 140.39251 -89.866163) (xy 140.423283 -89.912676)
			(xy 140.446955 -89.963173) (xy 140.463023 -90.01658) (xy 140.471143 -90.071756) (xy 140.471652 -90.099642)
			(xy 140.471143 -90.127528) (xy 140.463023 -90.182704) (xy 140.446955 -90.236111) (xy 140.423283 -90.286608)
			(xy 140.39251 -90.333121) (xy 140.355293 -90.374658) (xy 140.312425 -90.410333) (xy 140.264819 -90.439387)
			(xy 140.21349 -90.461199) (xy 140.159533 -90.475305) (xy 140.104096 -90.481405) (xy 140.048362 -90.479368)
			(xy 139.993519 -90.469238) (xy 139.940735 -90.451231) (xy 139.891135 -90.42573) (xy 139.845777 -90.393279)
			(xy 139.805628 -90.35457) (xy 139.771542 -90.310427) (xy 139.744246 -90.261792) (xy 139.724323 -90.209701)
			(xy 139.712197 -90.155264) (xy 139.708126 -90.099642) (xy 135.392852 -90.099642) (xy 135.386259 -90.121557)
			(xy 135.362587 -90.172054) (xy 135.331814 -90.218567) (xy 135.294597 -90.260104) (xy 135.251729 -90.295779)
			(xy 135.204123 -90.324833) (xy 135.152794 -90.346645) (xy 135.098837 -90.360751) (xy 135.0434 -90.366851)
			(xy 134.987666 -90.364814) (xy 134.932823 -90.354684) (xy 134.880039 -90.336677) (xy 134.830439 -90.311176)
			(xy 134.785081 -90.278725) (xy 134.744932 -90.240016) (xy 134.710846 -90.195873) (xy 134.68355 -90.147238)
			(xy 134.663627 -90.095147) (xy 134.651501 -90.04071) (xy 134.64743 -89.985088) (xy 112.156533 -89.985088)
			(xy 112.161801 -89.989472) (xy 112.199018 -90.031009) (xy 112.229791 -90.077522) (xy 112.253463 -90.128019)
			(xy 112.269531 -90.181426) (xy 112.277651 -90.236602) (xy 112.27816 -90.264488) (xy 112.277651 -90.292374)
			(xy 112.269531 -90.34755) (xy 112.253463 -90.400957) (xy 112.229791 -90.451454) (xy 112.199018 -90.497967)
			(xy 112.161801 -90.539504) (xy 112.118933 -90.575179) (xy 112.071327 -90.604233) (xy 112.019998 -90.626045)
			(xy 111.966041 -90.640151) (xy 111.910604 -90.646251) (xy 111.85487 -90.644214) (xy 111.800027 -90.634084)
			(xy 111.747243 -90.616077) (xy 111.697643 -90.590576) (xy 111.652285 -90.558125) (xy 111.612136 -90.519416)
			(xy 111.57805 -90.475273) (xy 111.550754 -90.426638) (xy 111.530831 -90.374547) (xy 111.518705 -90.32011)
			(xy 111.514634 -90.264488) (xy 108.613318 -90.264488) (xy 108.608549 -90.287274) (xy 108.591617 -90.337263)
			(xy 108.567957 -90.384442) (xy 108.538021 -90.427909) (xy 108.50238 -90.466836) (xy 108.461714 -90.50048)
			(xy 108.416799 -90.528197) (xy 108.368493 -90.549461) (xy 108.317718 -90.563863) (xy 108.265441 -90.571131)
			(xy 108.239052 -90.571574) (xy 108.211801 -90.571153) (xy 108.157853 -90.56339) (xy 108.10556 -90.548029)
			(xy 108.055984 -90.525384) (xy 108.010136 -90.495913) (xy 107.968947 -90.460219) (xy 107.933258 -90.419026)
			(xy 107.903793 -90.373174) (xy 107.881154 -90.323595) (xy 107.8658 -90.2713) (xy 107.858044 -90.217351)
			(xy 94.497353 -90.217351) (xy 94.463264 -90.231837) (xy 94.409307 -90.245943) (xy 94.35387 -90.252043)
			(xy 94.298136 -90.250006) (xy 94.243293 -90.239876) (xy 94.190509 -90.221869) (xy 94.140909 -90.196368)
			(xy 94.095551 -90.163917) (xy 94.055402 -90.125208) (xy 94.021316 -90.081065) (xy 93.99402 -90.03243)
			(xy 93.974097 -89.980339) (xy 93.961971 -89.925902) (xy 93.9579 -89.87028) (xy 93.213174 -89.87028)
			(xy 93.224865 -89.909138) (xy 93.232985 -89.964314) (xy 93.233494 -89.9922) (xy 93.232985 -90.020086)
			(xy 93.224865 -90.075262) (xy 93.208797 -90.128669) (xy 93.185125 -90.179166) (xy 93.154352 -90.225679)
			(xy 93.117135 -90.267216) (xy 93.074267 -90.302891) (xy 93.026661 -90.331945) (xy 92.975332 -90.353757)
			(xy 92.921375 -90.367863) (xy 92.865938 -90.373963) (xy 92.810204 -90.371926) (xy 92.755361 -90.361796)
			(xy 92.702577 -90.343789) (xy 92.652977 -90.318288) (xy 92.607619 -90.285837) (xy 92.56747 -90.247128)
			(xy 92.533384 -90.202985) (xy 92.506088 -90.15435) (xy 92.486165 -90.102259) (xy 92.474039 -90.047822)
			(xy 92.469968 -89.9922) (xy 92.263272 -89.9922) (xy 91.926114 -90.612722) (xy 104.01376 -90.612722)
			(xy 104.017831 -90.5571) (xy 104.029957 -90.502663) (xy 104.04988 -90.450572) (xy 104.077176 -90.401937)
			(xy 104.111262 -90.357794) (xy 104.151411 -90.319085) (xy 104.196769 -90.286634) (xy 104.246369 -90.261133)
			(xy 104.299153 -90.243126) (xy 104.353996 -90.232996) (xy 104.40973 -90.230959) (xy 104.465167 -90.237059)
			(xy 104.519124 -90.251165) (xy 104.570453 -90.272977) (xy 104.618059 -90.302031) (xy 104.660927 -90.337706)
			(xy 104.698144 -90.379243) (xy 104.728917 -90.425756) (xy 104.752589 -90.476253) (xy 104.768657 -90.52966)
			(xy 104.776777 -90.584836) (xy 104.777286 -90.612722) (xy 104.776777 -90.640608) (xy 104.768657 -90.695784)
			(xy 104.752589 -90.749191) (xy 104.728917 -90.799688) (xy 104.720697 -90.812112) (xy 105.427778 -90.812112)
			(xy 105.431849 -90.75649) (xy 105.443975 -90.702053) (xy 105.463898 -90.649962) (xy 105.491194 -90.601327)
			(xy 105.52528 -90.557184) (xy 105.565429 -90.518475) (xy 105.610787 -90.486024) (xy 105.660387 -90.460523)
			(xy 105.713171 -90.442516) (xy 105.768014 -90.432386) (xy 105.823748 -90.430349) (xy 105.879185 -90.436449)
			(xy 105.933142 -90.450555) (xy 105.984471 -90.472367) (xy 106.032077 -90.501421) (xy 106.074945 -90.537096)
			(xy 106.112162 -90.578633) (xy 106.142935 -90.625146) (xy 106.166607 -90.675643) (xy 106.175799 -90.706194)
			(xy 124.7935 -90.706194) (xy 124.797571 -90.650572) (xy 124.809697 -90.596135) (xy 124.82962 -90.544044)
			(xy 124.856916 -90.495409) (xy 124.891002 -90.451266) (xy 124.931151 -90.412557) (xy 124.976509 -90.380106)
			(xy 125.026109 -90.354605) (xy 125.078893 -90.336598) (xy 125.133736 -90.326468) (xy 125.18947 -90.324431)
			(xy 125.244907 -90.330531) (xy 125.298864 -90.344637) (xy 125.350193 -90.366449) (xy 125.397799 -90.395503)
			(xy 125.440667 -90.431178) (xy 125.477884 -90.472715) (xy 125.508657 -90.519228) (xy 125.532329 -90.569725)
			(xy 125.548397 -90.623132) (xy 125.556517 -90.678308) (xy 125.557026 -90.706194) (xy 125.556517 -90.73408)
			(xy 125.548397 -90.789256) (xy 125.532329 -90.842663) (xy 125.508657 -90.89316) (xy 125.477884 -90.939673)
			(xy 125.440667 -90.98121) (xy 125.397799 -91.016885) (xy 125.350193 -91.045939) (xy 125.298864 -91.067751)
			(xy 125.244907 -91.081857) (xy 125.18947 -91.087957) (xy 125.133736 -91.08592) (xy 125.078893 -91.07579)
			(xy 125.026109 -91.057783) (xy 124.976509 -91.032282) (xy 124.931151 -90.999831) (xy 124.891002 -90.961122)
			(xy 124.856916 -90.916979) (xy 124.82962 -90.868344) (xy 124.809697 -90.816253) (xy 124.797571 -90.761816)
			(xy 124.7935 -90.706194) (xy 106.175799 -90.706194) (xy 106.182675 -90.72905) (xy 106.190795 -90.784226)
			(xy 106.191304 -90.812112) (xy 106.190795 -90.839998) (xy 106.182675 -90.895174) (xy 106.166607 -90.948581)
			(xy 106.142935 -90.999078) (xy 106.112162 -91.045591) (xy 106.074945 -91.087128) (xy 106.032077 -91.122803)
			(xy 105.984471 -91.151857) (xy 105.933142 -91.173669) (xy 105.879185 -91.187775) (xy 105.823748 -91.193875)
			(xy 105.768014 -91.191838) (xy 105.713171 -91.181708) (xy 105.660387 -91.163701) (xy 105.610787 -91.1382)
			(xy 105.565429 -91.105749) (xy 105.52528 -91.06704) (xy 105.491194 -91.022897) (xy 105.463898 -90.974262)
			(xy 105.443975 -90.922171) (xy 105.431849 -90.867734) (xy 105.427778 -90.812112) (xy 104.720697 -90.812112)
			(xy 104.698144 -90.846201) (xy 104.660927 -90.887738) (xy 104.618059 -90.923413) (xy 104.570453 -90.952467)
			(xy 104.519124 -90.974279) (xy 104.465167 -90.988385) (xy 104.40973 -90.994485) (xy 104.353996 -90.992448)
			(xy 104.299153 -90.982318) (xy 104.246369 -90.964311) (xy 104.196769 -90.93881) (xy 104.151411 -90.906359)
			(xy 104.111262 -90.86765) (xy 104.077176 -90.823507) (xy 104.04988 -90.774872) (xy 104.029957 -90.722781)
			(xy 104.017831 -90.668344) (xy 104.01376 -90.612722) (xy 91.926114 -90.612722) (xy 91.607312 -91.199462)
			(xy 106.656884 -91.199462) (xy 106.660955 -91.14384) (xy 106.673081 -91.089403) (xy 106.693004 -91.037312)
			(xy 106.7203 -90.988677) (xy 106.754386 -90.944534) (xy 106.794535 -90.905825) (xy 106.839893 -90.873374)
			(xy 106.889493 -90.847873) (xy 106.942277 -90.829866) (xy 106.99712 -90.819736) (xy 107.052854 -90.817699)
			(xy 107.108291 -90.823799) (xy 107.162248 -90.837905) (xy 107.213577 -90.859717) (xy 107.261183 -90.888771)
			(xy 107.304051 -90.924446) (xy 107.341268 -90.965983) (xy 107.372041 -91.012496) (xy 107.395713 -91.062993)
			(xy 107.411781 -91.1164) (xy 107.419901 -91.171576) (xy 107.420285 -91.192604) (xy 108.032802 -91.192604)
			(xy 108.036873 -91.136982) (xy 108.048999 -91.082545) (xy 108.068922 -91.030454) (xy 108.096218 -90.981819)
			(xy 108.130304 -90.937676) (xy 108.170453 -90.898967) (xy 108.215811 -90.866516) (xy 108.265411 -90.841015)
			(xy 108.318195 -90.823008) (xy 108.373038 -90.812878) (xy 108.428772 -90.810841) (xy 108.484209 -90.816941)
			(xy 108.538166 -90.831047) (xy 108.589495 -90.852859) (xy 108.637101 -90.881913) (xy 108.679969 -90.917588)
			(xy 108.717186 -90.959125) (xy 108.747959 -91.005638) (xy 108.771631 -91.056135) (xy 108.787699 -91.109542)
			(xy 108.795819 -91.164718) (xy 108.796328 -91.192604) (xy 108.795819 -91.22049) (xy 108.787699 -91.275666)
			(xy 108.771631 -91.329073) (xy 108.747959 -91.37957) (xy 108.717389 -91.425776) (xy 118.321072 -91.425776)
			(xy 118.325143 -91.370154) (xy 118.337269 -91.315717) (xy 118.357192 -91.263626) (xy 118.384488 -91.214991)
			(xy 118.418574 -91.170848) (xy 118.458723 -91.132139) (xy 118.504081 -91.099688) (xy 118.553681 -91.074187)
			(xy 118.606465 -91.05618) (xy 118.661308 -91.04605) (xy 118.717042 -91.044013) (xy 118.772479 -91.050113)
			(xy 118.826436 -91.064219) (xy 118.877765 -91.086031) (xy 118.925371 -91.115085) (xy 118.968239 -91.15076)
			(xy 119.005456 -91.192297) (xy 119.036229 -91.23881) (xy 119.059901 -91.289307) (xy 119.075969 -91.342714)
			(xy 119.084089 -91.39789) (xy 119.084598 -91.425776) (xy 119.084089 -91.453662) (xy 119.082773 -91.462606)
			(xy 119.737884 -91.462606) (xy 119.741955 -91.406984) (xy 119.754081 -91.352547) (xy 119.774004 -91.300456)
			(xy 119.8013 -91.251821) (xy 119.835386 -91.207678) (xy 119.875535 -91.168969) (xy 119.920893 -91.136518)
			(xy 119.970493 -91.111017) (xy 120.023277 -91.09301) (xy 120.07812 -91.08288) (xy 120.133854 -91.080843)
			(xy 120.189291 -91.086943) (xy 120.243248 -91.101049) (xy 120.294577 -91.122861) (xy 120.342183 -91.151915)
			(xy 120.385051 -91.18759) (xy 120.422268 -91.229127) (xy 120.453041 -91.27564) (xy 120.476713 -91.326137)
			(xy 120.477116 -91.327478) (xy 134.913368 -91.327478) (xy 134.917439 -91.271856) (xy 134.929565 -91.217419)
			(xy 134.949488 -91.165328) (xy 134.976784 -91.116693) (xy 135.01087 -91.07255) (xy 135.051019 -91.033841)
			(xy 135.096377 -91.00139) (xy 135.145977 -90.975889) (xy 135.198761 -90.957882) (xy 135.253604 -90.947752)
			(xy 135.309338 -90.945715) (xy 135.364775 -90.951815) (xy 135.418732 -90.965921) (xy 135.470061 -90.987733)
			(xy 135.517667 -91.016787) (xy 135.560535 -91.052462) (xy 135.597752 -91.093999) (xy 135.628525 -91.140512)
			(xy 135.652197 -91.191009) (xy 135.667731 -91.242642) (xy 139.708126 -91.242642) (xy 139.712197 -91.18702)
			(xy 139.724323 -91.132583) (xy 139.744246 -91.080492) (xy 139.771542 -91.031857) (xy 139.805628 -90.987714)
			(xy 139.845777 -90.949005) (xy 139.891135 -90.916554) (xy 139.940735 -90.891053) (xy 139.993519 -90.873046)
			(xy 140.048362 -90.862916) (xy 140.104096 -90.860879) (xy 140.159533 -90.866979) (xy 140.21349 -90.881085)
			(xy 140.264819 -90.902897) (xy 140.312425 -90.931951) (xy 140.355293 -90.967626) (xy 140.39251 -91.009163)
			(xy 140.423283 -91.055676) (xy 140.446955 -91.106173) (xy 140.463023 -91.15958) (xy 140.471143 -91.214756)
			(xy 140.471652 -91.242642) (xy 140.471143 -91.270528) (xy 140.463023 -91.325704) (xy 140.446955 -91.379111)
			(xy 140.423283 -91.429608) (xy 140.39251 -91.476121) (xy 140.355293 -91.517658) (xy 140.312425 -91.553333)
			(xy 140.264819 -91.582387) (xy 140.21349 -91.604199) (xy 140.159533 -91.618305) (xy 140.104096 -91.624405)
			(xy 140.048362 -91.622368) (xy 139.993519 -91.612238) (xy 139.940735 -91.594231) (xy 139.891135 -91.56873)
			(xy 139.845777 -91.536279) (xy 139.805628 -91.49757) (xy 139.771542 -91.453427) (xy 139.744246 -91.404792)
			(xy 139.724323 -91.352701) (xy 139.712197 -91.298264) (xy 139.708126 -91.242642) (xy 135.667731 -91.242642)
			(xy 135.668265 -91.244416) (xy 135.676385 -91.299592) (xy 135.676894 -91.327478) (xy 135.676385 -91.355364)
			(xy 135.668265 -91.41054) (xy 135.652197 -91.463947) (xy 135.628525 -91.514444) (xy 135.597752 -91.560957)
			(xy 135.560535 -91.602494) (xy 135.517667 -91.638169) (xy 135.470061 -91.667223) (xy 135.418732 -91.689035)
			(xy 135.364775 -91.703141) (xy 135.309338 -91.709241) (xy 135.253604 -91.707204) (xy 135.198761 -91.697074)
			(xy 135.145977 -91.679067) (xy 135.096377 -91.653566) (xy 135.051019 -91.621115) (xy 135.01087 -91.582406)
			(xy 134.976784 -91.538263) (xy 134.949488 -91.489628) (xy 134.929565 -91.437537) (xy 134.917439 -91.3831)
			(xy 134.913368 -91.327478) (xy 120.477116 -91.327478) (xy 120.492781 -91.379544) (xy 120.500901 -91.43472)
			(xy 120.50141 -91.462606) (xy 120.500901 -91.490492) (xy 120.492781 -91.545668) (xy 120.476713 -91.599075)
			(xy 120.453041 -91.649572) (xy 120.422268 -91.696085) (xy 120.385051 -91.737622) (xy 120.342183 -91.773297)
			(xy 120.294577 -91.802351) (xy 120.243248 -91.824163) (xy 120.189291 -91.838269) (xy 120.133854 -91.844369)
			(xy 120.07812 -91.842332) (xy 120.023277 -91.832202) (xy 119.970493 -91.814195) (xy 119.920893 -91.788694)
			(xy 119.875535 -91.756243) (xy 119.835386 -91.717534) (xy 119.8013 -91.673391) (xy 119.774004 -91.624756)
			(xy 119.754081 -91.572665) (xy 119.741955 -91.518228) (xy 119.737884 -91.462606) (xy 119.082773 -91.462606)
			(xy 119.075969 -91.508838) (xy 119.059901 -91.562245) (xy 119.036229 -91.612742) (xy 119.005456 -91.659255)
			(xy 118.968239 -91.700792) (xy 118.925371 -91.736467) (xy 118.877765 -91.765521) (xy 118.826436 -91.787333)
			(xy 118.772479 -91.801439) (xy 118.717042 -91.807539) (xy 118.661308 -91.805502) (xy 118.606465 -91.795372)
			(xy 118.553681 -91.777365) (xy 118.504081 -91.751864) (xy 118.458723 -91.719413) (xy 118.418574 -91.680704)
			(xy 118.384488 -91.636561) (xy 118.357192 -91.587926) (xy 118.337269 -91.535835) (xy 118.325143 -91.481398)
			(xy 118.321072 -91.425776) (xy 108.717389 -91.425776) (xy 108.717186 -91.426083) (xy 108.679969 -91.46762)
			(xy 108.637101 -91.503295) (xy 108.589495 -91.532349) (xy 108.538166 -91.554161) (xy 108.484209 -91.568267)
			(xy 108.428772 -91.574367) (xy 108.373038 -91.57233) (xy 108.318195 -91.5622) (xy 108.265411 -91.544193)
			(xy 108.215811 -91.518692) (xy 108.170453 -91.486241) (xy 108.130304 -91.447532) (xy 108.096218 -91.403389)
			(xy 108.068922 -91.354754) (xy 108.048999 -91.302663) (xy 108.036873 -91.248226) (xy 108.032802 -91.192604)
			(xy 107.420285 -91.192604) (xy 107.42041 -91.199462) (xy 107.419901 -91.227348) (xy 107.411781 -91.282524)
			(xy 107.395713 -91.335931) (xy 107.372041 -91.386428) (xy 107.341268 -91.432941) (xy 107.304051 -91.474478)
			(xy 107.261183 -91.510153) (xy 107.213577 -91.539207) (xy 107.162248 -91.561019) (xy 107.108291 -91.575125)
			(xy 107.052854 -91.581225) (xy 106.99712 -91.579188) (xy 106.942277 -91.569058) (xy 106.889493 -91.551051)
			(xy 106.839893 -91.52555) (xy 106.794535 -91.493099) (xy 106.754386 -91.45439) (xy 106.7203 -91.410247)
			(xy 106.693004 -91.361612) (xy 106.673081 -91.309521) (xy 106.660955 -91.255084) (xy 106.656884 -91.199462)
			(xy 91.607312 -91.199462) (xy 91.374214 -91.628468) (xy 91.352624 -91.66606) (xy 91.043579 -92.179902)
			(xy 125.607824 -92.179902) (xy 125.611895 -92.12428) (xy 125.624021 -92.069843) (xy 125.643944 -92.017752)
			(xy 125.67124 -91.969117) (xy 125.705326 -91.924974) (xy 125.745475 -91.886265) (xy 125.790833 -91.853814)
			(xy 125.840433 -91.828313) (xy 125.893217 -91.810306) (xy 125.94806 -91.800176) (xy 126.003794 -91.798139)
			(xy 126.059231 -91.804239) (xy 126.113188 -91.818345) (xy 126.164517 -91.840157) (xy 126.212123 -91.869211)
			(xy 126.254991 -91.904886) (xy 126.292208 -91.946423) (xy 126.322981 -91.992936) (xy 126.346653 -92.043433)
			(xy 126.362721 -92.09684) (xy 126.370841 -92.152016) (xy 126.37135 -92.179902) (xy 126.370841 -92.207788)
			(xy 126.362721 -92.262964) (xy 126.346653 -92.316371) (xy 126.322981 -92.366868) (xy 126.292208 -92.413381)
			(xy 126.254991 -92.454918) (xy 126.212123 -92.490593) (xy 126.164517 -92.519647) (xy 126.113188 -92.541459)
			(xy 126.059231 -92.555565) (xy 126.003794 -92.561665) (xy 125.94806 -92.559628) (xy 125.893217 -92.549498)
			(xy 125.840433 -92.531491) (xy 125.790833 -92.50599) (xy 125.745475 -92.473539) (xy 125.705326 -92.43483)
			(xy 125.67124 -92.390687) (xy 125.643944 -92.342052) (xy 125.624021 -92.289961) (xy 125.611895 -92.235524)
			(xy 125.607824 -92.179902) (xy 91.043579 -92.179902) (xy 90.716354 -92.72397) (xy 90.281206 -93.447362)
			(xy 104.346754 -93.447362) (xy 104.350825 -93.39174) (xy 104.362951 -93.337303) (xy 104.382874 -93.285212)
			(xy 104.41017 -93.236577) (xy 104.444256 -93.192434) (xy 104.484405 -93.153725) (xy 104.529763 -93.121274)
			(xy 104.579363 -93.095773) (xy 104.632147 -93.077766) (xy 104.68699 -93.067636) (xy 104.742724 -93.065599)
			(xy 104.798161 -93.071699) (xy 104.852118 -93.085805) (xy 104.903447 -93.107617) (xy 104.951053 -93.136671)
			(xy 104.993921 -93.172346) (xy 105.031138 -93.213883) (xy 105.061911 -93.260396) (xy 105.085583 -93.310893)
			(xy 105.101651 -93.3643) (xy 105.109771 -93.419476) (xy 105.110076 -93.436186) (xy 106.40517 -93.436186)
			(xy 106.409241 -93.380564) (xy 106.421367 -93.326127) (xy 106.44129 -93.274036) (xy 106.468586 -93.225401)
			(xy 106.502672 -93.181258) (xy 106.542821 -93.142549) (xy 106.588179 -93.110098) (xy 106.637779 -93.084597)
			(xy 106.690563 -93.06659) (xy 106.745406 -93.05646) (xy 106.80114 -93.054423) (xy 106.856577 -93.060523)
			(xy 106.910534 -93.074629) (xy 106.961863 -93.096441) (xy 107.009469 -93.125495) (xy 107.052337 -93.16117)
			(xy 107.089554 -93.202707) (xy 107.120327 -93.24922) (xy 107.143999 -93.299717) (xy 107.160067 -93.353124)
			(xy 107.166422 -93.396308) (xy 115.412772 -93.396308) (xy 115.416843 -93.340686) (xy 115.428969 -93.286249)
			(xy 115.448892 -93.234158) (xy 115.476188 -93.185523) (xy 115.510274 -93.14138) (xy 115.550423 -93.102671)
			(xy 115.595781 -93.07022) (xy 115.645381 -93.044719) (xy 115.698165 -93.026712) (xy 115.753008 -93.016582)
			(xy 115.808742 -93.014545) (xy 115.864179 -93.020645) (xy 115.918136 -93.034751) (xy 115.969465 -93.056563)
			(xy 116.017071 -93.085617) (xy 116.059939 -93.121292) (xy 116.090604 -93.155516) (xy 118.878602 -93.155516)
			(xy 118.882673 -93.099894) (xy 118.894799 -93.045457) (xy 118.914722 -92.993366) (xy 118.942018 -92.944731)
			(xy 118.976104 -92.900588) (xy 119.016253 -92.861879) (xy 119.061611 -92.829428) (xy 119.111211 -92.803927)
			(xy 119.163995 -92.78592) (xy 119.218838 -92.77579) (xy 119.274572 -92.773753) (xy 119.330009 -92.779853)
			(xy 119.383966 -92.793959) (xy 119.435295 -92.815771) (xy 119.438033 -92.817442) (xy 124.345444 -92.817442)
			(xy 124.349515 -92.76182) (xy 124.361641 -92.707383) (xy 124.381564 -92.655292) (xy 124.40886 -92.606657)
			(xy 124.442946 -92.562514) (xy 124.483095 -92.523805) (xy 124.528453 -92.491354) (xy 124.578053 -92.465853)
			(xy 124.630837 -92.447846) (xy 124.68568 -92.437716) (xy 124.741414 -92.435679) (xy 124.796851 -92.441779)
			(xy 124.850808 -92.455885) (xy 124.902137 -92.477697) (xy 124.949743 -92.506751) (xy 124.992611 -92.542426)
			(xy 125.029828 -92.583963) (xy 125.060601 -92.630476) (xy 125.067636 -92.645484) (xy 135.053576 -92.645484)
			(xy 135.057647 -92.589862) (xy 135.069773 -92.535425) (xy 135.089696 -92.483334) (xy 135.116992 -92.434699)
			(xy 135.151078 -92.390556) (xy 135.191227 -92.351847) (xy 135.236585 -92.319396) (xy 135.286185 -92.293895)
			(xy 135.338969 -92.275888) (xy 135.393812 -92.265758) (xy 135.449546 -92.263721) (xy 135.504983 -92.269821)
			(xy 135.55894 -92.283927) (xy 135.610269 -92.305739) (xy 135.657875 -92.334793) (xy 135.700743 -92.370468)
			(xy 135.714339 -92.385642) (xy 139.708126 -92.385642) (xy 139.712197 -92.33002) (xy 139.724323 -92.275583)
			(xy 139.744246 -92.223492) (xy 139.771542 -92.174857) (xy 139.805628 -92.130714) (xy 139.845777 -92.092005)
			(xy 139.891135 -92.059554) (xy 139.940735 -92.034053) (xy 139.993519 -92.016046) (xy 140.048362 -92.005916)
			(xy 140.104096 -92.003879) (xy 140.159533 -92.009979) (xy 140.21349 -92.024085) (xy 140.264819 -92.045897)
			(xy 140.312425 -92.074951) (xy 140.355293 -92.110626) (xy 140.39251 -92.152163) (xy 140.423283 -92.198676)
			(xy 140.446955 -92.249173) (xy 140.463023 -92.30258) (xy 140.471143 -92.357756) (xy 140.471652 -92.385642)
			(xy 140.471143 -92.413528) (xy 140.463023 -92.468704) (xy 140.446955 -92.522111) (xy 140.423283 -92.572608)
			(xy 140.39251 -92.619121) (xy 140.355293 -92.660658) (xy 140.312425 -92.696333) (xy 140.264819 -92.725387)
			(xy 140.21349 -92.747199) (xy 140.159533 -92.761305) (xy 140.104096 -92.767405) (xy 140.048362 -92.765368)
			(xy 139.993519 -92.755238) (xy 139.940735 -92.737231) (xy 139.891135 -92.71173) (xy 139.845777 -92.679279)
			(xy 139.805628 -92.64057) (xy 139.771542 -92.596427) (xy 139.744246 -92.547792) (xy 139.724323 -92.495701)
			(xy 139.712197 -92.441264) (xy 139.708126 -92.385642) (xy 135.714339 -92.385642) (xy 135.73796 -92.412005)
			(xy 135.768733 -92.458518) (xy 135.792405 -92.509015) (xy 135.808473 -92.562422) (xy 135.816593 -92.617598)
			(xy 135.817102 -92.645484) (xy 135.816593 -92.67337) (xy 135.808473 -92.728546) (xy 135.792405 -92.781953)
			(xy 135.768733 -92.83245) (xy 135.73796 -92.878963) (xy 135.700743 -92.9205) (xy 135.657875 -92.956175)
			(xy 135.610269 -92.985229) (xy 135.55894 -93.007041) (xy 135.504983 -93.021147) (xy 135.449546 -93.027247)
			(xy 135.393812 -93.02521) (xy 135.338969 -93.01508) (xy 135.286185 -92.997073) (xy 135.236585 -92.971572)
			(xy 135.191227 -92.939121) (xy 135.151078 -92.900412) (xy 135.116992 -92.856269) (xy 135.089696 -92.807634)
			(xy 135.069773 -92.755543) (xy 135.057647 -92.701106) (xy 135.053576 -92.645484) (xy 125.067636 -92.645484)
			(xy 125.084273 -92.680973) (xy 125.100341 -92.73438) (xy 125.108461 -92.789556) (xy 125.10897 -92.817442)
			(xy 125.108461 -92.845328) (xy 125.100341 -92.900504) (xy 125.084273 -92.953911) (xy 125.060601 -93.004408)
			(xy 125.029828 -93.050921) (xy 124.992611 -93.092458) (xy 124.949743 -93.128133) (xy 124.902137 -93.157187)
			(xy 124.850808 -93.178999) (xy 124.796851 -93.193105) (xy 124.741414 -93.199205) (xy 124.68568 -93.197168)
			(xy 124.630837 -93.187038) (xy 124.578053 -93.169031) (xy 124.528453 -93.14353) (xy 124.483095 -93.111079)
			(xy 124.442946 -93.07237) (xy 124.40886 -93.028227) (xy 124.381564 -92.979592) (xy 124.361641 -92.927501)
			(xy 124.349515 -92.873064) (xy 124.345444 -92.817442) (xy 119.438033 -92.817442) (xy 119.482901 -92.844825)
			(xy 119.525769 -92.8805) (xy 119.562986 -92.922037) (xy 119.593759 -92.96855) (xy 119.617431 -93.019047)
			(xy 119.633499 -93.072454) (xy 119.641619 -93.12763) (xy 119.642128 -93.155516) (xy 119.641619 -93.183402)
			(xy 119.633499 -93.238578) (xy 119.617431 -93.291985) (xy 119.593759 -93.342482) (xy 119.562986 -93.388995)
			(xy 119.525769 -93.430532) (xy 119.482901 -93.466207) (xy 119.435295 -93.495261) (xy 119.383966 -93.517073)
			(xy 119.330009 -93.531179) (xy 119.274572 -93.537279) (xy 119.218838 -93.535242) (xy 119.163995 -93.525112)
			(xy 119.111211 -93.507105) (xy 119.061611 -93.481604) (xy 119.016253 -93.449153) (xy 118.976104 -93.410444)
			(xy 118.942018 -93.366301) (xy 118.914722 -93.317666) (xy 118.894799 -93.265575) (xy 118.882673 -93.211138)
			(xy 118.878602 -93.155516) (xy 116.090604 -93.155516) (xy 116.097156 -93.162829) (xy 116.127929 -93.209342)
			(xy 116.151601 -93.259839) (xy 116.167669 -93.313246) (xy 116.175789 -93.368422) (xy 116.176298 -93.396308)
			(xy 116.175789 -93.424194) (xy 116.167669 -93.47937) (xy 116.151601 -93.532777) (xy 116.127929 -93.583274)
			(xy 116.097156 -93.629787) (xy 116.059939 -93.671324) (xy 116.017071 -93.706999) (xy 115.969465 -93.736053)
			(xy 115.939925 -93.748606) (xy 119.737884 -93.748606) (xy 119.741955 -93.692984) (xy 119.754081 -93.638547)
			(xy 119.774004 -93.586456) (xy 119.8013 -93.537821) (xy 119.835386 -93.493678) (xy 119.875535 -93.454969)
			(xy 119.920893 -93.422518) (xy 119.970493 -93.397017) (xy 120.023277 -93.37901) (xy 120.07812 -93.36888)
			(xy 120.133854 -93.366843) (xy 120.189291 -93.372943) (xy 120.243248 -93.387049) (xy 120.294577 -93.408861)
			(xy 120.342183 -93.437915) (xy 120.385051 -93.47359) (xy 120.422268 -93.515127) (xy 120.453041 -93.56164)
			(xy 120.476713 -93.612137) (xy 120.492781 -93.665544) (xy 120.500901 -93.72072) (xy 120.50141 -93.748606)
			(xy 121.975878 -93.748606) (xy 121.979949 -93.692984) (xy 121.992075 -93.638547) (xy 122.011998 -93.586456)
			(xy 122.039294 -93.537821) (xy 122.07338 -93.493678) (xy 122.113529 -93.454969) (xy 122.158887 -93.422518)
			(xy 122.208487 -93.397017) (xy 122.261271 -93.37901) (xy 122.316114 -93.36888) (xy 122.371848 -93.366843)
			(xy 122.427285 -93.372943) (xy 122.481242 -93.387049) (xy 122.532571 -93.408861) (xy 122.580177 -93.437915)
			(xy 122.623045 -93.47359) (xy 122.660262 -93.515127) (xy 122.691035 -93.56164) (xy 122.714707 -93.612137)
			(xy 122.730775 -93.665544) (xy 122.738895 -93.72072) (xy 122.739404 -93.748606) (xy 122.738895 -93.776492)
			(xy 122.730775 -93.831668) (xy 122.728178 -93.8403) (xy 125.868174 -93.8403) (xy 125.872245 -93.784678)
			(xy 125.884371 -93.730241) (xy 125.904294 -93.67815) (xy 125.93159 -93.629515) (xy 125.965676 -93.585372)
			(xy 126.005825 -93.546663) (xy 126.051183 -93.514212) (xy 126.100783 -93.488711) (xy 126.153567 -93.470704)
			(xy 126.20841 -93.460574) (xy 126.264144 -93.458537) (xy 126.319581 -93.464637) (xy 126.373538 -93.478743)
			(xy 126.424867 -93.500555) (xy 126.472473 -93.529609) (xy 126.515341 -93.565284) (xy 126.552558 -93.606821)
			(xy 126.583331 -93.653334) (xy 126.607003 -93.703831) (xy 126.623071 -93.757238) (xy 126.624604 -93.767656)
			(xy 133.93623 -93.767656) (xy 133.940301 -93.712034) (xy 133.952427 -93.657597) (xy 133.97235 -93.605506)
			(xy 133.999646 -93.556871) (xy 134.033732 -93.512728) (xy 134.073881 -93.474019) (xy 134.119239 -93.441568)
			(xy 134.168839 -93.416067) (xy 134.221623 -93.39806) (xy 134.276466 -93.38793) (xy 134.3322 -93.385893)
			(xy 134.387637 -93.391993) (xy 134.441594 -93.406099) (xy 134.492923 -93.427911) (xy 134.540529 -93.456965)
			(xy 134.583397 -93.49264) (xy 134.615655 -93.528642) (xy 139.708126 -93.528642) (xy 139.712197 -93.47302)
			(xy 139.724323 -93.418583) (xy 139.744246 -93.366492) (xy 139.771542 -93.317857) (xy 139.805628 -93.273714)
			(xy 139.845777 -93.235005) (xy 139.891135 -93.202554) (xy 139.940735 -93.177053) (xy 139.993519 -93.159046)
			(xy 140.048362 -93.148916) (xy 140.104096 -93.146879) (xy 140.159533 -93.152979) (xy 140.21349 -93.167085)
			(xy 140.264819 -93.188897) (xy 140.312425 -93.217951) (xy 140.355293 -93.253626) (xy 140.39251 -93.295163)
			(xy 140.423283 -93.341676) (xy 140.446955 -93.392173) (xy 140.463023 -93.44558) (xy 140.471143 -93.500756)
			(xy 140.471652 -93.528642) (xy 140.471143 -93.556528) (xy 140.463023 -93.611704) (xy 140.446955 -93.665111)
			(xy 140.423283 -93.715608) (xy 140.39251 -93.762121) (xy 140.355293 -93.803658) (xy 140.312425 -93.839333)
			(xy 140.264819 -93.868387) (xy 140.21349 -93.890199) (xy 140.159533 -93.904305) (xy 140.104096 -93.910405)
			(xy 140.048362 -93.908368) (xy 139.993519 -93.898238) (xy 139.940735 -93.880231) (xy 139.891135 -93.85473)
			(xy 139.845777 -93.822279) (xy 139.805628 -93.78357) (xy 139.771542 -93.739427) (xy 139.744246 -93.690792)
			(xy 139.724323 -93.638701) (xy 139.712197 -93.584264) (xy 139.708126 -93.528642) (xy 134.615655 -93.528642)
			(xy 134.620614 -93.534177) (xy 134.651387 -93.58069) (xy 134.675059 -93.631187) (xy 134.691127 -93.684594)
			(xy 134.699247 -93.73977) (xy 134.699756 -93.767656) (xy 134.699247 -93.795542) (xy 134.691127 -93.850718)
			(xy 134.675059 -93.904125) (xy 134.651387 -93.954622) (xy 134.620614 -94.001135) (xy 134.583397 -94.042672)
			(xy 134.540529 -94.078347) (xy 134.492923 -94.107401) (xy 134.441594 -94.129213) (xy 134.387637 -94.143319)
			(xy 134.3322 -94.149419) (xy 134.276466 -94.147382) (xy 134.221623 -94.137252) (xy 134.168839 -94.119245)
			(xy 134.119239 -94.093744) (xy 134.073881 -94.061293) (xy 134.033732 -94.022584) (xy 133.999646 -93.978441)
			(xy 133.97235 -93.929806) (xy 133.952427 -93.877715) (xy 133.940301 -93.823278) (xy 133.93623 -93.767656)
			(xy 126.624604 -93.767656) (xy 126.631191 -93.812414) (xy 126.6317 -93.8403) (xy 126.631191 -93.868186)
			(xy 126.623071 -93.923362) (xy 126.607003 -93.976769) (xy 126.583331 -94.027266) (xy 126.552558 -94.073779)
			(xy 126.515341 -94.115316) (xy 126.472473 -94.150991) (xy 126.424867 -94.180045) (xy 126.373538 -94.201857)
			(xy 126.319581 -94.215963) (xy 126.264144 -94.222063) (xy 126.20841 -94.220026) (xy 126.153567 -94.209896)
			(xy 126.100783 -94.191889) (xy 126.051183 -94.166388) (xy 126.005825 -94.133937) (xy 125.965676 -94.095228)
			(xy 125.93159 -94.051085) (xy 125.904294 -94.00245) (xy 125.884371 -93.950359) (xy 125.872245 -93.895922)
			(xy 125.868174 -93.8403) (xy 122.728178 -93.8403) (xy 122.714707 -93.885075) (xy 122.691035 -93.935572)
			(xy 122.660262 -93.982085) (xy 122.623045 -94.023622) (xy 122.580177 -94.059297) (xy 122.532571 -94.088351)
			(xy 122.481242 -94.110163) (xy 122.427285 -94.124269) (xy 122.371848 -94.130369) (xy 122.316114 -94.128332)
			(xy 122.261271 -94.118202) (xy 122.208487 -94.100195) (xy 122.158887 -94.074694) (xy 122.113529 -94.042243)
			(xy 122.07338 -94.003534) (xy 122.039294 -93.959391) (xy 122.011998 -93.910756) (xy 121.992075 -93.858665)
			(xy 121.979949 -93.804228) (xy 121.975878 -93.748606) (xy 120.50141 -93.748606) (xy 120.500901 -93.776492)
			(xy 120.492781 -93.831668) (xy 120.476713 -93.885075) (xy 120.453041 -93.935572) (xy 120.422268 -93.982085)
			(xy 120.385051 -94.023622) (xy 120.342183 -94.059297) (xy 120.294577 -94.088351) (xy 120.243248 -94.110163)
			(xy 120.189291 -94.124269) (xy 120.133854 -94.130369) (xy 120.07812 -94.128332) (xy 120.023277 -94.118202)
			(xy 119.970493 -94.100195) (xy 119.920893 -94.074694) (xy 119.875535 -94.042243) (xy 119.835386 -94.003534)
			(xy 119.8013 -93.959391) (xy 119.774004 -93.910756) (xy 119.754081 -93.858665) (xy 119.741955 -93.804228)
			(xy 119.737884 -93.748606) (xy 115.939925 -93.748606) (xy 115.918136 -93.757865) (xy 115.864179 -93.771971)
			(xy 115.808742 -93.778071) (xy 115.753008 -93.776034) (xy 115.698165 -93.765904) (xy 115.645381 -93.747897)
			(xy 115.595781 -93.722396) (xy 115.550423 -93.689945) (xy 115.510274 -93.651236) (xy 115.476188 -93.607093)
			(xy 115.448892 -93.558458) (xy 115.428969 -93.506367) (xy 115.416843 -93.45193) (xy 115.412772 -93.396308)
			(xy 107.166422 -93.396308) (xy 107.168187 -93.4083) (xy 107.168696 -93.436186) (xy 107.168187 -93.464072)
			(xy 107.160067 -93.519248) (xy 107.143999 -93.572655) (xy 107.120327 -93.623152) (xy 107.089554 -93.669665)
			(xy 107.052337 -93.711202) (xy 107.009469 -93.746877) (xy 106.961863 -93.775931) (xy 106.910534 -93.797743)
			(xy 106.856577 -93.811849) (xy 106.80114 -93.817949) (xy 106.745406 -93.815912) (xy 106.690563 -93.805782)
			(xy 106.637779 -93.787775) (xy 106.588179 -93.762274) (xy 106.542821 -93.729823) (xy 106.502672 -93.691114)
			(xy 106.468586 -93.646971) (xy 106.44129 -93.598336) (xy 106.421367 -93.546245) (xy 106.409241 -93.491808)
			(xy 106.40517 -93.436186) (xy 105.110076 -93.436186) (xy 105.11028 -93.447362) (xy 105.109771 -93.475248)
			(xy 105.101651 -93.530424) (xy 105.085583 -93.583831) (xy 105.061911 -93.634328) (xy 105.031138 -93.680841)
			(xy 104.993921 -93.722378) (xy 104.951053 -93.758053) (xy 104.903447 -93.787107) (xy 104.852118 -93.808919)
			(xy 104.798161 -93.823025) (xy 104.742724 -93.829125) (xy 104.68699 -93.827088) (xy 104.632147 -93.816958)
			(xy 104.579363 -93.798951) (xy 104.529763 -93.77345) (xy 104.484405 -93.740999) (xy 104.444256 -93.70229)
			(xy 104.41017 -93.658147) (xy 104.382874 -93.609512) (xy 104.362951 -93.557421) (xy 104.350825 -93.502984)
			(xy 104.346754 -93.447362) (xy 90.281206 -93.447362) (xy 89.798845 -94.24924) (xy 95.43618 -94.24924)
			(xy 95.440251 -94.193618) (xy 95.452377 -94.139181) (xy 95.4723 -94.08709) (xy 95.499596 -94.038455)
			(xy 95.533682 -93.994312) (xy 95.573831 -93.955603) (xy 95.619189 -93.923152) (xy 95.668789 -93.897651)
			(xy 95.721573 -93.879644) (xy 95.776416 -93.869514) (xy 95.83215 -93.867477) (xy 95.887587 -93.873577)
			(xy 95.941544 -93.887683) (xy 95.992873 -93.909495) (xy 96.040479 -93.938549) (xy 96.083347 -93.974224)
			(xy 96.120564 -94.015761) (xy 96.151337 -94.062274) (xy 96.175009 -94.112771) (xy 96.191077 -94.166178)
			(xy 96.199197 -94.221354) (xy 96.199706 -94.24924) (xy 96.199632 -94.253304) (xy 96.45218 -94.253304)
			(xy 96.456251 -94.197682) (xy 96.468377 -94.143245) (xy 96.4883 -94.091154) (xy 96.515596 -94.042519)
			(xy 96.549682 -93.998376) (xy 96.589831 -93.959667) (xy 96.635189 -93.927216) (xy 96.684789 -93.901715)
			(xy 96.737573 -93.883708) (xy 96.792416 -93.873578) (xy 96.84815 -93.871541) (xy 96.903587 -93.877641)
			(xy 96.957544 -93.891747) (xy 97.008873 -93.913559) (xy 97.056479 -93.942613) (xy 97.099347 -93.978288)
			(xy 97.136564 -94.019825) (xy 97.167337 -94.066338) (xy 97.177719 -94.088485) (xy 109.149614 -94.088485)
			(xy 109.149614 -94.028515) (xy 109.157442 -93.969058) (xy 109.172963 -93.911131) (xy 109.195912 -93.855726)
			(xy 109.225897 -93.80379) (xy 109.262405 -93.756213) (xy 109.30481 -93.713807) (xy 109.352387 -93.6773)
			(xy 109.404322 -93.647314) (xy 109.459727 -93.624364) (xy 109.517654 -93.608843) (xy 109.577111 -93.601014)
			(xy 109.607096 -93.600524) (xy 110.470696 -93.600524) (xy 110.500681 -93.601021) (xy 110.560138 -93.608848)
			(xy 110.618064 -93.624369) (xy 110.673469 -93.647318) (xy 110.725405 -93.677303) (xy 110.772982 -93.71381)
			(xy 110.815388 -93.756215) (xy 110.851895 -93.803792) (xy 110.88188 -93.855727) (xy 110.90483 -93.911132)
			(xy 110.920351 -93.969058) (xy 110.928179 -94.028515) (xy 110.928179 -94.088485) (xy 110.920351 -94.147942)
			(xy 110.90483 -94.205868) (xy 110.88188 -94.261273) (xy 110.851895 -94.313208) (xy 110.815388 -94.360785)
			(xy 110.772982 -94.40319) (xy 110.725405 -94.439697) (xy 110.673469 -94.469682) (xy 110.618064 -94.492631)
			(xy 110.584158 -94.501716) (xy 114.13439 -94.501716) (xy 114.138461 -94.446094) (xy 114.150587 -94.391657)
			(xy 114.17051 -94.339566) (xy 114.197806 -94.290931) (xy 114.231892 -94.246788) (xy 114.272041 -94.208079)
			(xy 114.317399 -94.175628) (xy 114.366999 -94.150127) (xy 114.419783 -94.13212) (xy 114.474626 -94.12199)
			(xy 114.53036 -94.119953) (xy 114.585797 -94.126053) (xy 114.639754 -94.140159) (xy 114.691083 -94.161971)
			(xy 114.738689 -94.191025) (xy 114.781557 -94.2267) (xy 114.818774 -94.268237) (xy 114.849547 -94.31475)
			(xy 114.873219 -94.365247) (xy 114.889287 -94.418654) (xy 114.89411 -94.451424) (xy 135.029192 -94.451424)
			(xy 135.033263 -94.395802) (xy 135.045389 -94.341365) (xy 135.065312 -94.289274) (xy 135.092608 -94.240639)
			(xy 135.126694 -94.196496) (xy 135.166843 -94.157787) (xy 135.212201 -94.125336) (xy 135.261801 -94.099835)
			(xy 135.314585 -94.081828) (xy 135.369428 -94.071698) (xy 135.425162 -94.069661) (xy 135.480599 -94.075761)
			(xy 135.534556 -94.089867) (xy 135.585885 -94.111679) (xy 135.633491 -94.140733) (xy 135.676359 -94.176408)
			(xy 135.713576 -94.217945) (xy 135.744349 -94.264458) (xy 135.768021 -94.314955) (xy 135.784089 -94.368362)
			(xy 135.792209 -94.423538) (xy 135.792718 -94.451424) (xy 135.792209 -94.47931) (xy 135.784089 -94.534486)
			(xy 135.768021 -94.587893) (xy 135.744349 -94.63839) (xy 135.722349 -94.671642) (xy 139.708126 -94.671642)
			(xy 139.712197 -94.61602) (xy 139.724323 -94.561583) (xy 139.744246 -94.509492) (xy 139.771542 -94.460857)
			(xy 139.805628 -94.416714) (xy 139.845777 -94.378005) (xy 139.891135 -94.345554) (xy 139.940735 -94.320053)
			(xy 139.993519 -94.302046) (xy 140.048362 -94.291916) (xy 140.104096 -94.289879) (xy 140.159533 -94.295979)
			(xy 140.21349 -94.310085) (xy 140.264819 -94.331897) (xy 140.312425 -94.360951) (xy 140.355293 -94.396626)
			(xy 140.39251 -94.438163) (xy 140.423283 -94.484676) (xy 140.446955 -94.535173) (xy 140.463023 -94.58858)
			(xy 140.471143 -94.643756) (xy 140.471652 -94.671642) (xy 140.471143 -94.699528) (xy 140.463023 -94.754704)
			(xy 140.446955 -94.808111) (xy 140.423283 -94.858608) (xy 140.39251 -94.905121) (xy 140.355293 -94.946658)
			(xy 140.312425 -94.982333) (xy 140.264819 -95.011387) (xy 140.21349 -95.033199) (xy 140.159533 -95.047305)
			(xy 140.104096 -95.053405) (xy 140.048362 -95.051368) (xy 139.993519 -95.041238) (xy 139.940735 -95.023231)
			(xy 139.891135 -94.99773) (xy 139.845777 -94.965279) (xy 139.805628 -94.92657) (xy 139.771542 -94.882427)
			(xy 139.744246 -94.833792) (xy 139.724323 -94.781701) (xy 139.712197 -94.727264) (xy 139.708126 -94.671642)
			(xy 135.722349 -94.671642) (xy 135.713576 -94.684903) (xy 135.676359 -94.72644) (xy 135.633491 -94.762115)
			(xy 135.585885 -94.791169) (xy 135.534556 -94.812981) (xy 135.480599 -94.827087) (xy 135.425162 -94.833187)
			(xy 135.369428 -94.83115) (xy 135.314585 -94.82102) (xy 135.261801 -94.803013) (xy 135.212201 -94.777512)
			(xy 135.166843 -94.745061) (xy 135.126694 -94.706352) (xy 135.092608 -94.662209) (xy 135.065312 -94.613574)
			(xy 135.045389 -94.561483) (xy 135.033263 -94.507046) (xy 135.029192 -94.451424) (xy 114.89411 -94.451424)
			(xy 114.897407 -94.47383) (xy 114.897916 -94.501716) (xy 114.897407 -94.529602) (xy 114.889287 -94.584778)
			(xy 114.873219 -94.638185) (xy 114.849547 -94.688682) (xy 114.818774 -94.735195) (xy 114.781557 -94.776732)
			(xy 114.738689 -94.812407) (xy 114.691083 -94.841461) (xy 114.639754 -94.863273) (xy 114.585797 -94.877379)
			(xy 114.53036 -94.883479) (xy 114.474626 -94.881442) (xy 114.419783 -94.871312) (xy 114.366999 -94.853305)
			(xy 114.317399 -94.827804) (xy 114.272041 -94.795353) (xy 114.231892 -94.756644) (xy 114.197806 -94.712501)
			(xy 114.17051 -94.663866) (xy 114.150587 -94.611775) (xy 114.138461 -94.557338) (xy 114.13439 -94.501716)
			(xy 110.584158 -94.501716) (xy 110.560138 -94.508152) (xy 110.500681 -94.515979) (xy 110.470696 -94.516448)
			(xy 109.607096 -94.516448) (xy 109.577111 -94.515986) (xy 109.517654 -94.508157) (xy 109.459727 -94.492636)
			(xy 109.404322 -94.469686) (xy 109.352387 -94.4397) (xy 109.30481 -94.403193) (xy 109.262405 -94.360787)
			(xy 109.225897 -94.31321) (xy 109.195912 -94.261274) (xy 109.172963 -94.205869) (xy 109.157442 -94.147942)
			(xy 109.149614 -94.088485) (xy 97.177719 -94.088485) (xy 97.191009 -94.116835) (xy 97.207077 -94.170242)
			(xy 97.215197 -94.225418) (xy 97.215706 -94.253304) (xy 97.215197 -94.28119) (xy 97.207077 -94.336366)
			(xy 97.191009 -94.389773) (xy 97.167337 -94.44027) (xy 97.136564 -94.486783) (xy 97.099347 -94.52832)
			(xy 97.056479 -94.563995) (xy 97.008873 -94.593049) (xy 96.957544 -94.614861) (xy 96.903587 -94.628967)
			(xy 96.84815 -94.635067) (xy 96.792416 -94.63303) (xy 96.737573 -94.6229) (xy 96.684789 -94.604893)
			(xy 96.635189 -94.579392) (xy 96.589831 -94.546941) (xy 96.549682 -94.508232) (xy 96.515596 -94.464089)
			(xy 96.4883 -94.415454) (xy 96.468377 -94.363363) (xy 96.456251 -94.308926) (xy 96.45218 -94.253304)
			(xy 96.199632 -94.253304) (xy 96.199197 -94.277126) (xy 96.191077 -94.332302) (xy 96.175009 -94.385709)
			(xy 96.151337 -94.436206) (xy 96.120564 -94.482719) (xy 96.083347 -94.524256) (xy 96.040479 -94.559931)
			(xy 95.992873 -94.588985) (xy 95.941544 -94.610797) (xy 95.887587 -94.624903) (xy 95.83215 -94.631003)
			(xy 95.776416 -94.628966) (xy 95.721573 -94.618836) (xy 95.668789 -94.600829) (xy 95.619189 -94.575328)
			(xy 95.573831 -94.542877) (xy 95.533682 -94.504168) (xy 95.499596 -94.460025) (xy 95.4723 -94.41139)
			(xy 95.452377 -94.359299) (xy 95.440251 -94.304862) (xy 95.43618 -94.24924) (xy 89.798845 -94.24924)
			(xy 89.564464 -94.638876) (xy 89.562686 -94.647766) (xy 89.562686 -94.64802) (xy 89.557051 -94.67373)
			(xy 89.539657 -94.723406) (xy 89.515608 -94.770223) (xy 89.485357 -94.813294) (xy 89.449478 -94.851804)
			(xy 89.429336 -94.868746) (xy 89.422478 -94.874334) (xy 89.412119 -94.891606) (xy 119.737884 -94.891606)
			(xy 119.741955 -94.835984) (xy 119.754081 -94.781547) (xy 119.774004 -94.729456) (xy 119.8013 -94.680821)
			(xy 119.835386 -94.636678) (xy 119.875535 -94.597969) (xy 119.920893 -94.565518) (xy 119.970493 -94.540017)
			(xy 120.023277 -94.52201) (xy 120.07812 -94.51188) (xy 120.133854 -94.509843) (xy 120.189291 -94.515943)
			(xy 120.243248 -94.530049) (xy 120.294577 -94.551861) (xy 120.342183 -94.580915) (xy 120.385051 -94.61659)
			(xy 120.422268 -94.658127) (xy 120.453041 -94.70464) (xy 120.476713 -94.755137) (xy 120.492781 -94.808544)
			(xy 120.500901 -94.86372) (xy 120.50141 -94.891606) (xy 121.975878 -94.891606) (xy 121.979949 -94.835984)
			(xy 121.992075 -94.781547) (xy 122.011998 -94.729456) (xy 122.039294 -94.680821) (xy 122.07338 -94.636678)
			(xy 122.113529 -94.597969) (xy 122.158887 -94.565518) (xy 122.208487 -94.540017) (xy 122.261271 -94.52201)
			(xy 122.316114 -94.51188) (xy 122.371848 -94.509843) (xy 122.427285 -94.515943) (xy 122.481242 -94.530049)
			(xy 122.532571 -94.551861) (xy 122.580177 -94.580915) (xy 122.623045 -94.61659) (xy 122.660262 -94.658127)
			(xy 122.691035 -94.70464) (xy 122.714707 -94.755137) (xy 122.730775 -94.808544) (xy 122.738895 -94.86372)
			(xy 122.739404 -94.891606) (xy 124.302772 -94.891606) (xy 124.306843 -94.835984) (xy 124.318969 -94.781547)
			(xy 124.338892 -94.729456) (xy 124.366188 -94.680821) (xy 124.400274 -94.636678) (xy 124.440423 -94.597969)
			(xy 124.485781 -94.565518) (xy 124.535381 -94.540017) (xy 124.588165 -94.52201) (xy 124.643008 -94.51188)
			(xy 124.698742 -94.509843) (xy 124.754179 -94.515943) (xy 124.808136 -94.530049) (xy 124.859465 -94.551861)
			(xy 124.907071 -94.580915) (xy 124.949939 -94.61659) (xy 124.987156 -94.658127) (xy 125.017929 -94.70464)
			(xy 125.041601 -94.755137) (xy 125.057669 -94.808544) (xy 125.065789 -94.86372) (xy 125.066298 -94.891606)
			(xy 125.065789 -94.919492) (xy 125.057669 -94.974668) (xy 125.041601 -95.028075) (xy 125.017929 -95.078572)
			(xy 124.987156 -95.125085) (xy 124.949939 -95.166622) (xy 124.907071 -95.202297) (xy 124.859465 -95.231351)
			(xy 124.808136 -95.253163) (xy 124.754179 -95.267269) (xy 124.698742 -95.273369) (xy 124.643008 -95.271332)
			(xy 124.588165 -95.261202) (xy 124.535381 -95.243195) (xy 124.485781 -95.217694) (xy 124.440423 -95.185243)
			(xy 124.400274 -95.146534) (xy 124.366188 -95.102391) (xy 124.338892 -95.053756) (xy 124.318969 -95.001665)
			(xy 124.306843 -94.947228) (xy 124.302772 -94.891606) (xy 122.739404 -94.891606) (xy 122.738895 -94.919492)
			(xy 122.730775 -94.974668) (xy 122.714707 -95.028075) (xy 122.691035 -95.078572) (xy 122.660262 -95.125085)
			(xy 122.623045 -95.166622) (xy 122.580177 -95.202297) (xy 122.532571 -95.231351) (xy 122.481242 -95.253163)
			(xy 122.427285 -95.267269) (xy 122.371848 -95.273369) (xy 122.316114 -95.271332) (xy 122.261271 -95.261202)
			(xy 122.208487 -95.243195) (xy 122.158887 -95.217694) (xy 122.113529 -95.185243) (xy 122.07338 -95.146534)
			(xy 122.039294 -95.102391) (xy 122.011998 -95.053756) (xy 121.992075 -95.001665) (xy 121.979949 -94.947228)
			(xy 121.975878 -94.891606) (xy 120.50141 -94.891606) (xy 120.500901 -94.919492) (xy 120.492781 -94.974668)
			(xy 120.476713 -95.028075) (xy 120.453041 -95.078572) (xy 120.422268 -95.125085) (xy 120.385051 -95.166622)
			(xy 120.342183 -95.202297) (xy 120.294577 -95.231351) (xy 120.243248 -95.253163) (xy 120.189291 -95.267269)
			(xy 120.133854 -95.273369) (xy 120.07812 -95.271332) (xy 120.023277 -95.261202) (xy 119.970493 -95.243195)
			(xy 119.920893 -95.217694) (xy 119.875535 -95.185243) (xy 119.835386 -95.146534) (xy 119.8013 -95.102391)
			(xy 119.774004 -95.053756) (xy 119.754081 -95.001665) (xy 119.741955 -94.947228) (xy 119.737884 -94.891606)
			(xy 89.412119 -94.891606) (xy 89.15527 -95.31985) (xy 89.150698 -95.32747) (xy 89.147142 -95.344742)
			(xy 89.149174 -95.357696) (xy 89.169748 -95.429324) (xy 89.173812 -95.435674) (xy 89.179908 -95.445834)
			(xy 89.18448 -95.450152) (xy 89.19591 -95.461582) (xy 89.202768 -95.465138) (xy 89.228545 -95.47948)
			(xy 89.275729 -95.51488) (xy 89.3169 -95.557122) (xy 89.351076 -95.605199) (xy 89.377442 -95.657965)
			(xy 89.395369 -95.714162) (xy 89.404429 -95.772448) (xy 89.404952 -95.801942) (xy 90.674696 -95.801942)
			(xy 90.678767 -95.74632) (xy 90.690893 -95.691883) (xy 90.710816 -95.639792) (xy 90.738112 -95.591157)
			(xy 90.772198 -95.547014) (xy 90.812347 -95.508305) (xy 90.857705 -95.475854) (xy 90.907305 -95.450353)
			(xy 90.960089 -95.432346) (xy 91.014932 -95.422216) (xy 91.070666 -95.420179) (xy 91.126103 -95.426279)
			(xy 91.18006 -95.440385) (xy 91.231389 -95.462197) (xy 91.278995 -95.491251) (xy 91.321863 -95.526926)
			(xy 91.35908 -95.568463) (xy 91.389853 -95.614976) (xy 91.413525 -95.665473) (xy 91.429593 -95.71888)
			(xy 91.437713 -95.774056) (xy 91.438222 -95.801942) (xy 92.715586 -95.801942) (xy 92.719657 -95.74632)
			(xy 92.731783 -95.691883) (xy 92.751706 -95.639792) (xy 92.779002 -95.591157) (xy 92.813088 -95.547014)
			(xy 92.853237 -95.508305) (xy 92.898595 -95.475854) (xy 92.948195 -95.450353) (xy 93.000979 -95.432346)
			(xy 93.055822 -95.422216) (xy 93.111556 -95.420179) (xy 93.166993 -95.426279) (xy 93.22095 -95.440385)
			(xy 93.272279 -95.462197) (xy 93.319885 -95.491251) (xy 93.362753 -95.526926) (xy 93.39997 -95.568463)
			(xy 93.430743 -95.614976) (xy 93.454415 -95.665473) (xy 93.470483 -95.71888) (xy 93.478603 -95.774056)
			(xy 93.479112 -95.801942) (xy 93.721426 -95.801942) (xy 93.725497 -95.74632) (xy 93.737623 -95.691883)
			(xy 93.757546 -95.639792) (xy 93.784842 -95.591157) (xy 93.818928 -95.547014) (xy 93.859077 -95.508305)
			(xy 93.904435 -95.475854) (xy 93.954035 -95.450353) (xy 94.006819 -95.432346) (xy 94.061662 -95.422216)
			(xy 94.117396 -95.420179) (xy 94.172833 -95.426279) (xy 94.22679 -95.440385) (xy 94.278119 -95.462197)
			(xy 94.325725 -95.491251) (xy 94.368593 -95.526926) (xy 94.40581 -95.568463) (xy 94.436583 -95.614976)
			(xy 94.460255 -95.665473) (xy 94.476323 -95.71888) (xy 94.484443 -95.774056) (xy 94.484952 -95.801942)
			(xy 94.484443 -95.829828) (xy 94.477301 -95.878357) (xy 99.120179 -95.878357) (xy 99.127934 -95.82441)
			(xy 99.143288 -95.772116) (xy 99.165927 -95.722539) (xy 99.195392 -95.676689) (xy 99.231081 -95.635498)
			(xy 99.27227 -95.599806) (xy 99.318118 -95.570339) (xy 99.367693 -95.547696) (xy 99.419986 -95.53234)
			(xy 99.473933 -95.524581) (xy 99.528434 -95.524579) (xy 99.582381 -95.532332) (xy 99.634675 -95.547685)
			(xy 99.684253 -95.570323) (xy 99.730104 -95.599786) (xy 99.771295 -95.635475) (xy 99.806988 -95.676662)
			(xy 99.836457 -95.72251) (xy 99.8591 -95.772085) (xy 99.874458 -95.824377) (xy 99.882218 -95.878323)
			(xy 99.882706 -95.905574) (xy 99.882706 -95.906082) (xy 99.882623 -95.916454) (xy 99.881481 -95.937166)
			(xy 99.88042 -95.947484) (xy 99.879281 -95.962029) (xy 99.884489 -95.990727) (xy 99.897586 -96.016789)
			(xy 99.917505 -96.038095) (xy 99.942628 -96.052912) (xy 99.970911 -96.060037) (xy 100.000056 -96.05889)
			(xy 100.014024 -96.054672) (xy 100.043635 -96.045328) (xy 100.1049 -96.03524) (xy 100.135944 -96.034606)
			(xy 100.136198 -96.034606) (xy 119.737884 -96.034606) (xy 119.741955 -95.978984) (xy 119.754081 -95.924547)
			(xy 119.774004 -95.872456) (xy 119.8013 -95.823821) (xy 119.835386 -95.779678) (xy 119.875535 -95.740969)
			(xy 119.920893 -95.708518) (xy 119.970493 -95.683017) (xy 120.023277 -95.66501) (xy 120.07812 -95.65488)
			(xy 120.133854 -95.652843) (xy 120.189291 -95.658943) (xy 120.243248 -95.673049) (xy 120.294577 -95.694861)
			(xy 120.342183 -95.723915) (xy 120.385051 -95.75959) (xy 120.422268 -95.801127) (xy 120.453041 -95.84764)
			(xy 120.476713 -95.898137) (xy 120.492781 -95.951544) (xy 120.500901 -96.00672) (xy 120.50141 -96.034606)
			(xy 121.975878 -96.034606) (xy 121.979949 -95.978984) (xy 121.992075 -95.924547) (xy 122.011998 -95.872456)
			(xy 122.039294 -95.823821) (xy 122.07338 -95.779678) (xy 122.113529 -95.740969) (xy 122.158887 -95.708518)
			(xy 122.208487 -95.683017) (xy 122.261271 -95.66501) (xy 122.316114 -95.65488) (xy 122.371848 -95.652843)
			(xy 122.427285 -95.658943) (xy 122.481242 -95.673049) (xy 122.532571 -95.694861) (xy 122.580177 -95.723915)
			(xy 122.623045 -95.75959) (xy 122.660262 -95.801127) (xy 122.691035 -95.84764) (xy 122.71224 -95.892874)
			(xy 125.538482 -95.892874) (xy 125.542553 -95.837252) (xy 125.554679 -95.782815) (xy 125.574602 -95.730724)
			(xy 125.601898 -95.682089) (xy 125.635984 -95.637946) (xy 125.676133 -95.599237) (xy 125.721491 -95.566786)
			(xy 125.771091 -95.541285) (xy 125.823875 -95.523278) (xy 125.878718 -95.513148) (xy 125.934452 -95.511111)
			(xy 125.989889 -95.517211) (xy 125.999593 -95.519748) (xy 134.274558 -95.519748) (xy 134.278629 -95.464126)
			(xy 134.290755 -95.409689) (xy 134.310678 -95.357598) (xy 134.337974 -95.308963) (xy 134.37206 -95.26482)
			(xy 134.412209 -95.226111) (xy 134.457567 -95.19366) (xy 134.507167 -95.168159) (xy 134.559951 -95.150152)
			(xy 134.614794 -95.140022) (xy 134.670528 -95.137985) (xy 134.725965 -95.144085) (xy 134.779922 -95.158191)
			(xy 134.819642 -95.17507) (xy 145.281648 -95.17507) (xy 145.285719 -95.119448) (xy 145.297845 -95.065011)
			(xy 145.317768 -95.01292) (xy 145.345064 -94.964285) (xy 145.37915 -94.920142) (xy 145.419299 -94.881433)
			(xy 145.464657 -94.848982) (xy 145.514257 -94.823481) (xy 145.567041 -94.805474) (xy 145.621884 -94.795344)
			(xy 145.677618 -94.793307) (xy 145.733055 -94.799407) (xy 145.787012 -94.813513) (xy 145.838341 -94.835325)
			(xy 145.885947 -94.864379) (xy 145.928815 -94.900054) (xy 145.966032 -94.941591) (xy 145.996805 -94.988104)
			(xy 146.020477 -95.038601) (xy 146.036545 -95.092008) (xy 146.044665 -95.147184) (xy 146.045174 -95.17507)
			(xy 146.044665 -95.202956) (xy 146.036545 -95.258132) (xy 146.020477 -95.311539) (xy 145.996805 -95.362036)
			(xy 145.966032 -95.408549) (xy 145.928815 -95.450086) (xy 145.885947 -95.485761) (xy 145.838341 -95.514815)
			(xy 145.787012 -95.536627) (xy 145.733055 -95.550733) (xy 145.677618 -95.556833) (xy 145.621884 -95.554796)
			(xy 145.567041 -95.544666) (xy 145.514257 -95.526659) (xy 145.464657 -95.501158) (xy 145.419299 -95.468707)
			(xy 145.37915 -95.429998) (xy 145.345064 -95.385855) (xy 145.317768 -95.33722) (xy 145.297845 -95.285129)
			(xy 145.285719 -95.230692) (xy 145.281648 -95.17507) (xy 134.819642 -95.17507) (xy 134.831251 -95.180003)
			(xy 134.878857 -95.209057) (xy 134.921725 -95.244732) (xy 134.958942 -95.286269) (xy 134.989715 -95.332782)
			(xy 135.013387 -95.383279) (xy 135.029455 -95.436686) (xy 135.037575 -95.491862) (xy 135.038084 -95.519748)
			(xy 135.037575 -95.547634) (xy 135.029455 -95.60281) (xy 135.013387 -95.656217) (xy 134.989715 -95.706714)
			(xy 134.958942 -95.753227) (xy 134.921725 -95.794764) (xy 134.897839 -95.814642) (xy 139.708126 -95.814642)
			(xy 139.712197 -95.75902) (xy 139.724323 -95.704583) (xy 139.744246 -95.652492) (xy 139.771542 -95.603857)
			(xy 139.805628 -95.559714) (xy 139.845777 -95.521005) (xy 139.891135 -95.488554) (xy 139.940735 -95.463053)
			(xy 139.993519 -95.445046) (xy 140.048362 -95.434916) (xy 140.104096 -95.432879) (xy 140.159533 -95.438979)
			(xy 140.21349 -95.453085) (xy 140.264819 -95.474897) (xy 140.312425 -95.503951) (xy 140.355293 -95.539626)
			(xy 140.39251 -95.581163) (xy 140.423283 -95.627676) (xy 140.446955 -95.678173) (xy 140.463023 -95.73158)
			(xy 140.471143 -95.786756) (xy 140.471652 -95.814642) (xy 140.471143 -95.842528) (xy 140.463023 -95.897704)
			(xy 140.446955 -95.951111) (xy 140.423283 -96.001608) (xy 140.39251 -96.048121) (xy 140.355293 -96.089658)
			(xy 140.351856 -96.092518) (xy 144.382234 -96.092518) (xy 144.386305 -96.036896) (xy 144.398431 -95.982459)
			(xy 144.418354 -95.930368) (xy 144.44565 -95.881733) (xy 144.479736 -95.83759) (xy 144.519885 -95.798881)
			(xy 144.565243 -95.76643) (xy 144.614843 -95.740929) (xy 144.667627 -95.722922) (xy 144.72247 -95.712792)
			(xy 144.778204 -95.710755) (xy 144.833641 -95.716855) (xy 144.887598 -95.730961) (xy 144.938927 -95.752773)
			(xy 144.986533 -95.781827) (xy 145.029401 -95.817502) (xy 145.066618 -95.859039) (xy 145.097391 -95.905552)
			(xy 145.121063 -95.956049) (xy 145.137131 -96.009456) (xy 145.145251 -96.064632) (xy 145.14576 -96.092518)
			(xy 145.145251 -96.120404) (xy 145.137131 -96.17558) (xy 145.121063 -96.228987) (xy 145.097391 -96.279484)
			(xy 145.066618 -96.325997) (xy 145.029401 -96.367534) (xy 144.986533 -96.403209) (xy 144.938927 -96.432263)
			(xy 144.887598 -96.454075) (xy 144.833641 -96.468181) (xy 144.778204 -96.474281) (xy 144.72247 -96.472244)
			(xy 144.667627 -96.462114) (xy 144.614843 -96.444107) (xy 144.565243 -96.418606) (xy 144.519885 -96.386155)
			(xy 144.479736 -96.347446) (xy 144.44565 -96.303303) (xy 144.418354 -96.254668) (xy 144.398431 -96.202577)
			(xy 144.386305 -96.14814) (xy 144.382234 -96.092518) (xy 140.351856 -96.092518) (xy 140.312425 -96.125333)
			(xy 140.264819 -96.154387) (xy 140.21349 -96.176199) (xy 140.159533 -96.190305) (xy 140.104096 -96.196405)
			(xy 140.048362 -96.194368) (xy 139.993519 -96.184238) (xy 139.940735 -96.166231) (xy 139.891135 -96.14073)
			(xy 139.845777 -96.108279) (xy 139.805628 -96.06957) (xy 139.771542 -96.025427) (xy 139.744246 -95.976792)
			(xy 139.724323 -95.924701) (xy 139.712197 -95.870264) (xy 139.708126 -95.814642) (xy 134.897839 -95.814642)
			(xy 134.878857 -95.830439) (xy 134.831251 -95.859493) (xy 134.779922 -95.881305) (xy 134.725965 -95.895411)
			(xy 134.670528 -95.901511) (xy 134.614794 -95.899474) (xy 134.559951 -95.889344) (xy 134.507167 -95.871337)
			(xy 134.457567 -95.845836) (xy 134.412209 -95.813385) (xy 134.37206 -95.774676) (xy 134.337974 -95.730533)
			(xy 134.310678 -95.681898) (xy 134.290755 -95.629807) (xy 134.278629 -95.57537) (xy 134.274558 -95.519748)
			(xy 125.999593 -95.519748) (xy 126.043846 -95.531317) (xy 126.095175 -95.553129) (xy 126.142781 -95.582183)
			(xy 126.185649 -95.617858) (xy 126.222866 -95.659395) (xy 126.253639 -95.705908) (xy 126.277311 -95.756405)
			(xy 126.293379 -95.809812) (xy 126.301499 -95.864988) (xy 126.302008 -95.892874) (xy 126.301499 -95.92076)
			(xy 126.293379 -95.975936) (xy 126.277311 -96.029343) (xy 126.253639 -96.07984) (xy 126.222866 -96.126353)
			(xy 126.185649 -96.16789) (xy 126.142781 -96.203565) (xy 126.095175 -96.232619) (xy 126.043846 -96.254431)
			(xy 125.989889 -96.268537) (xy 125.934452 -96.274637) (xy 125.878718 -96.2726) (xy 125.823875 -96.26247)
			(xy 125.771091 -96.244463) (xy 125.721491 -96.218962) (xy 125.676133 -96.186511) (xy 125.635984 -96.147802)
			(xy 125.601898 -96.103659) (xy 125.574602 -96.055024) (xy 125.554679 -96.002933) (xy 125.542553 -95.948496)
			(xy 125.538482 -95.892874) (xy 122.71224 -95.892874) (xy 122.714707 -95.898137) (xy 122.730775 -95.951544)
			(xy 122.738895 -96.00672) (xy 122.739404 -96.034606) (xy 122.738895 -96.062492) (xy 122.730775 -96.117668)
			(xy 122.714707 -96.171075) (xy 122.691035 -96.221572) (xy 122.660262 -96.268085) (xy 122.623045 -96.309622)
			(xy 122.580177 -96.345297) (xy 122.532571 -96.374351) (xy 122.481242 -96.396163) (xy 122.427285 -96.410269)
			(xy 122.371848 -96.416369) (xy 122.316114 -96.414332) (xy 122.261271 -96.404202) (xy 122.208487 -96.386195)
			(xy 122.158887 -96.360694) (xy 122.113529 -96.328243) (xy 122.07338 -96.289534) (xy 122.039294 -96.245391)
			(xy 122.011998 -96.196756) (xy 121.992075 -96.144665) (xy 121.979949 -96.090228) (xy 121.975878 -96.034606)
			(xy 120.50141 -96.034606) (xy 120.500901 -96.062492) (xy 120.492781 -96.117668) (xy 120.476713 -96.171075)
			(xy 120.453041 -96.221572) (xy 120.422268 -96.268085) (xy 120.385051 -96.309622) (xy 120.342183 -96.345297)
			(xy 120.294577 -96.374351) (xy 120.243248 -96.396163) (xy 120.189291 -96.410269) (xy 120.133854 -96.416369)
			(xy 120.07812 -96.414332) (xy 120.023277 -96.404202) (xy 119.970493 -96.386195) (xy 119.920893 -96.360694)
			(xy 119.875535 -96.328243) (xy 119.835386 -96.289534) (xy 119.8013 -96.245391) (xy 119.774004 -96.196756)
			(xy 119.754081 -96.144665) (xy 119.741955 -96.090228) (xy 119.737884 -96.034606) (xy 100.136198 -96.034606)
			(xy 100.163449 -96.035076) (xy 100.217397 -96.042832) (xy 100.269692 -96.058187) (xy 100.319269 -96.080827)
			(xy 100.36512 -96.110293) (xy 100.40631 -96.145984) (xy 100.442002 -96.187174) (xy 100.471469 -96.233024)
			(xy 100.494111 -96.282601) (xy 100.509466 -96.334895) (xy 100.517224 -96.388843) (xy 100.517225 -96.429322)
			(xy 113.492534 -96.429322) (xy 113.49302 -96.402071) (xy 113.500776 -96.348123) (xy 113.516131 -96.295828)
			(xy 113.538773 -96.246251) (xy 113.568239 -96.200401) (xy 113.60393 -96.15921) (xy 113.645121 -96.123519)
			(xy 113.690971 -96.094053) (xy 113.740548 -96.071411) (xy 113.792843 -96.056056) (xy 113.846791 -96.0483)
			(xy 113.901293 -96.0483) (xy 113.955241 -96.056056) (xy 114.007536 -96.071411) (xy 114.057113 -96.094053)
			(xy 114.102963 -96.123519) (xy 114.144154 -96.15921) (xy 114.179845 -96.200401) (xy 114.209311 -96.246251)
			(xy 114.231953 -96.295828) (xy 114.247308 -96.348123) (xy 114.255064 -96.402071) (xy 114.25555 -96.429322)
			(xy 114.255339 -96.440498) (xy 128.268982 -96.440498) (xy 128.273053 -96.384876) (xy 128.285179 -96.330439)
			(xy 128.305102 -96.278348) (xy 128.332398 -96.229713) (xy 128.366484 -96.18557) (xy 128.406633 -96.146861)
			(xy 128.451991 -96.11441) (xy 128.501591 -96.088909) (xy 128.554375 -96.070902) (xy 128.609218 -96.060772)
			(xy 128.664952 -96.058735) (xy 128.720389 -96.064835) (xy 128.774346 -96.078941) (xy 128.825675 -96.100753)
			(xy 128.873281 -96.129807) (xy 128.916149 -96.165482) (xy 128.953366 -96.207019) (xy 128.984139 -96.253532)
			(xy 129.007811 -96.304029) (xy 129.023879 -96.357436) (xy 129.031999 -96.412612) (xy 129.032508 -96.440498)
			(xy 129.031999 -96.468384) (xy 129.023879 -96.52356) (xy 129.007811 -96.576967) (xy 128.984139 -96.627464)
			(xy 128.953366 -96.673977) (xy 128.920869 -96.710246) (xy 134.734044 -96.710246) (xy 134.738115 -96.654624)
			(xy 134.750241 -96.600187) (xy 134.770164 -96.548096) (xy 134.79746 -96.499461) (xy 134.831546 -96.455318)
			(xy 134.871695 -96.416609) (xy 134.917053 -96.384158) (xy 134.966653 -96.358657) (xy 135.019437 -96.34065)
			(xy 135.07428 -96.33052) (xy 135.130014 -96.328483) (xy 135.185451 -96.334583) (xy 135.239408 -96.348689)
			(xy 135.290737 -96.370501) (xy 135.338343 -96.399555) (xy 135.381211 -96.43523) (xy 135.418428 -96.476767)
			(xy 135.449201 -96.52328) (xy 135.472873 -96.573777) (xy 135.488941 -96.627184) (xy 135.497061 -96.68236)
			(xy 135.49757 -96.710246) (xy 135.497061 -96.738132) (xy 135.488941 -96.793308) (xy 135.472873 -96.846715)
			(xy 135.449201 -96.897212) (xy 135.418428 -96.943725) (xy 135.405958 -96.957642) (xy 139.708126 -96.957642)
			(xy 139.712197 -96.90202) (xy 139.724323 -96.847583) (xy 139.744246 -96.795492) (xy 139.771542 -96.746857)
			(xy 139.805628 -96.702714) (xy 139.845777 -96.664005) (xy 139.891135 -96.631554) (xy 139.940735 -96.606053)
			(xy 139.993519 -96.588046) (xy 140.048362 -96.577916) (xy 140.104096 -96.575879) (xy 140.159533 -96.581979)
			(xy 140.21349 -96.596085) (xy 140.264819 -96.617897) (xy 140.312425 -96.646951) (xy 140.355293 -96.682626)
			(xy 140.39251 -96.724163) (xy 140.423283 -96.770676) (xy 140.446955 -96.821173) (xy 140.463023 -96.87458)
			(xy 140.471143 -96.929756) (xy 140.471652 -96.957642) (xy 140.471143 -96.985528) (xy 140.463023 -97.040704)
			(xy 140.446955 -97.094111) (xy 140.423283 -97.144608) (xy 140.39251 -97.191121) (xy 140.355293 -97.232658)
			(xy 140.312425 -97.268333) (xy 140.264819 -97.297387) (xy 140.21349 -97.319199) (xy 140.159533 -97.333305)
			(xy 140.104096 -97.339405) (xy 140.048362 -97.337368) (xy 139.993519 -97.327238) (xy 139.940735 -97.309231)
			(xy 139.891135 -97.28373) (xy 139.845777 -97.251279) (xy 139.805628 -97.21257) (xy 139.771542 -97.168427)
			(xy 139.744246 -97.119792) (xy 139.724323 -97.067701) (xy 139.712197 -97.013264) (xy 139.708126 -96.957642)
			(xy 135.405958 -96.957642) (xy 135.381211 -96.985262) (xy 135.338343 -97.020937) (xy 135.290737 -97.049991)
			(xy 135.239408 -97.071803) (xy 135.185451 -97.085909) (xy 135.130014 -97.092009) (xy 135.07428 -97.089972)
			(xy 135.019437 -97.079842) (xy 134.966653 -97.061835) (xy 134.917053 -97.036334) (xy 134.871695 -97.003883)
			(xy 134.831546 -96.965174) (xy 134.79746 -96.921031) (xy 134.770164 -96.872396) (xy 134.750241 -96.820305)
			(xy 134.738115 -96.765868) (xy 134.734044 -96.710246) (xy 128.920869 -96.710246) (xy 128.916149 -96.715514)
			(xy 128.873281 -96.751189) (xy 128.825675 -96.780243) (xy 128.774346 -96.802055) (xy 128.720389 -96.816161)
			(xy 128.664952 -96.822261) (xy 128.609218 -96.820224) (xy 128.554375 -96.810094) (xy 128.501591 -96.792087)
			(xy 128.451991 -96.766586) (xy 128.406633 -96.734135) (xy 128.366484 -96.695426) (xy 128.332398 -96.651283)
			(xy 128.305102 -96.602648) (xy 128.285179 -96.550557) (xy 128.273053 -96.49612) (xy 128.268982 -96.440498)
			(xy 114.255339 -96.440498) (xy 114.255019 -96.457484) (xy 114.246741 -96.513196) (xy 114.230369 -96.567087)
			(xy 114.206258 -96.617989) (xy 114.17493 -96.664796) (xy 114.137067 -96.706494) (xy 114.115596 -96.724724)
			(xy 114.106873 -96.732498) (xy 114.097078 -96.753683) (xy 114.0968 -96.765364) (xy 114.099086 -96.857058)
			(xy 114.109754 -96.877632) (xy 114.119152 -96.884744) (xy 114.142549 -96.902905) (xy 114.184018 -96.945187)
			(xy 114.218455 -96.993369) (xy 114.245034 -97.046293) (xy 114.263115 -97.102689) (xy 114.272264 -97.161202)
			(xy 114.272573 -97.177606) (xy 119.737884 -97.177606) (xy 119.741955 -97.121984) (xy 119.754081 -97.067547)
			(xy 119.774004 -97.015456) (xy 119.8013 -96.966821) (xy 119.835386 -96.922678) (xy 119.875535 -96.883969)
			(xy 119.920893 -96.851518) (xy 119.970493 -96.826017) (xy 120.023277 -96.80801) (xy 120.07812 -96.79788)
			(xy 120.133854 -96.795843) (xy 120.189291 -96.801943) (xy 120.243248 -96.816049) (xy 120.294577 -96.837861)
			(xy 120.342183 -96.866915) (xy 120.385051 -96.90259) (xy 120.422268 -96.944127) (xy 120.453041 -96.99064)
			(xy 120.476713 -97.041137) (xy 120.492781 -97.094544) (xy 120.500901 -97.14972) (xy 120.50141 -97.177606)
			(xy 121.975878 -97.177606) (xy 121.979949 -97.121984) (xy 121.992075 -97.067547) (xy 122.011998 -97.015456)
			(xy 122.039294 -96.966821) (xy 122.07338 -96.922678) (xy 122.113529 -96.883969) (xy 122.158887 -96.851518)
			(xy 122.208487 -96.826017) (xy 122.261271 -96.80801) (xy 122.316114 -96.79788) (xy 122.371848 -96.795843)
			(xy 122.427285 -96.801943) (xy 122.481242 -96.816049) (xy 122.532571 -96.837861) (xy 122.580177 -96.866915)
			(xy 122.623045 -96.90259) (xy 122.660262 -96.944127) (xy 122.691035 -96.99064) (xy 122.714707 -97.041137)
			(xy 122.730775 -97.094544) (xy 122.738895 -97.14972) (xy 122.739316 -97.17278) (xy 124.302772 -97.17278)
			(xy 124.306843 -97.117158) (xy 124.318969 -97.062721) (xy 124.338892 -97.01063) (xy 124.366188 -96.961995)
			(xy 124.400274 -96.917852) (xy 124.440423 -96.879143) (xy 124.485781 -96.846692) (xy 124.535381 -96.821191)
			(xy 124.588165 -96.803184) (xy 124.643008 -96.793054) (xy 124.698742 -96.791017) (xy 124.754179 -96.797117)
			(xy 124.808136 -96.811223) (xy 124.859465 -96.833035) (xy 124.907071 -96.862089) (xy 124.949939 -96.897764)
			(xy 124.987156 -96.939301) (xy 125.017929 -96.985814) (xy 125.041601 -97.036311) (xy 125.057669 -97.089718)
			(xy 125.065789 -97.144894) (xy 125.066298 -97.17278) (xy 125.065789 -97.200666) (xy 125.057669 -97.255842)
			(xy 125.041601 -97.309249) (xy 125.017929 -97.359746) (xy 124.987156 -97.406259) (xy 124.949939 -97.447796)
			(xy 124.907071 -97.483471) (xy 124.859465 -97.512525) (xy 124.808136 -97.534337) (xy 124.754179 -97.548443)
			(xy 124.698742 -97.554543) (xy 124.643008 -97.552506) (xy 124.588165 -97.542376) (xy 124.535381 -97.524369)
			(xy 124.485781 -97.498868) (xy 124.440423 -97.466417) (xy 124.400274 -97.427708) (xy 124.366188 -97.383565)
			(xy 124.338892 -97.33493) (xy 124.318969 -97.282839) (xy 124.306843 -97.228402) (xy 124.302772 -97.17278)
			(xy 122.739316 -97.17278) (xy 122.739404 -97.177606) (xy 122.738895 -97.205492) (xy 122.730775 -97.260668)
			(xy 122.714707 -97.314075) (xy 122.691035 -97.364572) (xy 122.660262 -97.411085) (xy 122.623045 -97.452622)
			(xy 122.580177 -97.488297) (xy 122.532571 -97.517351) (xy 122.481242 -97.539163) (xy 122.427285 -97.553269)
			(xy 122.371848 -97.559369) (xy 122.316114 -97.557332) (xy 122.261271 -97.547202) (xy 122.208487 -97.529195)
			(xy 122.158887 -97.503694) (xy 122.113529 -97.471243) (xy 122.07338 -97.432534) (xy 122.039294 -97.388391)
			(xy 122.011998 -97.339756) (xy 121.992075 -97.287665) (xy 121.979949 -97.233228) (xy 121.975878 -97.177606)
			(xy 120.50141 -97.177606) (xy 120.500901 -97.205492) (xy 120.492781 -97.260668) (xy 120.476713 -97.314075)
			(xy 120.453041 -97.364572) (xy 120.422268 -97.411085) (xy 120.385051 -97.452622) (xy 120.342183 -97.488297)
			(xy 120.294577 -97.517351) (xy 120.243248 -97.539163) (xy 120.189291 -97.553269) (xy 120.133854 -97.559369)
			(xy 120.07812 -97.557332) (xy 120.023277 -97.547202) (xy 119.970493 -97.529195) (xy 119.920893 -97.503694)
			(xy 119.875535 -97.471243) (xy 119.835386 -97.432534) (xy 119.8013 -97.388391) (xy 119.774004 -97.339756)
			(xy 119.754081 -97.287665) (xy 119.741955 -97.233228) (xy 119.737884 -97.177606) (xy 114.272573 -97.177606)
			(xy 114.272822 -97.190814) (xy 114.272336 -97.218065) (xy 114.26458 -97.272013) (xy 114.249225 -97.324308)
			(xy 114.226583 -97.373885) (xy 114.197117 -97.419735) (xy 114.161426 -97.460926) (xy 114.120235 -97.496617)
			(xy 114.074385 -97.526083) (xy 114.024808 -97.548725) (xy 113.972513 -97.56408) (xy 113.918565 -97.571836)
			(xy 113.864063 -97.571836) (xy 113.810115 -97.56408) (xy 113.75782 -97.548725) (xy 113.708243 -97.526083)
			(xy 113.662393 -97.496617) (xy 113.621202 -97.460926) (xy 113.585511 -97.419735) (xy 113.556045 -97.373885)
			(xy 113.533403 -97.324308) (xy 113.518048 -97.272013) (xy 113.510292 -97.218065) (xy 113.509806 -97.190814)
			(xy 113.510272 -97.16265) (xy 113.51856 -97.106934) (xy 113.534944 -97.05304) (xy 113.559067 -97.002138)
			(xy 113.590407 -96.955333) (xy 113.628283 -96.91364) (xy 113.64976 -96.895412) (xy 113.658475 -96.887631)
			(xy 113.668272 -96.866452) (xy 113.668556 -96.854772) (xy 113.66627 -96.763078) (xy 113.655602 -96.742504)
			(xy 113.646204 -96.735392) (xy 113.622768 -96.717281) (xy 113.581303 -96.674987) (xy 113.546871 -96.626794)
			(xy 113.5203 -96.57386) (xy 113.502227 -96.517456) (xy 113.493087 -96.458937) (xy 113.492534 -96.429322)
			(xy 100.517225 -96.429322) (xy 100.517225 -96.443345) (xy 100.509469 -96.497293) (xy 100.494115 -96.549588)
			(xy 100.471475 -96.599166) (xy 100.442009 -96.645016) (xy 100.406319 -96.686207) (xy 100.365129 -96.7219)
			(xy 100.31928 -96.751367) (xy 100.269703 -96.774009) (xy 100.217409 -96.789366) (xy 100.163461 -96.797124)
			(xy 100.108959 -96.797125) (xy 100.055011 -96.78937) (xy 100.002716 -96.774016) (xy 99.953138 -96.751377)
			(xy 99.907287 -96.721912) (xy 99.866095 -96.686222) (xy 99.830403 -96.645032) (xy 99.800935 -96.599183)
			(xy 99.778292 -96.549607) (xy 99.762935 -96.497313) (xy 99.755177 -96.443365) (xy 99.75469 -96.416114)
			(xy 99.75469 -96.415606) (xy 99.754772 -96.405234) (xy 99.755915 -96.384522) (xy 99.756976 -96.374204)
			(xy 99.758131 -96.35966) (xy 99.75292 -96.33096) (xy 99.73982 -96.304898) (xy 99.719898 -96.283592)
			(xy 99.694773 -96.268774) (xy 99.666488 -96.26165) (xy 99.637341 -96.262798) (xy 99.623372 -96.267016)
			(xy 99.593761 -96.276361) (xy 99.532496 -96.286449) (xy 99.501452 -96.287082) (xy 99.501198 -96.287082)
			(xy 99.473947 -96.28662) (xy 99.420001 -96.278864) (xy 99.367707 -96.263509) (xy 99.318131 -96.240868)
			(xy 99.272281 -96.211403) (xy 99.231092 -96.175712) (xy 99.195401 -96.134523) (xy 99.165934 -96.088674)
			(xy 99.143293 -96.039098) (xy 99.127938 -95.986804) (xy 99.12018 -95.932858) (xy 99.120179 -95.878357)
			(xy 94.477301 -95.878357) (xy 94.476323 -95.885004) (xy 94.460255 -95.938411) (xy 94.436583 -95.988908)
			(xy 94.40581 -96.035421) (xy 94.368593 -96.076958) (xy 94.325725 -96.112633) (xy 94.278119 -96.141687)
			(xy 94.22679 -96.163499) (xy 94.172833 -96.177605) (xy 94.117396 -96.183705) (xy 94.061662 -96.181668)
			(xy 94.006819 -96.171538) (xy 93.954035 -96.153531) (xy 93.904435 -96.12803) (xy 93.859077 -96.095579)
			(xy 93.818928 -96.05687) (xy 93.784842 -96.012727) (xy 93.757546 -95.964092) (xy 93.737623 -95.912001)
			(xy 93.725497 -95.857564) (xy 93.721426 -95.801942) (xy 93.479112 -95.801942) (xy 93.478603 -95.829828)
			(xy 93.470483 -95.885004) (xy 93.454415 -95.938411) (xy 93.430743 -95.988908) (xy 93.39997 -96.035421)
			(xy 93.362753 -96.076958) (xy 93.319885 -96.112633) (xy 93.272279 -96.141687) (xy 93.22095 -96.163499)
			(xy 93.166993 -96.177605) (xy 93.111556 -96.183705) (xy 93.055822 -96.181668) (xy 93.000979 -96.171538)
			(xy 92.948195 -96.153531) (xy 92.898595 -96.12803) (xy 92.853237 -96.095579) (xy 92.813088 -96.05687)
			(xy 92.779002 -96.012727) (xy 92.751706 -95.964092) (xy 92.731783 -95.912001) (xy 92.719657 -95.857564)
			(xy 92.715586 -95.801942) (xy 91.438222 -95.801942) (xy 91.437713 -95.829828) (xy 91.429593 -95.885004)
			(xy 91.413525 -95.938411) (xy 91.389853 -95.988908) (xy 91.35908 -96.035421) (xy 91.321863 -96.076958)
			(xy 91.278995 -96.112633) (xy 91.231389 -96.141687) (xy 91.18006 -96.163499) (xy 91.126103 -96.177605)
			(xy 91.070666 -96.183705) (xy 91.014932 -96.181668) (xy 90.960089 -96.171538) (xy 90.907305 -96.153531)
			(xy 90.857705 -96.12803) (xy 90.812347 -96.095579) (xy 90.772198 -96.05687) (xy 90.738112 -96.012727)
			(xy 90.710816 -95.964092) (xy 90.690893 -95.912001) (xy 90.678767 -95.857564) (xy 90.674696 -95.801942)
			(xy 89.404952 -95.801942) (xy 89.404463 -95.829192) (xy 89.396702 -95.883138) (xy 89.381344 -95.93543)
			(xy 89.358701 -95.985005) (xy 89.329234 -96.030853) (xy 89.293543 -96.072042) (xy 89.252355 -96.107733)
			(xy 89.206507 -96.1372) (xy 89.156932 -96.159843) (xy 89.10464 -96.175202) (xy 89.050694 -96.182963)
			(xy 89.023444 -96.18345) (xy 89.022682 -96.18345) (xy 88.99351 -96.182852) (xy 88.935854 -96.173894)
			(xy 88.88023 -96.156281) (xy 88.827927 -96.13042) (xy 88.803734 -96.114108) (xy 88.80348 -96.113854)
			(xy 88.802972 -96.1136) (xy 88.794273 -96.108196) (xy 88.774223 -96.104122) (xy 88.76411 -96.105726)
			(xy 88.727788 -96.113346) (xy 88.690704 -96.12122) (xy 88.681461 -96.123761) (xy 88.665655 -96.134585)
			(xy 88.65997 -96.142302) (xy 88.613742 -96.218502) (xy 88.547956 -96.327976) (xy 88.519724 -96.374966)
			(xy 94.427038 -96.374966) (xy 94.431109 -96.319344) (xy 94.443235 -96.264907) (xy 94.463158 -96.212816)
			(xy 94.490454 -96.164181) (xy 94.52454 -96.120038) (xy 94.564689 -96.081329) (xy 94.610047 -96.048878)
			(xy 94.659647 -96.023377) (xy 94.712431 -96.00537) (xy 94.767274 -95.99524) (xy 94.823008 -95.993203)
			(xy 94.878445 -95.999303) (xy 94.932402 -96.013409) (xy 94.983731 -96.035221) (xy 95.031337 -96.064275)
			(xy 95.074205 -96.09995) (xy 95.111422 -96.141487) (xy 95.142195 -96.188) (xy 95.165867 -96.238497)
			(xy 95.180866 -96.288352) (xy 95.852232 -96.288352) (xy 95.856303 -96.23273) (xy 95.868429 -96.178293)
			(xy 95.888352 -96.126202) (xy 95.915648 -96.077567) (xy 95.949734 -96.033424) (xy 95.989883 -95.994715)
			(xy 96.035241 -95.962264) (xy 96.084841 -95.936763) (xy 96.137625 -95.918756) (xy 96.192468 -95.908626)
			(xy 96.248202 -95.906589) (xy 96.303639 -95.912689) (xy 96.357596 -95.926795) (xy 96.408925 -95.948607)
			(xy 96.456531 -95.977661) (xy 96.499399 -96.013336) (xy 96.536616 -96.054873) (xy 96.567389 -96.101386)
			(xy 96.591061 -96.151883) (xy 96.607129 -96.20529) (xy 96.615249 -96.260466) (xy 96.61548 -96.273112)
			(xy 97.197924 -96.273112) (xy 97.201995 -96.21749) (xy 97.214121 -96.163053) (xy 97.234044 -96.110962)
			(xy 97.26134 -96.062327) (xy 97.295426 -96.018184) (xy 97.335575 -95.979475) (xy 97.380933 -95.947024)
			(xy 97.430533 -95.921523) (xy 97.483317 -95.903516) (xy 97.53816 -95.893386) (xy 97.593894 -95.891349)
			(xy 97.649331 -95.897449) (xy 97.703288 -95.911555) (xy 97.754617 -95.933367) (xy 97.802223 -95.962421)
			(xy 97.845091 -95.998096) (xy 97.882308 -96.039633) (xy 97.913081 -96.086146) (xy 97.936753 -96.136643)
			(xy 97.952821 -96.19005) (xy 97.960941 -96.245226) (xy 97.96145 -96.273112) (xy 97.960941 -96.300998)
			(xy 97.952821 -96.356174) (xy 97.936753 -96.409581) (xy 97.913081 -96.460078) (xy 97.882308 -96.506591)
			(xy 97.845091 -96.548128) (xy 97.802223 -96.583803) (xy 97.754617 -96.612857) (xy 97.703288 -96.634669)
			(xy 97.649331 -96.648775) (xy 97.593894 -96.654875) (xy 97.53816 -96.652838) (xy 97.483317 -96.642708)
			(xy 97.430533 -96.624701) (xy 97.380933 -96.5992) (xy 97.335575 -96.566749) (xy 97.295426 -96.52804)
			(xy 97.26134 -96.483897) (xy 97.234044 -96.435262) (xy 97.214121 -96.383171) (xy 97.201995 -96.328734)
			(xy 97.197924 -96.273112) (xy 96.61548 -96.273112) (xy 96.615758 -96.288352) (xy 96.615249 -96.316238)
			(xy 96.607129 -96.371414) (xy 96.591061 -96.424821) (xy 96.567389 -96.475318) (xy 96.536616 -96.521831)
			(xy 96.499399 -96.563368) (xy 96.456531 -96.599043) (xy 96.408925 -96.628097) (xy 96.357596 -96.649909)
			(xy 96.303639 -96.664015) (xy 96.248202 -96.670115) (xy 96.192468 -96.668078) (xy 96.137625 -96.657948)
			(xy 96.084841 -96.639941) (xy 96.035241 -96.61444) (xy 95.989883 -96.581989) (xy 95.949734 -96.54328)
			(xy 95.915648 -96.499137) (xy 95.888352 -96.450502) (xy 95.868429 -96.398411) (xy 95.856303 -96.343974)
			(xy 95.852232 -96.288352) (xy 95.180866 -96.288352) (xy 95.181935 -96.291904) (xy 95.190055 -96.34708)
			(xy 95.190564 -96.374966) (xy 95.190055 -96.402852) (xy 95.181935 -96.458028) (xy 95.165867 -96.511435)
			(xy 95.142195 -96.561932) (xy 95.111422 -96.608445) (xy 95.074205 -96.649982) (xy 95.031337 -96.685657)
			(xy 94.983731 -96.714711) (xy 94.932402 -96.736523) (xy 94.878445 -96.750629) (xy 94.823008 -96.756729)
			(xy 94.767274 -96.754692) (xy 94.712431 -96.744562) (xy 94.659647 -96.726555) (xy 94.610047 -96.701054)
			(xy 94.564689 -96.668603) (xy 94.52454 -96.629894) (xy 94.490454 -96.585751) (xy 94.463158 -96.537116)
			(xy 94.443235 -96.485025) (xy 94.431109 -96.430588) (xy 94.427038 -96.374966) (xy 88.519724 -96.374966)
			(xy 88.435942 -96.514412) (xy 88.43518 -96.515936) (xy 88.367108 -96.63684) (xy 87.626936 -97.953576)
			(xy 88.342976 -97.953576) (xy 88.347047 -97.897954) (xy 88.359173 -97.843517) (xy 88.379096 -97.791426)
			(xy 88.406392 -97.742791) (xy 88.440478 -97.698648) (xy 88.480627 -97.659939) (xy 88.525985 -97.627488)
			(xy 88.575585 -97.601987) (xy 88.628369 -97.58398) (xy 88.683212 -97.57385) (xy 88.738946 -97.571813)
			(xy 88.794383 -97.577913) (xy 88.84834 -97.592019) (xy 88.899669 -97.613831) (xy 88.947275 -97.642885)
			(xy 88.990143 -97.67856) (xy 89.02736 -97.720097) (xy 89.058133 -97.76661) (xy 89.081805 -97.817107)
			(xy 89.083049 -97.821242) (xy 89.657426 -97.821242) (xy 89.661497 -97.76562) (xy 89.673623 -97.711183)
			(xy 89.693546 -97.659092) (xy 89.720842 -97.610457) (xy 89.754928 -97.566314) (xy 89.795077 -97.527605)
			(xy 89.840435 -97.495154) (xy 89.890035 -97.469653) (xy 89.942819 -97.451646) (xy 89.997662 -97.441516)
			(xy 90.053396 -97.439479) (xy 90.108833 -97.445579) (xy 90.16279 -97.459685) (xy 90.214119 -97.481497)
			(xy 90.261725 -97.510551) (xy 90.304593 -97.546226) (xy 90.34181 -97.587763) (xy 90.372583 -97.634276)
			(xy 90.396255 -97.684773) (xy 90.412323 -97.73818) (xy 90.420443 -97.793356) (xy 90.420952 -97.821242)
			(xy 90.420455 -97.848452) (xy 90.928397 -97.848452) (xy 90.928397 -97.793948) (xy 90.936155 -97.739999)
			(xy 90.951511 -97.687704) (xy 90.974154 -97.638126) (xy 91.003623 -97.592276) (xy 91.039318 -97.551087)
			(xy 91.080511 -97.515397) (xy 91.126365 -97.485933) (xy 91.175945 -97.463296) (xy 91.228242 -97.447945)
			(xy 91.282192 -97.440194) (xy 91.309444 -97.439734) (xy 91.33836 -97.44028) (xy 91.395531 -97.449001)
			(xy 91.450729 -97.466253) (xy 91.502692 -97.491639) (xy 91.550226 -97.524579) (xy 91.592244 -97.564316)
			(xy 91.610434 -97.5868) (xy 91.618036 -97.595613) (xy 91.638941 -97.605793) (xy 91.650566 -97.606358)
			(xy 91.730322 -97.606358) (xy 91.741956 -97.605832) (xy 91.762866 -97.595635) (xy 91.770454 -97.5868)
			(xy 91.788671 -97.564339) (xy 91.830685 -97.524602) (xy 91.878215 -97.49166) (xy 91.930171 -97.466268)
			(xy 91.985364 -97.449007) (xy 92.04253 -97.440272) (xy 92.071444 -97.439734) (xy 92.098696 -97.440139)
			(xy 92.152645 -97.447901) (xy 92.20494 -97.463262) (xy 92.254517 -97.485908) (xy 92.300367 -97.515379)
			(xy 92.341557 -97.551074) (xy 92.377248 -97.592268) (xy 92.406713 -97.638121) (xy 92.429353 -97.687701)
			(xy 92.444708 -97.739998) (xy 92.452464 -97.793948) (xy 92.452464 -97.821242) (xy 92.705426 -97.821242)
			(xy 92.709497 -97.76562) (xy 92.721623 -97.711183) (xy 92.741546 -97.659092) (xy 92.768842 -97.610457)
			(xy 92.802928 -97.566314) (xy 92.843077 -97.527605) (xy 92.888435 -97.495154) (xy 92.938035 -97.469653)
			(xy 92.990819 -97.451646) (xy 93.045662 -97.441516) (xy 93.101396 -97.439479) (xy 93.156833 -97.445579)
			(xy 93.21079 -97.459685) (xy 93.262119 -97.481497) (xy 93.309725 -97.510551) (xy 93.352593 -97.546226)
			(xy 93.38981 -97.587763) (xy 93.420583 -97.634276) (xy 93.444255 -97.684773) (xy 93.460323 -97.73818)
			(xy 93.468443 -97.793356) (xy 93.468952 -97.821242) (xy 93.468443 -97.849128) (xy 93.460323 -97.904304)
			(xy 93.444255 -97.957711) (xy 93.420583 -98.008208) (xy 93.38981 -98.054721) (xy 93.352593 -98.096258)
			(xy 93.309725 -98.131933) (xy 93.262119 -98.160987) (xy 93.21079 -98.182799) (xy 93.156833 -98.196905)
			(xy 93.101396 -98.203005) (xy 93.045662 -98.200968) (xy 92.990819 -98.190838) (xy 92.938035 -98.172831)
			(xy 92.888435 -98.14733) (xy 92.843077 -98.114879) (xy 92.802928 -98.07617) (xy 92.768842 -98.032027)
			(xy 92.741546 -97.983392) (xy 92.721623 -97.931301) (xy 92.709497 -97.876864) (xy 92.705426 -97.821242)
			(xy 92.452464 -97.821242) (xy 92.452464 -97.848452) (xy 92.444708 -97.902402) (xy 92.429353 -97.954699)
			(xy 92.406713 -98.004279) (xy 92.377248 -98.050132) (xy 92.341557 -98.091326) (xy 92.300367 -98.127021)
			(xy 92.254517 -98.156492) (xy 92.20494 -98.179138) (xy 92.152645 -98.194499) (xy 92.098696 -98.202261)
			(xy 92.071444 -98.20275) (xy 92.042527 -98.202219) (xy 91.985356 -98.193495) (xy 91.930156 -98.176241)
			(xy 91.878194 -98.150852) (xy 91.83066 -98.11791) (xy 91.788644 -98.078169) (xy 91.770454 -98.055684)
			(xy 91.76286 -98.046863) (xy 91.741949 -98.036687) (xy 91.730322 -98.036126) (xy 91.650566 -98.036126)
			(xy 91.638932 -98.036651) (xy 91.618022 -98.046849) (xy 91.610434 -98.055684) (xy 91.59222 -98.078148)
			(xy 91.550205 -98.117885) (xy 91.502675 -98.150827) (xy 91.450719 -98.176219) (xy 91.395525 -98.193479)
			(xy 91.338359 -98.202213) (xy 91.309444 -98.20275) (xy 91.282192 -98.202206) (xy 91.228242 -98.194455)
			(xy 91.175945 -98.179104) (xy 91.126365 -98.156467) (xy 91.080511 -98.127003) (xy 91.039318 -98.091313)
			(xy 91.003623 -98.050124) (xy 90.974154 -98.004274) (xy 90.951511 -97.954696) (xy 90.936155 -97.902401)
			(xy 90.928397 -97.848452) (xy 90.420455 -97.848452) (xy 90.420443 -97.849128) (xy 90.412323 -97.904304)
			(xy 90.396255 -97.957711) (xy 90.372583 -98.008208) (xy 90.34181 -98.054721) (xy 90.304593 -98.096258)
			(xy 90.261725 -98.131933) (xy 90.214119 -98.160987) (xy 90.16279 -98.182799) (xy 90.108833 -98.196905)
			(xy 90.053396 -98.203005) (xy 89.997662 -98.200968) (xy 89.942819 -98.190838) (xy 89.890035 -98.172831)
			(xy 89.840435 -98.14733) (xy 89.795077 -98.114879) (xy 89.754928 -98.07617) (xy 89.720842 -98.032027)
			(xy 89.693546 -97.983392) (xy 89.673623 -97.931301) (xy 89.661497 -97.876864) (xy 89.657426 -97.821242)
			(xy 89.083049 -97.821242) (xy 89.097873 -97.870514) (xy 89.105993 -97.92569) (xy 89.106502 -97.953576)
			(xy 89.105993 -97.981462) (xy 89.097873 -98.036638) (xy 89.081805 -98.090045) (xy 89.058133 -98.140542)
			(xy 89.02736 -98.187055) (xy 88.990143 -98.228592) (xy 88.947275 -98.264267) (xy 88.899669 -98.293321)
			(xy 88.84834 -98.315133) (xy 88.794383 -98.329239) (xy 88.738946 -98.335339) (xy 88.683212 -98.333302)
			(xy 88.628369 -98.323172) (xy 88.575585 -98.305165) (xy 88.525985 -98.279664) (xy 88.480627 -98.247213)
			(xy 88.440478 -98.208504) (xy 88.406392 -98.164361) (xy 88.379096 -98.115726) (xy 88.359173 -98.063635)
			(xy 88.347047 -98.009198) (xy 88.342976 -97.953576) (xy 87.626936 -97.953576) (xy 87.173894 -98.759518)
			(xy 99.171252 -98.759518) (xy 99.171716 -98.732148) (xy 99.179532 -98.677968) (xy 99.195021 -98.625464)
			(xy 99.217864 -98.575717) (xy 99.24759 -98.529751) (xy 99.265232 -98.50882) (xy 99.265486 -98.508566)
			(xy 99.27105 -98.501464) (xy 99.277311 -98.484559) (xy 99.277678 -98.475546) (xy 99.277678 -98.40849)
			(xy 99.277331 -98.399472) (xy 99.271077 -98.382555) (xy 99.265486 -98.37547) (xy 99.265232 -98.37547)
			(xy 99.265232 -98.375216) (xy 99.247609 -98.354269) (xy 99.217883 -98.308304) (xy 99.195036 -98.25856)
			(xy 99.179538 -98.20606) (xy 99.171708 -98.151883) (xy 99.171706 -98.097144) (xy 99.179532 -98.042966)
			(xy 99.195027 -97.990465) (xy 99.21787 -97.94072) (xy 99.247592 -97.894753) (xy 99.265232 -97.87382)
			(xy 99.265486 -97.873566) (xy 99.27105 -97.866464) (xy 99.277311 -97.849559) (xy 99.277678 -97.840546)
			(xy 99.277678 -97.77349) (xy 99.277331 -97.764472) (xy 99.271077 -97.747555) (xy 99.265486 -97.74047)
			(xy 99.265232 -97.74047) (xy 99.265232 -97.740216) (xy 99.247592 -97.719285) (xy 99.217879 -97.673312)
			(xy 99.195043 -97.623565) (xy 99.179552 -97.571063) (xy 99.171725 -97.516887) (xy 99.171252 -97.489518)
			(xy 99.171738 -97.462267) (xy 99.179494 -97.408319) (xy 99.194849 -97.356024) (xy 99.217491 -97.306447)
			(xy 99.246957 -97.260597) (xy 99.282648 -97.219406) (xy 99.323839 -97.183715) (xy 99.369689 -97.154249)
			(xy 99.419266 -97.131607) (xy 99.471561 -97.116252) (xy 99.525509 -97.108496) (xy 99.580011 -97.108496)
			(xy 99.633959 -97.116252) (xy 99.686254 -97.131607) (xy 99.735831 -97.154249) (xy 99.781681 -97.183715)
			(xy 99.822872 -97.219406) (xy 99.858563 -97.260597) (xy 99.888029 -97.306447) (xy 99.910671 -97.356024)
			(xy 99.926026 -97.408319) (xy 99.933782 -97.462267) (xy 99.934268 -97.489518) (xy 99.93382 -97.516889)
			(xy 99.925999 -97.571069) (xy 99.910506 -97.623573) (xy 99.88766 -97.673319) (xy 99.857931 -97.719285)
			(xy 99.840288 -97.740216) (xy 99.840034 -97.74047) (xy 99.834446 -97.747555) (xy 99.828202 -97.764473)
			(xy 99.827842 -97.77349) (xy 99.827842 -97.840546) (xy 99.828216 -97.849561) (xy 99.834451 -97.866479)
			(xy 99.840034 -97.873566) (xy 99.840288 -97.873566) (xy 99.840288 -97.87382) (xy 99.857946 -97.894739)
			(xy 99.887669 -97.940709) (xy 99.910512 -97.990458) (xy 99.926006 -98.042962) (xy 99.933833 -98.097142)
			(xy 99.933831 -98.151885) (xy 99.926 -98.206064) (xy 99.910502 -98.258567) (xy 99.887656 -98.308314)
			(xy 99.857929 -98.354283) (xy 99.840288 -98.375216) (xy 99.840034 -98.37547) (xy 99.834446 -98.382555)
			(xy 99.828202 -98.399473) (xy 99.827842 -98.40849) (xy 99.827842 -98.475546) (xy 99.828216 -98.484561)
			(xy 99.834451 -98.501479) (xy 99.836082 -98.503549) (xy 100.826086 -98.503549) (xy 100.826086 -98.449051)
			(xy 100.833841 -98.395108) (xy 100.849194 -98.342817) (xy 100.871832 -98.293244) (xy 100.901294 -98.247396)
			(xy 100.936981 -98.206207) (xy 100.978165 -98.170517) (xy 101.02401 -98.14105) (xy 101.073582 -98.118407)
			(xy 101.125871 -98.103049) (xy 101.179813 -98.095288) (xy 101.207062 -98.0948) (xy 101.233377 -98.095226)
			(xy 101.285508 -98.102469) (xy 101.336151 -98.116797) (xy 101.38435 -98.137937) (xy 101.429192 -98.16549)
			(xy 101.46983 -98.198935) (xy 101.487986 -98.21799) (xy 101.495512 -98.225386) (xy 101.514789 -98.233914)
			(xy 101.525324 -98.2345) (xy 101.6 -98.2345) (xy 101.610551 -98.233985) (xy 101.629847 -98.22544)
			(xy 101.637338 -98.21799) (xy 101.65548 -98.198921) (xy 101.696113 -98.165466) (xy 101.740956 -98.137909)
			(xy 101.789159 -98.116772) (xy 101.839809 -98.102458) (xy 101.891945 -98.095237) (xy 101.918262 -98.0948)
			(xy 101.945517 -98.095245) (xy 101.999473 -98.102998) (xy 102.051777 -98.118351) (xy 102.101363 -98.140991)
			(xy 102.147222 -98.170459) (xy 102.18842 -98.206153) (xy 102.224118 -98.247348) (xy 102.25359 -98.293204)
			(xy 102.273298 -98.336354) (xy 102.849426 -98.336354) (xy 102.849917 -98.308985) (xy 102.857728 -98.254806)
			(xy 102.873211 -98.202303) (xy 102.896047 -98.152556) (xy 102.925767 -98.106588) (xy 102.943406 -98.085656)
			(xy 102.94366 -98.085402) (xy 102.949259 -98.078324) (xy 102.955497 -98.0614) (xy 102.955852 -98.052382)
			(xy 102.955852 -97.985326) (xy 102.955493 -97.976309) (xy 102.949248 -97.959392) (xy 102.94366 -97.952306)
			(xy 102.943406 -97.952306) (xy 102.943406 -97.952052) (xy 102.925721 -97.931155) (xy 102.896 -97.885181)
			(xy 102.873158 -97.835428) (xy 102.857667 -97.782921) (xy 102.849843 -97.728738) (xy 102.849848 -97.673993)
			(xy 102.857681 -97.619811) (xy 102.873183 -97.567307) (xy 102.896033 -97.517558) (xy 102.925763 -97.471589)
			(xy 102.943406 -97.450656) (xy 102.94366 -97.450402) (xy 102.949259 -97.443324) (xy 102.955497 -97.4264)
			(xy 102.955852 -97.417382) (xy 102.955852 -97.350326) (xy 102.955493 -97.341309) (xy 102.949248 -97.324392)
			(xy 102.94366 -97.317306) (xy 102.943406 -97.317306) (xy 102.943406 -97.317052) (xy 102.925779 -97.29611)
			(xy 102.896065 -97.25014) (xy 102.873227 -97.200395) (xy 102.857733 -97.147897) (xy 102.849902 -97.093723)
			(xy 102.849426 -97.066354) (xy 102.849912 -97.039103) (xy 102.857668 -96.985155) (xy 102.873023 -96.93286)
			(xy 102.895665 -96.883283) (xy 102.925131 -96.837433) (xy 102.960822 -96.796242) (xy 103.002013 -96.760551)
			(xy 103.047863 -96.731085) (xy 103.09744 -96.708443) (xy 103.149735 -96.693088) (xy 103.203683 -96.685332)
			(xy 103.258185 -96.685332) (xy 103.312133 -96.693088) (xy 103.364428 -96.708443) (xy 103.414005 -96.731085)
			(xy 103.459855 -96.760551) (xy 103.501046 -96.796242) (xy 103.536737 -96.837433) (xy 103.566203 -96.883283)
			(xy 103.588845 -96.93286) (xy 103.6042 -96.985155) (xy 103.611956 -97.039103) (xy 103.612442 -97.066354)
			(xy 103.611963 -97.093724) (xy 103.604151 -97.147903) (xy 103.588665 -97.200407) (xy 103.565826 -97.250154)
			(xy 103.536103 -97.296121) (xy 103.518462 -97.317052) (xy 103.518208 -97.317306) (xy 103.512614 -97.324387)
			(xy 103.506371 -97.341308) (xy 103.506016 -97.350326) (xy 103.506016 -97.417382) (xy 103.506378 -97.426398)
			(xy 103.512622 -97.443316) (xy 103.518208 -97.450402) (xy 103.518462 -97.450402) (xy 103.518462 -97.450656)
			(xy 103.536058 -97.471625) (xy 103.565786 -97.517586) (xy 103.588634 -97.567326) (xy 103.604135 -97.619823)
			(xy 103.611968 -97.673997) (xy 103.611973 -97.728734) (xy 103.604149 -97.782909) (xy 103.588659 -97.835409)
			(xy 103.565819 -97.885153) (xy 103.5361 -97.93112) (xy 103.518462 -97.952052) (xy 103.518208 -97.952306)
			(xy 103.512614 -97.959387) (xy 103.506371 -97.976308) (xy 103.506016 -97.985326) (xy 103.506016 -98.052382)
			(xy 103.506378 -98.061398) (xy 103.512622 -98.078316) (xy 103.518208 -98.085402) (xy 103.518462 -98.085402)
			(xy 103.518462 -98.085656) (xy 103.536088 -98.106599) (xy 103.565803 -98.152568) (xy 103.588642 -98.202313)
			(xy 103.604136 -98.254811) (xy 103.611967 -98.308985) (xy 103.612442 -98.336354) (xy 103.612175 -98.35134)
			(xy 106.04373 -98.35134) (xy 106.044212 -98.32397) (xy 106.052025 -98.269792) (xy 106.06751 -98.217288)
			(xy 106.090348 -98.167541) (xy 106.12007 -98.121574) (xy 106.13771 -98.100642) (xy 106.137964 -98.100388)
			(xy 106.143569 -98.093315) (xy 106.149803 -98.076387) (xy 106.150156 -98.067368) (xy 106.150156 -98.000312)
			(xy 106.149803 -97.991295) (xy 106.143553 -97.974377) (xy 106.137964 -97.967292) (xy 106.13771 -97.967292)
			(xy 106.13771 -97.967038) (xy 106.120109 -97.946073) (xy 106.090384 -97.900111) (xy 106.067537 -97.850369)
			(xy 106.052039 -97.797872) (xy 106.044207 -97.743699) (xy 106.044202 -97.688962) (xy 106.052026 -97.634786)
			(xy 106.067516 -97.582287) (xy 106.090355 -97.532542) (xy 106.120073 -97.486575) (xy 106.13771 -97.465642)
			(xy 106.137964 -97.465388) (xy 106.143569 -97.458315) (xy 106.149803 -97.441387) (xy 106.150156 -97.432368)
			(xy 106.150156 -97.365312) (xy 106.149803 -97.356295) (xy 106.143553 -97.339377) (xy 106.137964 -97.332292)
			(xy 106.13771 -97.332292) (xy 106.13771 -97.332038) (xy 106.120077 -97.311101) (xy 106.090364 -97.26513)
			(xy 106.067527 -97.215384) (xy 106.052034 -97.162884) (xy 106.044205 -97.108709) (xy 106.04373 -97.08134)
			(xy 106.044216 -97.054089) (xy 106.051972 -97.000141) (xy 106.067327 -96.947846) (xy 106.089969 -96.898269)
			(xy 106.119435 -96.852419) (xy 106.155126 -96.811228) (xy 106.196317 -96.775537) (xy 106.242167 -96.746071)
			(xy 106.291744 -96.723429) (xy 106.344039 -96.708074) (xy 106.397987 -96.700318) (xy 106.452489 -96.700318)
			(xy 106.506437 -96.708074) (xy 106.558732 -96.723429) (xy 106.608309 -96.746071) (xy 106.654159 -96.775537)
			(xy 106.69535 -96.811228) (xy 106.731041 -96.852419) (xy 106.760507 -96.898269) (xy 106.783149 -96.947846)
			(xy 106.798504 -97.000141) (xy 106.80626 -97.054089) (xy 106.806746 -97.08134) (xy 106.806258 -97.10871)
			(xy 106.798447 -97.162888) (xy 106.782964 -97.215392) (xy 106.760127 -97.265139) (xy 106.730406 -97.311106)
			(xy 106.712766 -97.332038) (xy 106.712512 -97.332292) (xy 106.706924 -97.339378) (xy 106.700678 -97.356295)
			(xy 106.70032 -97.365312) (xy 106.70032 -97.432368) (xy 106.700688 -97.441384) (xy 106.706928 -97.458301)
			(xy 106.712512 -97.465388) (xy 106.712766 -97.465388) (xy 106.712766 -97.465642) (xy 106.730446 -97.486543)
			(xy 106.76017 -97.532516) (xy 106.783013 -97.582268) (xy 106.798507 -97.634774) (xy 106.806332 -97.688958)
			(xy 106.806327 -97.743703) (xy 106.798494 -97.797884) (xy 106.782992 -97.850389) (xy 106.760141 -97.900137)
			(xy 106.73041 -97.946105) (xy 106.712766 -97.967038) (xy 106.712512 -97.967292) (xy 106.706924 -97.974378)
			(xy 106.700678 -97.991295) (xy 106.70032 -98.000312) (xy 106.70032 -98.067368) (xy 106.700688 -98.076384)
			(xy 106.706928 -98.093301) (xy 106.712512 -98.100388) (xy 106.712766 -98.100388) (xy 106.712766 -98.100642)
			(xy 106.730386 -98.121589) (xy 106.760102 -98.167558) (xy 106.782942 -98.217301) (xy 106.798437 -98.269799)
			(xy 106.805783 -98.320606) (xy 119.737884 -98.320606) (xy 119.741955 -98.264984) (xy 119.754081 -98.210547)
			(xy 119.774004 -98.158456) (xy 119.8013 -98.109821) (xy 119.835386 -98.065678) (xy 119.875535 -98.026969)
			(xy 119.920893 -97.994518) (xy 119.970493 -97.969017) (xy 120.023277 -97.95101) (xy 120.07812 -97.94088)
			(xy 120.133854 -97.938843) (xy 120.189291 -97.944943) (xy 120.243248 -97.959049) (xy 120.294577 -97.980861)
			(xy 120.342183 -98.009915) (xy 120.385051 -98.04559) (xy 120.422268 -98.087127) (xy 120.453041 -98.13364)
			(xy 120.476713 -98.184137) (xy 120.492781 -98.237544) (xy 120.497566 -98.27006) (xy 125.399544 -98.27006)
			(xy 125.403615 -98.214438) (xy 125.415741 -98.160001) (xy 125.435664 -98.10791) (xy 125.46296 -98.059275)
			(xy 125.497046 -98.015132) (xy 125.537195 -97.976423) (xy 125.582553 -97.943972) (xy 125.632153 -97.918471)
			(xy 125.684937 -97.900464) (xy 125.73978 -97.890334) (xy 125.795514 -97.888297) (xy 125.850951 -97.894397)
			(xy 125.904908 -97.908503) (xy 125.956237 -97.930315) (xy 126.003843 -97.959369) (xy 126.028929 -97.980246)
			(xy 134.734044 -97.980246) (xy 134.738115 -97.924624) (xy 134.750241 -97.870187) (xy 134.770164 -97.818096)
			(xy 134.79746 -97.769461) (xy 134.831546 -97.725318) (xy 134.871695 -97.686609) (xy 134.917053 -97.654158)
			(xy 134.966653 -97.628657) (xy 135.019437 -97.61065) (xy 135.07428 -97.60052) (xy 135.130014 -97.598483)
			(xy 135.185451 -97.604583) (xy 135.239408 -97.618689) (xy 135.290737 -97.640501) (xy 135.338343 -97.669555)
			(xy 135.381211 -97.70523) (xy 135.418428 -97.746767) (xy 135.449201 -97.79328) (xy 135.472873 -97.843777)
			(xy 135.488941 -97.897184) (xy 135.497061 -97.95236) (xy 135.49757 -97.980246) (xy 135.497061 -98.008132)
			(xy 135.488941 -98.063308) (xy 135.477709 -98.100642) (xy 137.211306 -98.100642) (xy 137.215377 -98.04502)
			(xy 137.227503 -97.990583) (xy 137.247426 -97.938492) (xy 137.274722 -97.889857) (xy 137.308808 -97.845714)
			(xy 137.348957 -97.807005) (xy 137.394315 -97.774554) (xy 137.443915 -97.749053) (xy 137.496699 -97.731046)
			(xy 137.551542 -97.720916) (xy 137.607276 -97.718879) (xy 137.662713 -97.724979) (xy 137.71667 -97.739085)
			(xy 137.767999 -97.760897) (xy 137.810275 -97.786698) (xy 140.222984 -97.786698) (xy 140.227055 -97.731076)
			(xy 140.239181 -97.676639) (xy 140.259104 -97.624548) (xy 140.2864 -97.575913) (xy 140.320486 -97.53177)
			(xy 140.360635 -97.493061) (xy 140.405993 -97.46061) (xy 140.455593 -97.435109) (xy 140.508377 -97.417102)
			(xy 140.56322 -97.406972) (xy 140.618954 -97.404935) (xy 140.674391 -97.411035) (xy 140.728348 -97.425141)
			(xy 140.779677 -97.446953) (xy 140.827283 -97.476007) (xy 140.870151 -97.511682) (xy 140.907368 -97.553219)
			(xy 140.938141 -97.599732) (xy 140.961813 -97.650229) (xy 140.977881 -97.703636) (xy 140.986001 -97.758812)
			(xy 140.98651 -97.786698) (xy 140.986001 -97.814584) (xy 140.977881 -97.86976) (xy 140.961813 -97.923167)
			(xy 140.938141 -97.973664) (xy 140.907368 -98.020177) (xy 140.870151 -98.061714) (xy 140.827283 -98.097389)
			(xy 140.779677 -98.126443) (xy 140.728348 -98.148255) (xy 140.674391 -98.162361) (xy 140.618954 -98.168461)
			(xy 140.56322 -98.166424) (xy 140.508377 -98.156294) (xy 140.455593 -98.138287) (xy 140.405993 -98.112786)
			(xy 140.360635 -98.080335) (xy 140.320486 -98.041626) (xy 140.2864 -97.997483) (xy 140.259104 -97.948848)
			(xy 140.239181 -97.896757) (xy 140.227055 -97.84232) (xy 140.222984 -97.786698) (xy 137.810275 -97.786698)
			(xy 137.815605 -97.789951) (xy 137.858473 -97.825626) (xy 137.89569 -97.867163) (xy 137.926463 -97.913676)
			(xy 137.950135 -97.964173) (xy 137.966203 -98.01758) (xy 137.974323 -98.072756) (xy 137.974832 -98.100642)
			(xy 137.974323 -98.128528) (xy 137.966203 -98.183704) (xy 137.950135 -98.237111) (xy 137.926463 -98.287608)
			(xy 137.89569 -98.334121) (xy 137.858473 -98.375658) (xy 137.815605 -98.411333) (xy 137.767999 -98.440387)
			(xy 137.71667 -98.462199) (xy 137.662713 -98.476305) (xy 137.607276 -98.482405) (xy 137.551542 -98.480368)
			(xy 137.496699 -98.470238) (xy 137.443915 -98.452231) (xy 137.394315 -98.42673) (xy 137.348957 -98.394279)
			(xy 137.308808 -98.35557) (xy 137.274722 -98.311427) (xy 137.247426 -98.262792) (xy 137.227503 -98.210701)
			(xy 137.215377 -98.156264) (xy 137.211306 -98.100642) (xy 135.477709 -98.100642) (xy 135.472873 -98.116715)
			(xy 135.449201 -98.167212) (xy 135.418428 -98.213725) (xy 135.381211 -98.255262) (xy 135.338343 -98.290937)
			(xy 135.290737 -98.319991) (xy 135.239408 -98.341803) (xy 135.185451 -98.355909) (xy 135.130014 -98.362009)
			(xy 135.07428 -98.359972) (xy 135.019437 -98.349842) (xy 134.966653 -98.331835) (xy 134.917053 -98.306334)
			(xy 134.871695 -98.273883) (xy 134.831546 -98.235174) (xy 134.79746 -98.191031) (xy 134.770164 -98.142396)
			(xy 134.750241 -98.090305) (xy 134.738115 -98.035868) (xy 134.734044 -97.980246) (xy 126.028929 -97.980246)
			(xy 126.046711 -97.995044) (xy 126.083928 -98.036581) (xy 126.114701 -98.083094) (xy 126.138373 -98.133591)
			(xy 126.154441 -98.186998) (xy 126.162561 -98.242174) (xy 126.16307 -98.27006) (xy 126.162561 -98.297946)
			(xy 126.154441 -98.353122) (xy 126.138373 -98.406529) (xy 126.114701 -98.457026) (xy 126.083928 -98.503539)
			(xy 126.046711 -98.545076) (xy 126.003843 -98.580751) (xy 125.956237 -98.609805) (xy 125.904908 -98.631617)
			(xy 125.850951 -98.645723) (xy 125.795514 -98.651823) (xy 125.73978 -98.649786) (xy 125.684937 -98.639656)
			(xy 125.632153 -98.621649) (xy 125.582553 -98.596148) (xy 125.537195 -98.563697) (xy 125.497046 -98.524988)
			(xy 125.46296 -98.480845) (xy 125.435664 -98.43221) (xy 125.415741 -98.380119) (xy 125.403615 -98.325682)
			(xy 125.399544 -98.27006) (xy 120.497566 -98.27006) (xy 120.500901 -98.29272) (xy 120.50141 -98.320606)
			(xy 120.500901 -98.348492) (xy 120.492781 -98.403668) (xy 120.476713 -98.457075) (xy 120.453041 -98.507572)
			(xy 120.422268 -98.554085) (xy 120.385051 -98.595622) (xy 120.342183 -98.631297) (xy 120.294577 -98.660351)
			(xy 120.243248 -98.682163) (xy 120.189291 -98.696269) (xy 120.133854 -98.702369) (xy 120.07812 -98.700332)
			(xy 120.023277 -98.690202) (xy 119.970493 -98.672195) (xy 119.920893 -98.646694) (xy 119.875535 -98.614243)
			(xy 119.835386 -98.575534) (xy 119.8013 -98.531391) (xy 119.774004 -98.482756) (xy 119.754081 -98.430665)
			(xy 119.741955 -98.376228) (xy 119.737884 -98.320606) (xy 106.805783 -98.320606) (xy 106.80627 -98.323972)
			(xy 106.806746 -98.35134) (xy 106.80626 -98.378591) (xy 106.798504 -98.432539) (xy 106.783149 -98.484834)
			(xy 106.760507 -98.534411) (xy 106.731041 -98.580261) (xy 106.69535 -98.621452) (xy 106.654159 -98.657143)
			(xy 106.608309 -98.686609) (xy 106.558732 -98.709251) (xy 106.506437 -98.724606) (xy 106.452489 -98.732362)
			(xy 106.397987 -98.732362) (xy 106.344039 -98.724606) (xy 106.291744 -98.709251) (xy 106.242167 -98.686609)
			(xy 106.196317 -98.657143) (xy 106.155126 -98.621452) (xy 106.119435 -98.580261) (xy 106.089969 -98.534411)
			(xy 106.067327 -98.484834) (xy 106.051972 -98.432539) (xy 106.044216 -98.378591) (xy 106.04373 -98.35134)
			(xy 103.612175 -98.35134) (xy 103.611956 -98.363605) (xy 103.6042 -98.417553) (xy 103.588845 -98.469848)
			(xy 103.566203 -98.519425) (xy 103.536737 -98.565275) (xy 103.501046 -98.606466) (xy 103.459855 -98.642157)
			(xy 103.414005 -98.671623) (xy 103.364428 -98.694265) (xy 103.312133 -98.70962) (xy 103.258185 -98.717376)
			(xy 103.203683 -98.717376) (xy 103.149735 -98.70962) (xy 103.09744 -98.694265) (xy 103.047863 -98.671623)
			(xy 103.002013 -98.642157) (xy 102.960822 -98.606466) (xy 102.925131 -98.565275) (xy 102.895665 -98.519425)
			(xy 102.873023 -98.469848) (xy 102.857668 -98.417553) (xy 102.849912 -98.363605) (xy 102.849426 -98.336354)
			(xy 102.273298 -98.336354) (xy 102.276236 -98.342787) (xy 102.291594 -98.395089) (xy 102.299353 -98.449045)
			(xy 102.299353 -98.503555) (xy 102.291594 -98.557511) (xy 102.276236 -98.609813) (xy 102.25359 -98.659396)
			(xy 102.224118 -98.705252) (xy 102.18842 -98.746447) (xy 102.147222 -98.782141) (xy 102.101363 -98.811609)
			(xy 102.051777 -98.834249) (xy 101.999473 -98.849602) (xy 101.945517 -98.857355) (xy 101.918262 -98.857816)
			(xy 101.891947 -98.857369) (xy 101.839818 -98.850129) (xy 101.789175 -98.835806) (xy 101.740977 -98.814669)
			(xy 101.696134 -98.78712) (xy 101.655494 -98.753679) (xy 101.637338 -98.734626) (xy 101.629801 -98.727243)
			(xy 101.610533 -98.718707) (xy 101.6 -98.718116) (xy 101.525324 -98.718116) (xy 101.514774 -98.71864)
			(xy 101.495478 -98.727178) (xy 101.487986 -98.734626) (xy 101.469835 -98.753686) (xy 101.429204 -98.787142)
			(xy 101.384363 -98.8147) (xy 101.336161 -98.835837) (xy 101.285513 -98.850154) (xy 101.233378 -98.857378)
			(xy 101.207062 -98.857816) (xy 101.179813 -98.857312) (xy 101.125871 -98.849551) (xy 101.073582 -98.834193)
			(xy 101.02401 -98.81155) (xy 100.978165 -98.782083) (xy 100.936981 -98.746393) (xy 100.901294 -98.705204)
			(xy 100.871832 -98.659356) (xy 100.849194 -98.609783) (xy 100.833841 -98.557492) (xy 100.826086 -98.503549)
			(xy 99.836082 -98.503549) (xy 99.840034 -98.508566) (xy 99.840288 -98.509074) (xy 99.851231 -98.521809)
			(xy 99.871073 -98.5489) (xy 99.879912 -98.563176) (xy 99.885246 -98.572066) (xy 99.902264 -98.584258)
			(xy 99.995482 -98.604578) (xy 100.016056 -98.60026) (xy 100.024692 -98.594418) (xy 100.048758 -98.578421)
			(xy 100.100688 -98.553077) (xy 100.155846 -98.535851) (xy 100.21297 -98.527135) (xy 100.241862 -98.5266)
			(xy 100.269117 -98.527045) (xy 100.323073 -98.534798) (xy 100.375377 -98.550151) (xy 100.424963 -98.572791)
			(xy 100.470822 -98.602259) (xy 100.51202 -98.637953) (xy 100.547718 -98.679148) (xy 100.57719 -98.725004)
			(xy 100.599836 -98.774587) (xy 100.615194 -98.826889) (xy 100.622953 -98.880845) (xy 100.622953 -98.935355)
			(xy 100.615194 -98.989311) (xy 100.599836 -99.041613) (xy 100.57719 -99.091196) (xy 100.547718 -99.137052)
			(xy 100.51202 -99.178247) (xy 100.470822 -99.213941) (xy 100.424963 -99.243409) (xy 100.375377 -99.266049)
			(xy 100.323073 -99.281402) (xy 100.269117 -99.289155) (xy 100.241862 -99.289616) (xy 100.213769 -99.289152)
			(xy 100.158191 -99.28092) (xy 100.104421 -99.264623) (xy 100.053623 -99.240615) (xy 100.006897 -99.209416)
			(xy 99.965253 -99.171699) (xy 99.929592 -99.128282) (xy 99.91471 -99.10445) (xy 99.909376 -99.09556)
			(xy 99.892358 -99.083368) (xy 99.79914 -99.063048) (xy 99.778566 -99.067366) (xy 99.76993 -99.073208)
			(xy 99.74586 -99.089198) (xy 99.693931 -99.114543) (xy 99.638775 -99.131771) (xy 99.581652 -99.14049)
			(xy 99.55276 -99.141026) (xy 99.525509 -99.140559) (xy 99.471561 -99.132798) (xy 99.419267 -99.117439)
			(xy 99.369691 -99.094794) (xy 99.323842 -99.065325) (xy 99.282652 -99.029632) (xy 99.246961 -98.988441)
			(xy 99.217495 -98.94259) (xy 99.194854 -98.893012) (xy 99.179497 -98.840717) (xy 99.171739 -98.786769)
			(xy 99.171252 -98.759518) (xy 87.173894 -98.759518) (xy 86.786103 -99.449382) (xy 87.906096 -99.449382)
			(xy 87.910167 -99.39376) (xy 87.922293 -99.339323) (xy 87.942216 -99.287232) (xy 87.969512 -99.238597)
			(xy 88.003598 -99.194454) (xy 88.043747 -99.155745) (xy 88.089105 -99.123294) (xy 88.138705 -99.097793)
			(xy 88.191489 -99.079786) (xy 88.246332 -99.069656) (xy 88.302066 -99.067619) (xy 88.357503 -99.073719)
			(xy 88.41146 -99.087825) (xy 88.462789 -99.109637) (xy 88.510395 -99.138691) (xy 88.553263 -99.174366)
			(xy 88.59048 -99.215903) (xy 88.621253 -99.262416) (xy 88.644925 -99.312913) (xy 88.660993 -99.36632)
			(xy 88.669113 -99.421496) (xy 88.669622 -99.449382) (xy 88.669455 -99.458526) (xy 93.638622 -99.458526)
			(xy 93.642693 -99.402904) (xy 93.654819 -99.348467) (xy 93.674742 -99.296376) (xy 93.702038 -99.247741)
			(xy 93.736124 -99.203598) (xy 93.776273 -99.164889) (xy 93.821631 -99.132438) (xy 93.871231 -99.106937)
			(xy 93.924015 -99.08893) (xy 93.978858 -99.0788) (xy 94.034592 -99.076763) (xy 94.090029 -99.082863)
			(xy 94.143986 -99.096969) (xy 94.195315 -99.118781) (xy 94.242921 -99.147835) (xy 94.285789 -99.18351)
			(xy 94.323006 -99.225047) (xy 94.353779 -99.27156) (xy 94.377451 -99.322057) (xy 94.393519 -99.375464)
			(xy 94.401639 -99.43064) (xy 94.402148 -99.458526) (xy 94.402055 -99.463606) (xy 119.737884 -99.463606)
			(xy 119.741955 -99.407984) (xy 119.754081 -99.353547) (xy 119.774004 -99.301456) (xy 119.8013 -99.252821)
			(xy 119.835386 -99.208678) (xy 119.875535 -99.169969) (xy 119.920893 -99.137518) (xy 119.970493 -99.112017)
			(xy 120.023277 -99.09401) (xy 120.07812 -99.08388) (xy 120.133854 -99.081843) (xy 120.189291 -99.087943)
			(xy 120.243248 -99.102049) (xy 120.294577 -99.123861) (xy 120.342183 -99.152915) (xy 120.385051 -99.18859)
			(xy 120.422268 -99.230127) (xy 120.453041 -99.27664) (xy 120.476713 -99.327137) (xy 120.492781 -99.380544)
			(xy 120.500901 -99.43572) (xy 120.50141 -99.463606) (xy 124.405388 -99.463606) (xy 124.409459 -99.407984)
			(xy 124.421585 -99.353547) (xy 124.441508 -99.301456) (xy 124.468804 -99.252821) (xy 124.50289 -99.208678)
			(xy 124.543039 -99.169969) (xy 124.588397 -99.137518) (xy 124.637997 -99.112017) (xy 124.690781 -99.09401)
			(xy 124.745624 -99.08388) (xy 124.801358 -99.081843) (xy 124.856795 -99.087943) (xy 124.910752 -99.102049)
			(xy 124.962081 -99.123861) (xy 125.009687 -99.152915) (xy 125.052555 -99.18859) (xy 125.089772 -99.230127)
			(xy 125.098714 -99.243642) (xy 135.047988 -99.243642) (xy 135.052059 -99.18802) (xy 135.064185 -99.133583)
			(xy 135.084108 -99.081492) (xy 135.111404 -99.032857) (xy 135.14549 -98.988714) (xy 135.185639 -98.950005)
			(xy 135.230997 -98.917554) (xy 135.280597 -98.892053) (xy 135.333381 -98.874046) (xy 135.388224 -98.863916)
			(xy 135.443958 -98.861879) (xy 135.499395 -98.867979) (xy 135.553352 -98.882085) (xy 135.604681 -98.903897)
			(xy 135.652287 -98.932951) (xy 135.695155 -98.968626) (xy 135.732372 -99.010163) (xy 135.763145 -99.056676)
			(xy 135.786817 -99.107173) (xy 135.802885 -99.16058) (xy 135.811005 -99.215756) (xy 135.811514 -99.243642)
			(xy 135.811005 -99.271528) (xy 135.802885 -99.326704) (xy 135.786817 -99.380111) (xy 135.763145 -99.430608)
			(xy 135.732372 -99.477121) (xy 135.695155 -99.518658) (xy 135.652287 -99.554333) (xy 135.604681 -99.583387)
			(xy 135.553352 -99.605199) (xy 135.499395 -99.619305) (xy 135.483209 -99.621086) (xy 137.294618 -99.621086)
			(xy 137.298689 -99.565464) (xy 137.310815 -99.511027) (xy 137.330738 -99.458936) (xy 137.358034 -99.410301)
			(xy 137.39212 -99.366158) (xy 137.432269 -99.327449) (xy 137.477627 -99.294998) (xy 137.527227 -99.269497)
			(xy 137.580011 -99.25149) (xy 137.634854 -99.24136) (xy 137.690588 -99.239323) (xy 137.729839 -99.243642)
			(xy 139.729462 -99.243642) (xy 139.733533 -99.18802) (xy 139.745659 -99.133583) (xy 139.765582 -99.081492)
			(xy 139.792878 -99.032857) (xy 139.826964 -98.988714) (xy 139.867113 -98.950005) (xy 139.912471 -98.917554)
			(xy 139.962071 -98.892053) (xy 140.014855 -98.874046) (xy 140.069698 -98.863916) (xy 140.125432 -98.861879)
			(xy 140.180869 -98.867979) (xy 140.234826 -98.882085) (xy 140.286155 -98.903897) (xy 140.333761 -98.932951)
			(xy 140.376629 -98.968626) (xy 140.413846 -99.010163) (xy 140.444619 -99.056676) (xy 140.468291 -99.107173)
			(xy 140.484359 -99.16058) (xy 140.492479 -99.215756) (xy 140.492988 -99.243642) (xy 140.492479 -99.271528)
			(xy 140.484359 -99.326704) (xy 140.468291 -99.380111) (xy 140.444619 -99.430608) (xy 140.413846 -99.477121)
			(xy 140.376629 -99.518658) (xy 140.333761 -99.554333) (xy 140.286155 -99.583387) (xy 140.234826 -99.605199)
			(xy 140.180869 -99.619305) (xy 140.125432 -99.625405) (xy 140.069698 -99.623368) (xy 140.014855 -99.613238)
			(xy 139.962071 -99.595231) (xy 139.912471 -99.56973) (xy 139.867113 -99.537279) (xy 139.826964 -99.49857)
			(xy 139.792878 -99.454427) (xy 139.765582 -99.405792) (xy 139.745659 -99.353701) (xy 139.733533 -99.299264)
			(xy 139.729462 -99.243642) (xy 137.729839 -99.243642) (xy 137.746025 -99.245423) (xy 137.799982 -99.259529)
			(xy 137.851311 -99.281341) (xy 137.898917 -99.310395) (xy 137.941785 -99.34607) (xy 137.979002 -99.387607)
			(xy 138.009775 -99.43412) (xy 138.033447 -99.484617) (xy 138.049515 -99.538024) (xy 138.057635 -99.5932)
			(xy 138.058144 -99.621086) (xy 138.057635 -99.648972) (xy 138.049515 -99.704148) (xy 138.033447 -99.757555)
			(xy 138.009775 -99.808052) (xy 137.979002 -99.854565) (xy 137.941785 -99.896102) (xy 137.898917 -99.931777)
			(xy 137.851311 -99.960831) (xy 137.799982 -99.982643) (xy 137.746025 -99.996749) (xy 137.690588 -100.002849)
			(xy 137.634854 -100.000812) (xy 137.580011 -99.990682) (xy 137.527227 -99.972675) (xy 137.477627 -99.947174)
			(xy 137.432269 -99.914723) (xy 137.39212 -99.876014) (xy 137.358034 -99.831871) (xy 137.330738 -99.783236)
			(xy 137.310815 -99.731145) (xy 137.298689 -99.676708) (xy 137.294618 -99.621086) (xy 135.483209 -99.621086)
			(xy 135.443958 -99.625405) (xy 135.388224 -99.623368) (xy 135.333381 -99.613238) (xy 135.280597 -99.595231)
			(xy 135.230997 -99.56973) (xy 135.185639 -99.537279) (xy 135.14549 -99.49857) (xy 135.111404 -99.454427)
			(xy 135.084108 -99.405792) (xy 135.064185 -99.353701) (xy 135.052059 -99.299264) (xy 135.047988 -99.243642)
			(xy 125.098714 -99.243642) (xy 125.120545 -99.27664) (xy 125.144217 -99.327137) (xy 125.160285 -99.380544)
			(xy 125.168405 -99.43572) (xy 125.168914 -99.463606) (xy 125.168405 -99.491492) (xy 125.160285 -99.546668)
			(xy 125.144217 -99.600075) (xy 125.120545 -99.650572) (xy 125.089772 -99.697085) (xy 125.052555 -99.738622)
			(xy 125.009687 -99.774297) (xy 124.962081 -99.803351) (xy 124.910752 -99.825163) (xy 124.856795 -99.839269)
			(xy 124.801358 -99.845369) (xy 124.745624 -99.843332) (xy 124.690781 -99.833202) (xy 124.637997 -99.815195)
			(xy 124.588397 -99.789694) (xy 124.543039 -99.757243) (xy 124.50289 -99.718534) (xy 124.468804 -99.674391)
			(xy 124.441508 -99.625756) (xy 124.421585 -99.573665) (xy 124.409459 -99.519228) (xy 124.405388 -99.463606)
			(xy 120.50141 -99.463606) (xy 120.500901 -99.491492) (xy 120.492781 -99.546668) (xy 120.476713 -99.600075)
			(xy 120.453041 -99.650572) (xy 120.422268 -99.697085) (xy 120.385051 -99.738622) (xy 120.342183 -99.774297)
			(xy 120.294577 -99.803351) (xy 120.243248 -99.825163) (xy 120.189291 -99.839269) (xy 120.133854 -99.845369)
			(xy 120.07812 -99.843332) (xy 120.023277 -99.833202) (xy 119.970493 -99.815195) (xy 119.920893 -99.789694)
			(xy 119.875535 -99.757243) (xy 119.835386 -99.718534) (xy 119.8013 -99.674391) (xy 119.774004 -99.625756)
			(xy 119.754081 -99.573665) (xy 119.741955 -99.519228) (xy 119.737884 -99.463606) (xy 94.402055 -99.463606)
			(xy 94.401639 -99.486412) (xy 94.393519 -99.541588) (xy 94.377451 -99.594995) (xy 94.353779 -99.645492)
			(xy 94.323006 -99.692005) (xy 94.285789 -99.733542) (xy 94.242921 -99.769217) (xy 94.195315 -99.798271)
			(xy 94.143986 -99.820083) (xy 94.090029 -99.834189) (xy 94.034592 -99.840289) (xy 93.978858 -99.838252)
			(xy 93.924015 -99.828122) (xy 93.871231 -99.810115) (xy 93.821631 -99.784614) (xy 93.776273 -99.752163)
			(xy 93.736124 -99.713454) (xy 93.702038 -99.669311) (xy 93.674742 -99.620676) (xy 93.654819 -99.568585)
			(xy 93.642693 -99.514148) (xy 93.638622 -99.458526) (xy 88.669455 -99.458526) (xy 88.669113 -99.477268)
			(xy 88.660993 -99.532444) (xy 88.644925 -99.585851) (xy 88.621253 -99.636348) (xy 88.59048 -99.682861)
			(xy 88.553263 -99.724398) (xy 88.510395 -99.760073) (xy 88.462789 -99.789127) (xy 88.41146 -99.810939)
			(xy 88.357503 -99.825045) (xy 88.302066 -99.831145) (xy 88.246332 -99.829108) (xy 88.191489 -99.818978)
			(xy 88.138705 -99.800971) (xy 88.089105 -99.77547) (xy 88.043747 -99.743019) (xy 88.003598 -99.70431)
			(xy 87.969512 -99.660167) (xy 87.942216 -99.611532) (xy 87.922293 -99.559441) (xy 87.910167 -99.505004)
			(xy 87.906096 -99.449382) (xy 86.786103 -99.449382) (xy 86.349339 -100.226368) (xy 119.200166 -100.226368)
			(xy 119.204237 -100.170746) (xy 119.216363 -100.116309) (xy 119.236286 -100.064218) (xy 119.263582 -100.015583)
			(xy 119.297668 -99.97144) (xy 119.337817 -99.932731) (xy 119.383175 -99.90028) (xy 119.432775 -99.874779)
			(xy 119.485559 -99.856772) (xy 119.540402 -99.846642) (xy 119.596136 -99.844605) (xy 119.651573 -99.850705)
			(xy 119.70553 -99.864811) (xy 119.756859 -99.886623) (xy 119.804465 -99.915677) (xy 119.847333 -99.951352)
			(xy 119.88455 -99.992889) (xy 119.915323 -100.039402) (xy 119.938995 -100.089899) (xy 119.955063 -100.143306)
			(xy 119.963183 -100.198482) (xy 119.963692 -100.226368) (xy 119.963183 -100.254254) (xy 119.955063 -100.30943)
			(xy 119.938995 -100.362837) (xy 119.915323 -100.413334) (xy 119.88455 -100.459847) (xy 119.847333 -100.501384)
			(xy 119.804465 -100.537059) (xy 119.756859 -100.566113) (xy 119.70553 -100.587925) (xy 119.651573 -100.602031)
			(xy 119.596136 -100.608131) (xy 119.540402 -100.606094) (xy 119.485559 -100.595964) (xy 119.432775 -100.577957)
			(xy 119.383175 -100.552456) (xy 119.337817 -100.520005) (xy 119.297668 -100.481296) (xy 119.263582 -100.437153)
			(xy 119.236286 -100.388518) (xy 119.216363 -100.336427) (xy 119.204237 -100.28199) (xy 119.200166 -100.226368)
			(xy 86.349339 -100.226368) (xy 85.807741 -101.189848) (xy 96.99349 -101.189848) (xy 96.99349 -101.135352)
			(xy 97.001245 -101.08141) (xy 97.016598 -101.02912) (xy 97.039235 -100.979547) (xy 97.068696 -100.933701)
			(xy 97.104382 -100.892513) (xy 97.145565 -100.856822) (xy 97.191409 -100.827356) (xy 97.240979 -100.804713)
			(xy 97.293266 -100.789355) (xy 97.347208 -100.781593) (xy 97.374456 -100.781104) (xy 97.401825 -100.781595)
			(xy 97.456003 -100.789407) (xy 97.508506 -100.80489) (xy 97.558254 -100.827726) (xy 97.604221 -100.857445)
			(xy 97.625154 -100.875084) (xy 97.625408 -100.875338) (xy 97.632485 -100.880938) (xy 97.649409 -100.887176)
			(xy 97.658428 -100.88753) (xy 97.725484 -100.88753) (xy 97.734499 -100.887159) (xy 97.751416 -100.88092)
			(xy 97.758504 -100.875338) (xy 97.758504 -100.875084) (xy 97.758758 -100.875084) (xy 97.779693 -100.857449)
			(xy 97.825665 -100.827737) (xy 97.875412 -100.8049) (xy 97.927912 -100.789408) (xy 97.982087 -100.781579)
			(xy 98.009456 -100.781104) (xy 98.036712 -100.78154) (xy 98.090669 -100.789292) (xy 98.142974 -100.804645)
			(xy 98.192561 -100.827285) (xy 98.238422 -100.856753) (xy 98.279621 -100.892448) (xy 98.31532 -100.933643)
			(xy 98.343963 -100.978208) (xy 134.74395 -100.978208) (xy 134.748021 -100.922586) (xy 134.760147 -100.868149)
			(xy 134.78007 -100.816058) (xy 134.807366 -100.767423) (xy 134.841452 -100.72328) (xy 134.881601 -100.684571)
			(xy 134.926959 -100.65212) (xy 134.976559 -100.626619) (xy 135.029343 -100.608612) (xy 135.084186 -100.598482)
			(xy 135.13992 -100.596445) (xy 135.195357 -100.602545) (xy 135.249314 -100.616651) (xy 135.300643 -100.638463)
			(xy 135.348249 -100.667517) (xy 135.391117 -100.703192) (xy 135.428334 -100.744729) (xy 135.459107 -100.791242)
			(xy 135.482779 -100.841739) (xy 135.498847 -100.895146) (xy 135.506967 -100.950322) (xy 135.507476 -100.978208)
			(xy 135.506967 -101.006094) (xy 135.498847 -101.06127) (xy 135.482779 -101.114677) (xy 135.459107 -101.165174)
			(xy 135.428334 -101.211687) (xy 135.391117 -101.253224) (xy 135.348249 -101.288899) (xy 135.300643 -101.317953)
			(xy 135.249314 -101.339765) (xy 135.195357 -101.353871) (xy 135.13992 -101.359971) (xy 135.084186 -101.357934)
			(xy 135.029343 -101.347804) (xy 134.976559 -101.329797) (xy 134.926959 -101.304296) (xy 134.881601 -101.271845)
			(xy 134.841452 -101.233136) (xy 134.807366 -101.188993) (xy 134.78007 -101.140358) (xy 134.760147 -101.088267)
			(xy 134.748021 -101.03383) (xy 134.74395 -100.978208) (xy 98.343963 -100.978208) (xy 98.344793 -100.9795)
			(xy 98.36744 -101.029085) (xy 98.382799 -101.081388) (xy 98.390557 -101.135344) (xy 98.390557 -101.189856)
			(xy 98.382799 -101.243812) (xy 98.36744 -101.296115) (xy 98.344793 -101.3457) (xy 98.31532 -101.391557)
			(xy 98.279621 -101.432752) (xy 98.238422 -101.468447) (xy 98.192561 -101.497915) (xy 98.142974 -101.520555)
			(xy 98.090669 -101.535908) (xy 98.036712 -101.54366) (xy 98.009456 -101.54412) (xy 97.982086 -101.543641)
			(xy 97.927907 -101.535829) (xy 97.875403 -101.520344) (xy 97.825656 -101.497505) (xy 97.779689 -101.467781)
			(xy 97.758758 -101.45014) (xy 97.758504 -101.449886) (xy 97.751422 -101.444293) (xy 97.734502 -101.438051)
			(xy 97.725484 -101.437694) (xy 97.658428 -101.437694) (xy 97.649413 -101.438066) (xy 97.632496 -101.444303)
			(xy 97.625408 -101.449886) (xy 97.625408 -101.45014) (xy 97.625154 -101.45014) (xy 97.604218 -101.467774)
			(xy 97.558246 -101.497485) (xy 97.508499 -101.520322) (xy 97.455999 -101.535814) (xy 97.401825 -101.543645)
			(xy 97.374456 -101.54412) (xy 97.347208 -101.543607) (xy 97.293266 -101.535845) (xy 97.240979 -101.520487)
			(xy 97.191409 -101.497844) (xy 97.145565 -101.468378) (xy 97.104382 -101.432687) (xy 97.068696 -101.391499)
			(xy 97.039235 -101.345653) (xy 97.016598 -101.29608) (xy 97.001245 -101.24379) (xy 96.99349 -101.189848)
			(xy 85.807741 -101.189848) (xy 85.588892 -101.579172) (xy 87.770714 -101.579172) (xy 87.774785 -101.52355)
			(xy 87.786911 -101.469113) (xy 87.806834 -101.417022) (xy 87.83413 -101.368387) (xy 87.868216 -101.324244)
			(xy 87.908365 -101.285535) (xy 87.953723 -101.253084) (xy 88.003323 -101.227583) (xy 88.056107 -101.209576)
			(xy 88.11095 -101.199446) (xy 88.166684 -101.197409) (xy 88.222121 -101.203509) (xy 88.276078 -101.217615)
			(xy 88.327407 -101.239427) (xy 88.375013 -101.268481) (xy 88.417881 -101.304156) (xy 88.455098 -101.345693)
			(xy 88.485871 -101.392206) (xy 88.509543 -101.442703) (xy 88.525611 -101.49611) (xy 88.533731 -101.551286)
			(xy 88.53424 -101.579172) (xy 88.533731 -101.607058) (xy 88.525611 -101.662234) (xy 88.509543 -101.715641)
			(xy 88.485871 -101.766138) (xy 88.455098 -101.812651) (xy 88.417881 -101.854188) (xy 88.397963 -101.870764)
			(xy 93.23908 -101.870764) (xy 93.243151 -101.815142) (xy 93.255277 -101.760705) (xy 93.2752 -101.708614)
			(xy 93.302496 -101.659979) (xy 93.336582 -101.615836) (xy 93.376731 -101.577127) (xy 93.422089 -101.544676)
			(xy 93.471689 -101.519175) (xy 93.524473 -101.501168) (xy 93.579316 -101.491038) (xy 93.63505 -101.489001)
			(xy 93.690487 -101.495101) (xy 93.744444 -101.509207) (xy 93.795773 -101.531019) (xy 93.843379 -101.560073)
			(xy 93.886247 -101.595748) (xy 93.923464 -101.637285) (xy 93.954237 -101.683798) (xy 93.977909 -101.734295)
			(xy 93.993977 -101.787702) (xy 94.002097 -101.842878) (xy 94.002606 -101.870764) (xy 94.002097 -101.89865)
			(xy 93.993977 -101.953826) (xy 93.977909 -102.007233) (xy 93.954237 -102.05773) (xy 93.923464 -102.104243)
			(xy 93.899978 -102.130455) (xy 96.543029 -102.130455) (xy 96.543029 -102.075945) (xy 96.550787 -102.021989)
			(xy 96.566145 -101.969686) (xy 96.58879 -101.920102) (xy 96.618261 -101.874245) (xy 96.653959 -101.833049)
			(xy 96.695156 -101.797353) (xy 96.741014 -101.767883) (xy 96.790599 -101.74524) (xy 96.842902 -101.729884)
			(xy 96.896859 -101.722128) (xy 96.924114 -101.721666) (xy 96.951485 -101.722108) (xy 97.005666 -101.729929)
			(xy 97.05817 -101.745423) (xy 97.107917 -101.76827) (xy 97.153882 -101.798001) (xy 97.174812 -101.815646)
			(xy 97.175066 -101.8159) (xy 97.182158 -101.821478) (xy 97.199071 -101.82773) (xy 97.208086 -101.828092)
			(xy 97.275142 -101.828092) (xy 97.284156 -101.827709) (xy 97.301073 -101.82148) (xy 97.308162 -101.8159)
			(xy 97.308162 -101.815646) (xy 97.308416 -101.815646) (xy 97.329375 -101.79804) (xy 97.37534 -101.768322)
			(xy 97.42508 -101.745479) (xy 97.477575 -101.72998) (xy 97.531747 -101.722144) (xy 97.559114 -101.721666)
			(xy 97.586363 -101.722205) (xy 97.640305 -101.729963) (xy 97.692595 -101.745318) (xy 97.742167 -101.767958)
			(xy 97.788012 -101.797423) (xy 97.829198 -101.833112) (xy 97.864885 -101.874299) (xy 97.894348 -101.920146)
			(xy 97.916987 -101.969719) (xy 97.93234 -102.022009) (xy 97.940096 -102.075951) (xy 97.940096 -102.130449)
			(xy 97.93234 -102.184391) (xy 97.916987 -102.236681) (xy 97.894348 -102.286254) (xy 97.864885 -102.332101)
			(xy 97.829198 -102.373288) (xy 97.788012 -102.408977) (xy 97.742167 -102.438442) (xy 97.692595 -102.461082)
			(xy 97.640305 -102.476437) (xy 97.586363 -102.484195) (xy 97.559114 -102.484682) (xy 97.531744 -102.484212)
			(xy 97.477565 -102.476396) (xy 97.425062 -102.460908) (xy 97.375315 -102.438067) (xy 97.329348 -102.408343)
			(xy 97.308416 -102.390702) (xy 97.308162 -102.390448) (xy 97.301066 -102.384875) (xy 97.284156 -102.378621)
			(xy 97.275142 -102.378256) (xy 97.208086 -102.378256) (xy 97.199067 -102.378594) (xy 97.18215 -102.384854)
			(xy 97.175066 -102.390448) (xy 97.175066 -102.390702) (xy 97.174812 -102.390702) (xy 97.153886 -102.408349)
			(xy 97.107912 -102.43806) (xy 97.058163 -102.460894) (xy 97.005661 -102.476383) (xy 96.951484 -102.484209)
			(xy 96.924114 -102.484682) (xy 96.896859 -102.484272) (xy 96.842902 -102.476516) (xy 96.790599 -102.46116)
			(xy 96.741014 -102.438517) (xy 96.695156 -102.409047) (xy 96.653959 -102.373351) (xy 96.618261 -102.332155)
			(xy 96.58879 -102.286298) (xy 96.566145 -102.236714) (xy 96.550787 -102.184411) (xy 96.543029 -102.130455)
			(xy 93.899978 -102.130455) (xy 93.886247 -102.14578) (xy 93.843379 -102.181455) (xy 93.795773 -102.210509)
			(xy 93.744444 -102.232321) (xy 93.690487 -102.246427) (xy 93.63505 -102.252527) (xy 93.579316 -102.25049)
			(xy 93.524473 -102.24036) (xy 93.471689 -102.222353) (xy 93.422089 -102.196852) (xy 93.376731 -102.164401)
			(xy 93.336582 -102.125692) (xy 93.302496 -102.081549) (xy 93.2752 -102.032914) (xy 93.255277 -101.980823)
			(xy 93.243151 -101.926386) (xy 93.23908 -101.870764) (xy 88.397963 -101.870764) (xy 88.375013 -101.889863)
			(xy 88.327407 -101.918917) (xy 88.276078 -101.940729) (xy 88.222121 -101.954835) (xy 88.166684 -101.960935)
			(xy 88.11095 -101.958898) (xy 88.056107 -101.948768) (xy 88.003323 -101.930761) (xy 87.953723 -101.90526)
			(xy 87.908365 -101.872809) (xy 87.868216 -101.8341) (xy 87.83413 -101.789957) (xy 87.806834 -101.741322)
			(xy 87.786911 -101.689231) (xy 87.774785 -101.634794) (xy 87.770714 -101.579172) (xy 85.588892 -101.579172)
			(xy 84.711936 -103.13924) (xy 89.507058 -103.13924) (xy 89.511129 -103.083618) (xy 89.523255 -103.029181)
			(xy 89.543178 -102.97709) (xy 89.570474 -102.928455) (xy 89.60456 -102.884312) (xy 89.644709 -102.845603)
			(xy 89.690067 -102.813152) (xy 89.739667 -102.787651) (xy 89.792451 -102.769644) (xy 89.847294 -102.759514)
			(xy 89.903028 -102.757477) (xy 89.958465 -102.763577) (xy 90.012422 -102.777683) (xy 90.063751 -102.799495)
			(xy 90.111357 -102.828549) (xy 90.154225 -102.864224) (xy 90.191442 -102.905761) (xy 90.222215 -102.952274)
			(xy 90.245887 -103.002771) (xy 90.261955 -103.056178) (xy 90.270075 -103.111354) (xy 90.270584 -103.13924)
			(xy 90.270075 -103.167126) (xy 90.261955 -103.222302) (xy 90.245887 -103.275709) (xy 90.222215 -103.326206)
			(xy 90.191442 -103.372719) (xy 90.154225 -103.414256) (xy 90.111357 -103.449931) (xy 90.063751 -103.478985)
			(xy 90.012422 -103.500797) (xy 89.958465 -103.514903) (xy 89.903028 -103.521003) (xy 89.847294 -103.518966)
			(xy 89.792451 -103.508836) (xy 89.739667 -103.490829) (xy 89.690067 -103.465328) (xy 89.644709 -103.432877)
			(xy 89.60456 -103.394168) (xy 89.570474 -103.350025) (xy 89.543178 -103.30139) (xy 89.523255 -103.249299)
			(xy 89.511129 -103.194862) (xy 89.507058 -103.13924) (xy 84.711936 -103.13924) (xy 83.848687 -104.674924)
			(xy 88.559384 -104.674924) (xy 88.563455 -104.619302) (xy 88.575581 -104.564865) (xy 88.595504 -104.512774)
			(xy 88.6228 -104.464139) (xy 88.656886 -104.419996) (xy 88.697035 -104.381287) (xy 88.742393 -104.348836)
			(xy 88.791993 -104.323335) (xy 88.844777 -104.305328) (xy 88.89962 -104.295198) (xy 88.955354 -104.293161)
			(xy 89.010791 -104.299261) (xy 89.064748 -104.313367) (xy 89.116077 -104.335179) (xy 89.163683 -104.364233)
			(xy 89.206551 -104.399908) (xy 89.243768 -104.441445) (xy 89.274541 -104.487958) (xy 89.298213 -104.538455)
			(xy 89.314281 -104.591862) (xy 89.322401 -104.647038) (xy 89.32291 -104.674924) (xy 89.322401 -104.70281)
			(xy 89.314281 -104.757986) (xy 89.298213 -104.811393) (xy 89.274541 -104.86189) (xy 89.243768 -104.908403)
			(xy 89.206551 -104.94994) (xy 89.163683 -104.985615) (xy 89.116077 -105.014669) (xy 89.064748 -105.036481)
			(xy 89.010791 -105.050587) (xy 88.955354 -105.056687) (xy 88.89962 -105.05465) (xy 88.844777 -105.04452)
			(xy 88.791993 -105.026513) (xy 88.742393 -105.001012) (xy 88.697035 -104.968561) (xy 88.656886 -104.929852)
			(xy 88.6228 -104.885709) (xy 88.595504 -104.837074) (xy 88.575581 -104.784983) (xy 88.563455 -104.730546)
			(xy 88.559384 -104.674924) (xy 83.848687 -104.674924) (xy 83.1088 -105.991152) (xy 82.910426 -106.343704)
			(xy 82.908622 -106.347315) (xy 82.906073 -106.354973) (xy 82.905346 -106.358944) (xy 82.799582 -107.210352)
			(xy 85.74278 -107.210352) (xy 85.74328 -107.181612) (xy 85.751909 -107.124784) (xy 85.768965 -107.069893)
			(xy 85.794062 -107.018182) (xy 85.826631 -106.97082) (xy 85.845904 -106.949494) (xy 85.852508 -106.942636)
			(xy 85.85962 -106.924602) (xy 85.85962 -106.835702) (xy 85.852508 -106.817668) (xy 85.845904 -106.81081)
			(xy 85.826587 -106.789524) (xy 85.794025 -106.742154) (xy 85.768937 -106.690435) (xy 85.751891 -106.635539)
			(xy 85.743274 -106.578706) (xy 85.743279 -106.521224) (xy 85.751907 -106.464393) (xy 85.768963 -106.409499)
			(xy 85.79406 -106.357785) (xy 85.826631 -106.310421) (xy 85.845904 -106.289094) (xy 85.852508 -106.282236)
			(xy 85.85962 -106.264202) (xy 85.85962 -106.175302) (xy 85.852508 -106.157268) (xy 85.845904 -106.15041)
			(xy 85.826622 -106.129093) (xy 85.794055 -106.081729) (xy 85.768963 -106.030015) (xy 85.751916 -105.975122)
			(xy 85.743298 -105.918292) (xy 85.74278 -105.889552) (xy 85.743266 -105.862301) (xy 85.751022 -105.808353)
			(xy 85.766377 -105.756058) (xy 85.789019 -105.706481) (xy 85.818485 -105.660631) (xy 85.854176 -105.61944)
			(xy 85.895367 -105.583749) (xy 85.941217 -105.554283) (xy 85.990794 -105.531641) (xy 86.043089 -105.516286)
			(xy 86.097037 -105.50853) (xy 86.151539 -105.50853) (xy 86.205487 -105.516286) (xy 86.257782 -105.531641)
			(xy 86.307359 -105.554283) (xy 86.353209 -105.583749) (xy 86.3944 -105.61944) (xy 86.430091 -105.660631)
			(xy 86.459557 -105.706481) (xy 86.482199 -105.756058) (xy 86.497554 -105.808353) (xy 86.50531 -105.862301)
			(xy 86.505796 -105.889552) (xy 86.505305 -105.918292) (xy 86.496675 -105.975121) (xy 86.479617 -106.030012)
			(xy 86.454518 -106.081723) (xy 86.421946 -106.129084) (xy 86.402672 -106.15041) (xy 86.396068 -106.157268)
			(xy 86.388956 -106.175302) (xy 86.388956 -106.264202) (xy 86.396068 -106.282236) (xy 86.402672 -106.289094)
			(xy 86.421895 -106.310462) (xy 86.454463 -106.357817) (xy 86.479557 -106.409522) (xy 86.496611 -106.464407)
			(xy 86.505238 -106.521229) (xy 86.505243 -106.578702) (xy 86.496626 -106.635525) (xy 86.479583 -106.690412)
			(xy 86.454498 -106.742122) (xy 86.421939 -106.789483) (xy 86.402672 -106.81081) (xy 86.396068 -106.817668)
			(xy 86.388956 -106.835702) (xy 86.388956 -106.924602) (xy 86.396068 -106.942636) (xy 86.402672 -106.949494)
			(xy 86.421969 -106.970798) (xy 86.454531 -107.018167) (xy 86.473954 -107.058206) (xy 89.573862 -107.058206)
			(xy 89.5744 -107.029468) (xy 89.58302 -106.972641) (xy 89.600068 -106.917751) (xy 89.625156 -106.866039)
			(xy 89.657717 -106.818676) (xy 89.676986 -106.797348) (xy 89.68359 -106.79049) (xy 89.690702 -106.772456)
			(xy 89.690702 -106.683556) (xy 89.68359 -106.665522) (xy 89.676986 -106.658664) (xy 89.657723 -106.637331)
			(xy 89.625161 -106.589969) (xy 89.600071 -106.538258) (xy 89.583023 -106.483368) (xy 89.5744 -106.426542)
			(xy 89.5744 -106.369066) (xy 89.583021 -106.31224) (xy 89.600068 -106.257351) (xy 89.625156 -106.205639)
			(xy 89.657717 -106.158276) (xy 89.676986 -106.136948) (xy 89.68359 -106.13009) (xy 89.690702 -106.112056)
			(xy 89.690702 -106.023156) (xy 89.68359 -106.005122) (xy 89.676986 -105.998264) (xy 89.657726 -105.976927)
			(xy 89.625156 -105.929569) (xy 89.600061 -105.87786) (xy 89.583008 -105.822971) (xy 89.574384 -105.766145)
			(xy 89.573862 -105.737406) (xy 89.574348 -105.710155) (xy 89.582104 -105.656207) (xy 89.597459 -105.603912)
			(xy 89.620101 -105.554335) (xy 89.649567 -105.508485) (xy 89.685258 -105.467294) (xy 89.726449 -105.431603)
			(xy 89.772299 -105.402137) (xy 89.821876 -105.379495) (xy 89.874171 -105.36414) (xy 89.928119 -105.356384)
			(xy 89.982621 -105.356384) (xy 90.036569 -105.36414) (xy 90.088864 -105.379495) (xy 90.138441 -105.402137)
			(xy 90.184291 -105.431603) (xy 90.225482 -105.467294) (xy 90.261173 -105.508485) (xy 90.290639 -105.554335)
			(xy 90.313281 -105.603912) (xy 90.328636 -105.656207) (xy 90.336392 -105.710155) (xy 90.336878 -105.737406)
			(xy 90.336337 -105.766144) (xy 90.327715 -105.82297) (xy 90.310668 -105.877859) (xy 90.285581 -105.929571)
			(xy 90.253022 -105.976936) (xy 90.233754 -105.998264) (xy 90.22715 -106.005122) (xy 90.220038 -106.023156)
			(xy 90.220038 -106.112056) (xy 90.22715 -106.13009) (xy 90.233754 -106.136948) (xy 90.253032 -106.158269)
			(xy 90.285599 -106.205632) (xy 90.310691 -106.257344) (xy 90.327742 -106.312236) (xy 90.336365 -106.369065)
			(xy 90.336364 -106.426544) (xy 90.32774 -106.483372) (xy 90.310688 -106.538264) (xy 90.285594 -106.589976)
			(xy 90.253026 -106.637338) (xy 90.233754 -106.658664) (xy 90.22715 -106.665522) (xy 90.220038 -106.683556)
			(xy 90.220038 -106.772456) (xy 90.22715 -106.79049) (xy 90.233754 -106.797348) (xy 90.253026 -106.818674)
			(xy 90.285593 -106.866036) (xy 90.310685 -106.917748) (xy 90.327735 -106.972639) (xy 90.336357 -107.029467)
			(xy 90.336878 -107.058206) (xy 90.336392 -107.085457) (xy 90.328636 -107.139405) (xy 90.313281 -107.1917)
			(xy 90.290639 -107.241277) (xy 90.261173 -107.287127) (xy 90.225482 -107.328318) (xy 90.184291 -107.364009)
			(xy 90.138441 -107.393475) (xy 90.088864 -107.416117) (xy 90.036569 -107.431472) (xy 89.982621 -107.439228)
			(xy 89.928119 -107.439228) (xy 89.874171 -107.431472) (xy 89.821876 -107.416117) (xy 89.772299 -107.393475)
			(xy 89.726449 -107.364009) (xy 89.685258 -107.328318) (xy 89.649567 -107.287127) (xy 89.620101 -107.241277)
			(xy 89.597459 -107.1917) (xy 89.582104 -107.139405) (xy 89.574348 -107.085457) (xy 89.573862 -107.058206)
			(xy 86.473954 -107.058206) (xy 86.479619 -107.069884) (xy 86.496663 -107.12478) (xy 86.505279 -107.181611)
			(xy 86.505796 -107.210352) (xy 86.50531 -107.237603) (xy 86.497554 -107.291551) (xy 86.482199 -107.343846)
			(xy 86.459557 -107.393423) (xy 86.430091 -107.439273) (xy 86.3944 -107.480464) (xy 86.353209 -107.516155)
			(xy 86.307359 -107.545621) (xy 86.257782 -107.568263) (xy 86.205487 -107.583618) (xy 86.151539 -107.591374)
			(xy 86.097037 -107.591374) (xy 86.043089 -107.583618) (xy 85.990794 -107.568263) (xy 85.941217 -107.545621)
			(xy 85.895367 -107.516155) (xy 85.854176 -107.480464) (xy 85.818485 -107.439273) (xy 85.789019 -107.393423)
			(xy 85.766377 -107.343846) (xy 85.751022 -107.291551) (xy 85.743266 -107.237603) (xy 85.74278 -107.210352)
			(xy 82.799582 -107.210352) (xy 82.654409 -108.379006) (xy 90.462862 -108.379006) (xy 90.4634 -108.350268)
			(xy 90.47202 -108.293441) (xy 90.489068 -108.238551) (xy 90.514156 -108.186839) (xy 90.546717 -108.139476)
			(xy 90.565986 -108.118148) (xy 90.57259 -108.11129) (xy 90.579702 -108.093256) (xy 90.579702 -108.004356)
			(xy 90.57259 -107.986322) (xy 90.565986 -107.979464) (xy 90.546723 -107.958131) (xy 90.514161 -107.910769)
			(xy 90.489071 -107.859058) (xy 90.472023 -107.804168) (xy 90.4634 -107.747342) (xy 90.4634 -107.689866)
			(xy 90.472021 -107.63304) (xy 90.489068 -107.578151) (xy 90.514156 -107.526439) (xy 90.546717 -107.479076)
			(xy 90.565986 -107.457748) (xy 90.57259 -107.45089) (xy 90.579702 -107.432856) (xy 90.579702 -107.343956)
			(xy 90.57259 -107.325922) (xy 90.565986 -107.319064) (xy 90.546723 -107.297731) (xy 90.514161 -107.250369)
			(xy 90.489071 -107.198658) (xy 90.472023 -107.143768) (xy 90.4634 -107.086942) (xy 90.4634 -107.029466)
			(xy 90.472021 -106.97264) (xy 90.489068 -106.917751) (xy 90.514156 -106.866039) (xy 90.546717 -106.818676)
			(xy 90.565986 -106.797348) (xy 90.57259 -106.79049) (xy 90.579702 -106.772456) (xy 90.579702 -106.683556)
			(xy 90.57259 -106.665522) (xy 90.565986 -106.658664) (xy 90.546723 -106.637331) (xy 90.514161 -106.589969)
			(xy 90.489071 -106.538258) (xy 90.472023 -106.483368) (xy 90.4634 -106.426542) (xy 90.4634 -106.369066)
			(xy 90.472021 -106.31224) (xy 90.489068 -106.257351) (xy 90.514156 -106.205639) (xy 90.546717 -106.158276)
			(xy 90.565986 -106.136948) (xy 90.57259 -106.13009) (xy 90.579702 -106.112056) (xy 90.579702 -106.023156)
			(xy 90.57259 -106.005122) (xy 90.565986 -105.998264) (xy 90.546723 -105.976931) (xy 90.514161 -105.929569)
			(xy 90.489071 -105.877858) (xy 90.472023 -105.822968) (xy 90.4634 -105.766142) (xy 90.4634 -105.708666)
			(xy 90.472021 -105.65184) (xy 90.489068 -105.596951) (xy 90.514156 -105.545239) (xy 90.546717 -105.497876)
			(xy 90.565986 -105.476548) (xy 90.57259 -105.46969) (xy 90.579702 -105.451656) (xy 90.579702 -105.362756)
			(xy 90.57259 -105.344722) (xy 90.565986 -105.337864) (xy 90.546723 -105.316531) (xy 90.514161 -105.269169)
			(xy 90.489071 -105.217458) (xy 90.472023 -105.162568) (xy 90.4634 -105.105742) (xy 90.4634 -105.048266)
			(xy 90.472021 -104.99144) (xy 90.489068 -104.936551) (xy 90.514156 -104.884839) (xy 90.546717 -104.837476)
			(xy 90.565986 -104.816148) (xy 90.57259 -104.80929) (xy 90.579702 -104.791256) (xy 90.579702 -104.702356)
			(xy 90.57259 -104.684322) (xy 90.565986 -104.677464) (xy 90.546723 -104.656131) (xy 90.514161 -104.608769)
			(xy 90.489071 -104.557058) (xy 90.472023 -104.502168) (xy 90.4634 -104.445342) (xy 90.4634 -104.387866)
			(xy 90.472021 -104.33104) (xy 90.489068 -104.276151) (xy 90.514156 -104.224439) (xy 90.546717 -104.177076)
			(xy 90.565986 -104.155748) (xy 90.57259 -104.14889) (xy 90.579702 -104.130856) (xy 90.579702 -104.041956)
			(xy 90.57259 -104.023922) (xy 90.565986 -104.017064) (xy 90.546723 -103.995731) (xy 90.514161 -103.948369)
			(xy 90.489071 -103.896658) (xy 90.472023 -103.841768) (xy 90.4634 -103.784942) (xy 90.4634 -103.727466)
			(xy 90.472021 -103.67064) (xy 90.489068 -103.615751) (xy 90.514156 -103.564039) (xy 90.546717 -103.516676)
			(xy 90.565986 -103.495348) (xy 90.57259 -103.48849) (xy 90.579702 -103.470456) (xy 90.579702 -103.381556)
			(xy 90.57259 -103.363522) (xy 90.565986 -103.356664) (xy 90.546726 -103.335327) (xy 90.514156 -103.287969)
			(xy 90.489061 -103.23626) (xy 90.472008 -103.181371) (xy 90.463384 -103.124545) (xy 90.462862 -103.095806)
			(xy 90.463323 -103.068599) (xy 90.471046 -103.014737) (xy 90.486351 -102.962521) (xy 90.508926 -102.913012)
			(xy 90.538312 -102.867217) (xy 90.573912 -102.826066) (xy 90.615003 -102.790397) (xy 90.637614 -102.775258)
			(xy 90.645996 -102.769924) (xy 90.657172 -102.753668) (xy 90.67546 -102.674674) (xy 90.67726 -102.665044)
			(xy 90.674266 -102.645705) (xy 90.669618 -102.637082) (xy 90.669364 -102.637082) (xy 90.669364 -102.636574)
			(xy 90.656155 -102.614065) (xy 90.635301 -102.566222) (xy 90.621152 -102.515987) (xy 90.613969 -102.464294)
			(xy 90.613484 -102.4382) (xy 90.61397 -102.410949) (xy 90.621726 -102.357001) (xy 90.637081 -102.304706)
			(xy 90.659723 -102.255129) (xy 90.689189 -102.209279) (xy 90.72488 -102.168088) (xy 90.766071 -102.132397)
			(xy 90.811921 -102.102931) (xy 90.861498 -102.080289) (xy 90.913793 -102.064934) (xy 90.967741 -102.057178)
			(xy 91.022243 -102.057178) (xy 91.076191 -102.064934) (xy 91.128486 -102.080289) (xy 91.178063 -102.102931)
			(xy 91.223913 -102.132397) (xy 91.265104 -102.168088) (xy 91.300795 -102.209279) (xy 91.330261 -102.255129)
			(xy 91.352903 -102.304706) (xy 91.368258 -102.357001) (xy 91.376014 -102.410949) (xy 91.3765 -102.4382)
			(xy 91.376061 -102.465408) (xy 91.368336 -102.519271) (xy 91.353029 -102.571489) (xy 91.330451 -102.620999)
			(xy 91.301061 -102.666794) (xy 91.265456 -102.707943) (xy 91.224361 -102.743611) (xy 91.201748 -102.758748)
			(xy 91.193366 -102.764082) (xy 91.18219 -102.780338) (xy 91.163902 -102.859332) (xy 91.16209 -102.868961)
			(xy 91.16509 -102.888303) (xy 91.169744 -102.896924) (xy 91.169998 -102.896924) (xy 91.169998 -102.897432)
			(xy 91.183206 -102.919942) (xy 91.204061 -102.967784) (xy 91.218211 -103.018019) (xy 91.225393 -103.069712)
			(xy 91.225878 -103.095806) (xy 91.225337 -103.124544) (xy 91.216715 -103.18137) (xy 91.199668 -103.236259)
			(xy 91.174581 -103.287971) (xy 91.142022 -103.335336) (xy 91.122754 -103.356664) (xy 91.11615 -103.363522)
			(xy 91.109038 -103.381556) (xy 91.109038 -103.470456) (xy 91.11615 -103.48849) (xy 91.122754 -103.495348)
			(xy 91.142032 -103.516669) (xy 91.174599 -103.564032) (xy 91.199691 -103.615744) (xy 91.216742 -103.670636)
			(xy 91.225365 -103.727465) (xy 91.225364 -103.784944) (xy 91.21674 -103.841772) (xy 91.199688 -103.896664)
			(xy 91.174594 -103.948376) (xy 91.142026 -103.995738) (xy 91.122754 -104.017064) (xy 91.117128 -104.022906)
			(xy 95.86595 -104.022906) (xy 95.866405 -103.996591) (xy 95.873641 -103.944462) (xy 95.887961 -103.893818)
			(xy 95.909095 -103.845619) (xy 95.936644 -103.800776) (xy 95.970087 -103.760138) (xy 95.98914 -103.741982)
			(xy 95.996543 -103.734461) (xy 96.005069 -103.715181) (xy 96.00565 -103.704644) (xy 96.00565 -103.629968)
			(xy 96.005083 -103.619423) (xy 95.996573 -103.600128) (xy 95.98914 -103.59263) (xy 95.970095 -103.574465)
			(xy 95.936639 -103.533836) (xy 95.90908 -103.488997) (xy 95.88794 -103.440798) (xy 95.87362 -103.390153)
			(xy 95.866391 -103.338021) (xy 95.86595 -103.311706) (xy 95.866483 -103.284457) (xy 95.874238 -103.230513)
			(xy 95.88959 -103.178222) (xy 95.912227 -103.128647) (xy 95.941689 -103.082799) (xy 95.977376 -103.04161)
			(xy 96.01856 -103.005918) (xy 96.064405 -102.97645) (xy 96.113977 -102.953807) (xy 96.166266 -102.938448)
			(xy 96.220209 -102.930687) (xy 96.247458 -102.930198) (xy 96.275122 -102.930744) (xy 96.329869 -102.938737)
			(xy 96.38289 -102.954548) (xy 96.433074 -102.977846) (xy 96.47937 -103.008142) (xy 96.520809 -103.044802)
			(xy 96.556524 -103.087059) (xy 96.571562 -103.110284) (xy 96.578207 -103.119953) (xy 96.598063 -103.1324)
			(xy 96.609662 -103.13416) (xy 96.689672 -103.142034) (xy 96.70131 -103.142646) (xy 96.723146 -103.13458)
			(xy 96.731582 -103.12654) (xy 96.731836 -103.126286) (xy 96.749915 -103.107703) (xy 96.790247 -103.075125)
			(xy 96.834622 -103.048312) (xy 96.882221 -103.02776) (xy 96.932166 -103.013847) (xy 96.983535 -103.00683)
			(xy 97.009458 -103.006398) (xy 97.03671 -103.006894) (xy 97.09066 -103.014646) (xy 97.142958 -103.029997)
			(xy 97.192538 -103.052635) (xy 97.238392 -103.082099) (xy 97.279585 -103.117789) (xy 97.315279 -103.158979)
			(xy 97.344748 -103.20483) (xy 97.367391 -103.254408) (xy 97.382747 -103.306705) (xy 97.390503 -103.360654)
			(xy 97.390966 -103.387906) (xy 97.390512 -103.415277) (xy 97.382692 -103.469457) (xy 97.367201 -103.52196)
			(xy 97.344356 -103.571707) (xy 97.314629 -103.617673) (xy 97.296986 -103.638604) (xy 97.296732 -103.638858)
			(xy 97.291149 -103.645947) (xy 97.284902 -103.662862) (xy 97.28454 -103.671878) (xy 97.28454 -103.68565)
			(xy 108.492794 -103.68565) (xy 108.492794 -103.63115) (xy 108.50055 -103.577205) (xy 108.515905 -103.524912)
			(xy 108.538545 -103.475338) (xy 108.56801 -103.429489) (xy 108.603699 -103.388301) (xy 108.644888 -103.352611)
			(xy 108.690736 -103.323146) (xy 108.740311 -103.300505) (xy 108.792603 -103.285151) (xy 108.846548 -103.277394)
			(xy 108.873798 -103.276908) (xy 108.900112 -103.277374) (xy 108.952241 -103.284609) (xy 109.002884 -103.298928)
			(xy 109.051083 -103.320061) (xy 109.095926 -103.347607) (xy 109.136566 -103.381046) (xy 109.154722 -103.400098)
			(xy 109.162234 -103.407511) (xy 109.181521 -103.416029) (xy 109.19206 -103.416608) (xy 109.266736 -103.416608)
			(xy 109.277283 -103.416056) (xy 109.296579 -103.407537) (xy 109.304074 -103.400098) (xy 109.323894 -103.37931)
			(xy 109.368666 -103.343335) (xy 109.418324 -103.314475) (xy 109.471746 -103.293382) (xy 109.527725 -103.280533)
			(xy 109.584998 -103.276218) (xy 109.642271 -103.280533) (xy 109.69825 -103.293382) (xy 109.751672 -103.314475)
			(xy 109.80133 -103.343335) (xy 109.846102 -103.37931) (xy 109.865922 -103.400098) (xy 109.873434 -103.407511)
			(xy 109.892721 -103.416029) (xy 109.90326 -103.416608) (xy 109.977936 -103.416608) (xy 109.988483 -103.416056)
			(xy 110.007779 -103.407537) (xy 110.015274 -103.400098) (xy 110.033449 -103.381062) (xy 110.074074 -103.347603)
			(xy 110.118911 -103.320041) (xy 110.167108 -103.2989) (xy 110.217752 -103.284578) (xy 110.269883 -103.277349)
			(xy 110.296198 -103.276908) (xy 110.323452 -103.277339) (xy 110.377406 -103.285096) (xy 110.429706 -103.300452)
			(xy 110.479288 -103.323096) (xy 110.525144 -103.352565) (xy 110.566338 -103.38826) (xy 110.602034 -103.429455)
			(xy 110.631503 -103.47531) (xy 110.654147 -103.524892) (xy 110.669504 -103.577192) (xy 110.677261 -103.631146)
			(xy 110.677261 -103.685654) (xy 110.669504 -103.739608) (xy 110.654147 -103.791908) (xy 110.631503 -103.84149)
			(xy 110.602034 -103.887345) (xy 110.566338 -103.92854) (xy 110.525144 -103.964235) (xy 110.479288 -103.993704)
			(xy 110.429706 -104.016348) (xy 110.377406 -104.031704) (xy 110.323452 -104.039461) (xy 110.296198 -104.039924)
			(xy 110.269884 -104.03945) (xy 110.217756 -104.032216) (xy 110.167114 -104.017897) (xy 110.118915 -103.996766)
			(xy 110.074072 -103.969221) (xy 110.033431 -103.935785) (xy 110.015274 -103.916734) (xy 110.00776 -103.909324)
			(xy 109.988474 -103.900803) (xy 109.977936 -103.900224) (xy 109.90326 -103.900224) (xy 109.892712 -103.900765)
			(xy 109.873416 -103.909291) (xy 109.865922 -103.916734) (xy 109.846102 -103.937522) (xy 109.80133 -103.973497)
			(xy 109.751672 -104.002357) (xy 109.69825 -104.02345) (xy 109.642271 -104.036299) (xy 109.584998 -104.040614)
			(xy 109.527725 -104.036299) (xy 109.471746 -104.02345) (xy 109.418324 -104.002357) (xy 109.368666 -103.973497)
			(xy 109.323894 -103.937522) (xy 109.304074 -103.916734) (xy 109.29656 -103.909324) (xy 109.277274 -103.900803)
			(xy 109.266736 -103.900224) (xy 109.19206 -103.900224) (xy 109.181512 -103.900765) (xy 109.162216 -103.909291)
			(xy 109.154722 -103.916734) (xy 109.136555 -103.935778) (xy 109.095927 -103.969235) (xy 109.051089 -103.996795)
			(xy 109.002891 -104.017935) (xy 108.952245 -104.032255) (xy 108.900113 -104.039483) (xy 108.873798 -104.039924)
			(xy 108.846548 -104.039406) (xy 108.792603 -104.031649) (xy 108.740311 -104.016295) (xy 108.690736 -103.993654)
			(xy 108.644888 -103.964189) (xy 108.603699 -103.928499) (xy 108.56801 -103.887311) (xy 108.538545 -103.841462)
			(xy 108.515905 -103.791888) (xy 108.50055 -103.739595) (xy 108.492794 -103.68565) (xy 97.28454 -103.68565)
			(xy 97.28454 -103.738934) (xy 97.284872 -103.747954) (xy 97.291136 -103.764871) (xy 97.296732 -103.771954)
			(xy 97.296986 -103.771954) (xy 97.296986 -103.772208) (xy 97.31464 -103.793128) (xy 97.34435 -103.839104)
			(xy 97.367183 -103.888854) (xy 97.382671 -103.941358) (xy 97.390495 -103.995536) (xy 97.390966 -104.022906)
			(xy 97.39055 -104.050161) (xy 97.382791 -104.104116) (xy 97.367432 -104.156417) (xy 97.344786 -104.206)
			(xy 97.315314 -104.251855) (xy 97.279615 -104.293049) (xy 97.238417 -104.328742) (xy 97.192558 -104.358209)
			(xy 97.142972 -104.380849) (xy 97.090669 -104.396201) (xy 97.036713 -104.403954) (xy 97.009458 -104.404414)
			(xy 96.980541 -104.403886) (xy 96.923369 -104.395164) (xy 96.868169 -104.37791) (xy 96.816206 -104.35252)
			(xy 96.768673 -104.319576) (xy 96.726657 -104.279834) (xy 96.708468 -104.257348) (xy 96.700874 -104.248527)
			(xy 96.679963 -104.238353) (xy 96.668336 -104.23779) (xy 96.58858 -104.23779) (xy 96.576949 -104.238336)
			(xy 96.55604 -104.24852) (xy 96.548448 -104.257348) (xy 96.530242 -104.279818) (xy 96.488224 -104.319552)
			(xy 96.440692 -104.352491) (xy 96.388734 -104.377882) (xy 96.333539 -104.395141) (xy 96.276373 -104.403876)
			(xy 96.247458 -104.404414) (xy 96.220206 -104.403961) (xy 96.166257 -104.396199) (xy 96.113962 -104.380839)
			(xy 96.064385 -104.358193) (xy 96.018536 -104.328723) (xy 95.977346 -104.293029) (xy 95.941655 -104.251836)
			(xy 95.912189 -104.205983) (xy 95.889548 -104.156404) (xy 95.874193 -104.104107) (xy 95.866436 -104.050158)
			(xy 95.86595 -104.022906) (xy 91.117128 -104.022906) (xy 91.11615 -104.023922) (xy 91.109038 -104.041956)
			(xy 91.109038 -104.130856) (xy 91.11615 -104.14889) (xy 91.122754 -104.155748) (xy 91.142032 -104.177069)
			(xy 91.174599 -104.224432) (xy 91.199691 -104.276144) (xy 91.216742 -104.331036) (xy 91.225365 -104.387865)
			(xy 91.225364 -104.445344) (xy 91.21674 -104.502172) (xy 91.199688 -104.557064) (xy 91.174594 -104.608776)
			(xy 91.142026 -104.656138) (xy 91.122754 -104.677464) (xy 91.11615 -104.684322) (xy 91.109038 -104.702356)
			(xy 91.109038 -104.791256) (xy 91.11615 -104.80929) (xy 91.122754 -104.816148) (xy 91.142032 -104.837469)
			(xy 91.174599 -104.884832) (xy 91.199691 -104.936544) (xy 91.216742 -104.991436) (xy 91.225365 -105.048265)
			(xy 91.225364 -105.084455) (xy 95.743949 -105.084455) (xy 95.743949 -105.029945) (xy 95.751707 -104.975991)
			(xy 95.767065 -104.92369) (xy 95.78971 -104.874107) (xy 95.819181 -104.828252) (xy 95.854879 -104.787058)
			(xy 95.896076 -104.751363) (xy 95.941933 -104.721896) (xy 95.991518 -104.699255) (xy 96.04382 -104.683901)
			(xy 96.097775 -104.676147) (xy 96.12503 -104.675686) (xy 96.152401 -104.676138) (xy 96.20658 -104.68396)
			(xy 96.259083 -104.699452) (xy 96.30883 -104.722297) (xy 96.354796 -104.752024) (xy 96.375728 -104.769666)
			(xy 96.375982 -104.76992) (xy 96.383068 -104.775507) (xy 96.399985 -104.781753) (xy 96.409002 -104.782112)
			(xy 96.476058 -104.782112) (xy 96.485073 -104.781732) (xy 96.50199 -104.7755) (xy 96.509078 -104.76992)
			(xy 96.509078 -104.769666) (xy 96.509332 -104.769666) (xy 96.530265 -104.752025) (xy 96.576233 -104.722301)
			(xy 96.625979 -104.699455) (xy 96.678481 -104.683959) (xy 96.732659 -104.67613) (xy 96.787401 -104.67613)
			(xy 96.841579 -104.683959) (xy 96.894081 -104.699455) (xy 96.943827 -104.722301) (xy 96.989795 -104.752025)
			(xy 97.010728 -104.769666) (xy 97.010982 -104.76992) (xy 97.018068 -104.775507) (xy 97.034985 -104.781753)
			(xy 97.044002 -104.782112) (xy 97.111058 -104.782112) (xy 97.120073 -104.781732) (xy 97.13699 -104.7755)
			(xy 97.144078 -104.76992) (xy 97.144078 -104.769666) (xy 97.144332 -104.769666) (xy 97.165265 -104.752025)
			(xy 97.211233 -104.722301) (xy 97.260979 -104.699455) (xy 97.313481 -104.683959) (xy 97.367659 -104.67613)
			(xy 97.422401 -104.67613) (xy 97.476579 -104.683959) (xy 97.529081 -104.699455) (xy 97.578827 -104.722301)
			(xy 97.624795 -104.752025) (xy 97.645728 -104.769666) (xy 97.645982 -104.76992) (xy 97.653068 -104.775507)
			(xy 97.669985 -104.781753) (xy 97.679002 -104.782112) (xy 97.746058 -104.782112) (xy 97.755073 -104.781732)
			(xy 97.77199 -104.7755) (xy 97.779078 -104.76992) (xy 97.779078 -104.769666) (xy 97.779332 -104.769666)
			(xy 97.800275 -104.75204) (xy 97.846245 -104.722327) (xy 97.89599 -104.699489) (xy 97.948488 -104.683995)
			(xy 98.002662 -104.676163) (xy 98.03003 -104.675686) (xy 98.057279 -104.676186) (xy 98.111223 -104.683946)
			(xy 98.163513 -104.699303) (xy 98.213086 -104.721946) (xy 98.233191 -104.734868) (xy 124.328172 -104.734868)
			(xy 124.332243 -104.679246) (xy 124.344369 -104.624809) (xy 124.364292 -104.572718) (xy 124.391588 -104.524083)
			(xy 124.425674 -104.47994) (xy 124.465823 -104.441231) (xy 124.511181 -104.40878) (xy 124.560781 -104.383279)
			(xy 124.613565 -104.365272) (xy 124.668408 -104.355142) (xy 124.724142 -104.353105) (xy 124.779579 -104.359205)
			(xy 124.833536 -104.373311) (xy 124.884865 -104.395123) (xy 124.932471 -104.424177) (xy 124.975339 -104.459852)
			(xy 125.012556 -104.501389) (xy 125.043329 -104.547902) (xy 125.067001 -104.598399) (xy 125.083069 -104.651806)
			(xy 125.091189 -104.706982) (xy 125.091698 -104.734868) (xy 125.091189 -104.762754) (xy 125.083069 -104.81793)
			(xy 125.067001 -104.871337) (xy 125.043329 -104.921834) (xy 125.012556 -104.968347) (xy 124.975339 -105.009884)
			(xy 124.932471 -105.045559) (xy 124.884865 -105.074613) (xy 124.833536 -105.096425) (xy 124.779579 -105.110531)
			(xy 124.724142 -105.116631) (xy 124.668408 -105.114594) (xy 124.613565 -105.104464) (xy 124.560781 -105.086457)
			(xy 124.511181 -105.060956) (xy 124.465823 -105.028505) (xy 124.425674 -104.989796) (xy 124.391588 -104.945653)
			(xy 124.364292 -104.897018) (xy 124.344369 -104.844927) (xy 124.332243 -104.79049) (xy 124.328172 -104.734868)
			(xy 98.233191 -104.734868) (xy 98.258932 -104.751412) (xy 98.300118 -104.787103) (xy 98.335806 -104.828292)
			(xy 98.365269 -104.87414) (xy 98.387907 -104.923715) (xy 98.403261 -104.976006) (xy 98.411016 -105.029951)
			(xy 98.411016 -105.084449) (xy 98.403261 -105.138394) (xy 98.387907 -105.190685) (xy 98.365269 -105.24026)
			(xy 98.335806 -105.286108) (xy 98.300118 -105.327297) (xy 98.258932 -105.362988) (xy 98.213086 -105.392454)
			(xy 98.163513 -105.415097) (xy 98.111223 -105.430454) (xy 98.057279 -105.438214) (xy 98.03003 -105.438702)
			(xy 98.00266 -105.438218) (xy 97.948482 -105.430404) (xy 97.895979 -105.414919) (xy 97.846232 -105.392082)
			(xy 97.800264 -105.362361) (xy 97.779332 -105.344722) (xy 97.779078 -105.344468) (xy 97.772005 -105.338863)
			(xy 97.755078 -105.332628) (xy 97.746058 -105.332276) (xy 97.679002 -105.332276) (xy 97.669986 -105.332639)
			(xy 97.653069 -105.338883) (xy 97.645982 -105.344468) (xy 97.645728 -105.344722) (xy 97.624795 -105.362363)
			(xy 97.578827 -105.392087) (xy 97.529081 -105.414933) (xy 97.476579 -105.430429) (xy 97.422401 -105.438258)
			(xy 97.367659 -105.438258) (xy 97.313481 -105.430429) (xy 97.260979 -105.414933) (xy 97.211233 -105.392087)
			(xy 97.165265 -105.362363) (xy 97.144332 -105.344722) (xy 97.144078 -105.344468) (xy 97.137005 -105.338863)
			(xy 97.120078 -105.332628) (xy 97.111058 -105.332276) (xy 97.044002 -105.332276) (xy 97.034986 -105.332639)
			(xy 97.018069 -105.338883) (xy 97.010982 -105.344468) (xy 97.010982 -105.344722) (xy 97.010728 -105.344722)
			(xy 96.989795 -105.362363) (xy 96.943827 -105.392087) (xy 96.894081 -105.414933) (xy 96.841579 -105.430429)
			(xy 96.787401 -105.438258) (xy 96.732659 -105.438258) (xy 96.678481 -105.430429) (xy 96.625979 -105.414933)
			(xy 96.576233 -105.392087) (xy 96.530265 -105.362363) (xy 96.509332 -105.344722) (xy 96.509078 -105.344468)
			(xy 96.502005 -105.338863) (xy 96.485078 -105.332628) (xy 96.476058 -105.332276) (xy 96.409002 -105.332276)
			(xy 96.399986 -105.332639) (xy 96.383069 -105.338883) (xy 96.375982 -105.344468) (xy 96.375982 -105.344722)
			(xy 96.375728 -105.344722) (xy 96.354799 -105.362365) (xy 96.308825 -105.392075) (xy 96.259077 -105.41491)
			(xy 96.206575 -105.4304) (xy 96.152399 -105.438228) (xy 96.12503 -105.438702) (xy 96.097775 -105.438253)
			(xy 96.04382 -105.430499) (xy 95.991518 -105.415145) (xy 95.941933 -105.392504) (xy 95.896076 -105.363037)
			(xy 95.854879 -105.327342) (xy 95.819181 -105.286148) (xy 95.78971 -105.240293) (xy 95.767065 -105.19071)
			(xy 95.751707 -105.138409) (xy 95.743949 -105.084455) (xy 91.225364 -105.084455) (xy 91.225364 -105.105744)
			(xy 91.21674 -105.162572) (xy 91.199688 -105.217464) (xy 91.174594 -105.269176) (xy 91.142026 -105.316538)
			(xy 91.122754 -105.337864) (xy 91.11615 -105.344722) (xy 91.109038 -105.362756) (xy 91.109038 -105.451656)
			(xy 91.11615 -105.46969) (xy 91.122754 -105.476548) (xy 91.142032 -105.497869) (xy 91.174599 -105.545232)
			(xy 91.199691 -105.596944) (xy 91.216742 -105.651836) (xy 91.225365 -105.708665) (xy 91.225364 -105.766144)
			(xy 91.21674 -105.822972) (xy 91.199688 -105.877864) (xy 91.174594 -105.929576) (xy 91.142026 -105.976938)
			(xy 91.122754 -105.998264) (xy 91.11615 -106.005122) (xy 91.109038 -106.023156) (xy 91.109038 -106.112056)
			(xy 91.11615 -106.13009) (xy 91.122754 -106.136948) (xy 91.142032 -106.158269) (xy 91.174599 -106.205632)
			(xy 91.199691 -106.257344) (xy 91.206082 -106.277918) (xy 123.681234 -106.277918) (xy 123.685305 -106.222296)
			(xy 123.697431 -106.167859) (xy 123.717354 -106.115768) (xy 123.74465 -106.067133) (xy 123.778736 -106.02299)
			(xy 123.818885 -105.984281) (xy 123.864243 -105.95183) (xy 123.913843 -105.926329) (xy 123.966627 -105.908322)
			(xy 124.02147 -105.898192) (xy 124.077204 -105.896155) (xy 124.132641 -105.902255) (xy 124.186598 -105.916361)
			(xy 124.237927 -105.938173) (xy 124.285533 -105.967227) (xy 124.328401 -106.002902) (xy 124.365618 -106.044439)
			(xy 124.396391 -106.090952) (xy 124.420063 -106.141449) (xy 124.436131 -106.194856) (xy 124.444251 -106.250032)
			(xy 124.44476 -106.277918) (xy 124.444251 -106.305804) (xy 124.436131 -106.36098) (xy 124.420063 -106.414387)
			(xy 124.396391 -106.464884) (xy 124.365618 -106.511397) (xy 124.328401 -106.552934) (xy 124.285533 -106.588609)
			(xy 124.237927 -106.617663) (xy 124.186598 -106.639475) (xy 124.132641 -106.653581) (xy 124.077204 -106.659681)
			(xy 124.02147 -106.657644) (xy 123.966627 -106.647514) (xy 123.913843 -106.629507) (xy 123.864243 -106.604006)
			(xy 123.818885 -106.571555) (xy 123.778736 -106.532846) (xy 123.74465 -106.488703) (xy 123.717354 -106.440068)
			(xy 123.697431 -106.387977) (xy 123.685305 -106.33354) (xy 123.681234 -106.277918) (xy 91.206082 -106.277918)
			(xy 91.216742 -106.312236) (xy 91.225365 -106.369065) (xy 91.225364 -106.426544) (xy 91.21674 -106.483372)
			(xy 91.199688 -106.538264) (xy 91.174594 -106.589976) (xy 91.142026 -106.637338) (xy 91.122754 -106.658664)
			(xy 91.11615 -106.665522) (xy 91.109038 -106.683556) (xy 91.109038 -106.772456) (xy 91.11615 -106.79049)
			(xy 91.122754 -106.797348) (xy 91.127367 -106.80245) (xy 108.420905 -106.80245) (xy 108.420905 -106.74795)
			(xy 108.428662 -106.694005) (xy 108.444016 -106.641712) (xy 108.466657 -106.592138) (xy 108.496123 -106.54629)
			(xy 108.531814 -106.505102) (xy 108.573003 -106.469413) (xy 108.618852 -106.439949) (xy 108.668427 -106.417311)
			(xy 108.72072 -106.401958) (xy 108.774666 -106.394204) (xy 108.801916 -106.393742) (xy 108.828231 -106.394185)
			(xy 108.880361 -106.401423) (xy 108.931005 -106.415746) (xy 108.979204 -106.436883) (xy 109.024047 -106.464434)
			(xy 109.064685 -106.497878) (xy 109.08284 -106.516932) (xy 109.090354 -106.524343) (xy 109.109639 -106.532865)
			(xy 109.120178 -106.533442) (xy 109.194854 -106.533442) (xy 109.205401 -106.532889) (xy 109.224695 -106.524369)
			(xy 109.232192 -106.516932) (xy 109.252012 -106.496144) (xy 109.296784 -106.460169) (xy 109.346442 -106.431309)
			(xy 109.399864 -106.410216) (xy 109.455843 -106.397367) (xy 109.513116 -106.393052) (xy 109.570389 -106.397367)
			(xy 109.626368 -106.410216) (xy 109.67979 -106.431309) (xy 109.729448 -106.460169) (xy 109.77422 -106.496144)
			(xy 109.79404 -106.516932) (xy 109.801554 -106.524343) (xy 109.820839 -106.532865) (xy 109.831378 -106.533442)
			(xy 109.906054 -106.533442) (xy 109.916601 -106.532889) (xy 109.935895 -106.524369) (xy 109.943392 -106.516932)
			(xy 109.961565 -106.497893) (xy 110.00219 -106.464434) (xy 110.047026 -106.436871) (xy 110.095224 -106.41573)
			(xy 110.145869 -106.401409) (xy 110.198001 -106.394182) (xy 110.224316 -106.393742) (xy 110.25157 -106.394129)
			(xy 110.305523 -106.401888) (xy 110.357823 -106.417247) (xy 110.407405 -106.439892) (xy 110.453259 -106.469362)
			(xy 110.494453 -106.505059) (xy 110.530147 -106.546254) (xy 110.559616 -106.59211) (xy 110.582259 -106.641692)
			(xy 110.597615 -106.693993) (xy 110.605372 -106.747946) (xy 110.605372 -106.802454) (xy 110.597615 -106.856407)
			(xy 110.582259 -106.908708) (xy 110.559616 -106.95829) (xy 110.530147 -107.004146) (xy 110.494453 -107.045341)
			(xy 110.453259 -107.081038) (xy 110.407405 -107.110508) (xy 110.357823 -107.133153) (xy 110.305523 -107.148512)
			(xy 110.25157 -107.156271) (xy 110.224316 -107.156758) (xy 110.198002 -107.156293) (xy 110.145873 -107.14906)
			(xy 110.095229 -107.134741) (xy 110.04703 -107.113608) (xy 110.002187 -107.086061) (xy 109.961548 -107.052621)
			(xy 109.943392 -107.033568) (xy 109.935866 -107.026171) (xy 109.91659 -107.017642) (xy 109.906054 -107.017058)
			(xy 109.831378 -107.017058) (xy 109.820833 -107.017628) (xy 109.801538 -107.026136) (xy 109.79404 -107.033568)
			(xy 109.77422 -107.054356) (xy 109.729448 -107.090331) (xy 109.67979 -107.119191) (xy 109.626368 -107.140284)
			(xy 109.570389 -107.153133) (xy 109.513116 -107.157448) (xy 109.455843 -107.153133) (xy 109.399864 -107.140284)
			(xy 109.346442 -107.119191) (xy 109.296784 -107.090331) (xy 109.252012 -107.054356) (xy 109.232192 -107.033568)
			(xy 109.224666 -107.026171) (xy 109.20539 -107.017642) (xy 109.194854 -107.017058) (xy 109.120178 -107.017058)
			(xy 109.109633 -107.017628) (xy 109.090338 -107.026136) (xy 109.08284 -107.033568) (xy 109.0647 -107.05264)
			(xy 109.024068 -107.086096) (xy 108.979225 -107.113654) (xy 108.931021 -107.13479) (xy 108.88037 -107.149103)
			(xy 108.828233 -107.156323) (xy 108.801916 -107.156758) (xy 108.774666 -107.156196) (xy 108.72072 -107.148442)
			(xy 108.668427 -107.133089) (xy 108.618852 -107.110451) (xy 108.573003 -107.080987) (xy 108.531813 -107.045298)
			(xy 108.496123 -107.00411) (xy 108.466657 -106.958262) (xy 108.444016 -106.908688) (xy 108.428662 -106.856395)
			(xy 108.420905 -106.80245) (xy 91.127367 -106.80245) (xy 91.142032 -106.818669) (xy 91.174599 -106.866032)
			(xy 91.199691 -106.917744) (xy 91.216742 -106.972636) (xy 91.225365 -107.029465) (xy 91.225364 -107.086944)
			(xy 91.21674 -107.143772) (xy 91.199688 -107.198664) (xy 91.174594 -107.250376) (xy 91.142026 -107.297738)
			(xy 91.122754 -107.319064) (xy 91.11615 -107.325922) (xy 91.109038 -107.343956) (xy 91.109038 -107.432856)
			(xy 91.11615 -107.45089) (xy 91.122754 -107.457748) (xy 91.142032 -107.479069) (xy 91.174599 -107.526432)
			(xy 91.199691 -107.578144) (xy 91.216742 -107.633036) (xy 91.225365 -107.689865) (xy 91.225364 -107.740253)
			(xy 95.684273 -107.740253) (xy 95.684273 -107.685747) (xy 95.692031 -107.631795) (xy 95.707388 -107.579496)
			(xy 95.730033 -107.529916) (xy 95.759503 -107.484063) (xy 95.795199 -107.442871) (xy 95.836395 -107.407179)
			(xy 95.882251 -107.377714) (xy 95.931834 -107.355074) (xy 95.984134 -107.339723) (xy 96.038087 -107.331971)
			(xy 96.06534 -107.33151) (xy 96.092709 -107.332009) (xy 96.146887 -107.339818) (xy 96.19939 -107.3553)
			(xy 96.249137 -107.378134) (xy 96.295105 -107.407852) (xy 96.316038 -107.42549) (xy 96.316292 -107.425744)
			(xy 96.323373 -107.431339) (xy 96.340294 -107.437579) (xy 96.349312 -107.437936) (xy 96.416368 -107.437936)
			(xy 96.425382 -107.437556) (xy 96.442299 -107.431323) (xy 96.449388 -107.425744) (xy 96.449388 -107.42549)
			(xy 96.449642 -107.42549) (xy 96.470575 -107.407849) (xy 96.516543 -107.378125) (xy 96.566289 -107.355279)
			(xy 96.618791 -107.339783) (xy 96.672969 -107.331954) (xy 96.727711 -107.331954) (xy 96.781889 -107.339783)
			(xy 96.834391 -107.355279) (xy 96.884137 -107.378125) (xy 96.930105 -107.407849) (xy 96.951038 -107.42549)
			(xy 96.951292 -107.425744) (xy 96.958373 -107.431339) (xy 96.975294 -107.437579) (xy 96.984312 -107.437936)
			(xy 97.051368 -107.437936) (xy 97.060382 -107.437556) (xy 97.077299 -107.431323) (xy 97.084388 -107.425744)
			(xy 97.084388 -107.42549) (xy 97.084642 -107.42549) (xy 97.105575 -107.407849) (xy 97.151543 -107.378125)
			(xy 97.201289 -107.355279) (xy 97.253791 -107.339783) (xy 97.307969 -107.331954) (xy 97.362711 -107.331954)
			(xy 97.416889 -107.339783) (xy 97.469391 -107.355279) (xy 97.519137 -107.378125) (xy 97.565105 -107.407849)
			(xy 97.586038 -107.42549) (xy 97.586292 -107.425744) (xy 97.593373 -107.431339) (xy 97.610294 -107.437579)
			(xy 97.619312 -107.437936) (xy 97.686368 -107.437936) (xy 97.695382 -107.437556) (xy 97.712299 -107.431323)
			(xy 97.719388 -107.425744) (xy 97.719388 -107.42549) (xy 97.719642 -107.42549) (xy 97.740584 -107.407863)
			(xy 97.786554 -107.37815) (xy 97.836299 -107.355312) (xy 97.888798 -107.339818) (xy 97.942972 -107.331986)
			(xy 97.97034 -107.33151) (xy 97.997591 -107.331963) (xy 98.051537 -107.339724) (xy 98.103829 -107.355083)
			(xy 98.153404 -107.377728) (xy 98.199251 -107.407197) (xy 98.240438 -107.44289) (xy 98.276127 -107.484081)
			(xy 98.305591 -107.529932) (xy 98.328231 -107.579508) (xy 98.343584 -107.631803) (xy 98.35134 -107.685749)
			(xy 98.35134 -107.740251) (xy 98.343584 -107.794197) (xy 98.328231 -107.846492) (xy 98.305591 -107.896068)
			(xy 98.276127 -107.941919) (xy 98.240438 -107.98311) (xy 98.199251 -108.018803) (xy 98.153404 -108.048272)
			(xy 98.103829 -108.070917) (xy 98.051537 -108.086276) (xy 97.997591 -108.094037) (xy 97.97034 -108.094526)
			(xy 97.94297 -108.094055) (xy 97.88879 -108.086241) (xy 97.836286 -108.070754) (xy 97.786539 -108.047913)
			(xy 97.740573 -108.018188) (xy 97.719642 -108.000546) (xy 97.719388 -108.000292) (xy 97.71231 -107.994693)
			(xy 97.695387 -107.988454) (xy 97.686368 -107.9881) (xy 97.619312 -107.9881) (xy 97.610296 -107.988463)
			(xy 97.593379 -107.994706) (xy 97.586292 -108.000292) (xy 97.586038 -108.000546) (xy 97.565105 -108.018187)
			(xy 97.519137 -108.047911) (xy 97.469391 -108.070757) (xy 97.416889 -108.086253) (xy 97.362711 -108.094082)
			(xy 97.307969 -108.094082) (xy 97.253791 -108.086253) (xy 97.201289 -108.070757) (xy 97.151543 -108.047911)
			(xy 97.105575 -108.018187) (xy 97.084642 -108.000546) (xy 97.084388 -108.000292) (xy 97.07731 -107.994693)
			(xy 97.060387 -107.988454) (xy 97.051368 -107.9881) (xy 96.984312 -107.9881) (xy 96.975296 -107.988463)
			(xy 96.958379 -107.994706) (xy 96.951292 -108.000292) (xy 96.951292 -108.000546) (xy 96.951038 -108.000546)
			(xy 96.930105 -108.018187) (xy 96.884137 -108.047911) (xy 96.834391 -108.070757) (xy 96.781889 -108.086253)
			(xy 96.727711 -108.094082) (xy 96.672969 -108.094082) (xy 96.618791 -108.086253) (xy 96.566289 -108.070757)
			(xy 96.516543 -108.047911) (xy 96.470575 -108.018187) (xy 96.449642 -108.000546) (xy 96.449388 -108.000292)
			(xy 96.44231 -107.994693) (xy 96.425387 -107.988454) (xy 96.416368 -107.9881) (xy 96.349312 -107.9881)
			(xy 96.340296 -107.988463) (xy 96.323379 -107.994706) (xy 96.316292 -108.000292) (xy 96.316292 -108.000546)
			(xy 96.316038 -108.000546) (xy 96.295095 -108.018172) (xy 96.249126 -108.047888) (xy 96.199382 -108.070727)
			(xy 96.146883 -108.086221) (xy 96.092709 -108.094051) (xy 96.06534 -108.094526) (xy 96.038087 -108.094029)
			(xy 95.984134 -108.086277) (xy 95.931834 -108.070926) (xy 95.882251 -108.048286) (xy 95.836395 -108.018821)
			(xy 95.795199 -107.983129) (xy 95.759503 -107.941937) (xy 95.730033 -107.896084) (xy 95.707388 -107.846504)
			(xy 95.692031 -107.794205) (xy 95.684273 -107.740253) (xy 91.225364 -107.740253) (xy 91.225364 -107.747344)
			(xy 91.21674 -107.804172) (xy 91.199688 -107.859064) (xy 91.174594 -107.910776) (xy 91.142026 -107.958138)
			(xy 91.122754 -107.979464) (xy 91.11615 -107.986322) (xy 91.109038 -108.004356) (xy 91.109038 -108.093256)
			(xy 91.11615 -108.11129) (xy 91.122754 -108.118148) (xy 91.142026 -108.139474) (xy 91.174593 -108.186836)
			(xy 91.199685 -108.238548) (xy 91.216735 -108.293439) (xy 91.225357 -108.350267) (xy 91.225878 -108.379006)
			(xy 91.225392 -108.406257) (xy 91.217636 -108.460205) (xy 91.202281 -108.5125) (xy 91.179639 -108.562077)
			(xy 91.174865 -108.569506) (xy 106.861102 -108.569506) (xy 106.861571 -108.542136) (xy 106.869388 -108.487957)
			(xy 106.884876 -108.435454) (xy 106.907718 -108.385707) (xy 106.937441 -108.33974) (xy 106.955082 -108.318808)
			(xy 106.955336 -108.318554) (xy 106.96091 -108.311459) (xy 106.967163 -108.294549) (xy 106.967528 -108.285534)
			(xy 106.967528 -108.218478) (xy 106.967176 -108.209461) (xy 106.960924 -108.192544) (xy 106.955336 -108.185458)
			(xy 106.955082 -108.185458) (xy 106.955082 -108.185204) (xy 106.937429 -108.164284) (xy 106.907719 -108.118307)
			(xy 106.884887 -108.068557) (xy 106.869399 -108.016054) (xy 106.861574 -107.961876) (xy 106.861102 -107.934506)
			(xy 106.861588 -107.907255) (xy 106.869344 -107.853307) (xy 106.884699 -107.801012) (xy 106.907341 -107.751435)
			(xy 106.936807 -107.705585) (xy 106.972498 -107.664394) (xy 107.013689 -107.628703) (xy 107.059539 -107.599237)
			(xy 107.109116 -107.576595) (xy 107.161411 -107.56124) (xy 107.215359 -107.553484) (xy 107.269861 -107.553484)
			(xy 107.323809 -107.56124) (xy 107.376104 -107.576595) (xy 107.425681 -107.599237) (xy 107.471531 -107.628703)
			(xy 107.512722 -107.664394) (xy 107.548413 -107.705585) (xy 107.577879 -107.751435) (xy 107.600521 -107.801012)
			(xy 107.615876 -107.853307) (xy 107.623632 -107.907255) (xy 107.624118 -107.934506) (xy 107.623675 -107.961877)
			(xy 107.615855 -108.016058) (xy 107.600362 -108.068562) (xy 107.577514 -108.118309) (xy 107.547783 -108.164274)
			(xy 107.530138 -108.185204) (xy 107.529884 -108.185458) (xy 107.524307 -108.192551) (xy 107.518055 -108.209463)
			(xy 107.517692 -108.218478) (xy 107.517692 -108.285534) (xy 107.518035 -108.294552) (xy 107.524293 -108.311469)
			(xy 107.529884 -108.318554) (xy 107.530138 -108.318554) (xy 107.530138 -108.318808) (xy 107.547801 -108.339721)
			(xy 107.577508 -108.3857) (xy 107.600339 -108.435452) (xy 107.615824 -108.487957) (xy 107.623647 -108.542136)
			(xy 107.624118 -108.569506) (xy 107.623632 -108.596757) (xy 107.615876 -108.650705) (xy 107.600521 -108.703)
			(xy 107.577879 -108.752577) (xy 107.548413 -108.798427) (xy 107.512722 -108.839618) (xy 107.471531 -108.875309)
			(xy 107.425681 -108.904775) (xy 107.376104 -108.927417) (xy 107.323809 -108.942772) (xy 107.269861 -108.950528)
			(xy 107.215359 -108.950528) (xy 107.161411 -108.942772) (xy 107.109116 -108.927417) (xy 107.059539 -108.904775)
			(xy 107.013689 -108.875309) (xy 106.972498 -108.839618) (xy 106.936807 -108.798427) (xy 106.907341 -108.752577)
			(xy 106.884699 -108.703) (xy 106.869344 -108.650705) (xy 106.861588 -108.596757) (xy 106.861102 -108.569506)
			(xy 91.174865 -108.569506) (xy 91.150173 -108.607927) (xy 91.114482 -108.649118) (xy 91.073291 -108.684809)
			(xy 91.027441 -108.714275) (xy 90.977864 -108.736917) (xy 90.925569 -108.752272) (xy 90.871621 -108.760028)
			(xy 90.817119 -108.760028) (xy 90.763171 -108.752272) (xy 90.710876 -108.736917) (xy 90.661299 -108.714275)
			(xy 90.615449 -108.684809) (xy 90.574258 -108.649118) (xy 90.538567 -108.607927) (xy 90.509101 -108.562077)
			(xy 90.486459 -108.5125) (xy 90.471104 -108.460205) (xy 90.463348 -108.406257) (xy 90.462862 -108.379006)
			(xy 82.654409 -108.379006) (xy 82.514852 -109.502448) (xy 109.414562 -109.502448) (xy 109.418633 -109.446826)
			(xy 109.430759 -109.392389) (xy 109.450682 -109.340298) (xy 109.477978 -109.291663) (xy 109.512064 -109.24752)
			(xy 109.552213 -109.208811) (xy 109.597571 -109.17636) (xy 109.647171 -109.150859) (xy 109.699955 -109.132852)
			(xy 109.754798 -109.122722) (xy 109.810532 -109.120685) (xy 109.865969 -109.126785) (xy 109.919926 -109.140891)
			(xy 109.971255 -109.162703) (xy 110.018861 -109.191757) (xy 110.061729 -109.227432) (xy 110.098946 -109.268969)
			(xy 110.129719 -109.315482) (xy 110.153391 -109.365979) (xy 110.169459 -109.419386) (xy 110.177579 -109.474562)
			(xy 110.178088 -109.502448) (xy 110.177579 -109.530334) (xy 110.169459 -109.58551) (xy 110.153391 -109.638917)
			(xy 110.129719 -109.689414) (xy 110.118138 -109.706918) (xy 121.915172 -109.706918) (xy 121.919243 -109.651296)
			(xy 121.931369 -109.596859) (xy 121.951292 -109.544768) (xy 121.978588 -109.496133) (xy 122.012674 -109.45199)
			(xy 122.052823 -109.413281) (xy 122.098181 -109.38083) (xy 122.147781 -109.355329) (xy 122.200565 -109.337322)
			(xy 122.255408 -109.327192) (xy 122.311142 -109.325155) (xy 122.366579 -109.331255) (xy 122.420536 -109.345361)
			(xy 122.471865 -109.367173) (xy 122.519471 -109.396227) (xy 122.562339 -109.431902) (xy 122.599556 -109.473439)
			(xy 122.630329 -109.519952) (xy 122.654001 -109.570449) (xy 122.65685 -109.579918) (xy 123.947172 -109.579918)
			(xy 123.951243 -109.524296) (xy 123.963369 -109.469859) (xy 123.983292 -109.417768) (xy 124.010588 -109.369133)
			(xy 124.044674 -109.32499) (xy 124.084823 -109.286281) (xy 124.130181 -109.25383) (xy 124.179781 -109.228329)
			(xy 124.232565 -109.210322) (xy 124.287408 -109.200192) (xy 124.343142 -109.198155) (xy 124.398579 -109.204255)
			(xy 124.452536 -109.218361) (xy 124.503865 -109.240173) (xy 124.551471 -109.269227) (xy 124.594339 -109.304902)
			(xy 124.631556 -109.346439) (xy 124.662329 -109.392952) (xy 124.686001 -109.443449) (xy 124.702069 -109.496856)
			(xy 124.710189 -109.552032) (xy 124.710698 -109.579918) (xy 124.710189 -109.607804) (xy 124.702069 -109.66298)
			(xy 124.686001 -109.716387) (xy 124.662329 -109.766884) (xy 124.631556 -109.813397) (xy 124.594339 -109.854934)
			(xy 124.551471 -109.890609) (xy 124.503865 -109.919663) (xy 124.452536 -109.941475) (xy 124.398579 -109.955581)
			(xy 124.343142 -109.961681) (xy 124.287408 -109.959644) (xy 124.232565 -109.949514) (xy 124.179781 -109.931507)
			(xy 124.130181 -109.906006) (xy 124.084823 -109.873555) (xy 124.044674 -109.834846) (xy 124.010588 -109.790703)
			(xy 123.983292 -109.742068) (xy 123.963369 -109.689977) (xy 123.951243 -109.63554) (xy 123.947172 -109.579918)
			(xy 122.65685 -109.579918) (xy 122.670069 -109.623856) (xy 122.678189 -109.679032) (xy 122.678698 -109.706918)
			(xy 122.678189 -109.734804) (xy 122.670069 -109.78998) (xy 122.654001 -109.843387) (xy 122.630329 -109.893884)
			(xy 122.599556 -109.940397) (xy 122.562339 -109.981934) (xy 122.519471 -110.017609) (xy 122.471865 -110.046663)
			(xy 122.420536 -110.068475) (xy 122.366579 -110.082581) (xy 122.311142 -110.088681) (xy 122.255408 -110.086644)
			(xy 122.200565 -110.076514) (xy 122.147781 -110.058507) (xy 122.098181 -110.033006) (xy 122.052823 -110.000555)
			(xy 122.012674 -109.961846) (xy 121.978588 -109.917703) (xy 121.951292 -109.869068) (xy 121.931369 -109.816977)
			(xy 121.919243 -109.76254) (xy 121.915172 -109.706918) (xy 110.118138 -109.706918) (xy 110.098946 -109.735927)
			(xy 110.061729 -109.777464) (xy 110.018861 -109.813139) (xy 109.971255 -109.842193) (xy 109.919926 -109.864005)
			(xy 109.865969 -109.878111) (xy 109.810532 -109.884211) (xy 109.754798 -109.882174) (xy 109.699955 -109.872044)
			(xy 109.647171 -109.854037) (xy 109.597571 -109.828536) (xy 109.552213 -109.796085) (xy 109.512064 -109.757376)
			(xy 109.477978 -109.713233) (xy 109.450682 -109.664598) (xy 109.430759 -109.612507) (xy 109.418633 -109.55807)
			(xy 109.414562 -109.502448) (xy 82.514852 -109.502448) (xy 82.375832 -110.621572) (xy 90.56116 -110.621572)
			(xy 90.56159 -110.595257) (xy 90.568829 -110.543126) (xy 90.583155 -110.492481) (xy 90.604294 -110.444282)
			(xy 90.631848 -110.39944) (xy 90.665294 -110.358803) (xy 90.68435 -110.340648) (xy 90.691769 -110.333141)
			(xy 90.700285 -110.31385) (xy 90.70086 -110.30331) (xy 90.70086 -110.228634) (xy 90.700338 -110.218083)
			(xy 90.691799 -110.198787) (xy 90.68435 -110.191296) (xy 90.66529 -110.173145) (xy 90.631835 -110.132513)
			(xy 90.604278 -110.087672) (xy 90.583141 -110.03947) (xy 90.568824 -109.988822) (xy 90.561599 -109.936688)
			(xy 90.56116 -109.910372) (xy 90.561646 -109.883121) (xy 90.569402 -109.829173) (xy 90.584757 -109.776878)
			(xy 90.607399 -109.727301) (xy 90.636865 -109.681451) (xy 90.672556 -109.64026) (xy 90.713747 -109.604569)
			(xy 90.759597 -109.575103) (xy 90.809174 -109.552461) (xy 90.861469 -109.537106) (xy 90.915417 -109.52935)
			(xy 90.969919 -109.52935) (xy 91.023867 -109.537106) (xy 91.076162 -109.552461) (xy 91.125739 -109.575103)
			(xy 91.171589 -109.604569) (xy 91.21278 -109.64026) (xy 91.248471 -109.681451) (xy 91.277937 -109.727301)
			(xy 91.300579 -109.776878) (xy 91.315934 -109.829173) (xy 91.32369 -109.883121) (xy 91.324176 -109.910372)
			(xy 91.323764 -109.936688) (xy 91.316519 -109.988819) (xy 91.30219 -110.039463) (xy 91.281047 -110.087662)
			(xy 91.253491 -110.132504) (xy 91.220042 -110.173141) (xy 91.200986 -110.191296) (xy 91.193582 -110.198815)
			(xy 91.185059 -110.218097) (xy 91.184476 -110.228634) (xy 91.184476 -110.30331) (xy 91.184993 -110.313861)
			(xy 91.193538 -110.333156) (xy 91.200986 -110.340648) (xy 91.220055 -110.35879) (xy 91.253512 -110.399422)
			(xy 91.281069 -110.444265) (xy 91.302205 -110.492469) (xy 91.316519 -110.543119) (xy 91.32374 -110.595255)
			(xy 91.324176 -110.621572) (xy 91.32369 -110.648823) (xy 91.315934 -110.702771) (xy 91.300579 -110.755066)
			(xy 91.277937 -110.804643) (xy 91.248471 -110.850493) (xy 91.21278 -110.891684) (xy 91.171589 -110.927375)
			(xy 91.125739 -110.956841) (xy 91.076162 -110.979483) (xy 91.023867 -110.994838) (xy 90.969919 -111.002594)
			(xy 90.915417 -111.002594) (xy 90.861469 -110.994838) (xy 90.809174 -110.979483) (xy 90.759597 -110.956841)
			(xy 90.713747 -110.927375) (xy 90.672556 -110.891684) (xy 90.636865 -110.850493) (xy 90.607399 -110.804643)
			(xy 90.584757 -110.755066) (xy 90.569402 -110.702771) (xy 90.561646 -110.648823) (xy 90.56116 -110.621572)
			(xy 82.375832 -110.621572) (xy 82.190082 -112.11687) (xy 82.167574 -112.297972) (xy 93.069918 -112.297972)
			(xy 93.070361 -112.271657) (xy 93.0776 -112.219527) (xy 93.091924 -112.168884) (xy 93.113061 -112.120685)
			(xy 93.140611 -112.075842) (xy 93.174054 -112.035204) (xy 93.193108 -112.017048) (xy 93.200536 -112.009549)
			(xy 93.209045 -111.990252) (xy 93.209618 -111.97971) (xy 93.209618 -111.905034) (xy 93.209079 -111.894486)
			(xy 93.20055 -111.875191) (xy 93.193108 -111.867696) (xy 93.174059 -111.849534) (xy 93.140601 -111.808906)
			(xy 93.113041 -111.764067) (xy 93.091901 -111.715867) (xy 93.077583 -111.665221) (xy 93.070357 -111.613088)
			(xy 93.069918 -111.586772) (xy 93.070404 -111.559521) (xy 93.07816 -111.505573) (xy 93.093515 -111.453278)
			(xy 93.116157 -111.403701) (xy 93.145623 -111.357851) (xy 93.181314 -111.31666) (xy 93.222505 -111.280969)
			(xy 93.268355 -111.251503) (xy 93.317932 -111.228861) (xy 93.370227 -111.213506) (xy 93.424175 -111.20575)
			(xy 93.478677 -111.20575) (xy 93.532625 -111.213506) (xy 93.58492 -111.228861) (xy 93.634497 -111.251503)
			(xy 93.680347 -111.280969) (xy 93.721538 -111.31666) (xy 93.757229 -111.357851) (xy 93.786695 -111.403701)
			(xy 93.809337 -111.453278) (xy 93.824692 -111.505573) (xy 93.832448 -111.559521) (xy 93.832934 -111.586772)
			(xy 93.832504 -111.613087) (xy 93.82526 -111.665217) (xy 93.810933 -111.71586) (xy 93.789793 -111.764058)
			(xy 93.762241 -111.808901) (xy 93.728798 -111.84954) (xy 93.709744 -111.867696) (xy 93.702349 -111.875223)
			(xy 93.693819 -111.894499) (xy 93.693234 -111.905034) (xy 93.693234 -111.97971) (xy 93.693734 -111.990263)
			(xy 93.702289 -112.009559) (xy 93.709744 -112.017048) (xy 93.728824 -112.035179) (xy 93.762277 -112.075815)
			(xy 93.789832 -112.12066) (xy 93.810966 -112.168866) (xy 93.825278 -112.219517) (xy 93.832498 -112.271655)
			(xy 93.832934 -112.297972) (xy 95.101918 -112.297972) (xy 95.102361 -112.271657) (xy 95.1096 -112.219527)
			(xy 95.123924 -112.168884) (xy 95.145061 -112.120685) (xy 95.172611 -112.075842) (xy 95.206054 -112.035204)
			(xy 95.225108 -112.017048) (xy 95.232536 -112.009549) (xy 95.241045 -111.990252) (xy 95.241618 -111.97971)
			(xy 95.241618 -111.905034) (xy 95.241079 -111.894486) (xy 95.23255 -111.875191) (xy 95.225108 -111.867696)
			(xy 95.206059 -111.849534) (xy 95.172601 -111.808906) (xy 95.145041 -111.764067) (xy 95.123901 -111.715867)
			(xy 95.109583 -111.665221) (xy 95.102357 -111.613088) (xy 95.101918 -111.586772) (xy 95.102404 -111.559521)
			(xy 95.11016 -111.505573) (xy 95.125515 -111.453278) (xy 95.148157 -111.403701) (xy 95.177623 -111.357851)
			(xy 95.213314 -111.31666) (xy 95.254505 -111.280969) (xy 95.300355 -111.251503) (xy 95.349932 -111.228861)
			(xy 95.402227 -111.213506) (xy 95.456175 -111.20575) (xy 95.510677 -111.20575) (xy 95.564625 -111.213506)
			(xy 95.61692 -111.228861) (xy 95.666497 -111.251503) (xy 95.712347 -111.280969) (xy 95.753538 -111.31666)
			(xy 95.789229 -111.357851) (xy 95.818695 -111.403701) (xy 95.841337 -111.453278) (xy 95.856692 -111.505573)
			(xy 95.864448 -111.559521) (xy 95.864934 -111.586772) (xy 95.864504 -111.613087) (xy 95.85726 -111.665217)
			(xy 95.842933 -111.71586) (xy 95.821793 -111.764058) (xy 95.794241 -111.808901) (xy 95.760798 -111.84954)
			(xy 95.741744 -111.867696) (xy 95.734349 -111.875223) (xy 95.725819 -111.894499) (xy 95.725234 -111.905034)
			(xy 95.725234 -111.97971) (xy 95.725734 -111.990263) (xy 95.734289 -112.009559) (xy 95.741744 -112.017048)
			(xy 95.760824 -112.035179) (xy 95.762829 -112.037615) (xy 97.556142 -112.037615) (xy 97.560456 -111.980343)
			(xy 97.573304 -111.924365) (xy 97.594396 -111.870944) (xy 97.623255 -111.821288) (xy 97.65923 -111.776517)
			(xy 97.680018 -111.756698) (xy 97.687425 -111.749182) (xy 97.695946 -111.729897) (xy 97.696528 -111.71936)
			(xy 97.696528 -111.644684) (xy 97.696013 -111.634133) (xy 97.687467 -111.614838) (xy 97.680018 -111.607346)
			(xy 97.660947 -111.589206) (xy 97.62749 -111.548573) (xy 97.599933 -111.50373) (xy 97.578797 -111.455526)
			(xy 97.564484 -111.404876) (xy 97.557264 -111.352739) (xy 97.556828 -111.326422) (xy 97.557314 -111.299171)
			(xy 97.56507 -111.245223) (xy 97.580425 -111.192928) (xy 97.603067 -111.143351) (xy 97.632533 -111.097501)
			(xy 97.668224 -111.05631) (xy 97.709415 -111.020619) (xy 97.755265 -110.991153) (xy 97.804842 -110.968511)
			(xy 97.857137 -110.953156) (xy 97.911085 -110.9454) (xy 97.965587 -110.9454) (xy 98.019535 -110.953156)
			(xy 98.07183 -110.968511) (xy 98.121407 -110.991153) (xy 98.167257 -111.020619) (xy 98.208448 -111.05631)
			(xy 98.244139 -111.097501) (xy 98.273605 -111.143351) (xy 98.296247 -111.192928) (xy 98.311602 -111.245223)
			(xy 98.319358 -111.299171) (xy 98.319844 -111.326422) (xy 98.319409 -111.352737) (xy 98.31217 -111.404868)
			(xy 98.297846 -111.455512) (xy 98.276707 -111.503711) (xy 98.249155 -111.548554) (xy 98.215709 -111.589191)
			(xy 98.196654 -111.607346) (xy 98.189238 -111.614856) (xy 98.18072 -111.634144) (xy 98.180144 -111.644684)
			(xy 98.180144 -111.71936) (xy 98.180668 -111.729911) (xy 98.189206 -111.749207) (xy 98.196654 -111.756698)
			(xy 98.217462 -111.776497) (xy 98.253434 -111.821274) (xy 98.28229 -111.870935) (xy 98.303379 -111.924359)
			(xy 98.316226 -111.980341) (xy 98.320539 -112.037615) (xy 100.09439 -112.037615) (xy 100.098702 -111.980346)
			(xy 100.111547 -111.924369) (xy 100.132634 -111.87095) (xy 100.161488 -111.821292) (xy 100.197456 -111.776519)
			(xy 100.21824 -111.756698) (xy 100.225636 -111.749171) (xy 100.234165 -111.729895) (xy 100.23475 -111.71936)
			(xy 100.23475 -111.644684) (xy 100.234228 -111.634134) (xy 100.225686 -111.614839) (xy 100.21824 -111.607346)
			(xy 100.199154 -111.589222) (xy 100.165702 -111.548584) (xy 100.138148 -111.503737) (xy 100.117016 -111.45553)
			(xy 100.102704 -111.404878) (xy 100.095486 -111.35274) (xy 100.09505 -111.326422) (xy 100.095536 -111.299171)
			(xy 100.103292 -111.245223) (xy 100.118647 -111.192928) (xy 100.141289 -111.143351) (xy 100.170755 -111.097501)
			(xy 100.206446 -111.05631) (xy 100.247637 -111.020619) (xy 100.293487 -110.991153) (xy 100.343064 -110.968511)
			(xy 100.395359 -110.953156) (xy 100.449307 -110.9454) (xy 100.503809 -110.9454) (xy 100.557757 -110.953156)
			(xy 100.610052 -110.968511) (xy 100.659629 -110.991153) (xy 100.705479 -111.020619) (xy 100.74667 -111.05631)
			(xy 100.782361 -111.097501) (xy 100.811827 -111.143351) (xy 100.834469 -111.192928) (xy 100.849824 -111.245223)
			(xy 100.85758 -111.299171) (xy 100.858066 -111.326422) (xy 100.857624 -111.352737) (xy 100.850386 -111.404867)
			(xy 100.836062 -111.455511) (xy 100.814925 -111.50371) (xy 100.787374 -111.548553) (xy 100.75393 -111.589191)
			(xy 100.734876 -111.607346) (xy 100.727463 -111.614859) (xy 100.718942 -111.634145) (xy 100.718366 -111.644684)
			(xy 100.718366 -111.71936) (xy 100.718913 -111.729907) (xy 100.727437 -111.749202) (xy 100.734876 -111.756698)
			(xy 100.755688 -111.776495) (xy 100.791667 -111.821269) (xy 100.820529 -111.87093) (xy 100.841623 -111.924355)
			(xy 100.854472 -111.980338) (xy 100.855495 -111.993923) (xy 104.297324 -111.993923) (xy 104.301636 -111.936654)
			(xy 104.314481 -111.880678) (xy 104.335569 -111.827258) (xy 104.364423 -111.777602) (xy 104.400393 -111.73283)
			(xy 104.421178 -111.71301) (xy 104.428574 -111.705484) (xy 104.437102 -111.686207) (xy 104.437688 -111.675672)
			(xy 104.437688 -111.600996) (xy 104.437178 -111.590444) (xy 104.42863 -111.571149) (xy 104.421178 -111.563658)
			(xy 104.400424 -111.543804) (xy 104.364449 -111.499036) (xy 104.335589 -111.449383) (xy 104.314494 -111.395966)
			(xy 104.301643 -111.339992) (xy 104.297324 -111.282723) (xy 104.301636 -111.225454) (xy 104.314481 -111.169478)
			(xy 104.335569 -111.116058) (xy 104.364423 -111.066402) (xy 104.400393 -111.02163) (xy 104.421178 -111.00181)
			(xy 104.428574 -110.994284) (xy 104.437102 -110.975007) (xy 104.437688 -110.964472) (xy 104.437688 -110.889796)
			(xy 104.437178 -110.879244) (xy 104.42863 -110.859949) (xy 104.421178 -110.852458) (xy 104.402105 -110.83432)
			(xy 104.36865 -110.793686) (xy 104.341094 -110.748842) (xy 104.319959 -110.700638) (xy 104.305645 -110.649987)
			(xy 104.298424 -110.597851) (xy 104.297988 -110.571534) (xy 104.298487 -110.544282) (xy 104.306239 -110.490333)
			(xy 104.321591 -110.438036) (xy 104.344229 -110.388456) (xy 104.373693 -110.342603) (xy 104.409383 -110.30141)
			(xy 104.450572 -110.265716) (xy 104.496423 -110.236247) (xy 104.546 -110.213604) (xy 104.598296 -110.198247)
			(xy 104.652244 -110.19049) (xy 104.679496 -110.190026) (xy 104.70581 -110.190488) (xy 104.757939 -110.197723)
			(xy 104.808583 -110.212042) (xy 104.856782 -110.233176) (xy 104.901625 -110.260723) (xy 104.942264 -110.294164)
			(xy 104.96042 -110.313216) (xy 104.96793 -110.320631) (xy 104.987219 -110.329147) (xy 104.997758 -110.329726)
			(xy 105.072434 -110.329726) (xy 105.08298 -110.329167) (xy 105.102275 -110.320652) (xy 105.109772 -110.313216)
			(xy 105.127951 -110.294184) (xy 105.168576 -110.260724) (xy 105.213411 -110.233162) (xy 105.261607 -110.212019)
			(xy 105.31225 -110.197697) (xy 105.364381 -110.190467) (xy 105.390696 -110.190026) (xy 105.41795 -110.190459)
			(xy 105.471904 -110.198216) (xy 105.524205 -110.213574) (xy 105.573787 -110.236218) (xy 105.613417 -110.261688)
			(xy 106.914421 -110.261688) (xy 106.914421 -110.209712) (xy 106.922553 -110.158377) (xy 106.938615 -110.108946)
			(xy 106.962213 -110.062636) (xy 106.992766 -110.020588) (xy 107.02952 -109.983839) (xy 107.071572 -109.953291)
			(xy 107.117884 -109.929699) (xy 107.167318 -109.913643) (xy 107.218654 -109.905518) (xy 107.244642 -109.905038)
			(xy 107.271287 -109.905526) (xy 107.323889 -109.914057) (xy 107.374439 -109.930922) (xy 107.421625 -109.955684)
			(xy 107.464224 -109.987701) (xy 107.50113 -110.026141) (xy 107.516676 -110.047786) (xy 107.52504 -110.059072)
			(xy 107.546713 -110.076927) (xy 107.572427 -110.08821) (xy 107.600242 -110.092068) (xy 107.628057 -110.08821)
			(xy 107.653771 -110.076927) (xy 107.675444 -110.059072) (xy 107.683808 -110.047786) (xy 107.699397 -110.026178)
			(xy 107.73631 -109.987761) (xy 107.778906 -109.95576) (xy 107.826082 -109.931002) (xy 107.876617 -109.914129)
			(xy 107.929203 -109.905578) (xy 107.955842 -109.905038) (xy 107.981831 -109.905459) (xy 108.033167 -109.913596)
			(xy 108.082599 -109.929663) (xy 108.128909 -109.953264) (xy 108.170957 -109.983819) (xy 108.207709 -110.020575)
			(xy 108.238258 -110.062627) (xy 108.261853 -110.10894) (xy 108.277914 -110.158374) (xy 108.286044 -110.209711)
			(xy 108.286044 -110.261689) (xy 108.277914 -110.313026) (xy 108.261853 -110.36246) (xy 108.238258 -110.408773)
			(xy 108.207709 -110.450825) (xy 108.170957 -110.487581) (xy 108.132325 -110.515654) (xy 110.828072 -110.515654)
			(xy 110.832143 -110.460032) (xy 110.844269 -110.405595) (xy 110.864192 -110.353504) (xy 110.891488 -110.304869)
			(xy 110.925574 -110.260726) (xy 110.965723 -110.222017) (xy 111.011081 -110.189566) (xy 111.060681 -110.164065)
			(xy 111.113465 -110.146058) (xy 111.168308 -110.135928) (xy 111.224042 -110.133891) (xy 111.279479 -110.139991)
			(xy 111.333436 -110.154097) (xy 111.384765 -110.175909) (xy 111.432371 -110.204963) (xy 111.475239 -110.240638)
			(xy 111.512456 -110.282175) (xy 111.543229 -110.328688) (xy 111.566901 -110.379185) (xy 111.582969 -110.432592)
			(xy 111.591089 -110.487768) (xy 111.591598 -110.515654) (xy 111.591089 -110.54354) (xy 111.582969 -110.598716)
			(xy 111.566901 -110.652123) (xy 111.543229 -110.70262) (xy 111.512456 -110.749133) (xy 111.475239 -110.79067)
			(xy 111.432371 -110.826345) (xy 111.384765 -110.855399) (xy 111.333436 -110.877211) (xy 111.279479 -110.891317)
			(xy 111.224042 -110.897417) (xy 111.168308 -110.89538) (xy 111.113465 -110.88525) (xy 111.060681 -110.867243)
			(xy 111.011081 -110.841742) (xy 110.965723 -110.809291) (xy 110.925574 -110.770582) (xy 110.891488 -110.726439)
			(xy 110.864192 -110.677804) (xy 110.844269 -110.625713) (xy 110.832143 -110.571276) (xy 110.828072 -110.515654)
			(xy 108.132325 -110.515654) (xy 108.128909 -110.518136) (xy 108.082599 -110.541737) (xy 108.033167 -110.557804)
			(xy 107.981831 -110.565941) (xy 107.955842 -110.566454) (xy 107.929197 -110.565981) (xy 107.876594 -110.557448)
			(xy 107.826043 -110.54058) (xy 107.778857 -110.515815) (xy 107.736259 -110.483795) (xy 107.699354 -110.445352)
			(xy 107.683808 -110.423706) (xy 107.675444 -110.41242) (xy 107.653771 -110.394565) (xy 107.628057 -110.383282)
			(xy 107.600242 -110.379424) (xy 107.572427 -110.383282) (xy 107.546713 -110.394565) (xy 107.52504 -110.41242)
			(xy 107.516676 -110.423706) (xy 107.501095 -110.44532) (xy 107.46418 -110.483737) (xy 107.421583 -110.515738)
			(xy 107.374405 -110.540494) (xy 107.323869 -110.557366) (xy 107.271281 -110.565916) (xy 107.244642 -110.566454)
			(xy 107.218654 -110.565882) (xy 107.167318 -110.557757) (xy 107.117884 -110.541701) (xy 107.071572 -110.518109)
			(xy 107.02952 -110.487561) (xy 106.992766 -110.450812) (xy 106.962213 -110.408764) (xy 106.938615 -110.362454)
			(xy 106.922553 -110.313023) (xy 106.914421 -110.261688) (xy 105.613417 -110.261688) (xy 105.619642 -110.265689)
			(xy 105.660835 -110.301386) (xy 105.696529 -110.342582) (xy 105.725996 -110.388439) (xy 105.748637 -110.438024)
			(xy 105.76399 -110.490325) (xy 105.771743 -110.54428) (xy 105.772204 -110.571534) (xy 105.771758 -110.597849)
			(xy 105.764519 -110.649978) (xy 105.750195 -110.700621) (xy 105.729059 -110.74882) (xy 105.701509 -110.793663)
			(xy 105.668067 -110.834302) (xy 105.649014 -110.852458) (xy 105.641631 -110.859995) (xy 105.633095 -110.879263)
			(xy 105.632504 -110.889796) (xy 105.632504 -110.964472) (xy 105.633034 -110.975022) (xy 105.641568 -110.994317)
			(xy 105.649014 -111.00181) (xy 105.669836 -111.021596) (xy 105.705811 -111.066373) (xy 105.73467 -111.116036)
			(xy 105.752772 -111.16189) (xy 106.914397 -111.16189) (xy 106.914397 -111.10991) (xy 106.922529 -111.058571)
			(xy 106.938593 -111.009136) (xy 106.962193 -110.962823) (xy 106.992748 -110.920773) (xy 107.029505 -110.88402)
			(xy 107.071559 -110.853471) (xy 107.117875 -110.829877) (xy 107.167312 -110.813819) (xy 107.218652 -110.805694)
			(xy 107.244642 -110.805214) (xy 107.271286 -110.805713) (xy 107.323887 -110.814242) (xy 107.374436 -110.831106)
			(xy 107.421622 -110.855866) (xy 107.464222 -110.887881) (xy 107.501129 -110.926319) (xy 107.516676 -110.947962)
			(xy 107.52504 -110.959248) (xy 107.546713 -110.977103) (xy 107.572427 -110.988386) (xy 107.600242 -110.992244)
			(xy 107.628057 -110.988386) (xy 107.653771 -110.977103) (xy 107.675444 -110.959248) (xy 107.683808 -110.947962)
			(xy 107.69939 -110.926349) (xy 107.736306 -110.887933) (xy 107.778903 -110.855933) (xy 107.82608 -110.831177)
			(xy 107.876616 -110.814305) (xy 107.929203 -110.805754) (xy 107.955842 -110.805214) (xy 107.981829 -110.805683)
			(xy 108.033162 -110.813819) (xy 108.08259 -110.829885) (xy 108.128897 -110.853484) (xy 108.170942 -110.884037)
			(xy 108.20769 -110.92079) (xy 108.238238 -110.962839) (xy 108.261831 -111.009149) (xy 108.277891 -111.058579)
			(xy 108.286021 -111.109913) (xy 108.286021 -111.161887) (xy 108.277891 -111.213221) (xy 108.261831 -111.262651)
			(xy 108.238238 -111.308961) (xy 108.20769 -111.35101) (xy 108.170942 -111.387763) (xy 108.128897 -111.418316)
			(xy 108.08259 -111.441915) (xy 108.033162 -111.457981) (xy 107.981829 -111.466117) (xy 107.955842 -111.46663)
			(xy 107.929196 -111.466167) (xy 107.876592 -111.457633) (xy 107.826041 -111.440764) (xy 107.778855 -111.415997)
			(xy 107.736257 -111.383975) (xy 107.699353 -111.345529) (xy 107.683808 -111.323882) (xy 107.675444 -111.312596)
			(xy 107.653771 -111.294741) (xy 107.628057 -111.283458) (xy 107.600242 -111.2796) (xy 107.572427 -111.283458)
			(xy 107.546713 -111.294741) (xy 107.52504 -111.312596) (xy 107.516676 -111.323882) (xy 107.501117 -111.345512)
			(xy 107.464195 -111.383925) (xy 107.421592 -111.415922) (xy 107.374411 -111.440675) (xy 107.323872 -111.457543)
			(xy 107.271282 -111.466092) (xy 107.244642 -111.46663) (xy 107.218652 -111.466106) (xy 107.167312 -111.457981)
			(xy 107.117875 -111.441923) (xy 107.071559 -111.418329) (xy 107.029505 -111.38778) (xy 106.992748 -111.351027)
			(xy 106.962193 -111.308977) (xy 106.938593 -111.262664) (xy 106.922529 -111.213229) (xy 106.914397 -111.16189)
			(xy 105.752772 -111.16189) (xy 105.755761 -111.169462) (xy 105.768608 -111.225446) (xy 105.77292 -111.282723)
			(xy 105.768601 -111.339999) (xy 105.755748 -111.395982) (xy 105.73465 -111.449406) (xy 105.705785 -111.499065)
			(xy 105.669805 -111.543838) (xy 105.649014 -111.563658) (xy 105.641631 -111.571195) (xy 105.633095 -111.590463)
			(xy 105.632504 -111.600996) (xy 105.632504 -111.675672) (xy 105.633034 -111.686222) (xy 105.641568 -111.705517)
			(xy 105.649014 -111.71301) (xy 105.669836 -111.732796) (xy 105.705811 -111.777573) (xy 105.73467 -111.827236)
			(xy 105.755761 -111.880662) (xy 105.768608 -111.936646) (xy 105.77292 -111.993923) (xy 105.768601 -112.051199)
			(xy 105.76617 -112.061788) (xy 106.914419 -112.061788) (xy 106.914419 -112.009812) (xy 106.922551 -111.958476)
			(xy 106.938613 -111.909045) (xy 106.962212 -111.862735) (xy 106.992764 -111.820687) (xy 107.029519 -111.783937)
			(xy 107.071571 -111.75339) (xy 107.117884 -111.729797) (xy 107.167317 -111.713741) (xy 107.218654 -111.705616)
			(xy 107.244642 -111.705136) (xy 107.271287 -111.705625) (xy 107.323888 -111.714156) (xy 107.374438 -111.73102)
			(xy 107.421625 -111.755782) (xy 107.464224 -111.787799) (xy 107.501129 -111.826239) (xy 107.516676 -111.847884)
			(xy 107.52504 -111.85917) (xy 107.546713 -111.877025) (xy 107.572427 -111.888308) (xy 107.600242 -111.892166)
			(xy 107.628057 -111.888308) (xy 107.653771 -111.877025) (xy 107.675444 -111.85917) (xy 107.683808 -111.847884)
			(xy 107.699396 -111.826275) (xy 107.73631 -111.787859) (xy 107.778906 -111.755857) (xy 107.826082 -111.7311)
			(xy 107.876617 -111.714227) (xy 107.929203 -111.705676) (xy 107.955842 -111.705136) (xy 107.98183 -111.705561)
			(xy 108.033167 -111.713698) (xy 108.082598 -111.729765) (xy 108.128908 -111.753366) (xy 108.170956 -111.78392)
			(xy 108.17269 -111.785654) (xy 109.457742 -111.785654) (xy 109.461813 -111.730032) (xy 109.473939 -111.675595)
			(xy 109.493862 -111.623504) (xy 109.521158 -111.574869) (xy 109.555244 -111.530726) (xy 109.595393 -111.492017)
			(xy 109.640751 -111.459566) (xy 109.690351 -111.434065) (xy 109.743135 -111.416058) (xy 109.797978 -111.405928)
			(xy 109.853712 -111.403891) (xy 109.909149 -111.409991) (xy 109.963106 -111.424097) (xy 110.014435 -111.445909)
			(xy 110.062041 -111.474963) (xy 110.104909 -111.510638) (xy 110.142126 -111.552175) (xy 110.172899 -111.598688)
			(xy 110.196571 -111.649185) (xy 110.212639 -111.702592) (xy 110.217349 -111.7346) (xy 121.915172 -111.7346)
			(xy 121.919243 -111.678978) (xy 121.931369 -111.624541) (xy 121.951292 -111.57245) (xy 121.978588 -111.523815)
			(xy 122.012674 -111.479672) (xy 122.052823 -111.440963) (xy 122.098181 -111.408512) (xy 122.147781 -111.383011)
			(xy 122.200565 -111.365004) (xy 122.255408 -111.354874) (xy 122.311142 -111.352837) (xy 122.366579 -111.358937)
			(xy 122.420536 -111.373043) (xy 122.471865 -111.394855) (xy 122.519471 -111.423909) (xy 122.562339 -111.459584)
			(xy 122.599556 -111.501121) (xy 122.630329 -111.547634) (xy 122.654001 -111.598131) (xy 122.670069 -111.651538)
			(xy 122.678189 -111.706714) (xy 122.678698 -111.7346) (xy 122.678684 -111.735362) (xy 122.931172 -111.735362)
			(xy 122.935243 -111.67974) (xy 122.947369 -111.625303) (xy 122.967292 -111.573212) (xy 122.994588 -111.524577)
			(xy 123.028674 -111.480434) (xy 123.068823 -111.441725) (xy 123.114181 -111.409274) (xy 123.163781 -111.383773)
			(xy 123.216565 -111.365766) (xy 123.271408 -111.355636) (xy 123.327142 -111.353599) (xy 123.382579 -111.359699)
			(xy 123.436536 -111.373805) (xy 123.487865 -111.395617) (xy 123.535471 -111.424671) (xy 123.578339 -111.460346)
			(xy 123.615556 -111.501883) (xy 123.646329 -111.548396) (xy 123.670001 -111.598893) (xy 123.686069 -111.6523)
			(xy 123.694189 -111.707476) (xy 123.694698 -111.735362) (xy 123.947172 -111.735362) (xy 123.951243 -111.67974)
			(xy 123.963369 -111.625303) (xy 123.983292 -111.573212) (xy 124.010588 -111.524577) (xy 124.044674 -111.480434)
			(xy 124.084823 -111.441725) (xy 124.130181 -111.409274) (xy 124.179781 -111.383773) (xy 124.232565 -111.365766)
			(xy 124.287408 -111.355636) (xy 124.343142 -111.353599) (xy 124.398579 -111.359699) (xy 124.452536 -111.373805)
			(xy 124.503865 -111.395617) (xy 124.551471 -111.424671) (xy 124.594339 -111.460346) (xy 124.631556 -111.501883)
			(xy 124.662329 -111.548396) (xy 124.686001 -111.598893) (xy 124.702069 -111.6523) (xy 124.710189 -111.707476)
			(xy 124.710698 -111.735362) (xy 124.710624 -111.739426) (xy 127.565148 -111.739426) (xy 127.569219 -111.683804)
			(xy 127.581345 -111.629367) (xy 127.601268 -111.577276) (xy 127.628564 -111.528641) (xy 127.66265 -111.484498)
			(xy 127.702799 -111.445789) (xy 127.748157 -111.413338) (xy 127.797757 -111.387837) (xy 127.850541 -111.36983)
			(xy 127.905384 -111.3597) (xy 127.961118 -111.357663) (xy 128.016555 -111.363763) (xy 128.070512 -111.377869)
			(xy 128.121841 -111.399681) (xy 128.169447 -111.428735) (xy 128.212315 -111.46441) (xy 128.249532 -111.505947)
			(xy 128.280305 -111.55246) (xy 128.303977 -111.602957) (xy 128.320045 -111.656364) (xy 128.328165 -111.71154)
			(xy 128.328674 -111.739426) (xy 128.328165 -111.767312) (xy 128.320045 -111.822488) (xy 128.303977 -111.875895)
			(xy 128.280305 -111.926392) (xy 128.249532 -111.972905) (xy 128.212315 -112.014442) (xy 128.169447 -112.050117)
			(xy 128.121841 -112.079171) (xy 128.070512 -112.100983) (xy 128.016555 -112.115089) (xy 127.961118 -112.121189)
			(xy 127.905384 -112.119152) (xy 127.850541 -112.109022) (xy 127.797757 -112.091015) (xy 127.748157 -112.065514)
			(xy 127.702799 -112.033063) (xy 127.66265 -111.994354) (xy 127.628564 -111.950211) (xy 127.601268 -111.901576)
			(xy 127.581345 -111.849485) (xy 127.569219 -111.795048) (xy 127.565148 -111.739426) (xy 124.710624 -111.739426)
			(xy 124.710189 -111.763248) (xy 124.702069 -111.818424) (xy 124.686001 -111.871831) (xy 124.662329 -111.922328)
			(xy 124.631556 -111.968841) (xy 124.594339 -112.010378) (xy 124.551471 -112.046053) (xy 124.503865 -112.075107)
			(xy 124.452536 -112.096919) (xy 124.398579 -112.111025) (xy 124.343142 -112.117125) (xy 124.287408 -112.115088)
			(xy 124.232565 -112.104958) (xy 124.179781 -112.086951) (xy 124.130181 -112.06145) (xy 124.084823 -112.028999)
			(xy 124.044674 -111.99029) (xy 124.010588 -111.946147) (xy 123.983292 -111.897512) (xy 123.963369 -111.845421)
			(xy 123.951243 -111.790984) (xy 123.947172 -111.735362) (xy 123.694698 -111.735362) (xy 123.694189 -111.763248)
			(xy 123.686069 -111.818424) (xy 123.670001 -111.871831) (xy 123.646329 -111.922328) (xy 123.615556 -111.968841)
			(xy 123.578339 -112.010378) (xy 123.535471 -112.046053) (xy 123.487865 -112.075107) (xy 123.436536 -112.096919)
			(xy 123.382579 -112.111025) (xy 123.327142 -112.117125) (xy 123.271408 -112.115088) (xy 123.216565 -112.104958)
			(xy 123.163781 -112.086951) (xy 123.114181 -112.06145) (xy 123.068823 -112.028999) (xy 123.028674 -111.99029)
			(xy 122.994588 -111.946147) (xy 122.967292 -111.897512) (xy 122.947369 -111.845421) (xy 122.935243 -111.790984)
			(xy 122.931172 -111.735362) (xy 122.678684 -111.735362) (xy 122.678189 -111.762486) (xy 122.670069 -111.817662)
			(xy 122.654001 -111.871069) (xy 122.630329 -111.921566) (xy 122.599556 -111.968079) (xy 122.562339 -112.009616)
			(xy 122.519471 -112.045291) (xy 122.471865 -112.074345) (xy 122.420536 -112.096157) (xy 122.366579 -112.110263)
			(xy 122.311142 -112.116363) (xy 122.255408 -112.114326) (xy 122.200565 -112.104196) (xy 122.147781 -112.086189)
			(xy 122.098181 -112.060688) (xy 122.052823 -112.028237) (xy 122.012674 -111.989528) (xy 121.978588 -111.945385)
			(xy 121.951292 -111.89675) (xy 121.931369 -111.844659) (xy 121.919243 -111.790222) (xy 121.915172 -111.7346)
			(xy 110.217349 -111.7346) (xy 110.220759 -111.757768) (xy 110.221268 -111.785654) (xy 110.220759 -111.81354)
			(xy 110.212639 -111.868716) (xy 110.196571 -111.922123) (xy 110.172899 -111.97262) (xy 110.142126 -112.019133)
			(xy 110.104909 -112.06067) (xy 110.062041 -112.096345) (xy 110.014435 -112.125399) (xy 109.963106 -112.147211)
			(xy 109.909149 -112.161317) (xy 109.853712 -112.167417) (xy 109.797978 -112.16538) (xy 109.743135 -112.15525)
			(xy 109.690351 -112.137243) (xy 109.640751 -112.111742) (xy 109.595393 -112.079291) (xy 109.555244 -112.040582)
			(xy 109.521158 -111.996439) (xy 109.493862 -111.947804) (xy 109.473939 -111.895713) (xy 109.461813 -111.841276)
			(xy 109.457742 -111.785654) (xy 108.17269 -111.785654) (xy 108.207707 -111.820676) (xy 108.238256 -111.862728)
			(xy 108.261852 -111.909041) (xy 108.277912 -111.958474) (xy 108.286042 -112.009811) (xy 108.286042 -112.061789)
			(xy 108.277912 -112.113126) (xy 108.261852 -112.162559) (xy 108.238256 -112.208872) (xy 108.207707 -112.250924)
			(xy 108.170956 -112.28768) (xy 108.15819 -112.296956) (xy 110.894874 -112.296956) (xy 110.898945 -112.241334)
			(xy 110.911071 -112.186897) (xy 110.930994 -112.134806) (xy 110.95829 -112.086171) (xy 110.992376 -112.042028)
			(xy 111.032525 -112.003319) (xy 111.077883 -111.970868) (xy 111.127483 -111.945367) (xy 111.180267 -111.92736)
			(xy 111.23511 -111.91723) (xy 111.290844 -111.915193) (xy 111.346281 -111.921293) (xy 111.400238 -111.935399)
			(xy 111.451567 -111.957211) (xy 111.499173 -111.986265) (xy 111.542041 -112.02194) (xy 111.579258 -112.063477)
			(xy 111.610031 -112.10999) (xy 111.633703 -112.160487) (xy 111.649771 -112.213894) (xy 111.657891 -112.26907)
			(xy 111.6584 -112.296956) (xy 111.657891 -112.324842) (xy 111.649771 -112.380018) (xy 111.633703 -112.433425)
			(xy 111.610031 -112.483922) (xy 111.579258 -112.530435) (xy 111.570657 -112.540034) (xy 129.905504 -112.540034)
			(xy 129.909575 -112.484412) (xy 129.921701 -112.429975) (xy 129.941624 -112.377884) (xy 129.96892 -112.329249)
			(xy 130.003006 -112.285106) (xy 130.043155 -112.246397) (xy 130.088513 -112.213946) (xy 130.138113 -112.188445)
			(xy 130.190897 -112.170438) (xy 130.24574 -112.160308) (xy 130.301474 -112.158271) (xy 130.356911 -112.164371)
			(xy 130.410868 -112.178477) (xy 130.462197 -112.200289) (xy 130.509803 -112.229343) (xy 130.552671 -112.265018)
			(xy 130.589888 -112.306555) (xy 130.620661 -112.353068) (xy 130.644333 -112.403565) (xy 130.649627 -112.421162)
			(xy 131.907024 -112.421162) (xy 131.911095 -112.36554) (xy 131.923221 -112.311103) (xy 131.943144 -112.259012)
			(xy 131.97044 -112.210377) (xy 132.004526 -112.166234) (xy 132.044675 -112.127525) (xy 132.090033 -112.095074)
			(xy 132.139633 -112.069573) (xy 132.192417 -112.051566) (xy 132.24726 -112.041436) (xy 132.302994 -112.039399)
			(xy 132.358431 -112.045499) (xy 132.412388 -112.059605) (xy 132.463717 -112.081417) (xy 132.511323 -112.110471)
			(xy 132.554191 -112.146146) (xy 132.591408 -112.187683) (xy 132.622181 -112.234196) (xy 132.645853 -112.284693)
			(xy 132.661921 -112.3381) (xy 132.670041 -112.393276) (xy 132.67055 -112.421162) (xy 132.670041 -112.449048)
			(xy 132.661921 -112.504224) (xy 132.645853 -112.557631) (xy 132.622181 -112.608128) (xy 132.591408 -112.654641)
			(xy 132.554191 -112.696178) (xy 132.511323 -112.731853) (xy 132.463717 -112.760907) (xy 132.412388 -112.782719)
			(xy 132.358431 -112.796825) (xy 132.302994 -112.802925) (xy 132.24726 -112.800888) (xy 132.192417 -112.790758)
			(xy 132.139633 -112.772751) (xy 132.090033 -112.74725) (xy 132.044675 -112.714799) (xy 132.004526 -112.67609)
			(xy 131.97044 -112.631947) (xy 131.943144 -112.583312) (xy 131.923221 -112.531221) (xy 131.911095 -112.476784)
			(xy 131.907024 -112.421162) (xy 130.649627 -112.421162) (xy 130.660401 -112.456972) (xy 130.668521 -112.512148)
			(xy 130.66903 -112.540034) (xy 130.668521 -112.56792) (xy 130.660401 -112.623096) (xy 130.644333 -112.676503)
			(xy 130.620661 -112.727) (xy 130.589888 -112.773513) (xy 130.552671 -112.81505) (xy 130.509803 -112.850725)
			(xy 130.462197 -112.879779) (xy 130.410868 -112.901591) (xy 130.356911 -112.915697) (xy 130.301474 -112.921797)
			(xy 130.24574 -112.91976) (xy 130.190897 -112.90963) (xy 130.138113 -112.891623) (xy 130.088513 -112.866122)
			(xy 130.043155 -112.833671) (xy 130.003006 -112.794962) (xy 129.96892 -112.750819) (xy 129.941624 -112.702184)
			(xy 129.921701 -112.650093) (xy 129.909575 -112.595656) (xy 129.905504 -112.540034) (xy 111.570657 -112.540034)
			(xy 111.542041 -112.571972) (xy 111.499173 -112.607647) (xy 111.451567 -112.636701) (xy 111.400238 -112.658513)
			(xy 111.346281 -112.672619) (xy 111.290844 -112.678719) (xy 111.23511 -112.676682) (xy 111.180267 -112.666552)
			(xy 111.127483 -112.648545) (xy 111.077883 -112.623044) (xy 111.032525 -112.590593) (xy 110.992376 -112.551884)
			(xy 110.95829 -112.507741) (xy 110.930994 -112.459106) (xy 110.911071 -112.407015) (xy 110.898945 -112.352578)
			(xy 110.894874 -112.296956) (xy 108.15819 -112.296956) (xy 108.128908 -112.318234) (xy 108.082598 -112.341835)
			(xy 108.033167 -112.357902) (xy 107.98183 -112.366039) (xy 107.955842 -112.366552) (xy 107.929197 -112.36608)
			(xy 107.876594 -112.357547) (xy 107.826043 -112.340679) (xy 107.778857 -112.315913) (xy 107.736259 -112.283894)
			(xy 107.699354 -112.24545) (xy 107.683808 -112.223804) (xy 107.675444 -112.212518) (xy 107.653771 -112.194663)
			(xy 107.628057 -112.18338) (xy 107.600242 -112.179522) (xy 107.572427 -112.18338) (xy 107.546713 -112.194663)
			(xy 107.52504 -112.212518) (xy 107.516676 -112.223804) (xy 107.501094 -112.245417) (xy 107.46418 -112.283835)
			(xy 107.421582 -112.315836) (xy 107.374405 -112.340592) (xy 107.323869 -112.357464) (xy 107.271281 -112.366014)
			(xy 107.244642 -112.366552) (xy 107.218654 -112.365984) (xy 107.167317 -112.357859) (xy 107.117884 -112.341803)
			(xy 107.071571 -112.31821) (xy 107.029519 -112.287663) (xy 106.992764 -112.250913) (xy 106.962212 -112.208865)
			(xy 106.938613 -112.162555) (xy 106.922551 -112.113124) (xy 106.914419 -112.061788) (xy 105.76617 -112.061788)
			(xy 105.755748 -112.107182) (xy 105.73465 -112.160606) (xy 105.705785 -112.210265) (xy 105.669805 -112.255038)
			(xy 105.649014 -112.274858) (xy 105.641631 -112.282395) (xy 105.633095 -112.301663) (xy 105.632504 -112.312196)
			(xy 105.632504 -112.386872) (xy 105.633034 -112.397422) (xy 105.641568 -112.416717) (xy 105.649014 -112.42421)
			(xy 105.66807 -112.442365) (xy 105.701527 -112.482995) (xy 105.729085 -112.527836) (xy 105.750224 -112.576036)
			(xy 105.764541 -112.626684) (xy 105.771765 -112.678818) (xy 105.772204 -112.705134) (xy 105.771754 -112.732386)
			(xy 105.763993 -112.786335) (xy 105.748633 -112.838631) (xy 105.725988 -112.888209) (xy 105.696517 -112.934059)
			(xy 105.672482 -112.961794) (xy 106.914341 -112.961794) (xy 106.914341 -112.909806) (xy 106.922475 -112.858458)
			(xy 106.938541 -112.809015) (xy 106.962145 -112.762694) (xy 106.992705 -112.720636) (xy 107.029468 -112.683878)
			(xy 107.07153 -112.653323) (xy 107.117854 -112.629725) (xy 107.167299 -112.613665) (xy 107.218648 -112.605538)
			(xy 107.244642 -112.605058) (xy 107.271287 -112.605538) (xy 107.32389 -112.614069) (xy 107.37444 -112.630935)
			(xy 107.421627 -112.655699) (xy 107.464225 -112.687717) (xy 107.50113 -112.72616) (xy 107.516676 -112.747806)
			(xy 107.52504 -112.759092) (xy 107.546713 -112.776947) (xy 107.572427 -112.78823) (xy 107.600242 -112.792088)
			(xy 107.628057 -112.78823) (xy 107.653771 -112.776947) (xy 107.675444 -112.759092) (xy 107.683808 -112.747806)
			(xy 107.699373 -112.72618) (xy 107.736294 -112.687768) (xy 107.778896 -112.655771) (xy 107.826076 -112.631018)
			(xy 107.876614 -112.614148) (xy 107.929202 -112.605598) (xy 107.955842 -112.605058) (xy 107.981824 -112.605639)
			(xy 108.033148 -112.613774) (xy 108.082568 -112.629837) (xy 108.128867 -112.653432) (xy 108.170905 -112.68398)
			(xy 108.207648 -112.720727) (xy 108.23819 -112.762769) (xy 108.26178 -112.809071) (xy 108.277836 -112.858492)
			(xy 108.285965 -112.909818) (xy 108.285965 -112.961782) (xy 108.277836 -113.013108) (xy 108.26178 -113.062529)
			(xy 108.23819 -113.108831) (xy 108.207648 -113.150873) (xy 108.170905 -113.18762) (xy 108.128867 -113.218168)
			(xy 108.082568 -113.241763) (xy 108.033148 -113.257826) (xy 107.981824 -113.265961) (xy 107.955842 -113.266474)
			(xy 107.929197 -113.265992) (xy 107.876595 -113.25746) (xy 107.826045 -113.240593) (xy 107.778859 -113.21583)
			(xy 107.73626 -113.183812) (xy 107.699355 -113.145371) (xy 107.683808 -113.123726) (xy 107.675444 -113.11244)
			(xy 107.653771 -113.094585) (xy 107.628057 -113.083302) (xy 107.600242 -113.079444) (xy 107.572427 -113.083302)
			(xy 107.546713 -113.094585) (xy 107.52504 -113.11244) (xy 107.516676 -113.123726) (xy 107.501101 -113.145344)
			(xy 107.464184 -113.18376) (xy 107.421585 -113.21576) (xy 107.374407 -113.240516) (xy 107.32387 -113.257386)
			(xy 107.271281 -113.265936) (xy 107.244642 -113.266474) (xy 107.218648 -113.266062) (xy 107.167299 -113.257935)
			(xy 107.117854 -113.241875) (xy 107.07153 -113.218277) (xy 107.029468 -113.187722) (xy 106.992705 -113.150964)
			(xy 106.962145 -113.108906) (xy 106.938541 -113.062585) (xy 106.922475 -113.013142) (xy 106.914341 -112.961794)
			(xy 105.672482 -112.961794) (xy 105.660822 -112.975249) (xy 105.619629 -113.01094) (xy 105.573775 -113.040406)
			(xy 105.524195 -113.063046) (xy 105.471898 -113.078401) (xy 105.417948 -113.086157) (xy 105.390696 -113.086642)
			(xy 105.364381 -113.086196) (xy 105.312251 -113.078959) (xy 105.261607 -113.064637) (xy 105.213408 -113.043501)
			(xy 105.168565 -113.01595) (xy 105.127927 -112.982506) (xy 105.109772 -112.963452) (xy 105.102256 -112.956044)
			(xy 105.082972 -112.947521) (xy 105.072434 -112.946942) (xy 104.997758 -112.946942) (xy 104.987209 -112.947477)
			(xy 104.967912 -112.956007) (xy 104.96042 -112.963452) (xy 104.942258 -112.982501) (xy 104.901628 -113.015957)
			(xy 104.856789 -113.043515) (xy 104.80859 -113.064654) (xy 104.757944 -113.078974) (xy 104.705812 -113.086202)
			(xy 104.679496 -113.086642) (xy 104.652246 -113.086126) (xy 104.598301 -113.07837) (xy 104.546009 -113.063016)
			(xy 104.496434 -113.040377) (xy 104.450585 -113.010913) (xy 104.409396 -112.975225) (xy 104.373705 -112.934039)
			(xy 104.344238 -112.888192) (xy 104.321595 -112.838619) (xy 104.306237 -112.786328) (xy 104.298476 -112.732384)
			(xy 104.297988 -112.705134) (xy 104.298415 -112.678819) (xy 104.305659 -112.626689) (xy 104.319986 -112.576045)
			(xy 104.341126 -112.527847) (xy 104.368679 -112.483004) (xy 104.402124 -112.442366) (xy 104.421178 -112.42421)
			(xy 104.428574 -112.416684) (xy 104.437102 -112.397407) (xy 104.437688 -112.386872) (xy 104.437688 -112.312196)
			(xy 104.437178 -112.301644) (xy 104.42863 -112.282349) (xy 104.421178 -112.274858) (xy 104.400424 -112.255004)
			(xy 104.364449 -112.210236) (xy 104.335589 -112.160583) (xy 104.314494 -112.107166) (xy 104.301643 -112.051192)
			(xy 104.297324 -111.993923) (xy 100.855495 -111.993923) (xy 100.858786 -112.037615) (xy 100.854467 -112.094891)
			(xy 100.841614 -112.150873) (xy 100.820516 -112.204297) (xy 100.79165 -112.253956) (xy 100.755667 -112.298727)
			(xy 100.734876 -112.318546) (xy 100.727463 -112.326059) (xy 100.718942 -112.345345) (xy 100.718366 -112.355884)
			(xy 100.718366 -112.43056) (xy 100.718913 -112.441107) (xy 100.727437 -112.460402) (xy 100.734876 -112.467898)
			(xy 100.753919 -112.486066) (xy 100.787378 -112.526693) (xy 100.814939 -112.57153) (xy 100.83608 -112.619729)
			(xy 100.8504 -112.670374) (xy 100.857627 -112.722506) (xy 100.858066 -112.748822) (xy 100.85758 -112.776073)
			(xy 100.849824 -112.830021) (xy 100.834469 -112.882316) (xy 100.811827 -112.931893) (xy 100.782361 -112.977743)
			(xy 100.74667 -113.018934) (xy 100.705479 -113.054625) (xy 100.659629 -113.084091) (xy 100.610052 -113.106733)
			(xy 100.557757 -113.122088) (xy 100.503809 -113.129844) (xy 100.449307 -113.129844) (xy 100.395359 -113.122088)
			(xy 100.343064 -113.106733) (xy 100.293487 -113.084091) (xy 100.247637 -113.054625) (xy 100.206446 -113.018934)
			(xy 100.170755 -112.977743) (xy 100.141289 -112.931893) (xy 100.118647 -112.882316) (xy 100.103292 -112.830021)
			(xy 100.095536 -112.776073) (xy 100.09505 -112.748822) (xy 100.095516 -112.722508) (xy 100.102749 -112.670379)
			(xy 100.117067 -112.619735) (xy 100.1382 -112.571536) (xy 100.165747 -112.526693) (xy 100.199187 -112.486054)
			(xy 100.21824 -112.467898) (xy 100.225636 -112.460371) (xy 100.234165 -112.441095) (xy 100.23475 -112.43056)
			(xy 100.23475 -112.355884) (xy 100.234228 -112.345334) (xy 100.225686 -112.326039) (xy 100.21824 -112.318546)
			(xy 100.197476 -112.298703) (xy 100.161505 -112.253932) (xy 100.132647 -112.204277) (xy 100.111556 -112.150859)
			(xy 100.098707 -112.094884) (xy 100.09439 -112.037615) (xy 98.320539 -112.037615) (xy 98.316221 -112.094889)
			(xy 98.303371 -112.150869) (xy 98.282277 -112.204292) (xy 98.253417 -112.253951) (xy 98.217442 -112.298725)
			(xy 98.196654 -112.318546) (xy 98.189238 -112.326056) (xy 98.18072 -112.345344) (xy 98.180144 -112.355884)
			(xy 98.180144 -112.43056) (xy 98.180668 -112.441111) (xy 98.189206 -112.460407) (xy 98.196654 -112.467898)
			(xy 98.215712 -112.486051) (xy 98.249167 -112.526682) (xy 98.276724 -112.571524) (xy 98.297862 -112.619725)
			(xy 98.312179 -112.670372) (xy 98.319405 -112.722506) (xy 98.319844 -112.748822) (xy 98.319358 -112.776073)
			(xy 98.311602 -112.830021) (xy 98.296247 -112.882316) (xy 98.273605 -112.931893) (xy 98.244139 -112.977743)
			(xy 98.208448 -113.018934) (xy 98.167257 -113.054625) (xy 98.121407 -113.084091) (xy 98.07183 -113.106733)
			(xy 98.019535 -113.122088) (xy 97.965587 -113.129844) (xy 97.911085 -113.129844) (xy 97.857137 -113.122088)
			(xy 97.804842 -113.106733) (xy 97.755265 -113.084091) (xy 97.709415 -113.054625) (xy 97.668224 -113.018934)
			(xy 97.632533 -112.977743) (xy 97.603067 -112.931893) (xy 97.580425 -112.882316) (xy 97.56507 -112.830021)
			(xy 97.557314 -112.776073) (xy 97.556828 -112.748822) (xy 97.557301 -112.722508) (xy 97.564534 -112.67038)
			(xy 97.578851 -112.619737) (xy 97.599982 -112.571537) (xy 97.627528 -112.526694) (xy 97.660966 -112.486054)
			(xy 97.680018 -112.467898) (xy 97.687425 -112.460382) (xy 97.695946 -112.441097) (xy 97.696528 -112.43056)
			(xy 97.696528 -112.355884) (xy 97.696013 -112.345333) (xy 97.687467 -112.326038) (xy 97.680018 -112.318546)
			(xy 97.65925 -112.298705) (xy 97.623272 -112.253937) (xy 97.594409 -112.204283) (xy 97.573313 -112.150863)
			(xy 97.560461 -112.094886) (xy 97.556142 -112.037615) (xy 95.762829 -112.037615) (xy 95.794277 -112.075815)
			(xy 95.821832 -112.12066) (xy 95.842966 -112.168866) (xy 95.857278 -112.219517) (xy 95.864498 -112.271655)
			(xy 95.864934 -112.297972) (xy 95.864448 -112.325223) (xy 95.856692 -112.379171) (xy 95.841337 -112.431466)
			(xy 95.818695 -112.481043) (xy 95.789229 -112.526893) (xy 95.753538 -112.568084) (xy 95.712347 -112.603775)
			(xy 95.666497 -112.633241) (xy 95.61692 -112.655883) (xy 95.564625 -112.671238) (xy 95.510677 -112.678994)
			(xy 95.456175 -112.678994) (xy 95.402227 -112.671238) (xy 95.349932 -112.655883) (xy 95.300355 -112.633241)
			(xy 95.254505 -112.603775) (xy 95.213314 -112.568084) (xy 95.177623 -112.526893) (xy 95.148157 -112.481043)
			(xy 95.125515 -112.431466) (xy 95.11016 -112.379171) (xy 95.102404 -112.325223) (xy 95.101918 -112.297972)
			(xy 93.832934 -112.297972) (xy 93.832448 -112.325223) (xy 93.824692 -112.379171) (xy 93.809337 -112.431466)
			(xy 93.786695 -112.481043) (xy 93.757229 -112.526893) (xy 93.721538 -112.568084) (xy 93.680347 -112.603775)
			(xy 93.634497 -112.633241) (xy 93.58492 -112.655883) (xy 93.532625 -112.671238) (xy 93.478677 -112.678994)
			(xy 93.424175 -112.678994) (xy 93.370227 -112.671238) (xy 93.317932 -112.655883) (xy 93.268355 -112.633241)
			(xy 93.222505 -112.603775) (xy 93.181314 -112.568084) (xy 93.145623 -112.526893) (xy 93.116157 -112.481043)
			(xy 93.093515 -112.431466) (xy 93.07816 -112.379171) (xy 93.070404 -112.325223) (xy 93.069918 -112.297972)
			(xy 82.167574 -112.297972) (xy 82.002376 -113.627154) (xy 82.006948 -113.635536) (xy 82.018367 -113.656885)
			(xy 82.036324 -113.701848) (xy 82.048459 -113.74872) (xy 82.054579 -113.796748) (xy 82.054954 -113.820956)
			(xy 82.054954 -113.829592) (xy 82.05393 -113.855933) (xy 82.045529 -113.907974) (xy 82.030045 -113.958364)
			(xy 82.007774 -114.006143) (xy 81.979139 -114.050402) (xy 81.962244 -114.070638) (xy 81.953608 -114.08029)
			(xy 81.95056 -114.083592) (xy 81.950075 -114.084637) (xy 89.449407 -114.084637) (xy 89.449409 -114.03014)
			(xy 89.457166 -113.976198) (xy 89.472521 -113.923908) (xy 89.495161 -113.874336) (xy 89.524626 -113.828491)
			(xy 89.560315 -113.787305) (xy 89.601502 -113.751618) (xy 89.647348 -113.722155) (xy 89.696921 -113.699517)
			(xy 89.749211 -113.684163) (xy 89.803153 -113.676408) (xy 89.830402 -113.675922) (xy 89.83091 -113.675922)
			(xy 89.854668 -113.676301) (xy 89.901812 -113.682246) (xy 89.947855 -113.693991) (xy 89.970102 -113.702338)
			(xy 89.982802 -113.707418) (xy 90.009472 -113.703354) (xy 90.088974 -113.640108) (xy 90.095629 -113.634331)
			(xy 90.10491 -113.619367) (xy 90.108586 -113.602146) (xy 90.10777 -113.593372) (xy 90.10777 -113.592864)
			(xy 90.105906 -113.579288) (xy 90.103869 -113.551957) (xy 90.103706 -113.538254) (xy 90.104135 -113.511001)
			(xy 90.111898 -113.45705) (xy 90.12726 -113.404754) (xy 90.149907 -113.355176) (xy 90.17938 -113.309325)
			(xy 90.215077 -113.268135) (xy 90.256273 -113.232444) (xy 90.302128 -113.202979) (xy 90.35171 -113.180339)
			(xy 90.404009 -113.164985) (xy 90.457961 -113.157231) (xy 90.485214 -113.156746) (xy 90.514129 -113.157309)
			(xy 90.571299 -113.166026) (xy 90.626498 -113.183274) (xy 90.67846 -113.208657) (xy 90.725995 -113.241594)
			(xy 90.768013 -113.281329) (xy 90.786204 -113.303812) (xy 90.793817 -113.312613) (xy 90.814713 -113.322799)
			(xy 90.826336 -113.32337) (xy 90.906092 -113.32337) (xy 90.917723 -113.322822) (xy 90.938633 -113.312641)
			(xy 90.946224 -113.303812) (xy 90.964405 -113.28132) (xy 91.006426 -113.241584) (xy 91.053963 -113.208646)
			(xy 91.105926 -113.183259) (xy 91.161126 -113.166005) (xy 91.218297 -113.157279) (xy 91.247214 -113.156746)
			(xy 91.274464 -113.157265) (xy 91.328408 -113.165022) (xy 91.380699 -113.180376) (xy 91.430273 -113.203016)
			(xy 91.476121 -113.232479) (xy 91.51731 -113.268167) (xy 91.553001 -113.309353) (xy 91.582469 -113.355199)
			(xy 91.605112 -113.404771) (xy 91.620471 -113.457061) (xy 91.628233 -113.511005) (xy 91.628722 -113.538254)
			(xy 91.628284 -113.565013) (xy 91.627758 -113.568734) (xy 110.889794 -113.568734) (xy 110.893865 -113.513112)
			(xy 110.905991 -113.458675) (xy 110.925914 -113.406584) (xy 110.95321 -113.357949) (xy 110.987296 -113.313806)
			(xy 111.027445 -113.275097) (xy 111.072803 -113.242646) (xy 111.122403 -113.217145) (xy 111.175187 -113.199138)
			(xy 111.23003 -113.189008) (xy 111.285764 -113.186971) (xy 111.341201 -113.193071) (xy 111.395158 -113.207177)
			(xy 111.446487 -113.228989) (xy 111.494093 -113.258043) (xy 111.536961 -113.293718) (xy 111.574178 -113.335255)
			(xy 111.604951 -113.381768) (xy 111.628623 -113.432265) (xy 111.644691 -113.485672) (xy 111.652811 -113.540848)
			(xy 111.65332 -113.568734) (xy 111.652811 -113.59662) (xy 111.644691 -113.651796) (xy 111.628623 -113.705203)
			(xy 111.604951 -113.7557) (xy 111.574178 -113.802213) (xy 111.536961 -113.84375) (xy 111.494093 -113.879425)
			(xy 111.462959 -113.898426) (xy 127.55321 -113.898426) (xy 127.557281 -113.842804) (xy 127.569407 -113.788367)
			(xy 127.58933 -113.736276) (xy 127.616626 -113.687641) (xy 127.650712 -113.643498) (xy 127.690861 -113.604789)
			(xy 127.736219 -113.572338) (xy 127.785819 -113.546837) (xy 127.838603 -113.52883) (xy 127.893446 -113.5187)
			(xy 127.94918 -113.516663) (xy 128.004617 -113.522763) (xy 128.058574 -113.536869) (xy 128.109903 -113.558681)
			(xy 128.157509 -113.587735) (xy 128.200377 -113.62341) (xy 128.237594 -113.664947) (xy 128.268367 -113.71146)
			(xy 128.292039 -113.761957) (xy 128.308107 -113.815364) (xy 128.316227 -113.87054) (xy 128.316736 -113.898426)
			(xy 128.316227 -113.926312) (xy 128.308107 -113.981488) (xy 128.292039 -114.034895) (xy 128.268367 -114.085392)
			(xy 128.237594 -114.131905) (xy 128.200377 -114.173442) (xy 128.157509 -114.209117) (xy 128.109903 -114.238171)
			(xy 128.058574 -114.259983) (xy 128.004617 -114.274089) (xy 127.94918 -114.280189) (xy 127.893446 -114.278152)
			(xy 127.838603 -114.268022) (xy 127.785819 -114.250015) (xy 127.736219 -114.224514) (xy 127.690861 -114.192063)
			(xy 127.650712 -114.153354) (xy 127.616626 -114.109211) (xy 127.58933 -114.060576) (xy 127.569407 -114.008485)
			(xy 127.557281 -113.954048) (xy 127.55321 -113.898426) (xy 111.462959 -113.898426) (xy 111.446487 -113.908479)
			(xy 111.395158 -113.930291) (xy 111.341201 -113.944397) (xy 111.285764 -113.950497) (xy 111.23003 -113.94846)
			(xy 111.175187 -113.93833) (xy 111.122403 -113.920323) (xy 111.072803 -113.894822) (xy 111.027445 -113.862371)
			(xy 110.987296 -113.823662) (xy 110.95321 -113.779519) (xy 110.925914 -113.730884) (xy 110.905991 -113.678793)
			(xy 110.893865 -113.624356) (xy 110.889794 -113.568734) (xy 91.627758 -113.568734) (xy 91.620797 -113.618004)
			(xy 91.605979 -113.669429) (xy 91.58412 -113.718279) (xy 91.555649 -113.763594) (xy 91.521125 -113.804487)
			(xy 91.481225 -113.840153) (xy 91.436732 -113.869894) (xy 91.412822 -113.881916) (xy 91.412568 -113.881916)
			(xy 91.40182 -113.888029) (xy 91.387212 -113.907926) (xy 91.384628 -113.920016) (xy 91.369642 -114.015012)
			(xy 91.37777 -114.03838) (xy 91.38666 -114.047016) (xy 91.396783 -114.05681) (xy 91.415729 -114.077656)
			(xy 91.424506 -114.088672) (xy 91.432057 -114.097444) (xy 91.452825 -114.107619) (xy 91.464384 -114.10823)
			(xy 91.544394 -114.10823) (xy 91.556027 -114.107697) (xy 91.576938 -114.097506) (xy 91.584526 -114.088672)
			(xy 91.602695 -114.06617) (xy 91.64472 -114.026437) (xy 91.69226 -113.993501) (xy 91.744225 -113.968116)
			(xy 91.799426 -113.950864) (xy 91.856599 -113.942139) (xy 91.885516 -113.941606) (xy 91.912768 -113.942065)
			(xy 91.966715 -113.949824) (xy 92.01901 -113.965181) (xy 92.068587 -113.987824) (xy 92.114437 -114.017291)
			(xy 92.127342 -114.028474) (xy 105.005122 -114.028474) (xy 105.009193 -113.972852) (xy 105.021319 -113.918415)
			(xy 105.041242 -113.866324) (xy 105.068538 -113.817689) (xy 105.102624 -113.773546) (xy 105.142773 -113.734837)
			(xy 105.188131 -113.702386) (xy 105.237731 -113.676885) (xy 105.290515 -113.658878) (xy 105.345358 -113.648748)
			(xy 105.401092 -113.646711) (xy 105.456529 -113.652811) (xy 105.510486 -113.666917) (xy 105.561815 -113.688729)
			(xy 105.609421 -113.717783) (xy 105.652289 -113.753458) (xy 105.689506 -113.794995) (xy 105.720279 -113.841508)
			(xy 105.743951 -113.892005) (xy 105.760019 -113.945412) (xy 105.768139 -114.000588) (xy 105.768648 -114.028474)
			(xy 105.768139 -114.05636) (xy 105.760019 -114.111536) (xy 105.743951 -114.164943) (xy 105.720279 -114.21544)
			(xy 105.689506 -114.261953) (xy 105.652289 -114.30349) (xy 105.609421 -114.339165) (xy 105.561815 -114.368219)
			(xy 105.510486 -114.390031) (xy 105.456529 -114.404137) (xy 105.401092 -114.410237) (xy 105.345358 -114.4082)
			(xy 105.290515 -114.39807) (xy 105.237731 -114.380063) (xy 105.188131 -114.354562) (xy 105.142773 -114.322111)
			(xy 105.102624 -114.283402) (xy 105.068538 -114.239259) (xy 105.041242 -114.190624) (xy 105.021319 -114.138533)
			(xy 105.009193 -114.084096) (xy 105.005122 -114.028474) (xy 92.127342 -114.028474) (xy 92.155627 -114.052984)
			(xy 92.191318 -114.094175) (xy 92.220784 -114.140027) (xy 92.243425 -114.189605) (xy 92.25878 -114.2419)
			(xy 92.266536 -114.295848) (xy 92.266536 -114.350352) (xy 92.25878 -114.4043) (xy 92.243425 -114.456595)
			(xy 92.220784 -114.506173) (xy 92.191318 -114.552025) (xy 92.155627 -114.593216) (xy 92.114437 -114.628909)
			(xy 92.068587 -114.658376) (xy 92.01901 -114.681019) (xy 91.966715 -114.696376) (xy 91.912767 -114.704135)
			(xy 91.885516 -114.704622) (xy 91.856598 -114.704122) (xy 91.799425 -114.695393) (xy 91.744224 -114.678134)
			(xy 91.692262 -114.652739) (xy 91.644729 -114.619791) (xy 91.602714 -114.580044) (xy 91.584526 -114.557556)
			(xy 91.576905 -114.548763) (xy 91.556015 -114.538574) (xy 91.544394 -114.537998) (xy 91.464638 -114.537998)
			(xy 91.453004 -114.538516) (xy 91.432094 -114.54872) (xy 91.424506 -114.557556) (xy 91.4063 -114.580027)
			(xy 91.364285 -114.619765) (xy 91.316754 -114.652707) (xy 91.264795 -114.678098) (xy 91.209599 -114.695356)
			(xy 91.152431 -114.704087) (xy 91.123516 -114.704622) (xy 91.096264 -114.70413) (xy 91.042315 -114.696375)
			(xy 90.990019 -114.681022) (xy 90.940439 -114.658383) (xy 90.894587 -114.628917) (xy 90.853394 -114.593227)
			(xy 90.817701 -114.552037) (xy 90.788232 -114.506187) (xy 90.765588 -114.45661) (xy 90.750231 -114.404314)
			(xy 90.742472 -114.350366) (xy 90.742008 -114.323114) (xy 90.742459 -114.296356) (xy 90.749948 -114.243367)
			(xy 90.764767 -114.191945) (xy 90.786626 -114.143097) (xy 90.815095 -114.097782) (xy 90.849616 -114.056889)
			(xy 90.889512 -114.021221) (xy 90.934 -113.991476) (xy 90.957908 -113.979452) (xy 90.958162 -113.979452)
			(xy 90.968927 -113.973364) (xy 90.983526 -113.953449) (xy 90.986102 -113.941352) (xy 91.001088 -113.846356)
			(xy 90.99296 -113.822988) (xy 90.98407 -113.814352) (xy 90.973942 -113.804563) (xy 90.954999 -113.783714)
			(xy 90.946224 -113.772696) (xy 90.938648 -113.763949) (xy 90.9179 -113.753757) (xy 90.906346 -113.753138)
			(xy 90.826336 -113.753138) (xy 90.814699 -113.753642) (xy 90.793789 -113.763854) (xy 90.786204 -113.772696)
			(xy 90.76801 -113.795177) (xy 90.725991 -113.834912) (xy 90.678457 -113.867852) (xy 90.626496 -113.893241)
			(xy 90.571299 -113.910497) (xy 90.51413 -113.919227) (xy 90.485214 -113.919762) (xy 90.484706 -113.919762)
			(xy 90.460948 -113.919379) (xy 90.413804 -113.913436) (xy 90.367761 -113.901692) (xy 90.345514 -113.893346)
			(xy 90.332814 -113.888266) (xy 90.306144 -113.89233) (xy 90.226642 -113.955576) (xy 90.219982 -113.961347)
			(xy 90.210709 -113.976316) (xy 90.207033 -113.993537) (xy 90.207846 -114.002312) (xy 90.207846 -114.00282)
			(xy 90.209719 -114.016395) (xy 90.21175 -114.043727) (xy 90.21191 -114.05743) (xy 90.21139 -114.084679)
			(xy 90.20363 -114.138621) (xy 90.188272 -114.190909) (xy 90.16563 -114.24048) (xy 90.136163 -114.286324)
			(xy 90.100472 -114.327508) (xy 90.059283 -114.363193) (xy 90.013436 -114.392654) (xy 89.963862 -114.41529)
			(xy 89.911571 -114.430641) (xy 89.857628 -114.438393) (xy 89.803131 -114.43839) (xy 89.749189 -114.430632)
			(xy 89.6969 -114.415276) (xy 89.647328 -114.392634) (xy 89.601483 -114.363169) (xy 89.560299 -114.327479)
			(xy 89.524612 -114.286291) (xy 89.49515 -114.240444) (xy 89.472513 -114.19087) (xy 89.457161 -114.13858)
			(xy 89.449407 -114.084637) (xy 81.950075 -114.084637) (xy 81.947258 -114.090704) (xy 81.945672 -114.094286)
			(xy 81.943494 -114.101812) (xy 81.94294 -114.10569) (xy 81.909412 -114.375946) (xy 81.782025 -115.400836)
			(xy 87.260682 -115.400836) (xy 87.264753 -115.345214) (xy 87.276879 -115.290777) (xy 87.296802 -115.238686)
			(xy 87.324098 -115.190051) (xy 87.358184 -115.145908) (xy 87.398333 -115.107199) (xy 87.443691 -115.074748)
			(xy 87.493291 -115.049247) (xy 87.546075 -115.03124) (xy 87.600918 -115.02111) (xy 87.656652 -115.019073)
			(xy 87.712089 -115.025173) (xy 87.766046 -115.039279) (xy 87.817375 -115.061091) (xy 87.864981 -115.090145)
			(xy 87.907849 -115.12582) (xy 87.945066 -115.167357) (xy 87.975839 -115.21387) (xy 87.999511 -115.264367)
			(xy 88.015579 -115.317774) (xy 88.023317 -115.370356) (xy 89.361262 -115.370356) (xy 89.365333 -115.314734)
			(xy 89.377459 -115.260297) (xy 89.397382 -115.208206) (xy 89.424678 -115.159571) (xy 89.458764 -115.115428)
			(xy 89.498913 -115.076719) (xy 89.544271 -115.044268) (xy 89.593871 -115.018767) (xy 89.646655 -115.00076)
			(xy 89.701498 -114.99063) (xy 89.757232 -114.988593) (xy 89.812669 -114.994693) (xy 89.866626 -115.008799)
			(xy 89.871678 -115.010946) (xy 106.6198 -115.010946) (xy 106.623871 -114.955324) (xy 106.635997 -114.900887)
			(xy 106.65592 -114.848796) (xy 106.683216 -114.800161) (xy 106.717302 -114.756018) (xy 106.757451 -114.717309)
			(xy 106.802809 -114.684858) (xy 106.852409 -114.659357) (xy 106.905193 -114.64135) (xy 106.960036 -114.63122)
			(xy 107.01577 -114.629183) (xy 107.071207 -114.635283) (xy 107.125164 -114.649389) (xy 107.176493 -114.671201)
			(xy 107.224099 -114.700255) (xy 107.266967 -114.73593) (xy 107.304184 -114.777467) (xy 107.334957 -114.82398)
			(xy 107.358629 -114.874477) (xy 107.374697 -114.927884) (xy 107.382817 -114.98306) (xy 107.383326 -115.010946)
			(xy 107.382817 -115.038832) (xy 107.379893 -115.058698) (xy 107.98632 -115.058698) (xy 107.990391 -115.003076)
			(xy 108.002517 -114.948639) (xy 108.02244 -114.896548) (xy 108.049736 -114.847913) (xy 108.083822 -114.80377)
			(xy 108.123971 -114.765061) (xy 108.169329 -114.73261) (xy 108.218929 -114.707109) (xy 108.271713 -114.689102)
			(xy 108.326556 -114.678972) (xy 108.38229 -114.676935) (xy 108.437727 -114.683035) (xy 108.491684 -114.697141)
			(xy 108.543013 -114.718953) (xy 108.590619 -114.748007) (xy 108.633487 -114.783682) (xy 108.670704 -114.825219)
			(xy 108.701477 -114.871732) (xy 108.725149 -114.922229) (xy 108.741217 -114.975636) (xy 108.743386 -114.990372)
			(xy 109.365032 -114.990372) (xy 109.369103 -114.93475) (xy 109.381229 -114.880313) (xy 109.401152 -114.828222)
			(xy 109.428448 -114.779587) (xy 109.462534 -114.735444) (xy 109.502683 -114.696735) (xy 109.548041 -114.664284)
			(xy 109.597641 -114.638783) (xy 109.650425 -114.620776) (xy 109.705268 -114.610646) (xy 109.761002 -114.608609)
			(xy 109.816439 -114.614709) (xy 109.870396 -114.628815) (xy 109.921725 -114.650627) (xy 109.969331 -114.679681)
			(xy 110.012199 -114.715356) (xy 110.049416 -114.756893) (xy 110.080189 -114.803406) (xy 110.103861 -114.853903)
			(xy 110.119929 -114.90731) (xy 110.127779 -114.960654) (xy 110.891826 -114.960654) (xy 110.895897 -114.905032)
			(xy 110.908023 -114.850595) (xy 110.927946 -114.798504) (xy 110.955242 -114.749869) (xy 110.989328 -114.705726)
			(xy 111.029477 -114.667017) (xy 111.074835 -114.634566) (xy 111.124435 -114.609065) (xy 111.177219 -114.591058)
			(xy 111.232062 -114.580928) (xy 111.287796 -114.578891) (xy 111.343233 -114.584991) (xy 111.39719 -114.599097)
			(xy 111.448519 -114.620909) (xy 111.496125 -114.649963) (xy 111.538993 -114.685638) (xy 111.57621 -114.727175)
			(xy 111.606983 -114.773688) (xy 111.630655 -114.824185) (xy 111.646723 -114.877592) (xy 111.654843 -114.932768)
			(xy 111.655352 -114.960654) (xy 111.654843 -114.98854) (xy 111.646723 -115.043716) (xy 111.630655 -115.097123)
			(xy 111.606983 -115.14762) (xy 111.57621 -115.194133) (xy 111.538993 -115.23567) (xy 111.496125 -115.271345)
			(xy 111.448519 -115.300399) (xy 111.39719 -115.322211) (xy 111.343233 -115.336317) (xy 111.287796 -115.342417)
			(xy 111.232062 -115.34038) (xy 111.177219 -115.33025) (xy 111.124435 -115.312243) (xy 111.074835 -115.286742)
			(xy 111.029477 -115.254291) (xy 110.989328 -115.215582) (xy 110.955242 -115.171439) (xy 110.927946 -115.122804)
			(xy 110.908023 -115.070713) (xy 110.895897 -115.016276) (xy 110.891826 -114.960654) (xy 110.127779 -114.960654)
			(xy 110.128049 -114.962486) (xy 110.128558 -114.990372) (xy 110.128049 -115.018258) (xy 110.119929 -115.073434)
			(xy 110.103861 -115.126841) (xy 110.080189 -115.177338) (xy 110.049416 -115.223851) (xy 110.012199 -115.265388)
			(xy 109.969331 -115.301063) (xy 109.921725 -115.330117) (xy 109.870396 -115.351929) (xy 109.816439 -115.366035)
			(xy 109.761002 -115.372135) (xy 109.705268 -115.370098) (xy 109.650425 -115.359968) (xy 109.597641 -115.341961)
			(xy 109.548041 -115.31646) (xy 109.502683 -115.284009) (xy 109.462534 -115.2453) (xy 109.428448 -115.201157)
			(xy 109.401152 -115.152522) (xy 109.381229 -115.100431) (xy 109.369103 -115.045994) (xy 109.365032 -114.990372)
			(xy 108.743386 -114.990372) (xy 108.749337 -115.030812) (xy 108.749846 -115.058698) (xy 108.749337 -115.086584)
			(xy 108.741217 -115.14176) (xy 108.725149 -115.195167) (xy 108.701477 -115.245664) (xy 108.670704 -115.292177)
			(xy 108.633487 -115.333714) (xy 108.590619 -115.369389) (xy 108.543013 -115.398443) (xy 108.491684 -115.420255)
			(xy 108.437727 -115.434361) (xy 108.38229 -115.440461) (xy 108.326556 -115.438424) (xy 108.271713 -115.428294)
			(xy 108.218929 -115.410287) (xy 108.169329 -115.384786) (xy 108.123971 -115.352335) (xy 108.083822 -115.313626)
			(xy 108.049736 -115.269483) (xy 108.02244 -115.220848) (xy 108.002517 -115.168757) (xy 107.990391 -115.11432)
			(xy 107.98632 -115.058698) (xy 107.379893 -115.058698) (xy 107.374697 -115.094008) (xy 107.358629 -115.147415)
			(xy 107.334957 -115.197912) (xy 107.304184 -115.244425) (xy 107.266967 -115.285962) (xy 107.224099 -115.321637)
			(xy 107.176493 -115.350691) (xy 107.125164 -115.372503) (xy 107.071207 -115.386609) (xy 107.01577 -115.392709)
			(xy 106.960036 -115.390672) (xy 106.905193 -115.380542) (xy 106.852409 -115.362535) (xy 106.802809 -115.337034)
			(xy 106.757451 -115.304583) (xy 106.717302 -115.265874) (xy 106.683216 -115.221731) (xy 106.65592 -115.173096)
			(xy 106.635997 -115.121005) (xy 106.623871 -115.066568) (xy 106.6198 -115.010946) (xy 89.871678 -115.010946)
			(xy 89.917955 -115.030611) (xy 89.965561 -115.059665) (xy 90.008429 -115.09534) (xy 90.045646 -115.136877)
			(xy 90.076419 -115.18339) (xy 90.100091 -115.233887) (xy 90.116159 -115.287294) (xy 90.124279 -115.34247)
			(xy 90.124788 -115.370356) (xy 90.124279 -115.398242) (xy 90.116159 -115.453418) (xy 90.100091 -115.506825)
			(xy 90.076419 -115.557322) (xy 90.045646 -115.603835) (xy 90.008429 -115.645372) (xy 89.965561 -115.681047)
			(xy 89.917955 -115.710101) (xy 89.866626 -115.731913) (xy 89.812669 -115.746019) (xy 89.757232 -115.752119)
			(xy 89.701498 -115.750082) (xy 89.646655 -115.739952) (xy 89.593871 -115.721945) (xy 89.544271 -115.696444)
			(xy 89.498913 -115.663993) (xy 89.458764 -115.625284) (xy 89.424678 -115.581141) (xy 89.397382 -115.532506)
			(xy 89.377459 -115.480415) (xy 89.365333 -115.425978) (xy 89.361262 -115.370356) (xy 88.023317 -115.370356)
			(xy 88.023699 -115.37295) (xy 88.024208 -115.400836) (xy 88.023699 -115.428722) (xy 88.015579 -115.483898)
			(xy 87.999511 -115.537305) (xy 87.975839 -115.587802) (xy 87.945066 -115.634315) (xy 87.907849 -115.675852)
			(xy 87.864981 -115.711527) (xy 87.817375 -115.740581) (xy 87.766046 -115.762393) (xy 87.712089 -115.776499)
			(xy 87.656652 -115.782599) (xy 87.600918 -115.780562) (xy 87.546075 -115.770432) (xy 87.493291 -115.752425)
			(xy 87.443691 -115.726924) (xy 87.398333 -115.694473) (xy 87.358184 -115.655764) (xy 87.324098 -115.611621)
			(xy 87.296802 -115.562986) (xy 87.276879 -115.510895) (xy 87.264753 -115.456458) (xy 87.260682 -115.400836)
			(xy 81.782025 -115.400836) (xy 81.728355 -115.832636) (xy 92.979238 -115.832636) (xy 92.983309 -115.777014)
			(xy 92.995435 -115.722577) (xy 93.015358 -115.670486) (xy 93.042654 -115.621851) (xy 93.07674 -115.577708)
			(xy 93.116889 -115.538999) (xy 93.162247 -115.506548) (xy 93.211847 -115.481047) (xy 93.264631 -115.46304)
			(xy 93.319474 -115.45291) (xy 93.375208 -115.450873) (xy 93.430645 -115.456973) (xy 93.484602 -115.471079)
			(xy 93.535931 -115.492891) (xy 93.583537 -115.521945) (xy 93.626405 -115.55762) (xy 93.663622 -115.599157)
			(xy 93.694395 -115.64567) (xy 93.718067 -115.696167) (xy 93.734135 -115.749574) (xy 93.742255 -115.80475)
			(xy 93.742764 -115.832636) (xy 93.742255 -115.860522) (xy 93.734135 -115.915698) (xy 93.718067 -115.969105)
			(xy 93.694395 -116.019602) (xy 93.663622 -116.066115) (xy 93.626405 -116.107652) (xy 93.583537 -116.143327)
			(xy 93.535931 -116.172381) (xy 93.484602 -116.194193) (xy 93.430645 -116.208299) (xy 93.375208 -116.214399)
			(xy 93.319474 -116.212362) (xy 93.264631 -116.202232) (xy 93.211847 -116.184225) (xy 93.162247 -116.158724)
			(xy 93.116889 -116.126273) (xy 93.07674 -116.087564) (xy 93.042654 -116.043421) (xy 93.015358 -115.994786)
			(xy 92.995435 -115.942695) (xy 92.983309 -115.888258) (xy 92.979238 -115.832636) (xy 81.728355 -115.832636)
			(xy 81.624298 -116.66982) (xy 89.3732 -116.66982) (xy 89.377271 -116.614198) (xy 89.389397 -116.559761)
			(xy 89.40932 -116.50767) (xy 89.436616 -116.459035) (xy 89.470702 -116.414892) (xy 89.510851 -116.376183)
			(xy 89.556209 -116.343732) (xy 89.605809 -116.318231) (xy 89.658593 -116.300224) (xy 89.713436 -116.290094)
			(xy 89.76917 -116.288057) (xy 89.824607 -116.294157) (xy 89.878564 -116.308263) (xy 89.929893 -116.330075)
			(xy 89.977499 -116.359129) (xy 90.020367 -116.394804) (xy 90.057584 -116.436341) (xy 90.088357 -116.482854)
			(xy 90.112029 -116.533351) (xy 90.128097 -116.586758) (xy 90.13434 -116.62918) (xy 105.137964 -116.62918)
			(xy 105.142035 -116.573558) (xy 105.154161 -116.519121) (xy 105.174084 -116.46703) (xy 105.20138 -116.418395)
			(xy 105.235466 -116.374252) (xy 105.275615 -116.335543) (xy 105.320973 -116.303092) (xy 105.370573 -116.277591)
			(xy 105.423357 -116.259584) (xy 105.4782 -116.249454) (xy 105.533934 -116.247417) (xy 105.589371 -116.253517)
			(xy 105.643328 -116.267623) (xy 105.694657 -116.289435) (xy 105.742263 -116.318489) (xy 105.785131 -116.354164)
			(xy 105.822348 -116.395701) (xy 105.853121 -116.442214) (xy 105.876793 -116.492711) (xy 105.892861 -116.546118)
			(xy 105.900981 -116.601294) (xy 105.90149 -116.62918) (xy 105.900981 -116.657066) (xy 105.892861 -116.712242)
			(xy 105.876793 -116.765649) (xy 105.853121 -116.816146) (xy 105.822348 -116.862659) (xy 105.785131 -116.904196)
			(xy 105.742263 -116.939871) (xy 105.694657 -116.968925) (xy 105.643328 -116.990737) (xy 105.589371 -117.004843)
			(xy 105.533934 -117.010943) (xy 105.4782 -117.008906) (xy 105.423357 -116.998776) (xy 105.370573 -116.980769)
			(xy 105.320973 -116.955268) (xy 105.275615 -116.922817) (xy 105.235466 -116.884108) (xy 105.20138 -116.839965)
			(xy 105.174084 -116.79133) (xy 105.154161 -116.739239) (xy 105.142035 -116.684802) (xy 105.137964 -116.62918)
			(xy 90.13434 -116.62918) (xy 90.136217 -116.641934) (xy 90.136726 -116.66982) (xy 90.136217 -116.697706)
			(xy 90.128097 -116.752882) (xy 90.112029 -116.806289) (xy 90.088357 -116.856786) (xy 90.057584 -116.903299)
			(xy 90.020367 -116.944836) (xy 89.977499 -116.980511) (xy 89.929893 -117.009565) (xy 89.878564 -117.031377)
			(xy 89.824607 -117.045483) (xy 89.76917 -117.051583) (xy 89.713436 -117.049546) (xy 89.658593 -117.039416)
			(xy 89.605809 -117.021409) (xy 89.556209 -116.995908) (xy 89.510851 -116.963457) (xy 89.470702 -116.924748)
			(xy 89.436616 -116.880605) (xy 89.40932 -116.83197) (xy 89.389397 -116.779879) (xy 89.377271 -116.725442)
			(xy 89.3732 -116.66982) (xy 81.624298 -116.66982) (xy 81.534728 -117.390451) (xy 90.742495 -117.390451)
			(xy 90.742495 -117.335949) (xy 90.750252 -117.282003) (xy 90.765607 -117.229709) (xy 90.788248 -117.180133)
			(xy 90.817715 -117.134284) (xy 90.853406 -117.093095) (xy 90.894597 -117.057405) (xy 90.940447 -117.027941)
			(xy 90.990024 -117.005301) (xy 91.042318 -116.989948) (xy 91.096265 -116.982194) (xy 91.123516 -116.981732)
			(xy 91.152431 -116.982299) (xy 91.209601 -116.991016) (xy 91.264799 -117.008264) (xy 91.316761 -117.033646)
			(xy 91.364296 -117.066582) (xy 91.406315 -117.106316) (xy 91.424506 -117.128798) (xy 91.432121 -117.137598)
			(xy 91.453016 -117.147786) (xy 91.464638 -117.148356) (xy 91.544394 -117.148356) (xy 91.556026 -117.147815)
			(xy 91.576937 -117.137629) (xy 91.584526 -117.128798) (xy 91.602702 -117.106302) (xy 91.644725 -117.066567)
			(xy 91.692263 -117.03363) (xy 91.744227 -117.008244) (xy 91.799427 -116.99099) (xy 91.856599 -116.982265)
			(xy 91.885516 -116.981732) (xy 91.912769 -116.982139) (xy 91.966721 -116.989898) (xy 92.019019 -117.005256)
			(xy 92.0686 -117.027901) (xy 92.114453 -117.057371) (xy 92.155646 -117.093066) (xy 92.163938 -117.102636)
			(xy 92.979238 -117.102636) (xy 92.983309 -117.047014) (xy 92.995435 -116.992577) (xy 93.015358 -116.940486)
			(xy 93.042654 -116.891851) (xy 93.07674 -116.847708) (xy 93.116889 -116.808999) (xy 93.162247 -116.776548)
			(xy 93.211847 -116.751047) (xy 93.264631 -116.73304) (xy 93.319474 -116.72291) (xy 93.375208 -116.720873)
			(xy 93.430645 -116.726973) (xy 93.484602 -116.741079) (xy 93.535931 -116.762891) (xy 93.583537 -116.791945)
			(xy 93.626405 -116.82762) (xy 93.663622 -116.869157) (xy 93.694395 -116.91567) (xy 93.718067 -116.966167)
			(xy 93.734135 -117.019574) (xy 93.742255 -117.07475) (xy 93.742764 -117.102636) (xy 93.742255 -117.130522)
			(xy 93.734135 -117.185698) (xy 93.718067 -117.239105) (xy 93.713814 -117.248178) (xy 107.738924 -117.248178)
			(xy 107.742995 -117.192556) (xy 107.755121 -117.138119) (xy 107.775044 -117.086028) (xy 107.80234 -117.037393)
			(xy 107.836426 -116.99325) (xy 107.876575 -116.954541) (xy 107.921933 -116.92209) (xy 107.971533 -116.896589)
			(xy 108.024317 -116.878582) (xy 108.07916 -116.868452) (xy 108.134894 -116.866415) (xy 108.190331 -116.872515)
			(xy 108.244288 -116.886621) (xy 108.295617 -116.908433) (xy 108.343223 -116.937487) (xy 108.386091 -116.973162)
			(xy 108.423308 -117.014699) (xy 108.454081 -117.061212) (xy 108.477753 -117.111709) (xy 108.493821 -117.165116)
			(xy 108.501941 -117.220292) (xy 108.50245 -117.248178) (xy 108.754924 -117.248178) (xy 108.758995 -117.192556)
			(xy 108.771121 -117.138119) (xy 108.791044 -117.086028) (xy 108.81834 -117.037393) (xy 108.852426 -116.99325)
			(xy 108.892575 -116.954541) (xy 108.937933 -116.92209) (xy 108.987533 -116.896589) (xy 109.040317 -116.878582)
			(xy 109.09516 -116.868452) (xy 109.150894 -116.866415) (xy 109.206331 -116.872515) (xy 109.260288 -116.886621)
			(xy 109.311617 -116.908433) (xy 109.359223 -116.937487) (xy 109.402091 -116.973162) (xy 109.439308 -117.014699)
			(xy 109.470081 -117.061212) (xy 109.493753 -117.111709) (xy 109.509821 -117.165116) (xy 109.517941 -117.220292)
			(xy 109.51845 -117.248178) (xy 109.770924 -117.248178) (xy 109.774995 -117.192556) (xy 109.787121 -117.138119)
			(xy 109.807044 -117.086028) (xy 109.83434 -117.037393) (xy 109.868426 -116.99325) (xy 109.908575 -116.954541)
			(xy 109.953933 -116.92209) (xy 110.003533 -116.896589) (xy 110.056317 -116.878582) (xy 110.11116 -116.868452)
			(xy 110.166894 -116.866415) (xy 110.222331 -116.872515) (xy 110.276288 -116.886621) (xy 110.327617 -116.908433)
			(xy 110.375223 -116.937487) (xy 110.418091 -116.973162) (xy 110.422205 -116.977754) (xy 116.998945 -116.977754)
			(xy 116.998945 -116.923246) (xy 117.006702 -116.869293) (xy 117.022059 -116.816994) (xy 117.044702 -116.767412)
			(xy 117.074171 -116.721558) (xy 117.109866 -116.680364) (xy 117.151061 -116.644669) (xy 117.196916 -116.6152)
			(xy 117.246498 -116.592557) (xy 117.298797 -116.577201) (xy 117.35275 -116.569445) (xy 117.380004 -116.568982)
			(xy 117.408923 -116.569466) (xy 117.466097 -116.578198) (xy 117.521298 -116.595461) (xy 117.57326 -116.620859)
			(xy 117.620793 -116.65381) (xy 117.662806 -116.693559) (xy 117.680994 -116.716048) (xy 117.688605 -116.72485)
			(xy 117.709503 -116.735035) (xy 117.721126 -116.735606) (xy 117.800882 -116.735606) (xy 117.81251 -116.73504)
			(xy 117.83342 -116.72487) (xy 117.841014 -116.716048) (xy 117.859184 -116.693547) (xy 117.90121 -116.653815)
			(xy 117.948749 -116.62088) (xy 118.000715 -116.595495) (xy 118.055915 -116.578242) (xy 118.113087 -116.569516)
			(xy 118.142004 -116.568982) (xy 118.169254 -116.569489) (xy 118.2232 -116.577245) (xy 118.275493 -116.5926)
			(xy 118.325068 -116.615241) (xy 118.370917 -116.644707) (xy 118.402538 -116.672106) (xy 128.968754 -116.672106)
			(xy 128.96921 -116.644735) (xy 128.977029 -116.590555) (xy 128.992519 -116.538052) (xy 129.015363 -116.488305)
			(xy 129.045091 -116.442339) (xy 129.062734 -116.421408) (xy 129.062988 -116.421154) (xy 129.068557 -116.414055)
			(xy 129.074815 -116.397148) (xy 129.07518 -116.388134) (xy 129.07518 -116.321078) (xy 129.074838 -116.31206)
			(xy 129.06858 -116.295142) (xy 129.062988 -116.288058) (xy 129.062734 -116.288058) (xy 129.062734 -116.287804)
			(xy 129.045099 -116.266867) (xy 129.015373 -116.2209) (xy 128.992527 -116.171154) (xy 128.97703 -116.118653)
			(xy 128.969201 -116.064475) (xy 128.9692 -116.009734) (xy 128.977028 -115.955556) (xy 128.992524 -115.903054)
			(xy 129.015369 -115.853308) (xy 129.045093 -115.807341) (xy 129.062734 -115.786408) (xy 129.062988 -115.786154)
			(xy 129.068557 -115.779055) (xy 129.074815 -115.762148) (xy 129.07518 -115.753134) (xy 129.07518 -115.686078)
			(xy 129.074838 -115.67706) (xy 129.06858 -115.660142) (xy 129.062988 -115.653058) (xy 129.062734 -115.653058)
			(xy 129.062734 -115.652804) (xy 129.045089 -115.631877) (xy 129.015377 -115.585903) (xy 128.992541 -115.536155)
			(xy 128.977052 -115.483653) (xy 128.969226 -115.429476) (xy 128.968754 -115.402106) (xy 128.969283 -115.374857)
			(xy 128.977038 -115.320912) (xy 128.99239 -115.268621) (xy 129.015028 -115.219046) (xy 129.04449 -115.173198)
			(xy 129.080177 -115.132008) (xy 129.121362 -115.096317) (xy 129.167207 -115.066849) (xy 129.21678 -115.044206)
			(xy 129.269069 -115.028847) (xy 129.323013 -115.021086) (xy 129.350262 -115.020598) (xy 129.377631 -115.021087)
			(xy 129.431809 -115.028899) (xy 129.484312 -115.044383) (xy 129.53406 -115.06722) (xy 129.580027 -115.096939)
			(xy 129.60096 -115.114578) (xy 129.601214 -115.114832) (xy 129.60829 -115.120434) (xy 129.625215 -115.12667)
			(xy 129.634234 -115.127024) (xy 129.70129 -115.127024) (xy 129.710306 -115.126657) (xy 129.727222 -115.120416)
			(xy 129.73431 -115.114832) (xy 129.73431 -115.114578) (xy 129.734564 -115.114578) (xy 129.755496 -115.096939)
			(xy 129.801469 -115.067228) (xy 129.851217 -115.044392) (xy 129.903717 -115.028901) (xy 129.957893 -115.021072)
			(xy 129.985262 -115.020598) (xy 130.012514 -115.021091) (xy 130.066464 -115.028843) (xy 130.118762 -115.044194)
			(xy 130.168342 -115.066833) (xy 130.214196 -115.096297) (xy 130.255389 -115.131988) (xy 130.291084 -115.173178)
			(xy 130.320552 -115.219029) (xy 130.343195 -115.268608) (xy 130.358551 -115.320904) (xy 130.366307 -115.374854)
			(xy 130.36677 -115.402106) (xy 130.366315 -115.429477) (xy 130.358495 -115.483657) (xy 130.343004 -115.53616)
			(xy 130.32016 -115.585907) (xy 130.290433 -115.631873) (xy 130.27279 -115.652804) (xy 130.272536 -115.653058)
			(xy 130.266953 -115.660147) (xy 130.260706 -115.677062) (xy 130.260344 -115.686078) (xy 130.260344 -115.753134)
			(xy 130.260675 -115.762154) (xy 130.26694 -115.779071) (xy 130.272536 -115.786154) (xy 130.27279 -115.786154)
			(xy 130.27279 -115.786408) (xy 130.290436 -115.807336) (xy 130.320159 -115.853305) (xy 130.343003 -115.903052)
			(xy 130.358498 -115.955555) (xy 130.366326 -116.009734) (xy 130.366325 -116.064475) (xy 130.358496 -116.118654)
			(xy 130.343 -116.171156) (xy 130.320155 -116.220903) (xy 130.29043 -116.266871) (xy 130.27279 -116.287804)
			(xy 130.272536 -116.288058) (xy 130.266953 -116.295147) (xy 130.260706 -116.312062) (xy 130.260344 -116.321078)
			(xy 130.260344 -116.388134) (xy 130.260675 -116.397154) (xy 130.26694 -116.414071) (xy 130.272536 -116.421154)
			(xy 130.27279 -116.421154) (xy 130.27279 -116.421408) (xy 130.290445 -116.442327) (xy 130.320155 -116.488304)
			(xy 130.342988 -116.538054) (xy 130.358475 -116.590558) (xy 130.366299 -116.644736) (xy 130.36677 -116.672106)
			(xy 130.366631 -116.680234) (xy 131.250942 -116.680234) (xy 131.255013 -116.624612) (xy 131.267139 -116.570175)
			(xy 131.287062 -116.518084) (xy 131.314358 -116.469449) (xy 131.348444 -116.425306) (xy 131.388593 -116.386597)
			(xy 131.433951 -116.354146) (xy 131.483551 -116.328645) (xy 131.536335 -116.310638) (xy 131.591178 -116.300508)
			(xy 131.646912 -116.298471) (xy 131.702349 -116.304571) (xy 131.756306 -116.318677) (xy 131.807635 -116.340489)
			(xy 131.855241 -116.369543) (xy 131.898109 -116.405218) (xy 131.935326 -116.446755) (xy 131.966099 -116.493268)
			(xy 131.989771 -116.543765) (xy 132.005839 -116.597172) (xy 132.013959 -116.652348) (xy 132.014468 -116.680234)
			(xy 132.013959 -116.70812) (xy 132.005839 -116.763296) (xy 131.989771 -116.816703) (xy 131.966099 -116.8672)
			(xy 131.935326 -116.913713) (xy 131.898109 -116.95525) (xy 131.855241 -116.990925) (xy 131.807635 -117.019979)
			(xy 131.756306 -117.041791) (xy 131.702349 -117.055897) (xy 131.646912 -117.061997) (xy 131.591178 -117.05996)
			(xy 131.536335 -117.04983) (xy 131.483551 -117.031823) (xy 131.433951 -117.006322) (xy 131.388593 -116.973871)
			(xy 131.348444 -116.935162) (xy 131.314358 -116.891019) (xy 131.287062 -116.842384) (xy 131.267139 -116.790293)
			(xy 131.255013 -116.735856) (xy 131.250942 -116.680234) (xy 130.366631 -116.680234) (xy 130.366317 -116.698663)
			(xy 130.358948 -116.751262) (xy 130.344354 -116.802331) (xy 130.334004 -116.826792) (xy 130.329655 -116.83816)
			(xy 130.331003 -116.862434) (xy 130.336544 -116.873274) (xy 130.377946 -116.944394) (xy 130.38471 -116.95444)
			(xy 130.405096 -116.967442) (xy 130.417062 -116.969286) (xy 130.445045 -116.972458) (xy 130.499709 -116.985996)
			(xy 130.551788 -117.007424) (xy 130.600151 -117.036276) (xy 130.643746 -117.071926) (xy 130.681627 -117.113597)
			(xy 130.712968 -117.160385) (xy 130.73709 -117.211273) (xy 130.753467 -117.265155) (xy 130.758909 -117.301772)
			(xy 132.398006 -117.301772) (xy 132.402077 -117.24615) (xy 132.414203 -117.191713) (xy 132.434126 -117.139622)
			(xy 132.461422 -117.090987) (xy 132.495508 -117.046844) (xy 132.535657 -117.008135) (xy 132.581015 -116.975684)
			(xy 132.630615 -116.950183) (xy 132.683399 -116.932176) (xy 132.738242 -116.922046) (xy 132.793976 -116.920009)
			(xy 132.849413 -116.926109) (xy 132.90337 -116.940215) (xy 132.954699 -116.962027) (xy 133.002305 -116.991081)
			(xy 133.045173 -117.026756) (xy 133.08239 -117.068293) (xy 133.113163 -117.114806) (xy 133.136835 -117.165303)
			(xy 133.152903 -117.21871) (xy 133.158922 -117.259608) (xy 133.277356 -117.259608) (xy 133.277813 -117.232237)
			(xy 133.285631 -117.178057) (xy 133.301121 -117.125554) (xy 133.323966 -117.075807) (xy 133.353693 -117.029841)
			(xy 133.371336 -117.00891) (xy 133.37159 -117.008656) (xy 133.377158 -117.001557) (xy 133.383416 -116.98465)
			(xy 133.383782 -116.975636) (xy 133.383782 -116.90858) (xy 133.383438 -116.899562) (xy 133.377182 -116.882645)
			(xy 133.37159 -116.87556) (xy 133.371336 -116.87556) (xy 133.371336 -116.875306) (xy 133.353703 -116.854367)
			(xy 133.323977 -116.808401) (xy 133.301131 -116.758655) (xy 133.285633 -116.706154) (xy 133.277804 -116.651976)
			(xy 133.277803 -116.597236) (xy 133.285631 -116.543058) (xy 133.301126 -116.490556) (xy 133.323971 -116.44081)
			(xy 133.353696 -116.394843) (xy 133.371336 -116.37391) (xy 133.37159 -116.373656) (xy 133.377158 -116.366557)
			(xy 133.383416 -116.34965) (xy 133.383782 -116.340636) (xy 133.383782 -116.27358) (xy 133.383438 -116.264562)
			(xy 133.377182 -116.247645) (xy 133.37159 -116.24056) (xy 133.371336 -116.24056) (xy 133.371336 -116.240306)
			(xy 133.353692 -116.219378) (xy 133.32398 -116.173405) (xy 133.301144 -116.123656) (xy 133.285654 -116.071154)
			(xy 133.277828 -116.016978) (xy 133.277356 -115.989608) (xy 133.277885 -115.962359) (xy 133.28564 -115.908414)
			(xy 133.300992 -115.856123) (xy 133.323629 -115.806548) (xy 133.353092 -115.760699) (xy 133.388778 -115.71951)
			(xy 133.429964 -115.683818) (xy 133.475809 -115.654351) (xy 133.525381 -115.631707) (xy 133.577671 -115.616349)
			(xy 133.631615 -115.608588) (xy 133.658864 -115.6081) (xy 133.686233 -115.608587) (xy 133.740412 -115.6164)
			(xy 133.792915 -115.631884) (xy 133.842662 -115.654721) (xy 133.88863 -115.684441) (xy 133.909562 -115.70208)
			(xy 133.909816 -115.702334) (xy 133.916891 -115.707937) (xy 133.933817 -115.714173) (xy 133.942836 -115.714526)
			(xy 134.009892 -115.714526) (xy 134.018908 -115.714159) (xy 134.035824 -115.707918) (xy 134.042912 -115.702334)
			(xy 134.042912 -115.70208) (xy 134.043166 -115.70208) (xy 134.064097 -115.68444) (xy 134.110071 -115.654729)
			(xy 134.159818 -115.631894) (xy 134.212319 -115.616403) (xy 134.266495 -115.608574) (xy 134.293864 -115.6081)
			(xy 134.321116 -115.608589) (xy 134.375067 -115.616341) (xy 134.427365 -115.631693) (xy 134.476945 -115.654332)
			(xy 134.522799 -115.683797) (xy 134.563992 -115.719488) (xy 134.599686 -115.760679) (xy 134.629155 -115.80653)
			(xy 134.651797 -115.856109) (xy 134.667153 -115.908406) (xy 134.674909 -115.962356) (xy 134.675372 -115.989608)
			(xy 134.674917 -116.016979) (xy 134.667098 -116.071159) (xy 134.651606 -116.123662) (xy 134.628762 -116.173409)
			(xy 134.599035 -116.219375) (xy 134.581392 -116.240306) (xy 134.581138 -116.24056) (xy 134.575555 -116.247649)
			(xy 134.569308 -116.264564) (xy 134.568946 -116.27358) (xy 134.568946 -116.340636) (xy 134.569276 -116.349656)
			(xy 134.575541 -116.366573) (xy 134.581138 -116.373656) (xy 134.581392 -116.373656) (xy 134.581392 -116.37391)
			(xy 134.59904 -116.394837) (xy 134.628763 -116.440806) (xy 134.651606 -116.490553) (xy 134.667101 -116.543056)
			(xy 134.674929 -116.597235) (xy 134.674928 -116.651977) (xy 134.667099 -116.706156) (xy 134.651602 -116.758658)
			(xy 134.628757 -116.808405) (xy 134.599032 -116.854373) (xy 134.581392 -116.875306) (xy 134.581138 -116.87556)
			(xy 134.575555 -116.882649) (xy 134.569308 -116.899564) (xy 134.568946 -116.90858) (xy 134.568946 -116.975636)
			(xy 134.569276 -116.984656) (xy 134.575541 -117.001573) (xy 134.581138 -117.008656) (xy 134.581392 -117.008656)
			(xy 134.581392 -117.00891) (xy 134.599048 -117.029828) (xy 134.628758 -117.075805) (xy 134.65159 -117.125556)
			(xy 134.667077 -117.17806) (xy 134.674901 -117.232238) (xy 134.675372 -117.259608) (xy 134.674952 -117.286863)
			(xy 134.667193 -117.340817) (xy 134.651834 -117.393118) (xy 134.629188 -117.4427) (xy 134.599716 -117.488555)
			(xy 134.564018 -117.529749) (xy 134.52282 -117.565442) (xy 134.476962 -117.594909) (xy 134.427377 -117.61755)
			(xy 134.375074 -117.632902) (xy 134.321119 -117.640655) (xy 134.293864 -117.641116) (xy 134.266492 -117.640692)
			(xy 134.21231 -117.632867) (xy 134.159806 -117.617369) (xy 134.11006 -117.594518) (xy 134.064095 -117.564783)
			(xy 134.043166 -117.547136) (xy 134.042912 -117.546882) (xy 134.035828 -117.541292) (xy 134.018909 -117.535048)
			(xy 134.009892 -117.53469) (xy 133.942836 -117.53469) (xy 133.933821 -117.535066) (xy 133.916904 -117.541301)
			(xy 133.909816 -117.546882) (xy 133.909816 -117.547136) (xy 133.909562 -117.547136) (xy 133.888622 -117.564765)
			(xy 133.842651 -117.594477) (xy 133.792905 -117.617314) (xy 133.740407 -117.632808) (xy 133.686233 -117.64064)
			(xy 133.658864 -117.641116) (xy 133.631612 -117.640656) (xy 133.577664 -117.632894) (xy 133.525369 -117.617535)
			(xy 133.475792 -117.59489) (xy 133.429943 -117.565421) (xy 133.388753 -117.529727) (xy 133.353062 -117.488535)
			(xy 133.323596 -117.442683) (xy 133.300955 -117.393104) (xy 133.2856 -117.340809) (xy 133.277842 -117.28686)
			(xy 133.277356 -117.259608) (xy 133.158922 -117.259608) (xy 133.161023 -117.273886) (xy 133.161532 -117.301772)
			(xy 133.161023 -117.329658) (xy 133.152903 -117.384834) (xy 133.136835 -117.438241) (xy 133.113163 -117.488738)
			(xy 133.08239 -117.535251) (xy 133.045173 -117.576788) (xy 133.002305 -117.612463) (xy 132.954699 -117.641517)
			(xy 132.90337 -117.663329) (xy 132.849413 -117.677435) (xy 132.793976 -117.683535) (xy 132.738242 -117.681498)
			(xy 132.683399 -117.671368) (xy 132.630615 -117.653361) (xy 132.581015 -117.62786) (xy 132.535657 -117.595409)
			(xy 132.495508 -117.5567) (xy 132.461422 -117.512557) (xy 132.434126 -117.463922) (xy 132.414203 -117.411831)
			(xy 132.402077 -117.357394) (xy 132.398006 -117.301772) (xy 130.758909 -117.301772) (xy 130.761745 -117.320858)
			(xy 130.762248 -117.349016) (xy 130.761762 -117.376267) (xy 130.754006 -117.430215) (xy 130.738651 -117.48251)
			(xy 130.716009 -117.532087) (xy 130.686543 -117.577937) (xy 130.650852 -117.619128) (xy 130.609661 -117.654819)
			(xy 130.563811 -117.684285) (xy 130.514234 -117.706927) (xy 130.461939 -117.722282) (xy 130.407991 -117.730038)
			(xy 130.353489 -117.730038) (xy 130.299541 -117.722282) (xy 130.247246 -117.706927) (xy 130.197669 -117.684285)
			(xy 130.151819 -117.654819) (xy 130.110628 -117.619128) (xy 130.074937 -117.577937) (xy 130.045471 -117.532087)
			(xy 130.022829 -117.48251) (xy 130.007474 -117.430215) (xy 129.999718 -117.376267) (xy 129.999232 -117.349016)
			(xy 129.999692 -117.32246) (xy 130.007058 -117.26986) (xy 130.02165 -117.218791) (xy 130.031998 -117.19433)
			(xy 130.036333 -117.182957) (xy 130.034994 -117.158688) (xy 130.029458 -117.147848) (xy 129.988056 -117.076728)
			(xy 129.981359 -117.066629) (xy 129.960923 -117.053657) (xy 129.94894 -117.051836) (xy 129.919467 -117.048452)
			(xy 129.861998 -117.033735) (xy 129.807501 -117.010297) (xy 129.757291 -116.978703) (xy 129.734564 -116.959634)
			(xy 129.73431 -116.95938) (xy 129.727226 -116.953789) (xy 129.710307 -116.947546) (xy 129.70129 -116.947188)
			(xy 129.634234 -116.947188) (xy 129.625219 -116.947564) (xy 129.608302 -116.953799) (xy 129.601214 -116.95938)
			(xy 129.601214 -116.959634) (xy 129.60096 -116.959634) (xy 129.58002 -116.977264) (xy 129.534049 -117.006976)
			(xy 129.484304 -117.029813) (xy 129.431805 -117.045306) (xy 129.377631 -117.053138) (xy 129.350262 -117.053614)
			(xy 129.32301 -117.053158) (xy 129.269062 -117.045396) (xy 129.216767 -117.030036) (xy 129.16719 -117.007391)
			(xy 129.12134 -116.977922) (xy 129.08015 -116.942227) (xy 129.044459 -116.901035) (xy 129.014993 -116.855182)
			(xy 128.992352 -116.805603) (xy 128.976997 -116.753307) (xy 128.96924 -116.699358) (xy 128.968754 -116.672106)
			(xy 118.402538 -116.672106) (xy 118.412106 -116.680397) (xy 118.447796 -116.721586) (xy 118.477261 -116.767435)
			(xy 118.499901 -116.817011) (xy 118.515256 -116.869304) (xy 118.523012 -116.92325) (xy 118.523012 -116.97775)
			(xy 118.515256 -117.031696) (xy 118.499901 -117.083989) (xy 118.477261 -117.133565) (xy 118.447796 -117.179414)
			(xy 118.412106 -117.220603) (xy 118.370917 -117.256293) (xy 118.325068 -117.285759) (xy 118.275493 -117.3084)
			(xy 118.2232 -117.323755) (xy 118.197667 -117.327426) (xy 125.787148 -117.327426) (xy 125.791219 -117.271804)
			(xy 125.803345 -117.217367) (xy 125.823268 -117.165276) (xy 125.850564 -117.116641) (xy 125.88465 -117.072498)
			(xy 125.924799 -117.033789) (xy 125.970157 -117.001338) (xy 126.019757 -116.975837) (xy 126.072541 -116.95783)
			(xy 126.127384 -116.9477) (xy 126.183118 -116.945663) (xy 126.238555 -116.951763) (xy 126.292512 -116.965869)
			(xy 126.343841 -116.987681) (xy 126.391447 -117.016735) (xy 126.434315 -117.05241) (xy 126.471532 -117.093947)
			(xy 126.502305 -117.14046) (xy 126.525977 -117.190957) (xy 126.528826 -117.200426) (xy 127.819148 -117.200426)
			(xy 127.823219 -117.144804) (xy 127.835345 -117.090367) (xy 127.855268 -117.038276) (xy 127.882564 -116.989641)
			(xy 127.91665 -116.945498) (xy 127.956799 -116.906789) (xy 128.002157 -116.874338) (xy 128.051757 -116.848837)
			(xy 128.104541 -116.83083) (xy 128.159384 -116.8207) (xy 128.215118 -116.818663) (xy 128.270555 -116.824763)
			(xy 128.324512 -116.838869) (xy 128.375841 -116.860681) (xy 128.423447 -116.889735) (xy 128.466315 -116.92541)
			(xy 128.503532 -116.966947) (xy 128.534305 -117.01346) (xy 128.557977 -117.063957) (xy 128.574045 -117.117364)
			(xy 128.582165 -117.17254) (xy 128.582674 -117.200426) (xy 128.582165 -117.228312) (xy 128.574045 -117.283488)
			(xy 128.557977 -117.336895) (xy 128.534305 -117.387392) (xy 128.503532 -117.433905) (xy 128.466315 -117.475442)
			(xy 128.423447 -117.511117) (xy 128.375841 -117.540171) (xy 128.324512 -117.561983) (xy 128.270555 -117.576089)
			(xy 128.215118 -117.582189) (xy 128.159384 -117.580152) (xy 128.104541 -117.570022) (xy 128.051757 -117.552015)
			(xy 128.002157 -117.526514) (xy 127.956799 -117.494063) (xy 127.91665 -117.455354) (xy 127.882564 -117.411211)
			(xy 127.855268 -117.362576) (xy 127.835345 -117.310485) (xy 127.823219 -117.256048) (xy 127.819148 -117.200426)
			(xy 126.528826 -117.200426) (xy 126.542045 -117.244364) (xy 126.550165 -117.29954) (xy 126.550674 -117.327426)
			(xy 126.550165 -117.355312) (xy 126.542045 -117.410488) (xy 126.525977 -117.463895) (xy 126.502305 -117.514392)
			(xy 126.471532 -117.560905) (xy 126.434315 -117.602442) (xy 126.391447 -117.638117) (xy 126.343841 -117.667171)
			(xy 126.292512 -117.688983) (xy 126.238555 -117.703089) (xy 126.183118 -117.709189) (xy 126.127384 -117.707152)
			(xy 126.072541 -117.697022) (xy 126.019757 -117.679015) (xy 125.970157 -117.653514) (xy 125.924799 -117.621063)
			(xy 125.88465 -117.582354) (xy 125.850564 -117.538211) (xy 125.823268 -117.489576) (xy 125.803345 -117.437485)
			(xy 125.791219 -117.383048) (xy 125.787148 -117.327426) (xy 118.197667 -117.327426) (xy 118.169254 -117.331511)
			(xy 118.142004 -117.331998) (xy 118.113087 -117.331477) (xy 118.055916 -117.322749) (xy 118.000717 -117.305491)
			(xy 117.948756 -117.2801) (xy 117.901222 -117.247157) (xy 117.859204 -117.207417) (xy 117.841014 -117.184932)
			(xy 117.833403 -117.17613) (xy 117.812505 -117.165946) (xy 117.800882 -117.165374) (xy 117.721126 -117.165374)
			(xy 117.709494 -117.165916) (xy 117.688582 -117.1761) (xy 117.680994 -117.184932) (xy 117.662814 -117.207425)
			(xy 117.620791 -117.247158) (xy 117.573254 -117.280095) (xy 117.52129 -117.305482) (xy 117.466091 -117.322736)
			(xy 117.408921 -117.331464) (xy 117.380004 -117.331998) (xy 117.35275 -117.331555) (xy 117.298797 -117.323799)
			(xy 117.246498 -117.308443) (xy 117.196916 -117.2858) (xy 117.151061 -117.256331) (xy 117.109866 -117.220636)
			(xy 117.074171 -117.179442) (xy 117.044702 -117.133588) (xy 117.022059 -117.084006) (xy 117.006702 -117.031707)
			(xy 116.998945 -116.977754) (xy 110.422205 -116.977754) (xy 110.455308 -117.014699) (xy 110.486081 -117.061212)
			(xy 110.509753 -117.111709) (xy 110.525821 -117.165116) (xy 110.533941 -117.220292) (xy 110.53445 -117.248178)
			(xy 110.533941 -117.276064) (xy 110.525821 -117.33124) (xy 110.509753 -117.384647) (xy 110.486081 -117.435144)
			(xy 110.455308 -117.481657) (xy 110.418091 -117.523194) (xy 110.375223 -117.558869) (xy 110.327617 -117.587923)
			(xy 110.276288 -117.609735) (xy 110.222331 -117.623841) (xy 110.166894 -117.629941) (xy 110.11116 -117.627904)
			(xy 110.056317 -117.617774) (xy 110.003533 -117.599767) (xy 109.953933 -117.574266) (xy 109.908575 -117.541815)
			(xy 109.868426 -117.503106) (xy 109.83434 -117.458963) (xy 109.807044 -117.410328) (xy 109.787121 -117.358237)
			(xy 109.774995 -117.3038) (xy 109.770924 -117.248178) (xy 109.51845 -117.248178) (xy 109.517941 -117.276064)
			(xy 109.509821 -117.33124) (xy 109.493753 -117.384647) (xy 109.470081 -117.435144) (xy 109.439308 -117.481657)
			(xy 109.402091 -117.523194) (xy 109.359223 -117.558869) (xy 109.311617 -117.587923) (xy 109.260288 -117.609735)
			(xy 109.206331 -117.623841) (xy 109.150894 -117.629941) (xy 109.09516 -117.627904) (xy 109.040317 -117.617774)
			(xy 108.987533 -117.599767) (xy 108.937933 -117.574266) (xy 108.892575 -117.541815) (xy 108.852426 -117.503106)
			(xy 108.81834 -117.458963) (xy 108.791044 -117.410328) (xy 108.771121 -117.358237) (xy 108.758995 -117.3038)
			(xy 108.754924 -117.248178) (xy 108.50245 -117.248178) (xy 108.501941 -117.276064) (xy 108.493821 -117.33124)
			(xy 108.477753 -117.384647) (xy 108.454081 -117.435144) (xy 108.423308 -117.481657) (xy 108.386091 -117.523194)
			(xy 108.343223 -117.558869) (xy 108.295617 -117.587923) (xy 108.244288 -117.609735) (xy 108.190331 -117.623841)
			(xy 108.134894 -117.629941) (xy 108.07916 -117.627904) (xy 108.024317 -117.617774) (xy 107.971533 -117.599767)
			(xy 107.921933 -117.574266) (xy 107.876575 -117.541815) (xy 107.836426 -117.503106) (xy 107.80234 -117.458963)
			(xy 107.775044 -117.410328) (xy 107.755121 -117.358237) (xy 107.742995 -117.3038) (xy 107.738924 -117.248178)
			(xy 93.713814 -117.248178) (xy 93.694395 -117.289602) (xy 93.663622 -117.336115) (xy 93.626405 -117.377652)
			(xy 93.583537 -117.413327) (xy 93.535931 -117.442381) (xy 93.484602 -117.464193) (xy 93.430645 -117.478299)
			(xy 93.375208 -117.484399) (xy 93.319474 -117.482362) (xy 93.264631 -117.472232) (xy 93.211847 -117.454225)
			(xy 93.162247 -117.428724) (xy 93.116889 -117.396273) (xy 93.07674 -117.357564) (xy 93.042654 -117.313421)
			(xy 93.015358 -117.264786) (xy 92.995435 -117.212695) (xy 92.983309 -117.158258) (xy 92.979238 -117.102636)
			(xy 92.163938 -117.102636) (xy 92.191339 -117.13426) (xy 92.220807 -117.180114) (xy 92.243449 -117.229696)
			(xy 92.258805 -117.281995) (xy 92.266562 -117.335947) (xy 92.266562 -117.390453) (xy 92.258805 -117.444405)
			(xy 92.243449 -117.496704) (xy 92.220807 -117.546286) (xy 92.191339 -117.59214) (xy 92.155646 -117.633334)
			(xy 92.114453 -117.66903) (xy 92.0686 -117.698499) (xy 92.019019 -117.721144) (xy 91.974969 -117.73408)
			(xy 116.39626 -117.73408) (xy 116.400331 -117.678458) (xy 116.412457 -117.624021) (xy 116.43238 -117.57193)
			(xy 116.459676 -117.523295) (xy 116.493762 -117.479152) (xy 116.533911 -117.440443) (xy 116.579269 -117.407992)
			(xy 116.628869 -117.382491) (xy 116.681653 -117.364484) (xy 116.736496 -117.354354) (xy 116.79223 -117.352317)
			(xy 116.847667 -117.358417) (xy 116.901624 -117.372523) (xy 116.952953 -117.394335) (xy 117.000559 -117.423389)
			(xy 117.043427 -117.459064) (xy 117.080644 -117.500601) (xy 117.111417 -117.547114) (xy 117.135089 -117.597611)
			(xy 117.151157 -117.651018) (xy 117.159277 -117.706194) (xy 117.159786 -117.73408) (xy 117.159277 -117.761966)
			(xy 117.151157 -117.817142) (xy 117.135089 -117.870549) (xy 117.111417 -117.921046) (xy 117.080644 -117.967559)
			(xy 117.043427 -118.009096) (xy 117.021849 -118.027053) (xy 117.690342 -118.027053) (xy 117.690342 -117.972547)
			(xy 117.698099 -117.918594) (xy 117.713455 -117.866295) (xy 117.736098 -117.816714) (xy 117.765566 -117.77086)
			(xy 117.80126 -117.729666) (xy 117.842453 -117.693971) (xy 117.888307 -117.664502) (xy 117.937888 -117.641858)
			(xy 117.990187 -117.626501) (xy 118.044139 -117.618742) (xy 118.071392 -117.618256) (xy 118.10031 -117.618759)
			(xy 118.157483 -117.627488) (xy 118.212683 -117.644748) (xy 118.264645 -117.670142) (xy 118.312178 -117.703089)
			(xy 118.354193 -117.742834) (xy 118.372382 -117.765322) (xy 118.380003 -117.774115) (xy 118.400893 -117.784306)
			(xy 118.412514 -117.78488) (xy 118.49227 -117.78488) (xy 118.503899 -117.784316) (xy 118.524809 -117.774146)
			(xy 118.532402 -117.765322) (xy 118.550597 -117.742842) (xy 118.592616 -117.703106) (xy 118.640149 -117.670166)
			(xy 118.69211 -117.644776) (xy 118.747307 -117.62752) (xy 118.804476 -117.618791) (xy 118.833392 -117.618256)
			(xy 118.860643 -117.618791) (xy 118.914589 -117.626546) (xy 118.966883 -117.6419) (xy 119.01646 -117.66454)
			(xy 119.062309 -117.694005) (xy 119.103499 -117.729695) (xy 119.13919 -117.770884) (xy 119.168656 -117.816733)
			(xy 119.191297 -117.866309) (xy 119.206652 -117.918603) (xy 119.214409 -117.972549) (xy 119.214409 -118.027051)
			(xy 119.206652 -118.080997) (xy 119.191297 -118.133291) (xy 119.168656 -118.182867) (xy 119.13919 -118.228716)
			(xy 119.103499 -118.269905) (xy 119.062309 -118.305595) (xy 119.01646 -118.33506) (xy 118.966883 -118.3577)
			(xy 118.914589 -118.373054) (xy 118.860643 -118.380809) (xy 118.833392 -118.381272) (xy 118.804477 -118.380698)
			(xy 118.747308 -118.371982) (xy 118.69211 -118.354736) (xy 118.640148 -118.329355) (xy 118.592612 -118.29642)
			(xy 118.550594 -118.256687) (xy 118.532402 -118.234206) (xy 118.524783 -118.225411) (xy 118.503891 -118.21522)
			(xy 118.49227 -118.214648) (xy 118.412514 -118.214648) (xy 118.400882 -118.215193) (xy 118.379972 -118.225376)
			(xy 118.372382 -118.234206) (xy 118.354203 -118.256699) (xy 118.31218 -118.296434) (xy 118.264643 -118.329371)
			(xy 118.212679 -118.354758) (xy 118.15748 -118.372012) (xy 118.100309 -118.380738) (xy 118.071392 -118.381272)
			(xy 118.044139 -118.380858) (xy 117.990187 -118.373099) (xy 117.937888 -118.357742) (xy 117.888307 -118.335098)
			(xy 117.842453 -118.305629) (xy 117.80126 -118.269934) (xy 117.765566 -118.22874) (xy 117.736098 -118.182886)
			(xy 117.713455 -118.133305) (xy 117.698099 -118.081006) (xy 117.690342 -118.027053) (xy 117.021849 -118.027053)
			(xy 117.000559 -118.044771) (xy 116.952953 -118.073825) (xy 116.901624 -118.095637) (xy 116.847667 -118.109743)
			(xy 116.79223 -118.115843) (xy 116.736496 -118.113806) (xy 116.681653 -118.103676) (xy 116.628869 -118.085669)
			(xy 116.579269 -118.060168) (xy 116.533911 -118.027717) (xy 116.493762 -117.989008) (xy 116.459676 -117.944865)
			(xy 116.43238 -117.89623) (xy 116.412457 -117.844139) (xy 116.400331 -117.789702) (xy 116.39626 -117.73408)
			(xy 91.974969 -117.73408) (xy 91.966721 -117.736502) (xy 91.912769 -117.744261) (xy 91.885516 -117.744748)
			(xy 91.856599 -117.744238) (xy 91.799426 -117.73551) (xy 91.744226 -117.718252) (xy 91.692264 -117.692859)
			(xy 91.644731 -117.659913) (xy 91.602715 -117.620169) (xy 91.584526 -117.597682) (xy 91.576901 -117.588893)
			(xy 91.556014 -117.5787) (xy 91.544394 -117.578124) (xy 91.464638 -117.578124) (xy 91.453002 -117.578633)
			(xy 91.432092 -117.588842) (xy 91.424506 -117.597682) (xy 91.406307 -117.620159) (xy 91.364289 -117.659895)
			(xy 91.316756 -117.692836) (xy 91.264797 -117.718225) (xy 91.2096 -117.735483) (xy 91.152432 -117.744213)
			(xy 91.123516 -117.744748) (xy 91.096265 -117.744206) (xy 91.042318 -117.736452) (xy 90.990024 -117.721099)
			(xy 90.940447 -117.698459) (xy 90.894597 -117.668995) (xy 90.853406 -117.633305) (xy 90.817715 -117.592116)
			(xy 90.788248 -117.546267) (xy 90.765607 -117.496691) (xy 90.750252 -117.444397) (xy 90.742495 -117.390451)
			(xy 81.534728 -117.390451) (xy 81.451196 -118.062502) (xy 81.450942 -118.066566) (xy 81.45018 -118.08079)
			(xy 81.449926 -118.09095) (xy 81.447386 -118.149624) (xy 81.447879 -118.157964) (xy 81.453572 -118.173659)
			(xy 81.458562 -118.180358) (xy 81.474818 -118.1989) (xy 81.493868 -118.22049) (xy 81.50143 -118.228119)
			(xy 81.52099 -118.236935) (xy 81.531714 -118.237508) (xy 81.538826 -118.237508) (xy 81.56853 -118.238404)
			(xy 81.627343 -118.246931) (xy 81.684559 -118.262994) (xy 81.739217 -118.286324) (xy 81.790397 -118.316528)
			(xy 81.837239 -118.353099) (xy 81.878958 -118.395423) (xy 81.91485 -118.442787) (xy 81.929179 -118.467886)
			(xy 97.482404 -118.467886) (xy 97.486475 -118.412264) (xy 97.498601 -118.357827) (xy 97.518524 -118.305736)
			(xy 97.54582 -118.257101) (xy 97.579906 -118.212958) (xy 97.620055 -118.174249) (xy 97.665413 -118.141798)
			(xy 97.715013 -118.116297) (xy 97.767797 -118.09829) (xy 97.82264 -118.08816) (xy 97.878374 -118.086123)
			(xy 97.933811 -118.092223) (xy 97.987768 -118.106329) (xy 98.039097 -118.128141) (xy 98.086703 -118.157195)
			(xy 98.129571 -118.19287) (xy 98.166788 -118.234407) (xy 98.197561 -118.28092) (xy 98.221233 -118.331417)
			(xy 98.237301 -118.384824) (xy 98.245421 -118.44) (xy 98.24593 -118.467886) (xy 98.245421 -118.495772)
			(xy 98.237301 -118.550948) (xy 98.221233 -118.604355) (xy 98.197561 -118.654852) (xy 98.166788 -118.701365)
			(xy 98.129571 -118.742902) (xy 98.108737 -118.76024) (xy 102.564436 -118.76024) (xy 102.568507 -118.704618)
			(xy 102.580633 -118.650181) (xy 102.600556 -118.59809) (xy 102.627852 -118.549455) (xy 102.661938 -118.505312)
			(xy 102.702087 -118.466603) (xy 102.747445 -118.434152) (xy 102.797045 -118.408651) (xy 102.849829 -118.390644)
			(xy 102.904672 -118.380514) (xy 102.960406 -118.378477) (xy 103.015843 -118.384577) (xy 103.0698 -118.398683)
			(xy 103.121129 -118.420495) (xy 103.168735 -118.449549) (xy 103.211603 -118.485224) (xy 103.24882 -118.526761)
			(xy 103.279593 -118.573274) (xy 103.303265 -118.623771) (xy 103.319333 -118.677178) (xy 103.327453 -118.732354)
			(xy 103.327962 -118.76024) (xy 103.327453 -118.788126) (xy 103.319333 -118.843302) (xy 103.303265 -118.896709)
			(xy 103.279593 -118.947206) (xy 103.24882 -118.993719) (xy 103.211603 -119.035256) (xy 103.168735 -119.070931)
			(xy 103.157994 -119.077486) (xy 114.208558 -119.077486) (xy 114.212629 -119.021864) (xy 114.224755 -118.967427)
			(xy 114.244678 -118.915336) (xy 114.271974 -118.866701) (xy 114.30606 -118.822558) (xy 114.346209 -118.783849)
			(xy 114.391567 -118.751398) (xy 114.441167 -118.725897) (xy 114.493951 -118.70789) (xy 114.548794 -118.69776)
			(xy 114.604528 -118.695723) (xy 114.659965 -118.701823) (xy 114.713922 -118.715929) (xy 114.765251 -118.737741)
			(xy 114.812857 -118.766795) (xy 114.855725 -118.80247) (xy 114.892942 -118.844007) (xy 114.923715 -118.89052)
			(xy 114.947387 -118.941017) (xy 114.963455 -118.994424) (xy 114.971193 -119.047006) (xy 116.309138 -119.047006)
			(xy 116.313209 -118.991384) (xy 116.325335 -118.936947) (xy 116.345258 -118.884856) (xy 116.372554 -118.836221)
			(xy 116.40664 -118.792078) (xy 116.446789 -118.753369) (xy 116.492147 -118.720918) (xy 116.541747 -118.695417)
			(xy 116.594531 -118.67741) (xy 116.649374 -118.66728) (xy 116.705108 -118.665243) (xy 116.760545 -118.671343)
			(xy 116.814502 -118.685449) (xy 116.865831 -118.707261) (xy 116.913437 -118.736315) (xy 116.956305 -118.77199)
			(xy 116.993522 -118.813527) (xy 117.024295 -118.86004) (xy 117.047967 -118.910537) (xy 117.064035 -118.963944)
			(xy 117.072155 -119.01912) (xy 117.072664 -119.047006) (xy 117.072155 -119.074892) (xy 117.064035 -119.130068)
			(xy 117.047967 -119.183475) (xy 117.024295 -119.233972) (xy 116.993522 -119.280485) (xy 116.956305 -119.322022)
			(xy 116.913437 -119.357697) (xy 116.865831 -119.386751) (xy 116.814502 -119.408563) (xy 116.760545 -119.422669)
			(xy 116.705108 -119.428769) (xy 116.649374 -119.426732) (xy 116.594531 -119.416602) (xy 116.541747 -119.398595)
			(xy 116.492147 -119.373094) (xy 116.446789 -119.340643) (xy 116.40664 -119.301934) (xy 116.372554 -119.257791)
			(xy 116.345258 -119.209156) (xy 116.325335 -119.157065) (xy 116.313209 -119.102628) (xy 116.309138 -119.047006)
			(xy 114.971193 -119.047006) (xy 114.971575 -119.0496) (xy 114.972084 -119.077486) (xy 114.971575 -119.105372)
			(xy 114.963455 -119.160548) (xy 114.947387 -119.213955) (xy 114.923715 -119.264452) (xy 114.892942 -119.310965)
			(xy 114.855725 -119.352502) (xy 114.812857 -119.388177) (xy 114.765251 -119.417231) (xy 114.713922 -119.439043)
			(xy 114.659965 -119.453149) (xy 114.604528 -119.459249) (xy 114.548794 -119.457212) (xy 114.493951 -119.447082)
			(xy 114.441167 -119.429075) (xy 114.391567 -119.403574) (xy 114.346209 -119.371123) (xy 114.30606 -119.332414)
			(xy 114.271974 -119.288271) (xy 114.244678 -119.239636) (xy 114.224755 -119.187545) (xy 114.212629 -119.133108)
			(xy 114.208558 -119.077486) (xy 103.157994 -119.077486) (xy 103.121129 -119.099985) (xy 103.0698 -119.121797)
			(xy 103.015843 -119.135903) (xy 102.960406 -119.142003) (xy 102.904672 -119.139966) (xy 102.849829 -119.129836)
			(xy 102.797045 -119.111829) (xy 102.747445 -119.086328) (xy 102.702087 -119.053877) (xy 102.661938 -119.015168)
			(xy 102.627852 -118.971025) (xy 102.600556 -118.92239) (xy 102.580633 -118.870299) (xy 102.568507 -118.815862)
			(xy 102.564436 -118.76024) (xy 98.108737 -118.76024) (xy 98.086703 -118.778577) (xy 98.039097 -118.807631)
			(xy 97.987768 -118.829443) (xy 97.933811 -118.843549) (xy 97.878374 -118.849649) (xy 97.82264 -118.847612)
			(xy 97.767797 -118.837482) (xy 97.715013 -118.819475) (xy 97.665413 -118.793974) (xy 97.620055 -118.761523)
			(xy 97.579906 -118.722814) (xy 97.54582 -118.678671) (xy 97.518524 -118.630036) (xy 97.498601 -118.577945)
			(xy 97.486475 -118.523508) (xy 97.482404 -118.467886) (xy 81.929179 -118.467886) (xy 81.944314 -118.494397)
			(xy 81.966854 -118.549385) (xy 81.982092 -118.606826) (xy 81.989771 -118.665756) (xy 81.990184 -118.69547)
			(xy 81.990184 -119.407554) (xy 94.499632 -119.407554) (xy 94.499632 -119.353046) (xy 94.507389 -119.299093)
			(xy 94.522745 -119.246794) (xy 94.545388 -119.197211) (xy 94.574856 -119.151356) (xy 94.61055 -119.110162)
			(xy 94.651743 -119.074466) (xy 94.697597 -119.044995) (xy 94.747179 -119.022351) (xy 94.799478 -119.006992)
			(xy 94.85343 -118.999233) (xy 94.880684 -118.998746) (xy 94.908054 -118.99921) (xy 94.962234 -119.007027)
			(xy 95.014738 -119.022516) (xy 95.064484 -119.045358) (xy 95.110451 -119.075084) (xy 95.131382 -119.092726)
			(xy 95.131636 -119.09298) (xy 95.13873 -119.098555) (xy 95.155641 -119.104807) (xy 95.164656 -119.105172)
			(xy 95.231712 -119.105172) (xy 95.24073 -119.104827) (xy 95.257647 -119.098572) (xy 95.264732 -119.09298)
			(xy 95.264732 -119.092726) (xy 95.264986 -119.092726) (xy 95.285916 -119.075084) (xy 95.331889 -119.045372)
			(xy 95.381637 -119.022536) (xy 95.434138 -119.007046) (xy 95.488315 -118.999219) (xy 95.515684 -118.998746)
			(xy 95.542934 -118.9993) (xy 95.59688 -119.007054) (xy 95.649174 -119.022407) (xy 95.69875 -119.045046)
			(xy 95.7446 -119.07451) (xy 95.785789 -119.110199) (xy 95.82148 -119.151387) (xy 95.850946 -119.197236)
			(xy 95.873587 -119.246811) (xy 95.888942 -119.299104) (xy 95.896699 -119.35305) (xy 95.896699 -119.40755)
			(xy 95.888942 -119.461496) (xy 95.884381 -119.477028) (xy 99.60813 -119.477028) (xy 99.612201 -119.421406)
			(xy 99.624327 -119.366969) (xy 99.64425 -119.314878) (xy 99.671546 -119.266243) (xy 99.705632 -119.2221)
			(xy 99.745781 -119.183391) (xy 99.791139 -119.15094) (xy 99.840739 -119.125439) (xy 99.893523 -119.107432)
			(xy 99.948366 -119.097302) (xy 100.0041 -119.095265) (xy 100.059537 -119.101365) (xy 100.113494 -119.115471)
			(xy 100.164823 -119.137283) (xy 100.212429 -119.166337) (xy 100.255297 -119.202012) (xy 100.292514 -119.243549)
			(xy 100.323287 -119.290062) (xy 100.346959 -119.340559) (xy 100.363027 -119.393966) (xy 100.371147 -119.449142)
			(xy 100.371656 -119.477028) (xy 100.371147 -119.504914) (xy 100.363027 -119.56009) (xy 100.346959 -119.613497)
			(xy 100.323287 -119.663994) (xy 100.292514 -119.710507) (xy 100.255297 -119.752044) (xy 100.226222 -119.77624)
			(xy 100.535992 -119.77624) (xy 100.540063 -119.720618) (xy 100.552189 -119.666181) (xy 100.572112 -119.61409)
			(xy 100.599408 -119.565455) (xy 100.633494 -119.521312) (xy 100.673643 -119.482603) (xy 100.719001 -119.450152)
			(xy 100.768601 -119.424651) (xy 100.821385 -119.406644) (xy 100.876228 -119.396514) (xy 100.931962 -119.394477)
			(xy 100.987399 -119.400577) (xy 101.041356 -119.414683) (xy 101.092685 -119.436495) (xy 101.140291 -119.465549)
			(xy 101.183159 -119.501224) (xy 101.220376 -119.542761) (xy 101.251149 -119.589274) (xy 101.274821 -119.639771)
			(xy 101.290889 -119.693178) (xy 101.294665 -119.718836) (xy 107.536486 -119.718836) (xy 107.540557 -119.663214)
			(xy 107.552683 -119.608777) (xy 107.572606 -119.556686) (xy 107.599902 -119.508051) (xy 107.633988 -119.463908)
			(xy 107.674137 -119.425199) (xy 107.719495 -119.392748) (xy 107.769095 -119.367247) (xy 107.821879 -119.34924)
			(xy 107.876722 -119.33911) (xy 107.932456 -119.337073) (xy 107.987893 -119.343173) (xy 108.04185 -119.357279)
			(xy 108.093179 -119.379091) (xy 108.140785 -119.408145) (xy 108.183653 -119.44382) (xy 108.22087 -119.485357)
			(xy 108.236701 -119.509286) (xy 119.927114 -119.509286) (xy 119.931185 -119.453664) (xy 119.943311 -119.399227)
			(xy 119.963234 -119.347136) (xy 119.99053 -119.298501) (xy 120.024616 -119.254358) (xy 120.064765 -119.215649)
			(xy 120.110123 -119.183198) (xy 120.159723 -119.157697) (xy 120.212507 -119.13969) (xy 120.26735 -119.12956)
			(xy 120.323084 -119.127523) (xy 120.378521 -119.133623) (xy 120.432478 -119.147729) (xy 120.483807 -119.169541)
			(xy 120.531413 -119.198595) (xy 120.574281 -119.23427) (xy 120.611498 -119.275807) (xy 120.642271 -119.32232)
			(xy 120.665943 -119.372817) (xy 120.682011 -119.426224) (xy 120.690131 -119.4814) (xy 120.690223 -119.486426)
			(xy 125.787148 -119.486426) (xy 125.791219 -119.430804) (xy 125.803345 -119.376367) (xy 125.823268 -119.324276)
			(xy 125.850564 -119.275641) (xy 125.88465 -119.231498) (xy 125.924799 -119.192789) (xy 125.970157 -119.160338)
			(xy 126.019757 -119.134837) (xy 126.072541 -119.11683) (xy 126.127384 -119.1067) (xy 126.183118 -119.104663)
			(xy 126.238555 -119.110763) (xy 126.292512 -119.124869) (xy 126.343841 -119.146681) (xy 126.391447 -119.175735)
			(xy 126.434315 -119.21141) (xy 126.471532 -119.252947) (xy 126.502305 -119.29946) (xy 126.525977 -119.349957)
			(xy 126.527756 -119.35587) (xy 126.803148 -119.35587) (xy 126.807219 -119.300248) (xy 126.819345 -119.245811)
			(xy 126.839268 -119.19372) (xy 126.866564 -119.145085) (xy 126.90065 -119.100942) (xy 126.940799 -119.062233)
			(xy 126.986157 -119.029782) (xy 127.035757 -119.004281) (xy 127.088541 -118.986274) (xy 127.143384 -118.976144)
			(xy 127.199118 -118.974107) (xy 127.254555 -118.980207) (xy 127.308512 -118.994313) (xy 127.359841 -119.016125)
			(xy 127.407447 -119.045179) (xy 127.450315 -119.080854) (xy 127.487532 -119.122391) (xy 127.518305 -119.168904)
			(xy 127.541977 -119.219401) (xy 127.558045 -119.272808) (xy 127.566165 -119.327984) (xy 127.566674 -119.35587)
			(xy 127.819148 -119.35587) (xy 127.823219 -119.300248) (xy 127.835345 -119.245811) (xy 127.855268 -119.19372)
			(xy 127.882564 -119.145085) (xy 127.91665 -119.100942) (xy 127.956799 -119.062233) (xy 128.002157 -119.029782)
			(xy 128.051757 -119.004281) (xy 128.104541 -118.986274) (xy 128.159384 -118.976144) (xy 128.215118 -118.974107)
			(xy 128.270555 -118.980207) (xy 128.324512 -118.994313) (xy 128.375841 -119.016125) (xy 128.423447 -119.045179)
			(xy 128.466315 -119.080854) (xy 128.503532 -119.122391) (xy 128.534305 -119.168904) (xy 128.557977 -119.219401)
			(xy 128.574045 -119.272808) (xy 128.582165 -119.327984) (xy 128.582674 -119.35587) (xy 128.582165 -119.383756)
			(xy 128.581036 -119.39143) (xy 131.014722 -119.39143) (xy 131.018793 -119.335808) (xy 131.030919 -119.281371)
			(xy 131.050842 -119.22928) (xy 131.078138 -119.180645) (xy 131.112224 -119.136502) (xy 131.152373 -119.097793)
			(xy 131.197731 -119.065342) (xy 131.247331 -119.039841) (xy 131.300115 -119.021834) (xy 131.354958 -119.011704)
			(xy 131.410692 -119.009667) (xy 131.466129 -119.015767) (xy 131.520086 -119.029873) (xy 131.571415 -119.051685)
			(xy 131.619021 -119.080739) (xy 131.661889 -119.116414) (xy 131.699106 -119.157951) (xy 131.729879 -119.204464)
			(xy 131.753551 -119.254961) (xy 131.769619 -119.308368) (xy 131.777739 -119.363544) (xy 131.778248 -119.39143)
			(xy 131.777739 -119.419316) (xy 131.769619 -119.474492) (xy 131.753551 -119.527899) (xy 131.729879 -119.578396)
			(xy 131.699106 -119.624909) (xy 131.661889 -119.666446) (xy 131.619021 -119.702121) (xy 131.571415 -119.731175)
			(xy 131.520086 -119.752987) (xy 131.466129 -119.767093) (xy 131.410692 -119.773193) (xy 131.354958 -119.771156)
			(xy 131.300115 -119.761026) (xy 131.247331 -119.743019) (xy 131.197731 -119.717518) (xy 131.152373 -119.685067)
			(xy 131.112224 -119.646358) (xy 131.078138 -119.602215) (xy 131.050842 -119.55358) (xy 131.030919 -119.501489)
			(xy 131.018793 -119.447052) (xy 131.014722 -119.39143) (xy 128.581036 -119.39143) (xy 128.574045 -119.438932)
			(xy 128.557977 -119.492339) (xy 128.534305 -119.542836) (xy 128.503532 -119.589349) (xy 128.466315 -119.630886)
			(xy 128.423447 -119.666561) (xy 128.375841 -119.695615) (xy 128.324512 -119.717427) (xy 128.270555 -119.731533)
			(xy 128.215118 -119.737633) (xy 128.159384 -119.735596) (xy 128.104541 -119.725466) (xy 128.051757 -119.707459)
			(xy 128.002157 -119.681958) (xy 127.956799 -119.649507) (xy 127.91665 -119.610798) (xy 127.882564 -119.566655)
			(xy 127.855268 -119.51802) (xy 127.835345 -119.465929) (xy 127.823219 -119.411492) (xy 127.819148 -119.35587)
			(xy 127.566674 -119.35587) (xy 127.566165 -119.383756) (xy 127.558045 -119.438932) (xy 127.541977 -119.492339)
			(xy 127.518305 -119.542836) (xy 127.487532 -119.589349) (xy 127.450315 -119.630886) (xy 127.407447 -119.666561)
			(xy 127.359841 -119.695615) (xy 127.308512 -119.717427) (xy 127.254555 -119.731533) (xy 127.199118 -119.737633)
			(xy 127.143384 -119.735596) (xy 127.088541 -119.725466) (xy 127.035757 -119.707459) (xy 126.986157 -119.681958)
			(xy 126.940799 -119.649507) (xy 126.90065 -119.610798) (xy 126.866564 -119.566655) (xy 126.839268 -119.51802)
			(xy 126.819345 -119.465929) (xy 126.807219 -119.411492) (xy 126.803148 -119.35587) (xy 126.527756 -119.35587)
			(xy 126.542045 -119.403364) (xy 126.550165 -119.45854) (xy 126.550674 -119.486426) (xy 126.550165 -119.514312)
			(xy 126.542045 -119.569488) (xy 126.525977 -119.622895) (xy 126.502305 -119.673392) (xy 126.471532 -119.719905)
			(xy 126.434315 -119.761442) (xy 126.391447 -119.797117) (xy 126.343841 -119.826171) (xy 126.292512 -119.847983)
			(xy 126.238555 -119.862089) (xy 126.183118 -119.868189) (xy 126.127384 -119.866152) (xy 126.072541 -119.856022)
			(xy 126.019757 -119.838015) (xy 125.970157 -119.812514) (xy 125.924799 -119.780063) (xy 125.88465 -119.741354)
			(xy 125.850564 -119.697211) (xy 125.823268 -119.648576) (xy 125.803345 -119.596485) (xy 125.791219 -119.542048)
			(xy 125.787148 -119.486426) (xy 120.690223 -119.486426) (xy 120.69064 -119.509286) (xy 120.690131 -119.537172)
			(xy 120.682011 -119.592348) (xy 120.665943 -119.645755) (xy 120.642271 -119.696252) (xy 120.611498 -119.742765)
			(xy 120.574281 -119.784302) (xy 120.531413 -119.819977) (xy 120.483807 -119.849031) (xy 120.432478 -119.870843)
			(xy 120.378521 -119.884949) (xy 120.323084 -119.891049) (xy 120.26735 -119.889012) (xy 120.212507 -119.878882)
			(xy 120.159723 -119.860875) (xy 120.110123 -119.835374) (xy 120.064765 -119.802923) (xy 120.024616 -119.764214)
			(xy 119.99053 -119.720071) (xy 119.963234 -119.671436) (xy 119.943311 -119.619345) (xy 119.931185 -119.564908)
			(xy 119.927114 -119.509286) (xy 108.236701 -119.509286) (xy 108.251643 -119.53187) (xy 108.275315 -119.582367)
			(xy 108.291383 -119.635774) (xy 108.299503 -119.69095) (xy 108.300012 -119.718836) (xy 108.299503 -119.746722)
			(xy 108.291383 -119.801898) (xy 108.275315 -119.855305) (xy 108.251643 -119.905802) (xy 108.22087 -119.952315)
			(xy 108.183653 -119.993852) (xy 108.140785 -120.029527) (xy 108.093179 -120.058581) (xy 108.04185 -120.080393)
			(xy 107.987893 -120.094499) (xy 107.932456 -120.100599) (xy 107.876722 -120.098562) (xy 107.821879 -120.088432)
			(xy 107.769095 -120.070425) (xy 107.719495 -120.044924) (xy 107.674137 -120.012473) (xy 107.633988 -119.973764)
			(xy 107.599902 -119.929621) (xy 107.572606 -119.880986) (xy 107.552683 -119.828895) (xy 107.540557 -119.774458)
			(xy 107.536486 -119.718836) (xy 101.294665 -119.718836) (xy 101.299009 -119.748354) (xy 101.299518 -119.77624)
			(xy 101.299009 -119.804126) (xy 101.290889 -119.859302) (xy 101.274821 -119.912709) (xy 101.251149 -119.963206)
			(xy 101.220376 -120.009719) (xy 101.183159 -120.051256) (xy 101.140291 -120.086931) (xy 101.092685 -120.115985)
			(xy 101.041356 -120.137797) (xy 100.987399 -120.151903) (xy 100.931962 -120.158003) (xy 100.876228 -120.155966)
			(xy 100.821385 -120.145836) (xy 100.768601 -120.127829) (xy 100.719001 -120.102328) (xy 100.673643 -120.069877)
			(xy 100.633494 -120.031168) (xy 100.599408 -119.987025) (xy 100.572112 -119.93839) (xy 100.552189 -119.886299)
			(xy 100.540063 -119.831862) (xy 100.535992 -119.77624) (xy 100.226222 -119.77624) (xy 100.212429 -119.787719)
			(xy 100.164823 -119.816773) (xy 100.113494 -119.838585) (xy 100.059537 -119.852691) (xy 100.0041 -119.858791)
			(xy 99.948366 -119.856754) (xy 99.893523 -119.846624) (xy 99.840739 -119.828617) (xy 99.791139 -119.803116)
			(xy 99.745781 -119.770665) (xy 99.705632 -119.731956) (xy 99.671546 -119.687813) (xy 99.64425 -119.639178)
			(xy 99.624327 -119.587087) (xy 99.612201 -119.53265) (xy 99.60813 -119.477028) (xy 95.884381 -119.477028)
			(xy 95.873587 -119.513789) (xy 95.850946 -119.563364) (xy 95.82148 -119.609213) (xy 95.785789 -119.650401)
			(xy 95.7446 -119.68609) (xy 95.69875 -119.715554) (xy 95.649174 -119.738193) (xy 95.59688 -119.753546)
			(xy 95.542934 -119.7613) (xy 95.515684 -119.761762) (xy 95.488313 -119.761315) (xy 95.434133 -119.753494)
			(xy 95.381629 -119.738001) (xy 95.331882 -119.715155) (xy 95.285917 -119.685426) (xy 95.264986 -119.667782)
			(xy 95.264732 -119.667528) (xy 95.257647 -119.66194) (xy 95.240729 -119.655696) (xy 95.231712 -119.655336)
			(xy 95.164656 -119.655336) (xy 95.155641 -119.655712) (xy 95.138723 -119.661946) (xy 95.131636 -119.667528)
			(xy 95.131636 -119.667782) (xy 95.131382 -119.667782) (xy 95.110428 -119.685393) (xy 95.064461 -119.71511)
			(xy 95.014719 -119.737952) (xy 94.962224 -119.753449) (xy 94.908052 -119.761284) (xy 94.880684 -119.761762)
			(xy 94.85343 -119.761367) (xy 94.799478 -119.753608) (xy 94.747179 -119.738249) (xy 94.697597 -119.715605)
			(xy 94.651743 -119.686134) (xy 94.61055 -119.650438) (xy 94.574856 -119.609244) (xy 94.545388 -119.563389)
			(xy 94.522745 -119.513806) (xy 94.507389 -119.461507) (xy 94.499632 -119.407554) (xy 81.990184 -119.407554)
			(xy 81.990184 -119.55907) (xy 81.989717 -119.589057) (xy 81.981892 -119.64852) (xy 81.966373 -119.706452)
			(xy 81.943425 -119.761863) (xy 81.913441 -119.813805) (xy 81.876933 -119.861388) (xy 81.845245 -119.89308)
			(xy 97.569018 -119.89308) (xy 97.573089 -119.837458) (xy 97.585215 -119.783021) (xy 97.605138 -119.73093)
			(xy 97.632434 -119.682295) (xy 97.66652 -119.638152) (xy 97.706669 -119.599443) (xy 97.752027 -119.566992)
			(xy 97.801627 -119.541491) (xy 97.854411 -119.523484) (xy 97.909254 -119.513354) (xy 97.964988 -119.511317)
			(xy 98.020425 -119.517417) (xy 98.074382 -119.531523) (xy 98.125711 -119.553335) (xy 98.173317 -119.582389)
			(xy 98.216185 -119.618064) (xy 98.253402 -119.659601) (xy 98.284175 -119.706114) (xy 98.307847 -119.756611)
			(xy 98.323915 -119.810018) (xy 98.332035 -119.865194) (xy 98.332544 -119.89308) (xy 98.332035 -119.920966)
			(xy 98.323915 -119.976142) (xy 98.307847 -120.029549) (xy 98.284175 -120.080046) (xy 98.253402 -120.126559)
			(xy 98.216185 -120.168096) (xy 98.173317 -120.203771) (xy 98.125711 -120.232825) (xy 98.074382 -120.254637)
			(xy 98.020425 -120.268743) (xy 97.964988 -120.274843) (xy 97.909254 -120.272806) (xy 97.854411 -120.262676)
			(xy 97.801627 -120.244669) (xy 97.752027 -120.219168) (xy 97.706669 -120.186717) (xy 97.66652 -120.148008)
			(xy 97.632434 -120.103865) (xy 97.605138 -120.05523) (xy 97.585215 -120.003139) (xy 97.573089 -119.948702)
			(xy 97.569018 -119.89308) (xy 81.845245 -119.89308) (xy 81.834527 -119.903799) (xy 81.786948 -119.940312)
			(xy 81.73501 -119.970302) (xy 81.679601 -119.993257) (xy 81.621671 -120.008782) (xy 81.562209 -120.016613)
			(xy 81.532222 -120.017032) (xy 81.492344 -120.015254) (xy 81.477358 -120.01373) (xy 81.46669 -120.01246)
			(xy 81.457038 -120.015254) (xy 81.452048 -120.016865) (xy 81.442835 -120.02187) (xy 81.43875 -120.02516)
			(xy 81.380076 -120.07469) (xy 81.373931 -120.080752) (xy 81.36575 -120.09594) (xy 81.364074 -120.104408)
			(xy 81.310188 -121.365772) (xy 83.716368 -121.365772) (xy 83.716368 -120.502172) (xy 83.716858 -120.472188)
			(xy 83.724686 -120.412732) (xy 83.740207 -120.354807) (xy 83.763156 -120.299403) (xy 83.79314 -120.247469)
			(xy 83.829646 -120.199893) (xy 83.872051 -120.157488) (xy 83.919627 -120.120982) (xy 83.971561 -120.090998)
			(xy 84.026965 -120.068049) (xy 84.08489 -120.052528) (xy 84.144346 -120.0447) (xy 84.204314 -120.0447)
			(xy 84.26377 -120.052528) (xy 84.321695 -120.068049) (xy 84.377099 -120.090998) (xy 84.429033 -120.120982)
			(xy 84.476609 -120.157488) (xy 84.519014 -120.199893) (xy 84.55552 -120.247469) (xy 84.585504 -120.299403)
			(xy 84.608453 -120.354807) (xy 84.623974 -120.412732) (xy 84.631802 -120.472188) (xy 84.632292 -120.502172)
			(xy 84.632292 -121.365772) (xy 84.631802 -121.395756) (xy 84.623974 -121.455212) (xy 84.608453 -121.513137)
			(xy 84.585504 -121.568541) (xy 84.55552 -121.620475) (xy 84.519014 -121.668051) (xy 84.476609 -121.710456)
			(xy 84.429033 -121.746962) (xy 84.377099 -121.776946) (xy 84.321695 -121.799895) (xy 84.26377 -121.815416)
			(xy 84.204314 -121.823244) (xy 84.144346 -121.823244) (xy 84.08489 -121.815416) (xy 84.026965 -121.799895)
			(xy 83.971561 -121.776946) (xy 83.919627 -121.746962) (xy 83.872051 -121.710456) (xy 83.829646 -121.668051)
			(xy 83.79314 -121.620475) (xy 83.763156 -121.568541) (xy 83.740207 -121.513137) (xy 83.724686 -121.455212)
			(xy 83.716858 -121.395756) (xy 83.716368 -121.365772) (xy 81.310188 -121.365772) (xy 81.293716 -121.751344)
			(xy 81.294408 -121.762541) (xy 81.304164 -121.782711) (xy 81.312512 -121.790206) (xy 81.369154 -121.836434)
			(xy 81.37652 -121.842276) (xy 81.383309 -121.847212) (xy 81.399125 -121.852799) (xy 81.407508 -121.853198)
			(xy 81.419954 -121.851674) (xy 81.422748 -121.850912) (xy 81.423256 -121.850912) (xy 81.424018 -121.850658)
			(xy 81.428336 -121.849642) (xy 81.42859 -121.849642) (xy 81.434178 -121.848372) (xy 81.449019 -121.845221)
			(xy 81.479016 -121.840644) (xy 81.494122 -121.839228) (xy 81.532222 -121.837704) (xy 81.562206 -121.838195)
			(xy 81.621661 -121.846025) (xy 81.679586 -121.861548) (xy 81.734989 -121.884498) (xy 81.786923 -121.914482)
			(xy 81.834499 -121.950988) (xy 81.876904 -121.993392) (xy 81.913411 -122.040967) (xy 81.943397 -122.0929)
			(xy 81.966348 -122.148303) (xy 81.978069 -122.192034) (xy 89.450672 -122.192034) (xy 89.45114 -122.164664)
			(xy 89.458955 -122.110484) (xy 89.474443 -122.05798) (xy 89.497284 -122.008233) (xy 89.52701 -121.962267)
			(xy 89.544652 -121.941336) (xy 89.544906 -121.941082) (xy 89.550507 -121.934005) (xy 89.556745 -121.917081)
			(xy 89.557098 -121.908062) (xy 89.557098 -121.841006) (xy 89.556739 -121.831989) (xy 89.550493 -121.815072)
			(xy 89.544906 -121.807986) (xy 89.544652 -121.807986) (xy 89.544652 -121.807732) (xy 89.527044 -121.786773)
			(xy 89.497316 -121.74081) (xy 89.474467 -121.691068) (xy 89.458967 -121.63857) (xy 89.451134 -121.584395)
			(xy 89.451131 -121.529656) (xy 89.458956 -121.47548) (xy 89.474449 -121.42298) (xy 89.497291 -121.373235)
			(xy 89.527013 -121.327268) (xy 89.544652 -121.306336) (xy 89.544906 -121.306082) (xy 89.550507 -121.299005)
			(xy 89.556745 -121.282081) (xy 89.557098 -121.273062) (xy 89.557098 -121.206006) (xy 89.556739 -121.196989)
			(xy 89.550493 -121.180072) (xy 89.544906 -121.172986) (xy 89.544652 -121.172986) (xy 89.544652 -121.172732)
			(xy 89.527044 -121.151773) (xy 89.497316 -121.10581) (xy 89.474467 -121.056068) (xy 89.458967 -121.00357)
			(xy 89.451134 -120.949395) (xy 89.451131 -120.894656) (xy 89.458956 -120.84048) (xy 89.474449 -120.78798)
			(xy 89.497291 -120.738235) (xy 89.527013 -120.692268) (xy 89.544652 -120.671336) (xy 89.544906 -120.671082)
			(xy 89.550507 -120.664005) (xy 89.556745 -120.647081) (xy 89.557098 -120.638062) (xy 89.557098 -120.571006)
			(xy 89.556739 -120.561989) (xy 89.550493 -120.545072) (xy 89.544906 -120.537986) (xy 89.544652 -120.537986)
			(xy 89.544652 -120.537732) (xy 89.527023 -120.516792) (xy 89.497307 -120.470822) (xy 89.474469 -120.421077)
			(xy 89.458976 -120.368578) (xy 89.451146 -120.314403) (xy 89.450672 -120.287034) (xy 89.451158 -120.259783)
			(xy 89.458914 -120.205835) (xy 89.474269 -120.15354) (xy 89.496911 -120.103963) (xy 89.526377 -120.058113)
			(xy 89.562068 -120.016922) (xy 89.603259 -119.981231) (xy 89.649109 -119.951765) (xy 89.698686 -119.929123)
			(xy 89.750981 -119.913768) (xy 89.804929 -119.906012) (xy 89.859431 -119.906012) (xy 89.913379 -119.913768)
			(xy 89.965674 -119.929123) (xy 90.015251 -119.951765) (xy 90.061101 -119.981231) (xy 90.102292 -120.016922)
			(xy 90.137983 -120.058113) (xy 90.167449 -120.103963) (xy 90.190091 -120.15354) (xy 90.205446 -120.205835)
			(xy 90.213202 -120.259783) (xy 90.213688 -120.287034) (xy 90.213245 -120.314405) (xy 90.205422 -120.368585)
			(xy 90.189928 -120.421089) (xy 90.167081 -120.470835) (xy 90.152727 -120.493028) (xy 99.604066 -120.493028)
			(xy 99.608137 -120.437406) (xy 99.620263 -120.382969) (xy 99.640186 -120.330878) (xy 99.667482 -120.282243)
			(xy 99.701568 -120.2381) (xy 99.741717 -120.199391) (xy 99.787075 -120.16694) (xy 99.836675 -120.141439)
			(xy 99.889459 -120.123432) (xy 99.944302 -120.113302) (xy 100.000036 -120.111265) (xy 100.055473 -120.117365)
			(xy 100.10943 -120.131471) (xy 100.160759 -120.153283) (xy 100.208365 -120.182337) (xy 100.251233 -120.218012)
			(xy 100.28845 -120.259549) (xy 100.319223 -120.306062) (xy 100.342895 -120.356559) (xy 100.358963 -120.409966)
			(xy 100.367083 -120.465142) (xy 100.367592 -120.493028) (xy 100.367083 -120.520914) (xy 100.358963 -120.57609)
			(xy 100.342895 -120.629497) (xy 100.319223 -120.679994) (xy 100.28845 -120.726507) (xy 100.251233 -120.768044)
			(xy 100.222158 -120.79224) (xy 100.535992 -120.79224) (xy 100.540063 -120.736618) (xy 100.552189 -120.682181)
			(xy 100.572112 -120.63009) (xy 100.599408 -120.581455) (xy 100.633494 -120.537312) (xy 100.673643 -120.498603)
			(xy 100.719001 -120.466152) (xy 100.768601 -120.440651) (xy 100.821385 -120.422644) (xy 100.876228 -120.412514)
			(xy 100.931962 -120.410477) (xy 100.987399 -120.416577) (xy 101.041356 -120.430683) (xy 101.092685 -120.452495)
			(xy 101.140291 -120.481549) (xy 101.183159 -120.517224) (xy 101.220376 -120.558761) (xy 101.251149 -120.605274)
			(xy 101.274821 -120.655771) (xy 101.290889 -120.709178) (xy 101.299009 -120.764354) (xy 101.299518 -120.79224)
			(xy 102.691436 -120.79224) (xy 102.695507 -120.736618) (xy 102.707633 -120.682181) (xy 102.727556 -120.63009)
			(xy 102.754852 -120.581455) (xy 102.788938 -120.537312) (xy 102.829087 -120.498603) (xy 102.874445 -120.466152)
			(xy 102.924045 -120.440651) (xy 102.976829 -120.422644) (xy 103.031672 -120.412514) (xy 103.087406 -120.410477)
			(xy 103.142843 -120.416577) (xy 103.1968 -120.430683) (xy 103.248129 -120.452495) (xy 103.295735 -120.481549)
			(xy 103.338603 -120.517224) (xy 103.346737 -120.526302) (xy 105.993436 -120.526302) (xy 105.997507 -120.47068)
			(xy 106.009633 -120.416243) (xy 106.029556 -120.364152) (xy 106.056852 -120.315517) (xy 106.090938 -120.271374)
			(xy 106.131087 -120.232665) (xy 106.176445 -120.200214) (xy 106.226045 -120.174713) (xy 106.278829 -120.156706)
			(xy 106.333672 -120.146576) (xy 106.389406 -120.144539) (xy 106.444843 -120.150639) (xy 106.4988 -120.164745)
			(xy 106.550129 -120.186557) (xy 106.597735 -120.215611) (xy 106.640603 -120.251286) (xy 106.67782 -120.292823)
			(xy 106.708593 -120.339336) (xy 106.711937 -120.34647) (xy 116.321076 -120.34647) (xy 116.325147 -120.290848)
			(xy 116.337273 -120.236411) (xy 116.357196 -120.18432) (xy 116.384492 -120.135685) (xy 116.418578 -120.091542)
			(xy 116.458727 -120.052833) (xy 116.504085 -120.020382) (xy 116.553685 -119.994881) (xy 116.606469 -119.976874)
			(xy 116.661312 -119.966744) (xy 116.717046 -119.964707) (xy 116.772483 -119.970807) (xy 116.82644 -119.984913)
			(xy 116.877769 -120.006725) (xy 116.925375 -120.035779) (xy 116.968243 -120.071454) (xy 117.00546 -120.112991)
			(xy 117.036233 -120.159504) (xy 117.059905 -120.210001) (xy 117.075973 -120.263408) (xy 117.084093 -120.318584)
			(xy 117.084602 -120.34647) (xy 117.084093 -120.374356) (xy 117.075973 -120.429532) (xy 117.059905 -120.482939)
			(xy 117.036233 -120.533436) (xy 117.00546 -120.579949) (xy 116.968243 -120.621486) (xy 116.925375 -120.657161)
			(xy 116.877769 -120.686215) (xy 116.82644 -120.708027) (xy 116.772483 -120.722133) (xy 116.717046 -120.728233)
			(xy 116.661312 -120.726196) (xy 116.606469 -120.716066) (xy 116.553685 -120.698059) (xy 116.504085 -120.672558)
			(xy 116.458727 -120.640107) (xy 116.418578 -120.601398) (xy 116.384492 -120.557255) (xy 116.357196 -120.50862)
			(xy 116.337273 -120.456529) (xy 116.325147 -120.402092) (xy 116.321076 -120.34647) (xy 106.711937 -120.34647)
			(xy 106.732265 -120.389833) (xy 106.748333 -120.44324) (xy 106.756453 -120.498416) (xy 106.756962 -120.526302)
			(xy 106.756453 -120.554188) (xy 106.748333 -120.609364) (xy 106.732265 -120.662771) (xy 106.708593 -120.713268)
			(xy 106.67782 -120.759781) (xy 106.640603 -120.801318) (xy 106.597735 -120.836993) (xy 106.550129 -120.866047)
			(xy 106.4988 -120.887859) (xy 106.444843 -120.901965) (xy 106.389406 -120.908065) (xy 106.333672 -120.906028)
			(xy 106.278829 -120.895898) (xy 106.226045 -120.877891) (xy 106.176445 -120.85239) (xy 106.131087 -120.819939)
			(xy 106.090938 -120.78123) (xy 106.056852 -120.737087) (xy 106.029556 -120.688452) (xy 106.009633 -120.636361)
			(xy 105.997507 -120.581924) (xy 105.993436 -120.526302) (xy 103.346737 -120.526302) (xy 103.37582 -120.558761)
			(xy 103.406593 -120.605274) (xy 103.430265 -120.655771) (xy 103.446333 -120.709178) (xy 103.454453 -120.764354)
			(xy 103.454962 -120.79224) (xy 103.454453 -120.820126) (xy 103.446333 -120.875302) (xy 103.430265 -120.928709)
			(xy 103.406593 -120.979206) (xy 103.37582 -121.025719) (xy 103.338696 -121.067152) (xy 117.690368 -121.067152)
			(xy 117.690368 -121.012648) (xy 117.698124 -120.9587) (xy 117.713479 -120.906404) (xy 117.736121 -120.856826)
			(xy 117.765587 -120.810975) (xy 117.801278 -120.769784) (xy 117.842469 -120.734092) (xy 117.888319 -120.704624)
			(xy 117.937897 -120.681982) (xy 117.990192 -120.666626) (xy 118.04414 -120.658868) (xy 118.071392 -120.658382)
			(xy 118.10031 -120.658875) (xy 118.157484 -120.667605) (xy 118.212685 -120.684866) (xy 118.264647 -120.710262)
			(xy 118.31218 -120.743212) (xy 118.354194 -120.782959) (xy 118.372382 -120.805448) (xy 118.379999 -120.814245)
			(xy 118.400892 -120.824432) (xy 118.412514 -120.825006) (xy 118.49227 -120.825006) (xy 118.503898 -120.824433)
			(xy 118.524807 -120.814268) (xy 118.532402 -120.805448) (xy 118.550579 -120.782953) (xy 118.592603 -120.743221)
			(xy 118.640141 -120.710285) (xy 118.692105 -120.684899) (xy 118.747305 -120.667644) (xy 118.804475 -120.658917)
			(xy 118.833392 -120.658382) (xy 118.860645 -120.658865) (xy 118.914595 -120.666621) (xy 118.966892 -120.681976)
			(xy 119.016472 -120.704617) (xy 119.062325 -120.734084) (xy 119.103518 -120.769777) (xy 119.111758 -120.779286)
			(xy 119.927114 -120.779286) (xy 119.931185 -120.723664) (xy 119.943311 -120.669227) (xy 119.963234 -120.617136)
			(xy 119.99053 -120.568501) (xy 120.024616 -120.524358) (xy 120.064765 -120.485649) (xy 120.110123 -120.453198)
			(xy 120.159723 -120.427697) (xy 120.212507 -120.40969) (xy 120.26735 -120.39956) (xy 120.323084 -120.397523)
			(xy 120.378521 -120.403623) (xy 120.432478 -120.417729) (xy 120.483807 -120.439541) (xy 120.531413 -120.468595)
			(xy 120.574281 -120.50427) (xy 120.611498 -120.545807) (xy 120.642271 -120.59232) (xy 120.665943 -120.642817)
			(xy 120.682011 -120.696224) (xy 120.690131 -120.7514) (xy 120.69064 -120.779286) (xy 120.690131 -120.807172)
			(xy 120.682011 -120.862348) (xy 120.665943 -120.915755) (xy 120.642271 -120.966252) (xy 120.611498 -121.012765)
			(xy 120.574281 -121.054302) (xy 120.531413 -121.089977) (xy 120.483807 -121.119031) (xy 120.432478 -121.140843)
			(xy 120.378521 -121.154949) (xy 120.323084 -121.161049) (xy 120.26735 -121.159012) (xy 120.212507 -121.148882)
			(xy 120.159723 -121.130875) (xy 120.110123 -121.105374) (xy 120.064765 -121.072923) (xy 120.024616 -121.034214)
			(xy 119.99053 -120.990071) (xy 119.963234 -120.941436) (xy 119.943311 -120.889345) (xy 119.931185 -120.834908)
			(xy 119.927114 -120.779286) (xy 119.111758 -120.779286) (xy 119.139211 -120.810969) (xy 119.168679 -120.856821)
			(xy 119.191322 -120.9064) (xy 119.206678 -120.958697) (xy 119.214435 -121.012647) (xy 119.214435 -121.067153)
			(xy 119.206678 -121.121103) (xy 119.191322 -121.1734) (xy 119.168679 -121.222979) (xy 119.139211 -121.268831)
			(xy 119.103518 -121.310023) (xy 119.062325 -121.345716) (xy 119.016472 -121.375183) (xy 118.966892 -121.397824)
			(xy 118.914595 -121.413179) (xy 118.860645 -121.420935) (xy 118.833392 -121.421398) (xy 118.804477 -121.420815)
			(xy 118.747309 -121.412099) (xy 118.692112 -121.394854) (xy 118.64015 -121.369475) (xy 118.592614 -121.336543)
			(xy 118.550594 -121.296812) (xy 118.532402 -121.274332) (xy 118.524796 -121.265524) (xy 118.503894 -121.255344)
			(xy 118.49227 -121.254774) (xy 118.412514 -121.254774) (xy 118.400881 -121.25531) (xy 118.37997 -121.265498)
			(xy 118.372382 -121.274332) (xy 118.354209 -121.296831) (xy 118.312185 -121.336564) (xy 118.264646 -121.3695)
			(xy 118.212681 -121.394885) (xy 118.157481 -121.412139) (xy 118.100309 -121.420865) (xy 118.071392 -121.421398)
			(xy 118.04414 -121.420932) (xy 117.990192 -121.413174) (xy 117.937897 -121.397818) (xy 117.888319 -121.375176)
			(xy 117.842469 -121.345708) (xy 117.801278 -121.310016) (xy 117.765587 -121.268825) (xy 117.736121 -121.222974)
			(xy 117.713479 -121.173396) (xy 117.698124 -121.1211) (xy 117.690368 -121.067152) (xy 103.338696 -121.067152)
			(xy 103.338603 -121.067256) (xy 103.295735 -121.102931) (xy 103.248129 -121.131985) (xy 103.1968 -121.153797)
			(xy 103.142843 -121.167903) (xy 103.087406 -121.174003) (xy 103.031672 -121.171966) (xy 102.976829 -121.161836)
			(xy 102.924045 -121.143829) (xy 102.874445 -121.118328) (xy 102.829087 -121.085877) (xy 102.788938 -121.047168)
			(xy 102.754852 -121.003025) (xy 102.727556 -120.95439) (xy 102.707633 -120.902299) (xy 102.695507 -120.847862)
			(xy 102.691436 -120.79224) (xy 101.299518 -120.79224) (xy 101.299009 -120.820126) (xy 101.290889 -120.875302)
			(xy 101.274821 -120.928709) (xy 101.251149 -120.979206) (xy 101.220376 -121.025719) (xy 101.183159 -121.067256)
			(xy 101.140291 -121.102931) (xy 101.092685 -121.131985) (xy 101.041356 -121.153797) (xy 100.987399 -121.167903)
			(xy 100.931962 -121.174003) (xy 100.876228 -121.171966) (xy 100.821385 -121.161836) (xy 100.768601 -121.143829)
			(xy 100.719001 -121.118328) (xy 100.673643 -121.085877) (xy 100.633494 -121.047168) (xy 100.599408 -121.003025)
			(xy 100.572112 -120.95439) (xy 100.552189 -120.902299) (xy 100.540063 -120.847862) (xy 100.535992 -120.79224)
			(xy 100.222158 -120.79224) (xy 100.208365 -120.803719) (xy 100.160759 -120.832773) (xy 100.10943 -120.854585)
			(xy 100.055473 -120.868691) (xy 100.000036 -120.874791) (xy 99.944302 -120.872754) (xy 99.889459 -120.862624)
			(xy 99.836675 -120.844617) (xy 99.787075 -120.819116) (xy 99.741717 -120.786665) (xy 99.701568 -120.747956)
			(xy 99.667482 -120.703813) (xy 99.640186 -120.655178) (xy 99.620263 -120.603087) (xy 99.608137 -120.54865)
			(xy 99.604066 -120.493028) (xy 90.152727 -120.493028) (xy 90.137351 -120.516801) (xy 90.119708 -120.537732)
			(xy 90.119454 -120.537986) (xy 90.113862 -120.545068) (xy 90.10762 -120.561989) (xy 90.107262 -120.571006)
			(xy 90.107262 -120.638062) (xy 90.107645 -120.647076) (xy 90.113876 -120.663993) (xy 90.119454 -120.671082)
			(xy 90.119708 -120.671082) (xy 90.119708 -120.671336) (xy 90.137381 -120.692242) (xy 90.167101 -120.738216)
			(xy 90.189943 -120.787966) (xy 90.205435 -120.840472) (xy 90.213259 -120.894654) (xy 90.213256 -120.949397)
			(xy 90.205424 -121.003578) (xy 90.189925 -121.056082) (xy 90.167077 -121.105829) (xy 90.13735 -121.151799)
			(xy 90.119708 -121.172732) (xy 90.119454 -121.172986) (xy 90.113862 -121.180068) (xy 90.10762 -121.196989)
			(xy 90.10755 -121.198753) (xy 90.48544 -121.198753) (xy 90.48544 -121.144247) (xy 90.493196 -121.090297)
			(xy 90.508551 -121.038) (xy 90.531192 -120.98842) (xy 90.560659 -120.942566) (xy 90.59635 -120.901373)
			(xy 90.637541 -120.865678) (xy 90.683392 -120.836208) (xy 90.73297 -120.813562) (xy 90.785266 -120.798203)
			(xy 90.839216 -120.790442) (xy 90.866468 -120.789954) (xy 90.893838 -120.790426) (xy 90.948018 -120.79824)
			(xy 91.000521 -120.813727) (xy 91.050268 -120.836568) (xy 91.096235 -120.866293) (xy 91.117166 -120.883934)
			(xy 91.11742 -120.884188) (xy 91.124498 -120.889788) (xy 91.141421 -120.896027) (xy 91.15044 -120.89638)
			(xy 91.217496 -120.89638) (xy 91.226513 -120.896026) (xy 91.24343 -120.889777) (xy 91.250516 -120.884188)
			(xy 91.250516 -120.883934) (xy 91.25077 -120.883934) (xy 91.271707 -120.866301) (xy 91.317678 -120.836587)
			(xy 91.367424 -120.813749) (xy 91.419924 -120.798257) (xy 91.474099 -120.790428) (xy 91.501468 -120.789954)
			(xy 91.52872 -120.790491) (xy 91.582669 -120.798244) (xy 91.634965 -120.813595) (xy 91.684544 -120.836234)
			(xy 91.730397 -120.865698) (xy 91.771589 -120.901388) (xy 91.807283 -120.942577) (xy 91.836751 -120.988428)
			(xy 91.859394 -121.038005) (xy 91.87475 -121.0903) (xy 91.882507 -121.144248) (xy 91.882507 -121.198752)
			(xy 91.87475 -121.2527) (xy 91.859394 -121.304995) (xy 91.836751 -121.354572) (xy 91.807283 -121.400423)
			(xy 91.771589 -121.441612) (xy 91.730397 -121.477302) (xy 91.684544 -121.506766) (xy 91.634965 -121.529405)
			(xy 91.582669 -121.544756) (xy 91.52872 -121.552509) (xy 91.501468 -121.55297) (xy 91.474097 -121.55253)
			(xy 91.419916 -121.544707) (xy 91.367413 -121.529212) (xy 91.317666 -121.506365) (xy 91.271701 -121.476634)
			(xy 91.25077 -121.45899) (xy 91.250516 -121.458736) (xy 91.243435 -121.453142) (xy 91.226514 -121.446902)
			(xy 91.217496 -121.446544) (xy 91.15044 -121.446544) (xy 91.141424 -121.446911) (xy 91.124506 -121.45315)
			(xy 91.11742 -121.458736) (xy 91.11742 -121.45899) (xy 91.117166 -121.45899) (xy 91.096219 -121.47661)
			(xy 91.05025 -121.506325) (xy 91.000507 -121.529165) (xy 90.948009 -121.54466) (xy 90.893836 -121.552493)
			(xy 90.866468 -121.55297) (xy 90.839216 -121.552558) (xy 90.785266 -121.544797) (xy 90.73297 -121.529438)
			(xy 90.683392 -121.506792) (xy 90.637541 -121.477322) (xy 90.59635 -121.441627) (xy 90.560659 -121.400434)
			(xy 90.531192 -121.35458) (xy 90.508551 -121.305) (xy 90.493196 -121.252703) (xy 90.48544 -121.198753)
			(xy 90.10755 -121.198753) (xy 90.107262 -121.206006) (xy 90.107262 -121.273062) (xy 90.107645 -121.282076)
			(xy 90.113876 -121.298993) (xy 90.119454 -121.306082) (xy 90.119708 -121.306082) (xy 90.119708 -121.306336)
			(xy 90.137381 -121.327242) (xy 90.167101 -121.373216) (xy 90.189943 -121.422966) (xy 90.205435 -121.475472)
			(xy 90.213259 -121.529654) (xy 90.213256 -121.581672) (xy 91.994736 -121.581672) (xy 91.995177 -121.554301)
			(xy 92.002999 -121.50012) (xy 92.018494 -121.447617) (xy 92.041341 -121.39787) (xy 92.071072 -121.351905)
			(xy 92.088716 -121.330974) (xy 92.08897 -121.33072) (xy 92.094563 -121.323638) (xy 92.100804 -121.306717)
			(xy 92.101162 -121.2977) (xy 92.101162 -121.230644) (xy 92.100792 -121.221628) (xy 92.094554 -121.204711)
			(xy 92.08897 -121.197624) (xy 92.088716 -121.197624) (xy 92.088716 -121.19737) (xy 92.071099 -121.17642)
			(xy 92.041383 -121.130453) (xy 92.018543 -121.08071) (xy 92.003047 -121.028213) (xy 91.995213 -120.97404)
			(xy 91.994736 -120.946672) (xy 91.995129 -120.919416) (xy 92.002891 -120.865461) (xy 92.018253 -120.813159)
			(xy 92.040902 -120.763576) (xy 92.070377 -120.71772) (xy 92.106078 -120.676527) (xy 92.147278 -120.640834)
			(xy 92.193139 -120.611367) (xy 92.242726 -120.588728) (xy 92.295031 -120.573376) (xy 92.348988 -120.565624)
			(xy 92.376244 -120.565164) (xy 92.405365 -120.565735) (xy 92.462934 -120.574566) (xy 92.518491 -120.592047)
			(xy 92.570744 -120.617772) (xy 92.618478 -120.651142) (xy 92.660584 -120.691381) (xy 92.696083 -120.737554)
			(xy 92.724149 -120.788588) (xy 92.74413 -120.843295) (xy 92.750386 -120.871742) (xy 92.752672 -120.883426)
			(xy 92.76715 -120.902222) (xy 92.851224 -120.942608) (xy 92.862036 -120.947177) (xy 92.885477 -120.946915)
			(xy 92.896182 -120.9421) (xy 92.89669 -120.9421) (xy 92.923744 -120.928808) (xy 92.981022 -120.910034)
			(xy 93.040542 -120.900519) (xy 93.07068 -120.899936) (xy 93.097934 -120.900374) (xy 93.151888 -120.908129)
			(xy 93.20419 -120.923485) (xy 93.253772 -120.946129) (xy 93.299628 -120.975599) (xy 93.340822 -121.011295)
			(xy 93.376516 -121.052491) (xy 93.405983 -121.098349) (xy 93.428623 -121.147933) (xy 93.443976 -121.200235)
			(xy 93.449513 -121.238772) (xy 97.584258 -121.238772) (xy 97.588329 -121.18315) (xy 97.600455 -121.128713)
			(xy 97.620378 -121.076622) (xy 97.647674 -121.027987) (xy 97.68176 -120.983844) (xy 97.721909 -120.945135)
			(xy 97.767267 -120.912684) (xy 97.816867 -120.887183) (xy 97.869651 -120.869176) (xy 97.924494 -120.859046)
			(xy 97.980228 -120.857009) (xy 98.035665 -120.863109) (xy 98.089622 -120.877215) (xy 98.140951 -120.899027)
			(xy 98.188557 -120.928081) (xy 98.231425 -120.963756) (xy 98.268642 -121.005293) (xy 98.299415 -121.051806)
			(xy 98.323087 -121.102303) (xy 98.339155 -121.15571) (xy 98.347275 -121.210886) (xy 98.347784 -121.238772)
			(xy 98.347275 -121.266658) (xy 98.339155 -121.321834) (xy 98.323087 -121.375241) (xy 98.299415 -121.425738)
			(xy 98.268642 -121.472251) (xy 98.231425 -121.513788) (xy 98.188557 -121.549463) (xy 98.153678 -121.57075)
			(xy 129.719832 -121.57075) (xy 129.720256 -121.544434) (xy 129.727498 -121.492304) (xy 129.741825 -121.44166)
			(xy 129.762966 -121.393461) (xy 129.79052 -121.348618) (xy 129.823967 -121.307981) (xy 129.843022 -121.289826)
			(xy 129.850417 -121.2823) (xy 129.858945 -121.263023) (xy 129.859532 -121.252488) (xy 129.859532 -121.177812)
			(xy 129.859001 -121.167263) (xy 129.850466 -121.147968) (xy 129.843022 -121.140474) (xy 129.823965 -121.12232)
			(xy 129.790507 -121.08169) (xy 129.762948 -121.03685) (xy 129.741809 -120.988649) (xy 129.727493 -120.938001)
			(xy 129.72027 -120.885866) (xy 129.719832 -120.85955) (xy 129.720318 -120.832299) (xy 129.728074 -120.778351)
			(xy 129.743429 -120.726056) (xy 129.766071 -120.676479) (xy 129.795537 -120.630629) (xy 129.831228 -120.589438)
			(xy 129.872419 -120.553747) (xy 129.918269 -120.524281) (xy 129.967846 -120.501639) (xy 130.020141 -120.486284)
			(xy 130.074089 -120.478528) (xy 130.128591 -120.478528) (xy 130.182539 -120.486284) (xy 130.234834 -120.501639)
			(xy 130.284411 -120.524281) (xy 130.330261 -120.553747) (xy 130.371452 -120.589438) (xy 130.407143 -120.630629)
			(xy 130.436609 -120.676479) (xy 130.459251 -120.726056) (xy 130.474606 -120.778351) (xy 130.482362 -120.832299)
			(xy 130.482848 -120.85955) (xy 130.482431 -120.885866) (xy 130.475188 -120.937997) (xy 130.46086 -120.988642)
			(xy 130.439718 -121.036841) (xy 130.412163 -121.081683) (xy 130.378714 -121.12232) (xy 130.359658 -121.140474)
			(xy 130.352274 -121.148011) (xy 130.343738 -121.167279) (xy 130.343148 -121.177812) (xy 130.343148 -121.252488)
			(xy 130.343656 -121.263041) (xy 130.352204 -121.282337) (xy 130.359658 -121.289826) (xy 130.37873 -121.307965)
			(xy 130.412184 -121.348599) (xy 130.439739 -121.393443) (xy 130.460874 -121.441647) (xy 130.475188 -121.492297)
			(xy 130.482411 -121.544433) (xy 130.482848 -121.57075) (xy 130.482362 -121.598001) (xy 130.474606 -121.651949)
			(xy 130.459251 -121.704244) (xy 130.436609 -121.753821) (xy 130.407143 -121.799671) (xy 130.371452 -121.840862)
			(xy 130.330261 -121.876553) (xy 130.284411 -121.906019) (xy 130.234834 -121.928661) (xy 130.182539 -121.944016)
			(xy 130.128591 -121.951772) (xy 130.074089 -121.951772) (xy 130.020141 -121.944016) (xy 129.967846 -121.928661)
			(xy 129.918269 -121.906019) (xy 129.872419 -121.876553) (xy 129.831228 -121.840862) (xy 129.795537 -121.799671)
			(xy 129.766071 -121.753821) (xy 129.743429 -121.704244) (xy 129.728074 -121.651949) (xy 129.720318 -121.598001)
			(xy 129.719832 -121.57075) (xy 98.153678 -121.57075) (xy 98.140951 -121.578517) (xy 98.089622 -121.600329)
			(xy 98.035665 -121.614435) (xy 97.980228 -121.620535) (xy 97.924494 -121.618498) (xy 97.869651 -121.608368)
			(xy 97.816867 -121.590361) (xy 97.767267 -121.56486) (xy 97.721909 -121.532409) (xy 97.68176 -121.4937)
			(xy 97.647674 -121.449557) (xy 97.620378 -121.400922) (xy 97.600455 -121.348831) (xy 97.588329 -121.294394)
			(xy 97.584258 -121.238772) (xy 93.449513 -121.238772) (xy 93.451728 -121.25419) (xy 93.452188 -121.281444)
			(xy 93.451692 -121.308813) (xy 93.443882 -121.362991) (xy 93.4284 -121.415494) (xy 93.405565 -121.465241)
			(xy 93.375846 -121.511209) (xy 93.358208 -121.532142) (xy 93.357954 -121.532396) (xy 93.352357 -121.539476)
			(xy 93.346118 -121.556398) (xy 93.345762 -121.565416) (xy 93.345762 -121.632472) (xy 93.346141 -121.641486)
			(xy 93.352374 -121.658403) (xy 93.357954 -121.665492) (xy 93.358208 -121.665492) (xy 93.358208 -121.665746)
			(xy 93.375836 -121.686687) (xy 93.40555 -121.732657) (xy 93.428387 -121.782403) (xy 93.443881 -121.834901)
			(xy 93.451712 -121.889075) (xy 93.452188 -121.916444) (xy 93.451763 -121.943697) (xy 93.444 -121.997648)
			(xy 93.428638 -122.049945) (xy 93.405991 -122.099524) (xy 93.376518 -122.145375) (xy 93.34082 -122.186565)
			(xy 93.299624 -122.222256) (xy 93.253768 -122.251721) (xy 93.204185 -122.274361) (xy 93.151886 -122.289714)
			(xy 93.13168 -122.292618) (xy 125.880112 -122.292618) (xy 125.884183 -122.236996) (xy 125.896309 -122.182559)
			(xy 125.916232 -122.130468) (xy 125.943528 -122.081833) (xy 125.977614 -122.03769) (xy 126.017763 -121.998981)
			(xy 126.063121 -121.96653) (xy 126.112721 -121.941029) (xy 126.165505 -121.923022) (xy 126.220348 -121.912892)
			(xy 126.276082 -121.910855) (xy 126.331519 -121.916955) (xy 126.385476 -121.931061) (xy 126.436805 -121.952873)
			(xy 126.484411 -121.981927) (xy 126.527279 -122.017602) (xy 126.564496 -122.059139) (xy 126.595269 -122.105652)
			(xy 126.618941 -122.156149) (xy 126.635009 -122.209556) (xy 126.643129 -122.264732) (xy 126.643638 -122.292618)
			(xy 126.643129 -122.320504) (xy 126.635009 -122.37568) (xy 126.618941 -122.429087) (xy 126.599804 -122.46991)
			(xy 127.036828 -122.46991) (xy 127.040899 -122.414288) (xy 127.053025 -122.359851) (xy 127.072948 -122.30776)
			(xy 127.100244 -122.259125) (xy 127.13433 -122.214982) (xy 127.174479 -122.176273) (xy 127.219837 -122.143822)
			(xy 127.269437 -122.118321) (xy 127.322221 -122.100314) (xy 127.377064 -122.090184) (xy 127.432798 -122.088147)
			(xy 127.488235 -122.094247) (xy 127.542192 -122.108353) (xy 127.593521 -122.130165) (xy 127.641127 -122.159219)
			(xy 127.683995 -122.194894) (xy 127.721212 -122.236431) (xy 127.751985 -122.282944) (xy 127.775657 -122.333441)
			(xy 127.791725 -122.386848) (xy 127.799845 -122.442024) (xy 127.800354 -122.46991) (xy 127.799845 -122.497796)
			(xy 127.791725 -122.552972) (xy 127.775657 -122.606379) (xy 127.751985 -122.656876) (xy 127.721212 -122.703389)
			(xy 127.683995 -122.744926) (xy 127.641127 -122.780601) (xy 127.593521 -122.809655) (xy 127.542192 -122.831467)
			(xy 127.488235 -122.845573) (xy 127.432798 -122.851673) (xy 127.377064 -122.849636) (xy 127.322221 -122.839506)
			(xy 127.269437 -122.821499) (xy 127.219837 -122.795998) (xy 127.174479 -122.763547) (xy 127.13433 -122.724838)
			(xy 127.100244 -122.680695) (xy 127.072948 -122.63206) (xy 127.053025 -122.579969) (xy 127.040899 -122.525532)
			(xy 127.036828 -122.46991) (xy 126.599804 -122.46991) (xy 126.595269 -122.479584) (xy 126.564496 -122.526097)
			(xy 126.527279 -122.567634) (xy 126.484411 -122.603309) (xy 126.436805 -122.632363) (xy 126.385476 -122.654175)
			(xy 126.331519 -122.668281) (xy 126.276082 -122.674381) (xy 126.220348 -122.672344) (xy 126.165505 -122.662214)
			(xy 126.112721 -122.644207) (xy 126.063121 -122.618706) (xy 126.017763 -122.586255) (xy 125.977614 -122.547546)
			(xy 125.943528 -122.503403) (xy 125.916232 -122.454768) (xy 125.896309 -122.402677) (xy 125.884183 -122.34824)
			(xy 125.880112 -122.292618) (xy 93.13168 -122.292618) (xy 93.097933 -122.297468) (xy 93.07068 -122.297952)
			(xy 93.041557 -122.297438) (xy 92.983987 -122.288596) (xy 92.928429 -122.271105) (xy 92.876177 -122.245372)
			(xy 92.828443 -122.211995) (xy 92.786338 -122.171749) (xy 92.75084 -122.125571) (xy 92.722774 -122.074533)
			(xy 92.702793 -122.019822) (xy 92.696538 -121.991374) (xy 92.694252 -121.97969) (xy 92.679774 -121.960894)
			(xy 92.5957 -121.920508) (xy 92.584883 -121.915953) (xy 92.561446 -121.916206) (xy 92.550742 -121.921016)
			(xy 92.550234 -121.921016) (xy 92.523177 -121.934301) (xy 92.4659 -121.953077) (xy 92.406381 -121.962596)
			(xy 92.376244 -121.96318) (xy 92.348991 -121.962704) (xy 92.295039 -121.954952) (xy 92.24274 -121.9396)
			(xy 92.193158 -121.916961) (xy 92.147303 -121.887495) (xy 92.106109 -121.851802) (xy 92.070415 -121.81061)
			(xy 92.040947 -121.764756) (xy 92.018305 -121.715175) (xy 92.002951 -121.662877) (xy 91.995197 -121.608925)
			(xy 91.994736 -121.581672) (xy 90.213256 -121.581672) (xy 90.213256 -121.584397) (xy 90.205424 -121.638578)
			(xy 90.189925 -121.691082) (xy 90.167077 -121.740829) (xy 90.13735 -121.786799) (xy 90.119708 -121.807732)
			(xy 90.119454 -121.807986) (xy 90.113862 -121.815068) (xy 90.10762 -121.831989) (xy 90.107262 -121.841006)
			(xy 90.107262 -121.908062) (xy 90.107645 -121.917076) (xy 90.113876 -121.933993) (xy 90.119454 -121.941082)
			(xy 90.119708 -121.941082) (xy 90.119708 -121.941336) (xy 90.137332 -121.96228) (xy 90.167046 -122.00825)
			(xy 90.189884 -122.057994) (xy 90.205379 -122.110492) (xy 90.213212 -122.164666) (xy 90.213688 -122.192034)
			(xy 90.213202 -122.219285) (xy 90.205446 -122.273233) (xy 90.190091 -122.325528) (xy 90.167449 -122.375105)
			(xy 90.137983 -122.420955) (xy 90.102292 -122.462146) (xy 90.061101 -122.497837) (xy 90.015251 -122.527303)
			(xy 89.965674 -122.549945) (xy 89.913379 -122.5653) (xy 89.859431 -122.573056) (xy 89.804929 -122.573056)
			(xy 89.750981 -122.5653) (xy 89.698686 -122.549945) (xy 89.649109 -122.527303) (xy 89.603259 -122.497837)
			(xy 89.562068 -122.462146) (xy 89.526377 -122.420955) (xy 89.496911 -122.375105) (xy 89.474269 -122.325528)
			(xy 89.458914 -122.273233) (xy 89.451158 -122.219285) (xy 89.450672 -122.192034) (xy 81.978069 -122.192034)
			(xy 81.981873 -122.206227) (xy 81.989704 -122.265682) (xy 81.990184 -122.295666) (xy 81.990184 -123.159266)
			(xy 81.989717 -123.189254) (xy 81.981893 -123.248716) (xy 81.966374 -123.306649) (xy 81.943427 -123.36206)
			(xy 81.941988 -123.364553) (xy 94.064275 -123.364553) (xy 94.064275 -123.310047) (xy 94.072033 -123.256097)
			(xy 94.087389 -123.203799) (xy 94.110033 -123.15422) (xy 94.139502 -123.108368) (xy 94.175197 -123.067177)
			(xy 94.21639 -123.031485) (xy 94.262245 -123.002019) (xy 94.311826 -122.97938) (xy 94.364124 -122.964027)
			(xy 94.418075 -122.956273) (xy 94.445328 -122.955812) (xy 94.472699 -122.956259) (xy 94.526879 -122.964081)
			(xy 94.579382 -122.979574) (xy 94.629129 -123.00242) (xy 94.675095 -123.032149) (xy 94.696026 -123.049792)
			(xy 94.69628 -123.050046) (xy 94.703364 -123.055636) (xy 94.720283 -123.061879) (xy 94.7293 -123.062238)
			(xy 94.796356 -123.062238) (xy 94.80537 -123.061852) (xy 94.822286 -123.055624) (xy 94.829376 -123.050046)
			(xy 94.829376 -123.049792) (xy 94.82963 -123.049792) (xy 94.850563 -123.032151) (xy 94.896531 -123.002427)
			(xy 94.946277 -122.979581) (xy 94.998779 -122.964085) (xy 95.052957 -122.956256) (xy 95.107699 -122.956256)
			(xy 95.161877 -122.964085) (xy 95.214379 -122.979581) (xy 95.264125 -123.002427) (xy 95.310093 -123.032151)
			(xy 95.331026 -123.049792) (xy 95.33128 -123.050046) (xy 95.338364 -123.055636) (xy 95.355283 -123.061879)
			(xy 95.3643 -123.062238) (xy 95.431356 -123.062238) (xy 95.44037 -123.061852) (xy 95.457286 -123.055624)
			(xy 95.464376 -123.050046) (xy 95.464376 -123.049792) (xy 95.46463 -123.049792) (xy 95.485577 -123.032171)
			(xy 95.531546 -123.002457) (xy 95.581289 -122.979617) (xy 95.633787 -122.964122) (xy 95.68796 -122.956289)
			(xy 95.715328 -122.955812) (xy 95.742579 -122.95626) (xy 95.796527 -122.96402) (xy 95.848821 -122.979378)
			(xy 95.898397 -123.002022) (xy 95.944247 -123.031491) (xy 95.985436 -123.067184) (xy 96.021126 -123.108376)
			(xy 96.050591 -123.154227) (xy 96.073232 -123.203805) (xy 96.088586 -123.256101) (xy 96.096342 -123.310049)
			(xy 96.096342 -123.364551) (xy 96.088586 -123.4185) (xy 96.073232 -123.470795) (xy 96.050591 -123.520373)
			(xy 96.021126 -123.566224) (xy 95.985436 -123.607416) (xy 95.944247 -123.643109) (xy 95.898397 -123.672578)
			(xy 95.848821 -123.695222) (xy 95.796527 -123.71058) (xy 95.742579 -123.71834) (xy 95.715328 -123.718828)
			(xy 95.687958 -123.718363) (xy 95.633778 -123.710548) (xy 95.581274 -123.695059) (xy 95.531527 -123.672217)
			(xy 95.485561 -123.64249) (xy 95.46463 -123.624848) (xy 95.464376 -123.624594) (xy 95.457301 -123.618991)
			(xy 95.440375 -123.612754) (xy 95.431356 -123.612402) (xy 95.3643 -123.612402) (xy 95.355283 -123.612759)
			(xy 95.338366 -123.619006) (xy 95.33128 -123.624594) (xy 95.331026 -123.624848) (xy 95.310093 -123.642489)
			(xy 95.264125 -123.672213) (xy 95.214379 -123.695059) (xy 95.161877 -123.710555) (xy 95.107699 -123.718384)
			(xy 95.052957 -123.718384) (xy 94.998779 -123.710555) (xy 94.946277 -123.695059) (xy 94.896531 -123.672213)
			(xy 94.850563 -123.642489) (xy 94.82963 -123.624848) (xy 94.829376 -123.624594) (xy 94.822301 -123.618991)
			(xy 94.805375 -123.612754) (xy 94.796356 -123.612402) (xy 94.7293 -123.612402) (xy 94.720283 -123.612759)
			(xy 94.703366 -123.619006) (xy 94.69628 -123.624594) (xy 94.69628 -123.624848) (xy 94.696026 -123.624848)
			(xy 94.675088 -123.64248) (xy 94.629118 -123.672195) (xy 94.579372 -123.695033) (xy 94.526872 -123.710525)
			(xy 94.472697 -123.718354) (xy 94.445328 -123.718828) (xy 94.418075 -123.718327) (xy 94.364124 -123.710573)
			(xy 94.311826 -123.69522) (xy 94.262245 -123.672581) (xy 94.21639 -123.643115) (xy 94.175197 -123.607423)
			(xy 94.139502 -123.566232) (xy 94.110033 -123.52038) (xy 94.087389 -123.470801) (xy 94.072033 -123.418503)
			(xy 94.064275 -123.364553) (xy 81.941988 -123.364553) (xy 81.913442 -123.414002) (xy 81.876935 -123.461586)
			(xy 81.834528 -123.503998) (xy 81.786949 -123.540511) (xy 81.735011 -123.570502) (xy 81.679602 -123.593456)
			(xy 81.621671 -123.608982) (xy 81.56221 -123.616813) (xy 81.532222 -123.617228) (xy 81.49717 -123.615958)
			(xy 81.492852 -123.61545) (xy 81.492344 -123.61545) (xy 81.491328 -123.615196) (xy 81.48955 -123.615196)
			(xy 81.483962 -123.614688) (xy 81.482438 -123.614434) (xy 81.46923 -123.61291) (xy 81.468214 -123.61291)
			(xy 81.440511 -123.608561) (xy 81.386363 -123.593971) (xy 81.334409 -123.572864) (xy 81.309718 -123.55957)
			(xy 81.3054 -123.55703) (xy 81.295494 -123.553728) (xy 81.291953 -123.552766) (xy 81.284685 -123.551753)
			(xy 81.281016 -123.551696) (xy 81.269586 -123.551696) (xy 81.238598 -123.558554) (xy 81.230724 -123.563888)
			(xy 81.227168 -123.566174) (xy 81.221326 -123.576842) (xy 81.218628 -123.582054) (xy 81.21542 -123.593342)
			(xy 81.214976 -123.599194) (xy 81.156695 -124.965714) (xy 83.716368 -124.965714) (xy 83.716368 -124.102114)
			(xy 83.716858 -124.07213) (xy 83.724686 -124.012674) (xy 83.740207 -123.954749) (xy 83.763156 -123.899345)
			(xy 83.79314 -123.847411) (xy 83.829646 -123.799835) (xy 83.872051 -123.75743) (xy 83.919627 -123.720924)
			(xy 83.971561 -123.69094) (xy 84.026965 -123.667991) (xy 84.08489 -123.65247) (xy 84.144346 -123.644642)
			(xy 84.204314 -123.644642) (xy 84.26377 -123.65247) (xy 84.321695 -123.667991) (xy 84.377099 -123.69094)
			(xy 84.429033 -123.720924) (xy 84.476609 -123.75743) (xy 84.486939 -123.76776) (xy 97.442306 -123.76776)
			(xy 97.45006 -123.713817) (xy 97.465412 -123.661528) (xy 97.488049 -123.611955) (xy 97.51751 -123.566108)
			(xy 97.553197 -123.524921) (xy 97.594381 -123.489231) (xy 97.640225 -123.459765) (xy 97.689796 -123.437124)
			(xy 97.742084 -123.421767) (xy 97.796026 -123.414008) (xy 97.823274 -123.41352) (xy 97.823782 -123.41352)
			(xy 97.834154 -123.413603) (xy 97.854866 -123.414745) (xy 97.865184 -123.415806) (xy 97.879729 -123.41691)
			(xy 97.908422 -123.411704) (xy 97.934478 -123.398612) (xy 97.955781 -123.378698) (xy 97.970599 -123.353583)
			(xy 97.977727 -123.325307) (xy 97.976586 -123.296168) (xy 97.972372 -123.282202) (xy 97.963011 -123.252595)
			(xy 97.952934 -123.191327) (xy 97.952306 -123.160282) (xy 97.952306 -123.160028) (xy 97.952725 -123.132773)
			(xy 97.960479 -123.078817) (xy 97.975832 -123.026514) (xy 97.998473 -122.976928) (xy 98.02794 -122.931069)
			(xy 98.063634 -122.889871) (xy 98.104828 -122.854171) (xy 98.150683 -122.824698) (xy 98.200266 -122.80205)
			(xy 98.252567 -122.78669) (xy 98.306522 -122.778929) (xy 98.361032 -122.778925) (xy 98.414988 -122.78668)
			(xy 98.467291 -122.802034) (xy 98.516876 -122.824675) (xy 98.562735 -122.854143) (xy 98.603933 -122.889837)
			(xy 98.639632 -122.931032) (xy 98.669105 -122.976887) (xy 98.691751 -123.02647) (xy 98.707111 -123.078771)
			(xy 98.714872 -123.132726) (xy 98.714874 -123.187236) (xy 98.707119 -123.241192) (xy 98.704606 -123.249752)
			(xy 128.009867 -123.249752) (xy 128.009867 -123.195248) (xy 128.017624 -123.141298) (xy 128.03298 -123.089002)
			(xy 128.055622 -123.039423) (xy 128.085089 -122.993571) (xy 128.120782 -122.95238) (xy 128.161974 -122.916687)
			(xy 128.207826 -122.88722) (xy 128.257405 -122.864579) (xy 128.309702 -122.849223) (xy 128.363652 -122.841467)
			(xy 128.390904 -122.841004) (xy 128.417934 -122.841497) (xy 128.471452 -122.849135) (xy 128.523353 -122.864259)
			(xy 128.572597 -122.886563) (xy 128.618196 -122.915602) (xy 128.659234 -122.950791) (xy 128.677416 -122.970798)
			(xy 128.67767 -122.971052) (xy 128.685148 -122.978659) (xy 128.704606 -122.98735) (xy 128.715262 -122.987816)
			(xy 128.802892 -122.988324) (xy 128.82245 -122.979688) (xy 128.829816 -122.971306) (xy 128.847975 -122.951581)
			(xy 128.888876 -122.916917) (xy 128.934232 -122.888329) (xy 128.983148 -122.86638) (xy 129.034657 -122.851505)
			(xy 129.087743 -122.843997) (xy 129.11455 -122.843544) (xy 129.14192 -122.844029) (xy 129.196098 -122.85184)
			(xy 129.248602 -122.867324) (xy 129.298349 -122.890162) (xy 129.344316 -122.919884) (xy 129.365248 -122.937524)
			(xy 129.365502 -122.937778) (xy 129.372577 -122.943381) (xy 129.389503 -122.949616) (xy 129.398522 -122.94997)
			(xy 129.465578 -122.94997) (xy 129.474595 -122.949609) (xy 129.491512 -122.943365) (xy 129.498598 -122.937778)
			(xy 129.498598 -122.937524) (xy 129.498852 -122.937524) (xy 129.519785 -122.919883) (xy 129.565753 -122.890159)
			(xy 129.615499 -122.867313) (xy 129.668001 -122.851817) (xy 129.722179 -122.843988) (xy 129.776921 -122.843988)
			(xy 129.831099 -122.851817) (xy 129.883601 -122.867313) (xy 129.933347 -122.890159) (xy 129.979315 -122.919883)
			(xy 130.000248 -122.937524) (xy 130.000502 -122.937778) (xy 130.007577 -122.943381) (xy 130.024503 -122.949616)
			(xy 130.033522 -122.94997) (xy 130.100578 -122.94997) (xy 130.109595 -122.949609) (xy 130.126512 -122.943365)
			(xy 130.133598 -122.937778) (xy 130.134106 -122.937524) (xy 130.14684 -122.926579) (xy 130.173931 -122.906738)
			(xy 130.188208 -122.8979) (xy 130.197098 -122.892566) (xy 130.20929 -122.875548) (xy 130.22961 -122.78233)
			(xy 130.225292 -122.761756) (xy 130.21945 -122.75312) (xy 130.203451 -122.729056) (xy 130.178109 -122.677124)
			(xy 130.160884 -122.621966) (xy 130.152168 -122.564842) (xy 130.151632 -122.53595) (xy 130.152118 -122.508699)
			(xy 130.159874 -122.454751) (xy 130.175229 -122.402456) (xy 130.197871 -122.352879) (xy 130.227337 -122.307029)
			(xy 130.263028 -122.265838) (xy 130.304219 -122.230147) (xy 130.350069 -122.200681) (xy 130.399646 -122.178039)
			(xy 130.451941 -122.162684) (xy 130.505889 -122.154928) (xy 130.560391 -122.154928) (xy 130.614339 -122.162684)
			(xy 130.666634 -122.178039) (xy 130.716211 -122.200681) (xy 130.762061 -122.230147) (xy 130.803252 -122.265838)
			(xy 130.838943 -122.307029) (xy 130.868409 -122.352879) (xy 130.891051 -122.402456) (xy 130.906406 -122.454751)
			(xy 130.914162 -122.508699) (xy 130.914648 -122.53595) (xy 130.914099 -122.564039) (xy 130.90588 -122.619613)
			(xy 130.889597 -122.673381) (xy 130.865603 -122.724177) (xy 130.834417 -122.770905) (xy 130.796714 -122.812552)
			(xy 130.753308 -122.848217) (xy 130.729482 -122.863102) (xy 130.720592 -122.868436) (xy 130.7084 -122.885454)
			(xy 130.68808 -122.978672) (xy 130.692398 -122.999246) (xy 130.69824 -123.007882) (xy 130.714239 -123.031946)
			(xy 130.739581 -123.083878) (xy 130.756807 -123.139036) (xy 130.765523 -123.19616) (xy 130.766058 -123.225052)
			(xy 130.7656 -123.252306) (xy 130.757848 -123.30626) (xy 130.742496 -123.358561) (xy 130.719855 -123.408144)
			(xy 130.690387 -123.454) (xy 130.654693 -123.495194) (xy 130.613498 -123.530889) (xy 130.567642 -123.560356)
			(xy 130.518059 -123.582996) (xy 130.465758 -123.598349) (xy 130.411804 -123.6061) (xy 130.38455 -123.60656)
			(xy 130.35718 -123.606074) (xy 130.303002 -123.598263) (xy 130.250498 -123.582779) (xy 130.200751 -123.559941)
			(xy 130.154784 -123.53022) (xy 130.133852 -123.51258) (xy 130.133598 -123.512326) (xy 130.126522 -123.506724)
			(xy 130.109597 -123.500488) (xy 130.100578 -123.500134) (xy 130.033522 -123.500134) (xy 130.024505 -123.500494)
			(xy 130.007588 -123.506739) (xy 130.000502 -123.512326) (xy 130.000248 -123.51258) (xy 129.979315 -123.530221)
			(xy 129.933347 -123.559945) (xy 129.883601 -123.582791) (xy 129.831099 -123.598287) (xy 129.776921 -123.606116)
			(xy 129.722179 -123.606116) (xy 129.668001 -123.598287) (xy 129.615499 -123.582791) (xy 129.565753 -123.559945)
			(xy 129.519785 -123.530221) (xy 129.498852 -123.51258) (xy 129.498598 -123.512326) (xy 129.491522 -123.506724)
			(xy 129.474597 -123.500488) (xy 129.465578 -123.500134) (xy 129.398522 -123.500134) (xy 129.389505 -123.500494)
			(xy 129.372588 -123.506739) (xy 129.365502 -123.512326) (xy 129.365502 -123.51258) (xy 129.365248 -123.51258)
			(xy 129.344306 -123.530207) (xy 129.298336 -123.559921) (xy 129.248591 -123.58276) (xy 129.196093 -123.598254)
			(xy 129.141919 -123.606085) (xy 129.11455 -123.60656) (xy 129.08752 -123.606077) (xy 129.034003 -123.598433)
			(xy 128.982102 -123.583307) (xy 128.932859 -123.561) (xy 128.88726 -123.531961) (xy 128.846221 -123.496772)
			(xy 128.828038 -123.476766) (xy 128.827784 -123.476512) (xy 128.820315 -123.468894) (xy 128.80085 -123.460207)
			(xy 128.790192 -123.459748) (xy 128.702562 -123.45924) (xy 128.683004 -123.467876) (xy 128.675638 -123.476258)
			(xy 128.657465 -123.495969) (xy 128.616566 -123.530632) (xy 128.571212 -123.559221) (xy 128.522299 -123.581171)
			(xy 128.470793 -123.59605) (xy 128.41771 -123.603564) (xy 128.390904 -123.60402) (xy 128.363652 -123.603533)
			(xy 128.309702 -123.595777) (xy 128.257405 -123.580421) (xy 128.207826 -123.55778) (xy 128.161974 -123.528313)
			(xy 128.120782 -123.49262) (xy 128.085089 -123.451429) (xy 128.055622 -123.405577) (xy 128.03298 -123.355998)
			(xy 128.017624 -123.303702) (xy 128.009867 -123.249752) (xy 98.704606 -123.249752) (xy 98.691765 -123.293495)
			(xy 98.669122 -123.34308) (xy 98.639654 -123.388939) (xy 98.603959 -123.430136) (xy 98.562765 -123.465834)
			(xy 98.516909 -123.495307) (xy 98.467326 -123.517953) (xy 98.415024 -123.533312) (xy 98.361069 -123.541072)
			(xy 98.333814 -123.541536) (xy 98.333306 -123.541536) (xy 98.322934 -123.541454) (xy 98.302222 -123.540311)
			(xy 98.291904 -123.53925) (xy 98.277358 -123.538193) (xy 98.248676 -123.5434) (xy 98.222628 -123.556487)
			(xy 98.20133 -123.576392) (xy 98.186512 -123.601496) (xy 98.179379 -123.629761) (xy 98.18051 -123.658891)
			(xy 98.184716 -123.672854) (xy 98.194067 -123.702464) (xy 98.204151 -123.763729) (xy 98.204782 -123.794774)
			(xy 98.204782 -123.795028) (xy 98.204292 -123.822276) (xy 98.196532 -123.876218) (xy 98.181176 -123.928506)
			(xy 98.158534 -123.978077) (xy 98.129068 -124.023921) (xy 98.093378 -124.065105) (xy 98.05219 -124.100791)
			(xy 98.006343 -124.130252) (xy 97.956771 -124.152889) (xy 97.904481 -124.168241) (xy 97.850538 -124.175995)
			(xy 97.796042 -124.175993) (xy 97.7421 -124.168236) (xy 97.689811 -124.152882) (xy 97.640239 -124.130242)
			(xy 97.594394 -124.100779) (xy 97.553208 -124.065091) (xy 97.51752 -124.023905) (xy 97.488057 -123.978059)
			(xy 97.465417 -123.928487) (xy 97.450063 -123.876198) (xy 97.442307 -123.822256) (xy 97.442306 -123.76776)
			(xy 84.486939 -123.76776) (xy 84.519014 -123.799835) (xy 84.55552 -123.847411) (xy 84.585504 -123.899345)
			(xy 84.608453 -123.954749) (xy 84.623974 -124.012674) (xy 84.631802 -124.07213) (xy 84.632292 -124.102114)
			(xy 84.632292 -124.215144) (xy 94.606616 -124.215144) (xy 94.610687 -124.159522) (xy 94.622813 -124.105085)
			(xy 94.642736 -124.052994) (xy 94.670032 -124.004359) (xy 94.704118 -123.960216) (xy 94.744267 -123.921507)
			(xy 94.789625 -123.889056) (xy 94.839225 -123.863555) (xy 94.892009 -123.845548) (xy 94.946852 -123.835418)
			(xy 95.002586 -123.833381) (xy 95.058023 -123.839481) (xy 95.11198 -123.853587) (xy 95.163309 -123.875399)
			(xy 95.210915 -123.904453) (xy 95.253783 -123.940128) (xy 95.291 -123.981665) (xy 95.321773 -124.028178)
			(xy 95.345445 -124.078675) (xy 95.361513 -124.132082) (xy 95.369633 -124.187258) (xy 95.370142 -124.215144)
			(xy 95.369633 -124.24303) (xy 95.361513 -124.298206) (xy 95.345445 -124.351613) (xy 95.321773 -124.40211)
			(xy 95.291 -124.448623) (xy 95.253783 -124.49016) (xy 95.210915 -124.525835) (xy 95.163309 -124.554889)
			(xy 95.11198 -124.576701) (xy 95.058023 -124.590807) (xy 95.002586 -124.596907) (xy 94.946852 -124.59487)
			(xy 94.892009 -124.58474) (xy 94.839225 -124.566733) (xy 94.789625 -124.541232) (xy 94.744267 -124.508781)
			(xy 94.704118 -124.470072) (xy 94.670032 -124.425929) (xy 94.642736 -124.377294) (xy 94.622813 -124.325203)
			(xy 94.610687 -124.270766) (xy 94.606616 -124.215144) (xy 84.632292 -124.215144) (xy 84.632292 -124.965714)
			(xy 84.631802 -124.995698) (xy 84.623974 -125.055154) (xy 84.608453 -125.113079) (xy 84.585504 -125.168483)
			(xy 84.55552 -125.220417) (xy 84.519014 -125.267993) (xy 84.476609 -125.310398) (xy 84.429033 -125.346904)
			(xy 84.377099 -125.376888) (xy 84.321695 -125.399837) (xy 84.26377 -125.415358) (xy 84.204314 -125.423186)
			(xy 84.144346 -125.423186) (xy 84.08489 -125.415358) (xy 84.026965 -125.399837) (xy 83.971561 -125.376888)
			(xy 83.919627 -125.346904) (xy 83.872051 -125.310398) (xy 83.829646 -125.267993) (xy 83.79314 -125.220417)
			(xy 83.763156 -125.168483) (xy 83.740207 -125.113079) (xy 83.724686 -125.055154) (xy 83.716858 -124.995698)
			(xy 83.716368 -124.965714) (xy 81.156695 -124.965714) (xy 81.130902 -125.570488) (xy 81.117235 -125.891544)
			(xy 95.17507 -125.891544) (xy 95.17551 -125.865229) (xy 95.182752 -125.8131) (xy 95.197077 -125.762457)
			(xy 95.218214 -125.714258) (xy 95.245765 -125.669415) (xy 95.279207 -125.628776) (xy 95.29826 -125.61062)
			(xy 95.305649 -125.603087) (xy 95.314182 -125.583816) (xy 95.31477 -125.573282) (xy 95.31477 -125.498606)
			(xy 95.31426 -125.488054) (xy 95.305712 -125.468758) (xy 95.29826 -125.461268) (xy 95.279188 -125.443129)
			(xy 95.245734 -125.402495) (xy 95.218178 -125.357651) (xy 95.197043 -125.309447) (xy 95.182729 -125.258797)
			(xy 95.175507 -125.206661) (xy 95.17507 -125.180344) (xy 95.175556 -125.153093) (xy 95.183312 -125.099145)
			(xy 95.198667 -125.04685) (xy 95.221309 -124.997273) (xy 95.250775 -124.951423) (xy 95.286466 -124.910232)
			(xy 95.327657 -124.874541) (xy 95.373507 -124.845075) (xy 95.423084 -124.822433) (xy 95.475379 -124.807078)
			(xy 95.529327 -124.799322) (xy 95.583829 -124.799322) (xy 95.637777 -124.807078) (xy 95.690072 -124.822433)
			(xy 95.739649 -124.845075) (xy 95.785499 -124.874541) (xy 95.82669 -124.910232) (xy 95.862381 -124.951423)
			(xy 95.891847 -124.997273) (xy 95.914489 -125.04685) (xy 95.929844 -125.099145) (xy 95.9376 -125.153093)
			(xy 95.938086 -125.180344) (xy 95.937652 -125.206659) (xy 95.930411 -125.258789) (xy 95.916086 -125.309433)
			(xy 95.894947 -125.357632) (xy 95.867395 -125.402474) (xy 95.83395 -125.443112) (xy 95.814896 -125.461268)
			(xy 95.807506 -125.468799) (xy 95.798975 -125.488072) (xy 95.798386 -125.498606) (xy 95.798386 -125.573282)
			(xy 95.798916 -125.583831) (xy 95.807451 -125.603127) (xy 95.814896 -125.61062) (xy 95.833953 -125.628774)
			(xy 95.867411 -125.669404) (xy 95.894969 -125.714244) (xy 95.916108 -125.762445) (xy 95.930424 -125.813093)
			(xy 95.937648 -125.865228) (xy 95.938086 -125.891544) (xy 95.9376 -125.918795) (xy 95.929844 -125.972743)
			(xy 95.914489 -126.025038) (xy 95.891847 -126.074615) (xy 95.862381 -126.120465) (xy 95.82669 -126.161656)
			(xy 95.785499 -126.197347) (xy 95.739649 -126.226813) (xy 95.690072 -126.249455) (xy 95.637777 -126.26481)
			(xy 95.583829 -126.272566) (xy 95.529327 -126.272566) (xy 95.475379 -126.26481) (xy 95.423084 -126.249455)
			(xy 95.373507 -126.226813) (xy 95.327657 -126.197347) (xy 95.286466 -126.161656) (xy 95.250775 -126.120465)
			(xy 95.221309 -126.074615) (xy 95.198667 -126.025038) (xy 95.183312 -125.972743) (xy 95.175556 -125.918795)
			(xy 95.17507 -125.891544) (xy 81.117235 -125.891544) (xy 81.070386 -126.992126) (xy 104.844342 -126.992126)
			(xy 104.844813 -126.964756) (xy 104.852628 -126.910577) (xy 104.868115 -126.858073) (xy 104.890956 -126.808326)
			(xy 104.920681 -126.762359) (xy 104.938322 -126.741428) (xy 104.938576 -126.741174) (xy 104.944147 -126.734077)
			(xy 104.950401 -126.717168) (xy 104.950768 -126.708154) (xy 104.950768 -126.641098) (xy 104.950419 -126.63208)
			(xy 104.944167 -126.615163) (xy 104.938576 -126.608078) (xy 104.938322 -126.608078) (xy 104.938322 -126.607824)
			(xy 104.920707 -126.586871) (xy 104.890982 -126.540906) (xy 104.868135 -126.491163) (xy 104.852637 -126.438664)
			(xy 104.844806 -126.384489) (xy 104.844803 -126.32975) (xy 104.852629 -126.275574) (xy 104.868121 -126.223073)
			(xy 104.890963 -126.173328) (xy 104.920683 -126.127361) (xy 104.938322 -126.106428) (xy 104.938576 -126.106174)
			(xy 104.944147 -126.099077) (xy 104.950401 -126.082168) (xy 104.950768 -126.073154) (xy 104.950768 -126.006098)
			(xy 104.950419 -125.99708) (xy 104.944167 -125.980163) (xy 104.938576 -125.973078) (xy 104.938322 -125.973078)
			(xy 104.938322 -125.972824) (xy 104.920707 -125.951871) (xy 104.890982 -125.905906) (xy 104.868135 -125.856163)
			(xy 104.852637 -125.803664) (xy 104.844806 -125.749489) (xy 104.844803 -125.69475) (xy 104.852629 -125.640574)
			(xy 104.868121 -125.588073) (xy 104.890963 -125.538328) (xy 104.920683 -125.492361) (xy 104.938322 -125.471428)
			(xy 104.938576 -125.471174) (xy 104.944147 -125.464077) (xy 104.950401 -125.447168) (xy 104.950768 -125.438154)
			(xy 104.950768 -125.371098) (xy 104.950419 -125.36208) (xy 104.944167 -125.345163) (xy 104.938576 -125.338078)
			(xy 104.938322 -125.338078) (xy 104.938322 -125.337824) (xy 104.920684 -125.316891) (xy 104.890971 -125.270919)
			(xy 104.868135 -125.221172) (xy 104.852644 -125.168671) (xy 104.844816 -125.114495) (xy 104.844342 -125.087126)
			(xy 104.844828 -125.059875) (xy 104.852584 -125.005927) (xy 104.867939 -124.953632) (xy 104.890581 -124.904055)
			(xy 104.920047 -124.858205) (xy 104.955738 -124.817014) (xy 104.996929 -124.781323) (xy 105.042779 -124.751857)
			(xy 105.092356 -124.729215) (xy 105.144651 -124.71386) (xy 105.198599 -124.706104) (xy 105.253101 -124.706104)
			(xy 105.307049 -124.71386) (xy 105.359344 -124.729215) (xy 105.408921 -124.751857) (xy 105.454771 -124.781323)
			(xy 105.495962 -124.817014) (xy 105.531653 -124.858205) (xy 105.561119 -124.904055) (xy 105.583761 -124.953632)
			(xy 105.599116 -125.005927) (xy 105.606872 -125.059875) (xy 105.607358 -125.087126) (xy 105.606917 -125.114497)
			(xy 105.599095 -125.168678) (xy 105.583601 -125.221182) (xy 105.560753 -125.270928) (xy 105.531022 -125.316893)
			(xy 105.513378 -125.337824) (xy 105.513124 -125.338078) (xy 105.507532 -125.34516) (xy 105.50129 -125.362081)
			(xy 105.500932 -125.371098) (xy 105.500932 -125.438154) (xy 105.501304 -125.447169) (xy 105.50754 -125.464087)
			(xy 105.513124 -125.471174) (xy 105.513378 -125.471174) (xy 105.513378 -125.471428) (xy 105.531044 -125.49234)
			(xy 105.560767 -125.538312) (xy 105.583611 -125.588061) (xy 105.599105 -125.640567) (xy 105.606931 -125.694748)
			(xy 105.606928 -125.749491) (xy 105.599097 -125.803672) (xy 105.583597 -125.856175) (xy 105.560748 -125.905923)
			(xy 105.53102 -125.951891) (xy 105.513378 -125.972824) (xy 105.513124 -125.973078) (xy 105.507532 -125.98016)
			(xy 105.50129 -125.997081) (xy 105.500932 -126.006098) (xy 105.500932 -126.073154) (xy 105.501304 -126.082169)
			(xy 105.50754 -126.099087) (xy 105.513124 -126.106174) (xy 105.513378 -126.106174) (xy 105.513378 -126.106428)
			(xy 105.531044 -126.12734) (xy 105.560767 -126.173312) (xy 105.583611 -126.223061) (xy 105.599105 -126.275567)
			(xy 105.606931 -126.329748) (xy 105.606928 -126.384491) (xy 105.599097 -126.438672) (xy 105.583597 -126.491175)
			(xy 105.560748 -126.540923) (xy 105.53102 -126.586891) (xy 105.513378 -126.607824) (xy 105.513124 -126.608078)
			(xy 105.507532 -126.61516) (xy 105.50129 -126.632081) (xy 105.500932 -126.641098) (xy 105.500932 -126.708154)
			(xy 105.501304 -126.717169) (xy 105.50754 -126.734087) (xy 105.513124 -126.741174) (xy 105.513378 -126.741174)
			(xy 105.513378 -126.741428) (xy 105.530993 -126.762379) (xy 105.56071 -126.808346) (xy 105.58355 -126.858089)
			(xy 105.599047 -126.910586) (xy 105.606881 -126.964758) (xy 105.607358 -126.992126) (xy 105.606872 -127.019377)
			(xy 105.602208 -127.051816) (xy 107.500166 -127.051816) (xy 107.500625 -127.024445) (xy 107.508442 -126.970265)
			(xy 107.523932 -126.917762) (xy 107.546776 -126.868015) (xy 107.576503 -126.822049) (xy 107.594146 -126.801118)
			(xy 107.5944 -126.800864) (xy 107.599966 -126.793763) (xy 107.606225 -126.776857) (xy 107.606592 -126.767844)
			(xy 107.606592 -126.700788) (xy 107.606242 -126.69177) (xy 107.59999 -126.674853) (xy 107.5944 -126.667768)
			(xy 107.594146 -126.667768) (xy 107.594146 -126.667514) (xy 107.57652 -126.646569) (xy 107.546793 -126.600604)
			(xy 107.523946 -126.55086) (xy 107.508448 -126.498359) (xy 107.500617 -126.444182) (xy 107.500615 -126.389442)
			(xy 107.508442 -126.335264) (xy 107.523937 -126.282763) (xy 107.546782 -126.233017) (xy 107.576506 -126.18705)
			(xy 107.594146 -126.166118) (xy 107.5944 -126.165864) (xy 107.599966 -126.158763) (xy 107.606225 -126.141857)
			(xy 107.606592 -126.132844) (xy 107.606592 -126.065788) (xy 107.606242 -126.05677) (xy 107.59999 -126.039853)
			(xy 107.5944 -126.032768) (xy 107.594146 -126.032768) (xy 107.594146 -126.032514) (xy 107.57652 -126.011569)
			(xy 107.546793 -125.965604) (xy 107.523946 -125.91586) (xy 107.508448 -125.863359) (xy 107.500617 -125.809182)
			(xy 107.500615 -125.754442) (xy 107.508442 -125.700264) (xy 107.523937 -125.647763) (xy 107.546782 -125.598017)
			(xy 107.576506 -125.55205) (xy 107.594146 -125.531118) (xy 107.5944 -125.530864) (xy 107.599966 -125.523763)
			(xy 107.606225 -125.506857) (xy 107.606592 -125.497844) (xy 107.606592 -125.430788) (xy 107.606242 -125.42177)
			(xy 107.59999 -125.404853) (xy 107.5944 -125.397768) (xy 107.594146 -125.397768) (xy 107.594146 -125.397514)
			(xy 107.576507 -125.376582) (xy 107.546794 -125.33061) (xy 107.523957 -125.280862) (xy 107.508466 -125.228361)
			(xy 107.500639 -125.174185) (xy 107.500166 -125.146816) (xy 107.500652 -125.119565) (xy 107.508408 -125.065617)
			(xy 107.523763 -125.013322) (xy 107.546405 -124.963745) (xy 107.575871 -124.917895) (xy 107.611562 -124.876704)
			(xy 107.652753 -124.841013) (xy 107.698603 -124.811547) (xy 107.74818 -124.788905) (xy 107.800475 -124.77355)
			(xy 107.854423 -124.765794) (xy 107.908925 -124.765794) (xy 107.962873 -124.77355) (xy 108.015168 -124.788905)
			(xy 108.064745 -124.811547) (xy 108.110595 -124.841013) (xy 108.151786 -124.876704) (xy 108.158044 -124.883926)
			(xy 116.439948 -124.883926) (xy 116.444019 -124.828304) (xy 116.456145 -124.773867) (xy 116.476068 -124.721776)
			(xy 116.503364 -124.673141) (xy 116.53745 -124.628998) (xy 116.577599 -124.590289) (xy 116.622957 -124.557838)
			(xy 116.672557 -124.532337) (xy 116.725341 -124.51433) (xy 116.780184 -124.5042) (xy 116.835918 -124.502163)
			(xy 116.891355 -124.508263) (xy 116.945312 -124.522369) (xy 116.996641 -124.544181) (xy 117.044247 -124.573235)
			(xy 117.087115 -124.60891) (xy 117.124332 -124.650447) (xy 117.155105 -124.69696) (xy 117.178777 -124.747457)
			(xy 117.194845 -124.800864) (xy 117.202965 -124.85604) (xy 117.203474 -124.883926) (xy 117.202965 -124.911812)
			(xy 117.195369 -124.963428) (xy 124.772926 -124.963428) (xy 124.776997 -124.907806) (xy 124.789123 -124.853369)
			(xy 124.809046 -124.801278) (xy 124.836342 -124.752643) (xy 124.870428 -124.7085) (xy 124.910577 -124.669791)
			(xy 124.955935 -124.63734) (xy 125.005535 -124.611839) (xy 125.058319 -124.593832) (xy 125.113162 -124.583702)
			(xy 125.168896 -124.581665) (xy 125.224333 -124.587765) (xy 125.27829 -124.601871) (xy 125.329619 -124.623683)
			(xy 125.377225 -124.652737) (xy 125.420093 -124.688412) (xy 125.45731 -124.729949) (xy 125.488083 -124.776462)
			(xy 125.511755 -124.826959) (xy 125.527823 -124.880366) (xy 125.535943 -124.935542) (xy 125.536452 -124.963428)
			(xy 125.536137 -124.9807) (xy 126.928878 -124.9807) (xy 126.932949 -124.925078) (xy 126.945075 -124.870641)
			(xy 126.964998 -124.81855) (xy 126.992294 -124.769915) (xy 127.02638 -124.725772) (xy 127.066529 -124.687063)
			(xy 127.111887 -124.654612) (xy 127.161487 -124.629111) (xy 127.214271 -124.611104) (xy 127.269114 -124.600974)
			(xy 127.324848 -124.598937) (xy 127.380285 -124.605037) (xy 127.434242 -124.619143) (xy 127.485571 -124.640955)
			(xy 127.533177 -124.670009) (xy 127.576045 -124.705684) (xy 127.613262 -124.747221) (xy 127.644035 -124.793734)
			(xy 127.667707 -124.844231) (xy 127.683775 -124.897638) (xy 127.691895 -124.952814) (xy 127.692404 -124.9807)
			(xy 127.691895 -125.008586) (xy 127.683775 -125.063762) (xy 127.667707 -125.117169) (xy 127.644035 -125.167666)
			(xy 127.613262 -125.214179) (xy 127.576045 -125.255716) (xy 127.533177 -125.291391) (xy 127.485571 -125.320445)
			(xy 127.434242 -125.342257) (xy 127.380285 -125.356363) (xy 127.324848 -125.362463) (xy 127.269114 -125.360426)
			(xy 127.214271 -125.350296) (xy 127.161487 -125.332289) (xy 127.111887 -125.306788) (xy 127.066529 -125.274337)
			(xy 127.02638 -125.235628) (xy 126.992294 -125.191485) (xy 126.964998 -125.14285) (xy 126.945075 -125.090759)
			(xy 126.932949 -125.036322) (xy 126.928878 -124.9807) (xy 125.536137 -124.9807) (xy 125.535943 -124.991314)
			(xy 125.527823 -125.04649) (xy 125.511755 -125.099897) (xy 125.488083 -125.150394) (xy 125.45731 -125.196907)
			(xy 125.420093 -125.238444) (xy 125.377225 -125.274119) (xy 125.329619 -125.303173) (xy 125.27829 -125.324985)
			(xy 125.224333 -125.339091) (xy 125.168896 -125.345191) (xy 125.113162 -125.343154) (xy 125.058319 -125.333024)
			(xy 125.005535 -125.315017) (xy 124.955935 -125.289516) (xy 124.910577 -125.257065) (xy 124.870428 -125.218356)
			(xy 124.836342 -125.174213) (xy 124.809046 -125.125578) (xy 124.789123 -125.073487) (xy 124.776997 -125.01905)
			(xy 124.772926 -124.963428) (xy 117.195369 -124.963428) (xy 117.194845 -124.966988) (xy 117.178777 -125.020395)
			(xy 117.155105 -125.070892) (xy 117.124332 -125.117405) (xy 117.087115 -125.158942) (xy 117.044247 -125.194617)
			(xy 116.996641 -125.223671) (xy 116.945312 -125.245483) (xy 116.891355 -125.259589) (xy 116.835918 -125.265689)
			(xy 116.780184 -125.263652) (xy 116.725341 -125.253522) (xy 116.672557 -125.235515) (xy 116.622957 -125.210014)
			(xy 116.577599 -125.177563) (xy 116.53745 -125.138854) (xy 116.503364 -125.094711) (xy 116.476068 -125.046076)
			(xy 116.456145 -124.993985) (xy 116.444019 -124.939548) (xy 116.439948 -124.883926) (xy 108.158044 -124.883926)
			(xy 108.187477 -124.917895) (xy 108.216943 -124.963745) (xy 108.239585 -125.013322) (xy 108.25494 -125.065617)
			(xy 108.262696 -125.119565) (xy 108.263182 -125.146816) (xy 108.26273 -125.174187) (xy 108.254909 -125.228367)
			(xy 108.239417 -125.28087) (xy 108.216572 -125.330617) (xy 108.186845 -125.376583) (xy 108.169202 -125.397514)
			(xy 108.168948 -125.397768) (xy 108.164544 -125.403356) (xy 131.644136 -125.403356) (xy 131.644626 -125.375987)
			(xy 131.652437 -125.321808) (xy 131.66792 -125.269305) (xy 131.690756 -125.219558) (xy 131.720477 -125.17359)
			(xy 131.738116 -125.152658) (xy 131.73837 -125.152404) (xy 131.743969 -125.145326) (xy 131.750206 -125.128402)
			(xy 131.750562 -125.119384) (xy 131.750562 -125.052328) (xy 131.7502 -125.043312) (xy 131.743957 -125.026394)
			(xy 131.73837 -125.019308) (xy 131.738116 -125.019308) (xy 131.738116 -125.019054) (xy 131.720491 -124.99811)
			(xy 131.690777 -124.952141) (xy 131.667938 -124.902396) (xy 131.652443 -124.849898) (xy 131.644612 -124.795724)
			(xy 131.644136 -124.768356) (xy 131.644622 -124.741105) (xy 131.652378 -124.687157) (xy 131.667733 -124.634862)
			(xy 131.690375 -124.585285) (xy 131.719841 -124.539435) (xy 131.755532 -124.498244) (xy 131.796723 -124.462553)
			(xy 131.842573 -124.433087) (xy 131.89215 -124.410445) (xy 131.944445 -124.39509) (xy 131.998393 -124.387334)
			(xy 132.052895 -124.387334) (xy 132.106843 -124.39509) (xy 132.159138 -124.410445) (xy 132.208715 -124.433087)
			(xy 132.254565 -124.462553) (xy 132.295756 -124.498244) (xy 132.331447 -124.539435) (xy 132.360913 -124.585285)
			(xy 132.383555 -124.634862) (xy 132.39891 -124.687157) (xy 132.406666 -124.741105) (xy 132.407152 -124.768356)
			(xy 132.406672 -124.795726) (xy 132.398859 -124.849905) (xy 132.383374 -124.902408) (xy 132.360535 -124.952155)
			(xy 132.330813 -124.998122) (xy 132.313172 -125.019054) (xy 132.312918 -125.019308) (xy 132.307324 -125.02639)
			(xy 132.301082 -125.04331) (xy 132.300726 -125.052328) (xy 132.300726 -125.119384) (xy 132.301085 -125.128401)
			(xy 132.307331 -125.145318) (xy 132.312918 -125.152404) (xy 132.313172 -125.152404) (xy 132.313172 -125.152658)
			(xy 132.330801 -125.173599) (xy 132.360515 -125.219569) (xy 132.383353 -125.269314) (xy 132.398847 -125.321813)
			(xy 132.406677 -125.375987) (xy 132.407152 -125.403356) (xy 132.406666 -125.430607) (xy 132.39891 -125.484555)
			(xy 132.383555 -125.53685) (xy 132.360913 -125.586427) (xy 132.331447 -125.632277) (xy 132.295756 -125.673468)
			(xy 132.254565 -125.709159) (xy 132.208715 -125.738625) (xy 132.159138 -125.761267) (xy 132.106843 -125.776622)
			(xy 132.052895 -125.784378) (xy 131.998393 -125.784378) (xy 131.944445 -125.776622) (xy 131.89215 -125.761267)
			(xy 131.842573 -125.738625) (xy 131.796723 -125.709159) (xy 131.755532 -125.673468) (xy 131.719841 -125.632277)
			(xy 131.690375 -125.586427) (xy 131.667733 -125.53685) (xy 131.652378 -125.484555) (xy 131.644622 -125.430607)
			(xy 131.644136 -125.403356) (xy 108.164544 -125.403356) (xy 108.163362 -125.404855) (xy 108.157116 -125.421772)
			(xy 108.156756 -125.430788) (xy 108.156756 -125.497844) (xy 108.157128 -125.50686) (xy 108.163364 -125.523777)
			(xy 108.168948 -125.530864) (xy 108.169202 -125.530864) (xy 108.169202 -125.531118) (xy 108.186857 -125.552039)
			(xy 108.216579 -125.598009) (xy 108.239422 -125.647758) (xy 108.254916 -125.700261) (xy 108.262742 -125.754441)
			(xy 108.26274 -125.809183) (xy 108.25491 -125.863362) (xy 108.239413 -125.915865) (xy 108.216567 -125.965612)
			(xy 108.186843 -126.011581) (xy 108.169202 -126.032514) (xy 108.168948 -126.032768) (xy 108.163362 -126.039855)
			(xy 108.157116 -126.056772) (xy 108.156756 -126.065788) (xy 108.156756 -126.132844) (xy 108.157128 -126.14186)
			(xy 108.163364 -126.158777) (xy 108.168948 -126.165864) (xy 108.169202 -126.166118) (xy 108.186022 -126.186075)
			(xy 108.193742 -126.197868) (xy 116.44579 -126.197868) (xy 116.449861 -126.142246) (xy 116.461987 -126.087809)
			(xy 116.48191 -126.035718) (xy 116.509206 -125.987083) (xy 116.543292 -125.94294) (xy 116.583441 -125.904231)
			(xy 116.628799 -125.87178) (xy 116.678399 -125.846279) (xy 116.731183 -125.828272) (xy 116.786026 -125.818142)
			(xy 116.84176 -125.816105) (xy 116.897197 -125.822205) (xy 116.951154 -125.836311) (xy 117.002483 -125.858123)
			(xy 117.050089 -125.887177) (xy 117.065409 -125.899926) (xy 118.631714 -125.899926) (xy 118.635785 -125.844304)
			(xy 118.647911 -125.789867) (xy 118.667834 -125.737776) (xy 118.69513 -125.689141) (xy 118.729216 -125.644998)
			(xy 118.769365 -125.606289) (xy 118.814723 -125.573838) (xy 118.864323 -125.548337) (xy 118.917107 -125.53033)
			(xy 118.97195 -125.5202) (xy 119.027684 -125.518163) (xy 119.083121 -125.524263) (xy 119.137078 -125.538369)
			(xy 119.188407 -125.560181) (xy 119.236013 -125.589235) (xy 119.278881 -125.62491) (xy 119.316098 -125.666447)
			(xy 119.346871 -125.71296) (xy 119.370543 -125.763457) (xy 119.386611 -125.816864) (xy 119.394731 -125.87204)
			(xy 119.39524 -125.899926) (xy 119.394731 -125.927812) (xy 119.387135 -125.979428) (xy 124.772926 -125.979428)
			(xy 124.776997 -125.923806) (xy 124.789123 -125.869369) (xy 124.809046 -125.817278) (xy 124.836342 -125.768643)
			(xy 124.870428 -125.7245) (xy 124.910577 -125.685791) (xy 124.955935 -125.65334) (xy 125.005535 -125.627839)
			(xy 125.058319 -125.609832) (xy 125.113162 -125.599702) (xy 125.168896 -125.597665) (xy 125.224333 -125.603765)
			(xy 125.27829 -125.617871) (xy 125.329619 -125.639683) (xy 125.377225 -125.668737) (xy 125.420093 -125.704412)
			(xy 125.45731 -125.745949) (xy 125.488083 -125.792462) (xy 125.511755 -125.842959) (xy 125.527823 -125.896366)
			(xy 125.535943 -125.951542) (xy 125.536151 -125.962918) (xy 127.251204 -125.962918) (xy 127.255275 -125.907296)
			(xy 127.267401 -125.852859) (xy 127.287324 -125.800768) (xy 127.31462 -125.752133) (xy 127.348706 -125.70799)
			(xy 127.388855 -125.669281) (xy 127.434213 -125.63683) (xy 127.483813 -125.611329) (xy 127.536597 -125.593322)
			(xy 127.59144 -125.583192) (xy 127.647174 -125.581155) (xy 127.702611 -125.587255) (xy 127.756568 -125.601361)
			(xy 127.807897 -125.623173) (xy 127.855503 -125.652227) (xy 127.898371 -125.687902) (xy 127.935588 -125.729439)
			(xy 127.966361 -125.775952) (xy 127.990033 -125.826449) (xy 127.998231 -125.853698) (xy 132.584698 -125.853698)
			(xy 132.585163 -125.826328) (xy 132.592981 -125.772149) (xy 132.608471 -125.719646) (xy 132.631313 -125.669899)
			(xy 132.661037 -125.623932) (xy 132.678678 -125.603) (xy 132.678932 -125.602746) (xy 132.684509 -125.595653)
			(xy 132.69076 -125.578741) (xy 132.691124 -125.569726) (xy 132.691124 -125.50267) (xy 132.690776 -125.493652)
			(xy 132.684522 -125.476736) (xy 132.678932 -125.46965) (xy 132.678678 -125.46965) (xy 132.678678 -125.469396)
			(xy 132.66102 -125.448479) (xy 132.631312 -125.402502) (xy 132.60848 -125.35275) (xy 132.592993 -125.300246)
			(xy 132.58517 -125.246068) (xy 132.584698 -125.218698) (xy 132.585184 -125.191447) (xy 132.59294 -125.137499)
			(xy 132.608295 -125.085204) (xy 132.630937 -125.035627) (xy 132.660403 -124.989777) (xy 132.696094 -124.948586)
			(xy 132.737285 -124.912895) (xy 132.783135 -124.883429) (xy 132.832712 -124.860787) (xy 132.885007 -124.845432)
			(xy 132.938955 -124.837676) (xy 132.993457 -124.837676) (xy 133.047405 -124.845432) (xy 133.0997 -124.860787)
			(xy 133.149277 -124.883429) (xy 133.195127 -124.912895) (xy 133.236318 -124.948586) (xy 133.272009 -124.989777)
			(xy 133.301475 -125.035627) (xy 133.324117 -125.085204) (xy 133.339472 -125.137499) (xy 133.347228 -125.191447)
			(xy 133.347714 -125.218698) (xy 133.347243 -125.246068) (xy 133.339426 -125.300247) (xy 133.323938 -125.35275)
			(xy 133.301097 -125.402497) (xy 133.271374 -125.448464) (xy 133.253734 -125.469396) (xy 133.25348 -125.46965)
			(xy 133.247906 -125.476745) (xy 133.241652 -125.493655) (xy 133.241288 -125.50267) (xy 133.241288 -125.569726)
			(xy 133.241635 -125.578744) (xy 133.24789 -125.59566) (xy 133.25348 -125.602746) (xy 133.253734 -125.602746)
			(xy 133.253734 -125.603) (xy 133.271392 -125.623917) (xy 133.3011 -125.669894) (xy 133.323931 -125.719646)
			(xy 133.339418 -125.77215) (xy 133.347242 -125.826328) (xy 133.347714 -125.853698) (xy 133.347228 -125.880949)
			(xy 133.339472 -125.934897) (xy 133.324117 -125.987192) (xy 133.301475 -126.036769) (xy 133.272009 -126.082619)
			(xy 133.236318 -126.12381) (xy 133.195127 -126.159501) (xy 133.149277 -126.188967) (xy 133.0997 -126.211609)
			(xy 133.047405 -126.226964) (xy 132.993457 -126.23472) (xy 132.938955 -126.23472) (xy 132.885007 -126.226964)
			(xy 132.832712 -126.211609) (xy 132.783135 -126.188967) (xy 132.737285 -126.159501) (xy 132.696094 -126.12381)
			(xy 132.660403 -126.082619) (xy 132.630937 -126.036769) (xy 132.608295 -125.987192) (xy 132.59294 -125.934897)
			(xy 132.585184 -125.880949) (xy 132.584698 -125.853698) (xy 127.998231 -125.853698) (xy 128.006101 -125.879856)
			(xy 128.014221 -125.935032) (xy 128.01473 -125.962918) (xy 128.014221 -125.990804) (xy 128.006101 -126.04598)
			(xy 127.990033 -126.099387) (xy 127.966361 -126.149884) (xy 127.935588 -126.196397) (xy 127.898371 -126.237934)
			(xy 127.855503 -126.273609) (xy 127.807897 -126.302663) (xy 127.756568 -126.324475) (xy 127.702611 -126.338581)
			(xy 127.647174 -126.344681) (xy 127.59144 -126.342644) (xy 127.536597 -126.332514) (xy 127.483813 -126.314507)
			(xy 127.434213 -126.289006) (xy 127.388855 -126.256555) (xy 127.348706 -126.217846) (xy 127.31462 -126.173703)
			(xy 127.287324 -126.125068) (xy 127.267401 -126.072977) (xy 127.255275 -126.01854) (xy 127.251204 -125.962918)
			(xy 125.536151 -125.962918) (xy 125.536452 -125.979428) (xy 125.535943 -126.007314) (xy 125.527823 -126.06249)
			(xy 125.511755 -126.115897) (xy 125.488083 -126.166394) (xy 125.45731 -126.212907) (xy 125.420093 -126.254444)
			(xy 125.377225 -126.290119) (xy 125.329619 -126.319173) (xy 125.27829 -126.340985) (xy 125.224333 -126.355091)
			(xy 125.168896 -126.361191) (xy 125.113162 -126.359154) (xy 125.058319 -126.349024) (xy 125.005535 -126.331017)
			(xy 124.955935 -126.305516) (xy 124.910577 -126.273065) (xy 124.870428 -126.234356) (xy 124.836342 -126.190213)
			(xy 124.809046 -126.141578) (xy 124.789123 -126.089487) (xy 124.776997 -126.03505) (xy 124.772926 -125.979428)
			(xy 119.387135 -125.979428) (xy 119.386611 -125.982988) (xy 119.370543 -126.036395) (xy 119.346871 -126.086892)
			(xy 119.316098 -126.133405) (xy 119.278881 -126.174942) (xy 119.236013 -126.210617) (xy 119.188407 -126.239671)
			(xy 119.137078 -126.261483) (xy 119.083121 -126.275589) (xy 119.027684 -126.281689) (xy 118.97195 -126.279652)
			(xy 118.917107 -126.269522) (xy 118.864323 -126.251515) (xy 118.814723 -126.226014) (xy 118.769365 -126.193563)
			(xy 118.729216 -126.154854) (xy 118.69513 -126.110711) (xy 118.667834 -126.062076) (xy 118.647911 -126.009985)
			(xy 118.635785 -125.955548) (xy 118.631714 -125.899926) (xy 117.065409 -125.899926) (xy 117.092957 -125.922852)
			(xy 117.130174 -125.964389) (xy 117.160947 -126.010902) (xy 117.184619 -126.061399) (xy 117.200687 -126.114806)
			(xy 117.208807 -126.169982) (xy 117.209316 -126.197868) (xy 117.208807 -126.225754) (xy 117.200687 -126.28093)
			(xy 117.184619 -126.334337) (xy 117.160947 -126.384834) (xy 117.130174 -126.431347) (xy 117.092957 -126.472884)
			(xy 117.050089 -126.508559) (xy 117.014377 -126.530354) (xy 133.79323 -126.530354) (xy 133.79377 -126.50269)
			(xy 133.801763 -126.447941) (xy 133.817574 -126.39492) (xy 133.840871 -126.344735) (xy 133.871169 -126.298439)
			(xy 133.907831 -126.257) (xy 133.95009 -126.221287) (xy 133.973316 -126.20625) (xy 133.982968 -126.199582)
			(xy 133.995426 -126.179744) (xy 133.997192 -126.16815) (xy 134.005066 -126.08814) (xy 134.005661 -126.076503)
			(xy 133.997606 -126.054668) (xy 133.989572 -126.04623) (xy 133.989318 -126.045976) (xy 133.970746 -126.027885)
			(xy 133.938166 -125.987556) (xy 133.911352 -125.943184) (xy 133.890797 -125.895587) (xy 133.876882 -125.845644)
			(xy 133.869863 -125.794277) (xy 133.86943 -125.768354) (xy 133.869835 -125.7411) (xy 133.877599 -125.687147)
			(xy 133.892962 -125.634849) (xy 133.915611 -125.585269) (xy 133.945086 -125.539417) (xy 133.980786 -125.498226)
			(xy 134.021984 -125.462535) (xy 134.067843 -125.433071) (xy 134.117428 -125.410432) (xy 134.169729 -125.395081)
			(xy 134.223684 -125.387329) (xy 134.250938 -125.386846) (xy 134.278307 -125.387337) (xy 134.332486 -125.395147)
			(xy 134.384989 -125.41063) (xy 134.434737 -125.433466) (xy 134.480704 -125.463187) (xy 134.501636 -125.480826)
			(xy 134.50189 -125.48108) (xy 134.508968 -125.486678) (xy 134.525892 -125.492916) (xy 134.53491 -125.493272)
			(xy 134.601966 -125.493272) (xy 134.610982 -125.492905) (xy 134.627899 -125.486665) (xy 134.634986 -125.48108)
			(xy 134.634986 -125.480826) (xy 134.63524 -125.480826) (xy 134.656187 -125.463206) (xy 134.702155 -125.43349)
			(xy 134.751899 -125.41065) (xy 134.804397 -125.395155) (xy 134.85857 -125.387322) (xy 134.885938 -125.386846)
			(xy 134.913188 -125.387342) (xy 134.967133 -125.395103) (xy 135.019425 -125.41046) (xy 135.068999 -125.433103)
			(xy 135.114847 -125.462569) (xy 135.156036 -125.498259) (xy 135.191727 -125.539447) (xy 135.221194 -125.585294)
			(xy 135.243837 -125.634868) (xy 135.259195 -125.687159) (xy 135.266957 -125.741104) (xy 135.267446 -125.768354)
			(xy 135.266915 -125.797271) (xy 135.258192 -125.854442) (xy 135.240938 -125.909642) (xy 135.215548 -125.961604)
			(xy 135.182606 -126.009138) (xy 135.142865 -126.051154) (xy 135.12038 -126.069344) (xy 135.111559 -126.076938)
			(xy 135.101384 -126.097849) (xy 135.100822 -126.109476) (xy 135.100822 -126.189232) (xy 135.101349 -126.200866)
			(xy 135.111546 -126.221775) (xy 135.12038 -126.229364) (xy 135.142842 -126.24758) (xy 135.18258 -126.289594)
			(xy 135.215522 -126.337124) (xy 135.240914 -126.38908) (xy 135.258175 -126.444273) (xy 135.266908 -126.501439)
			(xy 135.267446 -126.530354) (xy 135.266902 -126.557604) (xy 135.259152 -126.61155) (xy 135.247051 -126.652782)
			(xy 135.538718 -126.652782) (xy 135.539169 -126.625411) (xy 135.54699 -126.571231) (xy 135.562482 -126.518728)
			(xy 135.585327 -126.468981) (xy 135.615055 -126.423015) (xy 135.632698 -126.402084) (xy 135.632952 -126.40183)
			(xy 135.638538 -126.394744) (xy 135.644784 -126.377826) (xy 135.645144 -126.36881) (xy 135.645144 -126.301754)
			(xy 135.644773 -126.292738) (xy 135.638537 -126.275821) (xy 135.632952 -126.268734) (xy 135.632698 -126.268734)
			(xy 135.632698 -126.26848) (xy 135.615041 -126.247561) (xy 135.585319 -126.20159) (xy 135.562476 -126.151841)
			(xy 135.546983 -126.099337) (xy 135.539157 -126.045158) (xy 135.539159 -125.990415) (xy 135.546989 -125.936236)
			(xy 135.562486 -125.883733) (xy 135.585332 -125.833986) (xy 135.615057 -125.788017) (xy 135.632698 -125.767084)
			(xy 135.632952 -125.76683) (xy 135.638538 -125.759744) (xy 135.644784 -125.742826) (xy 135.645144 -125.73381)
			(xy 135.645144 -125.666754) (xy 135.644773 -125.657738) (xy 135.638537 -125.640821) (xy 135.632952 -125.633734)
			(xy 135.632698 -125.633734) (xy 135.632698 -125.63348) (xy 135.615041 -125.612561) (xy 135.585319 -125.56659)
			(xy 135.562476 -125.516841) (xy 135.546983 -125.464337) (xy 135.539157 -125.410158) (xy 135.539159 -125.355415)
			(xy 135.546989 -125.301236) (xy 135.562486 -125.248733) (xy 135.585332 -125.198986) (xy 135.615057 -125.153017)
			(xy 135.632698 -125.132084) (xy 135.632952 -125.13183) (xy 135.638538 -125.124744) (xy 135.644784 -125.107826)
			(xy 135.645144 -125.09881) (xy 135.645144 -125.031754) (xy 135.644773 -125.022738) (xy 135.638537 -125.005821)
			(xy 135.632952 -124.998734) (xy 135.632698 -124.998734) (xy 135.632698 -124.99848) (xy 135.615083 -124.977529)
			(xy 135.585367 -124.931561) (xy 135.562527 -124.881819) (xy 135.54703 -124.829322) (xy 135.539196 -124.77515)
			(xy 135.538718 -124.747782) (xy 135.539204 -124.720531) (xy 135.54696 -124.666583) (xy 135.562315 -124.614288)
			(xy 135.584957 -124.564711) (xy 135.614423 -124.518861) (xy 135.650114 -124.47767) (xy 135.691305 -124.441979)
			(xy 135.737155 -124.412513) (xy 135.786732 -124.389871) (xy 135.839027 -124.374516) (xy 135.892975 -124.36676)
			(xy 135.947477 -124.36676) (xy 136.001425 -124.374516) (xy 136.05372 -124.389871) (xy 136.103297 -124.412513)
			(xy 136.149147 -124.441979) (xy 136.190338 -124.47767) (xy 136.226029 -124.518861) (xy 136.255495 -124.564711)
			(xy 136.278137 -124.614288) (xy 136.293492 -124.666583) (xy 136.301248 -124.720531) (xy 136.301734 -124.747782)
			(xy 136.301273 -124.775153) (xy 136.293457 -124.829333) (xy 136.277967 -124.881836) (xy 136.255124 -124.931583)
			(xy 136.225397 -124.977549) (xy 136.207754 -124.99848) (xy 136.2075 -124.998734) (xy 136.201935 -125.005835)
			(xy 136.195675 -125.022741) (xy 136.195308 -125.031754) (xy 136.195308 -125.09881) (xy 136.195659 -125.107828)
			(xy 136.20191 -125.124745) (xy 136.2075 -125.13183) (xy 136.207754 -125.13183) (xy 136.207754 -125.132084)
			(xy 136.225378 -125.153031) (xy 136.255105 -125.198996) (xy 136.277952 -125.248739) (xy 136.293451 -125.30124)
			(xy 136.301282 -125.355416) (xy 136.301284 -125.410156) (xy 136.293457 -125.464334) (xy 136.277962 -125.516835)
			(xy 136.255118 -125.566581) (xy 136.225394 -125.612548) (xy 136.207754 -125.63348) (xy 136.2075 -125.633734)
			(xy 136.201935 -125.640835) (xy 136.195675 -125.657741) (xy 136.195308 -125.666754) (xy 136.195308 -125.73381)
			(xy 136.195659 -125.742828) (xy 136.20191 -125.759745) (xy 136.2075 -125.76683) (xy 136.207754 -125.76683)
			(xy 136.207754 -125.767084) (xy 136.225378 -125.788031) (xy 136.255105 -125.833996) (xy 136.277952 -125.883739)
			(xy 136.293451 -125.93624) (xy 136.301282 -125.990416) (xy 136.301284 -126.045156) (xy 136.293457 -126.099334)
			(xy 136.277962 -126.151835) (xy 136.255118 -126.201581) (xy 136.225394 -126.247548) (xy 136.207754 -126.26848)
			(xy 136.2075 -126.268734) (xy 136.201935 -126.275835) (xy 136.195675 -126.292741) (xy 136.195308 -126.301754)
			(xy 136.195308 -126.36881) (xy 136.195659 -126.377828) (xy 136.20191 -126.394745) (xy 136.2075 -126.40183)
			(xy 136.207754 -126.40183) (xy 136.207754 -126.402084) (xy 136.225392 -126.423017) (xy 136.255105 -126.468989)
			(xy 136.277942 -126.518736) (xy 136.293434 -126.571237) (xy 136.301261 -126.625413) (xy 136.301734 -126.652782)
			(xy 136.301248 -126.680033) (xy 136.293492 -126.733981) (xy 136.278137 -126.786276) (xy 136.255495 -126.835853)
			(xy 136.226029 -126.881703) (xy 136.190338 -126.922894) (xy 136.149147 -126.958585) (xy 136.103297 -126.988051)
			(xy 136.05372 -127.010693) (xy 136.001425 -127.026048) (xy 135.947477 -127.033804) (xy 135.892975 -127.033804)
			(xy 135.839027 -127.026048) (xy 135.786732 -127.010693) (xy 135.737155 -126.988051) (xy 135.691305 -126.958585)
			(xy 135.650114 -126.922894) (xy 135.614423 -126.881703) (xy 135.584957 -126.835853) (xy 135.562315 -126.786276)
			(xy 135.54696 -126.733981) (xy 135.539204 -126.680033) (xy 135.538718 -126.652782) (xy 135.247051 -126.652782)
			(xy 135.243804 -126.663844) (xy 135.22117 -126.713422) (xy 135.19171 -126.759273) (xy 135.156025 -126.800465)
			(xy 135.11484 -126.83616) (xy 135.068995 -126.865629) (xy 135.019423 -126.888275) (xy 134.967132 -126.903634)
			(xy 134.913188 -126.911396) (xy 134.885938 -126.911862) (xy 134.859622 -126.911448) (xy 134.807491 -126.904204)
			(xy 134.756847 -126.889875) (xy 134.708647 -126.868733) (xy 134.663805 -126.841177) (xy 134.623169 -126.807728)
			(xy 134.605014 -126.788672) (xy 134.59748 -126.781285) (xy 134.57821 -126.77275) (xy 134.567676 -126.772162)
			(xy 134.493 -126.772162) (xy 134.48245 -126.772689) (xy 134.463156 -126.781227) (xy 134.455662 -126.788672)
			(xy 134.437512 -126.807734) (xy 134.396882 -126.841191) (xy 134.352041 -126.86875) (xy 134.303839 -126.889888)
			(xy 134.25319 -126.904203) (xy 134.201055 -126.911425) (xy 134.174738 -126.911862) (xy 134.147484 -126.911409)
			(xy 134.09353 -126.903656) (xy 134.041229 -126.888303) (xy 133.991646 -126.865661) (xy 133.945791 -126.836193)
			(xy 133.904597 -126.800498) (xy 133.868902 -126.759303) (xy 133.839435 -126.713447) (xy 133.816795 -126.663863)
			(xy 133.801442 -126.611562) (xy 133.79369 -126.557608) (xy 133.79323 -126.530354) (xy 117.014377 -126.530354)
			(xy 117.002483 -126.537613) (xy 116.951154 -126.559425) (xy 116.897197 -126.573531) (xy 116.84176 -126.579631)
			(xy 116.786026 -126.577594) (xy 116.731183 -126.567464) (xy 116.678399 -126.549457) (xy 116.628799 -126.523956)
			(xy 116.583441 -126.491505) (xy 116.543292 -126.452796) (xy 116.509206 -126.408653) (xy 116.48191 -126.360018)
			(xy 116.461987 -126.307927) (xy 116.449861 -126.25349) (xy 116.44579 -126.197868) (xy 108.193742 -126.197868)
			(xy 108.214608 -126.229744) (xy 108.236986 -126.276896) (xy 108.252738 -126.326655) (xy 108.257594 -126.3523)
			(xy 108.257594 -126.352554) (xy 108.259428 -126.360829) (xy 108.267719 -126.375599) (xy 108.280376 -126.386856)
			(xy 108.288074 -126.3904) (xy 108.379514 -126.429008) (xy 108.405168 -126.426214) (xy 108.415836 -126.418594)
			(xy 108.439986 -126.402441) (xy 108.492126 -126.376812) (xy 108.547549 -126.359386) (xy 108.604973 -126.350564)
			(xy 108.634022 -126.350014) (xy 108.661275 -126.350457) (xy 108.715225 -126.358217) (xy 108.767522 -126.373577)
			(xy 108.817101 -126.396222) (xy 108.862952 -126.425692) (xy 108.904143 -126.461388) (xy 108.939834 -126.502583)
			(xy 108.969299 -126.548438) (xy 108.991939 -126.598019) (xy 109.007292 -126.650318) (xy 109.015046 -126.704269)
			(xy 109.01553 -126.731522) (xy 109.015096 -126.758152) (xy 109.00769 -126.810896) (xy 108.993024 -126.862097)
			(xy 108.971382 -126.910763) (xy 108.943187 -126.955948) (xy 108.908984 -126.996776) (xy 108.869437 -127.032452)
			(xy 108.847636 -127.047752) (xy 108.837476 -127.05461) (xy 108.825792 -127.075438) (xy 108.821474 -127.18161)
			(xy 108.83138 -127.203454) (xy 108.841032 -127.211074) (xy 108.862881 -127.229325) (xy 108.901486 -127.27116)
			(xy 108.933453 -127.318263) (xy 108.95807 -127.369591) (xy 108.963528 -127.38735) (xy 110.308898 -127.38735)
			(xy 110.309418 -127.357979) (xy 110.318417 -127.29993) (xy 110.336209 -127.243946) (xy 110.362374 -127.191353)
			(xy 110.396293 -127.143393) (xy 110.41634 -127.12192) (xy 110.42272 -127.114735) (xy 110.430017 -127.096971)
			(xy 110.430564 -127.087376) (xy 110.431834 -127.008128) (xy 110.424976 -126.990094) (xy 110.418626 -126.982982)
			(xy 110.400068 -126.961814) (xy 110.368766 -126.915023) (xy 110.344678 -126.864142) (xy 110.328326 -126.810275)
			(xy 110.320065 -126.754589) (xy 110.319566 -126.726442) (xy 110.320094 -126.699191) (xy 110.327845 -126.645244)
			(xy 110.343194 -126.592949) (xy 110.36583 -126.543371) (xy 110.395291 -126.497519) (xy 110.430978 -126.456326)
			(xy 110.472164 -126.420632) (xy 110.518011 -126.391163) (xy 110.567585 -126.368518) (xy 110.619878 -126.353159)
			(xy 110.673823 -126.345399) (xy 110.701074 -126.344934) (xy 110.729754 -126.345504) (xy 110.786466 -126.35411)
			(xy 110.841253 -126.371103) (xy 110.892881 -126.3961) (xy 110.940189 -126.428538) (xy 110.982113 -126.467688)
			(xy 111.017708 -126.512669) (xy 111.046175 -126.562468) (xy 111.066872 -126.615966) (xy 111.079333 -126.671957)
			(xy 111.08182 -126.700534) (xy 111.082582 -126.713488) (xy 111.096552 -126.735332) (xy 111.194596 -126.788926)
			(xy 111.220504 -126.788926) (xy 111.231934 -126.782576) (xy 111.260181 -126.767818) (xy 111.320372 -126.746883)
			(xy 111.383205 -126.736248) (xy 111.415068 -126.735586) (xy 111.415576 -126.735586) (xy 111.44283 -126.73606)
			(xy 111.496782 -126.743814) (xy 111.549082 -126.759167) (xy 111.598664 -126.781808) (xy 111.64452 -126.811275)
			(xy 111.685715 -126.846968) (xy 111.72141 -126.888161) (xy 111.739255 -126.915926) (xy 118.631714 -126.915926)
			(xy 118.635785 -126.860304) (xy 118.647911 -126.805867) (xy 118.667834 -126.753776) (xy 118.69513 -126.705141)
			(xy 118.729216 -126.660998) (xy 118.769365 -126.622289) (xy 118.814723 -126.589838) (xy 118.864323 -126.564337)
			(xy 118.917107 -126.54633) (xy 118.97195 -126.5362) (xy 119.027684 -126.534163) (xy 119.083121 -126.540263)
			(xy 119.137078 -126.554369) (xy 119.188407 -126.576181) (xy 119.236013 -126.605235) (xy 119.278881 -126.64091)
			(xy 119.316098 -126.682447) (xy 119.346871 -126.72896) (xy 119.370543 -126.779457) (xy 119.386611 -126.832864)
			(xy 119.394731 -126.88804) (xy 119.39524 -126.915926) (xy 119.394731 -126.943812) (xy 119.386611 -126.998988)
			(xy 119.37087 -127.051308) (xy 126.844042 -127.051308) (xy 126.848113 -126.995686) (xy 126.860239 -126.941249)
			(xy 126.880162 -126.889158) (xy 126.907458 -126.840523) (xy 126.941544 -126.79638) (xy 126.981693 -126.757671)
			(xy 127.027051 -126.72522) (xy 127.076651 -126.699719) (xy 127.129435 -126.681712) (xy 127.184278 -126.671582)
			(xy 127.240012 -126.669545) (xy 127.295449 -126.675645) (xy 127.349406 -126.689751) (xy 127.400735 -126.711563)
			(xy 127.448341 -126.740617) (xy 127.491209 -126.776292) (xy 127.528426 -126.817829) (xy 127.559199 -126.864342)
			(xy 127.582871 -126.914839) (xy 127.598939 -126.968246) (xy 127.607059 -127.023422) (xy 127.607568 -127.051308)
			(xy 127.607059 -127.079194) (xy 127.598939 -127.13437) (xy 127.582871 -127.187777) (xy 127.559199 -127.238274)
			(xy 127.528426 -127.284787) (xy 127.491209 -127.326324) (xy 127.448341 -127.361999) (xy 127.400735 -127.391053)
			(xy 127.349406 -127.412865) (xy 127.295449 -127.426971) (xy 127.240012 -127.433071) (xy 127.184278 -127.431034)
			(xy 127.129435 -127.420904) (xy 127.076651 -127.402897) (xy 127.027051 -127.377396) (xy 126.981693 -127.344945)
			(xy 126.941544 -127.306236) (xy 126.907458 -127.262093) (xy 126.880162 -127.213458) (xy 126.860239 -127.161367)
			(xy 126.848113 -127.10693) (xy 126.844042 -127.051308) (xy 119.37087 -127.051308) (xy 119.370543 -127.052395)
			(xy 119.346871 -127.102892) (xy 119.316098 -127.149405) (xy 119.278881 -127.190942) (xy 119.236013 -127.226617)
			(xy 119.188407 -127.255671) (xy 119.137078 -127.277483) (xy 119.083121 -127.291589) (xy 119.027684 -127.297689)
			(xy 118.97195 -127.295652) (xy 118.917107 -127.285522) (xy 118.864323 -127.267515) (xy 118.814723 -127.242014)
			(xy 118.769365 -127.209563) (xy 118.729216 -127.170854) (xy 118.69513 -127.126711) (xy 118.667834 -127.078076)
			(xy 118.647911 -127.025985) (xy 118.635785 -126.971548) (xy 118.631714 -126.915926) (xy 111.739255 -126.915926)
			(xy 111.75088 -126.934014) (xy 111.773524 -126.983595) (xy 111.788881 -127.035894) (xy 111.796639 -127.089846)
			(xy 111.796639 -127.144354) (xy 111.788881 -127.198306) (xy 111.773524 -127.250605) (xy 111.75088 -127.300186)
			(xy 111.72141 -127.346039) (xy 111.685715 -127.387232) (xy 111.64452 -127.422925) (xy 111.598664 -127.452392)
			(xy 111.549082 -127.475033) (xy 111.518979 -127.48387) (xy 116.59438 -127.48387) (xy 116.598451 -127.428248)
			(xy 116.610577 -127.373811) (xy 116.6305 -127.32172) (xy 116.657796 -127.273085) (xy 116.691882 -127.228942)
			(xy 116.732031 -127.190233) (xy 116.777389 -127.157782) (xy 116.826989 -127.132281) (xy 116.879773 -127.114274)
			(xy 116.934616 -127.104144) (xy 116.99035 -127.102107) (xy 117.045787 -127.108207) (xy 117.099744 -127.122313)
			(xy 117.151073 -127.144125) (xy 117.198679 -127.173179) (xy 117.241547 -127.208854) (xy 117.278764 -127.250391)
			(xy 117.309537 -127.296904) (xy 117.333209 -127.347401) (xy 117.349277 -127.400808) (xy 117.357397 -127.455984)
			(xy 117.357906 -127.48387) (xy 117.357397 -127.511756) (xy 117.349277 -127.566932) (xy 117.333209 -127.620339)
			(xy 117.309537 -127.670836) (xy 117.278764 -127.717349) (xy 117.241547 -127.758886) (xy 117.198679 -127.794561)
			(xy 117.151073 -127.823615) (xy 117.099744 -127.845427) (xy 117.045787 -127.859533) (xy 116.99035 -127.865633)
			(xy 116.934616 -127.863596) (xy 116.879773 -127.853466) (xy 116.826989 -127.835459) (xy 116.777389 -127.809958)
			(xy 116.732031 -127.777507) (xy 116.691882 -127.738798) (xy 116.657796 -127.694655) (xy 116.6305 -127.64602)
			(xy 116.610577 -127.593929) (xy 116.598451 -127.539492) (xy 116.59438 -127.48387) (xy 111.518979 -127.48387)
			(xy 111.496782 -127.490386) (xy 111.44283 -127.49814) (xy 111.415576 -127.498602) (xy 111.388288 -127.498128)
			(xy 111.334267 -127.49036) (xy 111.281905 -127.47497) (xy 111.232272 -127.452274) (xy 111.209074 -127.437896)
			(xy 111.20882 -127.437642) (xy 111.198527 -127.431896) (xy 111.175101 -127.429514) (xy 111.163862 -127.43307)
			(xy 111.087408 -127.461264) (xy 111.076556 -127.465943) (xy 111.060406 -127.483158) (xy 111.05642 -127.494284)
			(xy 111.05642 -127.494792) (xy 111.048249 -127.520795) (xy 111.025627 -127.570382) (xy 110.996177 -127.616243)
			(xy 110.960498 -127.657445) (xy 110.919317 -127.693147) (xy 110.873472 -127.722623) (xy 110.823899 -127.745273)
			(xy 110.771605 -127.760634) (xy 110.717657 -127.768394) (xy 110.690406 -127.768858) (xy 110.663151 -127.768439)
			(xy 110.609196 -127.760681) (xy 110.556894 -127.745324) (xy 110.507311 -127.722678) (xy 110.461455 -127.693206)
			(xy 110.420261 -127.657508) (xy 110.384567 -127.61631) (xy 110.355101 -127.570451) (xy 110.332461 -127.520865)
			(xy 110.317109 -127.468561) (xy 110.309358 -127.414605) (xy 110.308898 -127.38735) (xy 108.963528 -127.38735)
			(xy 108.974793 -127.424005) (xy 108.983252 -127.480299) (xy 108.98378 -127.508762) (xy 108.983294 -127.536013)
			(xy 108.975538 -127.589961) (xy 108.960183 -127.642256) (xy 108.937541 -127.691833) (xy 108.908075 -127.737683)
			(xy 108.872384 -127.778874) (xy 108.831193 -127.814565) (xy 108.785343 -127.844031) (xy 108.735766 -127.866673)
			(xy 108.683471 -127.882028) (xy 108.629523 -127.889784) (xy 108.575021 -127.889784) (xy 108.521073 -127.882028)
			(xy 108.468778 -127.866673) (xy 108.419201 -127.844031) (xy 108.373351 -127.814565) (xy 108.33216 -127.778874)
			(xy 108.296469 -127.737683) (xy 108.267003 -127.691833) (xy 108.244361 -127.642256) (xy 108.229006 -127.589961)
			(xy 108.22125 -127.536013) (xy 108.220764 -127.508762) (xy 108.22178 -127.479552) (xy 108.22305 -127.465582)
			(xy 108.21035 -127.440182) (xy 108.110528 -127.376936) (xy 108.082588 -127.376428) (xy 108.070396 -127.383286)
			(xy 108.048743 -127.395152) (xy 108.003045 -127.413849) (xy 107.955319 -127.426507) (xy 107.906361 -127.432913)
			(xy 107.881674 -127.433324) (xy 107.854423 -127.432846) (xy 107.800476 -127.425087) (xy 107.748182 -127.409729)
			(xy 107.698605 -127.387086) (xy 107.652756 -127.357619) (xy 107.611566 -127.321926) (xy 107.575875 -127.280736)
			(xy 107.546409 -127.234886) (xy 107.523767 -127.185309) (xy 107.508411 -127.133015) (xy 107.500653 -127.079067)
			(xy 107.500166 -127.051816) (xy 105.602208 -127.051816) (xy 105.599116 -127.073325) (xy 105.583761 -127.12562)
			(xy 105.561119 -127.175197) (xy 105.531653 -127.221047) (xy 105.495962 -127.262238) (xy 105.454771 -127.297929)
			(xy 105.408921 -127.327395) (xy 105.359344 -127.350037) (xy 105.307049 -127.365392) (xy 105.253101 -127.373148)
			(xy 105.198599 -127.373148) (xy 105.144651 -127.365392) (xy 105.092356 -127.350037) (xy 105.042779 -127.327395)
			(xy 104.996929 -127.297929) (xy 104.955738 -127.262238) (xy 104.920047 -127.221047) (xy 104.890581 -127.175197)
			(xy 104.867939 -127.12562) (xy 104.852584 -127.073325) (xy 104.844828 -127.019377) (xy 104.844342 -126.992126)
			(xy 81.070386 -126.992126) (xy 81.016724 -128.252748) (xy 125.828328 -128.252748) (xy 125.828328 -128.198252)
			(xy 125.836084 -128.144312) (xy 125.851437 -128.092024) (xy 125.874075 -128.042454) (xy 125.903537 -127.99661)
			(xy 125.939223 -127.955425) (xy 125.980408 -127.919738) (xy 126.026252 -127.890276) (xy 126.075822 -127.867637)
			(xy 126.12811 -127.852284) (xy 126.18205 -127.844528) (xy 126.209298 -127.844042) (xy 126.236669 -127.844499)
			(xy 126.290849 -127.852317) (xy 126.343352 -127.867808) (xy 126.393099 -127.890652) (xy 126.439065 -127.920379)
			(xy 126.459996 -127.938022) (xy 126.46025 -127.938276) (xy 126.46734 -127.943857) (xy 126.484254 -127.950105)
			(xy 126.49327 -127.950468) (xy 126.560326 -127.950468) (xy 126.569345 -127.95013) (xy 126.586262 -127.94387)
			(xy 126.593346 -127.938276) (xy 126.593346 -127.938022) (xy 126.5936 -127.938022) (xy 126.614533 -127.920381)
			(xy 126.660501 -127.890657) (xy 126.710247 -127.867811) (xy 126.762749 -127.852315) (xy 126.816927 -127.844486)
			(xy 126.871669 -127.844486) (xy 126.925847 -127.852315) (xy 126.978349 -127.867811) (xy 127.028095 -127.890657)
			(xy 127.074063 -127.920381) (xy 127.094996 -127.938022) (xy 127.09525 -127.938276) (xy 127.10234 -127.943857)
			(xy 127.119254 -127.950105) (xy 127.12827 -127.950468) (xy 127.195326 -127.950468) (xy 127.204345 -127.95013)
			(xy 127.221262 -127.94387) (xy 127.228346 -127.938276) (xy 127.228346 -127.938022) (xy 127.2286 -127.938022)
			(xy 127.249524 -127.920373) (xy 127.295499 -127.890662) (xy 127.345248 -127.867827) (xy 127.397751 -127.852339)
			(xy 127.451928 -127.844514) (xy 127.479298 -127.844042) (xy 127.506555 -127.844405) (xy 127.560513 -127.852163)
			(xy 127.612818 -127.86752) (xy 127.662405 -127.890166) (xy 127.708264 -127.919638) (xy 127.749463 -127.955336)
			(xy 127.785161 -127.996534) (xy 127.814633 -128.042393) (xy 127.837279 -128.09198) (xy 127.852637 -128.144285)
			(xy 127.860395 -128.198243) (xy 127.860395 -128.252757) (xy 127.852637 -128.306715) (xy 127.837279 -128.35902)
			(xy 127.814633 -128.408607) (xy 127.785161 -128.454466) (xy 127.749463 -128.495664) (xy 127.708264 -128.531362)
			(xy 127.662405 -128.560834) (xy 127.612818 -128.58348) (xy 127.560513 -128.598837) (xy 127.506555 -128.606595)
			(xy 127.479298 -128.607058) (xy 127.451927 -128.606603) (xy 127.397747 -128.598784) (xy 127.345244 -128.583293)
			(xy 127.295497 -128.560449) (xy 127.249531 -128.530721) (xy 127.2286 -128.513078) (xy 127.228346 -128.512824)
			(xy 127.221257 -128.507242) (xy 127.204342 -128.500994) (xy 127.195326 -128.500632) (xy 127.12827 -128.500632)
			(xy 127.119251 -128.500968) (xy 127.102334 -128.507229) (xy 127.09525 -128.512824) (xy 127.094996 -128.513078)
			(xy 127.074063 -128.530719) (xy 127.028095 -128.560443) (xy 126.978349 -128.583289) (xy 126.925847 -128.598785)
			(xy 126.871669 -128.606614) (xy 126.816927 -128.606614) (xy 126.762749 -128.598785) (xy 126.710247 -128.583289)
			(xy 126.660501 -128.560443) (xy 126.614533 -128.530719) (xy 126.5936 -128.513078) (xy 126.593346 -128.512824)
			(xy 126.586257 -128.507242) (xy 126.569342 -128.500994) (xy 126.560326 -128.500632) (xy 126.49327 -128.500632)
			(xy 126.484251 -128.500968) (xy 126.467334 -128.507229) (xy 126.46025 -128.512824) (xy 126.46025 -128.513078)
			(xy 126.459996 -128.513078) (xy 126.439073 -128.530729) (xy 126.393098 -128.56044) (xy 126.343348 -128.583274)
			(xy 126.290846 -128.598762) (xy 126.236668 -128.606586) (xy 126.209298 -128.607058) (xy 126.18205 -128.606472)
			(xy 126.12811 -128.598716) (xy 126.075822 -128.583363) (xy 126.026252 -128.560724) (xy 125.980408 -128.531262)
			(xy 125.939223 -128.495575) (xy 125.903537 -128.45439) (xy 125.874075 -128.408546) (xy 125.851437 -128.358976)
			(xy 125.836084 -128.306688) (xy 125.828328 -128.252748) (xy 81.016724 -128.252748) (xy 80.999165 -128.665246)
			(xy 112.888324 -128.665246) (xy 112.888324 -128.610754) (xy 112.896079 -128.556815) (xy 112.91143 -128.504529)
			(xy 112.934066 -128.45496) (xy 112.963526 -128.409117) (xy 112.99921 -128.367933) (xy 113.040391 -128.332245)
			(xy 113.086232 -128.302782) (xy 113.135799 -128.280142) (xy 113.188084 -128.264786) (xy 113.242022 -128.257026)
			(xy 113.269268 -128.256538) (xy 113.296638 -128.257014) (xy 113.350817 -128.264828) (xy 113.40332 -128.280314)
			(xy 113.453067 -128.303154) (xy 113.499034 -128.332877) (xy 113.519966 -128.350518) (xy 113.52022 -128.350772)
			(xy 113.527291 -128.356382) (xy 113.54422 -128.362612) (xy 113.55324 -128.362964) (xy 113.620296 -128.362964)
			(xy 113.629314 -128.362613) (xy 113.646231 -128.356362) (xy 113.653316 -128.350772) (xy 113.653316 -128.350518)
			(xy 113.65357 -128.350518) (xy 113.674503 -128.332877) (xy 113.720471 -128.303153) (xy 113.770217 -128.280307)
			(xy 113.822719 -128.264811) (xy 113.876897 -128.256982) (xy 113.931639 -128.256982) (xy 113.985817 -128.264811)
			(xy 114.038319 -128.280307) (xy 114.088065 -128.303153) (xy 114.134033 -128.332877) (xy 114.154966 -128.350518)
			(xy 114.15522 -128.350772) (xy 114.162291 -128.356382) (xy 114.17922 -128.362612) (xy 114.18824 -128.362964)
			(xy 114.255296 -128.362964) (xy 114.264314 -128.362613) (xy 114.281231 -128.356362) (xy 114.288316 -128.350772)
			(xy 114.288316 -128.350518) (xy 114.28857 -128.350518) (xy 114.309505 -128.332882) (xy 114.355477 -128.303169)
			(xy 114.405223 -128.280332) (xy 114.457724 -128.264841) (xy 114.511899 -128.257012) (xy 114.539268 -128.256538)
			(xy 114.566526 -128.256907) (xy 114.620487 -128.264661) (xy 114.672795 -128.280016) (xy 114.722385 -128.30266)
			(xy 114.768248 -128.33213) (xy 114.809449 -128.367828) (xy 114.845151 -128.409027) (xy 114.874625 -128.454887)
			(xy 114.897273 -128.504475) (xy 114.912632 -128.556782) (xy 114.920391 -128.610742) (xy 114.920391 -128.665258)
			(xy 114.912632 -128.719218) (xy 114.897273 -128.771525) (xy 114.874625 -128.821113) (xy 114.845151 -128.866973)
			(xy 114.809449 -128.908172) (xy 114.768248 -128.94387) (xy 114.722385 -128.97334) (xy 114.672795 -128.995984)
			(xy 114.620487 -129.011339) (xy 114.566526 -129.019093) (xy 114.539268 -129.019554) (xy 114.511897 -129.019118)
			(xy 114.457716 -129.011295) (xy 114.405212 -128.995799) (xy 114.355465 -128.97295) (xy 114.3095 -128.943219)
			(xy 114.28857 -128.925574) (xy 114.288316 -128.92532) (xy 114.281236 -128.919725) (xy 114.264314 -128.913485)
			(xy 114.255296 -128.913128) (xy 114.18824 -128.913128) (xy 114.179224 -128.913498) (xy 114.162307 -128.919736)
			(xy 114.15522 -128.92532) (xy 114.154966 -128.925574) (xy 114.134033 -128.943215) (xy 114.088065 -128.972939)
			(xy 114.038319 -128.995785) (xy 113.985817 -129.011281) (xy 113.931639 -129.01911) (xy 113.876897 -129.01911)
			(xy 113.822719 -129.011281) (xy 113.770217 -128.995785) (xy 113.720471 -128.972939) (xy 113.674503 -128.943215)
			(xy 113.65357 -128.925574) (xy 113.653316 -128.92532) (xy 113.646236 -128.919725) (xy 113.629314 -128.913485)
			(xy 113.620296 -128.913128) (xy 113.55324 -128.913128) (xy 113.544224 -128.913498) (xy 113.527307 -128.919736)
			(xy 113.52022 -128.92532) (xy 113.52022 -128.925574) (xy 113.519966 -128.925574) (xy 113.499017 -128.943192)
			(xy 113.453049 -128.972908) (xy 113.403306 -128.995748) (xy 113.350809 -129.011244) (xy 113.296636 -129.019077)
			(xy 113.269268 -129.019554) (xy 113.242022 -129.018974) (xy 113.188084 -129.011214) (xy 113.135799 -128.995858)
			(xy 113.086232 -128.973218) (xy 113.040391 -128.943755) (xy 112.99921 -128.908067) (xy 112.963526 -128.866883)
			(xy 112.934067 -128.82104) (xy 112.91143 -128.771471) (xy 112.896079 -128.719185) (xy 112.888324 -128.665246)
			(xy 80.999165 -128.665246) (xy 80.972406 -129.293874) (xy 80.972689 -129.302131) (xy 80.977879 -129.317804)
			(xy 80.982566 -129.324608) (xy 81.007966 -129.342388) (xy 81.008474 -129.342642) (xy 81.024759 -129.347743)
			(xy 81.056431 -129.360461) (xy 81.07172 -129.368042) (xy 81.099649 -129.382976) (xy 81.135397 -129.409444)
			(xy 116.367812 -129.409444) (xy 116.371883 -129.353822) (xy 116.384009 -129.299385) (xy 116.403932 -129.247294)
			(xy 116.431228 -129.198659) (xy 116.465314 -129.154516) (xy 116.505463 -129.115807) (xy 116.550821 -129.083356)
			(xy 116.600421 -129.057855) (xy 116.653205 -129.039848) (xy 116.708048 -129.029718) (xy 116.763782 -129.027681)
			(xy 116.819219 -129.033781) (xy 116.873176 -129.047887) (xy 116.924505 -129.069699) (xy 116.972111 -129.098753)
			(xy 117.014979 -129.134428) (xy 117.052196 -129.175965) (xy 117.082969 -129.222478) (xy 117.106641 -129.272975)
			(xy 117.122709 -129.326382) (xy 117.130829 -129.381558) (xy 117.131338 -129.409444) (xy 117.130829 -129.43733)
			(xy 117.122709 -129.492506) (xy 117.106641 -129.545913) (xy 117.087504 -129.586736) (xy 117.524528 -129.586736)
			(xy 117.528599 -129.531114) (xy 117.540725 -129.476677) (xy 117.560648 -129.424586) (xy 117.587944 -129.375951)
			(xy 117.62203 -129.331808) (xy 117.662179 -129.293099) (xy 117.707537 -129.260648) (xy 117.757137 -129.235147)
			(xy 117.809921 -129.21714) (xy 117.864764 -129.20701) (xy 117.920498 -129.204973) (xy 117.975935 -129.211073)
			(xy 118.029892 -129.225179) (xy 118.081221 -129.246991) (xy 118.128827 -129.276045) (xy 118.171695 -129.31172)
			(xy 118.208912 -129.353257) (xy 118.239685 -129.39977) (xy 118.263357 -129.450267) (xy 118.279425 -129.503674)
			(xy 118.287545 -129.55885) (xy 118.288054 -129.586736) (xy 118.287545 -129.614622) (xy 118.279425 -129.669798)
			(xy 118.263357 -129.723205) (xy 118.239685 -129.773702) (xy 118.208912 -129.820215) (xy 118.171695 -129.861752)
			(xy 118.128827 -129.897427) (xy 118.081221 -129.926481) (xy 118.029892 -129.948293) (xy 117.975935 -129.962399)
			(xy 117.920498 -129.968499) (xy 117.864764 -129.966462) (xy 117.809921 -129.956332) (xy 117.757137 -129.938325)
			(xy 117.707537 -129.912824) (xy 117.662179 -129.880373) (xy 117.62203 -129.841664) (xy 117.587944 -129.797521)
			(xy 117.560648 -129.748886) (xy 117.540725 -129.696795) (xy 117.528599 -129.642358) (xy 117.524528 -129.586736)
			(xy 117.087504 -129.586736) (xy 117.082969 -129.59641) (xy 117.052196 -129.642923) (xy 117.014979 -129.68446)
			(xy 116.972111 -129.720135) (xy 116.924505 -129.749189) (xy 116.873176 -129.771001) (xy 116.819219 -129.785107)
			(xy 116.763782 -129.791207) (xy 116.708048 -129.78917) (xy 116.653205 -129.77904) (xy 116.600421 -129.761033)
			(xy 116.550821 -129.735532) (xy 116.505463 -129.703081) (xy 116.465314 -129.664372) (xy 116.431228 -129.620229)
			(xy 116.403932 -129.571594) (xy 116.384009 -129.519503) (xy 116.371883 -129.465066) (xy 116.367812 -129.409444)
			(xy 81.135397 -129.409444) (xy 81.150546 -129.42066) (xy 81.194514 -129.466238) (xy 81.212944 -129.491994)
			(xy 81.2165 -129.497074) (xy 81.225136 -129.504948) (xy 81.243678 -129.515108) (xy 81.252556 -129.519426)
			(xy 81.272155 -129.521637) (xy 81.281778 -129.519426) (xy 81.288636 -129.517394) (xy 81.294478 -129.513838)
			(xy 81.321426 -129.498133) (xy 81.378666 -129.473357) (xy 81.438737 -129.456567) (xy 81.500528 -129.448074)
			(xy 81.531714 -129.447544) (xy 81.532222 -129.447544) (xy 81.562205 -129.448035) (xy 81.621658 -129.455865)
			(xy 81.679581 -129.471388) (xy 81.734982 -129.494339) (xy 81.786913 -129.524324) (xy 81.834486 -129.560831)
			(xy 81.876888 -129.603235) (xy 81.913392 -129.65081) (xy 81.943374 -129.702743) (xy 81.966321 -129.758146)
			(xy 81.98184 -129.816069) (xy 81.989666 -129.875523) (xy 81.990184 -129.905506) (xy 81.990184 -129.951246)
			(xy 112.909426 -129.951246) (xy 112.909426 -129.896754) (xy 112.91718 -129.842818) (xy 112.932531 -129.790534)
			(xy 112.955166 -129.740966) (xy 112.984623 -129.695124) (xy 113.020305 -129.65394) (xy 113.061484 -129.618253)
			(xy 113.107322 -129.58879) (xy 113.156887 -129.566148) (xy 113.209169 -129.550791) (xy 113.263105 -129.54303)
			(xy 113.29035 -129.54254) (xy 113.31772 -129.543026) (xy 113.371898 -129.550837) (xy 113.424402 -129.566321)
			(xy 113.474149 -129.589159) (xy 113.520116 -129.61888) (xy 113.541048 -129.63652) (xy 113.541302 -129.636774)
			(xy 113.548378 -129.642376) (xy 113.565303 -129.648612) (xy 113.574322 -129.648966) (xy 113.641378 -129.648966)
			(xy 113.650395 -129.648606) (xy 113.667312 -129.642361) (xy 113.674398 -129.636774) (xy 113.674398 -129.63652)
			(xy 113.674652 -129.63652) (xy 113.695594 -129.618893) (xy 113.741564 -129.589179) (xy 113.791309 -129.56634)
			(xy 113.843807 -129.550846) (xy 113.897981 -129.543015) (xy 113.92535 -129.54254) (xy 113.952609 -129.542904)
			(xy 114.006572 -129.550656) (xy 114.058882 -129.566009) (xy 114.108475 -129.588652) (xy 114.15434 -129.618122)
			(xy 114.195544 -129.65382) (xy 114.231248 -129.69502) (xy 114.260724 -129.740881) (xy 114.283373 -129.790471)
			(xy 114.298734 -129.842779) (xy 114.306493 -129.896741) (xy 114.306493 -129.951259) (xy 114.298734 -130.005221)
			(xy 114.283373 -130.057529) (xy 114.260724 -130.107119) (xy 114.231248 -130.15298) (xy 114.195544 -130.19418)
			(xy 114.15434 -130.229878) (xy 114.108475 -130.259348) (xy 114.058882 -130.281991) (xy 114.006572 -130.297344)
			(xy 113.952609 -130.305096) (xy 113.92535 -130.305556) (xy 113.89798 -130.305071) (xy 113.843802 -130.29726)
			(xy 113.791298 -130.281776) (xy 113.741551 -130.258938) (xy 113.695584 -130.229216) (xy 113.674652 -130.211576)
			(xy 113.674398 -130.211322) (xy 113.667323 -130.205719) (xy 113.650397 -130.199484) (xy 113.641378 -130.19913)
			(xy 113.574322 -130.19913) (xy 113.565305 -130.199491) (xy 113.548388 -130.205735) (xy 113.541302 -130.211322)
			(xy 113.541302 -130.211576) (xy 113.541048 -130.211576) (xy 113.520106 -130.229202) (xy 113.474136 -130.258917)
			(xy 113.424391 -130.281756) (xy 113.371893 -130.29725) (xy 113.317719 -130.305081) (xy 113.29035 -130.305556)
			(xy 113.263105 -130.30497) (xy 113.209169 -130.297209) (xy 113.156887 -130.281852) (xy 113.107322 -130.259211)
			(xy 113.061484 -130.229747) (xy 113.020305 -130.19406) (xy 112.984623 -130.152876) (xy 112.955166 -130.107034)
			(xy 112.932531 -130.057466) (xy 112.91718 -130.005182) (xy 112.909426 -129.951246) (xy 81.990184 -129.951246)
			(xy 81.990184 -130.769106) (xy 81.989694 -130.799091) (xy 81.981866 -130.858547) (xy 81.966344 -130.916472)
			(xy 81.943395 -130.971877) (xy 81.913411 -131.023812) (xy 81.876905 -131.071389) (xy 81.834501 -131.113794)
			(xy 81.786925 -131.150302) (xy 81.734991 -131.180288) (xy 81.679587 -131.203239) (xy 81.621946 -131.218686)
			(xy 118.631714 -131.218686) (xy 118.635785 -131.163064) (xy 118.647911 -131.108627) (xy 118.667834 -131.056536)
			(xy 118.69513 -131.007901) (xy 118.729216 -130.963758) (xy 118.769365 -130.925049) (xy 118.814723 -130.892598)
			(xy 118.864323 -130.867097) (xy 118.917107 -130.84909) (xy 118.97195 -130.83896) (xy 119.027684 -130.836923)
			(xy 119.083121 -130.843023) (xy 119.137078 -130.857129) (xy 119.188407 -130.878941) (xy 119.236013 -130.907995)
			(xy 119.278881 -130.94367) (xy 119.316098 -130.985207) (xy 119.346871 -131.03172) (xy 119.370543 -131.082217)
			(xy 119.386611 -131.135624) (xy 119.394731 -131.1908) (xy 119.39524 -131.218686) (xy 119.394731 -131.246572)
			(xy 119.386611 -131.301748) (xy 119.370543 -131.355155) (xy 119.346871 -131.405652) (xy 119.319411 -131.447157)
			(xy 125.813209 -131.447157) (xy 125.813209 -131.392643) (xy 125.820967 -131.338685) (xy 125.836326 -131.28638)
			(xy 125.858972 -131.236793) (xy 125.888445 -131.190933) (xy 125.924144 -131.149735) (xy 125.965343 -131.114037)
			(xy 126.011203 -131.084566) (xy 126.060791 -131.061922) (xy 126.113096 -131.046565) (xy 126.167055 -131.038808)
			(xy 126.194312 -131.038346) (xy 126.221683 -131.038794) (xy 126.275863 -131.046614) (xy 126.328367 -131.062107)
			(xy 126.378114 -131.084953) (xy 126.424079 -131.114682) (xy 126.44501 -131.132326) (xy 126.445264 -131.13258)
			(xy 126.45235 -131.138167) (xy 126.469268 -131.144411) (xy 126.478284 -131.144772) (xy 126.54534 -131.144772)
			(xy 126.55436 -131.14444) (xy 126.571277 -131.138176) (xy 126.57836 -131.13258) (xy 126.57836 -131.132326)
			(xy 126.578614 -131.132326) (xy 126.599547 -131.114685) (xy 126.645515 -131.084961) (xy 126.695261 -131.062115)
			(xy 126.747763 -131.046619) (xy 126.801941 -131.03879) (xy 126.856683 -131.03879) (xy 126.910861 -131.046619)
			(xy 126.963363 -131.062115) (xy 127.013109 -131.084961) (xy 127.059077 -131.114685) (xy 127.08001 -131.132326)
			(xy 127.080264 -131.13258) (xy 127.08735 -131.138167) (xy 127.104268 -131.144411) (xy 127.113284 -131.144772)
			(xy 127.18034 -131.144772) (xy 127.18936 -131.14444) (xy 127.206277 -131.138176) (xy 127.21336 -131.13258)
			(xy 127.21336 -131.132326) (xy 127.213614 -131.132326) (xy 127.234571 -131.114718) (xy 127.280537 -131.085)
			(xy 127.330278 -131.062158) (xy 127.382773 -131.04666) (xy 127.436944 -131.038824) (xy 127.464312 -131.038346)
			(xy 127.491559 -131.038925) (xy 127.545499 -131.046682) (xy 127.597786 -131.062036) (xy 127.647356 -131.084675)
			(xy 127.693199 -131.114138) (xy 127.734383 -131.149826) (xy 127.770069 -131.19101) (xy 127.79953 -131.236855)
			(xy 127.822168 -131.286425) (xy 127.837521 -131.338712) (xy 127.845276 -131.392653) (xy 127.845276 -131.447147)
			(xy 127.837521 -131.501087) (xy 127.822168 -131.553375) (xy 127.79953 -131.602945) (xy 127.770069 -131.64879)
			(xy 127.734383 -131.689974) (xy 127.693199 -131.725662) (xy 127.647356 -131.755125) (xy 127.597786 -131.777764)
			(xy 127.545499 -131.793118) (xy 127.491559 -131.800875) (xy 127.464312 -131.801362) (xy 127.436942 -131.800898)
			(xy 127.382762 -131.793081) (xy 127.330259 -131.777592) (xy 127.280512 -131.75475) (xy 127.234545 -131.725024)
			(xy 127.213614 -131.707382) (xy 127.21336 -131.707128) (xy 127.206267 -131.701552) (xy 127.189355 -131.695301)
			(xy 127.18034 -131.694936) (xy 127.113284 -131.694936) (xy 127.104265 -131.695277) (xy 127.087348 -131.701535)
			(xy 127.080264 -131.707128) (xy 127.08001 -131.707382) (xy 127.059077 -131.725023) (xy 127.013109 -131.754747)
			(xy 126.963363 -131.777593) (xy 126.910861 -131.793089) (xy 126.856683 -131.800918) (xy 126.801941 -131.800918)
			(xy 126.747763 -131.793089) (xy 126.695261 -131.777593) (xy 126.645515 -131.754747) (xy 126.599547 -131.725023)
			(xy 126.578614 -131.707382) (xy 126.57836 -131.707128) (xy 126.571267 -131.701552) (xy 126.554355 -131.695301)
			(xy 126.54534 -131.694936) (xy 126.478284 -131.694936) (xy 126.469265 -131.695277) (xy 126.452348 -131.701535)
			(xy 126.445264 -131.707128) (xy 126.445264 -131.707382) (xy 126.44501 -131.707382) (xy 126.424083 -131.725027)
			(xy 126.378109 -131.754739) (xy 126.32836 -131.777574) (xy 126.275858 -131.793063) (xy 126.221682 -131.800889)
			(xy 126.194312 -131.801362) (xy 126.167055 -131.800992) (xy 126.113096 -131.793235) (xy 126.060791 -131.777878)
			(xy 126.011203 -131.755234) (xy 125.965343 -131.725763) (xy 125.924144 -131.690065) (xy 125.888445 -131.648867)
			(xy 125.858972 -131.603007) (xy 125.836326 -131.55342) (xy 125.820967 -131.501115) (xy 125.813209 -131.447157)
			(xy 119.319411 -131.447157) (xy 119.316098 -131.452165) (xy 119.278881 -131.493702) (xy 119.236013 -131.529377)
			(xy 119.188407 -131.558431) (xy 119.137078 -131.580243) (xy 119.083121 -131.594349) (xy 119.027684 -131.600449)
			(xy 118.97195 -131.598412) (xy 118.917107 -131.588282) (xy 118.864323 -131.570275) (xy 118.814723 -131.544774)
			(xy 118.769365 -131.512323) (xy 118.729216 -131.473614) (xy 118.69513 -131.429471) (xy 118.667834 -131.380836)
			(xy 118.647911 -131.328745) (xy 118.635785 -131.274308) (xy 118.631714 -131.218686) (xy 81.621946 -131.218686)
			(xy 81.621662 -131.218762) (xy 81.562207 -131.226593) (xy 81.532222 -131.227068) (xy 81.531714 -131.227068)
			(xy 81.500526 -131.226546) (xy 81.438727 -131.218083) (xy 81.378651 -131.201297) (xy 81.321416 -131.1765)
			(xy 81.294478 -131.160774) (xy 81.288636 -131.157218) (xy 81.281778 -131.155186) (xy 81.272159 -131.152978)
			(xy 81.252569 -131.155216) (xy 81.243678 -131.159504) (xy 81.225136 -131.169664) (xy 81.2165 -131.177538)
			(xy 81.212944 -131.182618) (xy 81.196539 -131.205603) (xy 81.158059 -131.246931) (xy 81.113911 -131.28214)
			(xy 81.065057 -131.31046) (xy 81.012564 -131.331274) (xy 80.957577 -131.344128) (xy 80.92948 -131.346956)
			(xy 80.91043 -131.34848) (xy 80.88376 -131.376166) (xy 80.832523 -132.575808) (xy 83.716368 -132.575808)
			(xy 83.716368 -131.712208) (xy 83.716858 -131.682224) (xy 83.724686 -131.622768) (xy 83.740207 -131.564843)
			(xy 83.763156 -131.509439) (xy 83.79314 -131.457505) (xy 83.829646 -131.409929) (xy 83.872051 -131.367524)
			(xy 83.919627 -131.331018) (xy 83.971561 -131.301034) (xy 84.026965 -131.278085) (xy 84.08489 -131.262564)
			(xy 84.144346 -131.254736) (xy 84.204314 -131.254736) (xy 84.26377 -131.262564) (xy 84.321695 -131.278085)
			(xy 84.377099 -131.301034) (xy 84.429033 -131.331018) (xy 84.476609 -131.367524) (xy 84.519014 -131.409929)
			(xy 84.55552 -131.457505) (xy 84.585504 -131.509439) (xy 84.608453 -131.564843) (xy 84.623974 -131.622768)
			(xy 84.631802 -131.682224) (xy 84.632292 -131.712208) (xy 84.632292 -131.715256) (xy 95.345756 -131.715256)
			(xy 95.349827 -131.659634) (xy 95.361953 -131.605197) (xy 95.381876 -131.553106) (xy 95.409172 -131.504471)
			(xy 95.443258 -131.460328) (xy 95.483407 -131.421619) (xy 95.528765 -131.389168) (xy 95.578365 -131.363667)
			(xy 95.631149 -131.34566) (xy 95.685992 -131.33553) (xy 95.741726 -131.333493) (xy 95.797163 -131.339593)
			(xy 95.85112 -131.353699) (xy 95.902449 -131.375511) (xy 95.950055 -131.404565) (xy 95.992923 -131.44024)
			(xy 96.03014 -131.481777) (xy 96.060913 -131.52829) (xy 96.084585 -131.578787) (xy 96.100653 -131.632194)
			(xy 96.108773 -131.68737) (xy 96.109282 -131.715256) (xy 96.108773 -131.743142) (xy 96.100653 -131.798318)
			(xy 96.084585 -131.851725) (xy 96.060913 -131.902222) (xy 96.03014 -131.948735) (xy 95.992923 -131.990272)
			(xy 95.950055 -132.025947) (xy 95.942192 -132.030746) (xy 112.909424 -132.030746) (xy 112.909424 -131.976254)
			(xy 112.917178 -131.922318) (xy 112.932529 -131.870033) (xy 112.955164 -131.820465) (xy 112.984622 -131.774623)
			(xy 113.020304 -131.733439) (xy 113.061483 -131.697752) (xy 113.107321 -131.668288) (xy 113.156886 -131.645647)
			(xy 113.209169 -131.630289) (xy 113.263104 -131.622528) (xy 113.29035 -131.622038) (xy 113.31772 -131.622524)
			(xy 113.371898 -131.630336) (xy 113.424401 -131.64582) (xy 113.474149 -131.668657) (xy 113.520116 -131.698378)
			(xy 113.541048 -131.716018) (xy 113.541302 -131.716272) (xy 113.548378 -131.721874) (xy 113.565303 -131.728109)
			(xy 113.574322 -131.728464) (xy 113.641378 -131.728464) (xy 113.650395 -131.728104) (xy 113.667312 -131.721859)
			(xy 113.674398 -131.716272) (xy 113.674398 -131.716018) (xy 113.674652 -131.716018) (xy 113.695594 -131.698391)
			(xy 113.741564 -131.668677) (xy 113.791309 -131.645838) (xy 113.843807 -131.630344) (xy 113.897981 -131.622513)
			(xy 113.92535 -131.622038) (xy 113.952608 -131.622406) (xy 114.006571 -131.630158) (xy 114.058882 -131.645511)
			(xy 114.108474 -131.668154) (xy 114.154339 -131.697624) (xy 114.195543 -131.733322) (xy 114.231246 -131.774521)
			(xy 114.260722 -131.820382) (xy 114.283371 -131.869971) (xy 114.298732 -131.92228) (xy 114.306491 -131.976242)
			(xy 114.306491 -132.030758) (xy 114.298732 -132.08472) (xy 114.283371 -132.137029) (xy 114.260722 -132.186618)
			(xy 114.231246 -132.232479) (xy 114.195543 -132.273678) (xy 114.154339 -132.309376) (xy 114.108474 -132.338846)
			(xy 114.058882 -132.361489) (xy 114.006571 -132.376842) (xy 113.952609 -132.384594) (xy 113.92535 -132.385054)
			(xy 113.89798 -132.38457) (xy 113.843802 -132.376758) (xy 113.791298 -132.361274) (xy 113.741551 -132.338436)
			(xy 113.695584 -132.308714) (xy 113.674652 -132.291074) (xy 113.674398 -132.29082) (xy 113.667323 -132.285217)
			(xy 113.650397 -132.278982) (xy 113.641378 -132.278628) (xy 113.574322 -132.278628) (xy 113.565305 -132.27899)
			(xy 113.548388 -132.285233) (xy 113.541302 -132.29082) (xy 113.541302 -132.291074) (xy 113.541048 -132.291074)
			(xy 113.520105 -132.3087) (xy 113.474136 -132.338415) (xy 113.424391 -132.361254) (xy 113.371893 -132.376748)
			(xy 113.317719 -132.384579) (xy 113.29035 -132.385054) (xy 113.263104 -132.384472) (xy 113.209169 -132.376711)
			(xy 113.156886 -132.361353) (xy 113.107321 -132.338712) (xy 113.061483 -132.309248) (xy 113.020304 -132.273561)
			(xy 112.984622 -132.232377) (xy 112.955164 -132.186535) (xy 112.932529 -132.136967) (xy 112.917178 -132.084682)
			(xy 112.909424 -132.030746) (xy 95.942192 -132.030746) (xy 95.902449 -132.055001) (xy 95.85112 -132.076813)
			(xy 95.797163 -132.090919) (xy 95.741726 -132.097019) (xy 95.685992 -132.094982) (xy 95.631149 -132.084852)
			(xy 95.578365 -132.066845) (xy 95.528765 -132.041344) (xy 95.483407 -132.008893) (xy 95.443258 -131.970184)
			(xy 95.409172 -131.926041) (xy 95.381876 -131.877406) (xy 95.361953 -131.825315) (xy 95.349827 -131.770878)
			(xy 95.345756 -131.715256) (xy 84.632292 -131.715256) (xy 84.632292 -132.575808) (xy 84.631802 -132.605792)
			(xy 84.623974 -132.665248) (xy 84.608453 -132.723173) (xy 84.585504 -132.778577) (xy 84.55552 -132.830511)
			(xy 84.519014 -132.878087) (xy 84.476609 -132.920492) (xy 84.429033 -132.956998) (xy 84.377099 -132.986982)
			(xy 84.321695 -133.009931) (xy 84.26377 -133.025452) (xy 84.204314 -133.03328) (xy 84.144346 -133.03328)
			(xy 84.08489 -133.025452) (xy 84.026965 -133.009931) (xy 83.971561 -132.986982) (xy 83.919627 -132.956998)
			(xy 83.872051 -132.920492) (xy 83.829646 -132.878087) (xy 83.79314 -132.830511) (xy 83.763156 -132.778577)
			(xy 83.740207 -132.723173) (xy 83.724686 -132.665248) (xy 83.716858 -132.605792) (xy 83.716368 -132.575808)
			(xy 80.832523 -132.575808) (xy 80.755923 -134.369302) (xy 81.07426 -134.369302) (xy 81.07426 -133.505702)
			(xy 81.07475 -133.475718) (xy 81.082578 -133.416262) (xy 81.098099 -133.358337) (xy 81.121048 -133.302933)
			(xy 81.151032 -133.250999) (xy 81.187538 -133.203423) (xy 81.229943 -133.161018) (xy 81.277519 -133.124512)
			(xy 81.329453 -133.094528) (xy 81.384857 -133.071579) (xy 81.442782 -133.056058) (xy 81.502238 -133.04823)
			(xy 81.562206 -133.04823) (xy 81.621662 -133.056058) (xy 81.679587 -133.071579) (xy 81.734991 -133.094528)
			(xy 81.786925 -133.124512) (xy 81.834501 -133.161018) (xy 81.876906 -133.203423) (xy 81.913412 -133.250999)
			(xy 81.943396 -133.302933) (xy 81.966345 -133.358337) (xy 81.981866 -133.416262) (xy 81.985482 -133.443726)
			(xy 127.222758 -133.443726) (xy 127.223224 -133.417412) (xy 127.230457 -133.365282) (xy 127.244775 -133.314639)
			(xy 127.265907 -133.26644) (xy 127.293455 -133.221596) (xy 127.326895 -133.180958) (xy 127.345948 -133.162802)
			(xy 127.353343 -133.155275) (xy 127.361873 -133.135999) (xy 127.362458 -133.125464) (xy 127.362458 -133.050788)
			(xy 127.361961 -133.040234) (xy 127.353405 -133.020938) (xy 127.345948 -133.01345) (xy 127.326865 -132.995322)
			(xy 127.293413 -132.954685) (xy 127.265858 -132.909839) (xy 127.244725 -132.861633) (xy 127.230413 -132.810981)
			(xy 127.223194 -132.758844) (xy 127.222758 -132.732526) (xy 127.223244 -132.705275) (xy 127.231 -132.651327)
			(xy 127.246355 -132.599032) (xy 127.268997 -132.549455) (xy 127.298463 -132.503605) (xy 127.334154 -132.462414)
			(xy 127.375345 -132.426723) (xy 127.421195 -132.397257) (xy 127.470772 -132.374615) (xy 127.523067 -132.35926)
			(xy 127.577015 -132.351504) (xy 127.631517 -132.351504) (xy 127.685465 -132.35926) (xy 127.73776 -132.374615)
			(xy 127.787337 -132.397257) (xy 127.833187 -132.426723) (xy 127.874378 -132.462414) (xy 127.910069 -132.503605)
			(xy 127.939535 -132.549455) (xy 127.962177 -132.599032) (xy 127.977532 -132.651327) (xy 127.985288 -132.705275)
			(xy 127.985774 -132.732526) (xy 127.985332 -132.758841) (xy 127.978093 -132.810971) (xy 127.96377 -132.861614)
			(xy 127.942633 -132.909814) (xy 127.915082 -132.954656) (xy 127.881638 -132.995294) (xy 127.862584 -133.01345)
			(xy 127.855156 -133.020949) (xy 127.846647 -133.040246) (xy 127.846074 -133.050788) (xy 127.846074 -133.125464)
			(xy 127.846617 -133.136012) (xy 127.855143 -133.155307) (xy 127.862584 -133.162802) (xy 127.88163 -133.180967)
			(xy 127.915089 -133.221594) (xy 127.94265 -133.266432) (xy 127.96379 -133.314631) (xy 127.978109 -133.365277)
			(xy 127.985335 -133.41741) (xy 127.985774 -133.443726) (xy 127.985288 -133.470977) (xy 127.977532 -133.524925)
			(xy 127.962177 -133.57722) (xy 127.939535 -133.626797) (xy 127.910069 -133.672647) (xy 127.874378 -133.713838)
			(xy 127.833187 -133.749529) (xy 127.787337 -133.778995) (xy 127.73776 -133.801637) (xy 127.685465 -133.816992)
			(xy 127.631517 -133.824748) (xy 127.577015 -133.824748) (xy 127.523067 -133.816992) (xy 127.470772 -133.801637)
			(xy 127.421195 -133.778995) (xy 127.375345 -133.749529) (xy 127.334154 -133.713838) (xy 127.298463 -133.672647)
			(xy 127.268997 -133.626797) (xy 127.246355 -133.57722) (xy 127.231 -133.524925) (xy 127.223244 -133.470977)
			(xy 127.222758 -133.443726) (xy 81.985482 -133.443726) (xy 81.989694 -133.475718) (xy 81.990184 -133.505702)
			(xy 81.990184 -134.042404) (xy 122.275852 -134.042404) (xy 122.279923 -133.986782) (xy 122.292049 -133.932345)
			(xy 122.311972 -133.880254) (xy 122.339268 -133.831619) (xy 122.373354 -133.787476) (xy 122.413503 -133.748767)
			(xy 122.458861 -133.716316) (xy 122.508461 -133.690815) (xy 122.561245 -133.672808) (xy 122.616088 -133.662678)
			(xy 122.671822 -133.660641) (xy 122.727259 -133.666741) (xy 122.781216 -133.680847) (xy 122.832545 -133.702659)
			(xy 122.880151 -133.731713) (xy 122.923019 -133.767388) (xy 122.960236 -133.808925) (xy 122.991009 -133.855438)
			(xy 123.014681 -133.905935) (xy 123.030749 -133.959342) (xy 123.038869 -134.014518) (xy 123.039378 -134.042404)
			(xy 123.038869 -134.07029) (xy 123.030749 -134.125466) (xy 123.014681 -134.178873) (xy 122.991009 -134.22937)
			(xy 122.960236 -134.275883) (xy 122.923019 -134.31742) (xy 122.880151 -134.353095) (xy 122.832545 -134.382149)
			(xy 122.781216 -134.403961) (xy 122.727259 -134.418067) (xy 122.671822 -134.424167) (xy 122.616088 -134.42213)
			(xy 122.561245 -134.412) (xy 122.508461 -134.393993) (xy 122.458861 -134.368492) (xy 122.413503 -134.336041)
			(xy 122.373354 -134.297332) (xy 122.339268 -134.253189) (xy 122.311972 -134.204554) (xy 122.292049 -134.152463)
			(xy 122.279923 -134.098026) (xy 122.275852 -134.042404) (xy 81.990184 -134.042404) (xy 81.990184 -134.369302)
			(xy 81.989694 -134.399286) (xy 81.981866 -134.458742) (xy 81.966345 -134.516667) (xy 81.943396 -134.572071)
			(xy 81.913412 -134.624005) (xy 81.876906 -134.671581) (xy 81.834501 -134.713986) (xy 81.786925 -134.750492)
			(xy 81.734991 -134.780476) (xy 81.679587 -134.803425) (xy 81.621662 -134.818946) (xy 81.562206 -134.826774)
			(xy 81.502238 -134.826774) (xy 81.442782 -134.818946) (xy 81.384857 -134.803425) (xy 81.329453 -134.780476)
			(xy 81.277519 -134.750492) (xy 81.229943 -134.713986) (xy 81.187538 -134.671581) (xy 81.151032 -134.624005)
			(xy 81.121048 -134.572071) (xy 81.098099 -134.516667) (xy 81.082578 -134.458742) (xy 81.07475 -134.399286)
			(xy 81.07426 -134.369302) (xy 80.755923 -134.369302) (xy 80.695292 -135.788908) (xy 80.695292 -136.17575)
			(xy 83.716368 -136.17575) (xy 83.716368 -135.31215) (xy 83.716858 -135.282166) (xy 83.724686 -135.22271)
			(xy 83.740207 -135.164785) (xy 83.763156 -135.109381) (xy 83.79314 -135.057447) (xy 83.829646 -135.009871)
			(xy 83.872051 -134.967466) (xy 83.919627 -134.93096) (xy 83.971561 -134.900976) (xy 84.026965 -134.878027)
			(xy 84.08489 -134.862506) (xy 84.144346 -134.854678) (xy 84.204314 -134.854678) (xy 84.26377 -134.862506)
			(xy 84.321695 -134.878027) (xy 84.377099 -134.900976) (xy 84.429033 -134.93096) (xy 84.476609 -134.967466)
			(xy 84.519014 -135.009871) (xy 84.55552 -135.057447) (xy 84.585504 -135.109381) (xy 84.599036 -135.142051)
			(xy 125.46177 -135.142051) (xy 125.46177 -135.087549) (xy 125.469526 -135.033603) (xy 125.48488 -134.981309)
			(xy 125.50752 -134.931732) (xy 125.536985 -134.885882) (xy 125.572674 -134.844691) (xy 125.613862 -134.808999)
			(xy 125.659711 -134.779531) (xy 125.709286 -134.756888) (xy 125.761579 -134.741531) (xy 125.815525 -134.733771)
			(xy 125.842776 -134.733284) (xy 125.871694 -134.733788) (xy 125.928867 -134.742515) (xy 125.984068 -134.759774)
			(xy 126.03603 -134.785168) (xy 126.083563 -134.818116) (xy 126.125578 -134.857862) (xy 126.143766 -134.88035)
			(xy 126.151557 -134.889338) (xy 126.173023 -134.899526) (xy 126.184914 -134.899908) (xy 126.278386 -134.897876)
			(xy 126.299722 -134.8867) (xy 126.30658 -134.876794) (xy 126.321977 -134.855883) (xy 126.357555 -134.818056)
			(xy 126.397935 -134.785404) (xy 126.442369 -134.75853) (xy 126.490038 -134.737929) (xy 126.54006 -134.723985)
			(xy 126.591511 -134.716952) (xy 126.617476 -134.71652) (xy 126.644846 -134.716995) (xy 126.699025 -134.72481)
			(xy 126.751528 -134.740297) (xy 126.801275 -134.763137) (xy 126.847242 -134.792859) (xy 126.868174 -134.8105)
			(xy 126.868428 -134.810754) (xy 126.875526 -134.816323) (xy 126.892434 -134.822579) (xy 126.901448 -134.822946)
			(xy 126.968504 -134.822946) (xy 126.977522 -134.822602) (xy 126.99444 -134.816347) (xy 127.001524 -134.810754)
			(xy 127.001524 -134.8105) (xy 127.001778 -134.8105) (xy 127.022711 -134.792859) (xy 127.068679 -134.763135)
			(xy 127.118425 -134.740289) (xy 127.170927 -134.724793) (xy 127.225105 -134.716964) (xy 127.279847 -134.716964)
			(xy 127.334025 -134.724793) (xy 127.386527 -134.740289) (xy 127.436273 -134.763135) (xy 127.482241 -134.792859)
			(xy 127.503174 -134.8105) (xy 127.503428 -134.810754) (xy 127.510526 -134.816323) (xy 127.527434 -134.822579)
			(xy 127.536448 -134.822946) (xy 127.603504 -134.822946) (xy 127.612522 -134.822602) (xy 127.62944 -134.816347)
			(xy 127.636524 -134.810754) (xy 127.637032 -134.8105) (xy 127.64977 -134.79956) (xy 127.676859 -134.779716)
			(xy 127.691134 -134.770876) (xy 127.700024 -134.765542) (xy 127.712216 -134.748524) (xy 127.732536 -134.655306)
			(xy 127.728218 -134.634732) (xy 127.722376 -134.626096) (xy 127.706369 -134.602036) (xy 127.681029 -134.550103)
			(xy 127.663805 -134.494944) (xy 127.655092 -134.437819) (xy 127.654558 -134.408926) (xy 127.655044 -134.381675)
			(xy 127.6628 -134.327727) (xy 127.678155 -134.275432) (xy 127.700797 -134.225855) (xy 127.730263 -134.180005)
			(xy 127.765954 -134.138814) (xy 127.807145 -134.103123) (xy 127.852995 -134.073657) (xy 127.902572 -134.051015)
			(xy 127.954867 -134.03566) (xy 128.008815 -134.027904) (xy 128.063317 -134.027904) (xy 128.117265 -134.03566)
			(xy 128.16956 -134.051015) (xy 128.219137 -134.073657) (xy 128.264987 -134.103123) (xy 128.306178 -134.138814)
			(xy 128.341869 -134.180005) (xy 128.371335 -134.225855) (xy 128.393977 -134.275432) (xy 128.409332 -134.327727)
			(xy 128.417088 -134.381675) (xy 128.417574 -134.408926) (xy 128.417121 -134.437019) (xy 128.408889 -134.492599)
			(xy 128.392592 -134.54637) (xy 128.368583 -134.597169) (xy 128.337381 -134.643895) (xy 128.299662 -134.685539)
			(xy 128.256242 -134.721198) (xy 128.232408 -134.736078) (xy 128.223518 -134.741412) (xy 128.211326 -134.75843)
			(xy 128.191006 -134.851648) (xy 128.195324 -134.872222) (xy 128.201166 -134.880858) (xy 128.217146 -134.904934)
			(xy 128.242495 -134.956861) (xy 128.259726 -135.012015) (xy 128.268447 -135.069136) (xy 128.268984 -135.098028)
			(xy 128.268548 -135.125281) (xy 128.260787 -135.179232) (xy 128.245427 -135.231529) (xy 128.222781 -135.281108)
			(xy 128.19331 -135.326959) (xy 128.157613 -135.36815) (xy 128.116418 -135.403841) (xy 128.070562 -135.433306)
			(xy 128.02098 -135.455946) (xy 127.968681 -135.471298) (xy 127.914729 -135.479052) (xy 127.887476 -135.479536)
			(xy 127.860105 -135.4791) (xy 127.805924 -135.471277) (xy 127.753419 -135.455782) (xy 127.703673 -135.432933)
			(xy 127.657708 -135.403201) (xy 127.636778 -135.385556) (xy 127.636524 -135.385302) (xy 127.629435 -135.37972)
			(xy 127.61252 -135.37347) (xy 127.603504 -135.37311) (xy 127.536448 -135.37311) (xy 127.527433 -135.373488)
			(xy 127.510516 -135.379721) (xy 127.503428 -135.385302) (xy 127.503428 -135.385556) (xy 127.503174 -135.385556)
			(xy 127.482241 -135.403197) (xy 127.436273 -135.432921) (xy 127.386527 -135.455767) (xy 127.334025 -135.471263)
			(xy 127.279847 -135.479092) (xy 127.225105 -135.479092) (xy 127.170927 -135.471263) (xy 127.118425 -135.455767)
			(xy 127.068679 -135.432921) (xy 127.022711 -135.403197) (xy 127.001778 -135.385556) (xy 127.001524 -135.385302)
			(xy 126.994435 -135.37972) (xy 126.97752 -135.37347) (xy 126.968504 -135.37311) (xy 126.901448 -135.37311)
			(xy 126.892433 -135.373488) (xy 126.875516 -135.379721) (xy 126.868428 -135.385302) (xy 126.868428 -135.385556)
			(xy 126.868174 -135.385556) (xy 126.847219 -135.403167) (xy 126.801253 -135.432885) (xy 126.751512 -135.455727)
			(xy 126.699016 -135.471224) (xy 126.644844 -135.479059) (xy 126.617476 -135.479536) (xy 126.58856 -135.478987)
			(xy 126.531389 -135.470268) (xy 126.47619 -135.453018) (xy 126.424227 -135.427632) (xy 126.376693 -135.394692)
			(xy 126.334676 -135.354954) (xy 126.316486 -135.33247) (xy 126.308668 -135.323509) (xy 126.287222 -135.313305)
			(xy 126.275338 -135.312912) (xy 126.181866 -135.314944) (xy 126.16053 -135.32612) (xy 126.153672 -135.336026)
			(xy 126.138249 -135.356917) (xy 126.102675 -135.394743) (xy 126.062299 -135.427397) (xy 126.017869 -135.454273)
			(xy 125.970205 -135.474877) (xy 125.920187 -135.488826) (xy 125.868739 -135.495864) (xy 125.842776 -135.4963)
			(xy 125.815525 -135.495829) (xy 125.761579 -135.488069) (xy 125.709286 -135.472712) (xy 125.659711 -135.450069)
			(xy 125.613862 -135.420601) (xy 125.572674 -135.384909) (xy 125.536985 -135.343718) (xy 125.50752 -135.297868)
			(xy 125.48488 -135.248291) (xy 125.469526 -135.195997) (xy 125.46177 -135.142051) (xy 84.599036 -135.142051)
			(xy 84.608453 -135.164785) (xy 84.623974 -135.22271) (xy 84.631802 -135.282166) (xy 84.632292 -135.31215)
			(xy 84.632292 -135.699246) (xy 122.258326 -135.699246) (xy 122.262397 -135.643624) (xy 122.274523 -135.589187)
			(xy 122.294446 -135.537096) (xy 122.321742 -135.488461) (xy 122.355828 -135.444318) (xy 122.395977 -135.405609)
			(xy 122.441335 -135.373158) (xy 122.490935 -135.347657) (xy 122.543719 -135.32965) (xy 122.598562 -135.31952)
			(xy 122.654296 -135.317483) (xy 122.709733 -135.323583) (xy 122.76369 -135.337689) (xy 122.815019 -135.359501)
			(xy 122.862625 -135.388555) (xy 122.905493 -135.42423) (xy 122.94271 -135.465767) (xy 122.973483 -135.51228)
			(xy 122.997155 -135.562777) (xy 123.013223 -135.616184) (xy 123.021343 -135.67136) (xy 123.021852 -135.699246)
			(xy 123.021343 -135.727132) (xy 123.013223 -135.782308) (xy 122.997155 -135.835715) (xy 122.982543 -135.866886)
			(xy 124.539754 -135.866886) (xy 124.543825 -135.811264) (xy 124.555951 -135.756827) (xy 124.575874 -135.704736)
			(xy 124.60317 -135.656101) (xy 124.637256 -135.611958) (xy 124.677405 -135.573249) (xy 124.722763 -135.540798)
			(xy 124.772363 -135.515297) (xy 124.825147 -135.49729) (xy 124.87999 -135.48716) (xy 124.935724 -135.485123)
			(xy 124.991161 -135.491223) (xy 125.045118 -135.505329) (xy 125.096447 -135.527141) (xy 125.144053 -135.556195)
			(xy 125.186921 -135.59187) (xy 125.224138 -135.633407) (xy 125.254911 -135.67992) (xy 125.278583 -135.730417)
			(xy 125.294651 -135.783824) (xy 125.302771 -135.839) (xy 125.30328 -135.866886) (xy 125.302771 -135.894772)
			(xy 125.294651 -135.949948) (xy 125.278583 -136.003355) (xy 125.254911 -136.053852) (xy 125.224138 -136.100365)
			(xy 125.186921 -136.141902) (xy 125.144053 -136.177577) (xy 125.096447 -136.206631) (xy 125.045118 -136.228443)
			(xy 124.991161 -136.242549) (xy 124.935724 -136.248649) (xy 124.87999 -136.246612) (xy 124.825147 -136.236482)
			(xy 124.772363 -136.218475) (xy 124.722763 -136.192974) (xy 124.677405 -136.160523) (xy 124.637256 -136.121814)
			(xy 124.60317 -136.077671) (xy 124.575874 -136.029036) (xy 124.555951 -135.976945) (xy 124.543825 -135.922508)
			(xy 124.539754 -135.866886) (xy 122.982543 -135.866886) (xy 122.973483 -135.886212) (xy 122.94271 -135.932725)
			(xy 122.905493 -135.974262) (xy 122.862625 -136.009937) (xy 122.815019 -136.038991) (xy 122.76369 -136.060803)
			(xy 122.709733 -136.074909) (xy 122.654296 -136.081009) (xy 122.598562 -136.078972) (xy 122.543719 -136.068842)
			(xy 122.490935 -136.050835) (xy 122.441335 -136.025334) (xy 122.395977 -135.992883) (xy 122.355828 -135.954174)
			(xy 122.321742 -135.910031) (xy 122.294446 -135.861396) (xy 122.274523 -135.809305) (xy 122.262397 -135.754868)
			(xy 122.258326 -135.699246) (xy 84.632292 -135.699246) (xy 84.632292 -136.17575) (xy 84.631802 -136.205734)
			(xy 84.623974 -136.26519) (xy 84.608453 -136.323115) (xy 84.585504 -136.378519) (xy 84.55552 -136.430453)
			(xy 84.519014 -136.478029) (xy 84.476609 -136.520434) (xy 84.429033 -136.55694) (xy 84.377099 -136.586924)
			(xy 84.321695 -136.609873) (xy 84.26377 -136.625394) (xy 84.204314 -136.633222) (xy 84.144346 -136.633222)
			(xy 84.08489 -136.625394) (xy 84.026965 -136.609873) (xy 83.971561 -136.586924) (xy 83.919627 -136.55694)
			(xy 83.872051 -136.520434) (xy 83.829646 -136.478029) (xy 83.79314 -136.430453) (xy 83.763156 -136.378519)
			(xy 83.740207 -136.323115) (xy 83.724686 -136.26519) (xy 83.716858 -136.205734) (xy 83.716368 -136.17575)
			(xy 80.695292 -136.17575) (xy 80.695292 -136.524238) (xy 80.695546 -136.528302) (xy 80.696959 -136.538916)
			(xy 80.707195 -136.557695) (xy 80.715358 -136.564624) (xy 80.715866 -136.565132) (xy 80.760824 -136.598406)
			(xy 80.781398 -136.613646) (xy 80.786351 -136.617164) (xy 80.797527 -136.621915) (xy 80.803496 -136.623044)
			(xy 80.81518 -136.624822) (xy 80.82661 -136.621266) (xy 80.854013 -136.613428) (xy 80.910381 -136.605005)
			(xy 80.938878 -136.604502) (xy 80.93964 -136.604502) (xy 80.966889 -136.604991) (xy 81.020831 -136.612752)
			(xy 81.073119 -136.62811) (xy 81.12269 -136.650753) (xy 81.168534 -136.680219) (xy 81.209718 -136.71591)
			(xy 81.245405 -136.757098) (xy 81.274866 -136.802945) (xy 81.297504 -136.852518) (xy 81.312857 -136.904809)
			(xy 81.320612 -136.958751) (xy 81.320612 -137.013249) (xy 81.312857 -137.067191) (xy 81.297504 -137.119482)
			(xy 81.274866 -137.169055) (xy 81.245405 -137.214902) (xy 81.209718 -137.25609) (xy 81.168534 -137.291781)
			(xy 81.12269 -137.321247) (xy 81.073119 -137.34389) (xy 81.020831 -137.359248) (xy 80.966889 -137.367009)
			(xy 80.93964 -137.367518) (xy 80.938878 -137.367518) (xy 80.909241 -137.366938) (xy 80.850682 -137.357755)
			(xy 80.822292 -137.34923) (xy 80.814926 -137.346944) (xy 80.803496 -137.348722) (xy 80.797542 -137.349901)
			(xy 80.786375 -137.354647) (xy 80.781398 -137.35812) (xy 80.715358 -137.407142) (xy 80.706373 -137.414736)
			(xy 80.695914 -137.43578) (xy 80.695292 -137.447528) (xy 80.695292 -137.44829) (xy 124.445012 -137.44829)
			(xy 124.449083 -137.392668) (xy 124.461209 -137.338231) (xy 124.481132 -137.28614) (xy 124.508428 -137.237505)
			(xy 124.542514 -137.193362) (xy 124.582663 -137.154653) (xy 124.628021 -137.122202) (xy 124.677621 -137.096701)
			(xy 124.730405 -137.078694) (xy 124.785248 -137.068564) (xy 124.840982 -137.066527) (xy 124.896419 -137.072627)
			(xy 124.950376 -137.086733) (xy 125.001705 -137.108545) (xy 125.049311 -137.137599) (xy 125.092179 -137.173274)
			(xy 125.129396 -137.214811) (xy 125.160169 -137.261324) (xy 125.167204 -137.276332) (xy 129.147062 -137.276332)
			(xy 129.147532 -137.248962) (xy 129.155346 -137.194782) (xy 129.170834 -137.142279) (xy 129.193675 -137.092532)
			(xy 129.2234 -137.046565) (xy 129.241042 -137.025634) (xy 129.241296 -137.02538) (xy 129.246897 -137.018303)
			(xy 129.253135 -137.001379) (xy 129.253488 -136.99236) (xy 129.253488 -136.925304) (xy 129.253132 -136.916287)
			(xy 129.246884 -136.89937) (xy 129.241296 -136.892284) (xy 129.241042 -136.892284) (xy 129.241042 -136.89203)
			(xy 129.22341 -136.871092) (xy 129.193696 -136.825122) (xy 129.170858 -136.775376) (xy 129.155365 -136.722876)
			(xy 129.147536 -136.668701) (xy 129.147062 -136.641332) (xy 129.147548 -136.614081) (xy 129.155304 -136.560133)
			(xy 129.170659 -136.507838) (xy 129.193301 -136.458261) (xy 129.222767 -136.412411) (xy 129.258458 -136.37122)
			(xy 129.299649 -136.335529) (xy 129.345499 -136.306063) (xy 129.395076 -136.283421) (xy 129.447371 -136.268066)
			(xy 129.501319 -136.26031) (xy 129.555821 -136.26031) (xy 129.609769 -136.268066) (xy 129.662064 -136.283421)
			(xy 129.711641 -136.306063) (xy 129.757491 -136.335529) (xy 129.798682 -136.37122) (xy 129.834373 -136.412411)
			(xy 129.863839 -136.458261) (xy 129.886481 -136.507838) (xy 129.901836 -136.560133) (xy 129.909592 -136.614081)
			(xy 129.910078 -136.641332) (xy 129.909636 -136.668703) (xy 129.901813 -136.722883) (xy 129.886319 -136.775387)
			(xy 129.863472 -136.825134) (xy 129.833742 -136.871099) (xy 129.816098 -136.89203) (xy 129.815844 -136.892284)
			(xy 129.810251 -136.899366) (xy 129.80401 -136.916287) (xy 129.803652 -136.925304) (xy 129.803652 -136.99236)
			(xy 129.804017 -137.001376) (xy 129.810258 -137.018294) (xy 129.815844 -137.02538) (xy 129.816098 -137.02538)
			(xy 129.816098 -137.025634) (xy 129.833719 -137.04658) (xy 129.863434 -137.092549) (xy 129.886273 -137.142293)
			(xy 129.901769 -137.194791) (xy 129.909601 -137.248964) (xy 129.910078 -137.276332) (xy 129.909592 -137.303583)
			(xy 129.901836 -137.357531) (xy 129.886481 -137.409826) (xy 129.863839 -137.459403) (xy 129.834373 -137.505253)
			(xy 129.798682 -137.546444) (xy 129.757491 -137.582135) (xy 129.711641 -137.611601) (xy 129.662064 -137.634243)
			(xy 129.609769 -137.649598) (xy 129.555821 -137.657354) (xy 129.501319 -137.657354) (xy 129.447371 -137.649598)
			(xy 129.395076 -137.634243) (xy 129.345499 -137.611601) (xy 129.299649 -137.582135) (xy 129.258458 -137.546444)
			(xy 129.222767 -137.505253) (xy 129.193301 -137.459403) (xy 129.170659 -137.409826) (xy 129.155304 -137.357531)
			(xy 129.147548 -137.303583) (xy 129.147062 -137.276332) (xy 125.167204 -137.276332) (xy 125.183841 -137.311821)
			(xy 125.199909 -137.365228) (xy 125.208029 -137.420404) (xy 125.208538 -137.44829) (xy 125.208029 -137.476176)
			(xy 125.199909 -137.531352) (xy 125.183841 -137.584759) (xy 125.160169 -137.635256) (xy 125.129396 -137.681769)
			(xy 125.092179 -137.723306) (xy 125.088132 -137.726674) (xy 130.087624 -137.726674) (xy 130.088069 -137.699303)
			(xy 130.095891 -137.645123) (xy 130.111385 -137.592619) (xy 130.134231 -137.542873) (xy 130.16396 -137.496907)
			(xy 130.181604 -137.475976) (xy 130.181858 -137.475722) (xy 130.187448 -137.468638) (xy 130.193691 -137.451719)
			(xy 130.19405 -137.442702) (xy 130.19405 -137.375646) (xy 130.193682 -137.36663) (xy 130.187443 -137.349712)
			(xy 130.181858 -137.342626) (xy 130.181604 -137.342626) (xy 130.181604 -137.342372) (xy 130.163986 -137.321423)
			(xy 130.134271 -137.275455) (xy 130.111431 -137.225712) (xy 130.095935 -137.173215) (xy 130.088101 -137.119042)
			(xy 130.087624 -137.091674) (xy 130.08811 -137.064423) (xy 130.095866 -137.010475) (xy 130.111221 -136.95818)
			(xy 130.133863 -136.908603) (xy 130.163329 -136.862753) (xy 130.19902 -136.821562) (xy 130.240211 -136.785871)
			(xy 130.286061 -136.756405) (xy 130.335638 -136.733763) (xy 130.387933 -136.718408) (xy 130.441881 -136.710652)
			(xy 130.496383 -136.710652) (xy 130.550331 -136.718408) (xy 130.602626 -136.733763) (xy 130.652203 -136.756405)
			(xy 130.698053 -136.785871) (xy 130.739244 -136.821562) (xy 130.774935 -136.862753) (xy 130.804401 -136.908603)
			(xy 130.827043 -136.95818) (xy 130.842398 -137.010475) (xy 130.850154 -137.064423) (xy 130.85064 -137.091674)
			(xy 130.850173 -137.119044) (xy 130.842358 -137.173224) (xy 130.82687 -137.225728) (xy 130.804028 -137.275475)
			(xy 130.774302 -137.321441) (xy 130.75666 -137.342372) (xy 130.756406 -137.342626) (xy 130.750845 -137.34973)
			(xy 130.744583 -137.366633) (xy 130.744214 -137.375646) (xy 130.744214 -137.442702) (xy 130.744567 -137.451719)
			(xy 130.750817 -137.468636) (xy 130.756406 -137.475722) (xy 130.75666 -137.475722) (xy 130.75666 -137.475976)
			(xy 130.774295 -137.496911) (xy 130.804009 -137.542883) (xy 130.826846 -137.592629) (xy 130.842338 -137.645129)
			(xy 130.850166 -137.699305) (xy 130.85064 -137.726674) (xy 130.850154 -137.753925) (xy 130.842398 -137.807873)
			(xy 130.827043 -137.860168) (xy 130.804401 -137.909745) (xy 130.774935 -137.955595) (xy 130.739244 -137.996786)
			(xy 130.698053 -138.032477) (xy 130.652203 -138.061943) (xy 130.602626 -138.084585) (xy 130.550331 -138.09994)
			(xy 130.496383 -138.107696) (xy 130.441881 -138.107696) (xy 130.387933 -138.09994) (xy 130.335638 -138.084585)
			(xy 130.286061 -138.061943) (xy 130.240211 -138.032477) (xy 130.19902 -137.996786) (xy 130.163329 -137.955595)
			(xy 130.133863 -137.909745) (xy 130.111221 -137.860168) (xy 130.095866 -137.807873) (xy 130.08811 -137.753925)
			(xy 130.087624 -137.726674) (xy 125.088132 -137.726674) (xy 125.049311 -137.758981) (xy 125.001705 -137.788035)
			(xy 124.950376 -137.809847) (xy 124.896419 -137.823953) (xy 124.840982 -137.830053) (xy 124.785248 -137.828016)
			(xy 124.730405 -137.817886) (xy 124.677621 -137.799879) (xy 124.628021 -137.774378) (xy 124.582663 -137.741927)
			(xy 124.542514 -137.703218) (xy 124.508428 -137.659075) (xy 124.481132 -137.61044) (xy 124.461209 -137.558349)
			(xy 124.449083 -137.503912) (xy 124.445012 -137.44829) (xy 80.695292 -137.44829) (xy 80.695292 -138.358372)
			(xy 84.809328 -138.358372) (xy 84.813399 -138.30275) (xy 84.825525 -138.248313) (xy 84.845448 -138.196222)
			(xy 84.872744 -138.147587) (xy 84.90683 -138.103444) (xy 84.946979 -138.064735) (xy 84.992337 -138.032284)
			(xy 85.041937 -138.006783) (xy 85.094721 -137.988776) (xy 85.149564 -137.978646) (xy 85.205298 -137.976609)
			(xy 85.260735 -137.982709) (xy 85.314692 -137.996815) (xy 85.366021 -138.018627) (xy 85.413627 -138.047681)
			(xy 85.456495 -138.083356) (xy 85.493712 -138.124893) (xy 85.524485 -138.171406) (xy 85.548157 -138.221903)
			(xy 85.564225 -138.27531) (xy 85.572345 -138.330486) (xy 85.572854 -138.358372) (xy 85.572345 -138.386258)
			(xy 85.564225 -138.441434) (xy 85.548157 -138.494841) (xy 85.524485 -138.545338) (xy 85.493712 -138.591851)
			(xy 85.456495 -138.633388) (xy 85.413627 -138.669063) (xy 85.366021 -138.698117) (xy 85.314692 -138.719929)
			(xy 85.260735 -138.734035) (xy 85.205298 -138.740135) (xy 85.149564 -138.738098) (xy 85.094721 -138.727968)
			(xy 85.041937 -138.709961) (xy 84.992337 -138.68446) (xy 84.946979 -138.652009) (xy 84.90683 -138.6133)
			(xy 84.872744 -138.569157) (xy 84.845448 -138.520522) (xy 84.825525 -138.468431) (xy 84.813399 -138.413994)
			(xy 84.809328 -138.358372) (xy 80.695292 -138.358372) (xy 80.695292 -139.03706) (xy 106.080052 -139.03706)
			(xy 106.080564 -139.008321) (xy 106.089192 -138.951494) (xy 106.106245 -138.896603) (xy 106.131339 -138.844892)
			(xy 106.163905 -138.797529) (xy 106.183176 -138.776202) (xy 106.18978 -138.769344) (xy 106.196892 -138.75131)
			(xy 106.196892 -138.66241) (xy 106.18978 -138.644376) (xy 106.183176 -138.637518) (xy 106.163893 -138.616202)
			(xy 106.131327 -138.568838) (xy 106.106236 -138.517123) (xy 106.089188 -138.46223) (xy 106.08057 -138.4054)
			(xy 106.080052 -138.37666) (xy 106.080538 -138.349409) (xy 106.088294 -138.295461) (xy 106.103649 -138.243166)
			(xy 106.126291 -138.193589) (xy 106.155757 -138.147739) (xy 106.191448 -138.106548) (xy 106.232639 -138.070857)
			(xy 106.278489 -138.041391) (xy 106.328066 -138.018749) (xy 106.380361 -138.003394) (xy 106.434309 -137.995638)
			(xy 106.488811 -137.995638) (xy 106.542759 -138.003394) (xy 106.595054 -138.018749) (xy 106.644631 -138.041391)
			(xy 106.690481 -138.070857) (xy 106.731672 -138.106548) (xy 106.767363 -138.147739) (xy 106.796829 -138.193589)
			(xy 106.819471 -138.243166) (xy 106.834826 -138.295461) (xy 106.842582 -138.349409) (xy 106.843068 -138.37666)
			(xy 106.842563 -138.405399) (xy 106.833933 -138.462227) (xy 106.816877 -138.517117) (xy 106.791782 -138.568828)
			(xy 106.759215 -138.616191) (xy 106.739944 -138.637518) (xy 106.73334 -138.644376) (xy 106.726228 -138.66241)
			(xy 106.726228 -138.75131) (xy 106.73334 -138.769344) (xy 106.739944 -138.776202) (xy 106.759193 -138.797548)
			(xy 106.791763 -138.844905) (xy 106.81686 -138.896611) (xy 106.833916 -138.951498) (xy 106.842544 -139.008322)
			(xy 106.843068 -139.03706) (xy 106.842617 -139.062965) (xy 106.835599 -139.114299) (xy 106.821702 -139.164211)
			(xy 106.80118 -139.211785) (xy 106.774411 -139.256145) (xy 106.758486 -139.276582) (xy 106.752749 -139.284343)
			(xy 106.747003 -139.30275) (xy 106.74731 -139.312396) (xy 106.752898 -139.381992) (xy 106.753985 -139.391424)
			(xy 106.76222 -139.408518) (xy 106.7689 -139.415266) (xy 106.769408 -139.415774) (xy 106.788658 -139.433887)
			(xy 106.822417 -139.474559) (xy 106.85024 -139.5195) (xy 106.871596 -139.56785) (xy 106.886076 -139.618685)
			(xy 106.893402 -139.671032) (xy 106.893868 -139.69746) (xy 106.893363 -139.726199) (xy 106.884733 -139.783027)
			(xy 106.867677 -139.837917) (xy 106.842582 -139.889628) (xy 106.810015 -139.936991) (xy 106.790744 -139.958318)
			(xy 106.78414 -139.965176) (xy 106.777028 -139.98321) (xy 106.777028 -140.07211) (xy 106.78414 -140.090144)
			(xy 106.790744 -140.097002) (xy 106.809977 -140.118362) (xy 106.842546 -140.165718) (xy 106.867642 -140.217424)
			(xy 106.884696 -140.27231) (xy 106.893323 -140.329134) (xy 106.893328 -140.386608) (xy 106.884709 -140.443433)
			(xy 106.867663 -140.498321) (xy 106.842575 -140.550031) (xy 106.810013 -140.597392) (xy 106.790744 -140.618718)
			(xy 106.78414 -140.625576) (xy 106.777028 -140.64361) (xy 106.777028 -140.73251) (xy 106.78414 -140.750544)
			(xy 106.790744 -140.757402) (xy 106.809993 -140.778748) (xy 106.842563 -140.826105) (xy 106.86766 -140.877811)
			(xy 106.884716 -140.932698) (xy 106.893344 -140.989522) (xy 106.893868 -141.01826) (xy 108.518452 -141.01826)
			(xy 108.518964 -140.989521) (xy 108.527592 -140.932694) (xy 108.544645 -140.877803) (xy 108.569739 -140.826092)
			(xy 108.602305 -140.778729) (xy 108.621576 -140.757402) (xy 108.62818 -140.750544) (xy 108.635292 -140.73251)
			(xy 108.635292 -140.64361) (xy 108.62818 -140.625576) (xy 108.621576 -140.618718) (xy 108.602268 -140.597425)
			(xy 108.569708 -140.550055) (xy 108.544622 -140.498337) (xy 108.527577 -140.443442) (xy 108.518959 -140.386611)
			(xy 108.518963 -140.329131) (xy 108.52759 -140.272301) (xy 108.544643 -140.217408) (xy 108.569737 -140.165694)
			(xy 108.602304 -140.11833) (xy 108.621576 -140.097002) (xy 108.62818 -140.090144) (xy 108.635292 -140.07211)
			(xy 108.635292 -139.98321) (xy 108.62818 -139.965176) (xy 108.621576 -139.958318) (xy 108.602293 -139.937002)
			(xy 108.569727 -139.889638) (xy 108.544636 -139.837923) (xy 108.527588 -139.78303) (xy 108.51897 -139.7262)
			(xy 108.518452 -139.69746) (xy 108.518993 -139.668544) (xy 108.527715 -139.611373) (xy 108.544967 -139.556173)
			(xy 108.570354 -139.504211) (xy 108.603295 -139.456677) (xy 108.643033 -139.41466) (xy 108.665518 -139.39647)
			(xy 108.674332 -139.388869) (xy 108.684511 -139.367964) (xy 108.685076 -139.356338) (xy 108.685076 -139.276582)
			(xy 108.684541 -139.264949) (xy 108.67435 -139.244039) (xy 108.665518 -139.23645) (xy 108.643062 -139.218226)
			(xy 108.603324 -139.176214) (xy 108.570382 -139.128686) (xy 108.544988 -139.076731) (xy 108.527726 -139.021539)
			(xy 108.518991 -138.964374) (xy 108.518452 -138.93546) (xy 108.518964 -138.906721) (xy 108.527592 -138.849894)
			(xy 108.544645 -138.795003) (xy 108.569739 -138.743292) (xy 108.602305 -138.695929) (xy 108.621576 -138.674602)
			(xy 108.62818 -138.667744) (xy 108.635292 -138.64971) (xy 108.635292 -138.56081) (xy 108.62818 -138.542776)
			(xy 108.621576 -138.535918) (xy 108.602293 -138.514602) (xy 108.569727 -138.467238) (xy 108.544636 -138.415523)
			(xy 108.527588 -138.36063) (xy 108.51897 -138.3038) (xy 108.518452 -138.27506) (xy 108.51894 -138.24781)
			(xy 108.526701 -138.193864) (xy 108.54206 -138.141572) (xy 108.564702 -138.091997) (xy 108.594169 -138.046149)
			(xy 108.62986 -138.00496) (xy 108.671049 -137.969269) (xy 108.716897 -137.939802) (xy 108.766472 -137.91716)
			(xy 108.818764 -137.901801) (xy 108.87271 -137.89404) (xy 108.89996 -137.893552) (xy 108.929295 -137.894104)
			(xy 108.987274 -137.903069) (xy 109.043197 -137.920808) (xy 109.095742 -137.946903) (xy 109.143671 -137.980739)
			(xy 109.165136 -138.00074) (xy 109.172502 -138.007852) (xy 109.190282 -138.014964) (xy 109.281214 -138.014964)
			(xy 109.298994 -138.007852) (xy 109.30636 -138.00074) (xy 109.327833 -137.980749) (xy 109.375767 -137.946923)
			(xy 109.42831 -137.920828) (xy 109.484228 -137.903079) (xy 109.542203 -137.894094) (xy 109.571536 -137.893552)
			(xy 109.598786 -137.894044) (xy 109.652732 -137.901805) (xy 109.705024 -137.917162) (xy 109.754599 -137.939805)
			(xy 109.800447 -137.969271) (xy 109.841636 -138.004962) (xy 109.877327 -138.04615) (xy 109.906793 -138.091998)
			(xy 109.929436 -138.141572) (xy 109.944795 -138.193864) (xy 109.952556 -138.24781) (xy 109.953044 -138.27506)
			(xy 109.952545 -138.3038) (xy 109.943915 -138.360628) (xy 109.926858 -138.415518) (xy 109.901761 -138.467229)
			(xy 109.869192 -138.514591) (xy 109.84992 -138.535918) (xy 109.843316 -138.542776) (xy 109.836204 -138.56081)
			(xy 109.836204 -138.64971) (xy 109.843316 -138.667744) (xy 109.84992 -138.674602) (xy 109.869165 -138.695952)
			(xy 109.901736 -138.743307) (xy 109.926834 -138.795013) (xy 109.943891 -138.849899) (xy 109.95252 -138.906722)
			(xy 109.953044 -138.93546) (xy 112.090708 -138.93546) (xy 112.091205 -138.90672) (xy 112.099834 -138.849891)
			(xy 112.11689 -138.795) (xy 112.141988 -138.743289) (xy 112.174559 -138.695928) (xy 112.193832 -138.674602)
			(xy 112.200436 -138.667744) (xy 112.207548 -138.64971) (xy 112.207548 -138.56081) (xy 112.200436 -138.542776)
			(xy 112.193832 -138.535918) (xy 112.174541 -138.514608) (xy 112.141978 -138.467241) (xy 112.116889 -138.415525)
			(xy 112.099844 -138.360631) (xy 112.091226 -138.3038) (xy 112.090708 -138.27506) (xy 112.091194 -138.247809)
			(xy 112.09895 -138.193861) (xy 112.114305 -138.141566) (xy 112.136947 -138.091989) (xy 112.166413 -138.046139)
			(xy 112.202104 -138.004948) (xy 112.243295 -137.969257) (xy 112.289145 -137.939791) (xy 112.338722 -137.917149)
			(xy 112.391017 -137.901794) (xy 112.444965 -137.894038) (xy 112.499467 -137.894038) (xy 112.553415 -137.901794)
			(xy 112.60571 -137.917149) (xy 112.655287 -137.939791) (xy 112.701137 -137.969257) (xy 112.742328 -138.004948)
			(xy 112.778019 -138.046139) (xy 112.807485 -138.091989) (xy 112.830127 -138.141566) (xy 112.845482 -138.193861)
			(xy 112.853238 -138.247809) (xy 112.853724 -138.27506) (xy 112.85323 -138.3038) (xy 112.844599 -138.360628)
			(xy 112.827542 -138.415519) (xy 112.802444 -138.46723) (xy 112.769873 -138.514592) (xy 112.7506 -138.535918)
			(xy 112.743996 -138.542776) (xy 112.736884 -138.56081) (xy 112.736884 -138.64971) (xy 112.743996 -138.667744)
			(xy 112.7506 -138.674602) (xy 112.769841 -138.695955) (xy 112.802414 -138.743309) (xy 112.827513 -138.795014)
			(xy 112.84457 -138.849899) (xy 112.853199 -138.906723) (xy 112.853724 -138.93546) (xy 112.85327 -138.960927)
			(xy 112.84647 -139.011406) (xy 112.833011 -139.060531) (xy 112.813134 -139.107427) (xy 112.787191 -139.15126)
			(xy 112.755645 -139.19125) (xy 112.737646 -139.209272) (xy 112.73007 -139.217369) (xy 112.72217 -139.238063)
			(xy 112.722406 -139.24915) (xy 112.727994 -139.32662) (xy 112.729248 -139.337683) (xy 112.739929 -139.357188)
			(xy 112.748568 -139.364212) (xy 112.772282 -139.382359) (xy 112.81434 -139.42474) (xy 112.849289 -139.473152)
			(xy 112.876276 -139.526413) (xy 112.894644 -139.583226) (xy 112.903944 -139.642206) (xy 112.904524 -139.67206)
			(xy 112.90403 -139.7008) (xy 112.895399 -139.757628) (xy 112.878342 -139.812519) (xy 112.853244 -139.86423)
			(xy 112.820673 -139.911592) (xy 112.8014 -139.932918) (xy 112.794796 -139.939776) (xy 112.787684 -139.95781)
			(xy 112.787684 -140.04671) (xy 112.794796 -140.064744) (xy 112.8014 -140.071602) (xy 112.82063 -140.092964)
			(xy 112.853195 -140.140321) (xy 112.878287 -140.192027) (xy 112.895339 -140.246912) (xy 112.903964 -140.303734)
			(xy 112.903969 -140.361207) (xy 112.895352 -140.418031) (xy 112.878308 -140.472919) (xy 112.853224 -140.524629)
			(xy 112.820667 -140.571991) (xy 112.8014 -140.593318) (xy 112.794796 -140.600176) (xy 112.787684 -140.61821)
			(xy 112.787684 -140.70711) (xy 112.794796 -140.725144) (xy 112.8014 -140.732002) (xy 112.820641 -140.753355)
			(xy 112.853214 -140.800709) (xy 112.878313 -140.852414) (xy 112.89537 -140.907299) (xy 112.903999 -140.964123)
			(xy 112.90406 -140.96746) (xy 114.529108 -140.96746) (xy 114.529605 -140.93872) (xy 114.538234 -140.881891)
			(xy 114.55529 -140.827) (xy 114.580388 -140.775289) (xy 114.612959 -140.727928) (xy 114.632232 -140.706602)
			(xy 114.638836 -140.699744) (xy 114.645948 -140.68171) (xy 114.645948 -140.59281) (xy 114.638836 -140.574776)
			(xy 114.632232 -140.567918) (xy 114.612921 -140.546626) (xy 114.580357 -140.499258) (xy 114.555267 -140.44754)
			(xy 114.538219 -140.392644) (xy 114.5296 -140.335812) (xy 114.529605 -140.27833) (xy 114.538232 -140.221499)
			(xy 114.555288 -140.166605) (xy 114.580386 -140.114892) (xy 114.612958 -140.067529) (xy 114.632232 -140.046202)
			(xy 114.638836 -140.039344) (xy 114.645948 -140.02131) (xy 114.645948 -139.93241) (xy 114.638836 -139.914376)
			(xy 114.632232 -139.907518) (xy 114.612941 -139.886208) (xy 114.580378 -139.838841) (xy 114.555289 -139.787125)
			(xy 114.538244 -139.732231) (xy 114.529626 -139.6754) (xy 114.529108 -139.64666) (xy 114.529546 -139.620345)
			(xy 114.536787 -139.568215) (xy 114.551111 -139.517572) (xy 114.572249 -139.469373) (xy 114.599801 -139.42453)
			(xy 114.633244 -139.383892) (xy 114.652298 -139.365736) (xy 114.659685 -139.358203) (xy 114.668218 -139.338931)
			(xy 114.668808 -139.328398) (xy 114.668808 -139.253722) (xy 114.668278 -139.243173) (xy 114.659743 -139.223877)
			(xy 114.652298 -139.216384) (xy 114.633241 -139.19823) (xy 114.599784 -139.1576) (xy 114.572226 -139.112759)
			(xy 114.551087 -139.064558) (xy 114.53677 -139.01391) (xy 114.529546 -138.961776) (xy 114.529108 -138.93546)
			(xy 114.529605 -138.90672) (xy 114.538234 -138.849891) (xy 114.55529 -138.795) (xy 114.580388 -138.743289)
			(xy 114.612959 -138.695928) (xy 114.632232 -138.674602) (xy 114.638836 -138.667744) (xy 114.645948 -138.64971)
			(xy 114.645948 -138.56081) (xy 114.638836 -138.542776) (xy 114.632232 -138.535918) (xy 114.612941 -138.514608)
			(xy 114.580378 -138.467241) (xy 114.555289 -138.415525) (xy 114.538244 -138.360631) (xy 114.529626 -138.3038)
			(xy 114.529108 -138.27506) (xy 114.529541 -138.247807) (xy 114.537303 -138.193857) (xy 114.552664 -138.14156)
			(xy 114.575311 -138.091981) (xy 114.604783 -138.04613) (xy 114.64048 -138.00494) (xy 114.681675 -137.969249)
			(xy 114.727531 -137.939784) (xy 114.777112 -137.917144) (xy 114.829411 -137.901791) (xy 114.883363 -137.894037)
			(xy 114.910616 -137.893552) (xy 114.93829 -137.894058) (xy 114.993059 -137.902052) (xy 115.046094 -137.917884)
			(xy 115.096283 -137.94122) (xy 115.142567 -137.971571) (xy 115.1636 -137.989564) (xy 115.170966 -137.996168)
			(xy 115.188746 -138.002518) (xy 115.278154 -137.999724) (xy 115.295934 -137.992104) (xy 115.302792 -137.985246)
			(xy 115.32441 -137.964521) (xy 115.372875 -137.929347) (xy 115.426241 -137.90218) (xy 115.483198 -137.883689)
			(xy 115.542344 -137.874327) (xy 115.572286 -137.87374) (xy 115.599541 -137.874169) (xy 115.653495 -137.881925)
			(xy 115.705797 -137.897281) (xy 115.75538 -137.919926) (xy 115.801236 -137.949397) (xy 115.84243 -137.985094)
			(xy 115.878124 -138.026292) (xy 115.90759 -138.07215) (xy 115.93023 -138.121735) (xy 115.945582 -138.174038)
			(xy 115.953334 -138.227993) (xy 115.953794 -138.255248) (xy 115.953301 -138.283988) (xy 115.944671 -138.340817)
			(xy 115.927614 -138.395708) (xy 115.902516 -138.447419) (xy 115.869944 -138.49478) (xy 115.85067 -138.516106)
			(xy 115.844066 -138.522964) (xy 115.836954 -138.540998) (xy 115.836954 -138.578844) (xy 118.705882 -138.578844)
			(xy 118.709953 -138.523222) (xy 118.722079 -138.468785) (xy 118.742002 -138.416694) (xy 118.769298 -138.368059)
			(xy 118.803384 -138.323916) (xy 118.843533 -138.285207) (xy 118.888891 -138.252756) (xy 118.938491 -138.227255)
			(xy 118.991275 -138.209248) (xy 119.046118 -138.199118) (xy 119.101852 -138.197081) (xy 119.157289 -138.203181)
			(xy 119.211246 -138.217287) (xy 119.262575 -138.239099) (xy 119.310181 -138.268153) (xy 119.353049 -138.303828)
			(xy 119.390266 -138.345365) (xy 119.400216 -138.360404) (xy 122.275852 -138.360404) (xy 122.279923 -138.304782)
			(xy 122.292049 -138.250345) (xy 122.311972 -138.198254) (xy 122.339268 -138.149619) (xy 122.373354 -138.105476)
			(xy 122.413503 -138.066767) (xy 122.458861 -138.034316) (xy 122.508461 -138.008815) (xy 122.561245 -137.990808)
			(xy 122.616088 -137.980678) (xy 122.671822 -137.978641) (xy 122.727259 -137.984741) (xy 122.781216 -137.998847)
			(xy 122.832545 -138.020659) (xy 122.880151 -138.049713) (xy 122.923019 -138.085388) (xy 122.960236 -138.126925)
			(xy 122.991009 -138.173438) (xy 123.014681 -138.223935) (xy 123.030749 -138.277342) (xy 123.038869 -138.332518)
			(xy 123.039378 -138.360404) (xy 123.038869 -138.38829) (xy 123.036656 -138.40333) (xy 131.296156 -138.40333)
			(xy 131.296666 -138.375664) (xy 131.304662 -138.320914) (xy 131.320477 -138.267891) (xy 131.34378 -138.217706)
			(xy 131.374082 -138.17141) (xy 131.41075 -138.129973) (xy 131.453014 -138.094262) (xy 131.476242 -138.079226)
			(xy 131.485908 -138.072576) (xy 131.498358 -138.052725) (xy 131.500118 -138.041126) (xy 131.507992 -137.961116)
			(xy 131.508594 -137.949479) (xy 131.500533 -137.927644) (xy 131.492498 -137.919206) (xy 131.492244 -137.918952)
			(xy 131.473666 -137.900868) (xy 131.441085 -137.860538) (xy 131.414271 -137.816164) (xy 131.393717 -137.768566)
			(xy 131.379804 -137.718622) (xy 131.372787 -137.667253) (xy 131.372356 -137.64133) (xy 131.372906 -137.614081)
			(xy 131.380658 -137.560138) (xy 131.396007 -137.507846) (xy 131.418642 -137.458272) (xy 131.448102 -137.412423)
			(xy 131.483787 -137.371233) (xy 131.52497 -137.335541) (xy 131.570814 -137.306074) (xy 131.620384 -137.28343)
			(xy 131.672673 -137.268072) (xy 131.726615 -137.260311) (xy 131.753864 -137.259822) (xy 131.781234 -137.260304)
			(xy 131.835412 -137.268117) (xy 131.887915 -137.283602) (xy 131.937663 -137.30644) (xy 131.98363 -137.336162)
			(xy 132.004562 -137.353802) (xy 132.004816 -137.354056) (xy 132.011889 -137.359662) (xy 132.028816 -137.365896)
			(xy 132.037836 -137.366248) (xy 132.104892 -137.366248) (xy 132.11391 -137.365898) (xy 132.130827 -137.359647)
			(xy 132.137912 -137.354056) (xy 132.137912 -137.353802) (xy 132.138166 -137.353802) (xy 132.1591 -137.336166)
			(xy 132.205072 -137.306453) (xy 132.254819 -137.283617) (xy 132.30732 -137.268125) (xy 132.361495 -137.260296)
			(xy 132.388864 -137.259822) (xy 132.416117 -137.260289) (xy 132.47007 -137.268042) (xy 132.522369 -137.283395)
			(xy 132.571951 -137.306035) (xy 132.617806 -137.335502) (xy 132.659 -137.371196) (xy 132.694694 -137.412389)
			(xy 132.724162 -137.458243) (xy 132.746803 -137.507825) (xy 132.762157 -137.560124) (xy 132.769911 -137.614077)
			(xy 132.770372 -137.64133) (xy 132.769814 -137.670246) (xy 132.761095 -137.727415) (xy 132.743846 -137.782614)
			(xy 132.718461 -137.834576) (xy 132.685524 -137.882111) (xy 132.645789 -137.924129) (xy 132.623306 -137.94232)
			(xy 132.614501 -137.949929) (xy 132.604316 -137.970828) (xy 132.603748 -137.982452) (xy 132.603748 -138.062208)
			(xy 132.60428 -138.073841) (xy 132.614472 -138.094752) (xy 132.623306 -138.10234) (xy 132.64581 -138.120507)
			(xy 132.685544 -138.162532) (xy 132.71848 -138.210072) (xy 132.743865 -138.262038) (xy 132.761117 -138.31724)
			(xy 132.76984 -138.374413) (xy 132.770372 -138.40333) (xy 132.769973 -138.430585) (xy 132.762211 -138.48454)
			(xy 132.750105 -138.525758) (xy 133.041644 -138.525758) (xy 133.042133 -138.498388) (xy 133.049944 -138.44421)
			(xy 133.065427 -138.391707) (xy 133.088264 -138.341959) (xy 133.117984 -138.295992) (xy 133.135624 -138.27506)
			(xy 133.135878 -138.274806) (xy 133.141477 -138.267729) (xy 133.147714 -138.250804) (xy 133.14807 -138.241786)
			(xy 133.14807 -138.17473) (xy 133.147705 -138.165714) (xy 133.141464 -138.148797) (xy 133.135878 -138.14171)
			(xy 133.135624 -138.14171) (xy 133.135624 -138.141456) (xy 133.117942 -138.120557) (xy 133.088219 -138.074583)
			(xy 133.065377 -138.024831) (xy 133.049884 -137.972324) (xy 133.042059 -137.918141) (xy 133.042064 -137.863396)
			(xy 133.049897 -137.809214) (xy 133.065399 -137.75671) (xy 133.08825 -137.706962) (xy 133.11798 -137.660993)
			(xy 133.135624 -137.64006) (xy 133.135878 -137.639806) (xy 133.141477 -137.632729) (xy 133.147714 -137.615804)
			(xy 133.14807 -137.606786) (xy 133.14807 -137.53973) (xy 133.147705 -137.530714) (xy 133.141464 -137.513797)
			(xy 133.135878 -137.50671) (xy 133.135624 -137.50671) (xy 133.135624 -137.506456) (xy 133.117942 -137.485557)
			(xy 133.088219 -137.439583) (xy 133.065377 -137.389831) (xy 133.049884 -137.337324) (xy 133.042059 -137.283141)
			(xy 133.042064 -137.228396) (xy 133.049897 -137.174214) (xy 133.065399 -137.12171) (xy 133.08825 -137.071962)
			(xy 133.11798 -137.025993) (xy 133.135624 -137.00506) (xy 133.135878 -137.004806) (xy 133.141477 -136.997729)
			(xy 133.147714 -136.980804) (xy 133.14807 -136.971786) (xy 133.14807 -136.90473) (xy 133.147705 -136.895714)
			(xy 133.141464 -136.878797) (xy 133.135878 -136.87171) (xy 133.135624 -136.87171) (xy 133.135624 -136.871456)
			(xy 133.118001 -136.850511) (xy 133.088286 -136.804542) (xy 133.065447 -136.754798) (xy 133.049952 -136.7023)
			(xy 133.04212 -136.648126) (xy 133.041644 -136.620758) (xy 133.04213 -136.593507) (xy 133.049886 -136.539559)
			(xy 133.065241 -136.487264) (xy 133.087883 -136.437687) (xy 133.117349 -136.391837) (xy 133.15304 -136.350646)
			(xy 133.194231 -136.314955) (xy 133.240081 -136.285489) (xy 133.289658 -136.262847) (xy 133.341953 -136.247492)
			(xy 133.395901 -136.239736) (xy 133.450403 -136.239736) (xy 133.504351 -136.247492) (xy 133.556646 -136.262847)
			(xy 133.606223 -136.285489) (xy 133.652073 -136.314955) (xy 133.693264 -136.350646) (xy 133.728955 -136.391837)
			(xy 133.758421 -136.437687) (xy 133.781063 -136.487264) (xy 133.796418 -136.539559) (xy 133.804174 -136.593507)
			(xy 133.80466 -136.620758) (xy 133.804179 -136.648128) (xy 133.796366 -136.702307) (xy 133.780881 -136.75481)
			(xy 133.758043 -136.804557) (xy 133.72832 -136.850524) (xy 133.71068 -136.871456) (xy 133.710426 -136.87171)
			(xy 133.70482 -136.878783) (xy 133.698587 -136.895711) (xy 133.698234 -136.90473) (xy 133.698234 -136.971786)
			(xy 133.698591 -136.980803) (xy 133.704838 -136.99772) (xy 133.710426 -137.004806) (xy 133.71068 -137.004806)
			(xy 133.71068 -137.00506) (xy 133.728279 -137.026026) (xy 133.758005 -137.071988) (xy 133.780853 -137.121729)
			(xy 133.796352 -137.174226) (xy 133.804184 -137.2284) (xy 133.804189 -137.283137) (xy 133.796365 -137.337312)
			(xy 133.780875 -137.389812) (xy 133.758036 -137.439556) (xy 133.728317 -137.485523) (xy 133.71068 -137.506456)
			(xy 133.710426 -137.50671) (xy 133.70482 -137.513783) (xy 133.698587 -137.530711) (xy 133.698234 -137.53973)
			(xy 133.698234 -137.606786) (xy 133.698591 -137.615803) (xy 133.704838 -137.63272) (xy 133.710426 -137.639806)
			(xy 133.71068 -137.639806) (xy 133.71068 -137.64006) (xy 133.728279 -137.661026) (xy 133.758005 -137.706988)
			(xy 133.780853 -137.756729) (xy 133.796352 -137.809226) (xy 133.804184 -137.8634) (xy 133.804189 -137.918137)
			(xy 133.796365 -137.972312) (xy 133.780875 -138.024812) (xy 133.758036 -138.074556) (xy 133.728317 -138.120523)
			(xy 133.71068 -138.141456) (xy 133.710426 -138.14171) (xy 133.70482 -138.148783) (xy 133.698587 -138.165711)
			(xy 133.698234 -138.17473) (xy 133.698234 -138.241786) (xy 133.698591 -138.250803) (xy 133.704838 -138.26772)
			(xy 133.710426 -138.274806) (xy 133.71068 -138.274806) (xy 133.71068 -138.27506) (xy 133.728311 -138.295999)
			(xy 133.758024 -138.34197) (xy 133.780862 -138.391715) (xy 133.796355 -138.444215) (xy 133.804185 -138.498389)
			(xy 133.80466 -138.525758) (xy 133.804185 -138.552387) (xy 133.796782 -138.605129) (xy 133.782114 -138.656328)
			(xy 133.760466 -138.704988) (xy 133.732259 -138.750164) (xy 133.715506 -138.770868) (xy 133.707632 -138.780266)
			(xy 133.702044 -138.803634) (xy 133.723634 -138.894566) (xy 133.726994 -138.90594) (xy 133.742225 -138.924083)
			(xy 133.752844 -138.929364) (xy 133.779561 -138.941549) (xy 133.829186 -138.972936) (xy 133.85165 -138.991848)
			(xy 133.851904 -138.992102) (xy 133.858985 -138.997697) (xy 133.875906 -139.003938) (xy 133.884924 -139.004294)
			(xy 133.95198 -139.004294) (xy 133.960996 -139.003929) (xy 133.977913 -138.997687) (xy 133.985 -138.992102)
			(xy 133.985 -138.991848) (xy 133.985254 -138.991848) (xy 134.006187 -138.974207) (xy 134.052155 -138.944483)
			(xy 134.101901 -138.921637) (xy 134.154403 -138.906141) (xy 134.208581 -138.898312) (xy 134.263323 -138.898312)
			(xy 134.317501 -138.906141) (xy 134.370003 -138.921637) (xy 134.419749 -138.944483) (xy 134.465717 -138.974207)
			(xy 134.48665 -138.991848) (xy 134.486904 -138.992102) (xy 134.493985 -138.997697) (xy 134.510906 -139.003938)
			(xy 134.519924 -139.004294) (xy 134.58698 -139.004294) (xy 134.595996 -139.003929) (xy 134.612913 -138.997687)
			(xy 134.62 -138.992102) (xy 134.62 -138.991848) (xy 134.620254 -138.991848) (xy 134.641187 -138.974207)
			(xy 134.687155 -138.944483) (xy 134.736901 -138.921637) (xy 134.789403 -138.906141) (xy 134.843581 -138.898312)
			(xy 134.898323 -138.898312) (xy 134.952501 -138.906141) (xy 135.005003 -138.921637) (xy 135.054749 -138.944483)
			(xy 135.100717 -138.974207) (xy 135.12165 -138.991848) (xy 135.121904 -138.992102) (xy 135.128985 -138.997697)
			(xy 135.145906 -139.003938) (xy 135.154924 -139.004294) (xy 135.22198 -139.004294) (xy 135.230996 -139.003929)
			(xy 135.247913 -138.997687) (xy 135.255 -138.992102) (xy 135.255 -138.991848) (xy 135.255254 -138.991848)
			(xy 135.276199 -138.974224) (xy 135.322167 -138.944509) (xy 135.371912 -138.921669) (xy 135.42441 -138.906174)
			(xy 135.478584 -138.898343) (xy 135.505952 -138.897868) (xy 135.533205 -138.898376) (xy 135.587158 -138.906127)
			(xy 135.639458 -138.921478) (xy 135.689041 -138.944116) (xy 135.734898 -138.973581) (xy 135.776094 -139.009272)
			(xy 135.81179 -139.050464) (xy 135.841261 -139.096316) (xy 135.863905 -139.145897) (xy 135.879263 -139.198195)
			(xy 135.887021 -139.252147) (xy 135.887021 -139.306653) (xy 135.879263 -139.360605) (xy 135.863905 -139.412903)
			(xy 135.841261 -139.462484) (xy 135.81179 -139.508336) (xy 135.776094 -139.549528) (xy 135.734898 -139.585219)
			(xy 135.689041 -139.614684) (xy 135.639458 -139.637322) (xy 135.587158 -139.652673) (xy 135.533205 -139.660424)
			(xy 135.505952 -139.660884) (xy 135.478583 -139.660391) (xy 135.424405 -139.652581) (xy 135.371902 -139.637098)
			(xy 135.322154 -139.614262) (xy 135.276186 -139.584543) (xy 135.255254 -139.566904) (xy 135.255 -139.56665)
			(xy 135.247922 -139.561051) (xy 135.230998 -139.554813) (xy 135.22198 -139.554458) (xy 135.154924 -139.554458)
			(xy 135.145907 -139.554814) (xy 135.128989 -139.561061) (xy 135.121904 -139.56665) (xy 135.121904 -139.566904)
			(xy 135.12165 -139.566904) (xy 135.100717 -139.584545) (xy 135.054749 -139.614269) (xy 135.005003 -139.637115)
			(xy 134.952501 -139.652611) (xy 134.898323 -139.66044) (xy 134.843581 -139.66044) (xy 134.789403 -139.652611)
			(xy 134.736901 -139.637115) (xy 134.687155 -139.614269) (xy 134.641187 -139.584545) (xy 134.620254 -139.566904)
			(xy 134.62 -139.56665) (xy 134.612922 -139.561051) (xy 134.595998 -139.554813) (xy 134.58698 -139.554458)
			(xy 134.519924 -139.554458) (xy 134.510907 -139.554814) (xy 134.493989 -139.561061) (xy 134.486904 -139.56665)
			(xy 134.486904 -139.566904) (xy 134.48665 -139.566904) (xy 134.465717 -139.584545) (xy 134.419749 -139.614269)
			(xy 134.370003 -139.637115) (xy 134.317501 -139.652611) (xy 134.263323 -139.66044) (xy 134.208581 -139.66044)
			(xy 134.154403 -139.652611) (xy 134.101901 -139.637115) (xy 134.052155 -139.614269) (xy 134.006187 -139.584545)
			(xy 133.985254 -139.566904) (xy 133.985 -139.56665) (xy 133.977922 -139.561051) (xy 133.960998 -139.554813)
			(xy 133.95198 -139.554458) (xy 133.884924 -139.554458) (xy 133.875907 -139.554814) (xy 133.858989 -139.561061)
			(xy 133.851904 -139.56665) (xy 133.851904 -139.566904) (xy 133.85165 -139.566904) (xy 133.83071 -139.584534)
			(xy 133.78474 -139.614247) (xy 133.734994 -139.637085) (xy 133.682495 -139.652578) (xy 133.628321 -139.660409)
			(xy 133.600952 -139.660884) (xy 133.573698 -139.660467) (xy 133.519747 -139.652703) (xy 133.46745 -139.637341)
			(xy 133.417871 -139.614692) (xy 133.372019 -139.585219) (xy 133.330829 -139.54952) (xy 133.295138 -139.508323)
			(xy 133.265673 -139.462466) (xy 133.243034 -139.412883) (xy 133.227682 -139.360583) (xy 133.219928 -139.30663)
			(xy 133.219444 -139.279376) (xy 133.21988 -139.252745) (xy 133.227292 -139.200002) (xy 133.241969 -139.148803)
			(xy 133.263626 -139.100143) (xy 133.291841 -139.054969) (xy 133.308598 -139.034266) (xy 133.316472 -139.024868)
			(xy 133.32206 -139.0015) (xy 133.30047 -138.910568) (xy 133.297138 -138.899183) (xy 133.281886 -138.881047)
			(xy 133.27126 -138.87577) (xy 133.246048 -138.864275) (xy 133.198951 -138.835085) (xy 133.156571 -138.799391)
			(xy 133.119797 -138.757944) (xy 133.089403 -138.711615) (xy 133.066029 -138.661377) (xy 133.050164 -138.608288)
			(xy 133.042143 -138.553462) (xy 133.041644 -138.525758) (xy 132.750105 -138.525758) (xy 132.746849 -138.536842)
			(xy 132.724201 -138.586424) (xy 132.694726 -138.632279) (xy 132.659026 -138.673472) (xy 132.617826 -138.709166)
			(xy 132.571966 -138.738632) (xy 132.52238 -138.761272) (xy 132.470076 -138.776625) (xy 132.416119 -138.784378)
			(xy 132.388864 -138.784838) (xy 132.362548 -138.784414) (xy 132.310417 -138.777173) (xy 132.259773 -138.762847)
			(xy 132.211573 -138.741706) (xy 132.166731 -138.714152) (xy 132.126094 -138.680704) (xy 132.10794 -138.661648)
			(xy 132.100399 -138.654269) (xy 132.081134 -138.64573) (xy 132.070602 -138.645138) (xy 131.995926 -138.645138)
			(xy 131.985375 -138.645657) (xy 131.966079 -138.654198) (xy 131.958588 -138.661648) (xy 131.940441 -138.680712)
			(xy 131.899808 -138.714166) (xy 131.854966 -138.741723) (xy 131.806764 -138.76286) (xy 131.756115 -138.777176)
			(xy 131.70398 -138.7844) (xy 131.677664 -138.784838) (xy 131.650413 -138.784356) (xy 131.596467 -138.776595)
			(xy 131.544174 -138.761237) (xy 131.494599 -138.738594) (xy 131.44875 -138.709127) (xy 131.407561 -138.673435)
			(xy 131.37187 -138.632245) (xy 131.342403 -138.586396) (xy 131.319761 -138.53682) (xy 131.304404 -138.484527)
			(xy 131.296644 -138.430581) (xy 131.296156 -138.40333) (xy 123.036656 -138.40333) (xy 123.030749 -138.443466)
			(xy 123.014681 -138.496873) (xy 122.991009 -138.54737) (xy 122.960236 -138.593883) (xy 122.923019 -138.63542)
			(xy 122.880151 -138.671095) (xy 122.832545 -138.700149) (xy 122.781216 -138.721961) (xy 122.727259 -138.736067)
			(xy 122.671822 -138.742167) (xy 122.616088 -138.74013) (xy 122.561245 -138.73) (xy 122.508461 -138.711993)
			(xy 122.458861 -138.686492) (xy 122.413503 -138.654041) (xy 122.373354 -138.615332) (xy 122.339268 -138.571189)
			(xy 122.311972 -138.522554) (xy 122.292049 -138.470463) (xy 122.279923 -138.416026) (xy 122.275852 -138.360404)
			(xy 119.400216 -138.360404) (xy 119.421039 -138.391878) (xy 119.444711 -138.442375) (xy 119.460779 -138.495782)
			(xy 119.468899 -138.550958) (xy 119.469408 -138.578844) (xy 119.468899 -138.60673) (xy 119.460779 -138.661906)
			(xy 119.444711 -138.715313) (xy 119.421039 -138.76581) (xy 119.390266 -138.812323) (xy 119.37939 -138.824462)
			(xy 124.461776 -138.824462) (xy 124.465847 -138.76884) (xy 124.477973 -138.714403) (xy 124.497896 -138.662312)
			(xy 124.525192 -138.613677) (xy 124.559278 -138.569534) (xy 124.599427 -138.530825) (xy 124.644785 -138.498374)
			(xy 124.694385 -138.472873) (xy 124.747169 -138.454866) (xy 124.802012 -138.444736) (xy 124.857746 -138.442699)
			(xy 124.913183 -138.448799) (xy 124.96714 -138.462905) (xy 125.018469 -138.484717) (xy 125.066075 -138.513771)
			(xy 125.108943 -138.549446) (xy 125.14616 -138.590983) (xy 125.176933 -138.637496) (xy 125.200605 -138.687993)
			(xy 125.216673 -138.7414) (xy 125.224793 -138.796576) (xy 125.225302 -138.824462) (xy 125.224793 -138.852348)
			(xy 125.216673 -138.907524) (xy 125.200605 -138.960931) (xy 125.176933 -139.011428) (xy 125.14616 -139.057941)
			(xy 125.108943 -139.099478) (xy 125.066075 -139.135153) (xy 125.018469 -139.164207) (xy 124.96714 -139.186019)
			(xy 124.913183 -139.200125) (xy 124.857746 -139.206225) (xy 124.802012 -139.204188) (xy 124.747169 -139.194058)
			(xy 124.694385 -139.176051) (xy 124.644785 -139.15055) (xy 124.599427 -139.118099) (xy 124.559278 -139.07939)
			(xy 124.525192 -139.035247) (xy 124.497896 -138.986612) (xy 124.477973 -138.934521) (xy 124.465847 -138.880084)
			(xy 124.461776 -138.824462) (xy 119.37939 -138.824462) (xy 119.353049 -138.85386) (xy 119.310181 -138.889535)
			(xy 119.262575 -138.918589) (xy 119.211246 -138.940401) (xy 119.157289 -138.954507) (xy 119.101852 -138.960607)
			(xy 119.046118 -138.95857) (xy 118.991275 -138.94844) (xy 118.938491 -138.930433) (xy 118.888891 -138.904932)
			(xy 118.843533 -138.872481) (xy 118.803384 -138.833772) (xy 118.769298 -138.789629) (xy 118.742002 -138.740994)
			(xy 118.722079 -138.688903) (xy 118.709953 -138.634466) (xy 118.705882 -138.578844) (xy 115.836954 -138.578844)
			(xy 115.836954 -138.629898) (xy 115.844066 -138.647932) (xy 115.85067 -138.65479) (xy 115.869965 -138.676096)
			(xy 115.902527 -138.723464) (xy 115.927615 -138.775181) (xy 115.94466 -138.830076) (xy 115.953277 -138.886908)
			(xy 115.953794 -138.915648) (xy 115.95336 -138.941963) (xy 115.946119 -138.994093) (xy 115.931793 -139.044737)
			(xy 115.910655 -139.092936) (xy 115.883102 -139.137778) (xy 115.849658 -139.178416) (xy 115.830604 -139.196572)
			(xy 115.823213 -139.204103) (xy 115.814683 -139.223376) (xy 115.814094 -139.23391) (xy 115.814094 -139.308586)
			(xy 115.814619 -139.319136) (xy 115.823157 -139.338431) (xy 115.830604 -139.345924) (xy 115.849665 -139.364074)
			(xy 115.859818 -139.376404) (xy 122.275852 -139.376404) (xy 122.279923 -139.320782) (xy 122.292049 -139.266345)
			(xy 122.311972 -139.214254) (xy 122.339268 -139.165619) (xy 122.373354 -139.121476) (xy 122.413503 -139.082767)
			(xy 122.458861 -139.050316) (xy 122.508461 -139.024815) (xy 122.561245 -139.006808) (xy 122.616088 -138.996678)
			(xy 122.671822 -138.994641) (xy 122.727259 -139.000741) (xy 122.781216 -139.014847) (xy 122.832545 -139.036659)
			(xy 122.880151 -139.065713) (xy 122.923019 -139.101388) (xy 122.960236 -139.142925) (xy 122.991009 -139.189438)
			(xy 123.014681 -139.239935) (xy 123.030749 -139.293342) (xy 123.038869 -139.348518) (xy 123.039378 -139.376404)
			(xy 123.038869 -139.40429) (xy 123.030749 -139.459466) (xy 123.014681 -139.512873) (xy 122.991009 -139.56337)
			(xy 122.960236 -139.609883) (xy 122.923019 -139.65142) (xy 122.880151 -139.687095) (xy 122.832545 -139.716149)
			(xy 122.781216 -139.737961) (xy 122.727259 -139.752067) (xy 122.671822 -139.758167) (xy 122.616088 -139.75613)
			(xy 122.561245 -139.746) (xy 122.508461 -139.727993) (xy 122.458861 -139.702492) (xy 122.413503 -139.670041)
			(xy 122.373354 -139.631332) (xy 122.339268 -139.587189) (xy 122.311972 -139.538554) (xy 122.292049 -139.486463)
			(xy 122.279923 -139.432026) (xy 122.275852 -139.376404) (xy 115.859818 -139.376404) (xy 115.883121 -139.404705)
			(xy 115.91068 -139.449547) (xy 115.931817 -139.497748) (xy 115.946133 -139.548397) (xy 115.953356 -139.600532)
			(xy 115.953794 -139.626848) (xy 115.953301 -139.655588) (xy 115.944671 -139.712417) (xy 115.927614 -139.767308)
			(xy 115.902516 -139.819019) (xy 115.869944 -139.86638) (xy 115.85067 -139.887706) (xy 115.844066 -139.894564)
			(xy 115.836954 -139.912598) (xy 115.836954 -140.001498) (xy 115.844066 -140.019532) (xy 115.85067 -140.02639)
			(xy 115.869989 -140.047675) (xy 115.902553 -140.095045) (xy 115.927642 -140.146763) (xy 115.944689 -140.20166)
			(xy 115.953307 -140.258494) (xy 115.953302 -140.315976) (xy 115.944673 -140.372808) (xy 115.938584 -140.392404)
			(xy 124.467618 -140.392404) (xy 124.471689 -140.336782) (xy 124.483815 -140.282345) (xy 124.503738 -140.230254)
			(xy 124.531034 -140.181619) (xy 124.56512 -140.137476) (xy 124.605269 -140.098767) (xy 124.650627 -140.066316)
			(xy 124.700227 -140.040815) (xy 124.753011 -140.022808) (xy 124.807854 -140.012678) (xy 124.863588 -140.010641)
			(xy 124.919025 -140.016741) (xy 124.972982 -140.030847) (xy 125.024311 -140.052659) (xy 125.071917 -140.081713)
			(xy 125.114785 -140.117388) (xy 125.152002 -140.158925) (xy 125.182775 -140.205438) (xy 125.206447 -140.255935)
			(xy 125.222515 -140.309342) (xy 125.230635 -140.364518) (xy 125.231144 -140.392404) (xy 125.230635 -140.42029)
			(xy 125.222515 -140.475466) (xy 125.206447 -140.528873) (xy 125.182775 -140.57937) (xy 125.152002 -140.625883)
			(xy 125.114785 -140.66742) (xy 125.071917 -140.703095) (xy 125.024311 -140.732149) (xy 124.972982 -140.753961)
			(xy 124.919025 -140.768067) (xy 124.863588 -140.774167) (xy 124.807854 -140.77213) (xy 124.753011 -140.762)
			(xy 124.700227 -140.743993) (xy 124.650627 -140.718492) (xy 124.605269 -140.686041) (xy 124.56512 -140.647332)
			(xy 124.531034 -140.603189) (xy 124.503738 -140.554554) (xy 124.483815 -140.502463) (xy 124.471689 -140.448026)
			(xy 124.467618 -140.392404) (xy 115.938584 -140.392404) (xy 115.927616 -140.427702) (xy 115.902518 -140.479416)
			(xy 115.869945 -140.526779) (xy 115.85067 -140.548106) (xy 115.844066 -140.554964) (xy 115.836954 -140.572998)
			(xy 115.836954 -140.661898) (xy 115.844066 -140.679932) (xy 115.85067 -140.68679) (xy 115.869965 -140.708096)
			(xy 115.902527 -140.755464) (xy 115.927615 -140.807181) (xy 115.94466 -140.862076) (xy 115.953277 -140.918908)
			(xy 115.953794 -140.947648) (xy 115.953367 -140.974901) (xy 115.945603 -141.028852) (xy 115.940404 -141.046551)
			(xy 126.854954 -141.046551) (xy 126.854954 -140.992049) (xy 126.86271 -140.9381) (xy 126.878064 -140.885805)
			(xy 126.900704 -140.836227) (xy 126.930169 -140.790375) (xy 126.965859 -140.749183) (xy 127.007048 -140.71349)
			(xy 127.052897 -140.684021) (xy 127.102473 -140.661376) (xy 127.154767 -140.646017) (xy 127.208715 -140.638256)
			(xy 127.235966 -140.637768) (xy 127.262281 -140.638202) (xy 127.314411 -140.645445) (xy 127.365054 -140.659771)
			(xy 127.413252 -140.68091) (xy 127.458095 -140.708462) (xy 127.498734 -140.741905) (xy 127.51689 -140.760958)
			(xy 127.524419 -140.768351) (xy 127.543693 -140.776882) (xy 127.554228 -140.777468) (xy 127.628904 -140.777468)
			(xy 127.639457 -140.776964) (xy 127.658752 -140.768412) (xy 127.666242 -140.760958) (xy 127.684376 -140.741881)
			(xy 127.725011 -140.708427) (xy 127.769856 -140.680872) (xy 127.818061 -140.659738) (xy 127.868712 -140.645425)
			(xy 127.920849 -140.638204) (xy 127.947166 -140.637768) (xy 127.974419 -140.638277) (xy 128.02837 -140.64603)
			(xy 128.080669 -140.661382) (xy 128.13025 -140.684021) (xy 128.176104 -140.713486) (xy 128.217299 -140.749177)
			(xy 128.252994 -140.790368) (xy 128.282463 -140.83622) (xy 128.305106 -140.8858) (xy 128.320463 -140.938097)
			(xy 128.328221 -140.992047) (xy 128.328221 -141.046553) (xy 128.320463 -141.100503) (xy 128.305106 -141.1528)
			(xy 128.282463 -141.20238) (xy 128.252994 -141.248232) (xy 128.217299 -141.289423) (xy 128.176104 -141.325114)
			(xy 128.13025 -141.354579) (xy 128.080669 -141.377218) (xy 128.02837 -141.39257) (xy 127.974419 -141.400323)
			(xy 127.947166 -141.400784) (xy 127.920851 -141.400344) (xy 127.868721 -141.393105) (xy 127.818078 -141.37878)
			(xy 127.769879 -141.357643) (xy 127.725036 -141.330092) (xy 127.684398 -141.296648) (xy 127.666242 -141.277594)
			(xy 127.658707 -141.270208) (xy 127.639437 -141.261675) (xy 127.628904 -141.261084) (xy 127.554228 -141.261084)
			(xy 127.543679 -141.26162) (xy 127.524384 -141.270151) (xy 127.51689 -141.277594) (xy 127.498731 -141.296646)
			(xy 127.458102 -141.330104) (xy 127.413263 -141.357664) (xy 127.365063 -141.378803) (xy 127.314416 -141.39312)
			(xy 127.262282 -141.400345) (xy 127.235966 -141.400784) (xy 127.208715 -141.400344) (xy 127.154767 -141.392583)
			(xy 127.102473 -141.377224) (xy 127.052897 -141.354579) (xy 127.007048 -141.32511) (xy 126.965859 -141.289417)
			(xy 126.930169 -141.248225) (xy 126.900704 -141.202373) (xy 126.878064 -141.152795) (xy 126.86271 -141.1005)
			(xy 126.854954 -141.046551) (xy 115.940404 -141.046551) (xy 115.930241 -141.081148) (xy 115.907594 -141.130727)
			(xy 115.878121 -141.176577) (xy 115.842424 -141.217767) (xy 115.801228 -141.253458) (xy 115.755372 -141.282923)
			(xy 115.70579 -141.305563) (xy 115.653491 -141.320917) (xy 115.599539 -141.328671) (xy 115.572286 -141.329156)
			(xy 115.544612 -141.328647) (xy 115.489844 -141.320653) (xy 115.436808 -141.304822) (xy 115.38662 -141.281486)
			(xy 115.340335 -141.251136) (xy 115.319302 -141.233144) (xy 115.311936 -141.22654) (xy 115.294156 -141.22019)
			(xy 115.204748 -141.222984) (xy 115.186968 -141.230604) (xy 115.18011 -141.237462) (xy 115.158536 -141.258235)
			(xy 115.11006 -141.293403) (xy 115.056682 -141.32056) (xy 114.999716 -141.33904) (xy 114.940561 -141.348388)
			(xy 114.910616 -141.348968) (xy 114.883362 -141.34853) (xy 114.829408 -141.340774) (xy 114.777107 -141.325418)
			(xy 114.727524 -141.302774) (xy 114.681669 -141.273304) (xy 114.640475 -141.237608) (xy 114.604781 -141.196412)
			(xy 114.575314 -141.150555) (xy 114.552674 -141.10097) (xy 114.537321 -141.048669) (xy 114.529569 -140.994714)
			(xy 114.529108 -140.96746) (xy 112.90406 -140.96746) (xy 112.904524 -140.99286) (xy 112.904038 -141.020111)
			(xy 112.896282 -141.074059) (xy 112.880927 -141.126354) (xy 112.858285 -141.175931) (xy 112.828819 -141.221781)
			(xy 112.793128 -141.262972) (xy 112.751937 -141.298663) (xy 112.706087 -141.328129) (xy 112.65651 -141.350771)
			(xy 112.604215 -141.366126) (xy 112.550267 -141.373882) (xy 112.495765 -141.373882) (xy 112.441817 -141.366126)
			(xy 112.389522 -141.350771) (xy 112.339945 -141.328129) (xy 112.294095 -141.298663) (xy 112.252904 -141.262972)
			(xy 112.217213 -141.221781) (xy 112.187747 -141.175931) (xy 112.165105 -141.126354) (xy 112.14975 -141.074059)
			(xy 112.141994 -141.020111) (xy 112.141508 -140.99286) (xy 112.142005 -140.96412) (xy 112.150634 -140.907291)
			(xy 112.16769 -140.8524) (xy 112.192788 -140.800689) (xy 112.225359 -140.753328) (xy 112.244632 -140.732002)
			(xy 112.251236 -140.725144) (xy 112.258348 -140.70711) (xy 112.258348 -140.61821) (xy 112.251236 -140.600176)
			(xy 112.244632 -140.593318) (xy 112.225321 -140.572026) (xy 112.192757 -140.524658) (xy 112.167667 -140.47294)
			(xy 112.150619 -140.418044) (xy 112.142 -140.361212) (xy 112.142005 -140.30373) (xy 112.150632 -140.246899)
			(xy 112.167688 -140.192005) (xy 112.192786 -140.140292) (xy 112.225358 -140.092929) (xy 112.244632 -140.071602)
			(xy 112.251236 -140.064744) (xy 112.258348 -140.04671) (xy 112.258348 -139.95781) (xy 112.251236 -139.939776)
			(xy 112.244632 -139.932918) (xy 112.225341 -139.911608) (xy 112.192778 -139.864241) (xy 112.167689 -139.812525)
			(xy 112.150644 -139.757631) (xy 112.142026 -139.7008) (xy 112.141508 -139.67206) (xy 112.141965 -139.646593)
			(xy 112.148764 -139.596114) (xy 112.162221 -139.546989) (xy 112.182098 -139.500093) (xy 112.20804 -139.456259)
			(xy 112.239586 -139.41627) (xy 112.257586 -139.398248) (xy 112.265156 -139.390147) (xy 112.273059 -139.369456)
			(xy 112.272826 -139.35837) (xy 112.267238 -139.2809) (xy 112.265962 -139.269842) (xy 112.255296 -139.250335)
			(xy 112.246664 -139.243308) (xy 112.222945 -139.225168) (xy 112.18089 -139.182783) (xy 112.145944 -139.134369)
			(xy 112.118958 -139.081107) (xy 112.100591 -139.024294) (xy 112.091289 -138.965314) (xy 112.090708 -138.93546)
			(xy 109.953044 -138.93546) (xy 109.952518 -138.964377) (xy 109.943794 -139.021549) (xy 109.926539 -139.076748)
			(xy 109.901149 -139.128711) (xy 109.868205 -139.176245) (xy 109.828464 -139.218261) (xy 109.805978 -139.23645)
			(xy 109.7972 -139.244085) (xy 109.787001 -139.264965) (xy 109.78642 -139.276582) (xy 109.78642 -139.356338)
			(xy 109.786945 -139.367972) (xy 109.797143 -139.388882) (xy 109.805978 -139.39647) (xy 109.828443 -139.414684)
			(xy 109.86818 -139.456698) (xy 109.901122 -139.504228) (xy 109.926514 -139.556185) (xy 109.943774 -139.611379)
			(xy 109.952507 -139.668545) (xy 109.953044 -139.69746) (xy 109.952545 -139.7262) (xy 109.943915 -139.783028)
			(xy 109.926858 -139.837918) (xy 109.901761 -139.889629) (xy 109.869192 -139.936991) (xy 109.84992 -139.958318)
			(xy 109.843316 -139.965176) (xy 109.836204 -139.98321) (xy 109.836204 -140.07211) (xy 109.843316 -140.090144)
			(xy 109.84992 -140.097002) (xy 109.869149 -140.118364) (xy 109.901712 -140.165722) (xy 109.926803 -140.217428)
			(xy 109.943854 -140.272313) (xy 109.952479 -140.329135) (xy 109.952483 -140.386607) (xy 109.943867 -140.44343)
			(xy 109.926824 -140.498318) (xy 109.901741 -140.550028) (xy 109.869186 -140.59739) (xy 109.84992 -140.618718)
			(xy 109.843316 -140.625576) (xy 109.836204 -140.64361) (xy 109.836204 -140.73251) (xy 109.843316 -140.750544)
			(xy 109.84992 -140.757402) (xy 109.869165 -140.778752) (xy 109.901736 -140.826107) (xy 109.926834 -140.877813)
			(xy 109.943891 -140.932699) (xy 109.95252 -140.989522) (xy 109.953044 -141.01826) (xy 109.952508 -141.04551)
			(xy 109.944757 -141.099457) (xy 109.929408 -141.151751) (xy 109.906773 -141.201329) (xy 109.877312 -141.24718)
			(xy 109.841626 -141.288372) (xy 109.800441 -141.324067) (xy 109.754595 -141.353536) (xy 109.705022 -141.376181)
			(xy 109.652731 -141.391541) (xy 109.598786 -141.399302) (xy 109.571536 -141.399768) (xy 109.542202 -141.399213)
			(xy 109.484222 -141.390248) (xy 109.4283 -141.372509) (xy 109.375755 -141.346415) (xy 109.327825 -141.312581)
			(xy 109.30636 -141.29258) (xy 109.298994 -141.285468) (xy 109.281214 -141.278356) (xy 109.190282 -141.278356)
			(xy 109.172502 -141.285468) (xy 109.165136 -141.29258) (xy 109.143652 -141.312559) (xy 109.095723 -141.34639)
			(xy 109.043182 -141.372489) (xy 108.987266 -141.39024) (xy 108.929293 -141.399226) (xy 108.89996 -141.399768)
			(xy 108.872706 -141.399359) (xy 108.818753 -141.391596) (xy 108.766455 -141.376234) (xy 108.716875 -141.353585)
			(xy 108.671023 -141.324111) (xy 108.629832 -141.288412) (xy 108.594141 -141.247213) (xy 108.564676 -141.201355)
			(xy 108.542038 -141.15177) (xy 108.526687 -141.099468) (xy 108.518935 -141.045514) (xy 108.518452 -141.01826)
			(xy 106.893868 -141.01826) (xy 106.893382 -141.045511) (xy 106.885626 -141.099459) (xy 106.870271 -141.151754)
			(xy 106.847629 -141.201331) (xy 106.818163 -141.247181) (xy 106.782472 -141.288372) (xy 106.741281 -141.324063)
			(xy 106.695431 -141.353529) (xy 106.645854 -141.376171) (xy 106.593559 -141.391526) (xy 106.539611 -141.399282)
			(xy 106.485109 -141.399282) (xy 106.431161 -141.391526) (xy 106.378866 -141.376171) (xy 106.329289 -141.353529)
			(xy 106.283439 -141.324063) (xy 106.242248 -141.288372) (xy 106.206557 -141.247181) (xy 106.177091 -141.201331)
			(xy 106.154449 -141.151754) (xy 106.139094 -141.099459) (xy 106.131338 -141.045511) (xy 106.130852 -141.01826)
			(xy 106.131364 -140.989521) (xy 106.139992 -140.932694) (xy 106.157045 -140.877803) (xy 106.182139 -140.826092)
			(xy 106.214705 -140.778729) (xy 106.233976 -140.757402) (xy 106.24058 -140.750544) (xy 106.247692 -140.73251)
			(xy 106.247692 -140.64361) (xy 106.24058 -140.625576) (xy 106.233976 -140.618718) (xy 106.214668 -140.597425)
			(xy 106.182108 -140.550055) (xy 106.157022 -140.498337) (xy 106.139977 -140.443442) (xy 106.131359 -140.386611)
			(xy 106.131363 -140.329131) (xy 106.13999 -140.272301) (xy 106.157043 -140.217408) (xy 106.182137 -140.165694)
			(xy 106.214704 -140.11833) (xy 106.233976 -140.097002) (xy 106.24058 -140.090144) (xy 106.247692 -140.07211)
			(xy 106.247692 -139.98321) (xy 106.24058 -139.965176) (xy 106.233976 -139.958318) (xy 106.214693 -139.937002)
			(xy 106.182127 -139.889638) (xy 106.157036 -139.837923) (xy 106.139988 -139.78303) (xy 106.13137 -139.7262)
			(xy 106.130852 -139.69746) (xy 106.13131 -139.671555) (xy 106.138325 -139.620221) (xy 106.152221 -139.570309)
			(xy 106.172741 -139.522735) (xy 106.199509 -139.478375) (xy 106.215434 -139.457938) (xy 106.221153 -139.450166)
			(xy 106.226912 -139.431767) (xy 106.22661 -139.422124) (xy 106.221022 -139.352528) (xy 106.21992 -139.343099)
			(xy 106.211695 -139.326005) (xy 106.20502 -139.319254) (xy 106.204512 -139.318746) (xy 106.185276 -139.300619)
			(xy 106.151515 -139.259951) (xy 106.123689 -139.215013) (xy 106.102331 -139.166665) (xy 106.087848 -139.115832)
			(xy 106.080519 -139.063487) (xy 106.080052 -139.03706) (xy 80.695292 -139.03706) (xy 80.695292 -139.71651)
			(xy 82.791806 -139.71651) (xy 82.795877 -139.660888) (xy 82.808003 -139.606451) (xy 82.827926 -139.55436)
			(xy 82.855222 -139.505725) (xy 82.889308 -139.461582) (xy 82.929457 -139.422873) (xy 82.974815 -139.390422)
			(xy 83.024415 -139.364921) (xy 83.077199 -139.346914) (xy 83.132042 -139.336784) (xy 83.187776 -139.334747)
			(xy 83.243213 -139.340847) (xy 83.29717 -139.354953) (xy 83.348499 -139.376765) (xy 83.396105 -139.405819)
			(xy 83.438973 -139.441494) (xy 83.47619 -139.483031) (xy 83.506963 -139.529544) (xy 83.530635 -139.580041)
			(xy 83.546703 -139.633448) (xy 83.554823 -139.688624) (xy 83.555332 -139.71651) (xy 83.554823 -139.744396)
			(xy 83.546703 -139.799572) (xy 83.530635 -139.852979) (xy 83.506963 -139.903476) (xy 83.47619 -139.949989)
			(xy 83.438973 -139.991526) (xy 83.396105 -140.027201) (xy 83.35748 -140.050774) (xy 85.235794 -140.050774)
			(xy 85.239865 -139.995152) (xy 85.251991 -139.940715) (xy 85.271914 -139.888624) (xy 85.29921 -139.839989)
			(xy 85.333296 -139.795846) (xy 85.373445 -139.757137) (xy 85.418803 -139.724686) (xy 85.468403 -139.699185)
			(xy 85.521187 -139.681178) (xy 85.57603 -139.671048) (xy 85.631764 -139.669011) (xy 85.687201 -139.675111)
			(xy 85.741158 -139.689217) (xy 85.792487 -139.711029) (xy 85.840093 -139.740083) (xy 85.882961 -139.775758)
			(xy 85.920178 -139.817295) (xy 85.950951 -139.863808) (xy 85.974623 -139.914305) (xy 85.990691 -139.967712)
			(xy 85.998811 -140.022888) (xy 85.99932 -140.050774) (xy 85.998811 -140.07866) (xy 85.990691 -140.133836)
			(xy 85.974623 -140.187243) (xy 85.950951 -140.23774) (xy 85.920178 -140.284253) (xy 85.882961 -140.32579)
			(xy 85.840093 -140.361465) (xy 85.792487 -140.390519) (xy 85.741158 -140.412331) (xy 85.687201 -140.426437)
			(xy 85.631764 -140.432537) (xy 85.57603 -140.4305) (xy 85.521187 -140.42037) (xy 85.468403 -140.402363)
			(xy 85.418803 -140.376862) (xy 85.373445 -140.344411) (xy 85.333296 -140.305702) (xy 85.29921 -140.261559)
			(xy 85.271914 -140.212924) (xy 85.251991 -140.160833) (xy 85.239865 -140.106396) (xy 85.235794 -140.050774)
			(xy 83.35748 -140.050774) (xy 83.348499 -140.056255) (xy 83.29717 -140.078067) (xy 83.243213 -140.092173)
			(xy 83.187776 -140.098273) (xy 83.132042 -140.096236) (xy 83.077199 -140.086106) (xy 83.024415 -140.068099)
			(xy 82.974815 -140.042598) (xy 82.929457 -140.010147) (xy 82.889308 -139.971438) (xy 82.855222 -139.927295)
			(xy 82.827926 -139.87866) (xy 82.808003 -139.826569) (xy 82.795877 -139.772132) (xy 82.791806 -139.71651)
			(xy 80.695292 -139.71651) (xy 80.695292 -140.534898) (xy 81.097372 -140.534898) (xy 81.101443 -140.479276)
			(xy 81.113569 -140.424839) (xy 81.133492 -140.372748) (xy 81.160788 -140.324113) (xy 81.194874 -140.27997)
			(xy 81.235023 -140.241261) (xy 81.280381 -140.20881) (xy 81.329981 -140.183309) (xy 81.382765 -140.165302)
			(xy 81.437608 -140.155172) (xy 81.493342 -140.153135) (xy 81.548779 -140.159235) (xy 81.602736 -140.173341)
			(xy 81.654065 -140.195153) (xy 81.701671 -140.224207) (xy 81.744539 -140.259882) (xy 81.781756 -140.301419)
			(xy 81.812529 -140.347932) (xy 81.836201 -140.398429) (xy 81.852269 -140.451836) (xy 81.860389 -140.507012)
			(xy 81.860898 -140.534898) (xy 81.860389 -140.562784) (xy 81.852269 -140.61796) (xy 81.836201 -140.671367)
			(xy 81.812529 -140.721864) (xy 81.781756 -140.768377) (xy 81.744539 -140.809914) (xy 81.701671 -140.845589)
			(xy 81.654065 -140.874643) (xy 81.602736 -140.896455) (xy 81.548779 -140.910561) (xy 81.493342 -140.916661)
			(xy 81.437608 -140.914624) (xy 81.382765 -140.904494) (xy 81.329981 -140.886487) (xy 81.280381 -140.860986)
			(xy 81.235023 -140.828535) (xy 81.194874 -140.789826) (xy 81.160788 -140.745683) (xy 81.133492 -140.697048)
			(xy 81.113569 -140.644957) (xy 81.101443 -140.59052) (xy 81.097372 -140.534898) (xy 80.695292 -140.534898)
			(xy 80.695292 -140.798296) (xy 80.694929 -140.836222) (xy 80.689147 -140.911854) (xy 80.677632 -140.986828)
			(xy 80.669384 -141.023848) (xy 80.586326 -141.380464) (xy 80.560672 -141.491462) (xy 80.428338 -142.060676)
			(xy 80.42783 -142.065756) (xy 80.367527 -143.479266) (xy 81.07426 -143.479266) (xy 81.07426 -142.615666)
			(xy 81.07475 -142.585682) (xy 81.082578 -142.526226) (xy 81.098099 -142.468301) (xy 81.121048 -142.412897)
			(xy 81.151032 -142.360963) (xy 81.187538 -142.313387) (xy 81.229943 -142.270982) (xy 81.277519 -142.234476)
			(xy 81.329453 -142.204492) (xy 81.384857 -142.181543) (xy 81.442782 -142.166022) (xy 81.502238 -142.158194)
			(xy 81.562206 -142.158194) (xy 81.621662 -142.166022) (xy 81.679587 -142.181543) (xy 81.734991 -142.204492)
			(xy 81.786925 -142.234476) (xy 81.834501 -142.270982) (xy 81.876906 -142.313387) (xy 81.913412 -142.360963)
			(xy 81.943396 -142.412897) (xy 81.966345 -142.468301) (xy 81.981866 -142.526226) (xy 81.989694 -142.585682)
			(xy 81.990184 -142.615666) (xy 81.990184 -143.078551) (xy 126.854954 -143.078551) (xy 126.854954 -143.024049)
			(xy 126.86271 -142.9701) (xy 126.878064 -142.917805) (xy 126.900704 -142.868227) (xy 126.930169 -142.822375)
			(xy 126.965859 -142.781183) (xy 127.007048 -142.74549) (xy 127.052897 -142.716021) (xy 127.102473 -142.693376)
			(xy 127.154767 -142.678017) (xy 127.208715 -142.670256) (xy 127.235966 -142.669768) (xy 127.262281 -142.670202)
			(xy 127.314411 -142.677445) (xy 127.365054 -142.691771) (xy 127.413252 -142.71291) (xy 127.458095 -142.740462)
			(xy 127.498734 -142.773905) (xy 127.51689 -142.792958) (xy 127.524419 -142.800351) (xy 127.543693 -142.808882)
			(xy 127.554228 -142.809468) (xy 127.628904 -142.809468) (xy 127.639457 -142.808964) (xy 127.658752 -142.800412)
			(xy 127.666242 -142.792958) (xy 127.684376 -142.773881) (xy 127.725011 -142.740427) (xy 127.769856 -142.712872)
			(xy 127.818061 -142.691738) (xy 127.868712 -142.677425) (xy 127.920849 -142.670204) (xy 127.947166 -142.669768)
			(xy 127.974419 -142.670277) (xy 128.02837 -142.67803) (xy 128.080669 -142.693382) (xy 128.13025 -142.716021)
			(xy 128.176104 -142.745486) (xy 128.217299 -142.781177) (xy 128.252994 -142.822368) (xy 128.282463 -142.86822)
			(xy 128.305106 -142.9178) (xy 128.320463 -142.970097) (xy 128.328221 -143.024047) (xy 128.328221 -143.078553)
			(xy 128.320463 -143.132503) (xy 128.305106 -143.1848) (xy 128.282463 -143.23438) (xy 128.252994 -143.280232)
			(xy 128.217299 -143.321423) (xy 128.176104 -143.357114) (xy 128.13025 -143.386579) (xy 128.080669 -143.409218)
			(xy 128.02837 -143.42457) (xy 127.974419 -143.432323) (xy 127.947166 -143.432784) (xy 127.920851 -143.432344)
			(xy 127.868721 -143.425105) (xy 127.818078 -143.41078) (xy 127.769879 -143.389643) (xy 127.725036 -143.362092)
			(xy 127.684398 -143.328648) (xy 127.666242 -143.309594) (xy 127.658707 -143.302208) (xy 127.639437 -143.293675)
			(xy 127.628904 -143.293084) (xy 127.554228 -143.293084) (xy 127.543679 -143.29362) (xy 127.524384 -143.302151)
			(xy 127.51689 -143.309594) (xy 127.498731 -143.328646) (xy 127.458102 -143.362104) (xy 127.413263 -143.389664)
			(xy 127.365063 -143.410803) (xy 127.314416 -143.42512) (xy 127.262282 -143.432345) (xy 127.235966 -143.432784)
			(xy 127.208715 -143.432344) (xy 127.154767 -143.424583) (xy 127.102473 -143.409224) (xy 127.052897 -143.386579)
			(xy 127.007048 -143.35711) (xy 126.965859 -143.321417) (xy 126.930169 -143.280225) (xy 126.900704 -143.234373)
			(xy 126.878064 -143.184795) (xy 126.86271 -143.1325) (xy 126.854954 -143.078551) (xy 81.990184 -143.078551)
			(xy 81.990184 -143.479266) (xy 81.989694 -143.50925) (xy 81.981866 -143.568706) (xy 81.966345 -143.626631)
			(xy 81.943396 -143.682035) (xy 81.913412 -143.733969) (xy 81.876906 -143.781545) (xy 81.834501 -143.82395)
			(xy 81.786925 -143.860456) (xy 81.734991 -143.89044) (xy 81.679587 -143.913389) (xy 81.621662 -143.92891)
			(xy 81.562206 -143.936738) (xy 81.502238 -143.936738) (xy 81.442782 -143.92891) (xy 81.384857 -143.913389)
			(xy 81.329453 -143.89044) (xy 81.277519 -143.860456) (xy 81.229943 -143.82395) (xy 81.187538 -143.781545)
			(xy 81.151032 -143.733969) (xy 81.121048 -143.682035) (xy 81.098099 -143.626631) (xy 81.082578 -143.568706)
			(xy 81.07475 -143.50925) (xy 81.07426 -143.479266) (xy 80.367527 -143.479266) (xy 80.29046 -145.285714)
			(xy 83.716368 -145.285714) (xy 83.716368 -144.422114) (xy 83.716858 -144.39213) (xy 83.724686 -144.332674)
			(xy 83.740207 -144.274749) (xy 83.763156 -144.219345) (xy 83.79314 -144.167411) (xy 83.829646 -144.119835)
			(xy 83.872051 -144.07743) (xy 83.919627 -144.040924) (xy 83.971561 -144.01094) (xy 84.026965 -143.987991)
			(xy 84.08489 -143.97247) (xy 84.144346 -143.964642) (xy 84.204314 -143.964642) (xy 84.217955 -143.966438)
			(xy 135.564118 -143.966438) (xy 135.564527 -143.940462) (xy 135.571578 -143.88899) (xy 135.585553 -143.838952)
			(xy 135.606195 -143.791276) (xy 135.63312 -143.746845) (xy 135.66583 -143.706483) (xy 135.703718 -143.670936)
			(xy 135.724646 -143.655542) (xy 135.734137 -143.64791) (xy 135.745282 -143.626298) (xy 135.745982 -143.61414)
			(xy 135.745982 -143.531336) (xy 135.745289 -143.519174) (xy 135.73415 -143.497553) (xy 135.724646 -143.489934)
			(xy 135.703727 -143.474531) (xy 135.665851 -143.438978) (xy 135.633151 -143.398613) (xy 135.606232 -143.354184)
			(xy 135.585593 -143.306511) (xy 135.571616 -143.256479) (xy 135.56456 -143.205012) (xy 135.564118 -143.179038)
			(xy 135.564626 -143.150299) (xy 135.573256 -143.093472) (xy 135.590311 -143.038582) (xy 135.615405 -142.98687)
			(xy 135.647971 -142.939507) (xy 135.667242 -142.91818) (xy 135.673846 -142.911322) (xy 135.680958 -142.893288)
			(xy 135.680958 -142.804388) (xy 135.673846 -142.786354) (xy 135.667242 -142.779496) (xy 135.648008 -142.758137)
			(xy 135.61544 -142.710781) (xy 135.590345 -142.659074) (xy 135.573292 -142.604188) (xy 135.564665 -142.547365)
			(xy 135.564661 -142.489891) (xy 135.573279 -142.433066) (xy 135.590325 -142.378177) (xy 135.615412 -142.326467)
			(xy 135.647973 -142.279106) (xy 135.667242 -142.25778) (xy 135.673846 -142.250922) (xy 135.680958 -142.232888)
			(xy 135.680958 -142.143988) (xy 135.673846 -142.125954) (xy 135.667242 -142.119096) (xy 135.648008 -142.097737)
			(xy 135.61544 -142.050381) (xy 135.590345 -141.998674) (xy 135.573292 -141.943788) (xy 135.564665 -141.886965)
			(xy 135.564661 -141.829491) (xy 135.573279 -141.772666) (xy 135.590325 -141.717777) (xy 135.615412 -141.666067)
			(xy 135.647973 -141.618706) (xy 135.667242 -141.59738) (xy 135.673846 -141.590522) (xy 135.680958 -141.572488)
			(xy 135.680958 -141.483588) (xy 135.673846 -141.465554) (xy 135.667242 -141.458696) (xy 135.648008 -141.437337)
			(xy 135.61544 -141.389981) (xy 135.590345 -141.338274) (xy 135.573292 -141.283388) (xy 135.564665 -141.226565)
			(xy 135.564661 -141.169091) (xy 135.573279 -141.112266) (xy 135.590325 -141.057377) (xy 135.615412 -141.005667)
			(xy 135.647973 -140.958306) (xy 135.667242 -140.93698) (xy 135.673846 -140.930122) (xy 135.680958 -140.912088)
			(xy 135.680958 -140.823188) (xy 135.673846 -140.805154) (xy 135.667242 -140.798296) (xy 135.64799 -140.776953)
			(xy 135.615421 -140.729595) (xy 135.590325 -140.677888) (xy 135.57327 -140.623001) (xy 135.564642 -140.566176)
			(xy 135.564118 -140.537438) (xy 135.564604 -140.510187) (xy 135.57236 -140.456239) (xy 135.587715 -140.403944)
			(xy 135.610357 -140.354367) (xy 135.639823 -140.308517) (xy 135.675514 -140.267326) (xy 135.716705 -140.231635)
			(xy 135.762555 -140.202169) (xy 135.812132 -140.179527) (xy 135.864427 -140.164172) (xy 135.918375 -140.156416)
			(xy 135.972877 -140.156416) (xy 136.026825 -140.164172) (xy 136.07912 -140.179527) (xy 136.128697 -140.202169)
			(xy 136.174547 -140.231635) (xy 136.215738 -140.267326) (xy 136.251429 -140.308517) (xy 136.280895 -140.354367)
			(xy 136.303537 -140.403944) (xy 136.318892 -140.456239) (xy 136.326648 -140.510187) (xy 136.327134 -140.537438)
			(xy 136.326624 -140.566177) (xy 136.317997 -140.623005) (xy 136.300943 -140.677895) (xy 136.275849 -140.729607)
			(xy 136.243281 -140.776969) (xy 136.22401 -140.798296) (xy 136.217406 -140.805154) (xy 136.210294 -140.823188)
			(xy 136.210294 -140.912088) (xy 136.217406 -140.930122) (xy 136.22401 -140.93698) (xy 136.243317 -140.958275)
			(xy 136.275878 -141.005644) (xy 136.300965 -141.057361) (xy 136.318011 -141.112256) (xy 136.326629 -141.169087)
			(xy 136.326625 -141.226568) (xy 136.317999 -141.283398) (xy 136.300945 -141.338291) (xy 136.27585 -141.390004)
			(xy 136.243282 -141.437368) (xy 136.22401 -141.458696) (xy 136.217406 -141.465554) (xy 136.210294 -141.483588)
			(xy 136.210294 -141.572488) (xy 136.217406 -141.590522) (xy 136.22401 -141.59738) (xy 136.243317 -141.618675)
			(xy 136.275878 -141.666044) (xy 136.300965 -141.717761) (xy 136.318011 -141.772656) (xy 136.326629 -141.829487)
			(xy 136.326625 -141.886968) (xy 136.317999 -141.943798) (xy 136.300945 -141.998691) (xy 136.27585 -142.050404)
			(xy 136.243282 -142.097768) (xy 136.22401 -142.119096) (xy 136.217406 -142.125954) (xy 136.210294 -142.143988)
			(xy 136.210294 -142.232888) (xy 136.217406 -142.250922) (xy 136.22401 -142.25778) (xy 136.243317 -142.279075)
			(xy 136.275878 -142.326444) (xy 136.300965 -142.378161) (xy 136.318011 -142.433056) (xy 136.326629 -142.489887)
			(xy 136.326625 -142.547368) (xy 136.317999 -142.604198) (xy 136.300945 -142.659091) (xy 136.27585 -142.710804)
			(xy 136.243282 -142.758168) (xy 136.22401 -142.779496) (xy 136.217406 -142.786354) (xy 136.210294 -142.804388)
			(xy 136.210294 -142.893288) (xy 136.217406 -142.911322) (xy 136.22401 -142.91818) (xy 136.24329 -142.939499)
			(xy 136.275857 -142.986863) (xy 136.300948 -143.038576) (xy 136.317996 -143.093469) (xy 136.326615 -143.150298)
			(xy 136.327134 -143.179038) (xy 136.326727 -143.205015) (xy 136.319679 -143.256488) (xy 136.305704 -143.306526)
			(xy 136.285063 -143.354203) (xy 136.258137 -143.398634) (xy 136.225426 -143.438996) (xy 136.187535 -143.474541)
			(xy 136.166606 -143.489934) (xy 136.157135 -143.497587) (xy 136.145977 -143.519183) (xy 136.14527 -143.531336)
			(xy 136.14527 -143.61414) (xy 136.145957 -143.626303) (xy 136.157098 -143.647926) (xy 136.166606 -143.655542)
			(xy 136.187525 -143.670945) (xy 136.225399 -143.706499) (xy 136.258098 -143.746865) (xy 136.285015 -143.791294)
			(xy 136.305654 -143.838966) (xy 136.319632 -143.888998) (xy 136.326691 -143.940464) (xy 136.327134 -143.966438)
			(xy 136.326648 -143.993689) (xy 136.318892 -144.047637) (xy 136.303537 -144.099932) (xy 136.280895 -144.149509)
			(xy 136.251429 -144.195359) (xy 136.215738 -144.23655) (xy 136.174547 -144.272241) (xy 136.128697 -144.301707)
			(xy 136.07912 -144.324349) (xy 136.026825 -144.339704) (xy 135.972877 -144.34746) (xy 135.918375 -144.34746)
			(xy 135.864427 -144.339704) (xy 135.812132 -144.324349) (xy 135.762555 -144.301707) (xy 135.716705 -144.272241)
			(xy 135.675514 -144.23655) (xy 135.639823 -144.195359) (xy 135.610357 -144.149509) (xy 135.587715 -144.099932)
			(xy 135.57236 -144.047637) (xy 135.564604 -143.993689) (xy 135.564118 -143.966438) (xy 84.217955 -143.966438)
			(xy 84.26377 -143.97247) (xy 84.321695 -143.987991) (xy 84.377099 -144.01094) (xy 84.429033 -144.040924)
			(xy 84.476609 -144.07743) (xy 84.519014 -144.119835) (xy 84.55552 -144.167411) (xy 84.585504 -144.219345)
			(xy 84.608453 -144.274749) (xy 84.623974 -144.332674) (xy 84.631802 -144.39213) (xy 84.632292 -144.422114)
			(xy 84.632292 -145.110551) (xy 126.854954 -145.110551) (xy 126.854954 -145.056049) (xy 126.86271 -145.0021)
			(xy 126.878064 -144.949805) (xy 126.900704 -144.900227) (xy 126.930169 -144.854375) (xy 126.965859 -144.813183)
			(xy 127.007048 -144.77749) (xy 127.052897 -144.748021) (xy 127.102473 -144.725376) (xy 127.154767 -144.710017)
			(xy 127.208715 -144.702256) (xy 127.235966 -144.701768) (xy 127.262281 -144.702202) (xy 127.314411 -144.709445)
			(xy 127.365054 -144.723771) (xy 127.413252 -144.74491) (xy 127.458095 -144.772462) (xy 127.498734 -144.805905)
			(xy 127.51689 -144.824958) (xy 127.524419 -144.832351) (xy 127.543693 -144.840882) (xy 127.554228 -144.841468)
			(xy 127.628904 -144.841468) (xy 127.639457 -144.840964) (xy 127.658752 -144.832412) (xy 127.666242 -144.824958)
			(xy 127.684376 -144.805881) (xy 127.725011 -144.772427) (xy 127.769856 -144.744872) (xy 127.818061 -144.723738)
			(xy 127.868712 -144.709425) (xy 127.920849 -144.702204) (xy 127.947166 -144.701768) (xy 127.974419 -144.702277)
			(xy 128.02837 -144.71003) (xy 128.080669 -144.725382) (xy 128.13025 -144.748021) (xy 128.176104 -144.777486)
			(xy 128.217299 -144.813177) (xy 128.252994 -144.854368) (xy 128.282463 -144.90022) (xy 128.305106 -144.9498)
			(xy 128.306411 -144.954244) (xy 134.038848 -144.954244) (xy 134.039419 -144.926996) (xy 134.047168 -144.873054)
			(xy 134.062516 -144.820763) (xy 134.085149 -144.771189) (xy 134.114606 -144.725341) (xy 134.150289 -144.684151)
			(xy 134.19147 -144.648459) (xy 134.237312 -144.618991) (xy 134.286881 -144.596347) (xy 134.339167 -144.580987)
			(xy 134.393108 -144.573225) (xy 134.420356 -144.572736) (xy 134.44913 -144.573257) (xy 134.506025 -144.581907)
			(xy 134.560976 -144.599004) (xy 134.612736 -144.624159) (xy 134.660132 -144.656801) (xy 134.681468 -144.676114)
			(xy 134.689342 -144.68348) (xy 134.709154 -144.690592) (xy 134.80542 -144.683226) (xy 134.824216 -144.67332)
			(xy 134.83082 -144.664938) (xy 134.849055 -144.642762) (xy 134.890987 -144.603551) (xy 134.938321 -144.571063)
			(xy 134.989987 -144.546033) (xy 135.04482 -144.529025) (xy 135.101581 -144.520423) (xy 135.130286 -144.519904)
			(xy 135.157539 -144.520368) (xy 135.211491 -144.528124) (xy 135.263789 -144.543479) (xy 135.31337 -144.56612)
			(xy 135.359224 -144.595588) (xy 135.400417 -144.631282) (xy 135.436111 -144.672475) (xy 135.465579 -144.718328)
			(xy 135.488221 -144.767909) (xy 135.503576 -144.820207) (xy 135.511331 -144.874159) (xy 135.511794 -144.901412)
			(xy 135.511345 -144.928315) (xy 135.503772 -144.981586) (xy 135.48879 -145.033265) (xy 135.466698 -145.082327)
			(xy 135.437933 -145.127799) (xy 135.403067 -145.16878) (xy 135.362789 -145.204457) (xy 135.340598 -145.219674)
			(xy 135.329676 -145.226786) (xy 135.317738 -145.249646) (xy 135.31977 -145.361914) (xy 135.332724 -145.384266)
			(xy 135.3439 -145.391124) (xy 135.367501 -145.406046) (xy 135.410453 -145.441725) (xy 135.447747 -145.483283)
			(xy 135.478584 -145.529833) (xy 135.502308 -145.58038) (xy 135.51841 -145.633846) (xy 135.526548 -145.689087)
			(xy 135.527034 -145.717006) (xy 135.526579 -145.744) (xy 135.518972 -145.797448) (xy 135.50391 -145.849292)
			(xy 135.481695 -145.898496) (xy 135.452769 -145.94408) (xy 135.435594 -145.96491) (xy 135.428482 -145.973038)
			(xy 135.422386 -145.993612) (xy 135.433308 -146.078956) (xy 135.435097 -146.089497) (xy 135.446141 -146.107781)
			(xy 135.454644 -146.114262) (xy 135.47585 -146.129648) (xy 135.514304 -146.16523) (xy 135.547524 -146.205741)
			(xy 135.574886 -146.250418) (xy 135.595874 -146.298421) (xy 135.610092 -146.348845) (xy 135.617273 -146.400741)
			(xy 135.617712 -146.426936) (xy 135.617226 -146.454187) (xy 135.60947 -146.508135) (xy 135.594115 -146.56043)
			(xy 135.571473 -146.610007) (xy 135.542007 -146.655857) (xy 135.506316 -146.697048) (xy 135.465125 -146.732739)
			(xy 135.419275 -146.762205) (xy 135.369698 -146.784847) (xy 135.317403 -146.800202) (xy 135.263455 -146.807958)
			(xy 135.208953 -146.807958) (xy 135.155005 -146.800202) (xy 135.10271 -146.784847) (xy 135.053133 -146.762205)
			(xy 135.007283 -146.732739) (xy 134.966092 -146.697048) (xy 134.930401 -146.655857) (xy 134.900935 -146.610007)
			(xy 134.878293 -146.56043) (xy 134.862938 -146.508135) (xy 134.855182 -146.454187) (xy 134.854696 -146.426936)
			(xy 134.855192 -146.399944) (xy 134.862792 -146.346498) (xy 134.877845 -146.294656) (xy 134.90005 -146.24545)
			(xy 134.928966 -146.199864) (xy 134.946136 -146.179032) (xy 134.953248 -146.170904) (xy 134.959344 -146.15033)
			(xy 134.948422 -146.064986) (xy 134.94665 -146.054441) (xy 134.935593 -146.036159) (xy 134.927086 -146.02968)
			(xy 134.902785 -146.012068) (xy 134.859526 -145.970472) (xy 134.84098 -145.946876) (xy 134.835138 -145.939002)
			(xy 134.817612 -145.928588) (xy 134.727188 -145.91538) (xy 134.707884 -145.920206) (xy 134.70001 -145.926048)
			(xy 134.699756 -145.926048) (xy 134.675012 -145.943552) (xy 134.62116 -145.971355) (xy 134.563588 -145.990291)
			(xy 134.503745 -145.999883) (xy 134.473442 -146.00047) (xy 134.446188 -146.000006) (xy 134.392236 -145.992253)
			(xy 134.339935 -145.976901) (xy 134.290353 -145.95426) (xy 134.244498 -145.924793) (xy 134.203304 -145.889099)
			(xy 134.167609 -145.847905) (xy 134.138142 -145.802051) (xy 134.115501 -145.752468) (xy 134.100148 -145.700168)
			(xy 134.092395 -145.646216) (xy 134.091934 -145.618962) (xy 134.092369 -145.592928) (xy 134.09946 -145.541345)
			(xy 134.113493 -145.491203) (xy 134.134206 -145.443432) (xy 134.161217 -145.398918) (xy 134.177278 -145.378424)
			(xy 134.183019 -145.370666) (xy 134.18876 -145.352256) (xy 134.188454 -145.34261) (xy 134.182104 -145.262854)
			(xy 134.173468 -145.245074) (xy 134.166102 -145.238724) (xy 134.146463 -145.220535) (xy 134.111937 -145.179632)
			(xy 134.083465 -145.134305) (xy 134.061605 -145.085444) (xy 134.046787 -145.034009) (xy 134.039302 -144.981008)
			(xy 134.038848 -144.954244) (xy 128.306411 -144.954244) (xy 128.320463 -145.002097) (xy 128.328221 -145.056047)
			(xy 128.328221 -145.110553) (xy 128.320463 -145.164503) (xy 128.305106 -145.2168) (xy 128.282463 -145.26638)
			(xy 128.252994 -145.312232) (xy 128.217299 -145.353423) (xy 128.176104 -145.389114) (xy 128.13025 -145.418579)
			(xy 128.080669 -145.441218) (xy 128.02837 -145.45657) (xy 127.974419 -145.464323) (xy 127.947166 -145.464784)
			(xy 127.920851 -145.464344) (xy 127.868721 -145.457105) (xy 127.818078 -145.44278) (xy 127.769879 -145.421643)
			(xy 127.725036 -145.394092) (xy 127.684398 -145.360648) (xy 127.666242 -145.341594) (xy 127.658707 -145.334208)
			(xy 127.639437 -145.325675) (xy 127.628904 -145.325084) (xy 127.554228 -145.325084) (xy 127.543679 -145.32562)
			(xy 127.524384 -145.334151) (xy 127.51689 -145.341594) (xy 127.498731 -145.360646) (xy 127.458102 -145.394104)
			(xy 127.413263 -145.421664) (xy 127.365063 -145.442803) (xy 127.314416 -145.45712) (xy 127.262282 -145.464345)
			(xy 127.235966 -145.464784) (xy 127.208715 -145.464344) (xy 127.154767 -145.456583) (xy 127.102473 -145.441224)
			(xy 127.052897 -145.418579) (xy 127.007048 -145.38911) (xy 126.965859 -145.353417) (xy 126.930169 -145.312225)
			(xy 126.900704 -145.266373) (xy 126.878064 -145.216795) (xy 126.86271 -145.1645) (xy 126.854954 -145.110551)
			(xy 84.632292 -145.110551) (xy 84.632292 -145.285714) (xy 84.631802 -145.315698) (xy 84.623974 -145.375154)
			(xy 84.608453 -145.433079) (xy 84.585504 -145.488483) (xy 84.55552 -145.540417) (xy 84.519014 -145.587993)
			(xy 84.476609 -145.630398) (xy 84.429033 -145.666904) (xy 84.377099 -145.696888) (xy 84.321695 -145.719837)
			(xy 84.26377 -145.735358) (xy 84.204314 -145.743186) (xy 84.144346 -145.743186) (xy 84.08489 -145.735358)
			(xy 84.026965 -145.719837) (xy 83.971561 -145.696888) (xy 83.919627 -145.666904) (xy 83.872051 -145.630398)
			(xy 83.829646 -145.587993) (xy 83.79314 -145.540417) (xy 83.763156 -145.488483) (xy 83.740207 -145.433079)
			(xy 83.724686 -145.375154) (xy 83.716858 -145.315698) (xy 83.716368 -145.285714) (xy 80.29046 -145.285714)
			(xy 80.26273 -145.9357) (xy 80.246982 -146.302984) (xy 80.246728 -146.30908) (xy 80.246728 -146.309588)
			(xy 80.244442 -146.342354) (xy 80.183819 -147.079208) (xy 81.07426 -147.079208) (xy 81.07426 -146.215608)
			(xy 81.07475 -146.185624) (xy 81.082578 -146.126168) (xy 81.098099 -146.068243) (xy 81.121048 -146.012839)
			(xy 81.151032 -145.960905) (xy 81.187538 -145.913329) (xy 81.229943 -145.870924) (xy 81.277519 -145.834418)
			(xy 81.329453 -145.804434) (xy 81.384857 -145.781485) (xy 81.442782 -145.765964) (xy 81.502238 -145.758136)
			(xy 81.562206 -145.758136) (xy 81.621662 -145.765964) (xy 81.679587 -145.781485) (xy 81.734991 -145.804434)
			(xy 81.786925 -145.834418) (xy 81.834501 -145.870924) (xy 81.876906 -145.913329) (xy 81.913412 -145.960905)
			(xy 81.943396 -146.012839) (xy 81.966345 -146.068243) (xy 81.981866 -146.126168) (xy 81.989694 -146.185624)
			(xy 81.990184 -146.215608) (xy 81.990184 -146.91487) (xy 135.716008 -146.91487) (xy 135.720079 -146.859248)
			(xy 135.732205 -146.804811) (xy 135.752128 -146.75272) (xy 135.779424 -146.704085) (xy 135.81351 -146.659942)
			(xy 135.853659 -146.621233) (xy 135.899017 -146.588782) (xy 135.948617 -146.563281) (xy 136.001401 -146.545274)
			(xy 136.056244 -146.535144) (xy 136.111978 -146.533107) (xy 136.167415 -146.539207) (xy 136.221372 -146.553313)
			(xy 136.272701 -146.575125) (xy 136.320307 -146.604179) (xy 136.363175 -146.639854) (xy 136.400392 -146.681391)
			(xy 136.431165 -146.727904) (xy 136.454837 -146.778401) (xy 136.470905 -146.831808) (xy 136.479025 -146.886984)
			(xy 136.479534 -146.91487) (xy 136.479025 -146.942756) (xy 136.470905 -146.997932) (xy 136.454837 -147.051339)
			(xy 136.449631 -147.062444) (xy 137.094212 -147.062444) (xy 137.098283 -147.006822) (xy 137.110409 -146.952385)
			(xy 137.130332 -146.900294) (xy 137.157628 -146.851659) (xy 137.191714 -146.807516) (xy 137.231863 -146.768807)
			(xy 137.277221 -146.736356) (xy 137.326821 -146.710855) (xy 137.379605 -146.692848) (xy 137.434448 -146.682718)
			(xy 137.490182 -146.680681) (xy 137.545619 -146.686781) (xy 137.599576 -146.700887) (xy 137.650905 -146.722699)
			(xy 137.698511 -146.751753) (xy 137.741379 -146.787428) (xy 137.778596 -146.828965) (xy 137.809369 -146.875478)
			(xy 137.833041 -146.925975) (xy 137.849109 -146.979382) (xy 137.857229 -147.034558) (xy 137.857738 -147.062444)
			(xy 137.857229 -147.09033) (xy 137.849109 -147.145506) (xy 137.833041 -147.198913) (xy 137.809369 -147.24941)
			(xy 137.778596 -147.295923) (xy 137.741379 -147.33746) (xy 137.698511 -147.373135) (xy 137.650905 -147.402189)
			(xy 137.599576 -147.424001) (xy 137.545619 -147.438107) (xy 137.490182 -147.444207) (xy 137.434448 -147.44217)
			(xy 137.379605 -147.43204) (xy 137.326821 -147.414033) (xy 137.277221 -147.388532) (xy 137.231863 -147.356081)
			(xy 137.191714 -147.317372) (xy 137.157628 -147.273229) (xy 137.130332 -147.224594) (xy 137.110409 -147.172503)
			(xy 137.098283 -147.118066) (xy 137.094212 -147.062444) (xy 136.449631 -147.062444) (xy 136.431165 -147.101836)
			(xy 136.400392 -147.148349) (xy 136.363175 -147.189886) (xy 136.320307 -147.225561) (xy 136.272701 -147.254615)
			(xy 136.221372 -147.276427) (xy 136.167415 -147.290533) (xy 136.111978 -147.296633) (xy 136.056244 -147.294596)
			(xy 136.001401 -147.284466) (xy 135.948617 -147.266459) (xy 135.899017 -147.240958) (xy 135.853659 -147.208507)
			(xy 135.81351 -147.169798) (xy 135.779424 -147.125655) (xy 135.752128 -147.07702) (xy 135.732205 -147.024929)
			(xy 135.720079 -146.970492) (xy 135.716008 -146.91487) (xy 81.990184 -146.91487) (xy 81.990184 -147.079208)
			(xy 81.989694 -147.109192) (xy 81.981866 -147.168648) (xy 81.966345 -147.226573) (xy 81.943396 -147.281977)
			(xy 81.913412 -147.333911) (xy 81.876906 -147.381487) (xy 81.834501 -147.423892) (xy 81.786925 -147.460398)
			(xy 81.734991 -147.490382) (xy 81.679587 -147.513331) (xy 81.621662 -147.528852) (xy 81.562206 -147.53668)
			(xy 81.502238 -147.53668) (xy 81.442782 -147.528852) (xy 81.384857 -147.513331) (xy 81.329453 -147.490382)
			(xy 81.277519 -147.460398) (xy 81.229943 -147.423892) (xy 81.187538 -147.381487) (xy 81.151032 -147.333911)
			(xy 81.121048 -147.281977) (xy 81.098099 -147.226573) (xy 81.082578 -147.168648) (xy 81.07475 -147.109192)
			(xy 81.07426 -147.079208) (xy 80.183819 -147.079208) (xy 80.035176 -148.88591) (xy 83.716368 -148.88591)
			(xy 83.716368 -148.02231) (xy 83.716858 -147.992326) (xy 83.724686 -147.93287) (xy 83.740207 -147.874945)
			(xy 83.763156 -147.819541) (xy 83.79314 -147.767607) (xy 83.829646 -147.720031) (xy 83.872051 -147.677626)
			(xy 83.919627 -147.64112) (xy 83.971561 -147.611136) (xy 84.026965 -147.588187) (xy 84.08489 -147.572666)
			(xy 84.144346 -147.564838) (xy 84.204314 -147.564838) (xy 84.26377 -147.572666) (xy 84.321695 -147.588187)
			(xy 84.377099 -147.611136) (xy 84.429033 -147.64112) (xy 84.450583 -147.657656) (xy 127.250343 -147.657656)
			(xy 127.250343 -147.603144) (xy 127.258101 -147.549188) (xy 127.27346 -147.496885) (xy 127.296107 -147.4473)
			(xy 127.32558 -147.401443) (xy 127.361279 -147.360248) (xy 127.402478 -147.324553) (xy 127.448339 -147.295085)
			(xy 127.497926 -147.272445) (xy 127.550231 -147.257092) (xy 127.604188 -147.24934) (xy 127.631444 -147.24888)
			(xy 127.657759 -147.249324) (xy 127.709888 -147.256565) (xy 127.760531 -147.270889) (xy 127.80873 -147.292026)
			(xy 127.853573 -147.319576) (xy 127.894212 -147.353017) (xy 127.912368 -147.37207) (xy 127.919904 -147.379455)
			(xy 127.939173 -147.38799) (xy 127.949706 -147.38858) (xy 128.024382 -147.38858) (xy 128.034933 -147.388061)
			(xy 128.054229 -147.379519) (xy 128.06172 -147.37207) (xy 128.08154 -147.351282) (xy 128.126312 -147.315307)
			(xy 128.17597 -147.286447) (xy 128.229392 -147.265354) (xy 128.285371 -147.252505) (xy 128.342644 -147.24819)
			(xy 128.399917 -147.252505) (xy 128.455896 -147.265354) (xy 128.509318 -147.286447) (xy 128.558976 -147.315307)
			(xy 128.603748 -147.351282) (xy 128.623568 -147.37207) (xy 128.631104 -147.379455) (xy 128.650373 -147.38799)
			(xy 128.660906 -147.38858) (xy 128.735582 -147.38858) (xy 128.746133 -147.388061) (xy 128.765429 -147.379519)
			(xy 128.77292 -147.37207) (xy 128.791067 -147.353006) (xy 128.831699 -147.319551) (xy 128.876541 -147.291994)
			(xy 128.924744 -147.270857) (xy 128.975393 -147.256541) (xy 129.027527 -147.249318) (xy 129.053844 -147.24888)
			(xy 129.081092 -147.249393) (xy 129.135034 -147.257155) (xy 129.187321 -147.272513) (xy 129.236891 -147.295156)
			(xy 129.282735 -147.324622) (xy 129.323918 -147.360313) (xy 129.359604 -147.401501) (xy 129.389065 -147.447347)
			(xy 129.411702 -147.49692) (xy 129.427055 -147.54921) (xy 129.43481 -147.603152) (xy 129.43481 -147.657648)
			(xy 129.427055 -147.71159) (xy 129.411702 -147.76388) (xy 129.389065 -147.813453) (xy 129.359604 -147.859299)
			(xy 129.323918 -147.900487) (xy 129.282735 -147.936178) (xy 129.236891 -147.965644) (xy 129.187321 -147.988287)
			(xy 129.135034 -148.003645) (xy 129.081092 -148.011407) (xy 129.053844 -148.011896) (xy 129.027529 -148.011467)
			(xy 128.975398 -148.004225) (xy 128.924755 -147.989898) (xy 128.876556 -147.968758) (xy 128.831714 -147.941205)
			(xy 128.791076 -147.90776) (xy 128.77292 -147.888706) (xy 128.765392 -147.881312) (xy 128.746117 -147.872783)
			(xy 128.735582 -147.872196) (xy 128.660906 -147.872196) (xy 128.650355 -147.872716) (xy 128.63106 -147.881258)
			(xy 128.623568 -147.888706) (xy 128.603748 -147.909494) (xy 128.558976 -147.945469) (xy 128.509318 -147.974329)
			(xy 128.455896 -147.995422) (xy 128.399917 -148.008271) (xy 128.342644 -148.012586) (xy 128.285371 -148.008271)
			(xy 128.229392 -147.995422) (xy 128.17597 -147.974329) (xy 128.126312 -147.945469) (xy 128.08154 -147.909494)
			(xy 128.06172 -147.888706) (xy 128.054192 -147.881312) (xy 128.034917 -147.872783) (xy 128.024382 -147.872196)
			(xy 127.949706 -147.872196) (xy 127.939155 -147.872716) (xy 127.91986 -147.881258) (xy 127.912368 -147.888706)
			(xy 127.894222 -147.907771) (xy 127.85359 -147.941227) (xy 127.808748 -147.968785) (xy 127.760545 -147.989922)
			(xy 127.709896 -148.004237) (xy 127.657761 -148.011459) (xy 127.631444 -148.011896) (xy 127.604188 -148.01146)
			(xy 127.550231 -148.003708) (xy 127.497926 -147.988355) (xy 127.448339 -147.965715) (xy 127.402478 -147.936247)
			(xy 127.361279 -147.900552) (xy 127.32558 -147.859357) (xy 127.296107 -147.8135) (xy 127.27346 -147.763915)
			(xy 127.258101 -147.711612) (xy 127.250343 -147.657656) (xy 84.450583 -147.657656) (xy 84.476609 -147.677626)
			(xy 84.519014 -147.720031) (xy 84.55552 -147.767607) (xy 84.585504 -147.819541) (xy 84.608453 -147.874945)
			(xy 84.623974 -147.93287) (xy 84.631802 -147.992326) (xy 84.632217 -148.017738) (xy 132.077458 -148.017738)
			(xy 132.081529 -147.962116) (xy 132.093655 -147.907679) (xy 132.113578 -147.855588) (xy 132.140874 -147.806953)
			(xy 132.17496 -147.76281) (xy 132.215109 -147.724101) (xy 132.260467 -147.69165) (xy 132.310067 -147.666149)
			(xy 132.362851 -147.648142) (xy 132.417694 -147.638012) (xy 132.473428 -147.635975) (xy 132.528865 -147.642075)
			(xy 132.582822 -147.656181) (xy 132.634151 -147.677993) (xy 132.681757 -147.707047) (xy 132.72302 -147.741386)
			(xy 137.981434 -147.741386) (xy 137.985505 -147.685764) (xy 137.997631 -147.631327) (xy 138.017554 -147.579236)
			(xy 138.04485 -147.530601) (xy 138.078936 -147.486458) (xy 138.119085 -147.447749) (xy 138.164443 -147.415298)
			(xy 138.214043 -147.389797) (xy 138.266827 -147.37179) (xy 138.32167 -147.36166) (xy 138.377404 -147.359623)
			(xy 138.432841 -147.365723) (xy 138.486798 -147.379829) (xy 138.538127 -147.401641) (xy 138.585733 -147.430695)
			(xy 138.628601 -147.46637) (xy 138.665818 -147.507907) (xy 138.696591 -147.55442) (xy 138.720263 -147.604917)
			(xy 138.736331 -147.658324) (xy 138.744451 -147.7135) (xy 138.74496 -147.741386) (xy 138.744451 -147.769272)
			(xy 138.736331 -147.824448) (xy 138.720263 -147.877855) (xy 138.696591 -147.928352) (xy 138.665818 -147.974865)
			(xy 138.628601 -148.016402) (xy 138.585733 -148.052077) (xy 138.538127 -148.081131) (xy 138.486798 -148.102943)
			(xy 138.432841 -148.117049) (xy 138.377404 -148.123149) (xy 138.32167 -148.121112) (xy 138.266827 -148.110982)
			(xy 138.214043 -148.092975) (xy 138.164443 -148.067474) (xy 138.119085 -148.035023) (xy 138.078936 -147.996314)
			(xy 138.04485 -147.952171) (xy 138.017554 -147.903536) (xy 137.997631 -147.851445) (xy 137.985505 -147.797008)
			(xy 137.981434 -147.741386) (xy 132.72302 -147.741386) (xy 132.724625 -147.742722) (xy 132.761842 -147.784259)
			(xy 132.792615 -147.830772) (xy 132.816287 -147.881269) (xy 132.832355 -147.934676) (xy 132.840475 -147.989852)
			(xy 132.840984 -148.017738) (xy 132.840475 -148.045624) (xy 132.832355 -148.1008) (xy 132.816287 -148.154207)
			(xy 132.792615 -148.204704) (xy 132.761842 -148.251217) (xy 132.724625 -148.292754) (xy 132.681757 -148.328429)
			(xy 132.634151 -148.357483) (xy 132.582822 -148.379295) (xy 132.528865 -148.393401) (xy 132.473428 -148.399501)
			(xy 132.417694 -148.397464) (xy 132.362851 -148.387334) (xy 132.310067 -148.369327) (xy 132.260467 -148.343826)
			(xy 132.215109 -148.311375) (xy 132.17496 -148.272666) (xy 132.140874 -148.228523) (xy 132.113578 -148.179888)
			(xy 132.093655 -148.127797) (xy 132.081529 -148.07336) (xy 132.077458 -148.017738) (xy 84.632217 -148.017738)
			(xy 84.632292 -148.02231) (xy 84.632292 -148.88591) (xy 84.631802 -148.915894) (xy 84.623974 -148.97535)
			(xy 84.608453 -149.033275) (xy 84.585504 -149.088679) (xy 84.55552 -149.140613) (xy 84.519014 -149.188189)
			(xy 84.476609 -149.230594) (xy 84.429033 -149.2671) (xy 84.377099 -149.297084) (xy 84.321695 -149.320033)
			(xy 84.26377 -149.335554) (xy 84.204314 -149.343382) (xy 84.144346 -149.343382) (xy 84.08489 -149.335554)
			(xy 84.026965 -149.320033) (xy 83.971561 -149.297084) (xy 83.919627 -149.2671) (xy 83.872051 -149.230594)
			(xy 83.829646 -149.188189) (xy 83.79314 -149.140613) (xy 83.763156 -149.088679) (xy 83.740207 -149.033275)
			(xy 83.724686 -148.97535) (xy 83.716858 -148.915894) (xy 83.716368 -148.88591) (xy 80.035176 -148.88591)
			(xy 79.88764 -150.67915) (xy 81.07426 -150.67915) (xy 81.07426 -149.81555) (xy 81.07475 -149.785566)
			(xy 81.082578 -149.72611) (xy 81.098099 -149.668185) (xy 81.121048 -149.612781) (xy 81.151032 -149.560847)
			(xy 81.187538 -149.513271) (xy 81.229943 -149.470866) (xy 81.277519 -149.43436) (xy 81.329453 -149.404376)
			(xy 81.384857 -149.381427) (xy 81.442782 -149.365906) (xy 81.502238 -149.358078) (xy 81.562206 -149.358078)
			(xy 81.621662 -149.365906) (xy 81.679587 -149.381427) (xy 81.734991 -149.404376) (xy 81.786925 -149.43436)
			(xy 81.834501 -149.470866) (xy 81.876906 -149.513271) (xy 81.913412 -149.560847) (xy 81.943396 -149.612781)
			(xy 81.966345 -149.668185) (xy 81.981866 -149.72611) (xy 81.989694 -149.785566) (xy 81.990184 -149.81555)
			(xy 81.990184 -150.195854) (xy 127.250365 -150.195854) (xy 127.250365 -150.141346) (xy 127.258123 -150.087392)
			(xy 127.273481 -150.035093) (xy 127.296126 -149.985511) (xy 127.325598 -149.939657) (xy 127.361295 -149.898464)
			(xy 127.402492 -149.862771) (xy 127.448349 -149.833305) (xy 127.497934 -149.810666) (xy 127.550236 -149.795314)
			(xy 127.60419 -149.787562) (xy 127.631444 -149.787102) (xy 127.657759 -149.787539) (xy 127.709889 -149.79478)
			(xy 127.760532 -149.809105) (xy 127.808731 -149.830243) (xy 127.853574 -149.857795) (xy 127.894212 -149.891238)
			(xy 127.912368 -149.910292) (xy 127.919901 -149.91768) (xy 127.939172 -149.926212) (xy 127.949706 -149.926802)
			(xy 128.024382 -149.926802) (xy 128.034932 -149.926276) (xy 128.054227 -149.917738) (xy 128.06172 -149.910292)
			(xy 128.08154 -149.889504) (xy 128.126312 -149.853529) (xy 128.17597 -149.824669) (xy 128.229392 -149.803576)
			(xy 128.285371 -149.790727) (xy 128.342644 -149.786412) (xy 128.399917 -149.790727) (xy 128.455896 -149.803576)
			(xy 128.509318 -149.824669) (xy 128.558976 -149.853529) (xy 128.603748 -149.889504) (xy 128.623568 -149.910292)
			(xy 128.631101 -149.91768) (xy 128.650372 -149.926212) (xy 128.660906 -149.926802) (xy 128.735582 -149.926802)
			(xy 128.746132 -149.926276) (xy 128.765427 -149.917738) (xy 128.77292 -149.910292) (xy 128.791071 -149.891232)
			(xy 128.831702 -149.857776) (xy 128.876543 -149.830218) (xy 128.924745 -149.80908) (xy 128.975393 -149.794764)
			(xy 129.027528 -149.78754) (xy 129.053844 -149.787102) (xy 129.081094 -149.787571) (xy 129.135038 -149.795333)
			(xy 129.187329 -149.810692) (xy 129.236902 -149.833336) (xy 129.282748 -149.862804) (xy 129.323934 -149.898497)
			(xy 129.359622 -149.939687) (xy 129.389085 -149.985537) (xy 129.411723 -150.035112) (xy 129.420045 -150.063454)
			(xy 131.938012 -150.063454) (xy 131.942083 -150.007832) (xy 131.954209 -149.953395) (xy 131.974132 -149.901304)
			(xy 132.001428 -149.852669) (xy 132.035514 -149.808526) (xy 132.075663 -149.769817) (xy 132.121021 -149.737366)
			(xy 132.170621 -149.711865) (xy 132.223405 -149.693858) (xy 132.278248 -149.683728) (xy 132.333982 -149.681691)
			(xy 132.389419 -149.687791) (xy 132.443376 -149.701897) (xy 132.494705 -149.723709) (xy 132.542311 -149.752763)
			(xy 132.585179 -149.788438) (xy 132.622396 -149.829975) (xy 132.653169 -149.876488) (xy 132.676841 -149.926985)
			(xy 132.692909 -149.980392) (xy 132.701029 -150.035568) (xy 132.701538 -150.063454) (xy 132.701029 -150.09134)
			(xy 132.692909 -150.146516) (xy 132.676841 -150.199923) (xy 132.653169 -150.25042) (xy 132.622396 -150.296933)
			(xy 132.585179 -150.33847) (xy 132.542311 -150.374145) (xy 132.494705 -150.403199) (xy 132.443376 -150.425011)
			(xy 132.389419 -150.439117) (xy 132.333982 -150.445217) (xy 132.278248 -150.44318) (xy 132.223405 -150.43305)
			(xy 132.170621 -150.415043) (xy 132.121021 -150.389542) (xy 132.075663 -150.357091) (xy 132.035514 -150.318382)
			(xy 132.001428 -150.274239) (xy 131.974132 -150.225604) (xy 131.954209 -150.173513) (xy 131.942083 -150.119076)
			(xy 131.938012 -150.063454) (xy 129.420045 -150.063454) (xy 129.427077 -150.087405) (xy 129.434832 -150.14135)
			(xy 129.434832 -150.19585) (xy 129.427077 -150.249795) (xy 129.411723 -150.302088) (xy 129.389085 -150.351663)
			(xy 129.359622 -150.397513) (xy 129.323934 -150.438703) (xy 129.282748 -150.474396) (xy 129.236902 -150.503864)
			(xy 129.187329 -150.526508) (xy 129.135038 -150.541867) (xy 129.081094 -150.549629) (xy 129.053844 -150.550118)
			(xy 129.027529 -150.549682) (xy 128.975399 -150.54244) (xy 128.924756 -150.528114) (xy 128.876558 -150.506976)
			(xy 128.831715 -150.479425) (xy 128.791076 -150.445982) (xy 128.77292 -150.426928) (xy 128.765389 -150.419537)
			(xy 128.746116 -150.411006) (xy 128.735582 -150.410418) (xy 128.660906 -150.410418) (xy 128.650354 -150.410932)
			(xy 128.631059 -150.419477) (xy 128.623568 -150.426928) (xy 128.603748 -150.447716) (xy 128.558976 -150.483691)
			(xy 128.509318 -150.512551) (xy 128.455896 -150.533644) (xy 128.399917 -150.546493) (xy 128.342644 -150.550808)
			(xy 128.285371 -150.546493) (xy 128.229392 -150.533644) (xy 128.17597 -150.512551) (xy 128.126312 -150.483691)
			(xy 128.08154 -150.447716) (xy 128.06172 -150.426928) (xy 128.054189 -150.419537) (xy 128.034916 -150.411006)
			(xy 128.024382 -150.410418) (xy 127.949706 -150.410418) (xy 127.939154 -150.410932) (xy 127.919859 -150.419477)
			(xy 127.912368 -150.426928) (xy 127.894226 -150.445997) (xy 127.853593 -150.479452) (xy 127.80875 -150.507009)
			(xy 127.760546 -150.528145) (xy 127.709897 -150.542459) (xy 127.657761 -150.549681) (xy 127.631444 -150.550118)
			(xy 127.60419 -150.549638) (xy 127.550236 -150.541886) (xy 127.497934 -150.526534) (xy 127.448349 -150.503895)
			(xy 127.402492 -150.474429) (xy 127.361295 -150.438736) (xy 127.325598 -150.397543) (xy 127.296126 -150.351689)
			(xy 127.273481 -150.302107) (xy 127.258123 -150.249808) (xy 127.250365 -150.195854) (xy 81.990184 -150.195854)
			(xy 81.990184 -150.67915) (xy 81.989694 -150.709134) (xy 81.981866 -150.76859) (xy 81.966345 -150.826515)
			(xy 81.943396 -150.881919) (xy 81.913412 -150.933853) (xy 81.876906 -150.981429) (xy 81.834501 -151.023834)
			(xy 81.786925 -151.06034) (xy 81.734991 -151.090324) (xy 81.679587 -151.113273) (xy 81.621662 -151.128794)
			(xy 81.562206 -151.136622) (xy 81.502238 -151.136622) (xy 81.442782 -151.128794) (xy 81.384857 -151.113273)
			(xy 81.329453 -151.090324) (xy 81.277519 -151.06034) (xy 81.229943 -151.023834) (xy 81.187538 -150.981429)
			(xy 81.151032 -150.933853) (xy 81.121048 -150.881919) (xy 81.098099 -150.826515) (xy 81.082578 -150.76859)
			(xy 81.07475 -150.709134) (xy 81.07426 -150.67915) (xy 79.88764 -150.67915) (xy 79.738997 -152.485852)
			(xy 83.716368 -152.485852) (xy 83.716368 -151.622252) (xy 83.716858 -151.592268) (xy 83.724686 -151.532812)
			(xy 83.740207 -151.474887) (xy 83.763156 -151.419483) (xy 83.79314 -151.367549) (xy 83.829646 -151.319973)
			(xy 83.872051 -151.277568) (xy 83.919627 -151.241062) (xy 83.971561 -151.211078) (xy 84.026965 -151.188129)
			(xy 84.08489 -151.172608) (xy 84.144346 -151.16478) (xy 84.204314 -151.16478) (xy 84.26377 -151.172608)
			(xy 84.321695 -151.188129) (xy 84.377099 -151.211078) (xy 84.429033 -151.241062) (xy 84.476609 -151.277568)
			(xy 84.519014 -151.319973) (xy 84.55552 -151.367549) (xy 84.585504 -151.419483) (xy 84.608453 -151.474887)
			(xy 84.623974 -151.532812) (xy 84.631802 -151.592268) (xy 84.632292 -151.622252) (xy 84.632292 -151.67102)
			(xy 131.893562 -151.67102) (xy 131.897633 -151.615398) (xy 131.909759 -151.560961) (xy 131.929682 -151.50887)
			(xy 131.956978 -151.460235) (xy 131.991064 -151.416092) (xy 132.031213 -151.377383) (xy 132.076571 -151.344932)
			(xy 132.126171 -151.319431) (xy 132.178955 -151.301424) (xy 132.233798 -151.291294) (xy 132.289532 -151.289257)
			(xy 132.344969 -151.295357) (xy 132.398926 -151.309463) (xy 132.450255 -151.331275) (xy 132.497861 -151.360329)
			(xy 132.540729 -151.396004) (xy 132.577946 -151.437541) (xy 132.608719 -151.484054) (xy 132.632391 -151.534551)
			(xy 132.648459 -151.587958) (xy 132.656579 -151.643134) (xy 132.657088 -151.67102) (xy 132.656615 -151.696928)
			(xy 132.909562 -151.696928) (xy 132.913633 -151.641306) (xy 132.925759 -151.586869) (xy 132.945682 -151.534778)
			(xy 132.972978 -151.486143) (xy 133.007064 -151.442) (xy 133.047213 -151.403291) (xy 133.092571 -151.37084)
			(xy 133.142171 -151.345339) (xy 133.194955 -151.327332) (xy 133.249798 -151.317202) (xy 133.305532 -151.315165)
			(xy 133.360969 -151.321265) (xy 133.414926 -151.335371) (xy 133.466255 -151.357183) (xy 133.513861 -151.386237)
			(xy 133.538337 -151.406606) (xy 134.136636 -151.406606) (xy 134.140707 -151.350984) (xy 134.152833 -151.296547)
			(xy 134.172756 -151.244456) (xy 134.200052 -151.195821) (xy 134.234138 -151.151678) (xy 134.274287 -151.112969)
			(xy 134.319645 -151.080518) (xy 134.369245 -151.055017) (xy 134.422029 -151.03701) (xy 134.476872 -151.02688)
			(xy 134.532606 -151.024843) (xy 134.588043 -151.030943) (xy 134.642 -151.045049) (xy 134.693329 -151.066861)
			(xy 134.740935 -151.095915) (xy 134.783803 -151.13159) (xy 134.82102 -151.173127) (xy 134.851793 -151.21964)
			(xy 134.875465 -151.270137) (xy 134.891533 -151.323544) (xy 134.899653 -151.37872) (xy 134.900162 -151.406606)
			(xy 134.899653 -151.434492) (xy 134.891533 -151.489668) (xy 134.875465 -151.543075) (xy 134.856923 -151.582628)
			(xy 135.462262 -151.582628) (xy 135.466333 -151.527006) (xy 135.478459 -151.472569) (xy 135.498382 -151.420478)
			(xy 135.525678 -151.371843) (xy 135.559764 -151.3277) (xy 135.599913 -151.288991) (xy 135.645271 -151.25654)
			(xy 135.694871 -151.231039) (xy 135.747655 -151.213032) (xy 135.802498 -151.202902) (xy 135.858232 -151.200865)
			(xy 135.913669 -151.206965) (xy 135.967626 -151.221071) (xy 136.018955 -151.242883) (xy 136.066561 -151.271937)
			(xy 136.109429 -151.307612) (xy 136.146646 -151.349149) (xy 136.177419 -151.395662) (xy 136.201091 -151.446159)
			(xy 136.217159 -151.499566) (xy 136.225279 -151.554742) (xy 136.225542 -151.569166) (xy 136.973562 -151.569166)
			(xy 136.977633 -151.513544) (xy 136.989759 -151.459107) (xy 137.009682 -151.407016) (xy 137.036978 -151.358381)
			(xy 137.071064 -151.314238) (xy 137.111213 -151.275529) (xy 137.156571 -151.243078) (xy 137.206171 -151.217577)
			(xy 137.258955 -151.19957) (xy 137.313798 -151.18944) (xy 137.369532 -151.187403) (xy 137.424969 -151.193503)
			(xy 137.478926 -151.207609) (xy 137.530255 -151.229421) (xy 137.577861 -151.258475) (xy 137.620729 -151.29415)
			(xy 137.657946 -151.335687) (xy 137.688719 -151.3822) (xy 137.712391 -151.432697) (xy 137.728459 -151.486104)
			(xy 137.736579 -151.54128) (xy 137.737088 -151.569166) (xy 137.736579 -151.597052) (xy 137.728459 -151.652228)
			(xy 137.712391 -151.705635) (xy 137.688719 -151.756132) (xy 137.657946 -151.802645) (xy 137.620729 -151.844182)
			(xy 137.577861 -151.879857) (xy 137.530255 -151.908911) (xy 137.478926 -151.930723) (xy 137.424969 -151.944829)
			(xy 137.369532 -151.950929) (xy 137.313798 -151.948892) (xy 137.258955 -151.938762) (xy 137.206171 -151.920755)
			(xy 137.156571 -151.895254) (xy 137.111213 -151.862803) (xy 137.071064 -151.824094) (xy 137.036978 -151.779951)
			(xy 137.009682 -151.731316) (xy 136.989759 -151.679225) (xy 136.977633 -151.624788) (xy 136.973562 -151.569166)
			(xy 136.225542 -151.569166) (xy 136.225788 -151.582628) (xy 136.225279 -151.610514) (xy 136.217159 -151.66569)
			(xy 136.201091 -151.719097) (xy 136.177419 -151.769594) (xy 136.146646 -151.816107) (xy 136.109429 -151.857644)
			(xy 136.066561 -151.893319) (xy 136.018955 -151.922373) (xy 135.967626 -151.944185) (xy 135.913669 -151.958291)
			(xy 135.858232 -151.964391) (xy 135.802498 -151.962354) (xy 135.747655 -151.952224) (xy 135.694871 -151.934217)
			(xy 135.645271 -151.908716) (xy 135.599913 -151.876265) (xy 135.559764 -151.837556) (xy 135.525678 -151.793413)
			(xy 135.498382 -151.744778) (xy 135.478459 -151.692687) (xy 135.466333 -151.63825) (xy 135.462262 -151.582628)
			(xy 134.856923 -151.582628) (xy 134.851793 -151.593572) (xy 134.82102 -151.640085) (xy 134.783803 -151.681622)
			(xy 134.740935 -151.717297) (xy 134.693329 -151.746351) (xy 134.642 -151.768163) (xy 134.588043 -151.782269)
			(xy 134.532606 -151.788369) (xy 134.476872 -151.786332) (xy 134.422029 -151.776202) (xy 134.369245 -151.758195)
			(xy 134.319645 -151.732694) (xy 134.274287 -151.700243) (xy 134.234138 -151.661534) (xy 134.200052 -151.617391)
			(xy 134.172756 -151.568756) (xy 134.152833 -151.516665) (xy 134.140707 -151.462228) (xy 134.136636 -151.406606)
			(xy 133.538337 -151.406606) (xy 133.556729 -151.421912) (xy 133.593946 -151.463449) (xy 133.624719 -151.509962)
			(xy 133.648391 -151.560459) (xy 133.664459 -151.613866) (xy 133.672579 -151.669042) (xy 133.673088 -151.696928)
			(xy 133.672579 -151.724814) (xy 133.664459 -151.77999) (xy 133.648391 -151.833397) (xy 133.624719 -151.883894)
			(xy 133.593946 -151.930407) (xy 133.556729 -151.971944) (xy 133.513861 -152.007619) (xy 133.466255 -152.036673)
			(xy 133.414926 -152.058485) (xy 133.360969 -152.072591) (xy 133.305532 -152.078691) (xy 133.249798 -152.076654)
			(xy 133.194955 -152.066524) (xy 133.142171 -152.048517) (xy 133.092571 -152.023016) (xy 133.047213 -151.990565)
			(xy 133.007064 -151.951856) (xy 132.972978 -151.907713) (xy 132.945682 -151.859078) (xy 132.925759 -151.806987)
			(xy 132.913633 -151.75255) (xy 132.909562 -151.696928) (xy 132.656615 -151.696928) (xy 132.656579 -151.698906)
			(xy 132.648459 -151.754082) (xy 132.632391 -151.807489) (xy 132.608719 -151.857986) (xy 132.577946 -151.904499)
			(xy 132.540729 -151.946036) (xy 132.497861 -151.981711) (xy 132.450255 -152.010765) (xy 132.398926 -152.032577)
			(xy 132.344969 -152.046683) (xy 132.289532 -152.052783) (xy 132.233798 -152.050746) (xy 132.178955 -152.040616)
			(xy 132.126171 -152.022609) (xy 132.076571 -151.997108) (xy 132.031213 -151.964657) (xy 131.991064 -151.925948)
			(xy 131.956978 -151.881805) (xy 131.929682 -151.83317) (xy 131.909759 -151.781079) (xy 131.897633 -151.726642)
			(xy 131.893562 -151.67102) (xy 84.632292 -151.67102) (xy 84.632292 -152.485852) (xy 84.631802 -152.515836)
			(xy 84.623974 -152.575292) (xy 84.608453 -152.633217) (xy 84.585504 -152.688621) (xy 84.55552 -152.740555)
			(xy 84.519014 -152.788131) (xy 84.476609 -152.830536) (xy 84.429033 -152.867042) (xy 84.377099 -152.897026)
			(xy 84.321695 -152.919975) (xy 84.26377 -152.935496) (xy 84.204314 -152.943324) (xy 84.144346 -152.943324)
			(xy 84.08489 -152.935496) (xy 84.026965 -152.919975) (xy 83.971561 -152.897026) (xy 83.919627 -152.867042)
			(xy 83.872051 -152.830536) (xy 83.829646 -152.788131) (xy 83.79314 -152.740555) (xy 83.763156 -152.688621)
			(xy 83.740207 -152.633217) (xy 83.724686 -152.575292) (xy 83.716858 -152.515836) (xy 83.716368 -152.485852)
			(xy 79.738997 -152.485852) (xy 79.618586 -153.9494) (xy 79.613252 -153.99893) (xy 79.576073 -154.279346)
			(xy 81.07426 -154.279346) (xy 81.07426 -153.415746) (xy 81.07475 -153.385762) (xy 81.082578 -153.326306)
			(xy 81.098099 -153.268381) (xy 81.121048 -153.212977) (xy 81.151032 -153.161043) (xy 81.187538 -153.113467)
			(xy 81.229943 -153.071062) (xy 81.277519 -153.034556) (xy 81.329453 -153.004572) (xy 81.384857 -152.981623)
			(xy 81.442782 -152.966102) (xy 81.502238 -152.958274) (xy 81.562206 -152.958274) (xy 81.621662 -152.966102)
			(xy 81.679587 -152.981623) (xy 81.734991 -153.004572) (xy 81.786925 -153.034556) (xy 81.834501 -153.071062)
			(xy 81.876906 -153.113467) (xy 81.913412 -153.161043) (xy 81.943396 -153.212977) (xy 81.966345 -153.268381)
			(xy 81.981866 -153.326306) (xy 81.989694 -153.385762) (xy 81.990184 -153.415746) (xy 81.990184 -153.782522)
			(xy 130.877562 -153.782522) (xy 130.881633 -153.7269) (xy 130.893759 -153.672463) (xy 130.913682 -153.620372)
			(xy 130.940978 -153.571737) (xy 130.975064 -153.527594) (xy 131.015213 -153.488885) (xy 131.060571 -153.456434)
			(xy 131.110171 -153.430933) (xy 131.162955 -153.412926) (xy 131.217798 -153.402796) (xy 131.273532 -153.400759)
			(xy 131.328969 -153.406859) (xy 131.382926 -153.420965) (xy 131.434255 -153.442777) (xy 131.481861 -153.471831)
			(xy 131.524729 -153.507506) (xy 131.561946 -153.549043) (xy 131.592719 -153.595556) (xy 131.616391 -153.646053)
			(xy 131.632459 -153.69946) (xy 131.640579 -153.754636) (xy 131.641088 -153.782522) (xy 131.893562 -153.782522)
			(xy 131.897633 -153.7269) (xy 131.909759 -153.672463) (xy 131.929682 -153.620372) (xy 131.956978 -153.571737)
			(xy 131.991064 -153.527594) (xy 132.031213 -153.488885) (xy 132.076571 -153.456434) (xy 132.126171 -153.430933)
			(xy 132.178955 -153.412926) (xy 132.233798 -153.402796) (xy 132.289532 -153.400759) (xy 132.344969 -153.406859)
			(xy 132.398926 -153.420965) (xy 132.450255 -153.442777) (xy 132.497861 -153.471831) (xy 132.540729 -153.507506)
			(xy 132.577946 -153.549043) (xy 132.608719 -153.595556) (xy 132.632391 -153.646053) (xy 132.648459 -153.69946)
			(xy 132.656579 -153.754636) (xy 132.657088 -153.782522) (xy 132.656579 -153.810408) (xy 132.653431 -153.831798)
			(xy 132.909562 -153.831798) (xy 132.913633 -153.776176) (xy 132.925759 -153.721739) (xy 132.945682 -153.669648)
			(xy 132.972978 -153.621013) (xy 133.007064 -153.57687) (xy 133.047213 -153.538161) (xy 133.092571 -153.50571)
			(xy 133.142171 -153.480209) (xy 133.194955 -153.462202) (xy 133.249798 -153.452072) (xy 133.305532 -153.450035)
			(xy 133.360969 -153.456135) (xy 133.414926 -153.470241) (xy 133.466255 -153.492053) (xy 133.513861 -153.521107)
			(xy 133.556729 -153.556782) (xy 133.593946 -153.598319) (xy 133.624719 -153.644832) (xy 133.648391 -153.695329)
			(xy 133.664459 -153.748736) (xy 133.669431 -153.782522) (xy 135.957562 -153.782522) (xy 135.961633 -153.7269)
			(xy 135.973759 -153.672463) (xy 135.993682 -153.620372) (xy 136.020978 -153.571737) (xy 136.055064 -153.527594)
			(xy 136.095213 -153.488885) (xy 136.140571 -153.456434) (xy 136.190171 -153.430933) (xy 136.242955 -153.412926)
			(xy 136.297798 -153.402796) (xy 136.353532 -153.400759) (xy 136.408969 -153.406859) (xy 136.462926 -153.420965)
			(xy 136.514255 -153.442777) (xy 136.561861 -153.471831) (xy 136.604729 -153.507506) (xy 136.641946 -153.549043)
			(xy 136.672719 -153.595556) (xy 136.696391 -153.646053) (xy 136.712459 -153.69946) (xy 136.720579 -153.754636)
			(xy 136.721088 -153.782522) (xy 137.989562 -153.782522) (xy 137.993633 -153.7269) (xy 138.005759 -153.672463)
			(xy 138.025682 -153.620372) (xy 138.052978 -153.571737) (xy 138.087064 -153.527594) (xy 138.127213 -153.488885)
			(xy 138.172571 -153.456434) (xy 138.222171 -153.430933) (xy 138.274955 -153.412926) (xy 138.329798 -153.402796)
			(xy 138.385532 -153.400759) (xy 138.440969 -153.406859) (xy 138.494926 -153.420965) (xy 138.546255 -153.442777)
			(xy 138.593861 -153.471831) (xy 138.636729 -153.507506) (xy 138.673946 -153.549043) (xy 138.704719 -153.595556)
			(xy 138.728391 -153.646053) (xy 138.744459 -153.69946) (xy 138.752579 -153.754636) (xy 138.753088 -153.782522)
			(xy 138.752579 -153.810408) (xy 138.744459 -153.865584) (xy 138.728391 -153.918991) (xy 138.704719 -153.969488)
			(xy 138.673946 -154.016001) (xy 138.636729 -154.057538) (xy 138.593861 -154.093213) (xy 138.546255 -154.122267)
			(xy 138.494926 -154.144079) (xy 138.440969 -154.158185) (xy 138.385532 -154.164285) (xy 138.329798 -154.162248)
			(xy 138.274955 -154.152118) (xy 138.222171 -154.134111) (xy 138.172571 -154.10861) (xy 138.127213 -154.076159)
			(xy 138.087064 -154.03745) (xy 138.052978 -153.993307) (xy 138.025682 -153.944672) (xy 138.005759 -153.892581)
			(xy 137.993633 -153.838144) (xy 137.989562 -153.782522) (xy 136.721088 -153.782522) (xy 136.720579 -153.810408)
			(xy 136.712459 -153.865584) (xy 136.696391 -153.918991) (xy 136.672719 -153.969488) (xy 136.641946 -154.016001)
			(xy 136.604729 -154.057538) (xy 136.561861 -154.093213) (xy 136.514255 -154.122267) (xy 136.462926 -154.144079)
			(xy 136.408969 -154.158185) (xy 136.353532 -154.164285) (xy 136.297798 -154.162248) (xy 136.242955 -154.152118)
			(xy 136.190171 -154.134111) (xy 136.140571 -154.10861) (xy 136.095213 -154.076159) (xy 136.055064 -154.03745)
			(xy 136.020978 -153.993307) (xy 135.993682 -153.944672) (xy 135.973759 -153.892581) (xy 135.961633 -153.838144)
			(xy 135.957562 -153.782522) (xy 133.669431 -153.782522) (xy 133.672579 -153.803912) (xy 133.673088 -153.831798)
			(xy 133.672579 -153.859684) (xy 133.664459 -153.91486) (xy 133.648391 -153.968267) (xy 133.624719 -154.018764)
			(xy 133.593946 -154.065277) (xy 133.556729 -154.106814) (xy 133.513861 -154.142489) (xy 133.466255 -154.171543)
			(xy 133.414926 -154.193355) (xy 133.360969 -154.207461) (xy 133.305532 -154.213561) (xy 133.249798 -154.211524)
			(xy 133.194955 -154.201394) (xy 133.142171 -154.183387) (xy 133.092571 -154.157886) (xy 133.047213 -154.125435)
			(xy 133.007064 -154.086726) (xy 132.972978 -154.042583) (xy 132.945682 -153.993948) (xy 132.925759 -153.941857)
			(xy 132.913633 -153.88742) (xy 132.909562 -153.831798) (xy 132.653431 -153.831798) (xy 132.648459 -153.865584)
			(xy 132.632391 -153.918991) (xy 132.608719 -153.969488) (xy 132.577946 -154.016001) (xy 132.540729 -154.057538)
			(xy 132.497861 -154.093213) (xy 132.450255 -154.122267) (xy 132.398926 -154.144079) (xy 132.344969 -154.158185)
			(xy 132.289532 -154.164285) (xy 132.233798 -154.162248) (xy 132.178955 -154.152118) (xy 132.126171 -154.134111)
			(xy 132.076571 -154.10861) (xy 132.031213 -154.076159) (xy 131.991064 -154.03745) (xy 131.956978 -153.993307)
			(xy 131.929682 -153.944672) (xy 131.909759 -153.892581) (xy 131.897633 -153.838144) (xy 131.893562 -153.782522)
			(xy 131.641088 -153.782522) (xy 131.640579 -153.810408) (xy 131.632459 -153.865584) (xy 131.616391 -153.918991)
			(xy 131.592719 -153.969488) (xy 131.561946 -154.016001) (xy 131.524729 -154.057538) (xy 131.481861 -154.093213)
			(xy 131.434255 -154.122267) (xy 131.382926 -154.144079) (xy 131.328969 -154.158185) (xy 131.273532 -154.164285)
			(xy 131.217798 -154.162248) (xy 131.162955 -154.152118) (xy 131.110171 -154.134111) (xy 131.060571 -154.10861)
			(xy 131.015213 -154.076159) (xy 130.975064 -154.03745) (xy 130.940978 -153.993307) (xy 130.913682 -153.944672)
			(xy 130.893759 -153.892581) (xy 130.881633 -153.838144) (xy 130.877562 -153.782522) (xy 81.990184 -153.782522)
			(xy 81.990184 -154.279346) (xy 81.989694 -154.30933) (xy 81.981866 -154.368786) (xy 81.966345 -154.426711)
			(xy 81.943396 -154.482115) (xy 81.913412 -154.534049) (xy 81.876906 -154.581625) (xy 81.834501 -154.62403)
			(xy 81.786925 -154.660536) (xy 81.734991 -154.69052) (xy 81.679587 -154.713469) (xy 81.621662 -154.72899)
			(xy 81.562206 -154.736818) (xy 81.502238 -154.736818) (xy 81.442782 -154.72899) (xy 81.384857 -154.713469)
			(xy 81.329453 -154.69052) (xy 81.277519 -154.660536) (xy 81.229943 -154.62403) (xy 81.187538 -154.581625)
			(xy 81.151032 -154.534049) (xy 81.121048 -154.482115) (xy 81.098099 -154.426711) (xy 81.082578 -154.368786)
			(xy 81.07475 -154.30933) (xy 81.07426 -154.279346) (xy 79.576073 -154.279346) (xy 79.541116 -154.542998)
			(xy 79.492348 -154.91206) (xy 79.492094 -154.9146) (xy 79.394129 -156.085794) (xy 83.716368 -156.085794)
			(xy 83.716368 -155.222194) (xy 83.716858 -155.19221) (xy 83.724686 -155.132754) (xy 83.740207 -155.074829)
			(xy 83.763156 -155.019425) (xy 83.79314 -154.967491) (xy 83.829646 -154.919915) (xy 83.872051 -154.87751)
			(xy 83.919627 -154.841004) (xy 83.971561 -154.81102) (xy 84.026965 -154.788071) (xy 84.08489 -154.77255)
			(xy 84.144346 -154.764722) (xy 84.204314 -154.764722) (xy 84.26377 -154.77255) (xy 84.321695 -154.788071)
			(xy 84.377099 -154.81102) (xy 84.429033 -154.841004) (xy 84.476609 -154.87751) (xy 84.519014 -154.919915)
			(xy 84.55552 -154.967491) (xy 84.585504 -155.019425) (xy 84.608453 -155.074829) (xy 84.623974 -155.132754)
			(xy 84.631802 -155.19221) (xy 84.632126 -155.212034) (xy 123.369068 -155.212034) (xy 123.373139 -155.156412)
			(xy 123.385265 -155.101975) (xy 123.405188 -155.049884) (xy 123.432484 -155.001249) (xy 123.46657 -154.957106)
			(xy 123.506719 -154.918397) (xy 123.552077 -154.885946) (xy 123.601677 -154.860445) (xy 123.654461 -154.842438)
			(xy 123.709304 -154.832308) (xy 123.765038 -154.830271) (xy 123.820475 -154.836371) (xy 123.874432 -154.850477)
			(xy 123.925761 -154.872289) (xy 123.973367 -154.901343) (xy 124.016235 -154.937018) (xy 124.053452 -154.978555)
			(xy 124.084225 -155.025068) (xy 124.107897 -155.075565) (xy 124.108988 -155.079192) (xy 125.969774 -155.079192)
			(xy 125.973845 -155.02357) (xy 125.985971 -154.969133) (xy 126.005894 -154.917042) (xy 126.03319 -154.868407)
			(xy 126.067276 -154.824264) (xy 126.107425 -154.785555) (xy 126.152783 -154.753104) (xy 126.202383 -154.727603)
			(xy 126.255167 -154.709596) (xy 126.31001 -154.699466) (xy 126.365744 -154.697429) (xy 126.421181 -154.703529)
			(xy 126.475138 -154.717635) (xy 126.526467 -154.739447) (xy 126.574073 -154.768501) (xy 126.616941 -154.804176)
			(xy 126.654158 -154.845713) (xy 126.684931 -154.892226) (xy 126.708603 -154.942723) (xy 126.724671 -154.99613)
			(xy 126.732791 -155.051306) (xy 126.7333 -155.079192) (xy 126.733235 -155.082748) (xy 127.293624 -155.082748)
			(xy 127.294049 -155.056433) (xy 127.301292 -155.004302) (xy 127.315618 -154.953658) (xy 127.336759 -154.905459)
			(xy 127.364313 -154.860617) (xy 127.397759 -154.819979) (xy 127.416814 -154.801824) (xy 127.424209 -154.794297)
			(xy 127.432737 -154.775021) (xy 127.433324 -154.764486) (xy 127.433324 -154.68981) (xy 127.432796 -154.67926)
			(xy 127.424259 -154.659965) (xy 127.416814 -154.652472) (xy 127.397755 -154.63432) (xy 127.364297 -154.59369)
			(xy 127.336738 -154.548849) (xy 127.3156 -154.500648) (xy 127.301284 -154.449999) (xy 127.294061 -154.397864)
			(xy 127.293624 -154.371548) (xy 127.2941 -154.344295) (xy 127.301851 -154.290343) (xy 127.317203 -154.238043)
			(xy 127.339842 -154.188461) (xy 127.369308 -154.142606) (xy 127.405001 -154.101412) (xy 127.446193 -154.065718)
			(xy 127.492047 -154.03625) (xy 127.541628 -154.013608) (xy 127.593927 -153.998255) (xy 127.647879 -153.990501)
			(xy 127.675132 -153.99004) (xy 127.701447 -153.990473) (xy 127.753578 -153.997713) (xy 127.804222 -154.012038)
			(xy 127.852421 -154.033177) (xy 127.897263 -154.06073) (xy 127.937901 -154.094175) (xy 127.956056 -154.11323)
			(xy 127.963601 -154.120604) (xy 127.982863 -154.129147) (xy 127.993394 -154.12974) (xy 128.06807 -154.12974)
			(xy 128.078618 -154.129197) (xy 128.097913 -154.12067) (xy 128.105408 -154.11323) (xy 128.125228 -154.092442)
			(xy 128.17 -154.056467) (xy 128.219658 -154.027607) (xy 128.27308 -154.006514) (xy 128.329059 -153.993665)
			(xy 128.386332 -153.98935) (xy 128.443605 -153.993665) (xy 128.499584 -154.006514) (xy 128.553006 -154.027607)
			(xy 128.602664 -154.056467) (xy 128.647436 -154.092442) (xy 128.667256 -154.11323) (xy 128.674801 -154.120604)
			(xy 128.694063 -154.129147) (xy 128.704594 -154.12974) (xy 128.77927 -154.12974) (xy 128.789818 -154.129197)
			(xy 128.809113 -154.12067) (xy 128.816608 -154.11323) (xy 128.836428 -154.092442) (xy 128.8812 -154.056467)
			(xy 128.930858 -154.027607) (xy 128.98428 -154.006514) (xy 129.040259 -153.993665) (xy 129.097532 -153.98935)
			(xy 129.154805 -153.993665) (xy 129.210784 -154.006514) (xy 129.264206 -154.027607) (xy 129.313864 -154.056467)
			(xy 129.358636 -154.092442) (xy 129.378456 -154.11323) (xy 129.386001 -154.120604) (xy 129.405263 -154.129147)
			(xy 129.415794 -154.12974) (xy 129.49047 -154.12974) (xy 129.501018 -154.129197) (xy 129.520313 -154.12067)
			(xy 129.527808 -154.11323) (xy 129.545973 -154.094183) (xy 129.5866 -154.060724) (xy 129.631438 -154.033163)
			(xy 129.679637 -154.012023) (xy 129.730283 -153.997704) (xy 129.782416 -153.990479) (xy 129.808732 -153.99004)
			(xy 129.835988 -153.990425) (xy 129.889944 -153.998188) (xy 129.942246 -154.01355) (xy 129.99183 -154.0362)
			(xy 130.037685 -154.065676) (xy 130.078879 -154.101378) (xy 130.114572 -154.142579) (xy 130.144038 -154.18844)
			(xy 130.166678 -154.238029) (xy 130.182029 -154.290334) (xy 130.18978 -154.344292) (xy 130.19024 -154.371548)
			(xy 130.189824 -154.397864) (xy 130.182581 -154.449995) (xy 130.168253 -154.50064) (xy 130.147111 -154.548839)
			(xy 130.119555 -154.593681) (xy 130.086107 -154.634318) (xy 130.06705 -154.652472) (xy 130.059666 -154.660009)
			(xy 130.05113 -154.679277) (xy 130.05054 -154.68981) (xy 130.05054 -154.764486) (xy 130.051051 -154.775038)
			(xy 130.059598 -154.794334) (xy 130.06705 -154.801824) (xy 130.08612 -154.819965) (xy 130.119574 -154.860599)
			(xy 130.14713 -154.905443) (xy 130.168265 -154.953646) (xy 130.18258 -155.004296) (xy 130.189802 -155.056431)
			(xy 130.19024 -155.082748) (xy 130.189767 -155.109999) (xy 130.182005 -155.163945) (xy 130.166645 -155.216238)
			(xy 130.144001 -155.265814) (xy 130.114532 -155.311662) (xy 130.07884 -155.352851) (xy 130.03765 -155.388542)
			(xy 129.9918 -155.418008) (xy 129.942223 -155.440651) (xy 129.88993 -155.456008) (xy 129.835983 -155.463768)
			(xy 129.808732 -155.464256) (xy 129.782416 -155.463848) (xy 129.730284 -155.456603) (xy 129.67964 -155.442273)
			(xy 129.631441 -155.42113) (xy 129.586599 -155.393572) (xy 129.545962 -155.360123) (xy 129.527808 -155.341066)
			(xy 129.520277 -155.333676) (xy 129.501004 -155.325143) (xy 129.49047 -155.324556) (xy 129.415794 -155.324556)
			(xy 129.405244 -155.325082) (xy 129.38595 -155.333621) (xy 129.378456 -155.341066) (xy 129.358636 -155.361854)
			(xy 129.313864 -155.397829) (xy 129.264206 -155.426689) (xy 129.210784 -155.447782) (xy 129.154805 -155.460631)
			(xy 129.097532 -155.464946) (xy 129.040259 -155.460631) (xy 128.98428 -155.447782) (xy 128.930858 -155.426689)
			(xy 128.8812 -155.397829) (xy 128.836428 -155.361854) (xy 128.816608 -155.341066) (xy 128.809077 -155.333676)
			(xy 128.789804 -155.325143) (xy 128.77927 -155.324556) (xy 128.704594 -155.324556) (xy 128.694044 -155.325082)
			(xy 128.67475 -155.333621) (xy 128.667256 -155.341066) (xy 128.647436 -155.361854) (xy 128.602664 -155.397829)
			(xy 128.553006 -155.426689) (xy 128.499584 -155.447782) (xy 128.443605 -155.460631) (xy 128.386332 -155.464946)
			(xy 128.329059 -155.460631) (xy 128.27308 -155.447782) (xy 128.219658 -155.426689) (xy 128.17 -155.397829)
			(xy 128.125228 -155.361854) (xy 128.105408 -155.341066) (xy 128.097877 -155.333676) (xy 128.078604 -155.325143)
			(xy 128.06807 -155.324556) (xy 127.993394 -155.324556) (xy 127.982844 -155.325082) (xy 127.96355 -155.333621)
			(xy 127.956056 -155.341066) (xy 127.937928 -155.360148) (xy 127.897291 -155.393601) (xy 127.852444 -155.421154)
			(xy 127.804238 -155.442288) (xy 127.753587 -155.4566) (xy 127.701449 -155.46382) (xy 127.675132 -155.464256)
			(xy 127.647884 -155.463692) (xy 127.593941 -155.455941) (xy 127.541651 -155.440593) (xy 127.492077 -155.417959)
			(xy 127.446229 -155.3885) (xy 127.40504 -155.352817) (xy 127.369348 -155.311635) (xy 127.33988 -155.265793)
			(xy 127.317235 -155.216224) (xy 127.301876 -155.163937) (xy 127.294114 -155.109996) (xy 127.293624 -155.082748)
			(xy 126.733235 -155.082748) (xy 126.732791 -155.107078) (xy 126.724671 -155.162254) (xy 126.708603 -155.215661)
			(xy 126.684931 -155.266158) (xy 126.654158 -155.312671) (xy 126.616941 -155.354208) (xy 126.574073 -155.389883)
			(xy 126.526467 -155.418937) (xy 126.475138 -155.440749) (xy 126.421181 -155.454855) (xy 126.365744 -155.460955)
			(xy 126.31001 -155.458918) (xy 126.255167 -155.448788) (xy 126.202383 -155.430781) (xy 126.152783 -155.40528)
			(xy 126.107425 -155.372829) (xy 126.067276 -155.33412) (xy 126.03319 -155.289977) (xy 126.005894 -155.241342)
			(xy 125.985971 -155.189251) (xy 125.973845 -155.134814) (xy 125.969774 -155.079192) (xy 124.108988 -155.079192)
			(xy 124.123965 -155.128972) (xy 124.132085 -155.184148) (xy 124.132594 -155.212034) (xy 124.132085 -155.23992)
			(xy 124.123965 -155.295096) (xy 124.107897 -155.348503) (xy 124.084225 -155.399) (xy 124.053452 -155.445513)
			(xy 124.016235 -155.48705) (xy 123.973367 -155.522725) (xy 123.925761 -155.551779) (xy 123.874432 -155.573591)
			(xy 123.820475 -155.587697) (xy 123.765038 -155.593797) (xy 123.709304 -155.59176) (xy 123.654461 -155.58163)
			(xy 123.601677 -155.563623) (xy 123.552077 -155.538122) (xy 123.506719 -155.505671) (xy 123.46657 -155.466962)
			(xy 123.432484 -155.422819) (xy 123.405188 -155.374184) (xy 123.385265 -155.322093) (xy 123.373139 -155.267656)
			(xy 123.369068 -155.212034) (xy 84.632126 -155.212034) (xy 84.632292 -155.222194) (xy 84.632292 -156.085794)
			(xy 84.631802 -156.115778) (xy 84.623974 -156.175234) (xy 84.608453 -156.233159) (xy 84.585504 -156.288563)
			(xy 84.55552 -156.340497) (xy 84.519014 -156.388073) (xy 84.476609 -156.430478) (xy 84.429033 -156.466984)
			(xy 84.377099 -156.496968) (xy 84.321695 -156.519917) (xy 84.26377 -156.535438) (xy 84.204314 -156.543266)
			(xy 84.144346 -156.543266) (xy 84.08489 -156.535438) (xy 84.026965 -156.519917) (xy 83.971561 -156.496968)
			(xy 83.919627 -156.466984) (xy 83.872051 -156.430478) (xy 83.829646 -156.388073) (xy 83.79314 -156.340497)
			(xy 83.763156 -156.288563) (xy 83.740207 -156.233159) (xy 83.724686 -156.175234) (xy 83.716858 -156.115778)
			(xy 83.716368 -156.085794) (xy 79.394129 -156.085794) (xy 79.343266 -156.69387) (xy 124.987302 -156.69387)
			(xy 124.991373 -156.638248) (xy 125.003499 -156.583811) (xy 125.023422 -156.53172) (xy 125.050718 -156.483085)
			(xy 125.084804 -156.438942) (xy 125.124953 -156.400233) (xy 125.170311 -156.367782) (xy 125.219911 -156.342281)
			(xy 125.272695 -156.324274) (xy 125.327538 -156.314144) (xy 125.383272 -156.312107) (xy 125.438709 -156.318207)
			(xy 125.492666 -156.332313) (xy 125.543995 -156.354125) (xy 125.591601 -156.383179) (xy 125.634469 -156.418854)
			(xy 125.671686 -156.460391) (xy 125.702459 -156.506904) (xy 125.726131 -156.557401) (xy 125.742199 -156.610808)
			(xy 125.750319 -156.665984) (xy 125.750828 -156.69387) (xy 125.750319 -156.721756) (xy 125.742199 -156.776932)
			(xy 125.726131 -156.830339) (xy 125.702459 -156.880836) (xy 125.671686 -156.927349) (xy 125.634469 -156.968886)
			(xy 125.591601 -157.004561) (xy 125.543995 -157.033615) (xy 125.492666 -157.055427) (xy 125.438709 -157.069533)
			(xy 125.383272 -157.075633) (xy 125.327538 -157.073596) (xy 125.272695 -157.063466) (xy 125.219911 -157.045459)
			(xy 125.170311 -157.019958) (xy 125.124953 -156.987507) (xy 125.084804 -156.948798) (xy 125.050718 -156.904655)
			(xy 125.023422 -156.85602) (xy 125.003499 -156.803929) (xy 124.991373 -156.749492) (xy 124.987302 -156.69387)
			(xy 79.343266 -156.69387) (xy 79.265272 -157.626304) (xy 79.265272 -157.62732) (xy 79.260954 -157.66796)
			(xy 79.252318 -157.72257) (xy 79.23571 -157.812994) (xy 122.75007 -157.812994) (xy 122.754141 -157.757372)
			(xy 122.766267 -157.702935) (xy 122.78619 -157.650844) (xy 122.813486 -157.602209) (xy 122.847572 -157.558066)
			(xy 122.887721 -157.519357) (xy 122.933079 -157.486906) (xy 122.982679 -157.461405) (xy 123.035463 -157.443398)
			(xy 123.090306 -157.433268) (xy 123.14604 -157.431231) (xy 123.201477 -157.437331) (xy 123.255434 -157.451437)
			(xy 123.306763 -157.473249) (xy 123.354369 -157.502303) (xy 123.397237 -157.537978) (xy 123.434454 -157.579515)
			(xy 123.465227 -157.626028) (xy 123.475477 -157.647894) (xy 127.113792 -157.647894) (xy 127.114327 -157.621251)
			(xy 127.12285 -157.568653) (xy 127.139707 -157.518105) (xy 127.164461 -157.470918) (xy 127.196468 -157.428318)
			(xy 127.2349 -157.391409) (xy 127.25654 -157.37586) (xy 127.267829 -157.367502) (xy 127.28568 -157.345826)
			(xy 127.296959 -157.320111) (xy 127.300815 -157.292297) (xy 127.296957 -157.264483) (xy 127.285677 -157.238768)
			(xy 127.267824 -157.217094) (xy 127.25654 -157.208728) (xy 127.234939 -157.193131) (xy 127.196524 -157.156217)
			(xy 127.164523 -157.113623) (xy 127.139765 -157.066449) (xy 127.12289 -157.015916) (xy 127.114334 -156.963332)
			(xy 127.113792 -156.936694) (xy 127.114302 -156.910707) (xy 127.122432 -156.859372) (xy 127.138493 -156.809942)
			(xy 127.162089 -156.763632) (xy 127.192639 -156.721584) (xy 127.22939 -156.684833) (xy 127.271438 -156.654283)
			(xy 127.317748 -156.630687) (xy 127.367178 -156.614626) (xy 127.418513 -156.606496) (xy 127.470487 -156.606496)
			(xy 127.521822 -156.614626) (xy 127.571252 -156.630687) (xy 127.617562 -156.654283) (xy 127.65961 -156.684833)
			(xy 127.696361 -156.721584) (xy 127.726911 -156.763632) (xy 127.750507 -156.809942) (xy 127.766568 -156.859372)
			(xy 127.774698 -156.910707) (xy 127.775208 -156.936694) (xy 127.774664 -156.963336) (xy 127.766143 -157.015935)
			(xy 127.749288 -157.066482) (xy 127.724536 -157.113669) (xy 127.69253 -157.156269) (xy 127.6541 -157.193179)
			(xy 127.63246 -157.208728) (xy 127.621182 -157.217101) (xy 127.603332 -157.238773) (xy 127.592052 -157.264485)
			(xy 127.588195 -157.292297) (xy 127.59205 -157.320108) (xy 127.603328 -157.345821) (xy 127.621177 -157.367494)
			(xy 127.63246 -157.37586) (xy 127.654056 -157.391465) (xy 127.692471 -157.428377) (xy 127.724472 -157.47097)
			(xy 127.749231 -157.518142) (xy 127.766107 -157.568673) (xy 127.774665 -157.621257) (xy 127.775208 -157.647894)
			(xy 128.013714 -157.647894) (xy 128.014239 -157.621251) (xy 128.022763 -157.568651) (xy 128.039622 -157.518103)
			(xy 128.064377 -157.470916) (xy 128.096387 -157.428316) (xy 128.13482 -157.391408) (xy 128.156462 -157.37586)
			(xy 128.167749 -157.3675) (xy 128.185596 -157.345824) (xy 128.196873 -157.320109) (xy 128.200728 -157.292297)
			(xy 128.196871 -157.264484) (xy 128.185593 -157.238771) (xy 128.167744 -157.217095) (xy 128.156462 -157.208728)
			(xy 128.134866 -157.193124) (xy 128.096449 -157.156213) (xy 128.064448 -157.11362) (xy 128.039689 -157.066447)
			(xy 128.022813 -157.015915) (xy 128.014256 -156.963332) (xy 128.013714 -156.936694) (xy 128.014224 -156.910707)
			(xy 128.022354 -156.859372) (xy 128.038415 -156.809942) (xy 128.062011 -156.763632) (xy 128.092561 -156.721584)
			(xy 128.129312 -156.684833) (xy 128.17136 -156.654283) (xy 128.21767 -156.630687) (xy 128.2671 -156.614626)
			(xy 128.318435 -156.606496) (xy 128.370409 -156.606496) (xy 128.421744 -156.614626) (xy 128.471174 -156.630687)
			(xy 128.517484 -156.654283) (xy 128.559532 -156.684833) (xy 128.596283 -156.721584) (xy 128.626833 -156.763632)
			(xy 128.650429 -156.809942) (xy 128.66649 -156.859372) (xy 128.67462 -156.910707) (xy 128.67513 -156.936694)
			(xy 128.67462 -156.963338) (xy 128.666096 -157.01594) (xy 128.649236 -157.06649) (xy 128.624478 -157.113677)
			(xy 128.592465 -157.156276) (xy 128.554026 -157.193182) (xy 128.532382 -157.208728) (xy 128.521103 -157.2171)
			(xy 128.503248 -157.238771) (xy 128.491966 -157.264484) (xy 128.488108 -157.292297) (xy 128.491964 -157.320109)
			(xy 128.503245 -157.345823) (xy 128.521098 -157.367495) (xy 128.532382 -157.37586) (xy 128.553982 -157.391458)
			(xy 128.592396 -157.428372) (xy 128.624396 -157.470967) (xy 128.649154 -157.51814) (xy 128.66603 -157.568673)
			(xy 128.674587 -157.621256) (xy 128.67513 -157.647894) (xy 128.913636 -157.647894) (xy 128.914152 -157.62125)
			(xy 128.922677 -157.56865) (xy 128.939536 -157.5181) (xy 128.964293 -157.470914) (xy 128.996305 -157.428314)
			(xy 129.034741 -157.391407) (xy 129.056384 -157.37586) (xy 129.067678 -157.367505) (xy 129.085539 -157.345831)
			(xy 129.096824 -157.320115) (xy 129.100683 -157.292297) (xy 129.096823 -157.264479) (xy 129.085535 -157.238763)
			(xy 129.067673 -157.217091) (xy 129.056384 -157.208728) (xy 129.034792 -157.193118) (xy 128.996375 -157.156208)
			(xy 128.964372 -157.113617) (xy 128.939612 -157.066446) (xy 128.922735 -157.015914) (xy 128.914178 -156.963331)
			(xy 128.913636 -156.936694) (xy 128.914146 -156.910707) (xy 128.922276 -156.859372) (xy 128.938337 -156.809942)
			(xy 128.961933 -156.763632) (xy 128.992483 -156.721584) (xy 129.029234 -156.684833) (xy 129.071282 -156.654283)
			(xy 129.117592 -156.630687) (xy 129.167022 -156.614626) (xy 129.218357 -156.606496) (xy 129.270331 -156.606496)
			(xy 129.321666 -156.614626) (xy 129.371096 -156.630687) (xy 129.417406 -156.654283) (xy 129.459454 -156.684833)
			(xy 129.496205 -156.721584) (xy 129.526755 -156.763632) (xy 129.550351 -156.809942) (xy 129.566412 -156.859372)
			(xy 129.574542 -156.910707) (xy 129.575052 -156.936694) (xy 129.574532 -156.963338) (xy 129.566009 -157.015938)
			(xy 129.549151 -157.066488) (xy 129.524395 -157.113674) (xy 129.492383 -157.156274) (xy 129.453947 -157.193181)
			(xy 129.432304 -157.208728) (xy 129.421023 -157.217099) (xy 129.403164 -157.238769) (xy 129.39188 -157.264482)
			(xy 129.38802 -157.292297) (xy 129.391878 -157.320111) (xy 129.403161 -157.345825) (xy 129.421018 -157.367497)
			(xy 129.432304 -157.37586) (xy 129.453887 -157.391481) (xy 129.492306 -157.428388) (xy 129.52431 -157.470977)
			(xy 129.549072 -157.518146) (xy 129.56595 -157.568676) (xy 129.574509 -157.621257) (xy 129.575052 -157.647894)
			(xy 129.813812 -157.647894) (xy 129.814338 -157.621251) (xy 129.822862 -157.568651) (xy 129.83972 -157.518103)
			(xy 129.864475 -157.470916) (xy 129.896485 -157.428316) (xy 129.934919 -157.391408) (xy 129.95656 -157.37586)
			(xy 129.967847 -157.3675) (xy 129.985695 -157.345824) (xy 129.996971 -157.320109) (xy 130.000827 -157.292297)
			(xy 129.99697 -157.264484) (xy 129.985691 -157.23877) (xy 129.967842 -157.217095) (xy 129.95656 -157.208728)
			(xy 129.934963 -157.193125) (xy 129.896547 -157.156213) (xy 129.864545 -157.11362) (xy 129.839786 -157.066447)
			(xy 129.822911 -157.015915) (xy 129.814354 -156.963332) (xy 129.813812 -156.936694) (xy 129.814322 -156.910707)
			(xy 129.822452 -156.859372) (xy 129.838513 -156.809942) (xy 129.862109 -156.763632) (xy 129.892659 -156.721584)
			(xy 129.92941 -156.684833) (xy 129.971458 -156.654283) (xy 130.017768 -156.630687) (xy 130.067198 -156.614626)
			(xy 130.118533 -156.606496) (xy 130.170507 -156.606496) (xy 130.221842 -156.614626) (xy 130.271272 -156.630687)
			(xy 130.317582 -156.654283) (xy 130.35963 -156.684833) (xy 130.396381 -156.721584) (xy 130.426931 -156.763632)
			(xy 130.450527 -156.809942) (xy 130.466588 -156.859372) (xy 130.474718 -156.910707) (xy 130.475228 -156.936694)
			(xy 130.474719 -156.963338) (xy 130.466195 -157.01594) (xy 130.449335 -157.06649) (xy 130.424577 -157.113677)
			(xy 130.392563 -157.156276) (xy 130.354124 -157.193182) (xy 130.33248 -157.208728) (xy 130.321201 -157.2171)
			(xy 130.303346 -157.238771) (xy 130.292064 -157.264484) (xy 130.288206 -157.292297) (xy 130.292063 -157.320109)
			(xy 130.303343 -157.345823) (xy 130.321196 -157.367495) (xy 130.33248 -157.37586) (xy 130.35408 -157.391459)
			(xy 130.392494 -157.428373) (xy 130.424494 -157.470967) (xy 130.449252 -157.518141) (xy 130.466128 -157.568673)
			(xy 130.474685 -157.621256) (xy 130.475187 -157.645862) (xy 131.429252 -157.645862) (xy 131.429677 -157.619546)
			(xy 131.436919 -157.567415) (xy 131.451245 -157.516771) (xy 131.472385 -157.468572) (xy 131.499939 -157.42373)
			(xy 131.533386 -157.383093) (xy 131.552442 -157.364938) (xy 131.55982 -157.357396) (xy 131.56836 -157.338132)
			(xy 131.568952 -157.3276) (xy 131.568952 -157.252924) (xy 131.568437 -157.242372) (xy 131.559893 -157.223076)
			(xy 131.552442 -157.215586) (xy 131.533376 -157.197442) (xy 131.499922 -157.156808) (xy 131.472366 -157.111965)
			(xy 131.451229 -157.063762) (xy 131.436914 -157.013114) (xy 131.42969 -156.960979) (xy 131.429252 -156.934662)
			(xy 131.429738 -156.907411) (xy 131.437494 -156.853463) (xy 131.452849 -156.801168) (xy 131.475491 -156.751591)
			(xy 131.504957 -156.705741) (xy 131.540648 -156.66455) (xy 131.581839 -156.628859) (xy 131.627689 -156.599393)
			(xy 131.677266 -156.576751) (xy 131.729561 -156.561396) (xy 131.783509 -156.55364) (xy 131.838011 -156.55364)
			(xy 131.891959 -156.561396) (xy 131.944254 -156.576751) (xy 131.993831 -156.599393) (xy 132.039681 -156.628859)
			(xy 132.058426 -156.645101) (xy 133.41382 -156.645101) (xy 133.418135 -156.587828) (xy 133.430985 -156.531848)
			(xy 133.452079 -156.478427) (xy 133.48094 -156.428769) (xy 133.516917 -156.383997) (xy 133.537706 -156.364178)
			(xy 133.54512 -156.356667) (xy 133.553637 -156.337379) (xy 133.554216 -156.32684) (xy 133.554216 -156.252164)
			(xy 133.553661 -156.241617) (xy 133.545144 -156.222322) (xy 133.537706 -156.214826) (xy 133.518671 -156.196649)
			(xy 133.485212 -156.156024) (xy 133.45765 -156.111189) (xy 133.436508 -156.062992) (xy 133.422186 -156.012348)
			(xy 133.414957 -155.960217) (xy 133.414516 -155.933902) (xy 133.415002 -155.906651) (xy 133.422758 -155.852703)
			(xy 133.438113 -155.800408) (xy 133.460755 -155.750831) (xy 133.490221 -155.704981) (xy 133.525912 -155.66379)
			(xy 133.567103 -155.628099) (xy 133.612953 -155.598633) (xy 133.66253 -155.575991) (xy 133.714825 -155.560636)
			(xy 133.768773 -155.55288) (xy 133.823275 -155.55288) (xy 133.877223 -155.560636) (xy 133.929518 -155.575991)
			(xy 133.979095 -155.598633) (xy 134.024945 -155.628099) (xy 134.066136 -155.66379) (xy 134.101827 -155.704981)
			(xy 134.131293 -155.750831) (xy 134.153935 -155.800408) (xy 134.16929 -155.852703) (xy 134.177046 -155.906651)
			(xy 134.177532 -155.933902) (xy 134.177056 -155.960216) (xy 134.169821 -156.012343) (xy 134.155503 -156.062985)
			(xy 134.134372 -156.111184) (xy 134.106828 -156.156028) (xy 134.073392 -156.196669) (xy 134.054342 -156.214826)
			(xy 134.046933 -156.222342) (xy 134.038412 -156.241626) (xy 134.037832 -156.252164) (xy 134.037832 -156.32684)
			(xy 134.038371 -156.337389) (xy 134.046898 -156.356685) (xy 134.054342 -156.364178) (xy 134.075131 -156.383997)
			(xy 134.111104 -156.42877) (xy 134.139961 -156.478428) (xy 134.161053 -156.53185) (xy 134.173901 -156.587829)
			(xy 134.178216 -156.645101) (xy 134.1739 -156.702373) (xy 134.172764 -156.707322) (xy 136.479628 -156.707322)
			(xy 136.48394 -156.650052) (xy 136.496786 -156.594075) (xy 136.517874 -156.540656) (xy 136.54673 -156.490999)
			(xy 136.5827 -156.446228) (xy 136.603486 -156.426408) (xy 136.610884 -156.418883) (xy 136.619411 -156.399606)
			(xy 136.619996 -156.38907) (xy 136.619996 -156.314394) (xy 136.619485 -156.303842) (xy 136.610937 -156.284547)
			(xy 136.603486 -156.277056) (xy 136.584413 -156.258918) (xy 136.550958 -156.218284) (xy 136.523402 -156.17344)
			(xy 136.502267 -156.125236) (xy 136.487953 -156.074585) (xy 136.480732 -156.022449) (xy 136.480296 -155.996132)
			(xy 136.480782 -155.968881) (xy 136.488538 -155.914933) (xy 136.503893 -155.862638) (xy 136.526535 -155.813061)
			(xy 136.556001 -155.767211) (xy 136.591692 -155.72602) (xy 136.632883 -155.690329) (xy 136.678733 -155.660863)
			(xy 136.72831 -155.638221) (xy 136.780605 -155.622866) (xy 136.834553 -155.61511) (xy 136.889055 -155.61511)
			(xy 136.943003 -155.622866) (xy 136.995298 -155.638221) (xy 137.044875 -155.660863) (xy 137.090725 -155.690329)
			(xy 137.131916 -155.72602) (xy 137.167607 -155.767211) (xy 137.197073 -155.813061) (xy 137.219715 -155.862638)
			(xy 137.23507 -155.914933) (xy 137.242826 -155.968881) (xy 137.243312 -155.996132) (xy 137.242862 -156.022447)
			(xy 137.235623 -156.074576) (xy 137.2213 -156.125219) (xy 137.200165 -156.173417) (xy 137.172616 -156.21826)
			(xy 137.139175 -156.2589) (xy 137.120122 -156.277056) (xy 137.112741 -156.284595) (xy 137.104204 -156.303862)
			(xy 137.103612 -156.314394) (xy 137.103612 -156.38907) (xy 137.10414 -156.39962) (xy 137.112676 -156.418915)
			(xy 137.120122 -156.426408) (xy 137.140942 -156.446196) (xy 137.176916 -156.490973) (xy 137.205775 -156.540636)
			(xy 137.226865 -156.594062) (xy 137.239712 -156.650045) (xy 137.244024 -156.707322) (xy 137.239705 -156.764598)
			(xy 137.226852 -156.820579) (xy 137.205756 -156.874003) (xy 137.176892 -156.923663) (xy 137.140912 -156.968436)
			(xy 137.120122 -156.988256) (xy 137.112741 -156.995795) (xy 137.104204 -157.015062) (xy 137.103612 -157.025594)
			(xy 137.103612 -157.10027) (xy 137.10414 -157.11082) (xy 137.112676 -157.130115) (xy 137.120122 -157.137608)
			(xy 137.139179 -157.155762) (xy 137.172635 -157.196393) (xy 137.200193 -157.241234) (xy 137.221331 -157.289434)
			(xy 137.235648 -157.340082) (xy 137.242873 -157.392216) (xy 137.243312 -157.418532) (xy 137.242826 -157.445783)
			(xy 137.23507 -157.499731) (xy 137.219715 -157.552026) (xy 137.197073 -157.601603) (xy 137.167607 -157.647453)
			(xy 137.131916 -157.688644) (xy 137.090725 -157.724335) (xy 137.044875 -157.753801) (xy 136.995298 -157.776443)
			(xy 136.943003 -157.791798) (xy 136.889055 -157.799554) (xy 136.834553 -157.799554) (xy 136.780605 -157.791798)
			(xy 136.72831 -157.776443) (xy 136.678733 -157.753801) (xy 136.632883 -157.724335) (xy 136.591692 -157.688644)
			(xy 136.556001 -157.647453) (xy 136.526535 -157.601603) (xy 136.503893 -157.552026) (xy 136.488538 -157.499731)
			(xy 136.480782 -157.445783) (xy 136.480296 -157.418532) (xy 136.480719 -157.392217) (xy 136.487963 -157.340086)
			(xy 136.502291 -157.289443) (xy 136.523432 -157.241244) (xy 136.550986 -157.196401) (xy 136.584431 -157.155764)
			(xy 136.603486 -157.137608) (xy 136.610884 -157.130083) (xy 136.619411 -157.110806) (xy 136.619996 -157.10027)
			(xy 136.619996 -157.025594) (xy 136.619485 -157.015042) (xy 136.610937 -156.995747) (xy 136.603486 -156.988256)
			(xy 136.58273 -156.968404) (xy 136.546754 -156.923636) (xy 136.517893 -156.873983) (xy 136.496798 -156.820566)
			(xy 136.483947 -156.764591) (xy 136.479628 -156.707322) (xy 134.172764 -156.707322) (xy 134.161052 -156.758352)
			(xy 134.13996 -156.811774) (xy 134.111102 -156.861432) (xy 134.075129 -156.906205) (xy 134.054342 -156.926026)
			(xy 134.046933 -156.933542) (xy 134.038412 -156.952826) (xy 134.037832 -156.963364) (xy 134.037832 -157.03804)
			(xy 134.038371 -157.048589) (xy 134.046898 -157.067885) (xy 134.054342 -157.075378) (xy 134.073388 -157.093543)
			(xy 134.106844 -157.134172) (xy 134.134404 -157.17901) (xy 134.155543 -157.227209) (xy 134.169863 -157.277854)
			(xy 134.177091 -157.329987) (xy 134.177532 -157.356302) (xy 134.177046 -157.383553) (xy 134.16929 -157.437501)
			(xy 134.153935 -157.489796) (xy 134.131293 -157.539373) (xy 134.101827 -157.585223) (xy 134.066136 -157.626414)
			(xy 134.024945 -157.662105) (xy 133.979095 -157.691571) (xy 133.929518 -157.714213) (xy 133.877223 -157.729568)
			(xy 133.823275 -157.737324) (xy 133.768773 -157.737324) (xy 133.714825 -157.729568) (xy 133.66253 -157.714213)
			(xy 133.612953 -157.691571) (xy 133.567103 -157.662105) (xy 133.525912 -157.626414) (xy 133.490221 -157.585223)
			(xy 133.460755 -157.539373) (xy 133.438113 -157.489796) (xy 133.422758 -157.437501) (xy 133.415002 -157.383553)
			(xy 133.414516 -157.356302) (xy 133.41498 -157.329988) (xy 133.422215 -157.277859) (xy 133.436534 -157.227216)
			(xy 133.457667 -157.179017) (xy 133.485214 -157.134174) (xy 133.518654 -157.093534) (xy 133.537706 -157.075378)
			(xy 133.54512 -157.067867) (xy 133.553637 -157.048579) (xy 133.554216 -157.03804) (xy 133.554216 -156.963364)
			(xy 133.553661 -156.952817) (xy 133.545144 -156.933522) (xy 133.537706 -156.926026) (xy 133.516919 -156.906205)
			(xy 133.480942 -156.861433) (xy 133.45208 -156.811776) (xy 133.430986 -156.758354) (xy 133.418136 -156.702375)
			(xy 133.41382 -156.645101) (xy 132.058426 -156.645101) (xy 132.080872 -156.66455) (xy 132.116563 -156.705741)
			(xy 132.146029 -156.751591) (xy 132.168671 -156.801168) (xy 132.184026 -156.853463) (xy 132.191782 -156.907411)
			(xy 132.192268 -156.934662) (xy 132.191852 -156.960978) (xy 132.184608 -157.013109) (xy 132.17028 -157.063753)
			(xy 132.149138 -157.111952) (xy 132.121582 -157.156794) (xy 132.088134 -157.197431) (xy 132.069078 -157.215586)
			(xy 132.061677 -157.223108) (xy 132.053153 -157.242388) (xy 132.052568 -157.252924) (xy 132.052568 -157.3276)
			(xy 132.053093 -157.33815) (xy 132.061632 -157.357445) (xy 132.069078 -157.364938) (xy 132.088141 -157.383086)
			(xy 132.121598 -157.423717) (xy 132.149157 -157.468559) (xy 132.170294 -157.516761) (xy 132.184609 -157.56741)
			(xy 132.191831 -157.619545) (xy 132.192268 -157.645862) (xy 132.191782 -157.673113) (xy 132.184026 -157.727061)
			(xy 132.168671 -157.779356) (xy 132.146029 -157.828933) (xy 132.116563 -157.874783) (xy 132.080872 -157.915974)
			(xy 132.039681 -157.951665) (xy 131.993831 -157.981131) (xy 131.944254 -158.003773) (xy 131.891959 -158.019128)
			(xy 131.838011 -158.026884) (xy 131.783509 -158.026884) (xy 131.729561 -158.019128) (xy 131.677266 -158.003773)
			(xy 131.627689 -157.981131) (xy 131.581839 -157.951665) (xy 131.540648 -157.915974) (xy 131.504957 -157.874783)
			(xy 131.475491 -157.828933) (xy 131.452849 -157.779356) (xy 131.437494 -157.727061) (xy 131.429738 -157.673113)
			(xy 131.429252 -157.645862) (xy 130.475187 -157.645862) (xy 130.475228 -157.647894) (xy 130.474718 -157.673881)
			(xy 130.466588 -157.725216) (xy 130.450527 -157.774646) (xy 130.426931 -157.820956) (xy 130.396381 -157.863004)
			(xy 130.35963 -157.899755) (xy 130.317582 -157.930305) (xy 130.271272 -157.953901) (xy 130.221842 -157.969962)
			(xy 130.170507 -157.978092) (xy 130.118533 -157.978092) (xy 130.067198 -157.969962) (xy 130.017768 -157.953901)
			(xy 129.971458 -157.930305) (xy 129.92941 -157.899755) (xy 129.892659 -157.863004) (xy 129.862109 -157.820956)
			(xy 129.838513 -157.774646) (xy 129.822452 -157.725216) (xy 129.814322 -157.673881) (xy 129.813812 -157.647894)
			(xy 129.575052 -157.647894) (xy 129.574542 -157.673881) (xy 129.566412 -157.725216) (xy 129.550351 -157.774646)
			(xy 129.526755 -157.820956) (xy 129.496205 -157.863004) (xy 129.459454 -157.899755) (xy 129.417406 -157.930305)
			(xy 129.371096 -157.953901) (xy 129.321666 -157.969962) (xy 129.270331 -157.978092) (xy 129.218357 -157.978092)
			(xy 129.167022 -157.969962) (xy 129.117592 -157.953901) (xy 129.071282 -157.930305) (xy 129.029234 -157.899755)
			(xy 128.992483 -157.863004) (xy 128.961933 -157.820956) (xy 128.938337 -157.774646) (xy 128.922276 -157.725216)
			(xy 128.914146 -157.673881) (xy 128.913636 -157.647894) (xy 128.67513 -157.647894) (xy 128.67462 -157.673881)
			(xy 128.66649 -157.725216) (xy 128.650429 -157.774646) (xy 128.626833 -157.820956) (xy 128.596283 -157.863004)
			(xy 128.559532 -157.899755) (xy 128.517484 -157.930305) (xy 128.471174 -157.953901) (xy 128.421744 -157.969962)
			(xy 128.370409 -157.978092) (xy 128.318435 -157.978092) (xy 128.2671 -157.969962) (xy 128.21767 -157.953901)
			(xy 128.17136 -157.930305) (xy 128.129312 -157.899755) (xy 128.092561 -157.863004) (xy 128.062011 -157.820956)
			(xy 128.038415 -157.774646) (xy 128.022354 -157.725216) (xy 128.014224 -157.673881) (xy 128.013714 -157.647894)
			(xy 127.775208 -157.647894) (xy 127.774698 -157.673881) (xy 127.766568 -157.725216) (xy 127.750507 -157.774646)
			(xy 127.726911 -157.820956) (xy 127.696361 -157.863004) (xy 127.65961 -157.899755) (xy 127.617562 -157.930305)
			(xy 127.571252 -157.953901) (xy 127.521822 -157.969962) (xy 127.470487 -157.978092) (xy 127.418513 -157.978092)
			(xy 127.367178 -157.969962) (xy 127.317748 -157.953901) (xy 127.271438 -157.930305) (xy 127.22939 -157.899755)
			(xy 127.192639 -157.863004) (xy 127.162089 -157.820956) (xy 127.138493 -157.774646) (xy 127.122432 -157.725216)
			(xy 127.114302 -157.673881) (xy 127.113792 -157.647894) (xy 123.475477 -157.647894) (xy 123.488899 -157.676525)
			(xy 123.504967 -157.729932) (xy 123.513087 -157.785108) (xy 123.513596 -157.812994) (xy 123.513087 -157.84088)
			(xy 123.504967 -157.896056) (xy 123.488899 -157.949463) (xy 123.465227 -157.99996) (xy 123.434454 -158.046473)
			(xy 123.421984 -158.06039) (xy 124.93955 -158.06039) (xy 124.943621 -158.004768) (xy 124.955747 -157.950331)
			(xy 124.97567 -157.89824) (xy 125.002966 -157.849605) (xy 125.037052 -157.805462) (xy 125.077201 -157.766753)
			(xy 125.122559 -157.734302) (xy 125.172159 -157.708801) (xy 125.224943 -157.690794) (xy 125.279786 -157.680664)
			(xy 125.33552 -157.678627) (xy 125.390957 -157.684727) (xy 125.444914 -157.698833) (xy 125.496243 -157.720645)
			(xy 125.543849 -157.749699) (xy 125.586717 -157.785374) (xy 125.623934 -157.826911) (xy 125.654707 -157.873424)
			(xy 125.678379 -157.923921) (xy 125.694447 -157.977328) (xy 125.702567 -158.032504) (xy 125.703076 -158.06039)
			(xy 125.702567 -158.088276) (xy 125.694447 -158.143452) (xy 125.678379 -158.196859) (xy 125.654707 -158.247356)
			(xy 125.623934 -158.293869) (xy 125.586717 -158.335406) (xy 125.543849 -158.371081) (xy 125.496243 -158.400135)
			(xy 125.444914 -158.421947) (xy 125.390957 -158.436053) (xy 125.33552 -158.442153) (xy 125.279786 -158.440116)
			(xy 125.224943 -158.429986) (xy 125.172159 -158.411979) (xy 125.122559 -158.386478) (xy 125.077201 -158.354027)
			(xy 125.037052 -158.315318) (xy 125.002966 -158.271175) (xy 124.97567 -158.22254) (xy 124.955747 -158.170449)
			(xy 124.943621 -158.116012) (xy 124.93955 -158.06039) (xy 123.421984 -158.06039) (xy 123.397237 -158.08801)
			(xy 123.354369 -158.123685) (xy 123.306763 -158.152739) (xy 123.255434 -158.174551) (xy 123.201477 -158.188657)
			(xy 123.14604 -158.194757) (xy 123.090306 -158.19272) (xy 123.035463 -158.18259) (xy 122.982679 -158.164583)
			(xy 122.933079 -158.139082) (xy 122.887721 -158.106631) (xy 122.847572 -158.067922) (xy 122.813486 -158.023779)
			(xy 122.78619 -157.975144) (xy 122.766267 -157.923053) (xy 122.754141 -157.868616) (xy 122.75007 -157.812994)
			(xy 79.23571 -157.812994) (xy 79.161022 -158.219648) (xy 81.182208 -158.219648) (xy 81.186279 -158.164026)
			(xy 81.198405 -158.109589) (xy 81.218328 -158.057498) (xy 81.245624 -158.008863) (xy 81.27971 -157.96472)
			(xy 81.319859 -157.926011) (xy 81.365217 -157.89356) (xy 81.414817 -157.868059) (xy 81.467601 -157.850052)
			(xy 81.522444 -157.839922) (xy 81.578178 -157.837885) (xy 81.633615 -157.843985) (xy 81.687572 -157.858091)
			(xy 81.738901 -157.879903) (xy 81.786507 -157.908957) (xy 81.829375 -157.944632) (xy 81.866592 -157.986169)
			(xy 81.897365 -158.032682) (xy 81.921037 -158.083179) (xy 81.937105 -158.136586) (xy 81.945225 -158.191762)
			(xy 81.945734 -158.219648) (xy 81.945225 -158.247534) (xy 81.937105 -158.30271) (xy 81.921037 -158.356117)
			(xy 81.897365 -158.406614) (xy 81.866592 -158.453127) (xy 81.829375 -158.494664) (xy 81.786507 -158.530339)
			(xy 81.738901 -158.559393) (xy 81.687572 -158.581205) (xy 81.633615 -158.595311) (xy 81.578178 -158.601411)
			(xy 81.522444 -158.599374) (xy 81.467601 -158.589244) (xy 81.414817 -158.571237) (xy 81.365217 -158.545736)
			(xy 81.319859 -158.513285) (xy 81.27971 -158.474576) (xy 81.245624 -158.430433) (xy 81.218328 -158.381798)
			(xy 81.198405 -158.329707) (xy 81.186279 -158.27527) (xy 81.182208 -158.219648) (xy 79.161022 -158.219648)
			(xy 79.02732 -158.947612) (xy 107.304584 -158.947612) (xy 107.308655 -158.89199) (xy 107.320781 -158.837553)
			(xy 107.340704 -158.785462) (xy 107.368 -158.736827) (xy 107.402086 -158.692684) (xy 107.442235 -158.653975)
			(xy 107.487593 -158.621524) (xy 107.537193 -158.596023) (xy 107.589977 -158.578016) (xy 107.64482 -158.567886)
			(xy 107.700554 -158.565849) (xy 107.755991 -158.571949) (xy 107.809948 -158.586055) (xy 107.861277 -158.607867)
			(xy 107.908883 -158.636921) (xy 107.951751 -158.672596) (xy 107.988968 -158.714133) (xy 108.019741 -158.760646)
			(xy 108.043413 -158.811143) (xy 108.048784 -158.828994) (xy 122.75007 -158.828994) (xy 122.754141 -158.773372)
			(xy 122.766267 -158.718935) (xy 122.78619 -158.666844) (xy 122.813486 -158.618209) (xy 122.847572 -158.574066)
			(xy 122.887721 -158.535357) (xy 122.933079 -158.502906) (xy 122.982679 -158.477405) (xy 123.035463 -158.459398)
			(xy 123.090306 -158.449268) (xy 123.14604 -158.447231) (xy 123.201477 -158.453331) (xy 123.255434 -158.467437)
			(xy 123.306763 -158.489249) (xy 123.354369 -158.518303) (xy 123.397237 -158.553978) (xy 123.434454 -158.595515)
			(xy 123.465227 -158.642028) (xy 123.488899 -158.692525) (xy 123.504967 -158.745932) (xy 123.506052 -158.753302)
			(xy 132.616446 -158.753302) (xy 132.620517 -158.69768) (xy 132.632643 -158.643243) (xy 132.652566 -158.591152)
			(xy 132.679862 -158.542517) (xy 132.713948 -158.498374) (xy 132.754097 -158.459665) (xy 132.799455 -158.427214)
			(xy 132.849055 -158.401713) (xy 132.901839 -158.383706) (xy 132.956682 -158.373576) (xy 133.012416 -158.371539)
			(xy 133.067853 -158.377639) (xy 133.12181 -158.391745) (xy 133.173139 -158.413557) (xy 133.220745 -158.442611)
			(xy 133.263613 -158.478286) (xy 133.30083 -158.519823) (xy 133.331603 -158.566336) (xy 133.355275 -158.616833)
			(xy 133.371343 -158.67024) (xy 133.379463 -158.725416) (xy 133.379972 -158.753302) (xy 133.379463 -158.781188)
			(xy 133.371343 -158.836364) (xy 133.355275 -158.889771) (xy 133.331603 -158.940268) (xy 133.30083 -158.986781)
			(xy 133.263613 -159.028318) (xy 133.220745 -159.063993) (xy 133.173139 -159.093047) (xy 133.12181 -159.114859)
			(xy 133.067853 -159.128965) (xy 133.012416 -159.135065) (xy 132.956682 -159.133028) (xy 132.901839 -159.122898)
			(xy 132.849055 -159.104891) (xy 132.799455 -159.07939) (xy 132.754097 -159.046939) (xy 132.713948 -159.00823)
			(xy 132.679862 -158.964087) (xy 132.652566 -158.915452) (xy 132.632643 -158.863361) (xy 132.620517 -158.808924)
			(xy 132.616446 -158.753302) (xy 123.506052 -158.753302) (xy 123.513087 -158.801108) (xy 123.513596 -158.828994)
			(xy 123.513087 -158.85688) (xy 123.504967 -158.912056) (xy 123.488899 -158.965463) (xy 123.465227 -159.01596)
			(xy 123.434454 -159.062473) (xy 123.397237 -159.10401) (xy 123.354369 -159.139685) (xy 123.306763 -159.168739)
			(xy 123.255434 -159.190551) (xy 123.201477 -159.204657) (xy 123.14604 -159.210757) (xy 123.090306 -159.20872)
			(xy 123.035463 -159.19859) (xy 122.982679 -159.180583) (xy 122.933079 -159.155082) (xy 122.887721 -159.122631)
			(xy 122.847572 -159.083922) (xy 122.813486 -159.039779) (xy 122.78619 -158.991144) (xy 122.766267 -158.939053)
			(xy 122.754141 -158.884616) (xy 122.75007 -158.828994) (xy 108.048784 -158.828994) (xy 108.059481 -158.86455)
			(xy 108.067601 -158.919726) (xy 108.06811 -158.947612) (xy 108.067601 -158.975498) (xy 108.059481 -159.030674)
			(xy 108.043413 -159.084081) (xy 108.019741 -159.134578) (xy 107.988968 -159.181091) (xy 107.951751 -159.222628)
			(xy 107.908883 -159.258303) (xy 107.861277 -159.287357) (xy 107.809948 -159.309169) (xy 107.755991 -159.323275)
			(xy 107.700554 -159.329375) (xy 107.64482 -159.327338) (xy 107.589977 -159.317208) (xy 107.537193 -159.299201)
			(xy 107.487593 -159.2737) (xy 107.442235 -159.241249) (xy 107.402086 -159.20254) (xy 107.368 -159.158397)
			(xy 107.340704 -159.109762) (xy 107.320781 -159.057671) (xy 107.308655 -159.003234) (xy 107.304584 -158.947612)
			(xy 79.02732 -158.947612) (xy 78.892545 -159.681418) (xy 112.176558 -159.681418) (xy 112.180629 -159.625796)
			(xy 112.192755 -159.571359) (xy 112.212678 -159.519268) (xy 112.239974 -159.470633) (xy 112.27406 -159.42649)
			(xy 112.314209 -159.387781) (xy 112.359567 -159.35533) (xy 112.409167 -159.329829) (xy 112.461951 -159.311822)
			(xy 112.516794 -159.301692) (xy 112.572528 -159.299655) (xy 112.627965 -159.305755) (xy 112.681922 -159.319861)
			(xy 112.733251 -159.341673) (xy 112.780857 -159.370727) (xy 112.823725 -159.406402) (xy 112.853024 -159.439102)
			(xy 125.007876 -159.439102) (xy 125.011947 -159.38348) (xy 125.024073 -159.329043) (xy 125.043996 -159.276952)
			(xy 125.071292 -159.228317) (xy 125.105378 -159.184174) (xy 125.145527 -159.145465) (xy 125.190885 -159.113014)
			(xy 125.240485 -159.087513) (xy 125.293269 -159.069506) (xy 125.348112 -159.059376) (xy 125.403846 -159.057339)
			(xy 125.459283 -159.063439) (xy 125.51324 -159.077545) (xy 125.564569 -159.099357) (xy 125.612175 -159.128411)
			(xy 125.655043 -159.164086) (xy 125.69226 -159.205623) (xy 125.723033 -159.252136) (xy 125.746705 -159.302633)
			(xy 125.762773 -159.35604) (xy 125.770893 -159.411216) (xy 125.771402 -159.439102) (xy 125.770893 -159.466988)
			(xy 125.762773 -159.522164) (xy 125.75987 -159.531812) (xy 128.212594 -159.531812) (xy 128.216665 -159.47619)
			(xy 128.228791 -159.421753) (xy 128.248714 -159.369662) (xy 128.27601 -159.321027) (xy 128.310096 -159.276884)
			(xy 128.350245 -159.238175) (xy 128.395603 -159.205724) (xy 128.445203 -159.180223) (xy 128.497987 -159.162216)
			(xy 128.55283 -159.152086) (xy 128.608564 -159.150049) (xy 128.664001 -159.156149) (xy 128.717958 -159.170255)
			(xy 128.769287 -159.192067) (xy 128.816893 -159.221121) (xy 128.859761 -159.256796) (xy 128.896978 -159.298333)
			(xy 128.927751 -159.344846) (xy 128.951423 -159.395343) (xy 128.967491 -159.44875) (xy 128.97336 -159.488632)
			(xy 130.4958 -159.488632) (xy 130.499871 -159.43301) (xy 130.511997 -159.378573) (xy 130.53192 -159.326482)
			(xy 130.559216 -159.277847) (xy 130.593302 -159.233704) (xy 130.633451 -159.194995) (xy 130.678809 -159.162544)
			(xy 130.728409 -159.137043) (xy 130.781193 -159.119036) (xy 130.836036 -159.108906) (xy 130.89177 -159.106869)
			(xy 130.947207 -159.112969) (xy 131.001164 -159.127075) (xy 131.052493 -159.148887) (xy 131.100099 -159.177941)
			(xy 131.142967 -159.213616) (xy 131.180184 -159.255153) (xy 131.210957 -159.301666) (xy 131.234629 -159.352163)
			(xy 131.250697 -159.40557) (xy 131.258817 -159.460746) (xy 131.259326 -159.488632) (xy 131.258817 -159.516518)
			(xy 131.250697 -159.571694) (xy 131.234629 -159.625101) (xy 131.210957 -159.675598) (xy 131.180184 -159.722111)
			(xy 131.142967 -159.763648) (xy 131.100099 -159.799323) (xy 131.052493 -159.828377) (xy 131.001164 -159.850189)
			(xy 130.947207 -159.864295) (xy 130.89177 -159.870395) (xy 130.836036 -159.868358) (xy 130.781193 -159.858228)
			(xy 130.728409 -159.840221) (xy 130.678809 -159.81472) (xy 130.633451 -159.782269) (xy 130.593302 -159.74356)
			(xy 130.559216 -159.699417) (xy 130.53192 -159.650782) (xy 130.511997 -159.598691) (xy 130.499871 -159.544254)
			(xy 130.4958 -159.488632) (xy 128.97336 -159.488632) (xy 128.975611 -159.503926) (xy 128.97612 -159.531812)
			(xy 128.975611 -159.559698) (xy 128.967491 -159.614874) (xy 128.951423 -159.668281) (xy 128.927751 -159.718778)
			(xy 128.896978 -159.765291) (xy 128.859761 -159.806828) (xy 128.816893 -159.842503) (xy 128.769287 -159.871557)
			(xy 128.717958 -159.893369) (xy 128.664001 -159.907475) (xy 128.608564 -159.913575) (xy 128.55283 -159.911538)
			(xy 128.497987 -159.901408) (xy 128.445203 -159.883401) (xy 128.395603 -159.8579) (xy 128.350245 -159.825449)
			(xy 128.310096 -159.78674) (xy 128.27601 -159.742597) (xy 128.248714 -159.693962) (xy 128.228791 -159.641871)
			(xy 128.216665 -159.587434) (xy 128.212594 -159.531812) (xy 125.75987 -159.531812) (xy 125.746705 -159.575571)
			(xy 125.723033 -159.626068) (xy 125.69226 -159.672581) (xy 125.655043 -159.714118) (xy 125.612175 -159.749793)
			(xy 125.564569 -159.778847) (xy 125.51324 -159.800659) (xy 125.459283 -159.814765) (xy 125.403846 -159.820865)
			(xy 125.348112 -159.818828) (xy 125.293269 -159.808698) (xy 125.240485 -159.790691) (xy 125.190885 -159.76519)
			(xy 125.145527 -159.732739) (xy 125.105378 -159.69403) (xy 125.071292 -159.649887) (xy 125.043996 -159.601252)
			(xy 125.024073 -159.549161) (xy 125.011947 -159.494724) (xy 125.007876 -159.439102) (xy 112.853024 -159.439102)
			(xy 112.860942 -159.447939) (xy 112.891715 -159.494452) (xy 112.915387 -159.544949) (xy 112.931455 -159.598356)
			(xy 112.939575 -159.653532) (xy 112.940084 -159.681418) (xy 112.939575 -159.709304) (xy 112.931455 -159.76448)
			(xy 112.915387 -159.817887) (xy 112.891715 -159.868384) (xy 112.860942 -159.914897) (xy 112.823725 -159.956434)
			(xy 112.780857 -159.992109) (xy 112.733251 -160.021163) (xy 112.681922 -160.042975) (xy 112.627965 -160.057081)
			(xy 112.572528 -160.063181) (xy 112.516794 -160.061144) (xy 112.461951 -160.051014) (xy 112.409167 -160.033007)
			(xy 112.359567 -160.007506) (xy 112.314209 -159.975055) (xy 112.27406 -159.936346) (xy 112.239974 -159.892203)
			(xy 112.212678 -159.843568) (xy 112.192755 -159.791477) (xy 112.180629 -159.73704) (xy 112.176558 -159.681418)
			(xy 78.892545 -159.681418) (xy 78.793552 -160.220406) (xy 113.389916 -160.220406) (xy 113.393987 -160.164784)
			(xy 113.406113 -160.110347) (xy 113.426036 -160.058256) (xy 113.453332 -160.009621) (xy 113.487418 -159.965478)
			(xy 113.527567 -159.926769) (xy 113.572925 -159.894318) (xy 113.622525 -159.868817) (xy 113.675309 -159.85081)
			(xy 113.730152 -159.84068) (xy 113.785886 -159.838643) (xy 113.841323 -159.844743) (xy 113.842283 -159.844994)
			(xy 122.75007 -159.844994) (xy 122.754141 -159.789372) (xy 122.766267 -159.734935) (xy 122.78619 -159.682844)
			(xy 122.813486 -159.634209) (xy 122.847572 -159.590066) (xy 122.887721 -159.551357) (xy 122.933079 -159.518906)
			(xy 122.982679 -159.493405) (xy 123.035463 -159.475398) (xy 123.090306 -159.465268) (xy 123.14604 -159.463231)
			(xy 123.201477 -159.469331) (xy 123.255434 -159.483437) (xy 123.306763 -159.505249) (xy 123.354369 -159.534303)
			(xy 123.397237 -159.569978) (xy 123.434454 -159.611515) (xy 123.465227 -159.658028) (xy 123.488899 -159.708525)
			(xy 123.504967 -159.761932) (xy 123.513087 -159.817108) (xy 123.513596 -159.844994) (xy 123.513087 -159.87288)
			(xy 123.504967 -159.928056) (xy 123.488899 -159.981463) (xy 123.465227 -160.03196) (xy 123.434454 -160.078473)
			(xy 123.397237 -160.12001) (xy 123.354369 -160.155685) (xy 123.306763 -160.184739) (xy 123.255434 -160.206551)
			(xy 123.201477 -160.220657) (xy 123.14604 -160.226757) (xy 123.090306 -160.22472) (xy 123.035463 -160.21459)
			(xy 122.982679 -160.196583) (xy 122.933079 -160.171082) (xy 122.887721 -160.138631) (xy 122.847572 -160.099922)
			(xy 122.813486 -160.055779) (xy 122.78619 -160.007144) (xy 122.766267 -159.955053) (xy 122.754141 -159.900616)
			(xy 122.75007 -159.844994) (xy 113.842283 -159.844994) (xy 113.89528 -159.858849) (xy 113.946609 -159.880661)
			(xy 113.994215 -159.909715) (xy 114.037083 -159.94539) (xy 114.0743 -159.986927) (xy 114.105073 -160.03344)
			(xy 114.128745 -160.083937) (xy 114.144813 -160.137344) (xy 114.152933 -160.19252) (xy 114.153442 -160.220406)
			(xy 114.152933 -160.248292) (xy 114.144813 -160.303468) (xy 114.128745 -160.356875) (xy 114.105073 -160.407372)
			(xy 114.0743 -160.453885) (xy 114.058189 -160.471866) (xy 114.82019 -160.471866) (xy 114.824261 -160.416244)
			(xy 114.836387 -160.361807) (xy 114.85631 -160.309716) (xy 114.883606 -160.261081) (xy 114.917692 -160.216938)
			(xy 114.957841 -160.178229) (xy 115.003199 -160.145778) (xy 115.052799 -160.120277) (xy 115.105583 -160.10227)
			(xy 115.160426 -160.09214) (xy 115.21616 -160.090103) (xy 115.271597 -160.096203) (xy 115.325554 -160.110309)
			(xy 115.376883 -160.132121) (xy 115.424489 -160.161175) (xy 115.467357 -160.19685) (xy 115.504574 -160.238387)
			(xy 115.535347 -160.2849) (xy 115.559019 -160.335397) (xy 115.575087 -160.388804) (xy 115.583207 -160.44398)
			(xy 115.583716 -160.471866) (xy 115.583207 -160.499752) (xy 115.575087 -160.554928) (xy 115.559019 -160.608335)
			(xy 115.535347 -160.658832) (xy 115.504574 -160.705345) (xy 115.467357 -160.746882) (xy 115.424489 -160.782557)
			(xy 115.376883 -160.811611) (xy 115.325554 -160.833423) (xy 115.271597 -160.847529) (xy 115.21616 -160.853629)
			(xy 115.160426 -160.851592) (xy 115.105583 -160.841462) (xy 115.052799 -160.823455) (xy 115.003199 -160.797954)
			(xy 114.957841 -160.765503) (xy 114.917692 -160.726794) (xy 114.883606 -160.682651) (xy 114.85631 -160.634016)
			(xy 114.836387 -160.581925) (xy 114.824261 -160.527488) (xy 114.82019 -160.471866) (xy 114.058189 -160.471866)
			(xy 114.037083 -160.495422) (xy 113.994215 -160.531097) (xy 113.946609 -160.560151) (xy 113.89528 -160.581963)
			(xy 113.841323 -160.596069) (xy 113.785886 -160.602169) (xy 113.730152 -160.600132) (xy 113.675309 -160.590002)
			(xy 113.622525 -160.571995) (xy 113.572925 -160.546494) (xy 113.527567 -160.514043) (xy 113.487418 -160.475334)
			(xy 113.453332 -160.431191) (xy 113.426036 -160.382556) (xy 113.406113 -160.330465) (xy 113.393987 -160.276028)
			(xy 113.389916 -160.220406) (xy 78.793552 -160.220406) (xy 78.772512 -160.33496) (xy 78.772004 -160.3375)
			(xy 78.762098 -160.412684) (xy 78.688517 -160.965896) (xy 125.037594 -160.965896) (xy 125.041665 -160.910274)
			(xy 125.053791 -160.855837) (xy 125.073714 -160.803746) (xy 125.10101 -160.755111) (xy 125.135096 -160.710968)
			(xy 125.175245 -160.672259) (xy 125.220603 -160.639808) (xy 125.270203 -160.614307) (xy 125.322987 -160.5963)
			(xy 125.37783 -160.58617) (xy 125.433564 -160.584133) (xy 125.489001 -160.590233) (xy 125.542958 -160.604339)
			(xy 125.594287 -160.626151) (xy 125.641893 -160.655205) (xy 125.684761 -160.69088) (xy 125.721978 -160.732417)
			(xy 125.752751 -160.77893) (xy 125.776423 -160.829427) (xy 125.792491 -160.882834) (xy 125.800611 -160.93801)
			(xy 125.801083 -160.963864) (xy 126.429514 -160.963864) (xy 126.433585 -160.908242) (xy 126.445711 -160.853805)
			(xy 126.465634 -160.801714) (xy 126.49293 -160.753079) (xy 126.527016 -160.708936) (xy 126.567165 -160.670227)
			(xy 126.612523 -160.637776) (xy 126.662123 -160.612275) (xy 126.714907 -160.594268) (xy 126.76975 -160.584138)
			(xy 126.825484 -160.582101) (xy 126.880921 -160.588201) (xy 126.934878 -160.602307) (xy 126.986207 -160.624119)
			(xy 127.033813 -160.653173) (xy 127.076681 -160.688848) (xy 127.113898 -160.730385) (xy 127.144671 -160.776898)
			(xy 127.168343 -160.827395) (xy 127.184411 -160.880802) (xy 127.192531 -160.935978) (xy 127.19304 -160.963864)
			(xy 127.192947 -160.968944) (xy 127.701292 -160.968944) (xy 127.705363 -160.913322) (xy 127.717489 -160.858885)
			(xy 127.737412 -160.806794) (xy 127.764708 -160.758159) (xy 127.798794 -160.714016) (xy 127.838943 -160.675307)
			(xy 127.884301 -160.642856) (xy 127.933901 -160.617355) (xy 127.986685 -160.599348) (xy 128.041528 -160.589218)
			(xy 128.097262 -160.587181) (xy 128.152699 -160.593281) (xy 128.206656 -160.607387) (xy 128.257985 -160.629199)
			(xy 128.305591 -160.658253) (xy 128.348459 -160.693928) (xy 128.385676 -160.735465) (xy 128.416449 -160.781978)
			(xy 128.440121 -160.832475) (xy 128.456189 -160.885882) (xy 128.458582 -160.902142) (xy 129.482594 -160.902142)
			(xy 129.486665 -160.84652) (xy 129.498791 -160.792083) (xy 129.518714 -160.739992) (xy 129.54601 -160.691357)
			(xy 129.580096 -160.647214) (xy 129.620245 -160.608505) (xy 129.665603 -160.576054) (xy 129.715203 -160.550553)
			(xy 129.767987 -160.532546) (xy 129.82283 -160.522416) (xy 129.878564 -160.520379) (xy 129.934001 -160.526479)
			(xy 129.987958 -160.540585) (xy 130.039287 -160.562397) (xy 130.086893 -160.591451) (xy 130.129761 -160.627126)
			(xy 130.166978 -160.668663) (xy 130.197751 -160.715176) (xy 130.221423 -160.765673) (xy 130.237491 -160.81908)
			(xy 130.245611 -160.874256) (xy 130.24612 -160.902142) (xy 130.245611 -160.930028) (xy 130.237491 -160.985204)
			(xy 130.221423 -161.038611) (xy 130.197751 -161.089108) (xy 130.166978 -161.135621) (xy 130.129761 -161.177158)
			(xy 130.086893 -161.212833) (xy 130.039287 -161.241887) (xy 129.987958 -161.263699) (xy 129.934001 -161.277805)
			(xy 129.878564 -161.283905) (xy 129.82283 -161.281868) (xy 129.767987 -161.271738) (xy 129.715203 -161.253731)
			(xy 129.665603 -161.22823) (xy 129.620245 -161.195779) (xy 129.580096 -161.15707) (xy 129.54601 -161.112927)
			(xy 129.518714 -161.064292) (xy 129.498791 -161.012201) (xy 129.486665 -160.957764) (xy 129.482594 -160.902142)
			(xy 128.458582 -160.902142) (xy 128.464309 -160.941058) (xy 128.464818 -160.968944) (xy 128.464309 -160.99683)
			(xy 128.456189 -161.052006) (xy 128.440121 -161.105413) (xy 128.416449 -161.15591) (xy 128.385676 -161.202423)
			(xy 128.348459 -161.24396) (xy 128.305591 -161.279635) (xy 128.257985 -161.308689) (xy 128.206656 -161.330501)
			(xy 128.152699 -161.344607) (xy 128.097262 -161.350707) (xy 128.041528 -161.34867) (xy 127.986685 -161.33854)
			(xy 127.933901 -161.320533) (xy 127.884301 -161.295032) (xy 127.838943 -161.262581) (xy 127.798794 -161.223872)
			(xy 127.764708 -161.179729) (xy 127.737412 -161.131094) (xy 127.717489 -161.079003) (xy 127.705363 -161.024566)
			(xy 127.701292 -160.968944) (xy 127.192947 -160.968944) (xy 127.192531 -160.99175) (xy 127.184411 -161.046926)
			(xy 127.168343 -161.100333) (xy 127.144671 -161.15083) (xy 127.113898 -161.197343) (xy 127.076681 -161.23888)
			(xy 127.033813 -161.274555) (xy 126.986207 -161.303609) (xy 126.934878 -161.325421) (xy 126.880921 -161.339527)
			(xy 126.825484 -161.345627) (xy 126.76975 -161.34359) (xy 126.714907 -161.33346) (xy 126.662123 -161.315453)
			(xy 126.612523 -161.289952) (xy 126.567165 -161.257501) (xy 126.527016 -161.218792) (xy 126.49293 -161.174649)
			(xy 126.465634 -161.126014) (xy 126.445711 -161.073923) (xy 126.433585 -161.019486) (xy 126.429514 -160.963864)
			(xy 125.801083 -160.963864) (xy 125.80112 -160.965896) (xy 125.800611 -160.993782) (xy 125.792491 -161.048958)
			(xy 125.776423 -161.102365) (xy 125.752751 -161.152862) (xy 125.721978 -161.199375) (xy 125.684761 -161.240912)
			(xy 125.641893 -161.276587) (xy 125.594287 -161.305641) (xy 125.542958 -161.327453) (xy 125.489001 -161.341559)
			(xy 125.433564 -161.347659) (xy 125.37783 -161.345622) (xy 125.322987 -161.335492) (xy 125.270203 -161.317485)
			(xy 125.220603 -161.291984) (xy 125.175245 -161.259533) (xy 125.135096 -161.220824) (xy 125.10101 -161.176681)
			(xy 125.073714 -161.128046) (xy 125.053791 -161.075955) (xy 125.041665 -161.021518) (xy 125.037594 -160.965896)
			(xy 78.688517 -160.965896) (xy 78.65872 -161.189924) (xy 78.65872 -161.190432) (xy 78.654656 -161.218626)
			(xy 78.654656 -161.219134) (xy 78.6511 -161.2392) (xy 78.487095 -162.131502) (xy 111.67313 -162.131502)
			(xy 111.677201 -162.07588) (xy 111.689327 -162.021443) (xy 111.70925 -161.969352) (xy 111.736546 -161.920717)
			(xy 111.770632 -161.876574) (xy 111.810781 -161.837865) (xy 111.856139 -161.805414) (xy 111.905739 -161.779913)
			(xy 111.958523 -161.761906) (xy 112.013366 -161.751776) (xy 112.0691 -161.749739) (xy 112.124537 -161.755839)
			(xy 112.178494 -161.769945) (xy 112.229823 -161.791757) (xy 112.252954 -161.805874) (xy 113.226848 -161.805874)
			(xy 113.230919 -161.750252) (xy 113.243045 -161.695815) (xy 113.262968 -161.643724) (xy 113.290264 -161.595089)
			(xy 113.32435 -161.550946) (xy 113.364499 -161.512237) (xy 113.409857 -161.479786) (xy 113.459457 -161.454285)
			(xy 113.512241 -161.436278) (xy 113.567084 -161.426148) (xy 113.622818 -161.424111) (xy 113.678255 -161.430211)
			(xy 113.732212 -161.444317) (xy 113.783541 -161.466129) (xy 113.831147 -161.495183) (xy 113.874015 -161.530858)
			(xy 113.911232 -161.572395) (xy 113.942005 -161.618908) (xy 113.965677 -161.669405) (xy 113.981745 -161.722812)
			(xy 113.989865 -161.777988) (xy 113.990374 -161.805874) (xy 113.989865 -161.83376) (xy 113.981745 -161.888936)
			(xy 113.965677 -161.942343) (xy 113.942005 -161.99284) (xy 113.911232 -162.039353) (xy 113.874015 -162.08089)
			(xy 113.831147 -162.116565) (xy 113.81125 -162.128708) (xy 115.561108 -162.128708) (xy 115.565179 -162.073086)
			(xy 115.577305 -162.018649) (xy 115.597228 -161.966558) (xy 115.624524 -161.917923) (xy 115.65861 -161.87378)
			(xy 115.698759 -161.835071) (xy 115.744117 -161.80262) (xy 115.793717 -161.777119) (xy 115.846501 -161.759112)
			(xy 115.901344 -161.748982) (xy 115.957078 -161.746945) (xy 116.012515 -161.753045) (xy 116.066472 -161.767151)
			(xy 116.117801 -161.788963) (xy 116.165407 -161.818017) (xy 116.208275 -161.853692) (xy 116.245492 -161.895229)
			(xy 116.276265 -161.941742) (xy 116.299937 -161.992239) (xy 116.316005 -162.045646) (xy 116.324125 -162.100822)
			(xy 116.324634 -162.128708) (xy 116.324125 -162.156594) (xy 116.316005 -162.21177) (xy 116.299937 -162.265177)
			(xy 116.276265 -162.315674) (xy 116.245492 -162.362187) (xy 116.208275 -162.403724) (xy 116.165407 -162.439399)
			(xy 116.117801 -162.468453) (xy 116.066472 -162.490265) (xy 116.012515 -162.504371) (xy 115.957078 -162.510471)
			(xy 115.901344 -162.508434) (xy 115.846501 -162.498304) (xy 115.793717 -162.480297) (xy 115.744117 -162.454796)
			(xy 115.698759 -162.422345) (xy 115.65861 -162.383636) (xy 115.624524 -162.339493) (xy 115.597228 -162.290858)
			(xy 115.577305 -162.238767) (xy 115.565179 -162.18433) (xy 115.561108 -162.128708) (xy 113.81125 -162.128708)
			(xy 113.783541 -162.145619) (xy 113.732212 -162.167431) (xy 113.678255 -162.181537) (xy 113.622818 -162.187637)
			(xy 113.567084 -162.1856) (xy 113.512241 -162.17547) (xy 113.459457 -162.157463) (xy 113.409857 -162.131962)
			(xy 113.364499 -162.099511) (xy 113.32435 -162.060802) (xy 113.290264 -162.016659) (xy 113.262968 -161.968024)
			(xy 113.243045 -161.915933) (xy 113.230919 -161.861496) (xy 113.226848 -161.805874) (xy 112.252954 -161.805874)
			(xy 112.277429 -161.820811) (xy 112.320297 -161.856486) (xy 112.357514 -161.898023) (xy 112.388287 -161.944536)
			(xy 112.411959 -161.995033) (xy 112.428027 -162.04844) (xy 112.436147 -162.103616) (xy 112.436656 -162.131502)
			(xy 112.436147 -162.159388) (xy 112.428027 -162.214564) (xy 112.411959 -162.267971) (xy 112.388287 -162.318468)
			(xy 112.357514 -162.364981) (xy 112.320297 -162.406518) (xy 112.277429 -162.442193) (xy 112.229823 -162.471247)
			(xy 112.178494 -162.493059) (xy 112.124537 -162.507165) (xy 112.0691 -162.513265) (xy 112.013366 -162.511228)
			(xy 111.958523 -162.501098) (xy 111.905739 -162.483091) (xy 111.856139 -162.45759) (xy 111.810781 -162.425139)
			(xy 111.770632 -162.38643) (xy 111.736546 -162.342287) (xy 111.70925 -162.293652) (xy 111.689327 -162.241561)
			(xy 111.677201 -162.187124) (xy 111.67313 -162.131502) (xy 78.487095 -162.131502) (xy 78.251475 -163.41344)
			(xy 113.15268 -163.41344) (xy 113.156751 -163.357818) (xy 113.168877 -163.303381) (xy 113.1888 -163.25129)
			(xy 113.216096 -163.202655) (xy 113.250182 -163.158512) (xy 113.290331 -163.119803) (xy 113.335689 -163.087352)
			(xy 113.385289 -163.061851) (xy 113.438073 -163.043844) (xy 113.492916 -163.033714) (xy 113.54865 -163.031677)
			(xy 113.604087 -163.037777) (xy 113.658044 -163.051883) (xy 113.709373 -163.073695) (xy 113.756979 -163.102749)
			(xy 113.771383 -163.114736) (xy 132.149594 -163.114736) (xy 132.153665 -163.059114) (xy 132.165791 -163.004677)
			(xy 132.185714 -162.952586) (xy 132.21301 -162.903951) (xy 132.247096 -162.859808) (xy 132.287245 -162.821099)
			(xy 132.332603 -162.788648) (xy 132.382203 -162.763147) (xy 132.434987 -162.74514) (xy 132.48983 -162.73501)
			(xy 132.545564 -162.732973) (xy 132.601001 -162.739073) (xy 132.654958 -162.753179) (xy 132.706287 -162.774991)
			(xy 132.753893 -162.804045) (xy 132.796761 -162.83972) (xy 132.833978 -162.881257) (xy 132.864751 -162.92777)
			(xy 132.888423 -162.978267) (xy 132.904491 -163.031674) (xy 132.912611 -163.08685) (xy 132.91312 -163.114736)
			(xy 132.912611 -163.142622) (xy 132.904491 -163.197798) (xy 132.888423 -163.251205) (xy 132.864751 -163.301702)
			(xy 132.833978 -163.348215) (xy 132.796761 -163.389752) (xy 132.753893 -163.425427) (xy 132.706287 -163.454481)
			(xy 132.654958 -163.476293) (xy 132.601001 -163.490399) (xy 132.545564 -163.496499) (xy 132.48983 -163.494462)
			(xy 132.434987 -163.484332) (xy 132.382203 -163.466325) (xy 132.332603 -163.440824) (xy 132.287245 -163.408373)
			(xy 132.247096 -163.369664) (xy 132.21301 -163.325521) (xy 132.185714 -163.276886) (xy 132.165791 -163.224795)
			(xy 132.153665 -163.170358) (xy 132.149594 -163.114736) (xy 113.771383 -163.114736) (xy 113.799847 -163.138424)
			(xy 113.837064 -163.179961) (xy 113.867837 -163.226474) (xy 113.891509 -163.276971) (xy 113.907577 -163.330378)
			(xy 113.915697 -163.385554) (xy 113.916206 -163.41344) (xy 113.915697 -163.441326) (xy 113.907577 -163.496502)
			(xy 113.891509 -163.549909) (xy 113.867837 -163.600406) (xy 113.837064 -163.646919) (xy 113.799847 -163.688456)
			(xy 113.756979 -163.724131) (xy 113.709373 -163.753185) (xy 113.658044 -163.774997) (xy 113.604087 -163.789103)
			(xy 113.54865 -163.795203) (xy 113.492916 -163.793166) (xy 113.438073 -163.783036) (xy 113.385289 -163.765029)
			(xy 113.335689 -163.739528) (xy 113.290331 -163.707077) (xy 113.250182 -163.668368) (xy 113.216096 -163.624225)
			(xy 113.1888 -163.57559) (xy 113.168877 -163.523499) (xy 113.156751 -163.469062) (xy 113.15268 -163.41344)
			(xy 78.251475 -163.41344) (xy 78.126546 -164.093144) (xy 121.833892 -164.093144) (xy 121.837963 -164.037522)
			(xy 121.850089 -163.983085) (xy 121.870012 -163.930994) (xy 121.897308 -163.882359) (xy 121.931394 -163.838216)
			(xy 121.971543 -163.799507) (xy 122.016901 -163.767056) (xy 122.066501 -163.741555) (xy 122.119285 -163.723548)
			(xy 122.174128 -163.713418) (xy 122.229862 -163.711381) (xy 122.285299 -163.717481) (xy 122.339256 -163.731587)
			(xy 122.390585 -163.753399) (xy 122.438191 -163.782453) (xy 122.481059 -163.818128) (xy 122.518276 -163.859665)
			(xy 122.549049 -163.906178) (xy 122.572721 -163.956675) (xy 122.588789 -164.010082) (xy 122.596909 -164.065258)
			(xy 122.597418 -164.093144) (xy 122.596909 -164.12103) (xy 122.588789 -164.176206) (xy 122.572721 -164.229613)
			(xy 122.549049 -164.28011) (xy 122.518276 -164.326623) (xy 122.481059 -164.36816) (xy 122.438191 -164.403835)
			(xy 122.390585 -164.432889) (xy 122.339256 -164.454701) (xy 122.285299 -164.468807) (xy 122.229862 -164.474907)
			(xy 122.174128 -164.47287) (xy 122.119285 -164.46274) (xy 122.066501 -164.444733) (xy 122.016901 -164.419232)
			(xy 121.971543 -164.386781) (xy 121.931394 -164.348072) (xy 121.897308 -164.303929) (xy 121.870012 -164.255294)
			(xy 121.850089 -164.203203) (xy 121.837963 -164.148766) (xy 121.833892 -164.093144) (xy 78.126546 -164.093144)
			(xy 77.592422 -166.999158) (xy 121.98096 -166.999158) (xy 121.98145 -166.972249) (xy 121.989032 -166.918967)
			(xy 122.004023 -166.867278) (xy 122.026129 -166.818209) (xy 122.054909 -166.772732) (xy 122.089793 -166.73175)
			(xy 122.130089 -166.696075) (xy 122.174997 -166.666415) (xy 122.223628 -166.64336) (xy 122.249184 -166.634922)
			(xy 122.249438 -166.634922) (xy 122.255133 -166.632947) (xy 122.265407 -166.626648) (xy 122.269758 -166.622476)
			(xy 123.520962 -165.371272) (xy 123.53973 -165.353237) (xy 123.581848 -165.322658) (xy 123.628225 -165.299032)
			(xy 123.677723 -165.282938) (xy 123.729126 -165.274771) (xy 123.75515 -165.274244) (xy 136.091422 -165.274244)
			(xy 136.117446 -165.274766) (xy 136.168851 -165.282931) (xy 136.218348 -165.299025) (xy 136.264725 -165.322654)
			(xy 136.30684 -165.353238) (xy 136.32561 -165.371272) (xy 138.016488 -167.06215) (xy 138.03451 -167.08093)
			(xy 138.065092 -167.123044) (xy 138.088722 -167.169418) (xy 138.104818 -167.218913) (xy 138.112988 -167.270315)
			(xy 138.113516 -167.296338) (xy 138.113516 -168.022016) (xy 139.692632 -168.022016) (xy 139.696703 -167.966394)
			(xy 139.708829 -167.911957) (xy 139.728752 -167.859866) (xy 139.756048 -167.811231) (xy 139.790134 -167.767088)
			(xy 139.830283 -167.728379) (xy 139.875641 -167.695928) (xy 139.925241 -167.670427) (xy 139.978025 -167.65242)
			(xy 140.032868 -167.64229) (xy 140.088602 -167.640253) (xy 140.144039 -167.646353) (xy 140.197996 -167.660459)
			(xy 140.249325 -167.682271) (xy 140.296931 -167.711325) (xy 140.339799 -167.747) (xy 140.377016 -167.788537)
			(xy 140.407789 -167.83505) (xy 140.431461 -167.885547) (xy 140.447529 -167.938954) (xy 140.455649 -167.99413)
			(xy 140.456158 -168.022016) (xy 140.455649 -168.049902) (xy 140.447529 -168.105078) (xy 140.431461 -168.158485)
			(xy 140.407789 -168.208982) (xy 140.377016 -168.255495) (xy 140.339799 -168.297032) (xy 140.296931 -168.332707)
			(xy 140.249325 -168.361761) (xy 140.197996 -168.383573) (xy 140.144039 -168.397679) (xy 140.088602 -168.403779)
			(xy 140.032868 -168.401742) (xy 139.978025 -168.391612) (xy 139.925241 -168.373605) (xy 139.875641 -168.348104)
			(xy 139.830283 -168.315653) (xy 139.790134 -168.276944) (xy 139.756048 -168.232801) (xy 139.728752 -168.184166)
			(xy 139.708829 -168.132075) (xy 139.696703 -168.077638) (xy 139.692632 -168.022016) (xy 138.113516 -168.022016)
			(xy 138.113516 -170.863768) (xy 138.113006 -170.889792) (xy 138.104836 -170.941197) (xy 138.088737 -170.990694)
			(xy 138.065106 -171.03707) (xy 138.034522 -171.079186) (xy 138.016488 -171.097956) (xy 134.203186 -174.911258)
			(xy 134.19637 -174.918677) (xy 134.188637 -174.937262) (xy 134.1882 -174.947326) (xy 134.1882 -175.46955)
			(xy 134.188488 -175.478169) (xy 134.194158 -175.494444) (xy 134.204934 -175.507895) (xy 134.212076 -175.51273)
			(xy 134.285228 -175.558196) (xy 134.292691 -175.562514) (xy 134.309509 -175.566275) (xy 134.326622 -175.564235)
			(xy 134.334504 -175.560736) (xy 134.359024 -175.549282) (xy 134.410667 -175.5331) (xy 134.464163 -175.524916)
			(xy 134.491222 -175.524414) (xy 134.519207 -175.524921) (xy 134.574487 -175.53368) (xy 134.627716 -175.550979)
			(xy 134.677584 -175.576391) (xy 134.722862 -175.609292) (xy 134.762436 -175.648871) (xy 134.795332 -175.694154)
			(xy 134.820738 -175.744025) (xy 134.838031 -175.797256) (xy 134.846783 -175.852537) (xy 134.84733 -175.880522)
			(xy 134.84733 -175.880776) (xy 134.846797 -175.908071) (xy 134.838433 -175.962017) (xy 134.821943 -176.014058)
			(xy 134.797713 -176.062977) (xy 134.766309 -176.107631) (xy 134.747762 -176.127664) (xy 134.74065 -176.13503)
			(xy 134.733538 -176.15281) (xy 134.733538 -176.243234) (xy 134.74065 -176.261014) (xy 134.747762 -176.26838)
			(xy 134.766351 -176.288415) (xy 134.797812 -176.333101) (xy 134.822066 -176.382074) (xy 134.838543 -176.434182)
			(xy 134.846855 -176.488196) (xy 134.84733 -176.515522) (xy 134.846814 -176.542843) (xy 134.838474 -176.596844)
			(xy 134.821991 -176.64894) (xy 134.797752 -176.697912) (xy 134.766325 -176.742611) (xy 134.747762 -176.762664)
			(xy 134.74065 -176.77003) (xy 134.733538 -176.78781) (xy 134.733538 -176.878234) (xy 134.74065 -176.896014)
			(xy 134.747762 -176.90338) (xy 134.759872 -176.916312) (xy 134.78176 -176.944174) (xy 134.79145 -176.959006)
			(xy 134.79145 -176.95926) (xy 134.798179 -176.968436) (xy 134.817555 -176.980309) (xy 134.828788 -176.98212)
			(xy 134.907528 -176.99101) (xy 134.918942 -176.991573) (xy 134.940444 -176.983931) (xy 134.94893 -176.976278)
			(xy 136.782302 -175.14316) (xy 136.788961 -175.135907) (xy 136.796642 -175.117797) (xy 136.796902 -175.098127)
			(xy 136.793732 -175.088804) (xy 136.754362 -174.987712) (xy 136.730232 -174.97044) (xy 136.714992 -174.969678)
			(xy 136.68405 -174.967709) (xy 136.62337 -174.954992) (xy 136.565552 -174.932615) (xy 136.512122 -174.901169)
			(xy 136.487916 -174.881794) (xy 136.48055 -174.875698) (xy 136.462516 -174.869602) (xy 136.38403 -174.873666)
			(xy 136.374546 -174.874564) (xy 136.357191 -174.882385) (xy 136.350248 -174.888906) (xy 136.332263 -174.906761)
			(xy 136.292345 -174.937986) (xy 136.248645 -174.963651) (xy 136.201931 -174.983304) (xy 136.153026 -174.996599)
			(xy 136.102792 -175.003303) (xy 136.077452 -175.003714) (xy 136.050203 -175.003213) (xy 135.996262 -174.995451)
			(xy 135.943974 -174.980092) (xy 135.894403 -174.957448) (xy 135.848559 -174.927981) (xy 135.807376 -174.89229)
			(xy 135.77169 -174.851102) (xy 135.742229 -174.805255) (xy 135.719591 -174.755681) (xy 135.704239 -174.703391)
			(xy 135.696484 -174.649449) (xy 135.696484 -174.594951) (xy 135.704239 -174.541009) (xy 135.719591 -174.488719)
			(xy 135.742229 -174.439145) (xy 135.77169 -174.393298) (xy 135.807376 -174.35211) (xy 135.848559 -174.316419)
			(xy 135.894403 -174.286952) (xy 135.943974 -174.264308) (xy 135.996262 -174.248949) (xy 136.050203 -174.241187)
			(xy 136.077452 -174.240698) (xy 136.077706 -174.240698) (xy 136.104205 -174.241155) (xy 136.15669 -174.248524)
			(xy 136.207652 -174.263076) (xy 136.256114 -174.284534) (xy 136.301143 -174.312484) (xy 136.3218 -174.32909)
			(xy 136.329166 -174.335186) (xy 136.3472 -174.341282) (xy 136.425686 -174.337218) (xy 136.435172 -174.336332)
			(xy 136.452526 -174.328503) (xy 136.459468 -174.321978) (xy 136.477489 -174.304161) (xy 136.517399 -174.272933)
			(xy 136.561092 -174.247263) (xy 136.607799 -174.227604) (xy 136.656697 -174.2143) (xy 136.706926 -174.207587)
			(xy 136.732264 -174.20717) (xy 136.75872 -174.207702) (xy 136.811121 -174.215035) (xy 136.862007 -174.229539)
			(xy 136.910401 -174.250934) (xy 136.955374 -174.278811) (xy 136.996064 -174.312634) (xy 137.03169 -174.351756)
			(xy 137.061569 -174.395424) (xy 137.085128 -174.442802) (xy 137.101915 -174.492981) (xy 137.111607 -174.544998)
			(xy 137.113264 -174.571406) (xy 137.114026 -174.586646) (xy 137.131298 -174.610776) (xy 137.23239 -174.650146)
			(xy 137.241721 -174.653229) (xy 137.261352 -174.652906) (xy 137.279453 -174.645302) (xy 137.286746 -174.638716)
			(xy 139.08278 -172.842682) (xy 139.089649 -172.835178) (xy 139.097342 -172.816365) (xy 139.0971 -172.796042)
			(xy 139.093448 -172.786548) (xy 139.055856 -172.69968) (xy 139.051448 -172.690518) (xy 139.036761 -172.676479)
			(xy 139.017765 -172.669272) (xy 139.007596 -172.6692) (xy 138.995912 -172.669454) (xy 138.995404 -172.669454)
			(xy 138.968166 -172.668944) (xy 138.914248 -172.661154) (xy 138.861987 -172.645773) (xy 138.812444 -172.623116)
			(xy 138.766628 -172.593643) (xy 138.72547 -172.557953) (xy 138.689807 -172.516771) (xy 138.660364 -172.470936)
			(xy 138.637739 -172.421379) (xy 138.622393 -172.369107) (xy 138.614638 -172.315185) (xy 138.61415 -172.287946)
			(xy 138.614589 -172.261333) (xy 138.621988 -172.208624) (xy 138.636648 -172.157457) (xy 138.658284 -172.108828)
			(xy 138.686476 -172.063681) (xy 138.720674 -172.022896) (xy 138.740134 -172.004736) (xy 138.748008 -171.997624)
			(xy 138.756644 -171.978574) (xy 138.758168 -171.88307) (xy 138.750294 -171.863766) (xy 138.742674 -171.8564)
			(xy 138.724675 -171.838349) (xy 138.693109 -171.798322) (xy 138.667154 -171.754449) (xy 138.647271 -171.707511)
			(xy 138.633814 -171.658343) (xy 138.627022 -171.607822) (xy 138.626596 -171.582334) (xy 138.627082 -171.555083)
			(xy 138.634838 -171.501135) (xy 138.650193 -171.44884) (xy 138.672835 -171.399263) (xy 138.702301 -171.353413)
			(xy 138.737992 -171.312222) (xy 138.779183 -171.276531) (xy 138.825033 -171.247065) (xy 138.87461 -171.224423)
			(xy 138.926905 -171.209068) (xy 138.980853 -171.201312) (xy 139.035355 -171.201312) (xy 139.089303 -171.209068)
			(xy 139.141598 -171.224423) (xy 139.191175 -171.247065) (xy 139.237025 -171.276531) (xy 139.278216 -171.312222)
			(xy 139.313907 -171.353413) (xy 139.343373 -171.399263) (xy 139.366015 -171.44884) (xy 139.38137 -171.501135)
			(xy 139.389126 -171.555083) (xy 139.389612 -171.582334) (xy 139.389172 -171.608947) (xy 139.381775 -171.661656)
			(xy 139.367116 -171.712824) (xy 139.34548 -171.761454) (xy 139.317288 -171.8066) (xy 139.283089 -171.847385)
			(xy 139.263628 -171.865544) (xy 139.255754 -171.872656) (xy 139.247118 -171.891706) (xy 139.245594 -171.98721)
			(xy 139.253468 -172.006514) (xy 139.261088 -172.01388) (xy 139.279089 -172.031929) (xy 139.310652 -172.071958)
			(xy 139.336606 -172.115832) (xy 139.356488 -172.16277) (xy 139.369946 -172.211937) (xy 139.376738 -172.262458)
			(xy 139.377166 -172.287946) (xy 139.376749 -172.312286) (xy 139.370506 -172.360566) (xy 139.36472 -172.384212)
			(xy 139.36472 -172.384466) (xy 139.362945 -172.392956) (xy 139.364479 -172.410218) (xy 139.37166 -172.42599)
			(xy 139.37742 -172.432472) (xy 139.447778 -172.504608) (xy 139.473178 -172.511974) (xy 139.486386 -172.508926)
			(xy 139.505159 -172.504757) (xy 139.543357 -172.5003) (xy 139.562586 -172.500036) (xy 142.984982 -172.500036)
			(xy 143.011005 -172.500585) (xy 143.062408 -172.508744) (xy 143.111905 -172.524832) (xy 143.158282 -172.548455)
			(xy 143.200399 -172.579033) (xy 143.21917 -172.597064) (xy 145.139664 -174.517558) (xy 145.157704 -174.536322)
			(xy 145.18828 -174.578442) (xy 145.211905 -174.62482) (xy 145.227998 -174.674318) (xy 145.236164 -174.725722)
			(xy 145.236692 -174.751746) (xy 145.236692 -184.967626) (xy 146.063206 -184.967626) (xy 146.067277 -184.912004)
			(xy 146.079403 -184.857567) (xy 146.099326 -184.805476) (xy 146.126622 -184.756841) (xy 146.160708 -184.712698)
			(xy 146.200857 -184.673989) (xy 146.246215 -184.641538) (xy 146.295815 -184.616037) (xy 146.348599 -184.59803)
			(xy 146.403442 -184.5879) (xy 146.459176 -184.585863) (xy 146.514613 -184.591963) (xy 146.56857 -184.606069)
			(xy 146.619899 -184.627881) (xy 146.667505 -184.656935) (xy 146.710373 -184.69261) (xy 146.74759 -184.734147)
			(xy 146.778363 -184.78066) (xy 146.802035 -184.831157) (xy 146.818103 -184.884564) (xy 146.826223 -184.93974)
			(xy 146.826732 -184.967626) (xy 146.826223 -184.995512) (xy 146.818103 -185.050688) (xy 146.802035 -185.104095)
			(xy 146.778363 -185.154592) (xy 146.74759 -185.201105) (xy 146.710373 -185.242642) (xy 146.667505 -185.278317)
			(xy 146.619899 -185.307371) (xy 146.56857 -185.329183) (xy 146.514613 -185.343289) (xy 146.459176 -185.349389)
			(xy 146.403442 -185.347352) (xy 146.348599 -185.337222) (xy 146.295815 -185.319215) (xy 146.246215 -185.293714)
			(xy 146.200857 -185.261263) (xy 146.160708 -185.222554) (xy 146.126622 -185.178411) (xy 146.099326 -185.129776)
			(xy 146.079403 -185.077685) (xy 146.067277 -185.023248) (xy 146.063206 -184.967626) (xy 145.236692 -184.967626)
			(xy 145.236692 -186.059318) (xy 145.916648 -186.059318) (xy 145.920719 -186.003696) (xy 145.932845 -185.949259)
			(xy 145.952768 -185.897168) (xy 145.980064 -185.848533) (xy 146.01415 -185.80439) (xy 146.054299 -185.765681)
			(xy 146.099657 -185.73323) (xy 146.149257 -185.707729) (xy 146.202041 -185.689722) (xy 146.256884 -185.679592)
			(xy 146.312618 -185.677555) (xy 146.368055 -185.683655) (xy 146.422012 -185.697761) (xy 146.473341 -185.719573)
			(xy 146.520947 -185.748627) (xy 146.563815 -185.784302) (xy 146.601032 -185.825839) (xy 146.631805 -185.872352)
			(xy 146.655477 -185.922849) (xy 146.671545 -185.976256) (xy 146.679665 -186.031432) (xy 146.680174 -186.059318)
			(xy 146.679665 -186.087204) (xy 146.671545 -186.14238) (xy 146.655477 -186.195787) (xy 146.631805 -186.246284)
			(xy 146.601032 -186.292797) (xy 146.563815 -186.334334) (xy 146.520947 -186.370009) (xy 146.473341 -186.399063)
			(xy 146.422012 -186.420875) (xy 146.368055 -186.434981) (xy 146.312618 -186.441081) (xy 146.256884 -186.439044)
			(xy 146.202041 -186.428914) (xy 146.149257 -186.410907) (xy 146.099657 -186.385406) (xy 146.054299 -186.352955)
			(xy 146.01415 -186.314246) (xy 145.980064 -186.270103) (xy 145.952768 -186.221468) (xy 145.932845 -186.169377)
			(xy 145.920719 -186.11494) (xy 145.916648 -186.059318) (xy 145.236692 -186.059318) (xy 145.236692 -188.855858)
			(xy 145.237115 -188.865928) (xy 145.244835 -188.884527) (xy 145.251678 -188.891926) (xy 145.832322 -189.472316)
			(xy 145.836716 -189.476431) (xy 145.84698 -189.482717) (xy 145.852642 -189.484762) (xy 145.85315 -189.484762)
			(xy 145.878692 -189.493215) (xy 145.927297 -189.516284) (xy 145.972178 -189.545953) (xy 146.012446 -189.581633)
			(xy 146.047302 -189.622617) (xy 146.076054 -189.66809) (xy 146.098133 -189.717152) (xy 146.1131 -189.76883)
			(xy 146.120659 -189.822097) (xy 146.12112 -189.848998) (xy 146.12062 -189.876249) (xy 146.112864 -189.930195)
			(xy 146.09751 -189.982489) (xy 146.07487 -190.032065) (xy 146.045405 -190.077915) (xy 146.009715 -190.119105)
			(xy 145.968527 -190.154797) (xy 145.922678 -190.184263) (xy 145.873102 -190.206905) (xy 145.820809 -190.222261)
			(xy 145.766863 -190.230019) (xy 145.739612 -190.230506) (xy 145.712703 -190.229992) (xy 145.659421 -190.222417)
			(xy 145.607732 -190.207431) (xy 145.558662 -190.18533) (xy 145.513184 -190.156553) (xy 145.472201 -190.121671)
			(xy 145.436526 -190.081376) (xy 145.406867 -190.036468) (xy 145.383813 -189.987838) (xy 145.375376 -189.962282)
			(xy 145.375376 -189.962028) (xy 145.3734 -189.956334) (xy 145.367101 -189.94606) (xy 145.36293 -189.941708)
			(xy 144.670272 -189.24905) (xy 144.652243 -189.230277) (xy 144.621663 -189.18816) (xy 144.598036 -189.141784)
			(xy 144.581941 -189.092288) (xy 144.573772 -189.040885) (xy 144.573244 -189.014862) (xy 144.573244 -188.970666)
			(xy 144.556226 -188.945012) (xy 144.541748 -188.93917) (xy 144.532357 -188.935825) (xy 144.512443 -188.935825)
			(xy 144.494032 -188.943415) (xy 144.48663 -188.950092) (xy 143.694658 -189.74181) (xy 143.687815 -189.749208)
			(xy 143.680098 -189.767809) (xy 143.679672 -189.777878) (xy 143.679672 -190.19901) (xy 143.680105 -190.209054)
			(xy 143.687811 -190.227607) (xy 143.70204 -190.241787) (xy 143.711168 -190.246) (xy 143.812768 -190.287402)
			(xy 143.842994 -190.281306) (xy 143.853916 -190.27013) (xy 143.871924 -190.252299) (xy 143.911836 -190.221071)
			(xy 143.955532 -190.195402) (xy 144.002241 -190.175744) (xy 144.051142 -190.162444) (xy 144.101373 -190.155736)
			(xy 144.126712 -190.155322) (xy 144.153965 -190.155749) (xy 144.207916 -190.163507) (xy 144.260213 -190.178865)
			(xy 144.309793 -190.201508) (xy 144.355645 -190.230977) (xy 144.396837 -190.266671) (xy 144.43253 -190.307865)
			(xy 144.461998 -190.353718) (xy 144.48464 -190.403298) (xy 144.499995 -190.455596) (xy 144.507752 -190.509547)
			(xy 144.507752 -190.564053) (xy 144.499995 -190.618004) (xy 144.48464 -190.670302) (xy 144.461998 -190.719882)
			(xy 144.43253 -190.765735) (xy 144.396837 -190.806929) (xy 144.355645 -190.842623) (xy 144.309793 -190.872092)
			(xy 144.260213 -190.894735) (xy 144.207916 -190.910093) (xy 144.153965 -190.917851) (xy 144.126712 -190.918338)
			(xy 144.101374 -190.917904) (xy 144.051145 -190.911197) (xy 144.002245 -190.8979) (xy 143.955536 -190.878245)
			(xy 143.91184 -190.85258) (xy 143.871927 -190.821357) (xy 143.853916 -190.80353) (xy 143.842994 -190.792354)
			(xy 143.812768 -190.786258) (xy 143.711168 -190.82766) (xy 143.702052 -190.831895) (xy 143.687819 -190.846066)
			(xy 143.680104 -190.864609) (xy 143.679672 -190.87465) (xy 143.679672 -191.094106) (xy 144.407634 -191.094106)
			(xy 144.411705 -191.038484) (xy 144.423831 -190.984047) (xy 144.443754 -190.931956) (xy 144.47105 -190.883321)
			(xy 144.505136 -190.839178) (xy 144.545285 -190.800469) (xy 144.590643 -190.768018) (xy 144.640243 -190.742517)
			(xy 144.693027 -190.72451) (xy 144.74787 -190.71438) (xy 144.803604 -190.712343) (xy 144.859041 -190.718443)
			(xy 144.912998 -190.732549) (xy 144.964327 -190.754361) (xy 145.011933 -190.783415) (xy 145.054801 -190.81909)
			(xy 145.092018 -190.860627) (xy 145.122791 -190.90714) (xy 145.146463 -190.957637) (xy 145.162531 -191.011044)
			(xy 145.170651 -191.06622) (xy 145.17116 -191.094106) (xy 145.170651 -191.121992) (xy 145.162531 -191.177168)
			(xy 145.146463 -191.230575) (xy 145.122791 -191.281072) (xy 145.092018 -191.327585) (xy 145.054801 -191.369122)
			(xy 145.011933 -191.404797) (xy 144.964327 -191.433851) (xy 144.912998 -191.455663) (xy 144.859041 -191.469769)
			(xy 144.803604 -191.475869) (xy 144.74787 -191.473832) (xy 144.693027 -191.463702) (xy 144.640243 -191.445695)
			(xy 144.590643 -191.420194) (xy 144.545285 -191.387743) (xy 144.505136 -191.349034) (xy 144.47105 -191.304891)
			(xy 144.443754 -191.256256) (xy 144.423831 -191.204165) (xy 144.411705 -191.149728) (xy 144.407634 -191.094106)
			(xy 143.679672 -191.094106) (xy 143.679672 -192.325498) (xy 143.679862 -192.331648) (xy 143.682817 -192.343589)
			(xy 143.685514 -192.34912) (xy 143.699327 -192.376658) (xy 143.718899 -192.435069) (xy 143.728841 -192.495865)
			(xy 143.729456 -192.526666) (xy 143.72897 -192.553917) (xy 143.721214 -192.607865) (xy 143.705859 -192.66016)
			(xy 143.683217 -192.709737) (xy 143.653751 -192.755587) (xy 143.61806 -192.796778) (xy 143.576869 -192.832469)
			(xy 143.531019 -192.861935) (xy 143.481442 -192.884577) (xy 143.429147 -192.899932) (xy 143.375199 -192.907688)
			(xy 143.320697 -192.907688) (xy 143.266749 -192.899932) (xy 143.214454 -192.884577) (xy 143.164877 -192.861935)
			(xy 143.119027 -192.832469) (xy 143.077836 -192.796778) (xy 143.042145 -192.755587) (xy 143.012679 -192.709737)
			(xy 142.990037 -192.66016) (xy 142.974682 -192.607865) (xy 142.966926 -192.553917) (xy 142.96644 -192.526666)
			(xy 142.967038 -192.495863) (xy 142.976968 -192.435061) (xy 142.996546 -192.376648) (xy 143.010382 -192.34912)
			(xy 143.013089 -192.343592) (xy 143.016051 -192.33165) (xy 143.016224 -192.325498) (xy 143.016224 -189.945264)
			(xy 142.999206 -189.91961) (xy 142.984728 -189.913768) (xy 142.975342 -189.910405) (xy 142.955424 -189.910412)
			(xy 142.937011 -189.918009) (xy 142.92961 -189.92469) (xy 142.045436 -190.808864) (xy 142.041318 -190.813256)
			(xy 142.035034 -190.823521) (xy 142.03299 -190.829184) (xy 142.03299 -190.829692) (xy 142.024517 -190.855227)
			(xy 142.001446 -190.903828) (xy 141.971778 -190.948706) (xy 141.9361 -190.988972) (xy 141.895119 -191.023827)
			(xy 141.849649 -191.052581) (xy 141.800591 -191.074662) (xy 141.748917 -191.089633) (xy 141.695653 -191.097198)
			(xy 141.668754 -191.097662) (xy 141.6415 -191.097265) (xy 141.587546 -191.089501) (xy 141.535247 -191.074138)
			(xy 141.485667 -191.051488) (xy 141.439814 -191.022012) (xy 141.398623 -190.986312) (xy 141.362932 -190.945112)
			(xy 141.333468 -190.899253) (xy 141.31083 -190.849667) (xy 141.29548 -190.797364) (xy 141.287729 -190.743409)
			(xy 141.287246 -190.716154) (xy 141.287743 -190.689245) (xy 141.295324 -190.635964) (xy 141.310316 -190.584276)
			(xy 141.332421 -190.535207) (xy 141.3612 -190.489731) (xy 141.396083 -190.448748) (xy 141.436378 -190.413073)
			(xy 141.481285 -190.383413) (xy 141.529914 -190.360356) (xy 141.55547 -190.351918) (xy 141.555724 -190.351918)
			(xy 141.561418 -190.34994) (xy 141.571693 -190.343643) (xy 141.576044 -190.339472) (xy 143.692626 -188.223144)
			(xy 143.699443 -188.215726) (xy 143.707176 -188.19714) (xy 143.707612 -188.187076) (xy 143.707612 -184.639458)
			(xy 143.707232 -184.629383) (xy 143.699482 -184.610784) (xy 143.692626 -184.60339) (xy 142.750286 -183.661304)
			(xy 142.745888 -183.657193) (xy 142.735627 -183.650905) (xy 142.729966 -183.648858) (xy 142.729458 -183.648858)
			(xy 142.704237 -183.64055) (xy 142.656219 -183.617877) (xy 142.61181 -183.588763) (xy 142.571868 -183.55377)
			(xy 142.537167 -183.513576) (xy 142.508376 -183.468957) (xy 142.486052 -183.420775) (xy 142.470627 -183.369963)
			(xy 142.46606 -183.343804) (xy 142.464028 -183.330088) (xy 142.446756 -183.309006) (xy 142.35049 -183.273192)
			(xy 142.341985 -183.270451) (xy 142.324127 -183.270396) (xy 142.307318 -183.276426) (xy 142.300198 -183.281828)
			(xy 142.29969 -183.282336) (xy 142.274795 -183.302764) (xy 142.220337 -183.337135) (xy 142.161597 -183.363532)
			(xy 142.099737 -183.381434) (xy 142.035979 -183.390487) (xy 142.00378 -183.391048) (xy 141.973824 -183.390538)
			(xy 141.914425 -183.382718) (xy 141.856553 -183.367216) (xy 141.801199 -183.344296) (xy 141.749308 -183.31435)
			(xy 141.701768 -183.277889) (xy 141.659392 -183.235538) (xy 141.622903 -183.18802) (xy 141.592925 -183.136147)
			(xy 141.569972 -183.080806) (xy 141.554435 -183.022944) (xy 141.54658 -182.96355) (xy 141.546072 -182.933594)
			(xy 141.546072 -182.069486) (xy 141.546562 -182.039518) (xy 141.554385 -181.980096) (xy 141.569898 -181.922203)
			(xy 141.592834 -181.86683) (xy 141.622801 -181.814924) (xy 141.659288 -181.767374) (xy 141.701668 -181.724994)
			(xy 141.749218 -181.688507) (xy 141.801124 -181.65854) (xy 141.856497 -181.635604) (xy 141.91439 -181.620091)
			(xy 141.973812 -181.612268) (xy 142.033748 -181.612268) (xy 142.09317 -181.620091) (xy 142.151063 -181.635604)
			(xy 142.206436 -181.65854) (xy 142.258342 -181.688507) (xy 142.305892 -181.724994) (xy 142.348272 -181.767374)
			(xy 142.384759 -181.814924) (xy 142.414726 -181.86683) (xy 142.437662 -181.922203) (xy 142.453175 -181.980096)
			(xy 142.460998 -182.039518) (xy 142.461488 -182.069486) (xy 142.461488 -182.933086) (xy 142.461368 -182.951323)
			(xy 142.458569 -182.987689) (xy 142.4559 -183.00573) (xy 142.45482 -183.015233) (xy 142.458872 -183.033903)
			(xy 142.469488 -183.049788) (xy 142.485187 -183.060676) (xy 142.503785 -183.065049) (xy 142.522692 -183.0623)
			(xy 142.539274 -183.05281) (xy 142.545562 -183.045608) (xy 142.563811 -183.023798) (xy 142.605621 -182.985255)
			(xy 142.652687 -182.953343) (xy 142.703968 -182.928769) (xy 142.758328 -182.912078) (xy 142.814564 -182.903639)
			(xy 142.842996 -182.903114) (xy 142.869906 -182.903607) (xy 142.923189 -182.911183) (xy 142.97488 -182.926172)
			(xy 143.023951 -182.948275) (xy 143.069429 -182.977055) (xy 143.110412 -183.01194) (xy 143.146086 -183.052237)
			(xy 143.175744 -183.097148) (xy 143.198797 -183.14578) (xy 143.207232 -183.171338) (xy 143.207232 -183.171592)
			(xy 143.209229 -183.177278) (xy 143.215513 -183.187557) (xy 143.219678 -183.191912) (xy 144.135602 -184.107836)
			(xy 144.165574 -184.113678) (xy 144.179798 -184.107836) (xy 144.188852 -184.103562) (xy 144.202933 -184.089348)
			(xy 144.210554 -184.070849) (xy 144.21104 -184.060846) (xy 144.21104 -175.060864) (xy 144.210649 -175.050791)
			(xy 144.202906 -175.032192) (xy 144.196054 -175.024796) (xy 142.711932 -173.540674) (xy 142.704518 -173.533852)
			(xy 142.685929 -173.526122) (xy 142.675864 -173.525688) (xy 142.466568 -173.525688) (xy 142.457412 -173.526118)
			(xy 142.440292 -173.532633) (xy 142.42653 -173.544722) (xy 142.421864 -173.552612) (xy 142.373096 -173.64456)
			(xy 142.37462 -173.672754) (xy 142.382494 -173.684184) (xy 142.397497 -173.706968) (xy 142.42255 -173.755431)
			(xy 142.441664 -173.806528) (xy 142.454569 -173.859535) (xy 142.46108 -173.913701) (xy 142.461488 -173.940978)
			(xy 142.461488 -174.805086) (xy 142.460998 -174.835054) (xy 142.453175 -174.894476) (xy 142.437662 -174.952369)
			(xy 142.414726 -175.007742) (xy 142.384759 -175.059648) (xy 142.348272 -175.107198) (xy 142.305892 -175.149578)
			(xy 142.258342 -175.186065) (xy 142.206436 -175.216032) (xy 142.151063 -175.238968) (xy 142.09317 -175.254481)
			(xy 142.033748 -175.262304) (xy 141.973812 -175.262304) (xy 141.91439 -175.254481) (xy 141.856497 -175.238968)
			(xy 141.801124 -175.216032) (xy 141.749218 -175.186065) (xy 141.701668 -175.149578) (xy 141.659288 -175.107198)
			(xy 141.622801 -175.059648) (xy 141.592834 -175.007742) (xy 141.569898 -174.952369) (xy 141.554385 -174.894476)
			(xy 141.546562 -174.835054) (xy 141.546072 -174.805086) (xy 141.546072 -173.940978) (xy 141.546499 -173.913702)
			(xy 141.55301 -173.859538) (xy 141.565913 -173.806533) (xy 141.585025 -173.755437) (xy 141.610076 -173.706976)
			(xy 141.625066 -173.684184) (xy 141.63294 -173.672754) (xy 141.634464 -173.64456) (xy 141.585696 -173.552612)
			(xy 141.581078 -173.544678) (xy 141.567328 -173.532538) (xy 141.550164 -173.526066) (xy 141.540992 -173.525688)
			(xy 139.91844 -173.525688) (xy 139.90837 -173.526111) (xy 139.889771 -173.533831) (xy 139.882372 -173.540674)
			(xy 136.58596 -176.837086) (xy 142.181072 -176.837086) (xy 142.181072 -175.973486) (xy 142.181562 -175.943518)
			(xy 142.189385 -175.884096) (xy 142.204898 -175.826203) (xy 142.227834 -175.77083) (xy 142.257801 -175.718924)
			(xy 142.294288 -175.671374) (xy 142.336668 -175.628994) (xy 142.384218 -175.592507) (xy 142.436124 -175.56254)
			(xy 142.491497 -175.539604) (xy 142.54939 -175.524091) (xy 142.608812 -175.516268) (xy 142.668748 -175.516268)
			(xy 142.72817 -175.524091) (xy 142.786063 -175.539604) (xy 142.841436 -175.56254) (xy 142.893342 -175.592507)
			(xy 142.940892 -175.628994) (xy 142.983272 -175.671374) (xy 143.019759 -175.718924) (xy 143.049726 -175.77083)
			(xy 143.072662 -175.826203) (xy 143.088175 -175.884096) (xy 143.095998 -175.943518) (xy 143.096488 -175.973486)
			(xy 143.096488 -176.837086) (xy 143.095998 -176.867054) (xy 143.088175 -176.926476) (xy 143.072662 -176.984369)
			(xy 143.049726 -177.039742) (xy 143.019759 -177.091648) (xy 142.983272 -177.139198) (xy 142.940892 -177.181578)
			(xy 142.893342 -177.218065) (xy 142.841436 -177.248032) (xy 142.786063 -177.270968) (xy 142.72817 -177.286481)
			(xy 142.668748 -177.294304) (xy 142.608812 -177.294304) (xy 142.54939 -177.286481) (xy 142.491497 -177.270968)
			(xy 142.436124 -177.248032) (xy 142.384218 -177.218065) (xy 142.336668 -177.181578) (xy 142.294288 -177.139198)
			(xy 142.257801 -177.091648) (xy 142.227834 -177.039742) (xy 142.204898 -176.984369) (xy 142.189385 -176.926476)
			(xy 142.181562 -176.867054) (xy 142.181072 -176.837086) (xy 136.58596 -176.837086) (xy 136.513062 -176.909984)
			(xy 136.506231 -176.917391) (xy 136.498507 -176.935985) (xy 136.498076 -176.946052) (xy 136.498076 -177.488088)
			(xy 137.565636 -177.488088) (xy 137.569707 -177.432466) (xy 137.581833 -177.378029) (xy 137.601756 -177.325938)
			(xy 137.629052 -177.277303) (xy 137.663138 -177.23316) (xy 137.703287 -177.194451) (xy 137.748645 -177.162)
			(xy 137.798245 -177.136499) (xy 137.851029 -177.118492) (xy 137.905872 -177.108362) (xy 137.961606 -177.106325)
			(xy 138.017043 -177.112425) (xy 138.071 -177.126531) (xy 138.122329 -177.148343) (xy 138.169935 -177.177397)
			(xy 138.212803 -177.213072) (xy 138.25002 -177.254609) (xy 138.280793 -177.301122) (xy 138.304465 -177.351619)
			(xy 138.320533 -177.405026) (xy 138.328653 -177.460202) (xy 138.329162 -177.488088) (xy 138.328653 -177.515974)
			(xy 138.320533 -177.57115) (xy 138.304465 -177.624557) (xy 138.280793 -177.675054) (xy 138.25002 -177.721567)
			(xy 138.212803 -177.763104) (xy 138.169935 -177.798779) (xy 138.122329 -177.827833) (xy 138.071 -177.849645)
			(xy 138.017043 -177.863751) (xy 137.961606 -177.869851) (xy 137.905872 -177.867814) (xy 137.851029 -177.857684)
			(xy 137.798245 -177.839677) (xy 137.748645 -177.814176) (xy 137.703287 -177.781725) (xy 137.663138 -177.743016)
			(xy 137.629052 -177.698873) (xy 137.601756 -177.650238) (xy 137.581833 -177.598147) (xy 137.569707 -177.54371)
			(xy 137.565636 -177.488088) (xy 136.498076 -177.488088) (xy 136.498076 -178.205892) (xy 136.500616 -178.217068)
			(xy 136.50341 -178.222402) (xy 136.503918 -178.223418) (xy 136.517645 -178.250891) (xy 136.537098 -178.309139)
			(xy 136.546972 -178.369751) (xy 136.547606 -178.400456) (xy 136.54712 -178.427707) (xy 136.539364 -178.481655)
			(xy 136.524009 -178.53395) (xy 136.501367 -178.583527) (xy 136.471901 -178.629377) (xy 136.43621 -178.670568)
			(xy 136.395019 -178.706259) (xy 136.349169 -178.735725) (xy 136.299592 -178.758367) (xy 136.247297 -178.773722)
			(xy 136.193349 -178.781478) (xy 136.138847 -178.781478) (xy 136.084899 -178.773722) (xy 136.032604 -178.758367)
			(xy 135.983027 -178.735725) (xy 135.937177 -178.706259) (xy 135.895986 -178.670568) (xy 135.860295 -178.629377)
			(xy 135.830829 -178.583527) (xy 135.808187 -178.53395) (xy 135.792832 -178.481655) (xy 135.785076 -178.427707)
			(xy 135.78459 -178.400456) (xy 135.78519 -178.369653) (xy 135.79512 -178.308851) (xy 135.814697 -178.250438)
			(xy 135.828532 -178.22291) (xy 135.828786 -178.222402) (xy 135.831257 -178.217079) (xy 135.833964 -178.205662)
			(xy 135.83412 -178.199796) (xy 135.83412 -177.136552) (xy 135.817102 -177.111152) (xy 135.802878 -177.10531)
			(xy 135.793436 -177.1019) (xy 135.773379 -177.101937) (xy 135.75487 -177.109666) (xy 135.747506 -177.116486)
			(xy 134.843774 -178.020218) (xy 134.829045 -178.034437) (xy 134.796691 -178.059522) (xy 134.779258 -178.070256)
			(xy 134.769938 -178.076592) (xy 134.75741 -178.095289) (xy 134.755128 -178.106324) (xy 134.74192 -178.195986)
			(xy 134.748524 -178.217322) (xy 134.756398 -178.225958) (xy 134.77379 -178.245757) (xy 134.803162 -178.289508)
			(xy 134.825772 -178.337108) (xy 134.841125 -178.387518) (xy 134.848887 -178.43964) (xy 134.849362 -178.465988)
			(xy 134.848864 -178.492637) (xy 134.840921 -178.545341) (xy 134.825211 -178.596271) (xy 134.802085 -178.644292)
			(xy 134.772061 -178.688329) (xy 134.735809 -178.7274) (xy 134.694138 -178.760631) (xy 134.64798 -178.78728)
			(xy 134.598366 -178.806752) (xy 134.546404 -178.818612) (xy 134.493254 -178.822596) (xy 134.440104 -178.818612)
			(xy 134.388142 -178.806752) (xy 134.338528 -178.78728) (xy 134.29237 -178.760631) (xy 134.250699 -178.7274)
			(xy 134.214447 -178.688329) (xy 134.184423 -178.644292) (xy 134.161297 -178.596271) (xy 134.145587 -178.545341)
			(xy 134.137644 -178.492637) (xy 134.137146 -178.465988) (xy 134.137572 -178.441203) (xy 134.144441 -178.392113)
			(xy 134.15806 -178.344451) (xy 134.178163 -178.299142) (xy 134.204361 -178.257062) (xy 134.236148 -178.219027)
			(xy 134.25424 -178.202082) (xy 134.261777 -178.194479) (xy 134.270438 -178.174927) (xy 134.271004 -178.164236)
			(xy 134.27075 -178.077876) (xy 134.26186 -178.058064) (xy 134.253732 -178.050952) (xy 134.235393 -178.034004)
			(xy 134.203205 -177.995824) (xy 134.176666 -177.953524) (xy 134.156295 -177.907931) (xy 134.142493 -177.859939)
			(xy 134.135529 -177.81049) (xy 134.135114 -177.785522) (xy 134.135114 -177.785268) (xy 134.135662 -177.757973)
			(xy 134.14402 -177.704027) (xy 134.160506 -177.651986) (xy 134.184733 -177.603066) (xy 134.216135 -177.558413)
			(xy 134.234682 -177.53838) (xy 134.241794 -177.531014) (xy 134.248906 -177.513234) (xy 134.248906 -177.42281)
			(xy 134.241794 -177.40503) (xy 134.234682 -177.397664) (xy 134.216057 -177.377661) (xy 134.184603 -177.332965)
			(xy 134.160356 -177.283984) (xy 134.143888 -177.23187) (xy 134.135585 -177.17785) (xy 134.135114 -177.150522)
			(xy 134.135645 -177.123202) (xy 134.14398 -177.0692) (xy 134.160458 -177.017104) (xy 134.184694 -176.968132)
			(xy 134.216119 -176.923432) (xy 134.234682 -176.90338) (xy 134.241794 -176.896014) (xy 134.248906 -176.878234)
			(xy 134.248906 -176.78781) (xy 134.241794 -176.77003) (xy 134.234682 -176.762664) (xy 134.216074 -176.742681)
			(xy 134.184642 -176.698031) (xy 134.160404 -176.649102) (xy 134.143928 -176.597043) (xy 134.135602 -176.543078)
			(xy 134.135114 -176.515776) (xy 134.135114 -176.515522) (xy 134.135513 -176.490779) (xy 134.142358 -176.441768)
			(xy 134.155919 -176.394176) (xy 134.175936 -176.348919) (xy 134.202023 -176.306867) (xy 134.233678 -176.268829)
			(xy 134.2517 -176.25187) (xy 134.259327 -176.244408) (xy 134.268008 -176.224938) (xy 134.268464 -176.214278)
			(xy 134.268464 -176.181766) (xy 134.267871 -176.171138) (xy 134.259208 -176.15172) (xy 134.2517 -176.144174)
			(xy 134.24408 -176.137062) (xy 134.236714 -176.12995) (xy 134.218934 -176.122838) (xy 134.12851 -176.122838)
			(xy 134.11073 -176.12995) (xy 134.103364 -176.137062) (xy 134.083353 -176.155677) (xy 134.03866 -176.187135)
			(xy 133.989681 -176.211384) (xy 133.937568 -176.227855) (xy 133.883549 -176.236159) (xy 133.856222 -176.23663)
			(xy 133.828902 -176.236087) (xy 133.774902 -176.227753) (xy 133.722806 -176.211277) (xy 133.673834 -176.187044)
			(xy 133.629133 -176.155623) (xy 133.60908 -176.137062) (xy 133.601714 -176.12995) (xy 133.583934 -176.122838)
			(xy 133.49351 -176.122838) (xy 133.47573 -176.12995) (xy 133.468364 -176.137062) (xy 133.448372 -176.155661)
			(xy 133.403725 -176.187096) (xy 133.354799 -176.211337) (xy 133.302742 -176.227814) (xy 133.248778 -176.236142)
			(xy 133.221476 -176.23663) (xy 133.221222 -176.23663) (xy 133.193241 -176.236039) (xy 133.137966 -176.227288)
			(xy 133.084741 -176.209998) (xy 133.034877 -176.184594) (xy 132.9896 -176.151703) (xy 132.950026 -176.112134)
			(xy 132.917129 -176.066861) (xy 132.891719 -176.016999) (xy 132.874423 -175.963777) (xy 132.865665 -175.908503)
			(xy 132.865114 -175.880522) (xy 132.865792 -175.849591) (xy 132.876525 -175.788667) (xy 132.88645 -175.759364)
			(xy 132.889244 -175.750982) (xy 132.889244 -174.911766) (xy 132.889745 -174.885679) (xy 132.897904 -174.834147)
			(xy 132.914032 -174.784529) (xy 132.93773 -174.738048) (xy 132.968414 -174.69585) (xy 132.986526 -174.67707)
			(xy 137.05967 -170.603926) (xy 137.066487 -170.596507) (xy 137.074221 -170.577923) (xy 137.074656 -170.567858)
			(xy 137.074656 -168.419526) (xy 137.074191 -168.409383) (xy 137.066373 -168.390667) (xy 137.05191 -168.376447)
			(xy 137.042652 -168.372282) (xy 136.94029 -168.331642) (xy 136.910318 -168.338246) (xy 136.899396 -168.349676)
			(xy 136.87767 -168.371863) (xy 136.82929 -168.410792) (xy 136.776095 -168.442829) (xy 136.719061 -168.467387)
			(xy 136.659231 -168.484016) (xy 136.597704 -168.492412) (xy 136.566656 -168.492932) (xy 135.703056 -168.492932)
			(xy 135.673092 -168.492391) (xy 135.613677 -168.484564) (xy 135.555791 -168.469049) (xy 135.500426 -168.446111)
			(xy 135.448529 -168.416143) (xy 135.400986 -168.379658) (xy 135.358612 -168.337281) (xy 135.322132 -168.289735)
			(xy 135.29217 -168.237834) (xy 135.269237 -168.182467) (xy 135.253728 -168.12458) (xy 135.245906 -168.065164)
			(xy 135.245906 -168.005236) (xy 135.253728 -167.94582) (xy 135.269237 -167.887933) (xy 135.29217 -167.832566)
			(xy 135.322132 -167.780665) (xy 135.358612 -167.733119) (xy 135.400986 -167.690742) (xy 135.448529 -167.654257)
			(xy 135.500426 -167.624289) (xy 135.555791 -167.601351) (xy 135.613677 -167.585836) (xy 135.673092 -167.578009)
			(xy 135.703056 -167.577516) (xy 136.566656 -167.577516) (xy 136.597706 -167.578044) (xy 136.659238 -167.58642)
			(xy 136.719073 -167.603038) (xy 136.776113 -167.627591) (xy 136.829309 -167.659631) (xy 136.877685 -167.698568)
			(xy 136.899396 -167.720772) (xy 136.910318 -167.732202) (xy 136.94029 -167.738806) (xy 137.042652 -167.698166)
			(xy 137.051916 -167.694013) (xy 137.066372 -167.679778) (xy 137.074212 -167.661066) (xy 137.074656 -167.650922)
			(xy 137.074656 -167.649144) (xy 137.074219 -167.639076) (xy 137.066508 -167.620477) (xy 137.05967 -167.613076)
			(xy 135.80872 -166.362126) (xy 135.801304 -166.355306) (xy 135.782717 -166.347574) (xy 135.772652 -166.34714)
			(xy 128.115568 -166.34714) (xy 128.105496 -166.347538) (xy 128.086897 -166.355277) (xy 128.0795 -166.362126)
			(xy 127.874522 -166.567104) (xy 127.866713 -166.575719) (xy 127.859154 -166.597676) (xy 127.860044 -166.609268)
			(xy 127.870204 -166.68877) (xy 127.872158 -166.700242) (xy 127.884873 -166.719701) (xy 127.894588 -166.726108)
			(xy 127.918578 -166.740982) (xy 127.962323 -166.776653) (xy 128.000338 -166.818376) (xy 128.031796 -166.865242)
			(xy 128.056011 -166.916229) (xy 128.072454 -166.970225) (xy 128.080769 -167.026054) (xy 128.081278 -167.054276)
			(xy 128.080822 -167.08153) (xy 128.073068 -167.135482) (xy 128.057713 -167.187782) (xy 128.035071 -167.237364)
			(xy 128.005603 -167.283219) (xy 127.969908 -167.324413) (xy 127.928714 -167.360107) (xy 127.882859 -167.389574)
			(xy 127.833277 -167.412215) (xy 127.780977 -167.427569) (xy 127.727024 -167.435323) (xy 127.69977 -167.435784)
			(xy 127.671382 -167.435287) (xy 127.615232 -167.426876) (xy 127.56095 -167.41023) (xy 127.509738 -167.385718)
			(xy 127.462728 -167.35388) (xy 127.42096 -167.315423) (xy 127.385358 -167.271195) (xy 127.35671 -167.222177)
			(xy 127.345694 -167.196008) (xy 127.34163 -167.186356) (xy 127.334264 -167.17899) (xy 127.326852 -167.172306)
			(xy 127.308419 -167.164709) (xy 127.288481 -167.164709) (xy 127.270048 -167.172306) (xy 127.262636 -167.17899)
			(xy 127.256794 -167.184832) (xy 127.252678 -167.189225) (xy 127.246393 -167.19949) (xy 127.244348 -167.205152)
			(xy 127.244348 -167.20566) (xy 127.235892 -167.231201) (xy 127.212823 -167.279805) (xy 127.183153 -167.324685)
			(xy 127.147474 -167.364953) (xy 127.106491 -167.399809) (xy 127.061018 -167.428561) (xy 127.011956 -167.450641)
			(xy 126.960279 -167.465609) (xy 126.907012 -167.473168) (xy 126.880112 -167.47363) (xy 126.852862 -167.473111)
			(xy 126.798917 -167.465356) (xy 126.746624 -167.450004) (xy 126.697048 -167.427366) (xy 126.651199 -167.397903)
			(xy 126.610009 -167.362215) (xy 126.574318 -167.321028) (xy 126.544851 -167.275182) (xy 126.522208 -167.225608)
			(xy 126.506851 -167.173317) (xy 126.499092 -167.119372) (xy 126.498604 -167.092122) (xy 126.499032 -167.06521)
			(xy 126.506619 -167.011924) (xy 126.521618 -166.960233) (xy 126.54373 -166.911161) (xy 126.572518 -166.865684)
			(xy 126.60741 -166.824702) (xy 126.647714 -166.789029) (xy 126.692631 -166.759372) (xy 126.741268 -166.736321)
			(xy 126.766828 -166.727886) (xy 126.767082 -166.727886) (xy 126.772777 -166.725911) (xy 126.78305 -166.719611)
			(xy 126.787402 -166.71544) (xy 127.489458 -166.013384) (xy 127.495554 -165.983412) (xy 127.489458 -165.969188)
			(xy 127.485274 -165.960043) (xy 127.471083 -165.94581) (xy 127.452518 -165.938111) (xy 127.442468 -165.937692)
			(xy 123.914154 -165.937692) (xy 123.904085 -165.938121) (xy 123.885485 -165.945837) (xy 123.878086 -165.952678)
			(xy 122.756926 -167.074088) (xy 125.212092 -167.074088) (xy 125.216163 -167.018466) (xy 125.228289 -166.964029)
			(xy 125.248212 -166.911938) (xy 125.275508 -166.863303) (xy 125.309594 -166.81916) (xy 125.349743 -166.780451)
			(xy 125.395101 -166.748) (xy 125.444701 -166.722499) (xy 125.497485 -166.704492) (xy 125.552328 -166.694362)
			(xy 125.608062 -166.692325) (xy 125.663499 -166.698425) (xy 125.717456 -166.712531) (xy 125.768785 -166.734343)
			(xy 125.816391 -166.763397) (xy 125.859259 -166.799072) (xy 125.896476 -166.840609) (xy 125.927249 -166.887122)
			(xy 125.950921 -166.937619) (xy 125.966989 -166.991026) (xy 125.975109 -167.046202) (xy 125.975618 -167.074088)
			(xy 125.975109 -167.101974) (xy 125.966989 -167.15715) (xy 125.950921 -167.210557) (xy 125.927249 -167.261054)
			(xy 125.896476 -167.307567) (xy 125.859259 -167.349104) (xy 125.816391 -167.384779) (xy 125.768785 -167.413833)
			(xy 125.717456 -167.435645) (xy 125.663499 -167.449751) (xy 125.608062 -167.455851) (xy 125.552328 -167.453814)
			(xy 125.497485 -167.443684) (xy 125.444701 -167.425677) (xy 125.395101 -167.400176) (xy 125.349743 -167.367725)
			(xy 125.309594 -167.329016) (xy 125.275508 -167.284873) (xy 125.248212 -167.236238) (xy 125.228289 -167.184147)
			(xy 125.216163 -167.12971) (xy 125.212092 -167.074088) (xy 122.756926 -167.074088) (xy 122.73915 -167.091868)
			(xy 122.735033 -167.09626) (xy 122.728748 -167.106525) (xy 122.726704 -167.112188) (xy 122.726704 -167.112696)
			(xy 122.718309 -167.138258) (xy 122.695231 -167.186863) (xy 122.665554 -167.231744) (xy 122.629866 -167.272011)
			(xy 122.588875 -167.306865) (xy 122.543395 -167.335615) (xy 122.494326 -167.35769) (xy 122.442643 -167.372653)
			(xy 122.389371 -167.380207) (xy 122.362468 -167.380666) (xy 122.335212 -167.380275) (xy 122.281257 -167.372512)
			(xy 122.228955 -167.35715) (xy 122.179372 -167.334501) (xy 122.133517 -167.305026) (xy 122.092323 -167.269324)
			(xy 122.05663 -167.228124) (xy 122.027164 -167.182263) (xy 122.004524 -167.132676) (xy 121.989172 -167.080371)
			(xy 121.98142 -167.026414) (xy 121.98096 -166.999158) (xy 77.592422 -166.999158) (xy 77.350967 -168.312846)
			(xy 122.314968 -168.312846) (xy 122.319039 -168.257224) (xy 122.331165 -168.202787) (xy 122.351088 -168.150696)
			(xy 122.378384 -168.102061) (xy 122.41247 -168.057918) (xy 122.452619 -168.019209) (xy 122.497977 -167.986758)
			(xy 122.547577 -167.961257) (xy 122.600361 -167.94325) (xy 122.655204 -167.93312) (xy 122.710938 -167.931083)
			(xy 122.766375 -167.937183) (xy 122.820332 -167.951289) (xy 122.871661 -167.973101) (xy 122.919267 -168.002155)
			(xy 122.962135 -168.03783) (xy 122.999352 -168.079367) (xy 123.030125 -168.12588) (xy 123.053797 -168.176377)
			(xy 123.069865 -168.229784) (xy 123.077985 -168.28496) (xy 123.078494 -168.312846) (xy 123.077985 -168.340732)
			(xy 123.069865 -168.395908) (xy 123.053797 -168.449315) (xy 123.030125 -168.499812) (xy 122.999352 -168.546325)
			(xy 122.962135 -168.587862) (xy 122.919267 -168.623537) (xy 122.871661 -168.652591) (xy 122.820332 -168.674403)
			(xy 122.766375 -168.688509) (xy 122.710938 -168.694609) (xy 122.655204 -168.692572) (xy 122.600361 -168.682442)
			(xy 122.547577 -168.664435) (xy 122.497977 -168.638934) (xy 122.452619 -168.606483) (xy 122.41247 -168.567774)
			(xy 122.378384 -168.523631) (xy 122.351088 -168.474996) (xy 122.331165 -168.422905) (xy 122.319039 -168.368468)
			(xy 122.314968 -168.312846) (xy 77.350967 -168.312846) (xy 77.137383 -169.474896) (xy 123.764292 -169.474896)
			(xy 123.768363 -169.419274) (xy 123.780489 -169.364837) (xy 123.800412 -169.312746) (xy 123.827708 -169.264111)
			(xy 123.861794 -169.219968) (xy 123.901943 -169.181259) (xy 123.947301 -169.148808) (xy 123.996901 -169.123307)
			(xy 124.049685 -169.1053) (xy 124.104528 -169.09517) (xy 124.160262 -169.093133) (xy 124.215699 -169.099233)
			(xy 124.269656 -169.113339) (xy 124.320985 -169.135151) (xy 124.368591 -169.164205) (xy 124.411459 -169.19988)
			(xy 124.448676 -169.241417) (xy 124.479449 -169.28793) (xy 124.503121 -169.338427) (xy 124.519189 -169.391834)
			(xy 124.527309 -169.44701) (xy 124.527818 -169.474896) (xy 124.527309 -169.502782) (xy 124.519189 -169.557958)
			(xy 124.503121 -169.611365) (xy 124.479449 -169.661862) (xy 124.448676 -169.708375) (xy 124.411459 -169.749912)
			(xy 124.368591 -169.785587) (xy 124.320985 -169.814641) (xy 124.269656 -169.836453) (xy 124.215699 -169.850559)
			(xy 124.160262 -169.856659) (xy 124.104528 -169.854622) (xy 124.049685 -169.844492) (xy 123.996901 -169.826485)
			(xy 123.947301 -169.800984) (xy 123.901943 -169.768533) (xy 123.861794 -169.729824) (xy 123.827708 -169.685681)
			(xy 123.800412 -169.637046) (xy 123.780489 -169.584955) (xy 123.768363 -169.530518) (xy 123.764292 -169.474896)
			(xy 77.137383 -169.474896) (xy 69.989192 -208.366106) (xy 69.991732 -208.37652) (xy 69.996484 -208.398115)
			(xy 70.001572 -208.44204) (xy 70.001892 -208.46415) (xy 70.001892 -208.474818) (xy 70.001384 -208.481676)
			(xy 69.99977 -208.507823) (xy 69.990267 -208.559341) (xy 69.973801 -208.609073) (xy 69.950681 -208.656082)
			(xy 69.93636 -208.678018) (xy 69.930264 -208.686908) (xy 69.576188 -210.613498) (xy 69.575221 -210.619806)
			(xy 69.576125 -210.632533) (xy 69.577966 -210.638644) (xy 69.579744 -210.643978) (xy 69.586348 -210.654392)
			(xy 69.58965 -210.657694) (xy 69.590158 -210.658202) (xy 69.593149 -210.66106) (xy 69.598256 -210.667569)
			(xy 69.600318 -210.671156) (xy 69.606338 -210.681115) (xy 69.625264 -210.694611) (xy 69.63664 -210.697064)
			(xy 69.649594 -210.697572) (xy 69.66585 -210.695286) (xy 69.670168 -210.694016) (xy 69.695066 -210.687521)
			(xy 69.746041 -210.680516) (xy 69.771768 -210.680046) (xy 69.777356 -210.680046) (xy 69.804407 -210.68082)
			(xy 69.857892 -210.689066) (xy 69.909675 -210.704787) (xy 69.958716 -210.727668) (xy 70.004031 -210.757251)
			(xy 70.044711 -210.79294) (xy 70.079939 -210.834021) (xy 70.109008 -210.879667) (xy 70.131334 -210.928964)
			(xy 70.146469 -210.980921) (xy 70.154109 -211.034496) (xy 70.154546 -211.061554) (xy 70.154086 -211.08881)
			(xy 70.146335 -211.142768) (xy 70.130983 -211.195074) (xy 70.108344 -211.244662) (xy 70.078878 -211.290524)
			(xy 70.043184 -211.331725) (xy 70.001991 -211.367427) (xy 69.956136 -211.396904) (xy 69.906552 -211.419554)
			(xy 69.85425 -211.434917) (xy 69.800294 -211.44268) (xy 69.773038 -211.443062) (xy 69.77253 -211.443062)
			(xy 69.74227 -211.442473) (xy 69.682509 -211.43291) (xy 69.625002 -211.41405) (xy 69.571185 -211.386364)
			(xy 69.54647 -211.368894) (xy 69.542406 -211.365846) (xy 69.529452 -211.35975) (xy 69.523839 -211.357739)
			(xy 69.512035 -211.35607) (xy 69.506084 -211.356448) (xy 69.493384 -211.359242) (xy 69.46138 -211.371942)
			(xy 69.461126 -211.372196) (xy 69.453277 -211.375634) (xy 69.440317 -211.386826) (xy 69.431816 -211.401691)
			(xy 69.429884 -211.410042) (xy 69.08165 -213.303612) (xy 68.703824 -215.359996) (xy 69.499224 -215.359996)
			(xy 69.503295 -215.304374) (xy 69.515421 -215.249937) (xy 69.535344 -215.197846) (xy 69.56264 -215.149211)
			(xy 69.596726 -215.105068) (xy 69.636875 -215.066359) (xy 69.682233 -215.033908) (xy 69.731833 -215.008407)
			(xy 69.784617 -214.9904) (xy 69.83946 -214.98027) (xy 69.895194 -214.978233) (xy 69.950631 -214.984333)
			(xy 70.004588 -214.998439) (xy 70.055917 -215.020251) (xy 70.103523 -215.049305) (xy 70.146391 -215.08498)
			(xy 70.183608 -215.126517) (xy 70.214381 -215.17303) (xy 70.238053 -215.223527) (xy 70.254121 -215.276934)
			(xy 70.262241 -215.33211) (xy 70.26275 -215.359996) (xy 70.262241 -215.387882) (xy 70.254121 -215.443058)
			(xy 70.238053 -215.496465) (xy 70.214381 -215.546962) (xy 70.183608 -215.593475) (xy 70.146391 -215.635012)
			(xy 70.103523 -215.670687) (xy 70.055917 -215.699741) (xy 70.004588 -215.721553) (xy 69.950631 -215.735659)
			(xy 69.895194 -215.741759) (xy 69.83946 -215.739722) (xy 69.784617 -215.729592) (xy 69.731833 -215.711585)
			(xy 69.682233 -215.686084) (xy 69.636875 -215.653633) (xy 69.596726 -215.614924) (xy 69.56264 -215.570781)
			(xy 69.535344 -215.522146) (xy 69.515421 -215.470055) (xy 69.503295 -215.415618) (xy 69.499224 -215.359996)
			(xy 68.703824 -215.359996) (xy 68.538852 -216.257886) (xy 68.538259 -216.27049) (xy 68.547852 -216.293795)
			(xy 68.55714 -216.302336) (xy 68.560767 -216.305174) (xy 68.568814 -216.309653) (xy 68.573142 -216.311226)
			(xy 68.584572 -216.314274) (xy 68.612618 -216.320883) (xy 68.66646 -216.341397) (xy 68.716608 -216.36977)
			(xy 68.761923 -216.405357) (xy 68.801376 -216.447349) (xy 68.834071 -216.494793) (xy 68.859264 -216.546611)
			(xy 68.876384 -216.601627) (xy 68.885043 -216.658591) (xy 68.885562 -216.6874) (xy 68.885076 -216.714669)
			(xy 68.877314 -216.768653) (xy 68.861949 -216.820983) (xy 68.839292 -216.870593) (xy 68.809806 -216.916474)
			(xy 68.774091 -216.957691) (xy 68.732874 -216.993406) (xy 68.686993 -217.022892) (xy 68.637383 -217.045549)
			(xy 68.585053 -217.060914) (xy 68.531069 -217.068676) (xy 68.5038 -217.069162) (xy 68.48952 -217.069021)
			(xy 68.461042 -217.066857) (xy 68.446904 -217.064844) (xy 68.446396 -217.064844) (xy 68.431664 -217.063828)
			(xy 68.420295 -217.064797) (xy 68.40005 -217.075255) (xy 68.386308 -217.093432) (xy 68.383404 -217.104468)
			(xy 67.93252 -219.5576) (xy 69.569582 -219.5576) (xy 69.573653 -219.501978) (xy 69.585779 -219.447541)
			(xy 69.605702 -219.39545) (xy 69.632998 -219.346815) (xy 69.667084 -219.302672) (xy 69.707233 -219.263963)
			(xy 69.752591 -219.231512) (xy 69.802191 -219.206011) (xy 69.854975 -219.188004) (xy 69.909818 -219.177874)
			(xy 69.965552 -219.175837) (xy 70.020989 -219.181937) (xy 70.074946 -219.196043) (xy 70.126275 -219.217855)
			(xy 70.173881 -219.246909) (xy 70.216749 -219.282584) (xy 70.253966 -219.324121) (xy 70.284739 -219.370634)
			(xy 70.308411 -219.421131) (xy 70.324479 -219.474538) (xy 70.332599 -219.529714) (xy 70.333108 -219.5576)
			(xy 70.332599 -219.585486) (xy 70.324479 -219.640662) (xy 70.308411 -219.694069) (xy 70.284739 -219.744566)
			(xy 70.253966 -219.791079) (xy 70.216749 -219.832616) (xy 70.173881 -219.868291) (xy 70.126275 -219.897345)
			(xy 70.074946 -219.919157) (xy 70.020989 -219.933263) (xy 69.965552 -219.939363) (xy 69.909818 -219.937326)
			(xy 69.854975 -219.927196) (xy 69.802191 -219.909189) (xy 69.752591 -219.883688) (xy 69.707233 -219.851237)
			(xy 69.667084 -219.812528) (xy 69.632998 -219.768385) (xy 69.605702 -219.71975) (xy 69.585779 -219.667659)
			(xy 69.573653 -219.613222) (xy 69.569582 -219.5576) (xy 67.93252 -219.5576) (xy 66.698216 -226.273106)
			(xy 70.331582 -226.273106) (xy 70.335653 -226.217484) (xy 70.347779 -226.163047) (xy 70.367702 -226.110956)
			(xy 70.394998 -226.062321) (xy 70.429084 -226.018178) (xy 70.469233 -225.979469) (xy 70.514591 -225.947018)
			(xy 70.564191 -225.921517) (xy 70.616975 -225.90351) (xy 70.671818 -225.89338) (xy 70.727552 -225.891343)
			(xy 70.782989 -225.897443) (xy 70.836946 -225.911549) (xy 70.888275 -225.933361) (xy 70.935881 -225.962415)
			(xy 70.978749 -225.99809) (xy 71.015966 -226.039627) (xy 71.046739 -226.08614) (xy 71.070411 -226.136637)
			(xy 71.086479 -226.190044) (xy 71.094599 -226.24522) (xy 71.095108 -226.273106) (xy 71.094599 -226.300992)
			(xy 71.086479 -226.356168) (xy 71.070411 -226.409575) (xy 71.046739 -226.460072) (xy 71.015966 -226.506585)
			(xy 70.978749 -226.548122) (xy 70.935881 -226.583797) (xy 70.888275 -226.612851) (xy 70.836946 -226.634663)
			(xy 70.782989 -226.648769) (xy 70.727552 -226.654869) (xy 70.671818 -226.652832) (xy 70.616975 -226.642702)
			(xy 70.564191 -226.624695) (xy 70.514591 -226.599194) (xy 70.469233 -226.566743) (xy 70.429084 -226.528034)
			(xy 70.394998 -226.483891) (xy 70.367702 -226.435256) (xy 70.347779 -226.383165) (xy 70.335653 -226.328728)
			(xy 70.331582 -226.273106) (xy 66.698216 -226.273106) (xy 66.298546 -228.4476) (xy 69.569582 -228.4476)
			(xy 69.573653 -228.391978) (xy 69.585779 -228.337541) (xy 69.605702 -228.28545) (xy 69.632998 -228.236815)
			(xy 69.667084 -228.192672) (xy 69.707233 -228.153963) (xy 69.752591 -228.121512) (xy 69.802191 -228.096011)
			(xy 69.854975 -228.078004) (xy 69.909818 -228.067874) (xy 69.965552 -228.065837) (xy 70.020989 -228.071937)
			(xy 70.074946 -228.086043) (xy 70.126275 -228.107855) (xy 70.173881 -228.136909) (xy 70.216749 -228.172584)
			(xy 70.253966 -228.214121) (xy 70.284739 -228.260634) (xy 70.308411 -228.311131) (xy 70.324479 -228.364538)
			(xy 70.332599 -228.419714) (xy 70.333108 -228.4476) (xy 70.332599 -228.475486) (xy 70.324479 -228.530662)
			(xy 70.308411 -228.584069) (xy 70.284739 -228.634566) (xy 70.253966 -228.681079) (xy 70.216749 -228.722616)
			(xy 70.173881 -228.758291) (xy 70.126275 -228.787345) (xy 70.074946 -228.809157) (xy 70.020989 -228.823263)
			(xy 69.965552 -228.829363) (xy 69.909818 -228.827326) (xy 69.854975 -228.817196) (xy 69.802191 -228.799189)
			(xy 69.752591 -228.773688) (xy 69.707233 -228.741237) (xy 69.667084 -228.702528) (xy 69.632998 -228.658385)
			(xy 69.605702 -228.60975) (xy 69.585779 -228.557659) (xy 69.573653 -228.503222) (xy 69.569582 -228.4476)
			(xy 66.298546 -228.4476) (xy 65.040899 -235.290106) (xy 70.550276 -235.290106) (xy 70.554347 -235.234484)
			(xy 70.566473 -235.180047) (xy 70.586396 -235.127956) (xy 70.613692 -235.079321) (xy 70.647778 -235.035178)
			(xy 70.687927 -234.996469) (xy 70.733285 -234.964018) (xy 70.782885 -234.938517) (xy 70.835669 -234.92051)
			(xy 70.890512 -234.91038) (xy 70.946246 -234.908343) (xy 71.001683 -234.914443) (xy 71.05564 -234.928549)
			(xy 71.106969 -234.950361) (xy 71.154575 -234.979415) (xy 71.197443 -235.01509) (xy 71.23466 -235.056627)
			(xy 71.265433 -235.10314) (xy 71.289105 -235.153637) (xy 71.305173 -235.207044) (xy 71.313293 -235.26222)
			(xy 71.313802 -235.290106) (xy 71.313293 -235.317992) (xy 71.305173 -235.373168) (xy 71.289105 -235.426575)
			(xy 71.265433 -235.477072) (xy 71.23466 -235.523585) (xy 71.197443 -235.565122) (xy 71.154575 -235.600797)
			(xy 71.106969 -235.629851) (xy 71.05564 -235.651663) (xy 71.001683 -235.665769) (xy 70.946246 -235.671869)
			(xy 70.890512 -235.669832) (xy 70.835669 -235.659702) (xy 70.782885 -235.641695) (xy 70.733285 -235.616194)
			(xy 70.687927 -235.583743) (xy 70.647778 -235.545034) (xy 70.613692 -235.500891) (xy 70.586396 -235.452256)
			(xy 70.566473 -235.400165) (xy 70.554347 -235.345728) (xy 70.550276 -235.290106) (xy 65.040899 -235.290106)
			(xy 64.569381 -237.855506) (xy 70.417688 -237.855506) (xy 70.421759 -237.799884) (xy 70.433885 -237.745447)
			(xy 70.453808 -237.693356) (xy 70.481104 -237.644721) (xy 70.51519 -237.600578) (xy 70.555339 -237.561869)
			(xy 70.600697 -237.529418) (xy 70.650297 -237.503917) (xy 70.703081 -237.48591) (xy 70.757924 -237.47578)
			(xy 70.813658 -237.473743) (xy 70.869095 -237.479843) (xy 70.923052 -237.493949) (xy 70.974381 -237.515761)
			(xy 71.021987 -237.544815) (xy 71.064855 -237.58049) (xy 71.102072 -237.622027) (xy 71.132845 -237.66854)
			(xy 71.156517 -237.719037) (xy 71.172585 -237.772444) (xy 71.180705 -237.82762) (xy 71.181214 -237.855506)
			(xy 71.180705 -237.883392) (xy 71.172585 -237.938568) (xy 71.156517 -237.991975) (xy 71.132845 -238.042472)
			(xy 71.102072 -238.088985) (xy 71.064855 -238.130522) (xy 71.021987 -238.166197) (xy 70.974381 -238.195251)
			(xy 70.923052 -238.217063) (xy 70.869095 -238.231169) (xy 70.813658 -238.237269) (xy 70.757924 -238.235232)
			(xy 70.703081 -238.225102) (xy 70.650297 -238.207095) (xy 70.600697 -238.181594) (xy 70.555339 -238.149143)
			(xy 70.51519 -238.110434) (xy 70.481104 -238.066291) (xy 70.453808 -238.017656) (xy 70.433885 -237.965565)
			(xy 70.421759 -237.911128) (xy 70.417688 -237.855506) (xy 64.569381 -237.855506) (xy 59.363864 -266.177268)
			(xy 59.363356 -266.18438) (xy 59.363356 -271.399762) (xy 59.362822 -271.445327) (xy 59.354457 -271.536072)
			(xy 59.337849 -271.625675) (xy 59.313136 -271.71339) (xy 59.297316 -271.756124) (xy 59.29503 -271.764506)
			(xy 59.293252 -271.77365) (xy 59.292236 -271.783302) (xy 59.292236 -272.7833) (xy 59.292597 -272.792379)
			(xy 59.298937 -272.809394) (xy 59.310845 -272.823101) (xy 59.318652 -272.82775) (xy 59.397646 -272.865596)
			(xy 59.423808 -272.862294) (xy 59.437016 -272.850864) (xy 59.45482 -272.836191) (xy 59.493775 -272.811475)
			(xy 59.535819 -272.792482) (xy 59.580116 -272.77959) (xy 59.625785 -272.773054) (xy 59.648852 -272.772632)
			(xy 59.649614 -272.772632) (xy 59.675299 -272.773137) (xy 59.726035 -272.781175) (xy 59.77489 -272.79705)
			(xy 59.82066 -272.820373) (xy 59.862218 -272.850568) (xy 59.898541 -272.886893) (xy 59.928734 -272.928452)
			(xy 59.952055 -272.974223) (xy 59.967929 -273.023078) (xy 59.975964 -273.073815) (xy 59.975964 -273.125185)
			(xy 59.975915 -273.125492) (xy 61.222886 -273.125492) (xy 61.222886 -273.074076) (xy 61.230929 -273.023294)
			(xy 61.246817 -272.974395) (xy 61.27016 -272.928583) (xy 61.300381 -272.886987) (xy 61.336737 -272.850631)
			(xy 61.378333 -272.82041) (xy 61.424145 -272.797067) (xy 61.473044 -272.781179) (xy 61.523826 -272.773136)
			(xy 61.575242 -272.773136) (xy 61.626024 -272.781179) (xy 61.674923 -272.797067) (xy 61.720735 -272.82041)
			(xy 61.762331 -272.850631) (xy 61.798687 -272.886987) (xy 61.828908 -272.928583) (xy 61.852251 -272.974395)
			(xy 61.868139 -273.023294) (xy 61.876182 -273.074076) (xy 61.876686 -273.099784) (xy 61.876182 -273.125492)
			(xy 63.12306 -273.125492) (xy 63.12306 -273.074076) (xy 63.131103 -273.023294) (xy 63.146991 -272.974395)
			(xy 63.170334 -272.928583) (xy 63.200555 -272.886987) (xy 63.236911 -272.850631) (xy 63.278507 -272.82041)
			(xy 63.324319 -272.797067) (xy 63.373218 -272.781179) (xy 63.424 -272.773136) (xy 63.475416 -272.773136)
			(xy 63.526198 -272.781179) (xy 63.575097 -272.797067) (xy 63.620909 -272.82041) (xy 63.662505 -272.850631)
			(xy 63.698861 -272.886987) (xy 63.729082 -272.928583) (xy 63.752425 -272.974395) (xy 63.768313 -273.023294)
			(xy 63.776356 -273.074076) (xy 63.77686 -273.099784) (xy 63.776356 -273.125492) (xy 65.02298 -273.125492)
			(xy 65.02298 -273.074076) (xy 65.031023 -273.023294) (xy 65.046911 -272.974395) (xy 65.070254 -272.928583)
			(xy 65.100475 -272.886987) (xy 65.136831 -272.850631) (xy 65.178427 -272.82041) (xy 65.224239 -272.797067)
			(xy 65.273138 -272.781179) (xy 65.32392 -272.773136) (xy 65.375336 -272.773136) (xy 65.426118 -272.781179)
			(xy 65.475017 -272.797067) (xy 65.520829 -272.82041) (xy 65.562425 -272.850631) (xy 65.598781 -272.886987)
			(xy 65.629002 -272.928583) (xy 65.652345 -272.974395) (xy 65.668233 -273.023294) (xy 65.676276 -273.074076)
			(xy 65.67678 -273.099784) (xy 65.676276 -273.125492) (xy 66.9229 -273.125492) (xy 66.9229 -273.074076)
			(xy 66.930943 -273.023294) (xy 66.946831 -272.974395) (xy 66.970174 -272.928583) (xy 67.000395 -272.886987)
			(xy 67.036751 -272.850631) (xy 67.078347 -272.82041) (xy 67.124159 -272.797067) (xy 67.173058 -272.781179)
			(xy 67.22384 -272.773136) (xy 67.275256 -272.773136) (xy 67.326038 -272.781179) (xy 67.374937 -272.797067)
			(xy 67.420749 -272.82041) (xy 67.462345 -272.850631) (xy 67.498701 -272.886987) (xy 67.528922 -272.928583)
			(xy 67.552265 -272.974395) (xy 67.568153 -273.023294) (xy 67.576196 -273.074076) (xy 67.5767 -273.099784)
			(xy 67.576196 -273.125492) (xy 68.823074 -273.125492) (xy 68.823074 -273.074076) (xy 68.831117 -273.023294)
			(xy 68.847005 -272.974395) (xy 68.870348 -272.928583) (xy 68.900569 -272.886987) (xy 68.936925 -272.850631)
			(xy 68.978521 -272.82041) (xy 69.024333 -272.797067) (xy 69.073232 -272.781179) (xy 69.124014 -272.773136)
			(xy 69.17543 -272.773136) (xy 69.226212 -272.781179) (xy 69.275111 -272.797067) (xy 69.320923 -272.82041)
			(xy 69.362519 -272.850631) (xy 69.398875 -272.886987) (xy 69.429096 -272.928583) (xy 69.452439 -272.974395)
			(xy 69.468327 -273.023294) (xy 69.47637 -273.074076) (xy 69.476874 -273.099784) (xy 69.47637 -273.125492)
			(xy 70.722994 -273.125492) (xy 70.722994 -273.074076) (xy 70.731037 -273.023294) (xy 70.746925 -272.974395)
			(xy 70.770268 -272.928583) (xy 70.800489 -272.886987) (xy 70.836845 -272.850631) (xy 70.878441 -272.82041)
			(xy 70.924253 -272.797067) (xy 70.973152 -272.781179) (xy 71.023934 -272.773136) (xy 71.07535 -272.773136)
			(xy 71.126132 -272.781179) (xy 71.175031 -272.797067) (xy 71.220843 -272.82041) (xy 71.262439 -272.850631)
			(xy 71.298795 -272.886987) (xy 71.329016 -272.928583) (xy 71.352359 -272.974395) (xy 71.368247 -273.023294)
			(xy 71.37629 -273.074076) (xy 71.376794 -273.099784) (xy 71.37629 -273.125492) (xy 72.622914 -273.125492)
			(xy 72.622914 -273.074076) (xy 72.630957 -273.023294) (xy 72.646845 -272.974395) (xy 72.670188 -272.928583)
			(xy 72.700409 -272.886987) (xy 72.736765 -272.850631) (xy 72.778361 -272.82041) (xy 72.824173 -272.797067)
			(xy 72.873072 -272.781179) (xy 72.923854 -272.773136) (xy 72.97527 -272.773136) (xy 73.026052 -272.781179)
			(xy 73.074951 -272.797067) (xy 73.120763 -272.82041) (xy 73.162359 -272.850631) (xy 73.198715 -272.886987)
			(xy 73.228936 -272.928583) (xy 73.252279 -272.974395) (xy 73.268167 -273.023294) (xy 73.27621 -273.074076)
			(xy 73.276714 -273.099784) (xy 73.27621 -273.125492) (xy 74.523088 -273.125492) (xy 74.523088 -273.074076)
			(xy 74.531131 -273.023294) (xy 74.547019 -272.974395) (xy 74.570362 -272.928583) (xy 74.600583 -272.886987)
			(xy 74.636939 -272.850631) (xy 74.678535 -272.82041) (xy 74.724347 -272.797067) (xy 74.773246 -272.781179)
			(xy 74.824028 -272.773136) (xy 74.875444 -272.773136) (xy 74.926226 -272.781179) (xy 74.975125 -272.797067)
			(xy 75.020937 -272.82041) (xy 75.062533 -272.850631) (xy 75.098889 -272.886987) (xy 75.12911 -272.928583)
			(xy 75.152453 -272.974395) (xy 75.168341 -273.023294) (xy 75.176384 -273.074076) (xy 75.176888 -273.099784)
			(xy 75.176384 -273.125492) (xy 76.423008 -273.125492) (xy 76.423008 -273.074076) (xy 76.431051 -273.023294)
			(xy 76.446939 -272.974395) (xy 76.470282 -272.928583) (xy 76.500503 -272.886987) (xy 76.536859 -272.850631)
			(xy 76.578455 -272.82041) (xy 76.624267 -272.797067) (xy 76.673166 -272.781179) (xy 76.723948 -272.773136)
			(xy 76.775364 -272.773136) (xy 76.826146 -272.781179) (xy 76.875045 -272.797067) (xy 76.920857 -272.82041)
			(xy 76.962453 -272.850631) (xy 76.998809 -272.886987) (xy 77.02903 -272.928583) (xy 77.052373 -272.974395)
			(xy 77.068261 -273.023294) (xy 77.076304 -273.074076) (xy 77.076808 -273.099784) (xy 77.076304 -273.125492)
			(xy 78.322928 -273.125492) (xy 78.322928 -273.074076) (xy 78.330971 -273.023294) (xy 78.346859 -272.974395)
			(xy 78.370202 -272.928583) (xy 78.400423 -272.886987) (xy 78.436779 -272.850631) (xy 78.478375 -272.82041)
			(xy 78.524187 -272.797067) (xy 78.573086 -272.781179) (xy 78.623868 -272.773136) (xy 78.675284 -272.773136)
			(xy 78.726066 -272.781179) (xy 78.774965 -272.797067) (xy 78.820777 -272.82041) (xy 78.862373 -272.850631)
			(xy 78.898729 -272.886987) (xy 78.92895 -272.928583) (xy 78.952293 -272.974395) (xy 78.968181 -273.023294)
			(xy 78.976224 -273.074076) (xy 78.976728 -273.099784) (xy 78.976224 -273.125492) (xy 80.222848 -273.125492)
			(xy 80.222848 -273.074076) (xy 80.230891 -273.023294) (xy 80.246779 -272.974395) (xy 80.270122 -272.928583)
			(xy 80.300343 -272.886987) (xy 80.336699 -272.850631) (xy 80.378295 -272.82041) (xy 80.424107 -272.797067)
			(xy 80.473006 -272.781179) (xy 80.523788 -272.773136) (xy 80.575204 -272.773136) (xy 80.625986 -272.781179)
			(xy 80.674885 -272.797067) (xy 80.720697 -272.82041) (xy 80.762293 -272.850631) (xy 80.798649 -272.886987)
			(xy 80.82887 -272.928583) (xy 80.852213 -272.974395) (xy 80.868101 -273.023294) (xy 80.876144 -273.074076)
			(xy 80.876648 -273.099784) (xy 80.876144 -273.125492) (xy 80.868101 -273.176274) (xy 80.852213 -273.225173)
			(xy 80.82887 -273.270985) (xy 80.798649 -273.312581) (xy 80.762293 -273.348937) (xy 80.720697 -273.379158)
			(xy 80.674885 -273.402501) (xy 80.625986 -273.418389) (xy 80.575204 -273.426432) (xy 80.523788 -273.426432)
			(xy 80.473006 -273.418389) (xy 80.424107 -273.402501) (xy 80.378295 -273.379158) (xy 80.336699 -273.348937)
			(xy 80.300343 -273.312581) (xy 80.270122 -273.270985) (xy 80.246779 -273.225173) (xy 80.230891 -273.176274)
			(xy 80.222848 -273.125492) (xy 78.976224 -273.125492) (xy 78.968181 -273.176274) (xy 78.952293 -273.225173)
			(xy 78.92895 -273.270985) (xy 78.898729 -273.312581) (xy 78.862373 -273.348937) (xy 78.820777 -273.379158)
			(xy 78.774965 -273.402501) (xy 78.726066 -273.418389) (xy 78.675284 -273.426432) (xy 78.623868 -273.426432)
			(xy 78.573086 -273.418389) (xy 78.524187 -273.402501) (xy 78.478375 -273.379158) (xy 78.436779 -273.348937)
			(xy 78.400423 -273.312581) (xy 78.370202 -273.270985) (xy 78.346859 -273.225173) (xy 78.330971 -273.176274)
			(xy 78.322928 -273.125492) (xy 77.076304 -273.125492) (xy 77.068261 -273.176274) (xy 77.052373 -273.225173)
			(xy 77.02903 -273.270985) (xy 76.998809 -273.312581) (xy 76.962453 -273.348937) (xy 76.920857 -273.379158)
			(xy 76.875045 -273.402501) (xy 76.826146 -273.418389) (xy 76.775364 -273.426432) (xy 76.723948 -273.426432)
			(xy 76.673166 -273.418389) (xy 76.624267 -273.402501) (xy 76.578455 -273.379158) (xy 76.536859 -273.348937)
			(xy 76.500503 -273.312581) (xy 76.470282 -273.270985) (xy 76.446939 -273.225173) (xy 76.431051 -273.176274)
			(xy 76.423008 -273.125492) (xy 75.176384 -273.125492) (xy 75.168341 -273.176274) (xy 75.152453 -273.225173)
			(xy 75.12911 -273.270985) (xy 75.098889 -273.312581) (xy 75.062533 -273.348937) (xy 75.020937 -273.379158)
			(xy 74.975125 -273.402501) (xy 74.926226 -273.418389) (xy 74.875444 -273.426432) (xy 74.824028 -273.426432)
			(xy 74.773246 -273.418389) (xy 74.724347 -273.402501) (xy 74.678535 -273.379158) (xy 74.636939 -273.348937)
			(xy 74.600583 -273.312581) (xy 74.570362 -273.270985) (xy 74.547019 -273.225173) (xy 74.531131 -273.176274)
			(xy 74.523088 -273.125492) (xy 73.27621 -273.125492) (xy 73.268167 -273.176274) (xy 73.252279 -273.225173)
			(xy 73.228936 -273.270985) (xy 73.198715 -273.312581) (xy 73.162359 -273.348937) (xy 73.120763 -273.379158)
			(xy 73.074951 -273.402501) (xy 73.026052 -273.418389) (xy 72.97527 -273.426432) (xy 72.923854 -273.426432)
			(xy 72.873072 -273.418389) (xy 72.824173 -273.402501) (xy 72.778361 -273.379158) (xy 72.736765 -273.348937)
			(xy 72.700409 -273.312581) (xy 72.670188 -273.270985) (xy 72.646845 -273.225173) (xy 72.630957 -273.176274)
			(xy 72.622914 -273.125492) (xy 71.37629 -273.125492) (xy 71.368247 -273.176274) (xy 71.352359 -273.225173)
			(xy 71.329016 -273.270985) (xy 71.298795 -273.312581) (xy 71.262439 -273.348937) (xy 71.220843 -273.379158)
			(xy 71.175031 -273.402501) (xy 71.126132 -273.418389) (xy 71.07535 -273.426432) (xy 71.023934 -273.426432)
			(xy 70.973152 -273.418389) (xy 70.924253 -273.402501) (xy 70.878441 -273.379158) (xy 70.836845 -273.348937)
			(xy 70.800489 -273.312581) (xy 70.770268 -273.270985) (xy 70.746925 -273.225173) (xy 70.731037 -273.176274)
			(xy 70.722994 -273.125492) (xy 69.47637 -273.125492) (xy 69.468327 -273.176274) (xy 69.452439 -273.225173)
			(xy 69.429096 -273.270985) (xy 69.398875 -273.312581) (xy 69.362519 -273.348937) (xy 69.320923 -273.379158)
			(xy 69.275111 -273.402501) (xy 69.226212 -273.418389) (xy 69.17543 -273.426432) (xy 69.124014 -273.426432)
			(xy 69.073232 -273.418389) (xy 69.024333 -273.402501) (xy 68.978521 -273.379158) (xy 68.936925 -273.348937)
			(xy 68.900569 -273.312581) (xy 68.870348 -273.270985) (xy 68.847005 -273.225173) (xy 68.831117 -273.176274)
			(xy 68.823074 -273.125492) (xy 67.576196 -273.125492) (xy 67.568153 -273.176274) (xy 67.552265 -273.225173)
			(xy 67.528922 -273.270985) (xy 67.498701 -273.312581) (xy 67.462345 -273.348937) (xy 67.420749 -273.379158)
			(xy 67.374937 -273.402501) (xy 67.326038 -273.418389) (xy 67.275256 -273.426432) (xy 67.22384 -273.426432)
			(xy 67.173058 -273.418389) (xy 67.124159 -273.402501) (xy 67.078347 -273.379158) (xy 67.036751 -273.348937)
			(xy 67.000395 -273.312581) (xy 66.970174 -273.270985) (xy 66.946831 -273.225173) (xy 66.930943 -273.176274)
			(xy 66.9229 -273.125492) (xy 65.676276 -273.125492) (xy 65.668233 -273.176274) (xy 65.652345 -273.225173)
			(xy 65.629002 -273.270985) (xy 65.598781 -273.312581) (xy 65.562425 -273.348937) (xy 65.520829 -273.379158)
			(xy 65.475017 -273.402501) (xy 65.426118 -273.418389) (xy 65.375336 -273.426432) (xy 65.32392 -273.426432)
			(xy 65.273138 -273.418389) (xy 65.224239 -273.402501) (xy 65.178427 -273.379158) (xy 65.136831 -273.348937)
			(xy 65.100475 -273.312581) (xy 65.070254 -273.270985) (xy 65.046911 -273.225173) (xy 65.031023 -273.176274)
			(xy 65.02298 -273.125492) (xy 63.776356 -273.125492) (xy 63.768313 -273.176274) (xy 63.752425 -273.225173)
			(xy 63.729082 -273.270985) (xy 63.698861 -273.312581) (xy 63.662505 -273.348937) (xy 63.620909 -273.379158)
			(xy 63.575097 -273.402501) (xy 63.526198 -273.418389) (xy 63.475416 -273.426432) (xy 63.424 -273.426432)
			(xy 63.373218 -273.418389) (xy 63.324319 -273.402501) (xy 63.278507 -273.379158) (xy 63.236911 -273.348937)
			(xy 63.200555 -273.312581) (xy 63.170334 -273.270985) (xy 63.146991 -273.225173) (xy 63.131103 -273.176274)
			(xy 63.12306 -273.125492) (xy 61.876182 -273.125492) (xy 61.868139 -273.176274) (xy 61.852251 -273.225173)
			(xy 61.828908 -273.270985) (xy 61.798687 -273.312581) (xy 61.762331 -273.348937) (xy 61.720735 -273.379158)
			(xy 61.674923 -273.402501) (xy 61.626024 -273.418389) (xy 61.575242 -273.426432) (xy 61.523826 -273.426432)
			(xy 61.473044 -273.418389) (xy 61.424145 -273.402501) (xy 61.378333 -273.379158) (xy 61.336737 -273.348937)
			(xy 61.300381 -273.312581) (xy 61.27016 -273.270985) (xy 61.246817 -273.225173) (xy 61.230929 -273.176274)
			(xy 61.222886 -273.125492) (xy 59.975915 -273.125492) (xy 59.967929 -273.175922) (xy 59.952055 -273.224777)
			(xy 59.928734 -273.270548) (xy 59.898541 -273.312107) (xy 59.862218 -273.348432) (xy 59.82066 -273.378627)
			(xy 59.77489 -273.40195) (xy 59.726035 -273.417825) (xy 59.675299 -273.425863) (xy 59.649614 -273.426428)
			(xy 59.648852 -273.426428) (xy 59.625787 -273.425995) (xy 59.580122 -273.419443) (xy 59.53583 -273.406547)
			(xy 59.493786 -273.387561) (xy 59.454823 -273.362862) (xy 59.437016 -273.348196) (xy 59.423808 -273.336766)
			(xy 59.412632 -273.335496) (xy 59.405279 -273.334781) (xy 59.390692 -273.337093) (xy 59.38393 -273.340068)
			(xy 59.318652 -273.37131) (xy 59.310889 -273.376005) (xy 59.299034 -273.389721) (xy 59.292669 -273.406697)
			(xy 59.292236 -273.41576) (xy 59.292236 -273.73326) (xy 59.292591 -273.742343) (xy 59.298921 -273.759369)
			(xy 59.310827 -273.773087) (xy 59.318652 -273.77771) (xy 59.397646 -273.815556) (xy 59.423808 -273.812254)
			(xy 59.437016 -273.800824) (xy 59.454821 -273.786153) (xy 59.493777 -273.76144) (xy 59.535821 -273.742449)
			(xy 59.580117 -273.729559) (xy 59.625786 -273.723024) (xy 59.648852 -273.722592) (xy 59.649614 -273.722592)
			(xy 59.675302 -273.723097) (xy 59.726045 -273.731136) (xy 59.774905 -273.747013) (xy 59.820681 -273.770339)
			(xy 59.862244 -273.800538) (xy 59.898571 -273.836867) (xy 59.928768 -273.878431) (xy 59.952092 -273.924208)
			(xy 59.967968 -273.973069) (xy 59.976004 -274.023812) (xy 59.976004 -274.075188) (xy 59.975962 -274.075452)
			(xy 61.222886 -274.075452) (xy 61.222886 -274.024036) (xy 61.230929 -273.973254) (xy 61.246817 -273.924355)
			(xy 61.27016 -273.878543) (xy 61.300381 -273.836947) (xy 61.336737 -273.800591) (xy 61.378333 -273.77037)
			(xy 61.424145 -273.747027) (xy 61.473044 -273.731139) (xy 61.523826 -273.723096) (xy 61.575242 -273.723096)
			(xy 61.626024 -273.731139) (xy 61.674923 -273.747027) (xy 61.720735 -273.77037) (xy 61.762331 -273.800591)
			(xy 61.798687 -273.836947) (xy 61.828908 -273.878543) (xy 61.852251 -273.924355) (xy 61.868139 -273.973254)
			(xy 61.876182 -274.024036) (xy 61.876686 -274.049744) (xy 61.876182 -274.075452) (xy 63.12306 -274.075452)
			(xy 63.12306 -274.024036) (xy 63.131103 -273.973254) (xy 63.146991 -273.924355) (xy 63.170334 -273.878543)
			(xy 63.200555 -273.836947) (xy 63.236911 -273.800591) (xy 63.278507 -273.77037) (xy 63.324319 -273.747027)
			(xy 63.373218 -273.731139) (xy 63.424 -273.723096) (xy 63.475416 -273.723096) (xy 63.526198 -273.731139)
			(xy 63.575097 -273.747027) (xy 63.620909 -273.77037) (xy 63.662505 -273.800591) (xy 63.698861 -273.836947)
			(xy 63.729082 -273.878543) (xy 63.752425 -273.924355) (xy 63.768313 -273.973254) (xy 63.776356 -274.024036)
			(xy 63.77686 -274.049744) (xy 63.776356 -274.075452) (xy 65.02298 -274.075452) (xy 65.02298 -274.024036)
			(xy 65.031023 -273.973254) (xy 65.046911 -273.924355) (xy 65.070254 -273.878543) (xy 65.100475 -273.836947)
			(xy 65.136831 -273.800591) (xy 65.178427 -273.77037) (xy 65.224239 -273.747027) (xy 65.273138 -273.731139)
			(xy 65.32392 -273.723096) (xy 65.375336 -273.723096) (xy 65.426118 -273.731139) (xy 65.475017 -273.747027)
			(xy 65.520829 -273.77037) (xy 65.562425 -273.800591) (xy 65.598781 -273.836947) (xy 65.629002 -273.878543)
			(xy 65.652345 -273.924355) (xy 65.668233 -273.973254) (xy 65.676276 -274.024036) (xy 65.67678 -274.049744)
			(xy 65.676276 -274.075452) (xy 66.9229 -274.075452) (xy 66.9229 -274.024036) (xy 66.930943 -273.973254)
			(xy 66.946831 -273.924355) (xy 66.970174 -273.878543) (xy 67.000395 -273.836947) (xy 67.036751 -273.800591)
			(xy 67.078347 -273.77037) (xy 67.124159 -273.747027) (xy 67.173058 -273.731139) (xy 67.22384 -273.723096)
			(xy 67.275256 -273.723096) (xy 67.326038 -273.731139) (xy 67.374937 -273.747027) (xy 67.420749 -273.77037)
			(xy 67.462345 -273.800591) (xy 67.498701 -273.836947) (xy 67.528922 -273.878543) (xy 67.552265 -273.924355)
			(xy 67.568153 -273.973254) (xy 67.576196 -274.024036) (xy 67.5767 -274.049744) (xy 67.576196 -274.075452)
			(xy 68.823074 -274.075452) (xy 68.823074 -274.024036) (xy 68.831117 -273.973254) (xy 68.847005 -273.924355)
			(xy 68.870348 -273.878543) (xy 68.900569 -273.836947) (xy 68.936925 -273.800591) (xy 68.978521 -273.77037)
			(xy 69.024333 -273.747027) (xy 69.073232 -273.731139) (xy 69.124014 -273.723096) (xy 69.17543 -273.723096)
			(xy 69.226212 -273.731139) (xy 69.275111 -273.747027) (xy 69.320923 -273.77037) (xy 69.362519 -273.800591)
			(xy 69.398875 -273.836947) (xy 69.429096 -273.878543) (xy 69.452439 -273.924355) (xy 69.468327 -273.973254)
			(xy 69.47637 -274.024036) (xy 69.476874 -274.049744) (xy 69.47637 -274.075452) (xy 70.722994 -274.075452)
			(xy 70.722994 -274.024036) (xy 70.731037 -273.973254) (xy 70.746925 -273.924355) (xy 70.770268 -273.878543)
			(xy 70.800489 -273.836947) (xy 70.836845 -273.800591) (xy 70.878441 -273.77037) (xy 70.924253 -273.747027)
			(xy 70.973152 -273.731139) (xy 71.023934 -273.723096) (xy 71.07535 -273.723096) (xy 71.126132 -273.731139)
			(xy 71.175031 -273.747027) (xy 71.220843 -273.77037) (xy 71.262439 -273.800591) (xy 71.298795 -273.836947)
			(xy 71.329016 -273.878543) (xy 71.352359 -273.924355) (xy 71.368247 -273.973254) (xy 71.37629 -274.024036)
			(xy 71.376794 -274.049744) (xy 71.37629 -274.075452) (xy 72.622914 -274.075452) (xy 72.622914 -274.024036)
			(xy 72.630957 -273.973254) (xy 72.646845 -273.924355) (xy 72.670188 -273.878543) (xy 72.700409 -273.836947)
			(xy 72.736765 -273.800591) (xy 72.778361 -273.77037) (xy 72.824173 -273.747027) (xy 72.873072 -273.731139)
			(xy 72.923854 -273.723096) (xy 72.97527 -273.723096) (xy 73.026052 -273.731139) (xy 73.074951 -273.747027)
			(xy 73.120763 -273.77037) (xy 73.162359 -273.800591) (xy 73.198715 -273.836947) (xy 73.228936 -273.878543)
			(xy 73.252279 -273.924355) (xy 73.268167 -273.973254) (xy 73.27621 -274.024036) (xy 73.276714 -274.049744)
			(xy 73.27621 -274.075452) (xy 74.523088 -274.075452) (xy 74.523088 -274.024036) (xy 74.531131 -273.973254)
			(xy 74.547019 -273.924355) (xy 74.570362 -273.878543) (xy 74.600583 -273.836947) (xy 74.636939 -273.800591)
			(xy 74.678535 -273.77037) (xy 74.724347 -273.747027) (xy 74.773246 -273.731139) (xy 74.824028 -273.723096)
			(xy 74.875444 -273.723096) (xy 74.926226 -273.731139) (xy 74.975125 -273.747027) (xy 75.020937 -273.77037)
			(xy 75.062533 -273.800591) (xy 75.098889 -273.836947) (xy 75.12911 -273.878543) (xy 75.152453 -273.924355)
			(xy 75.168341 -273.973254) (xy 75.176384 -274.024036) (xy 75.176888 -274.049744) (xy 75.176384 -274.075452)
			(xy 76.423008 -274.075452) (xy 76.423008 -274.024036) (xy 76.431051 -273.973254) (xy 76.446939 -273.924355)
			(xy 76.470282 -273.878543) (xy 76.500503 -273.836947) (xy 76.536859 -273.800591) (xy 76.578455 -273.77037)
			(xy 76.624267 -273.747027) (xy 76.673166 -273.731139) (xy 76.723948 -273.723096) (xy 76.775364 -273.723096)
			(xy 76.826146 -273.731139) (xy 76.875045 -273.747027) (xy 76.920857 -273.77037) (xy 76.962453 -273.800591)
			(xy 76.998809 -273.836947) (xy 77.02903 -273.878543) (xy 77.052373 -273.924355) (xy 77.068261 -273.973254)
			(xy 77.076304 -274.024036) (xy 77.076808 -274.049744) (xy 77.076304 -274.075452) (xy 78.322928 -274.075452)
			(xy 78.322928 -274.024036) (xy 78.330971 -273.973254) (xy 78.346859 -273.924355) (xy 78.370202 -273.878543)
			(xy 78.400423 -273.836947) (xy 78.436779 -273.800591) (xy 78.478375 -273.77037) (xy 78.524187 -273.747027)
			(xy 78.573086 -273.731139) (xy 78.623868 -273.723096) (xy 78.675284 -273.723096) (xy 78.726066 -273.731139)
			(xy 78.774965 -273.747027) (xy 78.820777 -273.77037) (xy 78.862373 -273.800591) (xy 78.898729 -273.836947)
			(xy 78.92895 -273.878543) (xy 78.952293 -273.924355) (xy 78.968181 -273.973254) (xy 78.976224 -274.024036)
			(xy 78.976728 -274.049744) (xy 78.976224 -274.075452) (xy 80.222848 -274.075452) (xy 80.222848 -274.024036)
			(xy 80.230891 -273.973254) (xy 80.246779 -273.924355) (xy 80.270122 -273.878543) (xy 80.300343 -273.836947)
			(xy 80.336699 -273.800591) (xy 80.378295 -273.77037) (xy 80.424107 -273.747027) (xy 80.473006 -273.731139)
			(xy 80.523788 -273.723096) (xy 80.575204 -273.723096) (xy 80.625986 -273.731139) (xy 80.674885 -273.747027)
			(xy 80.720697 -273.77037) (xy 80.762293 -273.800591) (xy 80.798649 -273.836947) (xy 80.82887 -273.878543)
			(xy 80.852213 -273.924355) (xy 80.868101 -273.973254) (xy 80.876144 -274.024036) (xy 80.876648 -274.049744)
			(xy 80.876144 -274.075452) (xy 80.868101 -274.126234) (xy 80.852213 -274.175133) (xy 80.82887 -274.220945)
			(xy 80.798649 -274.262541) (xy 80.762293 -274.298897) (xy 80.720697 -274.329118) (xy 80.674885 -274.352461)
			(xy 80.625986 -274.368349) (xy 80.575204 -274.376392) (xy 80.523788 -274.376392) (xy 80.473006 -274.368349)
			(xy 80.424107 -274.352461) (xy 80.378295 -274.329118) (xy 80.336699 -274.298897) (xy 80.300343 -274.262541)
			(xy 80.270122 -274.220945) (xy 80.246779 -274.175133) (xy 80.230891 -274.126234) (xy 80.222848 -274.075452)
			(xy 78.976224 -274.075452) (xy 78.968181 -274.126234) (xy 78.952293 -274.175133) (xy 78.92895 -274.220945)
			(xy 78.898729 -274.262541) (xy 78.862373 -274.298897) (xy 78.820777 -274.329118) (xy 78.774965 -274.352461)
			(xy 78.726066 -274.368349) (xy 78.675284 -274.376392) (xy 78.623868 -274.376392) (xy 78.573086 -274.368349)
			(xy 78.524187 -274.352461) (xy 78.478375 -274.329118) (xy 78.436779 -274.298897) (xy 78.400423 -274.262541)
			(xy 78.370202 -274.220945) (xy 78.346859 -274.175133) (xy 78.330971 -274.126234) (xy 78.322928 -274.075452)
			(xy 77.076304 -274.075452) (xy 77.068261 -274.126234) (xy 77.052373 -274.175133) (xy 77.02903 -274.220945)
			(xy 76.998809 -274.262541) (xy 76.962453 -274.298897) (xy 76.920857 -274.329118) (xy 76.875045 -274.352461)
			(xy 76.826146 -274.368349) (xy 76.775364 -274.376392) (xy 76.723948 -274.376392) (xy 76.673166 -274.368349)
			(xy 76.624267 -274.352461) (xy 76.578455 -274.329118) (xy 76.536859 -274.298897) (xy 76.500503 -274.262541)
			(xy 76.470282 -274.220945) (xy 76.446939 -274.175133) (xy 76.431051 -274.126234) (xy 76.423008 -274.075452)
			(xy 75.176384 -274.075452) (xy 75.168341 -274.126234) (xy 75.152453 -274.175133) (xy 75.12911 -274.220945)
			(xy 75.098889 -274.262541) (xy 75.062533 -274.298897) (xy 75.020937 -274.329118) (xy 74.975125 -274.352461)
			(xy 74.926226 -274.368349) (xy 74.875444 -274.376392) (xy 74.824028 -274.376392) (xy 74.773246 -274.368349)
			(xy 74.724347 -274.352461) (xy 74.678535 -274.329118) (xy 74.636939 -274.298897) (xy 74.600583 -274.262541)
			(xy 74.570362 -274.220945) (xy 74.547019 -274.175133) (xy 74.531131 -274.126234) (xy 74.523088 -274.075452)
			(xy 73.27621 -274.075452) (xy 73.268167 -274.126234) (xy 73.252279 -274.175133) (xy 73.228936 -274.220945)
			(xy 73.198715 -274.262541) (xy 73.162359 -274.298897) (xy 73.120763 -274.329118) (xy 73.074951 -274.352461)
			(xy 73.026052 -274.368349) (xy 72.97527 -274.376392) (xy 72.923854 -274.376392) (xy 72.873072 -274.368349)
			(xy 72.824173 -274.352461) (xy 72.778361 -274.329118) (xy 72.736765 -274.298897) (xy 72.700409 -274.262541)
			(xy 72.670188 -274.220945) (xy 72.646845 -274.175133) (xy 72.630957 -274.126234) (xy 72.622914 -274.075452)
			(xy 71.37629 -274.075452) (xy 71.368247 -274.126234) (xy 71.352359 -274.175133) (xy 71.329016 -274.220945)
			(xy 71.298795 -274.262541) (xy 71.262439 -274.298897) (xy 71.220843 -274.329118) (xy 71.175031 -274.352461)
			(xy 71.126132 -274.368349) (xy 71.07535 -274.376392) (xy 71.023934 -274.376392) (xy 70.973152 -274.368349)
			(xy 70.924253 -274.352461) (xy 70.878441 -274.329118) (xy 70.836845 -274.298897) (xy 70.800489 -274.262541)
			(xy 70.770268 -274.220945) (xy 70.746925 -274.175133) (xy 70.731037 -274.126234) (xy 70.722994 -274.075452)
			(xy 69.47637 -274.075452) (xy 69.468327 -274.126234) (xy 69.452439 -274.175133) (xy 69.429096 -274.220945)
			(xy 69.398875 -274.262541) (xy 69.362519 -274.298897) (xy 69.320923 -274.329118) (xy 69.275111 -274.352461)
			(xy 69.226212 -274.368349) (xy 69.17543 -274.376392) (xy 69.124014 -274.376392) (xy 69.073232 -274.368349)
			(xy 69.024333 -274.352461) (xy 68.978521 -274.329118) (xy 68.936925 -274.298897) (xy 68.900569 -274.262541)
			(xy 68.870348 -274.220945) (xy 68.847005 -274.175133) (xy 68.831117 -274.126234) (xy 68.823074 -274.075452)
			(xy 67.576196 -274.075452) (xy 67.568153 -274.126234) (xy 67.552265 -274.175133) (xy 67.528922 -274.220945)
			(xy 67.498701 -274.262541) (xy 67.462345 -274.298897) (xy 67.420749 -274.329118) (xy 67.374937 -274.352461)
			(xy 67.326038 -274.368349) (xy 67.275256 -274.376392) (xy 67.22384 -274.376392) (xy 67.173058 -274.368349)
			(xy 67.124159 -274.352461) (xy 67.078347 -274.329118) (xy 67.036751 -274.298897) (xy 67.000395 -274.262541)
			(xy 66.970174 -274.220945) (xy 66.946831 -274.175133) (xy 66.930943 -274.126234) (xy 66.9229 -274.075452)
			(xy 65.676276 -274.075452) (xy 65.668233 -274.126234) (xy 65.652345 -274.175133) (xy 65.629002 -274.220945)
			(xy 65.598781 -274.262541) (xy 65.562425 -274.298897) (xy 65.520829 -274.329118) (xy 65.475017 -274.352461)
			(xy 65.426118 -274.368349) (xy 65.375336 -274.376392) (xy 65.32392 -274.376392) (xy 65.273138 -274.368349)
			(xy 65.224239 -274.352461) (xy 65.178427 -274.329118) (xy 65.136831 -274.298897) (xy 65.100475 -274.262541)
			(xy 65.070254 -274.220945) (xy 65.046911 -274.175133) (xy 65.031023 -274.126234) (xy 65.02298 -274.075452)
			(xy 63.776356 -274.075452) (xy 63.768313 -274.126234) (xy 63.752425 -274.175133) (xy 63.729082 -274.220945)
			(xy 63.698861 -274.262541) (xy 63.662505 -274.298897) (xy 63.620909 -274.329118) (xy 63.575097 -274.352461)
			(xy 63.526198 -274.368349) (xy 63.475416 -274.376392) (xy 63.424 -274.376392) (xy 63.373218 -274.368349)
			(xy 63.324319 -274.352461) (xy 63.278507 -274.329118) (xy 63.236911 -274.298897) (xy 63.200555 -274.262541)
			(xy 63.170334 -274.220945) (xy 63.146991 -274.175133) (xy 63.131103 -274.126234) (xy 63.12306 -274.075452)
			(xy 61.876182 -274.075452) (xy 61.868139 -274.126234) (xy 61.852251 -274.175133) (xy 61.828908 -274.220945)
			(xy 61.798687 -274.262541) (xy 61.762331 -274.298897) (xy 61.720735 -274.329118) (xy 61.674923 -274.352461)
			(xy 61.626024 -274.368349) (xy 61.575242 -274.376392) (xy 61.523826 -274.376392) (xy 61.473044 -274.368349)
			(xy 61.424145 -274.352461) (xy 61.378333 -274.329118) (xy 61.336737 -274.298897) (xy 61.300381 -274.262541)
			(xy 61.27016 -274.220945) (xy 61.246817 -274.175133) (xy 61.230929 -274.126234) (xy 61.222886 -274.075452)
			(xy 59.975962 -274.075452) (xy 59.967968 -274.125931) (xy 59.952092 -274.174792) (xy 59.928768 -274.220569)
			(xy 59.898571 -274.262133) (xy 59.862244 -274.298462) (xy 59.820681 -274.328661) (xy 59.774905 -274.351987)
			(xy 59.726045 -274.367864) (xy 59.675302 -274.375903) (xy 59.649614 -274.376388) (xy 59.648852 -274.376388)
			(xy 59.625787 -274.375955) (xy 59.580123 -274.369403) (xy 59.535832 -274.356505) (xy 59.493789 -274.337517)
			(xy 59.454828 -274.312816) (xy 59.437016 -274.298156) (xy 59.423808 -274.286726) (xy 59.412632 -274.285456)
			(xy 59.405279 -274.284741) (xy 59.390693 -274.287056) (xy 59.38393 -274.290028) (xy 59.318652 -274.32127)
			(xy 59.310885 -274.325963) (xy 59.299019 -274.339678) (xy 59.292641 -274.356654) (xy 59.292236 -274.36572)
			(xy 59.292236 -275.025412) (xy 60.272926 -275.025412) (xy 60.272926 -274.973996) (xy 60.280969 -274.923214)
			(xy 60.296857 -274.874315) (xy 60.3202 -274.828503) (xy 60.350421 -274.786907) (xy 60.386777 -274.750551)
			(xy 60.428373 -274.72033) (xy 60.474185 -274.696987) (xy 60.523084 -274.681099) (xy 60.573866 -274.673056)
			(xy 60.625282 -274.673056) (xy 60.676064 -274.681099) (xy 60.724963 -274.696987) (xy 60.770775 -274.72033)
			(xy 60.812371 -274.750551) (xy 60.848727 -274.786907) (xy 60.878948 -274.828503) (xy 60.902291 -274.874315)
			(xy 60.918179 -274.923214) (xy 60.926222 -274.973996) (xy 60.926726 -274.999704) (xy 60.926222 -275.025412)
			(xy 60.926182 -275.025666) (xy 62.172846 -275.025666) (xy 62.172846 -274.97425) (xy 62.180889 -274.923468)
			(xy 62.196777 -274.874569) (xy 62.22012 -274.828757) (xy 62.250341 -274.787161) (xy 62.286697 -274.750805)
			(xy 62.328293 -274.720584) (xy 62.374105 -274.697241) (xy 62.423004 -274.681353) (xy 62.473786 -274.67331)
			(xy 62.525202 -274.67331) (xy 62.575984 -274.681353) (xy 62.624883 -274.697241) (xy 62.670695 -274.720584)
			(xy 62.712291 -274.750805) (xy 62.748647 -274.787161) (xy 62.778868 -274.828757) (xy 62.802211 -274.874569)
			(xy 62.818099 -274.923468) (xy 62.826142 -274.97425) (xy 62.826646 -274.999958) (xy 62.826147 -275.025412)
			(xy 64.07302 -275.025412) (xy 64.07302 -274.973996) (xy 64.081063 -274.923214) (xy 64.096951 -274.874315)
			(xy 64.120294 -274.828503) (xy 64.150515 -274.786907) (xy 64.186871 -274.750551) (xy 64.228467 -274.72033)
			(xy 64.274279 -274.696987) (xy 64.323178 -274.681099) (xy 64.37396 -274.673056) (xy 64.425376 -274.673056)
			(xy 64.476158 -274.681099) (xy 64.525057 -274.696987) (xy 64.570869 -274.72033) (xy 64.612465 -274.750551)
			(xy 64.648821 -274.786907) (xy 64.679042 -274.828503) (xy 64.702385 -274.874315) (xy 64.718273 -274.923214)
			(xy 64.726316 -274.973996) (xy 64.72682 -274.999704) (xy 64.726316 -275.025412) (xy 64.726276 -275.025666)
			(xy 65.97294 -275.025666) (xy 65.97294 -274.97425) (xy 65.980983 -274.923468) (xy 65.996871 -274.874569)
			(xy 66.020214 -274.828757) (xy 66.050435 -274.787161) (xy 66.086791 -274.750805) (xy 66.128387 -274.720584)
			(xy 66.174199 -274.697241) (xy 66.223098 -274.681353) (xy 66.27388 -274.67331) (xy 66.325296 -274.67331)
			(xy 66.376078 -274.681353) (xy 66.424977 -274.697241) (xy 66.470789 -274.720584) (xy 66.512385 -274.750805)
			(xy 66.548741 -274.787161) (xy 66.578962 -274.828757) (xy 66.602305 -274.874569) (xy 66.618193 -274.923468)
			(xy 66.626236 -274.97425) (xy 66.62674 -274.999958) (xy 66.626241 -275.025412) (xy 67.87286 -275.025412)
			(xy 67.87286 -274.973996) (xy 67.880903 -274.923214) (xy 67.896791 -274.874315) (xy 67.920134 -274.828503)
			(xy 67.950355 -274.786907) (xy 67.986711 -274.750551) (xy 68.028307 -274.72033) (xy 68.074119 -274.696987)
			(xy 68.123018 -274.681099) (xy 68.1738 -274.673056) (xy 68.225216 -274.673056) (xy 68.275998 -274.681099)
			(xy 68.324897 -274.696987) (xy 68.370709 -274.72033) (xy 68.412305 -274.750551) (xy 68.448661 -274.786907)
			(xy 68.478882 -274.828503) (xy 68.502225 -274.874315) (xy 68.518113 -274.923214) (xy 68.526156 -274.973996)
			(xy 68.52666 -274.999704) (xy 68.526156 -275.025412) (xy 68.526116 -275.025666) (xy 69.77278 -275.025666)
			(xy 69.77278 -274.97425) (xy 69.780823 -274.923468) (xy 69.796711 -274.874569) (xy 69.820054 -274.828757)
			(xy 69.850275 -274.787161) (xy 69.886631 -274.750805) (xy 69.928227 -274.720584) (xy 69.974039 -274.697241)
			(xy 70.022938 -274.681353) (xy 70.07372 -274.67331) (xy 70.125136 -274.67331) (xy 70.175918 -274.681353)
			(xy 70.224817 -274.697241) (xy 70.270629 -274.720584) (xy 70.312225 -274.750805) (xy 70.348581 -274.787161)
			(xy 70.378802 -274.828757) (xy 70.402145 -274.874569) (xy 70.418033 -274.923468) (xy 70.426076 -274.97425)
			(xy 70.42658 -274.999958) (xy 70.426081 -275.025412) (xy 71.672954 -275.025412) (xy 71.672954 -274.973996)
			(xy 71.680997 -274.923214) (xy 71.696885 -274.874315) (xy 71.720228 -274.828503) (xy 71.750449 -274.786907)
			(xy 71.786805 -274.750551) (xy 71.828401 -274.72033) (xy 71.874213 -274.696987) (xy 71.923112 -274.681099)
			(xy 71.973894 -274.673056) (xy 72.02531 -274.673056) (xy 72.076092 -274.681099) (xy 72.124991 -274.696987)
			(xy 72.170803 -274.72033) (xy 72.212399 -274.750551) (xy 72.248755 -274.786907) (xy 72.278976 -274.828503)
			(xy 72.302319 -274.874315) (xy 72.318207 -274.923214) (xy 72.32625 -274.973996) (xy 72.326754 -274.999704)
			(xy 72.32625 -275.025412) (xy 72.32621 -275.025666) (xy 73.572874 -275.025666) (xy 73.572874 -274.97425)
			(xy 73.580917 -274.923468) (xy 73.596805 -274.874569) (xy 73.620148 -274.828757) (xy 73.650369 -274.787161)
			(xy 73.686725 -274.750805) (xy 73.728321 -274.720584) (xy 73.774133 -274.697241) (xy 73.823032 -274.681353)
			(xy 73.873814 -274.67331) (xy 73.92523 -274.67331) (xy 73.976012 -274.681353) (xy 74.024911 -274.697241)
			(xy 74.070723 -274.720584) (xy 74.112319 -274.750805) (xy 74.148675 -274.787161) (xy 74.178896 -274.828757)
			(xy 74.202239 -274.874569) (xy 74.218127 -274.923468) (xy 74.22617 -274.97425) (xy 74.226674 -274.999958)
			(xy 74.226175 -275.025412) (xy 75.473048 -275.025412) (xy 75.473048 -274.973996) (xy 75.481091 -274.923214)
			(xy 75.496979 -274.874315) (xy 75.520322 -274.828503) (xy 75.550543 -274.786907) (xy 75.586899 -274.750551)
			(xy 75.628495 -274.72033) (xy 75.674307 -274.696987) (xy 75.723206 -274.681099) (xy 75.773988 -274.673056)
			(xy 75.825404 -274.673056) (xy 75.876186 -274.681099) (xy 75.925085 -274.696987) (xy 75.970897 -274.72033)
			(xy 76.012493 -274.750551) (xy 76.048849 -274.786907) (xy 76.07907 -274.828503) (xy 76.102413 -274.874315)
			(xy 76.118301 -274.923214) (xy 76.126344 -274.973996) (xy 76.126848 -274.999704) (xy 76.126344 -275.025412)
			(xy 76.126304 -275.025666) (xy 77.372968 -275.025666) (xy 77.372968 -274.97425) (xy 77.381011 -274.923468)
			(xy 77.396899 -274.874569) (xy 77.420242 -274.828757) (xy 77.450463 -274.787161) (xy 77.486819 -274.750805)
			(xy 77.528415 -274.720584) (xy 77.574227 -274.697241) (xy 77.623126 -274.681353) (xy 77.673908 -274.67331)
			(xy 77.725324 -274.67331) (xy 77.776106 -274.681353) (xy 77.825005 -274.697241) (xy 77.870817 -274.720584)
			(xy 77.912413 -274.750805) (xy 77.948769 -274.787161) (xy 77.97899 -274.828757) (xy 78.002333 -274.874569)
			(xy 78.018221 -274.923468) (xy 78.026264 -274.97425) (xy 78.026768 -274.999958) (xy 78.026264 -275.025666)
			(xy 79.272888 -275.025666) (xy 79.272888 -274.97425) (xy 79.280931 -274.923468) (xy 79.296819 -274.874569)
			(xy 79.320162 -274.828757) (xy 79.350383 -274.787161) (xy 79.386739 -274.750805) (xy 79.428335 -274.720584)
			(xy 79.474147 -274.697241) (xy 79.523046 -274.681353) (xy 79.573828 -274.67331) (xy 79.625244 -274.67331)
			(xy 79.676026 -274.681353) (xy 79.724925 -274.697241) (xy 79.770737 -274.720584) (xy 79.812333 -274.750805)
			(xy 79.848689 -274.787161) (xy 79.87891 -274.828757) (xy 79.902253 -274.874569) (xy 79.918141 -274.923468)
			(xy 79.926184 -274.97425) (xy 79.926688 -274.999958) (xy 79.926189 -275.025412) (xy 81.173316 -275.025412)
			(xy 81.173316 -274.973996) (xy 81.181359 -274.923214) (xy 81.197247 -274.874315) (xy 81.22059 -274.828503)
			(xy 81.250811 -274.786907) (xy 81.287167 -274.750551) (xy 81.328763 -274.72033) (xy 81.374575 -274.696987)
			(xy 81.423474 -274.681099) (xy 81.474256 -274.673056) (xy 81.525672 -274.673056) (xy 81.576454 -274.681099)
			(xy 81.625353 -274.696987) (xy 81.671165 -274.72033) (xy 81.712761 -274.750551) (xy 81.749117 -274.786907)
			(xy 81.779338 -274.828503) (xy 81.802681 -274.874315) (xy 81.818569 -274.923214) (xy 81.826612 -274.973996)
			(xy 81.827116 -274.999704) (xy 81.826612 -275.025412) (xy 82.123276 -275.025412) (xy 82.123276 -274.973996)
			(xy 82.131319 -274.923214) (xy 82.147207 -274.874315) (xy 82.17055 -274.828503) (xy 82.200771 -274.786907)
			(xy 82.237127 -274.750551) (xy 82.278723 -274.72033) (xy 82.324535 -274.696987) (xy 82.373434 -274.681099)
			(xy 82.424216 -274.673056) (xy 82.475632 -274.673056) (xy 82.526414 -274.681099) (xy 82.575313 -274.696987)
			(xy 82.621125 -274.72033) (xy 82.662721 -274.750551) (xy 82.699077 -274.786907) (xy 82.729298 -274.828503)
			(xy 82.752641 -274.874315) (xy 82.768529 -274.923214) (xy 82.776572 -274.973996) (xy 82.777076 -274.999704)
			(xy 82.776572 -275.025412) (xy 82.768529 -275.076194) (xy 82.752641 -275.125093) (xy 82.729298 -275.170905)
			(xy 82.699077 -275.212501) (xy 82.662721 -275.248857) (xy 82.621125 -275.279078) (xy 82.575313 -275.302421)
			(xy 82.526414 -275.318309) (xy 82.475632 -275.326352) (xy 82.424216 -275.326352) (xy 82.373434 -275.318309)
			(xy 82.324535 -275.302421) (xy 82.278723 -275.279078) (xy 82.237127 -275.248857) (xy 82.200771 -275.212501)
			(xy 82.17055 -275.170905) (xy 82.147207 -275.125093) (xy 82.131319 -275.076194) (xy 82.123276 -275.025412)
			(xy 81.826612 -275.025412) (xy 81.818569 -275.076194) (xy 81.802681 -275.125093) (xy 81.779338 -275.170905)
			(xy 81.749117 -275.212501) (xy 81.712761 -275.248857) (xy 81.671165 -275.279078) (xy 81.625353 -275.302421)
			(xy 81.576454 -275.318309) (xy 81.525672 -275.326352) (xy 81.474256 -275.326352) (xy 81.423474 -275.318309)
			(xy 81.374575 -275.302421) (xy 81.328763 -275.279078) (xy 81.287167 -275.248857) (xy 81.250811 -275.212501)
			(xy 81.22059 -275.170905) (xy 81.197247 -275.125093) (xy 81.181359 -275.076194) (xy 81.173316 -275.025412)
			(xy 79.926189 -275.025412) (xy 79.926184 -275.025666) (xy 79.918141 -275.076448) (xy 79.902253 -275.125347)
			(xy 79.87891 -275.171159) (xy 79.848689 -275.212755) (xy 79.812333 -275.249111) (xy 79.770737 -275.279332)
			(xy 79.724925 -275.302675) (xy 79.676026 -275.318563) (xy 79.625244 -275.326606) (xy 79.573828 -275.326606)
			(xy 79.523046 -275.318563) (xy 79.474147 -275.302675) (xy 79.428335 -275.279332) (xy 79.386739 -275.249111)
			(xy 79.350383 -275.212755) (xy 79.320162 -275.171159) (xy 79.296819 -275.125347) (xy 79.280931 -275.076448)
			(xy 79.272888 -275.025666) (xy 78.026264 -275.025666) (xy 78.018221 -275.076448) (xy 78.002333 -275.125347)
			(xy 77.97899 -275.171159) (xy 77.948769 -275.212755) (xy 77.912413 -275.249111) (xy 77.870817 -275.279332)
			(xy 77.825005 -275.302675) (xy 77.776106 -275.318563) (xy 77.725324 -275.326606) (xy 77.673908 -275.326606)
			(xy 77.623126 -275.318563) (xy 77.574227 -275.302675) (xy 77.528415 -275.279332) (xy 77.486819 -275.249111)
			(xy 77.450463 -275.212755) (xy 77.420242 -275.171159) (xy 77.396899 -275.125347) (xy 77.381011 -275.076448)
			(xy 77.372968 -275.025666) (xy 76.126304 -275.025666) (xy 76.118301 -275.076194) (xy 76.102413 -275.125093)
			(xy 76.07907 -275.170905) (xy 76.048849 -275.212501) (xy 76.012493 -275.248857) (xy 75.970897 -275.279078)
			(xy 75.925085 -275.302421) (xy 75.876186 -275.318309) (xy 75.825404 -275.326352) (xy 75.773988 -275.326352)
			(xy 75.723206 -275.318309) (xy 75.674307 -275.302421) (xy 75.628495 -275.279078) (xy 75.586899 -275.248857)
			(xy 75.550543 -275.212501) (xy 75.520322 -275.170905) (xy 75.496979 -275.125093) (xy 75.481091 -275.076194)
			(xy 75.473048 -275.025412) (xy 74.226175 -275.025412) (xy 74.22617 -275.025666) (xy 74.218127 -275.076448)
			(xy 74.202239 -275.125347) (xy 74.178896 -275.171159) (xy 74.148675 -275.212755) (xy 74.112319 -275.249111)
			(xy 74.070723 -275.279332) (xy 74.024911 -275.302675) (xy 73.976012 -275.318563) (xy 73.92523 -275.326606)
			(xy 73.873814 -275.326606) (xy 73.823032 -275.318563) (xy 73.774133 -275.302675) (xy 73.728321 -275.279332)
			(xy 73.686725 -275.249111) (xy 73.650369 -275.212755) (xy 73.620148 -275.171159) (xy 73.596805 -275.125347)
			(xy 73.580917 -275.076448) (xy 73.572874 -275.025666) (xy 72.32621 -275.025666) (xy 72.318207 -275.076194)
			(xy 72.302319 -275.125093) (xy 72.278976 -275.170905) (xy 72.248755 -275.212501) (xy 72.212399 -275.248857)
			(xy 72.170803 -275.279078) (xy 72.124991 -275.302421) (xy 72.076092 -275.318309) (xy 72.02531 -275.326352)
			(xy 71.973894 -275.326352) (xy 71.923112 -275.318309) (xy 71.874213 -275.302421) (xy 71.828401 -275.279078)
			(xy 71.786805 -275.248857) (xy 71.750449 -275.212501) (xy 71.720228 -275.170905) (xy 71.696885 -275.125093)
			(xy 71.680997 -275.076194) (xy 71.672954 -275.025412) (xy 70.426081 -275.025412) (xy 70.426076 -275.025666)
			(xy 70.418033 -275.076448) (xy 70.402145 -275.125347) (xy 70.378802 -275.171159) (xy 70.348581 -275.212755)
			(xy 70.312225 -275.249111) (xy 70.270629 -275.279332) (xy 70.224817 -275.302675) (xy 70.175918 -275.318563)
			(xy 70.125136 -275.326606) (xy 70.07372 -275.326606) (xy 70.022938 -275.318563) (xy 69.974039 -275.302675)
			(xy 69.928227 -275.279332) (xy 69.886631 -275.249111) (xy 69.850275 -275.212755) (xy 69.820054 -275.171159)
			(xy 69.796711 -275.125347) (xy 69.780823 -275.076448) (xy 69.77278 -275.025666) (xy 68.526116 -275.025666)
			(xy 68.518113 -275.076194) (xy 68.502225 -275.125093) (xy 68.478882 -275.170905) (xy 68.448661 -275.212501)
			(xy 68.412305 -275.248857) (xy 68.370709 -275.279078) (xy 68.324897 -275.302421) (xy 68.275998 -275.318309)
			(xy 68.225216 -275.326352) (xy 68.1738 -275.326352) (xy 68.123018 -275.318309) (xy 68.074119 -275.302421)
			(xy 68.028307 -275.279078) (xy 67.986711 -275.248857) (xy 67.950355 -275.212501) (xy 67.920134 -275.170905)
			(xy 67.896791 -275.125093) (xy 67.880903 -275.076194) (xy 67.87286 -275.025412) (xy 66.626241 -275.025412)
			(xy 66.626236 -275.025666) (xy 66.618193 -275.076448) (xy 66.602305 -275.125347) (xy 66.578962 -275.171159)
			(xy 66.548741 -275.212755) (xy 66.512385 -275.249111) (xy 66.470789 -275.279332) (xy 66.424977 -275.302675)
			(xy 66.376078 -275.318563) (xy 66.325296 -275.326606) (xy 66.27388 -275.326606) (xy 66.223098 -275.318563)
			(xy 66.174199 -275.302675) (xy 66.128387 -275.279332) (xy 66.086791 -275.249111) (xy 66.050435 -275.212755)
			(xy 66.020214 -275.171159) (xy 65.996871 -275.125347) (xy 65.980983 -275.076448) (xy 65.97294 -275.025666)
			(xy 64.726276 -275.025666) (xy 64.718273 -275.076194) (xy 64.702385 -275.125093) (xy 64.679042 -275.170905)
			(xy 64.648821 -275.212501) (xy 64.612465 -275.248857) (xy 64.570869 -275.279078) (xy 64.525057 -275.302421)
			(xy 64.476158 -275.318309) (xy 64.425376 -275.326352) (xy 64.37396 -275.326352) (xy 64.323178 -275.318309)
			(xy 64.274279 -275.302421) (xy 64.228467 -275.279078) (xy 64.186871 -275.248857) (xy 64.150515 -275.212501)
			(xy 64.120294 -275.170905) (xy 64.096951 -275.125093) (xy 64.081063 -275.076194) (xy 64.07302 -275.025412)
			(xy 62.826147 -275.025412) (xy 62.826142 -275.025666) (xy 62.818099 -275.076448) (xy 62.802211 -275.125347)
			(xy 62.778868 -275.171159) (xy 62.748647 -275.212755) (xy 62.712291 -275.249111) (xy 62.670695 -275.279332)
			(xy 62.624883 -275.302675) (xy 62.575984 -275.318563) (xy 62.525202 -275.326606) (xy 62.473786 -275.326606)
			(xy 62.423004 -275.318563) (xy 62.374105 -275.302675) (xy 62.328293 -275.279332) (xy 62.286697 -275.249111)
			(xy 62.250341 -275.212755) (xy 62.22012 -275.171159) (xy 62.196777 -275.125347) (xy 62.180889 -275.076448)
			(xy 62.172846 -275.025666) (xy 60.926182 -275.025666) (xy 60.918179 -275.076194) (xy 60.902291 -275.125093)
			(xy 60.878948 -275.170905) (xy 60.848727 -275.212501) (xy 60.812371 -275.248857) (xy 60.770775 -275.279078)
			(xy 60.724963 -275.302421) (xy 60.676064 -275.318309) (xy 60.625282 -275.326352) (xy 60.573866 -275.326352)
			(xy 60.523084 -275.318309) (xy 60.474185 -275.302421) (xy 60.428373 -275.279078) (xy 60.386777 -275.248857)
			(xy 60.350421 -275.212501) (xy 60.3202 -275.170905) (xy 60.296857 -275.125093) (xy 60.280969 -275.076194)
			(xy 60.272926 -275.025412) (xy 59.292236 -275.025412) (xy 59.292236 -275.975372) (xy 60.272926 -275.975372)
			(xy 60.272926 -275.923956) (xy 60.280969 -275.873174) (xy 60.296857 -275.824275) (xy 60.3202 -275.778463)
			(xy 60.350421 -275.736867) (xy 60.386777 -275.700511) (xy 60.428373 -275.67029) (xy 60.474185 -275.646947)
			(xy 60.523084 -275.631059) (xy 60.573866 -275.623016) (xy 60.625282 -275.623016) (xy 60.676064 -275.631059)
			(xy 60.724963 -275.646947) (xy 60.770775 -275.67029) (xy 60.812371 -275.700511) (xy 60.848727 -275.736867)
			(xy 60.878948 -275.778463) (xy 60.902291 -275.824275) (xy 60.918179 -275.873174) (xy 60.926222 -275.923956)
			(xy 60.926726 -275.949664) (xy 60.926222 -275.975372) (xy 60.926182 -275.975626) (xy 62.172846 -275.975626)
			(xy 62.172846 -275.92421) (xy 62.180889 -275.873428) (xy 62.196777 -275.824529) (xy 62.22012 -275.778717)
			(xy 62.250341 -275.737121) (xy 62.286697 -275.700765) (xy 62.328293 -275.670544) (xy 62.374105 -275.647201)
			(xy 62.423004 -275.631313) (xy 62.473786 -275.62327) (xy 62.525202 -275.62327) (xy 62.575984 -275.631313)
			(xy 62.624883 -275.647201) (xy 62.670695 -275.670544) (xy 62.712291 -275.700765) (xy 62.748647 -275.737121)
			(xy 62.778868 -275.778717) (xy 62.802211 -275.824529) (xy 62.818099 -275.873428) (xy 62.826142 -275.92421)
			(xy 62.826646 -275.949918) (xy 62.826147 -275.975372) (xy 64.07302 -275.975372) (xy 64.07302 -275.923956)
			(xy 64.081063 -275.873174) (xy 64.096951 -275.824275) (xy 64.120294 -275.778463) (xy 64.150515 -275.736867)
			(xy 64.186871 -275.700511) (xy 64.228467 -275.67029) (xy 64.274279 -275.646947) (xy 64.323178 -275.631059)
			(xy 64.37396 -275.623016) (xy 64.425376 -275.623016) (xy 64.476158 -275.631059) (xy 64.525057 -275.646947)
			(xy 64.570869 -275.67029) (xy 64.612465 -275.700511) (xy 64.648821 -275.736867) (xy 64.679042 -275.778463)
			(xy 64.702385 -275.824275) (xy 64.718273 -275.873174) (xy 64.726316 -275.923956) (xy 64.72682 -275.949664)
			(xy 64.726316 -275.975372) (xy 64.726276 -275.975626) (xy 65.97294 -275.975626) (xy 65.97294 -275.92421)
			(xy 65.980983 -275.873428) (xy 65.996871 -275.824529) (xy 66.020214 -275.778717) (xy 66.050435 -275.737121)
			(xy 66.086791 -275.700765) (xy 66.128387 -275.670544) (xy 66.174199 -275.647201) (xy 66.223098 -275.631313)
			(xy 66.27388 -275.62327) (xy 66.325296 -275.62327) (xy 66.376078 -275.631313) (xy 66.424977 -275.647201)
			(xy 66.470789 -275.670544) (xy 66.512385 -275.700765) (xy 66.548741 -275.737121) (xy 66.578962 -275.778717)
			(xy 66.602305 -275.824529) (xy 66.618193 -275.873428) (xy 66.626236 -275.92421) (xy 66.62674 -275.949918)
			(xy 66.626241 -275.975372) (xy 67.87286 -275.975372) (xy 67.87286 -275.923956) (xy 67.880903 -275.873174)
			(xy 67.896791 -275.824275) (xy 67.920134 -275.778463) (xy 67.950355 -275.736867) (xy 67.986711 -275.700511)
			(xy 68.028307 -275.67029) (xy 68.074119 -275.646947) (xy 68.123018 -275.631059) (xy 68.1738 -275.623016)
			(xy 68.225216 -275.623016) (xy 68.275998 -275.631059) (xy 68.324897 -275.646947) (xy 68.370709 -275.67029)
			(xy 68.412305 -275.700511) (xy 68.448661 -275.736867) (xy 68.478882 -275.778463) (xy 68.502225 -275.824275)
			(xy 68.518113 -275.873174) (xy 68.526156 -275.923956) (xy 68.52666 -275.949664) (xy 68.526156 -275.975372)
			(xy 68.526116 -275.975626) (xy 69.77278 -275.975626) (xy 69.77278 -275.92421) (xy 69.780823 -275.873428)
			(xy 69.796711 -275.824529) (xy 69.820054 -275.778717) (xy 69.850275 -275.737121) (xy 69.886631 -275.700765)
			(xy 69.928227 -275.670544) (xy 69.974039 -275.647201) (xy 70.022938 -275.631313) (xy 70.07372 -275.62327)
			(xy 70.125136 -275.62327) (xy 70.175918 -275.631313) (xy 70.224817 -275.647201) (xy 70.270629 -275.670544)
			(xy 70.312225 -275.700765) (xy 70.348581 -275.737121) (xy 70.378802 -275.778717) (xy 70.402145 -275.824529)
			(xy 70.418033 -275.873428) (xy 70.426076 -275.92421) (xy 70.42658 -275.949918) (xy 70.426081 -275.975372)
			(xy 71.672954 -275.975372) (xy 71.672954 -275.923956) (xy 71.680997 -275.873174) (xy 71.696885 -275.824275)
			(xy 71.720228 -275.778463) (xy 71.750449 -275.736867) (xy 71.786805 -275.700511) (xy 71.828401 -275.67029)
			(xy 71.874213 -275.646947) (xy 71.923112 -275.631059) (xy 71.973894 -275.623016) (xy 72.02531 -275.623016)
			(xy 72.076092 -275.631059) (xy 72.124991 -275.646947) (xy 72.170803 -275.67029) (xy 72.212399 -275.700511)
			(xy 72.248755 -275.736867) (xy 72.278976 -275.778463) (xy 72.302319 -275.824275) (xy 72.318207 -275.873174)
			(xy 72.32625 -275.923956) (xy 72.326754 -275.949664) (xy 72.32625 -275.975372) (xy 72.32621 -275.975626)
			(xy 73.572874 -275.975626) (xy 73.572874 -275.92421) (xy 73.580917 -275.873428) (xy 73.596805 -275.824529)
			(xy 73.620148 -275.778717) (xy 73.650369 -275.737121) (xy 73.686725 -275.700765) (xy 73.728321 -275.670544)
			(xy 73.774133 -275.647201) (xy 73.823032 -275.631313) (xy 73.873814 -275.62327) (xy 73.92523 -275.62327)
			(xy 73.976012 -275.631313) (xy 74.024911 -275.647201) (xy 74.070723 -275.670544) (xy 74.112319 -275.700765)
			(xy 74.148675 -275.737121) (xy 74.178896 -275.778717) (xy 74.202239 -275.824529) (xy 74.218127 -275.873428)
			(xy 74.22617 -275.92421) (xy 74.226674 -275.949918) (xy 74.226175 -275.975372) (xy 75.473048 -275.975372)
			(xy 75.473048 -275.923956) (xy 75.481091 -275.873174) (xy 75.496979 -275.824275) (xy 75.520322 -275.778463)
			(xy 75.550543 -275.736867) (xy 75.586899 -275.700511) (xy 75.628495 -275.67029) (xy 75.674307 -275.646947)
			(xy 75.723206 -275.631059) (xy 75.773988 -275.623016) (xy 75.825404 -275.623016) (xy 75.876186 -275.631059)
			(xy 75.925085 -275.646947) (xy 75.970897 -275.67029) (xy 76.012493 -275.700511) (xy 76.048849 -275.736867)
			(xy 76.07907 -275.778463) (xy 76.102413 -275.824275) (xy 76.118301 -275.873174) (xy 76.126344 -275.923956)
			(xy 76.126848 -275.949664) (xy 76.126344 -275.975372) (xy 76.126304 -275.975626) (xy 77.372968 -275.975626)
			(xy 77.372968 -275.92421) (xy 77.381011 -275.873428) (xy 77.396899 -275.824529) (xy 77.420242 -275.778717)
			(xy 77.450463 -275.737121) (xy 77.486819 -275.700765) (xy 77.528415 -275.670544) (xy 77.574227 -275.647201)
			(xy 77.623126 -275.631313) (xy 77.673908 -275.62327) (xy 77.725324 -275.62327) (xy 77.776106 -275.631313)
			(xy 77.825005 -275.647201) (xy 77.870817 -275.670544) (xy 77.912413 -275.700765) (xy 77.948769 -275.737121)
			(xy 77.97899 -275.778717) (xy 78.002333 -275.824529) (xy 78.018221 -275.873428) (xy 78.026264 -275.92421)
			(xy 78.026768 -275.949918) (xy 78.026264 -275.975626) (xy 79.272888 -275.975626) (xy 79.272888 -275.92421)
			(xy 79.280931 -275.873428) (xy 79.296819 -275.824529) (xy 79.320162 -275.778717) (xy 79.350383 -275.737121)
			(xy 79.386739 -275.700765) (xy 79.428335 -275.670544) (xy 79.474147 -275.647201) (xy 79.523046 -275.631313)
			(xy 79.573828 -275.62327) (xy 79.625244 -275.62327) (xy 79.676026 -275.631313) (xy 79.724925 -275.647201)
			(xy 79.770737 -275.670544) (xy 79.812333 -275.700765) (xy 79.848689 -275.737121) (xy 79.87891 -275.778717)
			(xy 79.902253 -275.824529) (xy 79.918141 -275.873428) (xy 79.926184 -275.92421) (xy 79.926688 -275.949918)
			(xy 79.926184 -275.975626) (xy 79.918141 -276.026408) (xy 79.902253 -276.075307) (xy 79.87891 -276.121119)
			(xy 79.848689 -276.162715) (xy 79.812333 -276.199071) (xy 79.770737 -276.229292) (xy 79.724925 -276.252635)
			(xy 79.676026 -276.268523) (xy 79.625244 -276.276566) (xy 79.573828 -276.276566) (xy 79.523046 -276.268523)
			(xy 79.474147 -276.252635) (xy 79.428335 -276.229292) (xy 79.386739 -276.199071) (xy 79.350383 -276.162715)
			(xy 79.320162 -276.121119) (xy 79.296819 -276.075307) (xy 79.280931 -276.026408) (xy 79.272888 -275.975626)
			(xy 78.026264 -275.975626) (xy 78.018221 -276.026408) (xy 78.002333 -276.075307) (xy 77.97899 -276.121119)
			(xy 77.948769 -276.162715) (xy 77.912413 -276.199071) (xy 77.870817 -276.229292) (xy 77.825005 -276.252635)
			(xy 77.776106 -276.268523) (xy 77.725324 -276.276566) (xy 77.673908 -276.276566) (xy 77.623126 -276.268523)
			(xy 77.574227 -276.252635) (xy 77.528415 -276.229292) (xy 77.486819 -276.199071) (xy 77.450463 -276.162715)
			(xy 77.420242 -276.121119) (xy 77.396899 -276.075307) (xy 77.381011 -276.026408) (xy 77.372968 -275.975626)
			(xy 76.126304 -275.975626) (xy 76.118301 -276.026154) (xy 76.102413 -276.075053) (xy 76.07907 -276.120865)
			(xy 76.048849 -276.162461) (xy 76.012493 -276.198817) (xy 75.970897 -276.229038) (xy 75.925085 -276.252381)
			(xy 75.876186 -276.268269) (xy 75.825404 -276.276312) (xy 75.773988 -276.276312) (xy 75.723206 -276.268269)
			(xy 75.674307 -276.252381) (xy 75.628495 -276.229038) (xy 75.586899 -276.198817) (xy 75.550543 -276.162461)
			(xy 75.520322 -276.120865) (xy 75.496979 -276.075053) (xy 75.481091 -276.026154) (xy 75.473048 -275.975372)
			(xy 74.226175 -275.975372) (xy 74.22617 -275.975626) (xy 74.218127 -276.026408) (xy 74.202239 -276.075307)
			(xy 74.178896 -276.121119) (xy 74.148675 -276.162715) (xy 74.112319 -276.199071) (xy 74.070723 -276.229292)
			(xy 74.024911 -276.252635) (xy 73.976012 -276.268523) (xy 73.92523 -276.276566) (xy 73.873814 -276.276566)
			(xy 73.823032 -276.268523) (xy 73.774133 -276.252635) (xy 73.728321 -276.229292) (xy 73.686725 -276.199071)
			(xy 73.650369 -276.162715) (xy 73.620148 -276.121119) (xy 73.596805 -276.075307) (xy 73.580917 -276.026408)
			(xy 73.572874 -275.975626) (xy 72.32621 -275.975626) (xy 72.318207 -276.026154) (xy 72.302319 -276.075053)
			(xy 72.278976 -276.120865) (xy 72.248755 -276.162461) (xy 72.212399 -276.198817) (xy 72.170803 -276.229038)
			(xy 72.124991 -276.252381) (xy 72.076092 -276.268269) (xy 72.02531 -276.276312) (xy 71.973894 -276.276312)
			(xy 71.923112 -276.268269) (xy 71.874213 -276.252381) (xy 71.828401 -276.229038) (xy 71.786805 -276.198817)
			(xy 71.750449 -276.162461) (xy 71.720228 -276.120865) (xy 71.696885 -276.075053) (xy 71.680997 -276.026154)
			(xy 71.672954 -275.975372) (xy 70.426081 -275.975372) (xy 70.426076 -275.975626) (xy 70.418033 -276.026408)
			(xy 70.402145 -276.075307) (xy 70.378802 -276.121119) (xy 70.348581 -276.162715) (xy 70.312225 -276.199071)
			(xy 70.270629 -276.229292) (xy 70.224817 -276.252635) (xy 70.175918 -276.268523) (xy 70.125136 -276.276566)
			(xy 70.07372 -276.276566) (xy 70.022938 -276.268523) (xy 69.974039 -276.252635) (xy 69.928227 -276.229292)
			(xy 69.886631 -276.199071) (xy 69.850275 -276.162715) (xy 69.820054 -276.121119) (xy 69.796711 -276.075307)
			(xy 69.780823 -276.026408) (xy 69.77278 -275.975626) (xy 68.526116 -275.975626) (xy 68.518113 -276.026154)
			(xy 68.502225 -276.075053) (xy 68.478882 -276.120865) (xy 68.448661 -276.162461) (xy 68.412305 -276.198817)
			(xy 68.370709 -276.229038) (xy 68.324897 -276.252381) (xy 68.275998 -276.268269) (xy 68.225216 -276.276312)
			(xy 68.1738 -276.276312) (xy 68.123018 -276.268269) (xy 68.074119 -276.252381) (xy 68.028307 -276.229038)
			(xy 67.986711 -276.198817) (xy 67.950355 -276.162461) (xy 67.920134 -276.120865) (xy 67.896791 -276.075053)
			(xy 67.880903 -276.026154) (xy 67.87286 -275.975372) (xy 66.626241 -275.975372) (xy 66.626236 -275.975626)
			(xy 66.618193 -276.026408) (xy 66.602305 -276.075307) (xy 66.578962 -276.121119) (xy 66.548741 -276.162715)
			(xy 66.512385 -276.199071) (xy 66.470789 -276.229292) (xy 66.424977 -276.252635) (xy 66.376078 -276.268523)
			(xy 66.325296 -276.276566) (xy 66.27388 -276.276566) (xy 66.223098 -276.268523) (xy 66.174199 -276.252635)
			(xy 66.128387 -276.229292) (xy 66.086791 -276.199071) (xy 66.050435 -276.162715) (xy 66.020214 -276.121119)
			(xy 65.996871 -276.075307) (xy 65.980983 -276.026408) (xy 65.97294 -275.975626) (xy 64.726276 -275.975626)
			(xy 64.718273 -276.026154) (xy 64.702385 -276.075053) (xy 64.679042 -276.120865) (xy 64.648821 -276.162461)
			(xy 64.612465 -276.198817) (xy 64.570869 -276.229038) (xy 64.525057 -276.252381) (xy 64.476158 -276.268269)
			(xy 64.425376 -276.276312) (xy 64.37396 -276.276312) (xy 64.323178 -276.268269) (xy 64.274279 -276.252381)
			(xy 64.228467 -276.229038) (xy 64.186871 -276.198817) (xy 64.150515 -276.162461) (xy 64.120294 -276.120865)
			(xy 64.096951 -276.075053) (xy 64.081063 -276.026154) (xy 64.07302 -275.975372) (xy 62.826147 -275.975372)
			(xy 62.826142 -275.975626) (xy 62.818099 -276.026408) (xy 62.802211 -276.075307) (xy 62.778868 -276.121119)
			(xy 62.748647 -276.162715) (xy 62.712291 -276.199071) (xy 62.670695 -276.229292) (xy 62.624883 -276.252635)
			(xy 62.575984 -276.268523) (xy 62.525202 -276.276566) (xy 62.473786 -276.276566) (xy 62.423004 -276.268523)
			(xy 62.374105 -276.252635) (xy 62.328293 -276.229292) (xy 62.286697 -276.199071) (xy 62.250341 -276.162715)
			(xy 62.22012 -276.121119) (xy 62.196777 -276.075307) (xy 62.180889 -276.026408) (xy 62.172846 -275.975626)
			(xy 60.926182 -275.975626) (xy 60.918179 -276.026154) (xy 60.902291 -276.075053) (xy 60.878948 -276.120865)
			(xy 60.848727 -276.162461) (xy 60.812371 -276.198817) (xy 60.770775 -276.229038) (xy 60.724963 -276.252381)
			(xy 60.676064 -276.268269) (xy 60.625282 -276.276312) (xy 60.573866 -276.276312) (xy 60.523084 -276.268269)
			(xy 60.474185 -276.252381) (xy 60.428373 -276.229038) (xy 60.386777 -276.198817) (xy 60.350421 -276.162461)
			(xy 60.3202 -276.120865) (xy 60.296857 -276.075053) (xy 60.280969 -276.026154) (xy 60.272926 -275.975372)
			(xy 59.292236 -275.975372) (xy 59.292236 -276.925586) (xy 81.173316 -276.925586) (xy 81.173316 -276.87417)
			(xy 81.181359 -276.823388) (xy 81.197247 -276.774489) (xy 81.22059 -276.728677) (xy 81.250811 -276.687081)
			(xy 81.287167 -276.650725) (xy 81.328763 -276.620504) (xy 81.374575 -276.597161) (xy 81.423474 -276.581273)
			(xy 81.474256 -276.57323) (xy 81.525672 -276.57323) (xy 81.576454 -276.581273) (xy 81.625353 -276.597161)
			(xy 81.671165 -276.620504) (xy 81.712761 -276.650725) (xy 81.749117 -276.687081) (xy 81.779338 -276.728677)
			(xy 81.802681 -276.774489) (xy 81.818569 -276.823388) (xy 81.826612 -276.87417) (xy 81.827116 -276.899878)
			(xy 81.826612 -276.925586) (xy 82.123276 -276.925586) (xy 82.123276 -276.87417) (xy 82.131319 -276.823388)
			(xy 82.147207 -276.774489) (xy 82.17055 -276.728677) (xy 82.200771 -276.687081) (xy 82.237127 -276.650725)
			(xy 82.278723 -276.620504) (xy 82.324535 -276.597161) (xy 82.373434 -276.581273) (xy 82.424216 -276.57323)
			(xy 82.475632 -276.57323) (xy 82.526414 -276.581273) (xy 82.575313 -276.597161) (xy 82.621125 -276.620504)
			(xy 82.662721 -276.650725) (xy 82.699077 -276.687081) (xy 82.729298 -276.728677) (xy 82.752641 -276.774489)
			(xy 82.768529 -276.823388) (xy 82.776572 -276.87417) (xy 82.777076 -276.899878) (xy 82.776572 -276.925586)
			(xy 82.768529 -276.976368) (xy 82.752641 -277.025267) (xy 82.729298 -277.071079) (xy 82.699077 -277.112675)
			(xy 82.662721 -277.149031) (xy 82.621125 -277.179252) (xy 82.575313 -277.202595) (xy 82.526414 -277.218483)
			(xy 82.475632 -277.226526) (xy 82.424216 -277.226526) (xy 82.373434 -277.218483) (xy 82.324535 -277.202595)
			(xy 82.278723 -277.179252) (xy 82.237127 -277.149031) (xy 82.200771 -277.112675) (xy 82.17055 -277.071079)
			(xy 82.147207 -277.025267) (xy 82.131319 -276.976368) (xy 82.123276 -276.925586) (xy 81.826612 -276.925586)
			(xy 81.818569 -276.976368) (xy 81.802681 -277.025267) (xy 81.779338 -277.071079) (xy 81.749117 -277.112675)
			(xy 81.712761 -277.149031) (xy 81.671165 -277.179252) (xy 81.625353 -277.202595) (xy 81.576454 -277.218483)
			(xy 81.525672 -277.226526) (xy 81.474256 -277.226526) (xy 81.423474 -277.218483) (xy 81.374575 -277.202595)
			(xy 81.328763 -277.179252) (xy 81.287167 -277.149031) (xy 81.250811 -277.112675) (xy 81.22059 -277.071079)
			(xy 81.197247 -277.025267) (xy 81.181359 -276.976368) (xy 81.173316 -276.925586) (xy 59.292236 -276.925586)
			(xy 59.292236 -277.533608) (xy 59.292599 -277.542687) (xy 59.29894 -277.559699) (xy 59.310849 -277.573404)
			(xy 59.318652 -277.578058) (xy 59.397646 -277.615904) (xy 59.423808 -277.612602) (xy 59.437016 -277.601172)
			(xy 59.45482 -277.586499) (xy 59.493775 -277.561782) (xy 59.535819 -277.542789) (xy 59.580115 -277.529896)
			(xy 59.625785 -277.52336) (xy 59.648852 -277.52294) (xy 59.649614 -277.52294) (xy 59.675298 -277.523445)
			(xy 59.726034 -277.531482) (xy 59.774887 -277.547358) (xy 59.820656 -277.57068) (xy 59.862213 -277.600874)
			(xy 59.898535 -277.637198) (xy 59.928728 -277.678756) (xy 59.952048 -277.724526) (xy 59.967921 -277.77338)
			(xy 59.975956 -277.824116) (xy 59.975956 -277.875484) (xy 59.975946 -277.875546) (xy 61.222886 -277.875546)
			(xy 61.222886 -277.82413) (xy 61.230929 -277.773348) (xy 61.246817 -277.724449) (xy 61.27016 -277.678637)
			(xy 61.300381 -277.637041) (xy 61.336737 -277.600685) (xy 61.378333 -277.570464) (xy 61.424145 -277.547121)
			(xy 61.473044 -277.531233) (xy 61.523826 -277.52319) (xy 61.575242 -277.52319) (xy 61.626024 -277.531233)
			(xy 61.674923 -277.547121) (xy 61.720735 -277.570464) (xy 61.762331 -277.600685) (xy 61.798687 -277.637041)
			(xy 61.828908 -277.678637) (xy 61.852251 -277.724449) (xy 61.868139 -277.773348) (xy 61.876182 -277.82413)
			(xy 61.876686 -277.849838) (xy 61.876182 -277.875546) (xy 63.12306 -277.875546) (xy 63.12306 -277.82413)
			(xy 63.131103 -277.773348) (xy 63.146991 -277.724449) (xy 63.170334 -277.678637) (xy 63.200555 -277.637041)
			(xy 63.236911 -277.600685) (xy 63.278507 -277.570464) (xy 63.324319 -277.547121) (xy 63.373218 -277.531233)
			(xy 63.424 -277.52319) (xy 63.475416 -277.52319) (xy 63.526198 -277.531233) (xy 63.575097 -277.547121)
			(xy 63.620909 -277.570464) (xy 63.662505 -277.600685) (xy 63.698861 -277.637041) (xy 63.729082 -277.678637)
			(xy 63.752425 -277.724449) (xy 63.768313 -277.773348) (xy 63.776356 -277.82413) (xy 63.77686 -277.849838)
			(xy 63.776356 -277.875546) (xy 65.02298 -277.875546) (xy 65.02298 -277.82413) (xy 65.031023 -277.773348)
			(xy 65.046911 -277.724449) (xy 65.070254 -277.678637) (xy 65.100475 -277.637041) (xy 65.136831 -277.600685)
			(xy 65.178427 -277.570464) (xy 65.224239 -277.547121) (xy 65.273138 -277.531233) (xy 65.32392 -277.52319)
			(xy 65.375336 -277.52319) (xy 65.426118 -277.531233) (xy 65.475017 -277.547121) (xy 65.520829 -277.570464)
			(xy 65.562425 -277.600685) (xy 65.598781 -277.637041) (xy 65.629002 -277.678637) (xy 65.652345 -277.724449)
			(xy 65.668233 -277.773348) (xy 65.676276 -277.82413) (xy 65.67678 -277.849838) (xy 65.676276 -277.875546)
			(xy 66.9229 -277.875546) (xy 66.9229 -277.82413) (xy 66.930943 -277.773348) (xy 66.946831 -277.724449)
			(xy 66.970174 -277.678637) (xy 67.000395 -277.637041) (xy 67.036751 -277.600685) (xy 67.078347 -277.570464)
			(xy 67.124159 -277.547121) (xy 67.173058 -277.531233) (xy 67.22384 -277.52319) (xy 67.275256 -277.52319)
			(xy 67.326038 -277.531233) (xy 67.374937 -277.547121) (xy 67.420749 -277.570464) (xy 67.462345 -277.600685)
			(xy 67.498701 -277.637041) (xy 67.528922 -277.678637) (xy 67.552265 -277.724449) (xy 67.568153 -277.773348)
			(xy 67.576196 -277.82413) (xy 67.5767 -277.849838) (xy 67.576196 -277.875546) (xy 68.823074 -277.875546)
			(xy 68.823074 -277.82413) (xy 68.831117 -277.773348) (xy 68.847005 -277.724449) (xy 68.870348 -277.678637)
			(xy 68.900569 -277.637041) (xy 68.936925 -277.600685) (xy 68.978521 -277.570464) (xy 69.024333 -277.547121)
			(xy 69.073232 -277.531233) (xy 69.124014 -277.52319) (xy 69.17543 -277.52319) (xy 69.226212 -277.531233)
			(xy 69.275111 -277.547121) (xy 69.320923 -277.570464) (xy 69.362519 -277.600685) (xy 69.398875 -277.637041)
			(xy 69.429096 -277.678637) (xy 69.452439 -277.724449) (xy 69.468327 -277.773348) (xy 69.47637 -277.82413)
			(xy 69.476874 -277.849838) (xy 69.47637 -277.875546) (xy 70.722994 -277.875546) (xy 70.722994 -277.82413)
			(xy 70.731037 -277.773348) (xy 70.746925 -277.724449) (xy 70.770268 -277.678637) (xy 70.800489 -277.637041)
			(xy 70.836845 -277.600685) (xy 70.878441 -277.570464) (xy 70.924253 -277.547121) (xy 70.973152 -277.531233)
			(xy 71.023934 -277.52319) (xy 71.07535 -277.52319) (xy 71.126132 -277.531233) (xy 71.175031 -277.547121)
			(xy 71.220843 -277.570464) (xy 71.262439 -277.600685) (xy 71.298795 -277.637041) (xy 71.329016 -277.678637)
			(xy 71.352359 -277.724449) (xy 71.368247 -277.773348) (xy 71.37629 -277.82413) (xy 71.376794 -277.849838)
			(xy 71.37629 -277.875546) (xy 72.622914 -277.875546) (xy 72.622914 -277.82413) (xy 72.630957 -277.773348)
			(xy 72.646845 -277.724449) (xy 72.670188 -277.678637) (xy 72.700409 -277.637041) (xy 72.736765 -277.600685)
			(xy 72.778361 -277.570464) (xy 72.824173 -277.547121) (xy 72.873072 -277.531233) (xy 72.923854 -277.52319)
			(xy 72.97527 -277.52319) (xy 73.026052 -277.531233) (xy 73.074951 -277.547121) (xy 73.120763 -277.570464)
			(xy 73.162359 -277.600685) (xy 73.198715 -277.637041) (xy 73.228936 -277.678637) (xy 73.252279 -277.724449)
			(xy 73.268167 -277.773348) (xy 73.27621 -277.82413) (xy 73.276714 -277.849838) (xy 73.27621 -277.875546)
			(xy 74.523088 -277.875546) (xy 74.523088 -277.82413) (xy 74.531131 -277.773348) (xy 74.547019 -277.724449)
			(xy 74.570362 -277.678637) (xy 74.600583 -277.637041) (xy 74.636939 -277.600685) (xy 74.678535 -277.570464)
			(xy 74.724347 -277.547121) (xy 74.773246 -277.531233) (xy 74.824028 -277.52319) (xy 74.875444 -277.52319)
			(xy 74.926226 -277.531233) (xy 74.975125 -277.547121) (xy 75.020937 -277.570464) (xy 75.062533 -277.600685)
			(xy 75.098889 -277.637041) (xy 75.12911 -277.678637) (xy 75.152453 -277.724449) (xy 75.168341 -277.773348)
			(xy 75.176384 -277.82413) (xy 75.176888 -277.849838) (xy 75.176384 -277.875546) (xy 76.423008 -277.875546)
			(xy 76.423008 -277.82413) (xy 76.431051 -277.773348) (xy 76.446939 -277.724449) (xy 76.470282 -277.678637)
			(xy 76.500503 -277.637041) (xy 76.536859 -277.600685) (xy 76.578455 -277.570464) (xy 76.624267 -277.547121)
			(xy 76.673166 -277.531233) (xy 76.723948 -277.52319) (xy 76.775364 -277.52319) (xy 76.826146 -277.531233)
			(xy 76.875045 -277.547121) (xy 76.920857 -277.570464) (xy 76.962453 -277.600685) (xy 76.998809 -277.637041)
			(xy 77.02903 -277.678637) (xy 77.052373 -277.724449) (xy 77.068261 -277.773348) (xy 77.076304 -277.82413)
			(xy 77.076808 -277.849838) (xy 77.076304 -277.875546) (xy 78.322928 -277.875546) (xy 78.322928 -277.82413)
			(xy 78.330971 -277.773348) (xy 78.346859 -277.724449) (xy 78.370202 -277.678637) (xy 78.400423 -277.637041)
			(xy 78.436779 -277.600685) (xy 78.478375 -277.570464) (xy 78.524187 -277.547121) (xy 78.573086 -277.531233)
			(xy 78.623868 -277.52319) (xy 78.675284 -277.52319) (xy 78.726066 -277.531233) (xy 78.774965 -277.547121)
			(xy 78.820777 -277.570464) (xy 78.862373 -277.600685) (xy 78.898729 -277.637041) (xy 78.92895 -277.678637)
			(xy 78.952293 -277.724449) (xy 78.968181 -277.773348) (xy 78.976224 -277.82413) (xy 78.976728 -277.849838)
			(xy 78.976224 -277.875546) (xy 80.223102 -277.875546) (xy 80.223102 -277.82413) (xy 80.231145 -277.773348)
			(xy 80.247033 -277.724449) (xy 80.270376 -277.678637) (xy 80.300597 -277.637041) (xy 80.336953 -277.600685)
			(xy 80.378549 -277.570464) (xy 80.424361 -277.547121) (xy 80.47326 -277.531233) (xy 80.524042 -277.52319)
			(xy 80.575458 -277.52319) (xy 80.62624 -277.531233) (xy 80.675139 -277.547121) (xy 80.720951 -277.570464)
			(xy 80.762547 -277.600685) (xy 80.798903 -277.637041) (xy 80.829124 -277.678637) (xy 80.852467 -277.724449)
			(xy 80.868355 -277.773348) (xy 80.876398 -277.82413) (xy 80.876902 -277.849838) (xy 80.876398 -277.875546)
			(xy 80.868355 -277.926328) (xy 80.852467 -277.975227) (xy 80.829124 -278.021039) (xy 80.798903 -278.062635)
			(xy 80.762547 -278.098991) (xy 80.720951 -278.129212) (xy 80.675139 -278.152555) (xy 80.62624 -278.168443)
			(xy 80.575458 -278.176486) (xy 80.524042 -278.176486) (xy 80.47326 -278.168443) (xy 80.424361 -278.152555)
			(xy 80.378549 -278.129212) (xy 80.336953 -278.098991) (xy 80.300597 -278.062635) (xy 80.270376 -278.021039)
			(xy 80.247033 -277.975227) (xy 80.231145 -277.926328) (xy 80.223102 -277.875546) (xy 78.976224 -277.875546)
			(xy 78.968181 -277.926328) (xy 78.952293 -277.975227) (xy 78.92895 -278.021039) (xy 78.898729 -278.062635)
			(xy 78.862373 -278.098991) (xy 78.820777 -278.129212) (xy 78.774965 -278.152555) (xy 78.726066 -278.168443)
			(xy 78.675284 -278.176486) (xy 78.623868 -278.176486) (xy 78.573086 -278.168443) (xy 78.524187 -278.152555)
			(xy 78.478375 -278.129212) (xy 78.436779 -278.098991) (xy 78.400423 -278.062635) (xy 78.370202 -278.021039)
			(xy 78.346859 -277.975227) (xy 78.330971 -277.926328) (xy 78.322928 -277.875546) (xy 77.076304 -277.875546)
			(xy 77.068261 -277.926328) (xy 77.052373 -277.975227) (xy 77.02903 -278.021039) (xy 76.998809 -278.062635)
			(xy 76.962453 -278.098991) (xy 76.920857 -278.129212) (xy 76.875045 -278.152555) (xy 76.826146 -278.168443)
			(xy 76.775364 -278.176486) (xy 76.723948 -278.176486) (xy 76.673166 -278.168443) (xy 76.624267 -278.152555)
			(xy 76.578455 -278.129212) (xy 76.536859 -278.098991) (xy 76.500503 -278.062635) (xy 76.470282 -278.021039)
			(xy 76.446939 -277.975227) (xy 76.431051 -277.926328) (xy 76.423008 -277.875546) (xy 75.176384 -277.875546)
			(xy 75.168341 -277.926328) (xy 75.152453 -277.975227) (xy 75.12911 -278.021039) (xy 75.098889 -278.062635)
			(xy 75.062533 -278.098991) (xy 75.020937 -278.129212) (xy 74.975125 -278.152555) (xy 74.926226 -278.168443)
			(xy 74.875444 -278.176486) (xy 74.824028 -278.176486) (xy 74.773246 -278.168443) (xy 74.724347 -278.152555)
			(xy 74.678535 -278.129212) (xy 74.636939 -278.098991) (xy 74.600583 -278.062635) (xy 74.570362 -278.021039)
			(xy 74.547019 -277.975227) (xy 74.531131 -277.926328) (xy 74.523088 -277.875546) (xy 73.27621 -277.875546)
			(xy 73.268167 -277.926328) (xy 73.252279 -277.975227) (xy 73.228936 -278.021039) (xy 73.198715 -278.062635)
			(xy 73.162359 -278.098991) (xy 73.120763 -278.129212) (xy 73.074951 -278.152555) (xy 73.026052 -278.168443)
			(xy 72.97527 -278.176486) (xy 72.923854 -278.176486) (xy 72.873072 -278.168443) (xy 72.824173 -278.152555)
			(xy 72.778361 -278.129212) (xy 72.736765 -278.098991) (xy 72.700409 -278.062635) (xy 72.670188 -278.021039)
			(xy 72.646845 -277.975227) (xy 72.630957 -277.926328) (xy 72.622914 -277.875546) (xy 71.37629 -277.875546)
			(xy 71.368247 -277.926328) (xy 71.352359 -277.975227) (xy 71.329016 -278.021039) (xy 71.298795 -278.062635)
			(xy 71.262439 -278.098991) (xy 71.220843 -278.129212) (xy 71.175031 -278.152555) (xy 71.126132 -278.168443)
			(xy 71.07535 -278.176486) (xy 71.023934 -278.176486) (xy 70.973152 -278.168443) (xy 70.924253 -278.152555)
			(xy 70.878441 -278.129212) (xy 70.836845 -278.098991) (xy 70.800489 -278.062635) (xy 70.770268 -278.021039)
			(xy 70.746925 -277.975227) (xy 70.731037 -277.926328) (xy 70.722994 -277.875546) (xy 69.47637 -277.875546)
			(xy 69.468327 -277.926328) (xy 69.452439 -277.975227) (xy 69.429096 -278.021039) (xy 69.398875 -278.062635)
			(xy 69.362519 -278.098991) (xy 69.320923 -278.129212) (xy 69.275111 -278.152555) (xy 69.226212 -278.168443)
			(xy 69.17543 -278.176486) (xy 69.124014 -278.176486) (xy 69.073232 -278.168443) (xy 69.024333 -278.152555)
			(xy 68.978521 -278.129212) (xy 68.936925 -278.098991) (xy 68.900569 -278.062635) (xy 68.870348 -278.021039)
			(xy 68.847005 -277.975227) (xy 68.831117 -277.926328) (xy 68.823074 -277.875546) (xy 67.576196 -277.875546)
			(xy 67.568153 -277.926328) (xy 67.552265 -277.975227) (xy 67.528922 -278.021039) (xy 67.498701 -278.062635)
			(xy 67.462345 -278.098991) (xy 67.420749 -278.129212) (xy 67.374937 -278.152555) (xy 67.326038 -278.168443)
			(xy 67.275256 -278.176486) (xy 67.22384 -278.176486) (xy 67.173058 -278.168443) (xy 67.124159 -278.152555)
			(xy 67.078347 -278.129212) (xy 67.036751 -278.098991) (xy 67.000395 -278.062635) (xy 66.970174 -278.021039)
			(xy 66.946831 -277.975227) (xy 66.930943 -277.926328) (xy 66.9229 -277.875546) (xy 65.676276 -277.875546)
			(xy 65.668233 -277.926328) (xy 65.652345 -277.975227) (xy 65.629002 -278.021039) (xy 65.598781 -278.062635)
			(xy 65.562425 -278.098991) (xy 65.520829 -278.129212) (xy 65.475017 -278.152555) (xy 65.426118 -278.168443)
			(xy 65.375336 -278.176486) (xy 65.32392 -278.176486) (xy 65.273138 -278.168443) (xy 65.224239 -278.152555)
			(xy 65.178427 -278.129212) (xy 65.136831 -278.098991) (xy 65.100475 -278.062635) (xy 65.070254 -278.021039)
			(xy 65.046911 -277.975227) (xy 65.031023 -277.926328) (xy 65.02298 -277.875546) (xy 63.776356 -277.875546)
			(xy 63.768313 -277.926328) (xy 63.752425 -277.975227) (xy 63.729082 -278.021039) (xy 63.698861 -278.062635)
			(xy 63.662505 -278.098991) (xy 63.620909 -278.129212) (xy 63.575097 -278.152555) (xy 63.526198 -278.168443)
			(xy 63.475416 -278.176486) (xy 63.424 -278.176486) (xy 63.373218 -278.168443) (xy 63.324319 -278.152555)
			(xy 63.278507 -278.129212) (xy 63.236911 -278.098991) (xy 63.200555 -278.062635) (xy 63.170334 -278.021039)
			(xy 63.146991 -277.975227) (xy 63.131103 -277.926328) (xy 63.12306 -277.875546) (xy 61.876182 -277.875546)
			(xy 61.868139 -277.926328) (xy 61.852251 -277.975227) (xy 61.828908 -278.021039) (xy 61.798687 -278.062635)
			(xy 61.762331 -278.098991) (xy 61.720735 -278.129212) (xy 61.674923 -278.152555) (xy 61.626024 -278.168443)
			(xy 61.575242 -278.176486) (xy 61.523826 -278.176486) (xy 61.473044 -278.168443) (xy 61.424145 -278.152555)
			(xy 61.378333 -278.129212) (xy 61.336737 -278.098991) (xy 61.300381 -278.062635) (xy 61.27016 -278.021039)
			(xy 61.246817 -277.975227) (xy 61.230929 -277.926328) (xy 61.222886 -277.875546) (xy 59.975946 -277.875546)
			(xy 59.967921 -277.92622) (xy 59.952048 -277.975074) (xy 59.928728 -278.020844) (xy 59.898535 -278.062402)
			(xy 59.862213 -278.098726) (xy 59.820656 -278.12892) (xy 59.774887 -278.152242) (xy 59.726034 -278.168118)
			(xy 59.675298 -278.176155) (xy 59.649614 -278.176736) (xy 59.648852 -278.176736) (xy 59.625787 -278.176303)
			(xy 59.580122 -278.169751) (xy 59.53583 -278.156855) (xy 59.493785 -278.13787) (xy 59.454822 -278.113171)
			(xy 59.437016 -278.098504) (xy 59.423808 -278.087074) (xy 59.412632 -278.085804) (xy 59.405279 -278.085089)
			(xy 59.390692 -278.087402) (xy 59.38393 -278.090376) (xy 59.318652 -278.121618) (xy 59.31089 -278.126314)
			(xy 59.299037 -278.14003) (xy 59.292675 -278.157006) (xy 59.292236 -278.166068) (xy 59.292236 -278.483568)
			(xy 59.292592 -278.49265) (xy 59.298925 -278.509674) (xy 59.310831 -278.52339) (xy 59.318652 -278.528018)
			(xy 59.397646 -278.565864) (xy 59.423808 -278.562562) (xy 59.437016 -278.551132) (xy 59.45482 -278.536461)
			(xy 59.493777 -278.511747) (xy 59.53582 -278.492756) (xy 59.580117 -278.479865) (xy 59.625785 -278.47333)
			(xy 59.648852 -278.4729) (xy 59.649614 -278.4729) (xy 59.675301 -278.473405) (xy 59.726043 -278.481444)
			(xy 59.774902 -278.497321) (xy 59.820677 -278.520646) (xy 59.862239 -278.550844) (xy 59.898565 -278.587172)
			(xy 59.928762 -278.628735) (xy 59.952085 -278.674511) (xy 59.96796 -278.723371) (xy 59.975996 -278.774113)
			(xy 59.975996 -278.825487) (xy 59.975993 -278.825506) (xy 61.222886 -278.825506) (xy 61.222886 -278.77409)
			(xy 61.230929 -278.723308) (xy 61.246817 -278.674409) (xy 61.27016 -278.628597) (xy 61.300381 -278.587001)
			(xy 61.336737 -278.550645) (xy 61.378333 -278.520424) (xy 61.424145 -278.497081) (xy 61.473044 -278.481193)
			(xy 61.523826 -278.47315) (xy 61.575242 -278.47315) (xy 61.626024 -278.481193) (xy 61.674923 -278.497081)
			(xy 61.720735 -278.520424) (xy 61.762331 -278.550645) (xy 61.798687 -278.587001) (xy 61.828908 -278.628597)
			(xy 61.852251 -278.674409) (xy 61.868139 -278.723308) (xy 61.876182 -278.77409) (xy 61.876686 -278.799798)
			(xy 61.876182 -278.825506) (xy 63.12306 -278.825506) (xy 63.12306 -278.77409) (xy 63.131103 -278.723308)
			(xy 63.146991 -278.674409) (xy 63.170334 -278.628597) (xy 63.200555 -278.587001) (xy 63.236911 -278.550645)
			(xy 63.278507 -278.520424) (xy 63.324319 -278.497081) (xy 63.373218 -278.481193) (xy 63.424 -278.47315)
			(xy 63.475416 -278.47315) (xy 63.526198 -278.481193) (xy 63.575097 -278.497081) (xy 63.620909 -278.520424)
			(xy 63.662505 -278.550645) (xy 63.698861 -278.587001) (xy 63.729082 -278.628597) (xy 63.752425 -278.674409)
			(xy 63.768313 -278.723308) (xy 63.776356 -278.77409) (xy 63.77686 -278.799798) (xy 63.776356 -278.825506)
			(xy 65.02298 -278.825506) (xy 65.02298 -278.77409) (xy 65.031023 -278.723308) (xy 65.046911 -278.674409)
			(xy 65.070254 -278.628597) (xy 65.100475 -278.587001) (xy 65.136831 -278.550645) (xy 65.178427 -278.520424)
			(xy 65.224239 -278.497081) (xy 65.273138 -278.481193) (xy 65.32392 -278.47315) (xy 65.375336 -278.47315)
			(xy 65.426118 -278.481193) (xy 65.475017 -278.497081) (xy 65.520829 -278.520424) (xy 65.562425 -278.550645)
			(xy 65.598781 -278.587001) (xy 65.629002 -278.628597) (xy 65.652345 -278.674409) (xy 65.668233 -278.723308)
			(xy 65.676276 -278.77409) (xy 65.67678 -278.799798) (xy 65.676276 -278.825506) (xy 66.9229 -278.825506)
			(xy 66.9229 -278.77409) (xy 66.930943 -278.723308) (xy 66.946831 -278.674409) (xy 66.970174 -278.628597)
			(xy 67.000395 -278.587001) (xy 67.036751 -278.550645) (xy 67.078347 -278.520424) (xy 67.124159 -278.497081)
			(xy 67.173058 -278.481193) (xy 67.22384 -278.47315) (xy 67.275256 -278.47315) (xy 67.326038 -278.481193)
			(xy 67.374937 -278.497081) (xy 67.420749 -278.520424) (xy 67.462345 -278.550645) (xy 67.498701 -278.587001)
			(xy 67.528922 -278.628597) (xy 67.552265 -278.674409) (xy 67.568153 -278.723308) (xy 67.576196 -278.77409)
			(xy 67.5767 -278.799798) (xy 67.576196 -278.825506) (xy 68.823074 -278.825506) (xy 68.823074 -278.77409)
			(xy 68.831117 -278.723308) (xy 68.847005 -278.674409) (xy 68.870348 -278.628597) (xy 68.900569 -278.587001)
			(xy 68.936925 -278.550645) (xy 68.978521 -278.520424) (xy 69.024333 -278.497081) (xy 69.073232 -278.481193)
			(xy 69.124014 -278.47315) (xy 69.17543 -278.47315) (xy 69.226212 -278.481193) (xy 69.275111 -278.497081)
			(xy 69.320923 -278.520424) (xy 69.362519 -278.550645) (xy 69.398875 -278.587001) (xy 69.429096 -278.628597)
			(xy 69.452439 -278.674409) (xy 69.468327 -278.723308) (xy 69.47637 -278.77409) (xy 69.476874 -278.799798)
			(xy 69.47637 -278.825506) (xy 70.722994 -278.825506) (xy 70.722994 -278.77409) (xy 70.731037 -278.723308)
			(xy 70.746925 -278.674409) (xy 70.770268 -278.628597) (xy 70.800489 -278.587001) (xy 70.836845 -278.550645)
			(xy 70.878441 -278.520424) (xy 70.924253 -278.497081) (xy 70.973152 -278.481193) (xy 71.023934 -278.47315)
			(xy 71.07535 -278.47315) (xy 71.126132 -278.481193) (xy 71.175031 -278.497081) (xy 71.220843 -278.520424)
			(xy 71.262439 -278.550645) (xy 71.298795 -278.587001) (xy 71.329016 -278.628597) (xy 71.352359 -278.674409)
			(xy 71.368247 -278.723308) (xy 71.37629 -278.77409) (xy 71.376794 -278.799798) (xy 71.37629 -278.825506)
			(xy 72.622914 -278.825506) (xy 72.622914 -278.77409) (xy 72.630957 -278.723308) (xy 72.646845 -278.674409)
			(xy 72.670188 -278.628597) (xy 72.700409 -278.587001) (xy 72.736765 -278.550645) (xy 72.778361 -278.520424)
			(xy 72.824173 -278.497081) (xy 72.873072 -278.481193) (xy 72.923854 -278.47315) (xy 72.97527 -278.47315)
			(xy 73.026052 -278.481193) (xy 73.074951 -278.497081) (xy 73.120763 -278.520424) (xy 73.162359 -278.550645)
			(xy 73.198715 -278.587001) (xy 73.228936 -278.628597) (xy 73.252279 -278.674409) (xy 73.268167 -278.723308)
			(xy 73.27621 -278.77409) (xy 73.276714 -278.799798) (xy 73.27621 -278.825506) (xy 74.523088 -278.825506)
			(xy 74.523088 -278.77409) (xy 74.531131 -278.723308) (xy 74.547019 -278.674409) (xy 74.570362 -278.628597)
			(xy 74.600583 -278.587001) (xy 74.636939 -278.550645) (xy 74.678535 -278.520424) (xy 74.724347 -278.497081)
			(xy 74.773246 -278.481193) (xy 74.824028 -278.47315) (xy 74.875444 -278.47315) (xy 74.926226 -278.481193)
			(xy 74.975125 -278.497081) (xy 75.020937 -278.520424) (xy 75.062533 -278.550645) (xy 75.098889 -278.587001)
			(xy 75.12911 -278.628597) (xy 75.152453 -278.674409) (xy 75.168341 -278.723308) (xy 75.176384 -278.77409)
			(xy 75.176888 -278.799798) (xy 75.176384 -278.825506) (xy 76.423008 -278.825506) (xy 76.423008 -278.77409)
			(xy 76.431051 -278.723308) (xy 76.446939 -278.674409) (xy 76.470282 -278.628597) (xy 76.500503 -278.587001)
			(xy 76.536859 -278.550645) (xy 76.578455 -278.520424) (xy 76.624267 -278.497081) (xy 76.673166 -278.481193)
			(xy 76.723948 -278.47315) (xy 76.775364 -278.47315) (xy 76.826146 -278.481193) (xy 76.875045 -278.497081)
			(xy 76.920857 -278.520424) (xy 76.962453 -278.550645) (xy 76.998809 -278.587001) (xy 77.02903 -278.628597)
			(xy 77.052373 -278.674409) (xy 77.068261 -278.723308) (xy 77.076304 -278.77409) (xy 77.076808 -278.799798)
			(xy 77.076304 -278.825506) (xy 78.322928 -278.825506) (xy 78.322928 -278.77409) (xy 78.330971 -278.723308)
			(xy 78.346859 -278.674409) (xy 78.370202 -278.628597) (xy 78.400423 -278.587001) (xy 78.436779 -278.550645)
			(xy 78.478375 -278.520424) (xy 78.524187 -278.497081) (xy 78.573086 -278.481193) (xy 78.623868 -278.47315)
			(xy 78.675284 -278.47315) (xy 78.726066 -278.481193) (xy 78.774965 -278.497081) (xy 78.820777 -278.520424)
			(xy 78.862373 -278.550645) (xy 78.898729 -278.587001) (xy 78.92895 -278.628597) (xy 78.952293 -278.674409)
			(xy 78.968181 -278.723308) (xy 78.976224 -278.77409) (xy 78.976728 -278.799798) (xy 78.976224 -278.825506)
			(xy 80.223102 -278.825506) (xy 80.223102 -278.77409) (xy 80.231145 -278.723308) (xy 80.247033 -278.674409)
			(xy 80.270376 -278.628597) (xy 80.300597 -278.587001) (xy 80.336953 -278.550645) (xy 80.378549 -278.520424)
			(xy 80.424361 -278.497081) (xy 80.47326 -278.481193) (xy 80.524042 -278.47315) (xy 80.575458 -278.47315)
			(xy 80.62624 -278.481193) (xy 80.675139 -278.497081) (xy 80.720951 -278.520424) (xy 80.762547 -278.550645)
			(xy 80.798903 -278.587001) (xy 80.829124 -278.628597) (xy 80.852467 -278.674409) (xy 80.868355 -278.723308)
			(xy 80.876398 -278.77409) (xy 80.876902 -278.799798) (xy 80.876398 -278.825506) (xy 80.868355 -278.876288)
			(xy 80.852467 -278.925187) (xy 80.829124 -278.970999) (xy 80.798903 -279.012595) (xy 80.762547 -279.048951)
			(xy 80.720951 -279.079172) (xy 80.675139 -279.102515) (xy 80.62624 -279.118403) (xy 80.575458 -279.126446)
			(xy 80.524042 -279.126446) (xy 80.47326 -279.118403) (xy 80.424361 -279.102515) (xy 80.378549 -279.079172)
			(xy 80.336953 -279.048951) (xy 80.300597 -279.012595) (xy 80.270376 -278.970999) (xy 80.247033 -278.925187)
			(xy 80.231145 -278.876288) (xy 80.223102 -278.825506) (xy 78.976224 -278.825506) (xy 78.968181 -278.876288)
			(xy 78.952293 -278.925187) (xy 78.92895 -278.970999) (xy 78.898729 -279.012595) (xy 78.862373 -279.048951)
			(xy 78.820777 -279.079172) (xy 78.774965 -279.102515) (xy 78.726066 -279.118403) (xy 78.675284 -279.126446)
			(xy 78.623868 -279.126446) (xy 78.573086 -279.118403) (xy 78.524187 -279.102515) (xy 78.478375 -279.079172)
			(xy 78.436779 -279.048951) (xy 78.400423 -279.012595) (xy 78.370202 -278.970999) (xy 78.346859 -278.925187)
			(xy 78.330971 -278.876288) (xy 78.322928 -278.825506) (xy 77.076304 -278.825506) (xy 77.068261 -278.876288)
			(xy 77.052373 -278.925187) (xy 77.02903 -278.970999) (xy 76.998809 -279.012595) (xy 76.962453 -279.048951)
			(xy 76.920857 -279.079172) (xy 76.875045 -279.102515) (xy 76.826146 -279.118403) (xy 76.775364 -279.126446)
			(xy 76.723948 -279.126446) (xy 76.673166 -279.118403) (xy 76.624267 -279.102515) (xy 76.578455 -279.079172)
			(xy 76.536859 -279.048951) (xy 76.500503 -279.012595) (xy 76.470282 -278.970999) (xy 76.446939 -278.925187)
			(xy 76.431051 -278.876288) (xy 76.423008 -278.825506) (xy 75.176384 -278.825506) (xy 75.168341 -278.876288)
			(xy 75.152453 -278.925187) (xy 75.12911 -278.970999) (xy 75.098889 -279.012595) (xy 75.062533 -279.048951)
			(xy 75.020937 -279.079172) (xy 74.975125 -279.102515) (xy 74.926226 -279.118403) (xy 74.875444 -279.126446)
			(xy 74.824028 -279.126446) (xy 74.773246 -279.118403) (xy 74.724347 -279.102515) (xy 74.678535 -279.079172)
			(xy 74.636939 -279.048951) (xy 74.600583 -279.012595) (xy 74.570362 -278.970999) (xy 74.547019 -278.925187)
			(xy 74.531131 -278.876288) (xy 74.523088 -278.825506) (xy 73.27621 -278.825506) (xy 73.268167 -278.876288)
			(xy 73.252279 -278.925187) (xy 73.228936 -278.970999) (xy 73.198715 -279.012595) (xy 73.162359 -279.048951)
			(xy 73.120763 -279.079172) (xy 73.074951 -279.102515) (xy 73.026052 -279.118403) (xy 72.97527 -279.126446)
			(xy 72.923854 -279.126446) (xy 72.873072 -279.118403) (xy 72.824173 -279.102515) (xy 72.778361 -279.079172)
			(xy 72.736765 -279.048951) (xy 72.700409 -279.012595) (xy 72.670188 -278.970999) (xy 72.646845 -278.925187)
			(xy 72.630957 -278.876288) (xy 72.622914 -278.825506) (xy 71.37629 -278.825506) (xy 71.368247 -278.876288)
			(xy 71.352359 -278.925187) (xy 71.329016 -278.970999) (xy 71.298795 -279.012595) (xy 71.262439 -279.048951)
			(xy 71.220843 -279.079172) (xy 71.175031 -279.102515) (xy 71.126132 -279.118403) (xy 71.07535 -279.126446)
			(xy 71.023934 -279.126446) (xy 70.973152 -279.118403) (xy 70.924253 -279.102515) (xy 70.878441 -279.079172)
			(xy 70.836845 -279.048951) (xy 70.800489 -279.012595) (xy 70.770268 -278.970999) (xy 70.746925 -278.925187)
			(xy 70.731037 -278.876288) (xy 70.722994 -278.825506) (xy 69.47637 -278.825506) (xy 69.468327 -278.876288)
			(xy 69.452439 -278.925187) (xy 69.429096 -278.970999) (xy 69.398875 -279.012595) (xy 69.362519 -279.048951)
			(xy 69.320923 -279.079172) (xy 69.275111 -279.102515) (xy 69.226212 -279.118403) (xy 69.17543 -279.126446)
			(xy 69.124014 -279.126446) (xy 69.073232 -279.118403) (xy 69.024333 -279.102515) (xy 68.978521 -279.079172)
			(xy 68.936925 -279.048951) (xy 68.900569 -279.012595) (xy 68.870348 -278.970999) (xy 68.847005 -278.925187)
			(xy 68.831117 -278.876288) (xy 68.823074 -278.825506) (xy 67.576196 -278.825506) (xy 67.568153 -278.876288)
			(xy 67.552265 -278.925187) (xy 67.528922 -278.970999) (xy 67.498701 -279.012595) (xy 67.462345 -279.048951)
			(xy 67.420749 -279.079172) (xy 67.374937 -279.102515) (xy 67.326038 -279.118403) (xy 67.275256 -279.126446)
			(xy 67.22384 -279.126446) (xy 67.173058 -279.118403) (xy 67.124159 -279.102515) (xy 67.078347 -279.079172)
			(xy 67.036751 -279.048951) (xy 67.000395 -279.012595) (xy 66.970174 -278.970999) (xy 66.946831 -278.925187)
			(xy 66.930943 -278.876288) (xy 66.9229 -278.825506) (xy 65.676276 -278.825506) (xy 65.668233 -278.876288)
			(xy 65.652345 -278.925187) (xy 65.629002 -278.970999) (xy 65.598781 -279.012595) (xy 65.562425 -279.048951)
			(xy 65.520829 -279.079172) (xy 65.475017 -279.102515) (xy 65.426118 -279.118403) (xy 65.375336 -279.126446)
			(xy 65.32392 -279.126446) (xy 65.273138 -279.118403) (xy 65.224239 -279.102515) (xy 65.178427 -279.079172)
			(xy 65.136831 -279.048951) (xy 65.100475 -279.012595) (xy 65.070254 -278.970999) (xy 65.046911 -278.925187)
			(xy 65.031023 -278.876288) (xy 65.02298 -278.825506) (xy 63.776356 -278.825506) (xy 63.768313 -278.876288)
			(xy 63.752425 -278.925187) (xy 63.729082 -278.970999) (xy 63.698861 -279.012595) (xy 63.662505 -279.048951)
			(xy 63.620909 -279.079172) (xy 63.575097 -279.102515) (xy 63.526198 -279.118403) (xy 63.475416 -279.126446)
			(xy 63.424 -279.126446) (xy 63.373218 -279.118403) (xy 63.324319 -279.102515) (xy 63.278507 -279.079172)
			(xy 63.236911 -279.048951) (xy 63.200555 -279.012595) (xy 63.170334 -278.970999) (xy 63.146991 -278.925187)
			(xy 63.131103 -278.876288) (xy 63.12306 -278.825506) (xy 61.876182 -278.825506) (xy 61.868139 -278.876288)
			(xy 61.852251 -278.925187) (xy 61.828908 -278.970999) (xy 61.798687 -279.012595) (xy 61.762331 -279.048951)
			(xy 61.720735 -279.079172) (xy 61.674923 -279.102515) (xy 61.626024 -279.118403) (xy 61.575242 -279.126446)
			(xy 61.523826 -279.126446) (xy 61.473044 -279.118403) (xy 61.424145 -279.102515) (xy 61.378333 -279.079172)
			(xy 61.336737 -279.048951) (xy 61.300381 -279.012595) (xy 61.27016 -278.970999) (xy 61.246817 -278.925187)
			(xy 61.230929 -278.876288) (xy 61.222886 -278.825506) (xy 59.975993 -278.825506) (xy 59.96796 -278.876229)
			(xy 59.952085 -278.925089) (xy 59.928762 -278.970865) (xy 59.898565 -279.012428) (xy 59.862239 -279.048756)
			(xy 59.820677 -279.078954) (xy 59.774902 -279.102279) (xy 59.726043 -279.118156) (xy 59.675301 -279.126195)
			(xy 59.649614 -279.126696) (xy 59.64936 -279.126696) (xy 59.620658 -279.125426) (xy 59.60618 -279.124156)
			(xy 59.580526 -279.136856) (xy 59.538616 -279.205182) (xy 59.535163 -279.211239) (xy 59.531305 -279.224632)
			(xy 59.530996 -279.231598) (xy 59.538108 -279.257506) (xy 59.54141 -279.263094) (xy 59.558936 -279.294844)
			(xy 59.569043 -279.314153) (xy 59.587718 -279.353539) (xy 59.596274 -279.373584) (xy 59.599331 -279.380259)
			(xy 59.608623 -279.391619) (xy 59.614562 -279.395936) (xy 59.648344 -279.418796) (xy 59.660028 -279.419304)
			(xy 59.685474 -279.420561) (xy 59.735552 -279.429926) (xy 59.783602 -279.446859) (xy 59.828487 -279.470959)
			(xy 59.869145 -279.501657) (xy 59.904616 -279.538227) (xy 59.93406 -279.579802) (xy 59.956781 -279.625401)
			(xy 59.97224 -279.673945) (xy 59.980074 -279.724285) (xy 59.980576 -279.749758) (xy 59.980576 -279.750266)
			(xy 59.978798 -279.784302) (xy 59.977528 -279.795478) (xy 59.985148 -279.817068) (xy 60.057284 -279.889458)
			(xy 60.078874 -279.897078) (xy 60.090304 -279.895808) (xy 60.124594 -279.89403) (xy 60.125356 -279.89403)
			(xy 60.138687 -279.894177) (xy 60.165262 -279.896341) (xy 60.178442 -279.898348) (xy 60.18276 -279.89911)
			(xy 60.183014 -279.89911) (xy 60.191142 -279.90038) (xy 60.202064 -279.897078) (xy 60.207716 -279.895192)
			(xy 60.217985 -279.889158) (xy 60.222384 -279.88514) (xy 60.271406 -279.838658) (xy 60.279026 -279.814782)
			(xy 60.276994 -279.802336) (xy 60.274969 -279.789222) (xy 60.272811 -279.762773) (xy 60.272676 -279.749504)
			(xy 60.27318 -279.723799) (xy 60.281221 -279.673021) (xy 60.297107 -279.624127) (xy 60.320446 -279.57832)
			(xy 60.350663 -279.536727) (xy 60.387015 -279.500374) (xy 60.428606 -279.470154) (xy 60.474412 -279.446813)
			(xy 60.523306 -279.430925) (xy 60.574083 -279.422881) (xy 60.625493 -279.422879) (xy 60.676271 -279.430919)
			(xy 60.725166 -279.446804) (xy 60.770974 -279.470142) (xy 60.812567 -279.500358) (xy 60.848921 -279.536709)
			(xy 60.879141 -279.578299) (xy 60.902484 -279.624105) (xy 60.918373 -279.672998) (xy 60.926418 -279.723775)
			(xy 60.926422 -279.775185) (xy 60.918383 -279.825963) (xy 60.902499 -279.874858) (xy 60.879162 -279.920667)
			(xy 60.848947 -279.962261) (xy 60.812597 -279.998616) (xy 60.771008 -280.028837) (xy 60.725203 -280.052181)
			(xy 60.67631 -280.068071) (xy 60.625533 -280.076118) (xy 60.599828 -280.076656) (xy 60.58656 -280.076508)
			(xy 60.560112 -280.074346) (xy 60.546996 -280.072338) (xy 60.53455 -280.070306) (xy 60.510674 -280.07818)
			(xy 60.456572 -280.135076) (xy 60.456064 -280.135584) (xy 60.448952 -280.157936) (xy 60.449968 -280.16454)
			(xy 60.450476 -280.16708) (xy 60.45284 -280.181377) (xy 60.45538 -280.210247) (xy 60.455556 -280.224738)
			(xy 60.455556 -280.295096) (xy 60.45581 -280.30043) (xy 60.457001 -280.30861) (xy 60.463874 -280.323632)
			(xy 60.469272 -280.329894) (xy 60.47232 -280.332942) (xy 60.515754 -280.372058) (xy 60.537598 -280.378408)
			(xy 60.549028 -280.37663) (xy 60.561648 -280.374808) (xy 60.587077 -280.372899) (xy 60.599828 -280.37282)
			(xy 60.625513 -280.373326) (xy 60.67625 -280.381366) (xy 60.725104 -280.397243) (xy 60.770874 -280.420567)
			(xy 60.812432 -280.450764) (xy 60.848754 -280.48709) (xy 60.878947 -280.52865) (xy 60.902267 -280.574421)
			(xy 60.918141 -280.623277) (xy 60.926176 -280.674015) (xy 60.926176 -280.725385) (xy 60.918141 -280.776123)
			(xy 60.902267 -280.824979) (xy 60.878947 -280.87075) (xy 60.848754 -280.91231) (xy 60.812432 -280.948636)
			(xy 60.770874 -280.978833) (xy 60.725104 -281.002157) (xy 60.67625 -281.018034) (xy 60.625513 -281.026074)
			(xy 60.599828 -281.026616) (xy 60.587077 -281.026534) (xy 60.561648 -281.024628) (xy 60.549028 -281.022806)
			(xy 60.537598 -281.021028) (xy 60.515754 -281.027378) (xy 60.47232 -281.066494) (xy 60.469272 -281.069542)
			(xy 60.463845 -281.075784) (xy 60.456969 -281.090817) (xy 60.45581 -281.099006) (xy 60.455556 -281.10434)
			(xy 60.455556 -281.173936) (xy 60.455302 -281.178762) (xy 60.455302 -281.184096) (xy 60.455944 -281.191931)
			(xy 60.461372 -281.206676) (xy 60.46597 -281.213052) (xy 60.469018 -281.216608) (xy 60.481464 -281.229816)
			(xy 60.481972 -281.23007) (xy 60.52058 -281.269694) (xy 60.52439 -281.272996) (xy 60.524898 -281.273504)
			(xy 60.531861 -281.278706) (xy 60.548219 -281.28455) (xy 60.556902 -281.284934) (xy 61.551566 -281.284934)
			(xy 61.560964 -281.285696) (xy 61.565536 -281.286712)
		)
		(stroke
			(width 0)
			(type solid)
		)
		(fill yes)
		(layer "In11.Cu")
		(net "GND")
	)
	(gr_line
		(start 30.109922 -371.972078)
		(end 30.109922 -371.590062)
		(stroke
			(width 0.08255)
			(type default)
		)
		(layer "In11.Cu")
	)
	(gr_line
		(start 30.236922 -372.099078)
		(end 30.109922 -371.972078)
		(stroke
			(width 0.08255)
			(type default)
		)
		(layer "In11.Cu")
	)
	(gr_line
		(start 31.805372 -367.110518)
		(end 31.82874 -367.26876)
		(stroke
			(width 0.08255)
			(type default)
		)
		(layer "In11.Cu")
	)
	(gr_line
		(start 32.10052 -366.712246)
		(end 31.805372 -367.110518)
		(stroke
			(width 0.08255)
			(type default)
		)
		(layer "In11.Cu")
	)
	(gr_line
		(start 32.258762 -366.688878)
		(end 32.10052 -366.712246)
		(stroke
			(width 0.08255)
			(type default)
		)
		(layer "In11.Cu")
	)
	(gr_line
		(start 32.31007 -370.872258)
		(end 32.31007 -370.489988)
		(stroke
			(width 0.08255)
			(type default)
		)
		(layer "In11.Cu")
	)
	(gr_line
		(start 32.43707 -370.999258)
		(end 32.31007 -370.872258)
		(stroke
			(width 0.08255)
			(type default)
		)
		(layer "In11.Cu")
	)
	(gr_line
		(start 32.531812 -366.131094)
		(end 32.55518 -366.289082)
		(stroke
			(width 0.08255)
			(type default)
		)
		(layer "In11.Cu")
	)
	(gr_line
		(start 32.82696 -365.732822)
		(end 32.531812 -366.131094)
		(stroke
			(width 0.08255)
			(type default)
		)
		(layer "In11.Cu")
	)
	(gr_line
		(start 32.985202 -365.709454)
		(end 32.82696 -365.732822)
		(stroke
			(width 0.08255)
			(type default)
		)
		(layer "In11.Cu")
	)
	(gr_line
		(start 32.98698 -365.7092)
		(end 32.986726 -365.7092)
		(stroke
			(width 0.08255)
			(type default)
		)
		(layer "In11.Cu")
	)
	(gr_line
		(start 33.257998 -365.15167)
		(end 33.281366 -365.309912)
		(stroke
			(width 0.08255)
			(type default)
		)
		(layer "In11.Cu")
	)
	(gr_line
		(start 33.553146 -364.753398)
		(end 33.257998 -365.15167)
		(stroke
			(width 0.08255)
			(type default)
		)
		(layer "In11.Cu")
	)
	(gr_line
		(start 33.711642 -364.73003)
		(end 33.553146 -364.753398)
		(stroke
			(width 0.08255)
			(type default)
		)
		(layer "In11.Cu")
	)
	(gr_line
		(start 34.021776 -367.260886)
		(end 34.053018 -367.417858)
		(stroke
			(width 0.08255)
			(type default)
		)
		(layer "In11.Cu")
	)
	(gr_line
		(start 34.297112 -366.848898)
		(end 34.021776 -367.260886)
		(stroke
			(width 0.08255)
			(type default)
		)
		(layer "In11.Cu")
	)
	(gr_line
		(start 34.454084 -366.817402)
		(end 34.297112 -366.848898)
		(stroke
			(width 0.08255)
			(type default)
		)
		(layer "In11.Cu")
	)
	(gr_line
		(start 34.509964 -372.508018)
		(end 34.509964 -372.890034)
		(stroke
			(width 0.08255)
			(type default)
		)
		(layer "In11.Cu")
	)
	(gr_line
		(start 34.509964 -371.972078)
		(end 34.509964 -371.590062)
		(stroke
			(width 0.08255)
			(type default)
		)
		(layer "In11.Cu")
	)
	(gr_line
		(start 34.636964 -372.381018)
		(end 34.509964 -372.508018)
		(stroke
			(width 0.08255)
			(type default)
		)
		(layer "In11.Cu")
	)
	(gr_line
		(start 34.636964 -372.099078)
		(end 34.509964 -371.972078)
		(stroke
			(width 0.08255)
			(type default)
		)
		(layer "In11.Cu")
	)
	(gr_line
		(start 34.699194 -366.246918)
		(end 34.730436 -366.404144)
		(stroke
			(width 0.08255)
			(type default)
		)
		(layer "In11.Cu")
	)
	(gr_line
		(start 34.854642 -363.020102)
		(end 34.87547 -363.160564)
		(stroke
			(width 0.08255)
			(type default)
		)
		(layer "In11.Cu")
	)
	(gr_line
		(start 34.97453 -365.83493)
		(end 34.699194 -366.246918)
		(stroke
			(width 0.08255)
			(type default)
		)
		(layer "In11.Cu")
	)
	(gr_line
		(start 35.131502 -365.803688)
		(end 34.97453 -365.83493)
		(stroke
			(width 0.08255)
			(type default)
		)
		(layer "In11.Cu")
	)
	(gr_line
		(start 35.150044 -362.62183)
		(end 34.854642 -363.020102)
		(stroke
			(width 0.08255)
			(type default)
		)
		(layer "In11.Cu")
	)
	(gr_line
		(start 35.290506 -362.601002)
		(end 35.150044 -362.62183)
		(stroke
			(width 0.08255)
			(type default)
		)
		(layer "In11.Cu")
	)
	(gr_line
		(start 35.376612 -365.233204)
		(end 35.407854 -365.390176)
		(stroke
			(width 0.08255)
			(type default)
		)
		(layer "In11.Cu")
	)
	(gr_line
		(start 35.565842 -362.060998)
		(end 35.58667 -362.20146)
		(stroke
			(width 0.08255)
			(type default)
		)
		(layer "In11.Cu")
	)
	(gr_line
		(start 35.651948 -364.821216)
		(end 35.376612 -365.233204)
		(stroke
			(width 0.08255)
			(type default)
		)
		(layer "In11.Cu")
	)
	(gr_line
		(start 35.80384 -367.980722)
		(end 35.864546 -368.109246)
		(stroke
			(width 0.08255)
			(type default)
		)
		(layer "In11.Cu")
	)
	(gr_line
		(start 35.80892 -364.78972)
		(end 35.651948 -364.821216)
		(stroke
			(width 0.08255)
			(type default)
		)
		(layer "In11.Cu")
	)
	(gr_line
		(start 35.861244 -361.662726)
		(end 35.565842 -362.060998)
		(stroke
			(width 0.08255)
			(type default)
		)
		(layer "In11.Cu")
	)
	(gr_line
		(start 35.970718 -367.514124)
		(end 35.80384 -367.980722)
		(stroke
			(width 0.08255)
			(type default)
		)
		(layer "In11.Cu")
	)
	(gr_line
		(start 36.001706 -361.641898)
		(end 35.861244 -361.662726)
		(stroke
			(width 0.08255)
			(type default)
		)
		(layer "In11.Cu")
	)
	(gr_line
		(start 36.05403 -364.219236)
		(end 36.085272 -364.376462)
		(stroke
			(width 0.08255)
			(type default)
		)
		(layer "In11.Cu")
	)
	(gr_line
		(start 36.099242 -367.453418)
		(end 35.970718 -367.514124)
		(stroke
			(width 0.08255)
			(type default)
		)
		(layer "In11.Cu")
	)
	(gr_line
		(start 36.277042 -361.101894)
		(end 36.29787 -361.24261)
		(stroke
			(width 0.08255)
			(type default)
		)
		(layer "In11.Cu")
	)
	(gr_line
		(start 36.329366 -363.807248)
		(end 36.05403 -364.219236)
		(stroke
			(width 0.08255)
			(type default)
		)
		(layer "In11.Cu")
	)
	(gr_line
		(start 36.36645 -367.547652)
		(end 36.130992 -368.205512)
		(stroke
			(width 0.08255)
			(type default)
		)
		(layer "In11.Cu")
	)
	(gr_line
		(start 36.486338 -363.776006)
		(end 36.329366 -363.807248)
		(stroke
			(width 0.08255)
			(type default)
		)
		(layer "In11.Cu")
	)
	(gr_line
		(start 36.572444 -360.703876)
		(end 36.277042 -361.101894)
		(stroke
			(width 0.08255)
			(type default)
		)
		(layer "In11.Cu")
	)
	(gr_line
		(start 36.710112 -370.872258)
		(end 36.710112 -370.489988)
		(stroke
			(width 0.08255)
			(type default)
		)
		(layer "In11.Cu")
	)
	(gr_line
		(start 36.712906 -360.683048)
		(end 36.572444 -360.703876)
		(stroke
			(width 0.08255)
			(type default)
		)
		(layer "In11.Cu")
	)
	(gr_line
		(start 36.731448 -363.205522)
		(end 36.76269 -363.362494)
		(stroke
			(width 0.08255)
			(type default)
		)
		(layer "In11.Cu")
	)
	(gr_line
		(start 36.837112 -370.999258)
		(end 36.710112 -370.872258)
		(stroke
			(width 0.08255)
			(type default)
		)
		(layer "In11.Cu")
	)
	(gr_line
		(start 36.884102 -365.662464)
		(end 36.899596 -365.82223)
		(stroke
			(width 0.08255)
			(type default)
		)
		(layer "In11.Cu")
	)
	(gr_line
		(start 36.988242 -360.143044)
		(end 37.00907 -360.283506)
		(stroke
			(width 0.08255)
			(type default)
		)
		(layer "In11.Cu")
	)
	(gr_line
		(start 37.006784 -362.793534)
		(end 36.731448 -363.205522)
		(stroke
			(width 0.08255)
			(type default)
		)
		(layer "In11.Cu")
	)
	(gr_line
		(start 37.163756 -362.762292)
		(end 37.006784 -362.793534)
		(stroke
			(width 0.08255)
			(type default)
		)
		(layer "In11.Cu")
	)
	(gr_line
		(start 37.198554 -365.279432)
		(end 36.884102 -365.662464)
		(stroke
			(width 0.08255)
			(type default)
		)
		(layer "In11.Cu")
	)
	(gr_line
		(start 37.283644 -359.745026)
		(end 36.988242 -360.143044)
		(stroke
			(width 0.08255)
			(type default)
		)
		(layer "In11.Cu")
	)
	(gr_line
		(start 37.357812 -365.263938)
		(end 37.198554 -365.279432)
		(stroke
			(width 0.08255)
			(type default)
		)
		(layer "In11.Cu")
	)
	(gr_line
		(start 37.424106 -359.724198)
		(end 37.283644 -359.745026)
		(stroke
			(width 0.08255)
			(type default)
		)
		(layer "In11.Cu")
	)
	(gr_line
		(start 37.425884 -359.723944)
		(end 37.42563 -359.723944)
		(stroke
			(width 0.08255)
			(type default)
		)
		(layer "In11.Cu")
	)
	(gr_line
		(start 37.577522 -365.442754)
		(end 37.118036 -366.00257)
		(stroke
			(width 0.08255)
			(type default)
		)
		(layer "In11.Cu")
	)
	(gr_line
		(start 37.657532 -364.720124)
		(end 37.67328 -364.879382)
		(stroke
			(width 0.08255)
			(type default)
		)
		(layer "In11.Cu")
	)
	(gr_line
		(start 37.708586 -361.74299)
		(end 37.740082 -361.899962)
		(stroke
			(width 0.08255)
			(type default)
		)
		(layer "In11.Cu")
	)
	(gr_line
		(start 37.971984 -364.336838)
		(end 37.657532 -364.720124)
		(stroke
			(width 0.08255)
			(type default)
		)
		(layer "In11.Cu")
	)
	(gr_line
		(start 37.984176 -361.331002)
		(end 37.708586 -361.74299)
		(stroke
			(width 0.08255)
			(type default)
		)
		(layer "In11.Cu")
	)
	(gr_line
		(start 37.986208 -357.75773)
		(end 38.277038 -358.04856)
		(stroke
			(width 0.08255)
			(type default)
		)
		(layer "In11.Cu")
	)
	(gr_line
		(start 38.04412 -368.136932)
		(end 38.075362 -368.293904)
		(stroke
			(width 0.08255)
			(type default)
		)
		(layer "In11.Cu")
	)
	(gr_line
		(start 38.131496 -364.321344)
		(end 37.971984 -364.336838)
		(stroke
			(width 0.08255)
			(type default)
		)
		(layer "In11.Cu")
	)
	(gr_line
		(start 38.140894 -361.29976)
		(end 37.984176 -361.331002)
		(stroke
			(width 0.08255)
			(type default)
		)
		(layer "In11.Cu")
	)
	(gr_line
		(start 38.276784 -358.576118)
		(end 38.277038 -358.575864)
		(stroke
			(width 0.08255)
			(type default)
		)
		(layer "In11.Cu")
	)
	(gr_line
		(start 38.277038 -354.441252)
		(end 37.986208 -354.732082)
		(stroke
			(width 0.08255)
			(type default)
		)
		(layer "In11.Cu")
	)
	(gr_line
		(start 38.319456 -367.724944)
		(end 38.04412 -368.136932)
		(stroke
			(width 0.08255)
			(type default)
		)
		(layer "In11.Cu")
	)
	(gr_line
		(start 38.351206 -364.50016)
		(end 37.89172 -365.059976)
		(stroke
			(width 0.08255)
			(type default)
		)
		(layer "In11.Cu")
	)
	(gr_line
		(start 38.386258 -360.729022)
		(end 38.4175 -360.885994)
		(stroke
			(width 0.08255)
			(type default)
		)
		(layer "In11.Cu")
	)
	(gr_line
		(start 38.431216 -363.77753)
		(end 38.446964 -363.936788)
		(stroke
			(width 0.08255)
			(type default)
		)
		(layer "In11.Cu")
	)
	(gr_line
		(start 38.476174 -367.693702)
		(end 38.319456 -367.724944)
		(stroke
			(width 0.08255)
			(type default)
		)
		(layer "In11.Cu")
	)
	(gr_line
		(start 38.477952 -367.693448)
		(end 38.477698 -367.693448)
		(stroke
			(width 0.08255)
			(type default)
		)
		(layer "In11.Cu")
	)
	(gr_line
		(start 38.661594 -360.317034)
		(end 38.386258 -360.729022)
		(stroke
			(width 0.08255)
			(type default)
		)
		(layer "In11.Cu")
	)
	(gr_line
		(start 38.721284 -367.123218)
		(end 38.752526 -367.28019)
		(stroke
			(width 0.08255)
			(type default)
		)
		(layer "In11.Cu")
	)
	(gr_line
		(start 38.745668 -363.394244)
		(end 38.431216 -363.77753)
		(stroke
			(width 0.08255)
			(type default)
		)
		(layer "In11.Cu")
	)
	(gr_line
		(start 38.818566 -360.285792)
		(end 38.661594 -360.317034)
		(stroke
			(width 0.08255)
			(type default)
		)
		(layer "In11.Cu")
	)
	(gr_line
		(start 38.90518 -363.37875)
		(end 38.745668 -363.394244)
		(stroke
			(width 0.08255)
			(type default)
		)
		(layer "In11.Cu")
	)
	(gr_line
		(start 38.910006 -372.508018)
		(end 38.910006 -372.890034)
		(stroke
			(width 0.08255)
			(type default)
		)
		(layer "In11.Cu")
	)
	(gr_line
		(start 38.910006 -371.972078)
		(end 38.910006 -371.590062)
		(stroke
			(width 0.08255)
			(type default)
		)
		(layer "In11.Cu")
	)
	(gr_line
		(start 38.99662 -366.710976)
		(end 38.721284 -367.123218)
		(stroke
			(width 0.08255)
			(type default)
		)
		(layer "In11.Cu")
	)
	(gr_line
		(start 39.037006 -372.381018)
		(end 38.910006 -372.508018)
		(stroke
			(width 0.08255)
			(type default)
		)
		(layer "In11.Cu")
	)
	(gr_line
		(start 39.037006 -372.099078)
		(end 38.910006 -371.972078)
		(stroke
			(width 0.08255)
			(type default)
		)
		(layer "In11.Cu")
	)
	(gr_line
		(start 39.063676 -359.715308)
		(end 39.094918 -359.87228)
		(stroke
			(width 0.08255)
			(type default)
		)
		(layer "In11.Cu")
	)
	(gr_line
		(start 39.124636 -363.557566)
		(end 38.66515 -364.117382)
		(stroke
			(width 0.08255)
			(type default)
		)
		(layer "In11.Cu")
	)
	(gr_line
		(start 39.153592 -366.679734)
		(end 38.99662 -366.710976)
		(stroke
			(width 0.08255)
			(type default)
		)
		(layer "In11.Cu")
	)
	(gr_line
		(start 39.2049 -362.834936)
		(end 39.220648 -362.99394)
		(stroke
			(width 0.08255)
			(type default)
		)
		(layer "In11.Cu")
	)
	(gr_line
		(start 39.339012 -359.303066)
		(end 39.063676 -359.715308)
		(stroke
			(width 0.08255)
			(type default)
		)
		(layer "In11.Cu")
	)
	(gr_line
		(start 39.398702 -366.10925)
		(end 39.429944 -366.266222)
		(stroke
			(width 0.08255)
			(type default)
		)
		(layer "In11.Cu")
	)
	(gr_line
		(start 39.495984 -359.271824)
		(end 39.339012 -359.303066)
		(stroke
			(width 0.08255)
			(type default)
		)
		(layer "In11.Cu")
	)
	(gr_line
		(start 39.519352 -362.45165)
		(end 39.2049 -362.834936)
		(stroke
			(width 0.08255)
			(type default)
		)
		(layer "In11.Cu")
	)
	(gr_line
		(start 39.633144 -359.069132)
		(end 39.497762 -359.27157)
		(stroke
			(width 0.08255)
			(type default)
		)
		(layer "In11.Cu")
	)
	(gr_line
		(start 39.674038 -365.697008)
		(end 39.398702 -366.10925)
		(stroke
			(width 0.08255)
			(type default)
		)
		(layer "In11.Cu")
	)
	(gr_line
		(start 39.67861 -362.436156)
		(end 39.519352 -362.45165)
		(stroke
			(width 0.08255)
			(type default)
		)
		(layer "In11.Cu")
	)
	(gr_line
		(start 39.83101 -365.665766)
		(end 39.674038 -365.697008)
		(stroke
			(width 0.08255)
			(type default)
		)
		(layer "In11.Cu")
	)
	(gr_line
		(start 39.89832 -362.614718)
		(end 39.438834 -363.174534)
		(stroke
			(width 0.08255)
			(type default)
		)
		(layer "In11.Cu")
	)
	(gr_line
		(start 39.983156 -361.939586)
		(end 39.994078 -362.0516)
		(stroke
			(width 0.08255)
			(type default)
		)
		(layer "In11.Cu")
	)
	(gr_line
		(start 40.04945 -367.816384)
		(end 40.077136 -367.955576)
		(stroke
			(width 0.08255)
			(type default)
		)
		(layer "In11.Cu")
	)
	(gr_line
		(start 40.07612 -365.095282)
		(end 40.107362 -365.252254)
		(stroke
			(width 0.08255)
			(type default)
		)
		(layer "In11.Cu")
	)
	(gr_line
		(start 40.232838 -341.079836)
		(end 40.211248 -341.131652)
		(stroke
			(width 0.08255)
			(type default)
		)
		(layer "In11.Cu")
	)
	(gr_line
		(start 40.272208 -341.040212)
		(end 40.232838 -341.079836)
		(stroke
			(width 0.08255)
			(type default)
		)
		(layer "In11.Cu")
	)
	(gr_line
		(start 40.272462 -341.040212)
		(end 40.272208 -341.040212)
		(stroke
			(width 0.08255)
			(type default)
		)
		(layer "In11.Cu")
	)
	(gr_line
		(start 40.324786 -367.404396)
		(end 40.04945 -367.816384)
		(stroke
			(width 0.08255)
			(type default)
		)
		(layer "In11.Cu")
	)
	(gr_line
		(start 40.34028 -361.504484)
		(end 39.983156 -361.939586)
		(stroke
			(width 0.08255)
			(type default)
		)
		(layer "In11.Cu")
	)
	(gr_line
		(start 40.351456 -364.68304)
		(end 40.07612 -365.095282)
		(stroke
			(width 0.08255)
			(type default)
		)
		(layer "In11.Cu")
	)
	(gr_line
		(start 40.452294 -361.493562)
		(end 40.34028 -361.504484)
		(stroke
			(width 0.08255)
			(type default)
		)
		(layer "In11.Cu")
	)
	(gr_line
		(start 40.463978 -367.37671)
		(end 40.324786 -367.404396)
		(stroke
			(width 0.08255)
			(type default)
		)
		(layer "In11.Cu")
	)
	(gr_line
		(start 40.465502 -367.376456)
		(end 40.465756 -367.376456)
		(stroke
			(width 0.08255)
			(type default)
		)
		(layer "In11.Cu")
	)
	(gr_line
		(start 40.508174 -364.651798)
		(end 40.351456 -364.68304)
		(stroke
			(width 0.08255)
			(type default)
		)
		(layer "In11.Cu")
	)
	(gr_line
		(start 40.67175 -361.672124)
		(end 40.212518 -362.23194)
		(stroke
			(width 0.08255)
			(type default)
		)
		(layer "In11.Cu")
	)
	(gr_line
		(start 40.699944 -367.533174)
		(end 40.311832 -368.114072)
		(stroke
			(width 0.08255)
			(type default)
		)
		(layer "In11.Cu")
	)
	(gr_line
		(start 40.712644 -366.823752)
		(end 40.74033 -366.963198)
		(stroke
			(width 0.08255)
			(type default)
		)
		(layer "In11.Cu")
	)
	(gr_line
		(start 40.76065 -364.118144)
		(end 40.78478 -364.238032)
		(stroke
			(width 0.08255)
			(type default)
		)
		(layer "In11.Cu")
	)
	(gr_line
		(start 40.98798 -366.411764)
		(end 40.712644 -366.823752)
		(stroke
			(width 0.08255)
			(type default)
		)
		(layer "In11.Cu")
	)
	(gr_line
		(start 41.065704 -363.661706)
		(end 40.76065 -364.118144)
		(stroke
			(width 0.08255)
			(type default)
		)
		(layer "In11.Cu")
	)
	(gr_line
		(start 41.095168 -351.611438)
		(end 41.385998 -351.902268)
		(stroke
			(width 0.08255)
			(type default)
		)
		(layer "In11.Cu")
	)
	(gr_line
		(start 41.1099 -370.872258)
		(end 41.1099 -370.489988)
		(stroke
			(width 0.08255)
			(type default)
		)
		(layer "In11.Cu")
	)
	(gr_line
		(start 41.127172 -366.384078)
		(end 40.98798 -366.411764)
		(stroke
			(width 0.08255)
			(type default)
		)
		(layer "In11.Cu")
	)
	(gr_line
		(start 41.185592 -363.63783)
		(end 41.065704 -363.661706)
		(stroke
			(width 0.08255)
			(type default)
		)
		(layer "In11.Cu")
	)
	(gr_line
		(start 41.20515 -366.269778)
		(end 41.12895 -366.383824)
		(stroke
			(width 0.08255)
			(type default)
		)
		(layer "In11.Cu")
	)
	(gr_line
		(start 41.2369 -370.999258)
		(end 41.1099 -370.872258)
		(stroke
			(width 0.08255)
			(type default)
		)
		(layer "In11.Cu")
	)
	(gr_line
		(start 41.363392 -366.540542)
		(end 40.975026 -367.12144)
		(stroke
			(width 0.08255)
			(type default)
		)
		(layer "In11.Cu")
	)
	(gr_line
		(start 41.364154 -360.244136)
		(end 41.376092 -360.36758)
		(stroke
			(width 0.08255)
			(type default)
		)
		(layer "In11.Cu")
	)
	(gr_line
		(start 41.376092 -365.83112)
		(end 41.403778 -365.970312)
		(stroke
			(width 0.08255)
			(type default)
		)
		(layer "In11.Cu")
	)
	(gr_line
		(start 41.385998 -348.29496)
		(end 41.095168 -348.58579)
		(stroke
			(width 0.08255)
			(type default)
		)
		(layer "In11.Cu")
	)
	(gr_line
		(start 41.439592 -366.426496)
		(end 41.363392 -366.540542)
		(stroke
			(width 0.08255)
			(type default)
		)
		(layer "In11.Cu")
	)
	(gr_line
		(start 41.651428 -365.419132)
		(end 41.376092 -365.83112)
		(stroke
			(width 0.08255)
			(type default)
		)
		(layer "In11.Cu")
	)
	(gr_line
		(start 41.678606 -359.86085)
		(end 41.364154 -360.244136)
		(stroke
			(width 0.08255)
			(type default)
		)
		(layer "In11.Cu")
	)
	(gr_line
		(start 41.790366 -365.3917)
		(end 41.651428 -365.419132)
		(stroke
			(width 0.08255)
			(type default)
		)
		(layer "In11.Cu")
	)
	(gr_line
		(start 41.792144 -365.391192)
		(end 41.792398 -365.391192)
		(stroke
			(width 0.08255)
			(type default)
		)
		(layer "In11.Cu")
	)
	(gr_line
		(start 41.80205 -359.848912)
		(end 41.678606 -359.86085)
		(stroke
			(width 0.08255)
			(type default)
		)
		(layer "In11.Cu")
	)
	(gr_line
		(start 42.021506 -360.027728)
		(end 41.594532 -360.548174)
		(stroke
			(width 0.08255)
			(type default)
		)
		(layer "In11.Cu")
	)
	(gr_line
		(start 42.026586 -365.54791)
		(end 41.638474 -366.128808)
		(stroke
			(width 0.08255)
			(type default)
		)
		(layer "In11.Cu")
	)
	(gr_line
		(start 42.03573 -364.820962)
		(end 42.066972 -364.977934)
		(stroke
			(width 0.08255)
			(type default)
		)
		(layer "In11.Cu")
	)
	(gr_line
		(start 42.10558 -359.340658)
		(end 42.117518 -359.464102)
		(stroke
			(width 0.08255)
			(type default)
		)
		(layer "In11.Cu")
	)
	(gr_line
		(start 42.21734 -368.48542)
		(end 42.278554 -368.633248)
		(stroke
			(width 0.08255)
			(type default)
		)
		(layer "In11.Cu")
	)
	(gr_line
		(start 42.293032 -361.776518)
		(end 42.324274 -361.93349)
		(stroke
			(width 0.08255)
			(type default)
		)
		(layer "In11.Cu")
	)
	(gr_line
		(start 42.311066 -364.408974)
		(end 42.03573 -364.820962)
		(stroke
			(width 0.08255)
			(type default)
		)
		(layer "In11.Cu")
	)
	(gr_line
		(start 42.406824 -368.027458)
		(end 42.21734 -368.48542)
		(stroke
			(width 0.08255)
			(type default)
		)
		(layer "In11.Cu")
	)
	(gr_line
		(start 42.420032 -358.957626)
		(end 42.10558 -359.340658)
		(stroke
			(width 0.08255)
			(type default)
		)
		(layer "In11.Cu")
	)
	(gr_line
		(start 42.467784 -364.377732)
		(end 42.311066 -364.408974)
		(stroke
			(width 0.08255)
			(type default)
		)
		(layer "In11.Cu")
	)
	(gr_line
		(start 42.543476 -358.945434)
		(end 42.420032 -358.957626)
		(stroke
			(width 0.08255)
			(type default)
		)
		(layer "In11.Cu")
	)
	(gr_line
		(start 42.554906 -367.966498)
		(end 42.406824 -368.027458)
		(stroke
			(width 0.08255)
			(type default)
		)
		(layer "In11.Cu")
	)
	(gr_line
		(start 42.568368 -361.364276)
		(end 42.293032 -361.776518)
		(stroke
			(width 0.08255)
			(type default)
		)
		(layer "In11.Cu")
	)
	(gr_line
		(start 42.683938 -367.35893)
		(end 42.745152 -367.506504)
		(stroke
			(width 0.08255)
			(type default)
		)
		(layer "In11.Cu")
	)
	(gr_line
		(start 42.704004 -364.534196)
		(end 42.301668 -365.136176)
		(stroke
			(width 0.08255)
			(type default)
		)
		(layer "In11.Cu")
	)
	(gr_line
		(start 42.72534 -361.333034)
		(end 42.568368 -361.364276)
		(stroke
			(width 0.08255)
			(type default)
		)
		(layer "In11.Cu")
	)
	(gr_line
		(start 42.763186 -359.12425)
		(end 42.335704 -359.644696)
		(stroke
			(width 0.08255)
			(type default)
		)
		(layer "In11.Cu")
	)
	(gr_line
		(start 42.873422 -366.900968)
		(end 42.683938 -367.35893)
		(stroke
			(width 0.08255)
			(type default)
		)
		(layer "In11.Cu")
	)
	(gr_line
		(start 42.97045 -360.76255)
		(end 43.001692 -360.919522)
		(stroke
			(width 0.08255)
			(type default)
		)
		(layer "In11.Cu")
	)
	(gr_line
		(start 43.02125 -366.840008)
		(end 42.873422 -366.900968)
		(stroke
			(width 0.08255)
			(type default)
		)
		(layer "In11.Cu")
	)
	(gr_line
		(start 43.024552 -366.83569)
		(end 43.023028 -366.839246)
		(stroke
			(width 0.08255)
			(type default)
		)
		(layer "In11.Cu")
	)
	(gr_line
		(start 43.063922 -363.304836)
		(end 43.091862 -363.444028)
		(stroke
			(width 0.08255)
			(type default)
		)
		(layer "In11.Cu")
	)
	(gr_line
		(start 43.245786 -360.350308)
		(end 42.97045 -360.76255)
		(stroke
			(width 0.08255)
			(type default)
		)
		(layer "In11.Cu")
	)
	(gr_line
		(start 43.310048 -371.972078)
		(end 43.310048 -371.590062)
		(stroke
			(width 0.08255)
			(type default)
		)
		(layer "In11.Cu")
	)
	(gr_line
		(start 43.339512 -362.892848)
		(end 43.063922 -363.304836)
		(stroke
			(width 0.08255)
			(type default)
		)
		(layer "In11.Cu")
	)
	(gr_line
		(start 43.402758 -360.319066)
		(end 43.245786 -360.350308)
		(stroke
			(width 0.08255)
			(type default)
		)
		(layer "In11.Cu")
	)
	(gr_line
		(start 43.437048 -372.099078)
		(end 43.310048 -371.972078)
		(stroke
			(width 0.08255)
			(type default)
		)
		(layer "In11.Cu")
	)
	(gr_line
		(start 43.47845 -362.865416)
		(end 43.339512 -362.892848)
		(stroke
			(width 0.08255)
			(type default)
		)
		(layer "In11.Cu")
	)
	(gr_line
		(start 43.480228 -362.864908)
		(end 43.480482 -362.864908)
		(stroke
			(width 0.08255)
			(type default)
		)
		(layer "In11.Cu")
	)
	(gr_line
		(start 43.647868 -359.748582)
		(end 43.67911 -359.905554)
		(stroke
			(width 0.08255)
			(type default)
		)
		(layer "In11.Cu")
	)
	(gr_line
		(start 43.71467 -363.021626)
		(end 43.326558 -363.602524)
		(stroke
			(width 0.08255)
			(type default)
		)
		(layer "In11.Cu")
	)
	(gr_line
		(start 43.72737 -365.488982)
		(end 43.743118 -365.64824)
		(stroke
			(width 0.08255)
			(type default)
		)
		(layer "In11.Cu")
	)
	(gr_line
		(start 43.72737 -362.312204)
		(end 43.755056 -362.45165)
		(stroke
			(width 0.08255)
			(type default)
		)
		(layer "In11.Cu")
	)
	(gr_line
		(start 43.923204 -359.336594)
		(end 43.647868 -359.748582)
		(stroke
			(width 0.08255)
			(type default)
		)
		(layer "In11.Cu")
	)
	(gr_line
		(start 44.002706 -361.900216)
		(end 43.72737 -362.312204)
		(stroke
			(width 0.08255)
			(type default)
		)
		(layer "In11.Cu")
	)
	(gr_line
		(start 44.042076 -365.10595)
		(end 43.72737 -365.488982)
		(stroke
			(width 0.08255)
			(type default)
		)
		(layer "In11.Cu")
	)
	(gr_line
		(start 44.079922 -359.305352)
		(end 43.923204 -359.336594)
		(stroke
			(width 0.08255)
			(type default)
		)
		(layer "In11.Cu")
	)
	(gr_line
		(start 44.0817 -359.305098)
		(end 44.081446 -359.305098)
		(stroke
			(width 0.08255)
			(type default)
		)
		(layer "In11.Cu")
	)
	(gr_line
		(start 44.141898 -361.87253)
		(end 44.002706 -361.900216)
		(stroke
			(width 0.08255)
			(type default)
		)
		(layer "In11.Cu")
	)
	(gr_line
		(start 44.143422 -361.872276)
		(end 44.143676 -361.872276)
		(stroke
			(width 0.08255)
			(type default)
		)
		(layer "In11.Cu")
	)
	(gr_line
		(start 44.201334 -365.090202)
		(end 44.042076 -365.10595)
		(stroke
			(width 0.08255)
			(type default)
		)
		(layer "In11.Cu")
	)
	(gr_line
		(start 44.204128 -357.75773)
		(end 44.494958 -358.04856)
		(stroke
			(width 0.08255)
			(type default)
		)
		(layer "In11.Cu")
	)
	(gr_line
		(start 44.204128 -345.465146)
		(end 44.494958 -345.755976)
		(stroke
			(width 0.08255)
			(type default)
		)
		(layer "In11.Cu")
	)
	(gr_line
		(start 44.378118 -362.028994)
		(end 43.989752 -362.609892)
		(stroke
			(width 0.08255)
			(type default)
		)
		(layer "In11.Cu")
	)
	(gr_line
		(start 44.397422 -361.354878)
		(end 44.41825 -361.459018)
		(stroke
			(width 0.08255)
			(type default)
		)
		(layer "In11.Cu")
	)
	(gr_line
		(start 44.493688 -358.688132)
		(end 44.478956 -358.71023)
		(stroke
			(width 0.08255)
			(type default)
		)
		(layer "In11.Cu")
	)
	(gr_line
		(start 44.494958 -354.441252)
		(end 44.204128 -354.732082)
		(stroke
			(width 0.08255)
			(type default)
		)
		(layer "In11.Cu")
	)
	(gr_line
		(start 44.494958 -342.148668)
		(end 44.204128 -342.439498)
		(stroke
			(width 0.08255)
			(type default)
		)
		(layer "In11.Cu")
	)
	(gr_line
		(start 44.494958 -341.135462)
		(end 44.494958 -341.252302)
		(stroke
			(width 0.08255)
			(type default)
		)
		(layer "In11.Cu")
	)
	(gr_line
		(start 44.501054 -364.546388)
		(end 44.516802 -364.705646)
		(stroke
			(width 0.08255)
			(type default)
		)
		(layer "In11.Cu")
	)
	(gr_line
		(start 44.577254 -341.052912)
		(end 44.494958 -341.135462)
		(stroke
			(width 0.08255)
			(type default)
		)
		(layer "In11.Cu")
	)
	(gr_line
		(start 44.577254 -341.052912)
		(end 44.577508 -341.052912)
		(stroke
			(width 0.08255)
			(type default)
		)
		(layer "In11.Cu")
	)
	(gr_line
		(start 44.673012 -360.94289)
		(end 44.397422 -361.354878)
		(stroke
			(width 0.08255)
			(type default)
		)
		(layer "In11.Cu")
	)
	(gr_line
		(start 44.776898 -360.922062)
		(end 44.673012 -360.94289)
		(stroke
			(width 0.08255)
			(type default)
		)
		(layer "In11.Cu")
	)
	(gr_line
		(start 44.776898 -342.148668)
		(end 45.067728 -342.439498)
		(stroke
			(width 0.08255)
			(type default)
		)
		(layer "In11.Cu")
	)
	(gr_line
		(start 44.815506 -364.163102)
		(end 44.501054 -364.546388)
		(stroke
			(width 0.08255)
			(type default)
		)
		(layer "In11.Cu")
	)
	(gr_line
		(start 44.975018 -364.147608)
		(end 44.815506 -364.163102)
		(stroke
			(width 0.08255)
			(type default)
		)
		(layer "In11.Cu")
	)
	(gr_line
		(start 44.996862 -367.396014)
		(end 45.028104 -367.55324)
		(stroke
			(width 0.08255)
			(type default)
		)
		(layer "In11.Cu")
	)
	(gr_line
		(start 45.013118 -361.078526)
		(end 44.6532 -361.61726)
		(stroke
			(width 0.08255)
			(type default)
		)
		(layer "In11.Cu")
	)
	(gr_line
		(start 45.022262 -360.351578)
		(end 45.053504 -360.50855)
		(stroke
			(width 0.08255)
			(type default)
		)
		(layer "In11.Cu")
	)
	(gr_line
		(start 45.067728 -345.465146)
		(end 44.776898 -345.755976)
		(stroke
			(width 0.08255)
			(type default)
		)
		(layer "In11.Cu")
	)
	(gr_line
		(start 45.272452 -366.984026)
		(end 44.996862 -367.396014)
		(stroke
			(width 0.08255)
			(type default)
		)
		(layer "In11.Cu")
	)
	(gr_line
		(start 45.274738 -363.603794)
		(end 45.290486 -363.763052)
		(stroke
			(width 0.08255)
			(type default)
		)
		(layer "In11.Cu")
	)
	(gr_line
		(start 45.297598 -359.93959)
		(end 45.022262 -360.351578)
		(stroke
			(width 0.08255)
			(type default)
		)
		(layer "In11.Cu")
	)
	(gr_line
		(start 45.42917 -366.952784)
		(end 45.272452 -366.984026)
		(stroke
			(width 0.08255)
			(type default)
		)
		(layer "In11.Cu")
	)
	(gr_line
		(start 45.454316 -359.908348)
		(end 45.297598 -359.93959)
		(stroke
			(width 0.08255)
			(type default)
		)
		(layer "In11.Cu")
	)
	(gr_line
		(start 45.58919 -363.220508)
		(end 45.274738 -363.603794)
		(stroke
			(width 0.08255)
			(type default)
		)
		(layer "In11.Cu")
	)
	(gr_line
		(start 45.674534 -366.3823)
		(end 45.705776 -366.539018)
		(stroke
			(width 0.08255)
			(type default)
		)
		(layer "In11.Cu")
	)
	(gr_line
		(start 45.690536 -360.064812)
		(end 45.2882 -360.666792)
		(stroke
			(width 0.08255)
			(type default)
		)
		(layer "In11.Cu")
	)
	(gr_line
		(start 45.748448 -363.205014)
		(end 45.58919 -363.220508)
		(stroke
			(width 0.08255)
			(type default)
		)
		(layer "In11.Cu")
	)
	(gr_line
		(start 45.94987 -365.970312)
		(end 45.674534 -366.3823)
		(stroke
			(width 0.08255)
			(type default)
		)
		(layer "In11.Cu")
	)
	(gr_line
		(start 46.106842 -365.938816)
		(end 45.94987 -365.970312)
		(stroke
			(width 0.08255)
			(type default)
		)
		(layer "In11.Cu")
	)
	(gr_line
		(start 46.351952 -365.368332)
		(end 46.383194 -365.525304)
		(stroke
			(width 0.08255)
			(type default)
		)
		(layer "In11.Cu")
	)
	(gr_line
		(start 46.627288 -364.956344)
		(end 46.351952 -365.368332)
		(stroke
			(width 0.08255)
			(type default)
		)
		(layer "In11.Cu")
	)
	(gr_line
		(start 46.69028 -361.939332)
		(end 46.70044 -362.044996)
		(stroke
			(width 0.08255)
			(type default)
		)
		(layer "In11.Cu")
	)
	(gr_line
		(start 46.78426 -364.924848)
		(end 46.627288 -364.956344)
		(stroke
			(width 0.08255)
			(type default)
		)
		(layer "In11.Cu")
	)
	(gr_line
		(start 47.004732 -361.556046)
		(end 46.69028 -361.939332)
		(stroke
			(width 0.08255)
			(type default)
		)
		(layer "In11.Cu")
	)
	(gr_line
		(start 47.02937 -364.354364)
		(end 47.060612 -364.511336)
		(stroke
			(width 0.08255)
			(type default)
		)
		(layer "In11.Cu")
	)
	(gr_line
		(start 47.110396 -361.545886)
		(end 47.004732 -361.556046)
		(stroke
			(width 0.08255)
			(type default)
		)
		(layer "In11.Cu")
	)
	(gr_line
		(start 47.304706 -363.942376)
		(end 47.02937 -364.354364)
		(stroke
			(width 0.08255)
			(type default)
		)
		(layer "In11.Cu")
	)
	(gr_line
		(start 47.313088 -351.611438)
		(end 47.603918 -351.902268)
		(stroke
			(width 0.08255)
			(type default)
		)
		(layer "In11.Cu")
	)
	(gr_line
		(start 47.41545 -361.055666)
		(end 47.425864 -361.161076)
		(stroke
			(width 0.08255)
			(type default)
		)
		(layer "In11.Cu")
	)
	(gr_line
		(start 47.461678 -363.91088)
		(end 47.304706 -363.942376)
		(stroke
			(width 0.08255)
			(type default)
		)
		(layer "In11.Cu")
	)
	(gr_line
		(start 47.58309 -409.795218)
		(end 47.59071 -409.795218)
		(stroke
			(width 0.08255)
			(type default)
		)
		(layer "In11.Cu")
	)
	(gr_line
		(start 47.58436 -410.078428)
		(end 47.71009 -410.204158)
		(stroke
			(width 0.08255)
			(type default)
		)
		(layer "In11.Cu")
	)
	(gr_line
		(start 47.59071 -409.795218)
		(end 47.71009 -409.675838)
		(stroke
			(width 0.08255)
			(type default)
		)
		(layer "In11.Cu")
	)
	(gr_line
		(start 47.603918 -348.29496)
		(end 47.313088 -348.58579)
		(stroke
			(width 0.08255)
			(type default)
		)
		(layer "In11.Cu")
	)
	(gr_line
		(start 47.71009 -410.204158)
		(end 47.71009 -410.589984)
		(stroke
			(width 0.08255)
			(type default)
		)
		(layer "In11.Cu")
	)
	(gr_line
		(start 47.71009 -409.675838)
		(end 47.71009 -409.290012)
		(stroke
			(width 0.08255)
			(type default)
		)
		(layer "In11.Cu")
	)
	(gr_line
		(start 47.71009 -405.775922)
		(end 47.82947 -405.895302)
		(stroke
			(width 0.08255)
			(type default)
		)
		(layer "In11.Cu")
	)
	(gr_line
		(start 47.71009 -405.390096)
		(end 47.71009 -405.775922)
		(stroke
			(width 0.08255)
			(type default)
		)
		(layer "In11.Cu")
	)
	(gr_line
		(start 47.729902 -360.67238)
		(end 47.41545 -361.055666)
		(stroke
			(width 0.08255)
			(type default)
		)
		(layer "In11.Cu")
	)
	(gr_line
		(start 47.816008 -394.774928)
		(end 47.66818 -394.713714)
		(stroke
			(width 0.08255)
			(type default)
		)
		(layer "In11.Cu")
	)
	(gr_line
		(start 47.82947 -405.895302)
		(end 47.83709 -405.895302)
		(stroke
			(width 0.08255)
			(type default)
		)
		(layer "In11.Cu")
	)
	(gr_line
		(start 47.835566 -360.66222)
		(end 47.729902 -360.67238)
		(stroke
			(width 0.08255)
			(type default)
		)
		(layer "In11.Cu")
	)
	(gr_line
		(start 47.885858 -348.29496)
		(end 48.176688 -348.58579)
		(stroke
			(width 0.08255)
			(type default)
		)
		(layer "In11.Cu")
	)
	(gr_line
		(start 48.176688 -351.611438)
		(end 47.885858 -351.902268)
		(stroke
			(width 0.08255)
			(type default)
		)
		(layer "In11.Cu")
	)
	(gr_line
		(start 48.227234 -394.174726)
		(end 47.558452 -394.452602)
		(stroke
			(width 0.08255)
			(type default)
		)
		(layer "In11.Cu")
	)
	(gr_line
		(start 48.273716 -394.584682)
		(end 47.816008 -394.774928)
		(stroke
			(width 0.08255)
			(type default)
		)
		(layer "In11.Cu")
	)
	(gr_line
		(start 48.334676 -394.4366)
		(end 48.273716 -394.584682)
		(stroke
			(width 0.08255)
			(type default)
		)
		(layer "In11.Cu")
	)
	(gr_line
		(start 48.648874 -361.930442)
		(end 48.680116 -362.087414)
		(stroke
			(width 0.08255)
			(type default)
		)
		(layer "In11.Cu")
	)
	(gr_line
		(start 48.92421 -361.518454)
		(end 48.648874 -361.930442)
		(stroke
			(width 0.08255)
			(type default)
		)
		(layer "In11.Cu")
	)
	(gr_line
		(start 48.94199 -394.306806)
		(end 48.794162 -394.245592)
		(stroke
			(width 0.08255)
			(type default)
		)
		(layer "In11.Cu")
	)
	(gr_line
		(start 49.044098 -356.45725)
		(end 49.157128 -356.57028)
		(stroke
			(width 0.08255)
			(type default)
		)
		(layer "In11.Cu")
	)
	(gr_line
		(start 49.044098 -355.96195)
		(end 49.044098 -356.45725)
		(stroke
			(width 0.08255)
			(type default)
		)
		(layer "In11.Cu")
	)
	(gr_line
		(start 49.081182 -361.487212)
		(end 48.92421 -361.518454)
		(stroke
			(width 0.08255)
			(type default)
		)
		(layer "In11.Cu")
	)
	(gr_line
		(start 49.157128 -355.84892)
		(end 49.044098 -355.96195)
		(stroke
			(width 0.08255)
			(type default)
		)
		(layer "In11.Cu")
	)
	(gr_line
		(start 49.326292 -360.916474)
		(end 49.357534 -361.0737)
		(stroke
			(width 0.08255)
			(type default)
		)
		(layer "In11.Cu")
	)
	(gr_line
		(start 49.353216 -393.706604)
		(end 48.684434 -393.98448)
		(stroke
			(width 0.08255)
			(type default)
		)
		(layer "In11.Cu")
	)
	(gr_line
		(start 49.399698 -394.11656)
		(end 48.94199 -394.306806)
		(stroke
			(width 0.08255)
			(type default)
		)
		(layer "In11.Cu")
	)
	(gr_line
		(start 49.460912 -393.968478)
		(end 49.399698 -394.11656)
		(stroke
			(width 0.08255)
			(type default)
		)
		(layer "In11.Cu")
	)
	(gr_line
		(start 49.601628 -360.504486)
		(end 49.326292 -360.916474)
		(stroke
			(width 0.08255)
			(type default)
		)
		(layer "In11.Cu")
	)
	(gr_line
		(start 49.7586 -360.473244)
		(end 49.601628 -360.504486)
		(stroke
			(width 0.08255)
			(type default)
		)
		(layer "In11.Cu")
	)
	(gr_line
		(start 50.003964 -359.902506)
		(end 50.035206 -360.059478)
		(stroke
			(width 0.08255)
			(type default)
		)
		(layer "In11.Cu")
	)
	(gr_line
		(start 50.035206 -360.061256)
		(end 50.03546 -360.061256)
		(stroke
			(width 0.08255)
			(type default)
		)
		(layer "In11.Cu")
	)
	(gr_line
		(start 50.067972 -393.838684)
		(end 49.91989 -393.77747)
		(stroke
			(width 0.08255)
			(type default)
		)
		(layer "In11.Cu")
	)
	(gr_line
		(start 50.2793 -359.490518)
		(end 50.003964 -359.902506)
		(stroke
			(width 0.08255)
			(type default)
		)
		(layer "In11.Cu")
	)
	(gr_line
		(start 50.422048 -357.75773)
		(end 50.712878 -358.04856)
		(stroke
			(width 0.08255)
			(type default)
		)
		(layer "In11.Cu")
	)
	(gr_line
		(start 50.422048 -345.465146)
		(end 50.712878 -345.755976)
		(stroke
			(width 0.08255)
			(type default)
		)
		(layer "In11.Cu")
	)
	(gr_line
		(start 50.436018 -359.459276)
		(end 50.2793 -359.490518)
		(stroke
			(width 0.08255)
			(type default)
		)
		(layer "In11.Cu")
	)
	(gr_line
		(start 50.479198 -393.238482)
		(end 49.810416 -393.516358)
		(stroke
			(width 0.08255)
			(type default)
		)
		(layer "In11.Cu")
	)
	(gr_line
		(start 50.52568 -393.648438)
		(end 50.067972 -393.838684)
		(stroke
			(width 0.08255)
			(type default)
		)
		(layer "In11.Cu")
	)
	(gr_line
		(start 50.586894 -393.500356)
		(end 50.52568 -393.648438)
		(stroke
			(width 0.08255)
			(type default)
		)
		(layer "In11.Cu")
	)
	(gr_line
		(start 50.712878 -354.441252)
		(end 50.422048 -354.732082)
		(stroke
			(width 0.08255)
			(type default)
		)
		(layer "In11.Cu")
	)
	(gr_line
		(start 50.712878 -342.148668)
		(end 50.422048 -342.439498)
		(stroke
			(width 0.08255)
			(type default)
		)
		(layer "In11.Cu")
	)
	(gr_line
		(start 54.4068 -392.892026)
		(end 54.405784 -392.892026)
		(stroke
			(width 0.08255)
			(type default)
		)
		(layer "In11.Cu")
	)
	(gr_line
		(start 54.407308 -392.892026)
		(end 54.4068 -392.892026)
		(stroke
			(width 0.08255)
			(type default)
		)
		(layer "In11.Cu")
	)
	(gr_line
		(start 55.738522 -392.998706)
		(end 55.62473 -392.886184)
		(stroke
			(width 0.08255)
			(type default)
		)
		(layer "In11.Cu")
	)
	(gr_line
		(start 56.234076 -392.995912)
		(end 55.738522 -392.998706)
		(stroke
			(width 0.08255)
			(type default)
		)
		(layer "In11.Cu")
	)
	(gr_line
		(start 56.346344 -392.59891)
		(end 55.62219 -392.602974)
		(stroke
			(width 0.08255)
			(type default)
		)
		(layer "In11.Cu")
	)
	(gr_line
		(start 56.346598 -392.88212)
		(end 56.234076 -392.995912)
		(stroke
			(width 0.08255)
			(type default)
		)
		(layer "In11.Cu")
	)
	(gr_line
		(start 56.347868 -392.881104)
		(end 56.347868 -392.88085)
		(stroke
			(width 0.08255)
			(type default)
		)
		(layer "In11.Cu")
	)
	(gr_line
		(start 56.842914 -392.878056)
		(end 56.842914 -392.87831)
		(stroke
			(width 0.08255)
			(type default)
		)
		(layer "In11.Cu")
	)
	(gr_line
		(start 56.96077 -392.994642)
		(end 56.844184 -392.879326)
		(stroke
			(width 0.08255)
			(type default)
		)
		(layer "In11.Cu")
	)
	(gr_line
		(start 57.456324 -392.991594)
		(end 56.96077 -392.994642)
		(stroke
			(width 0.08255)
			(type default)
		)
		(layer "In11.Cu")
	)
	(gr_line
		(start 57.57037 -392.591798)
		(end 56.84139 -392.596116)
		(stroke
			(width 0.08255)
			(type default)
		)
		(layer "In11.Cu")
	)
	(gr_line
		(start 57.571386 -392.875008)
		(end 57.456324 -392.991594)
		(stroke
			(width 0.08255)
			(type default)
		)
		(layer "In11.Cu")
	)
	(gr_line
		(start 58.083958 -271.427448)
		(end 58.083958 -271.399)
		(stroke
			(width 0.05715)
			(type default)
		)
		(layer "In11.Cu")
	)
	(gr_line
		(start 58.129678 -271.473168)
		(end 58.083958 -271.427448)
		(stroke
			(width 0.05715)
			(type default)
		)
		(layer "In11.Cu")
	)
	(gr_line
		(start 58.17997 -392.98753)
		(end 58.063384 -392.872214)
		(stroke
			(width 0.08255)
			(type default)
		)
		(layer "In11.Cu")
	)
	(gr_line
		(start 58.675524 -392.984482)
		(end 58.17997 -392.98753)
		(stroke
			(width 0.08255)
			(type default)
		)
		(layer "In11.Cu")
	)
	(gr_line
		(start 58.699908 -280.699718)
		(end 58.699908 -280.434288)
		(stroke
			(width 0.05715)
			(type default)
		)
		(layer "In11.Cu")
	)
	(gr_line
		(start 58.699908 -280.434288)
		(end 58.585608 -280.319988)
		(stroke
			(width 0.05715)
			(type default)
		)
		(layer "In11.Cu")
	)
	(gr_line
		(start 58.78957 -392.58494)
		(end 58.06059 -392.589004)
		(stroke
			(width 0.08255)
			(type default)
		)
		(layer "In11.Cu")
	)
	(gr_line
		(start 58.790586 -392.86815)
		(end 58.675524 -392.984482)
		(stroke
			(width 0.08255)
			(type default)
		)
		(layer "In11.Cu")
	)
	(gr_line
		(start 59.39917 -392.980418)
		(end 59.282584 -392.865102)
		(stroke
			(width 0.08255)
			(type default)
		)
		(layer "In11.Cu")
	)
	(gr_line
		(start 59.894724 -392.977624)
		(end 59.39917 -392.980418)
		(stroke
			(width 0.08255)
			(type default)
		)
		(layer "In11.Cu")
	)
	(gr_line
		(start 60.009024 -392.577828)
		(end 59.27979 -392.581892)
		(stroke
			(width 0.08255)
			(type default)
		)
		(layer "In11.Cu")
	)
	(gr_line
		(start 60.009532 -392.861038)
		(end 59.894724 -392.977624)
		(stroke
			(width 0.08255)
			(type default)
		)
		(layer "In11.Cu")
	)
	(gr_line
		(start 60.61837 -392.973306)
		(end 60.502038 -392.858244)
		(stroke
			(width 0.08255)
			(type default)
		)
		(layer "In11.Cu")
	)
	(gr_line
		(start 61.113924 -392.970512)
		(end 60.61837 -392.973306)
		(stroke
			(width 0.08255)
			(type default)
		)
		(layer "In11.Cu")
	)
	(gr_line
		(start 61.228224 -392.570716)
		(end 60.499498 -392.575034)
		(stroke
			(width 0.08255)
			(type default)
		)
		(layer "In11.Cu")
	)
	(gr_line
		(start 61.228732 -392.853926)
		(end 61.113924 -392.970512)
		(stroke
			(width 0.08255)
			(type default)
		)
		(layer "In11.Cu")
	)
	(gr_line
		(start 64.41313 -392.837162)
		(end 64.41186 -392.835638)
		(stroke
			(width 0.08255)
			(type default)
		)
		(layer "In11.Cu")
	)
	(gr_line
		(start 64.41313 -392.836908)
		(end 64.41313 -392.837162)
		(stroke
			(width 0.08255)
			(type default)
		)
		(layer "In11.Cu")
	)
	(gr_line
		(start 64.413892 -392.552428)
		(end 64.409574 -392.552428)
		(stroke
			(width 0.08255)
			(type default)
		)
		(layer "In11.Cu")
	)
	(gr_line
		(start 64.415416 -392.834368)
		(end 64.41313 -392.836908)
		(stroke
			(width 0.08255)
			(type default)
		)
		(layer "In11.Cu")
	)
	(gr_line
		(start 69.831204 -392.919712)
		(end 69.71538 -392.805158)
		(stroke
			(width 0.08255)
			(type default)
		)
		(layer "In11.Cu")
	)
	(gr_line
		(start 70.326758 -392.916918)
		(end 69.831204 -392.919712)
		(stroke
			(width 0.08255)
			(type default)
		)
		(layer "In11.Cu")
	)
	(gr_line
		(start 70.44055 -392.517884)
		(end 69.71284 -392.521948)
		(stroke
			(width 0.08255)
			(type default)
		)
		(layer "In11.Cu")
	)
	(gr_line
		(start 70.441058 -392.801094)
		(end 70.326758 -392.916918)
		(stroke
			(width 0.08255)
			(type default)
		)
		(layer "In11.Cu")
	)
	(gr_line
		(start 71.050658 -392.9126)
		(end 70.935088 -392.7983)
		(stroke
			(width 0.08255)
			(type default)
		)
		(layer "In11.Cu")
	)
	(gr_line
		(start 71.546212 -392.909552)
		(end 71.050658 -392.9126)
		(stroke
			(width 0.08255)
			(type default)
		)
		(layer "In11.Cu")
	)
	(gr_line
		(start 71.65975 -392.511026)
		(end 70.932548 -392.51509)
		(stroke
			(width 0.08255)
			(type default)
		)
		(layer "In11.Cu")
	)
	(gr_line
		(start 71.660258 -392.794236)
		(end 71.546212 -392.909552)
		(stroke
			(width 0.08255)
			(type default)
		)
		(layer "In11.Cu")
	)
	(gr_line
		(start 72.269858 -392.905488)
		(end 72.154288 -392.791188)
		(stroke
			(width 0.08255)
			(type default)
		)
		(layer "In11.Cu")
	)
	(gr_line
		(start 72.765412 -392.90244)
		(end 72.269858 -392.905488)
		(stroke
			(width 0.08255)
			(type default)
		)
		(layer "In11.Cu")
	)
	(gr_line
		(start 72.878696 -392.503914)
		(end 72.151748 -392.507978)
		(stroke
			(width 0.08255)
			(type default)
		)
		(layer "In11.Cu")
	)
	(gr_line
		(start 72.879204 -392.787124)
		(end 72.765412 -392.90244)
		(stroke
			(width 0.08255)
			(type default)
		)
		(layer "In11.Cu")
	)
	(gr_line
		(start 73.489058 -392.898376)
		(end 73.373742 -392.78433)
		(stroke
			(width 0.08255)
			(type default)
		)
		(layer "In11.Cu")
	)
	(gr_line
		(start 73.984612 -392.895328)
		(end 73.489058 -392.898376)
		(stroke
			(width 0.08255)
			(type default)
		)
		(layer "In11.Cu")
	)
	(gr_line
		(start 74.097896 -392.497056)
		(end 73.371202 -392.50112)
		(stroke
			(width 0.08255)
			(type default)
		)
		(layer "In11.Cu")
	)
	(gr_line
		(start 74.098404 -392.780266)
		(end 73.984612 -392.895328)
		(stroke
			(width 0.08255)
			(type default)
		)
		(layer "In11.Cu")
	)
	(gr_line
		(start 74.708258 -392.891264)
		(end 74.592942 -392.777218)
		(stroke
			(width 0.08255)
			(type default)
		)
		(layer "In11.Cu")
	)
	(gr_line
		(start 74.84999 -308.249828)
		(end 75.14082 -308.249828)
		(stroke
			(width 0.05715)
			(type default)
		)
		(layer "In11.Cu")
	)
	(gr_line
		(start 74.84999 -306.349908)
		(end 75.14082 -306.349908)
		(stroke
			(width 0.05715)
			(type default)
		)
		(layer "In11.Cu")
	)
	(gr_line
		(start 74.84999 -304.449734)
		(end 75.14082 -304.449734)
		(stroke
			(width 0.05715)
			(type default)
		)
		(layer "In11.Cu")
	)
	(gr_line
		(start 75.14082 -308.249828)
		(end 75.22972 -308.338728)
		(stroke
			(width 0.05715)
			(type default)
		)
		(layer "In11.Cu")
	)
	(gr_line
		(start 75.14082 -306.349908)
		(end 75.22972 -306.438808)
		(stroke
			(width 0.05715)
			(type default)
		)
		(layer "In11.Cu")
	)
	(gr_line
		(start 75.14082 -304.449734)
		(end 75.22972 -304.538634)
		(stroke
			(width 0.05715)
			(type default)
		)
		(layer "In11.Cu")
	)
	(gr_line
		(start 75.203812 -392.888216)
		(end 74.708258 -392.891264)
		(stroke
			(width 0.08255)
			(type default)
		)
		(layer "In11.Cu")
	)
	(gr_line
		(start 75.315826 -392.489944)
		(end 74.590402 -392.494008)
		(stroke
			(width 0.08255)
			(type default)
		)
		(layer "In11.Cu")
	)
	(gr_line
		(start 75.31735 -392.773154)
		(end 75.203812 -392.888216)
		(stroke
			(width 0.08255)
			(type default)
		)
		(layer "In11.Cu")
	)
	(gr_line
		(start 75.50912 -308.249828)
		(end 75.42022 -308.338728)
		(stroke
			(width 0.05715)
			(type default)
		)
		(layer "In11.Cu")
	)
	(gr_line
		(start 75.50912 -306.349908)
		(end 75.42022 -306.438808)
		(stroke
			(width 0.05715)
			(type default)
		)
		(layer "In11.Cu")
	)
	(gr_line
		(start 75.79995 -308.249828)
		(end 75.50912 -308.249828)
		(stroke
			(width 0.05715)
			(type default)
		)
		(layer "In11.Cu")
	)
	(gr_line
		(start 75.79995 -306.349908)
		(end 75.50912 -306.349908)
		(stroke
			(width 0.05715)
			(type default)
		)
		(layer "In11.Cu")
	)
	(gr_line
		(start 76.74991 -309.199788)
		(end 77.04074 -309.199788)
		(stroke
			(width 0.05715)
			(type default)
		)
		(layer "In11.Cu")
	)
	(gr_line
		(start 76.74991 -307.299868)
		(end 77.04074 -307.299868)
		(stroke
			(width 0.05715)
			(type default)
		)
		(layer "In11.Cu")
	)
	(gr_line
		(start 76.74991 -305.399948)
		(end 77.04074 -305.399948)
		(stroke
			(width 0.05715)
			(type default)
		)
		(layer "In11.Cu")
	)
	(gr_line
		(start 77.04074 -309.199788)
		(end 77.12964 -309.288688)
		(stroke
			(width 0.05715)
			(type default)
		)
		(layer "In11.Cu")
	)
	(gr_line
		(start 77.04074 -307.299868)
		(end 77.12964 -307.388768)
		(stroke
			(width 0.05715)
			(type default)
		)
		(layer "In11.Cu")
	)
	(gr_line
		(start 77.04074 -305.399948)
		(end 77.12964 -305.488848)
		(stroke
			(width 0.05715)
			(type default)
		)
		(layer "In11.Cu")
	)
	(gr_line
		(start 81.499964 -312.049922)
		(end 81.790794 -312.049922)
		(stroke
			(width 0.05715)
			(type default)
		)
		(layer "In11.Cu")
	)
	(gr_line
		(start 81.790794 -312.049922)
		(end 81.879694 -312.138822)
		(stroke
			(width 0.05715)
			(type default)
		)
		(layer "In11.Cu")
	)
	(gr_line
		(start 83.492086 -313.88431)
		(end 83.512152 -313.904376)
		(stroke
			(width 0.05715)
			(type default)
		)
		(layer "In11.Cu")
	)
	(gr_line
		(start 83.492086 -313.820048)
		(end 83.492086 -313.88431)
		(stroke
			(width 0.05715)
			(type default)
		)
		(layer "In11.Cu")
	)
	(gr_line
		(start 83.54568 -305.97602)
		(end 83.5914 -306.02174)
		(stroke
			(width 0.05715)
			(type default)
		)
		(layer "In11.Cu")
	)
	(gr_line
		(start 83.568286 -309.78602)
		(end 83.614006 -309.83174)
		(stroke
			(width 0.05715)
			(type default)
		)
		(layer "In11.Cu")
	)
	(gr_line
		(start 83.57108 -307.88102)
		(end 83.6168 -307.92674)
		(stroke
			(width 0.05715)
			(type default)
		)
		(layer "In11.Cu")
	)
	(gr_line
		(start 83.57108 -306.91328)
		(end 83.6168 -306.959)
		(stroke
			(width 0.05715)
			(type default)
		)
		(layer "In11.Cu")
	)
	(gr_line
		(start 83.57108 -306.72278)
		(end 83.6168 -306.67706)
		(stroke
			(width 0.05715)
			(type default)
		)
		(layer "In11.Cu")
	)
	(gr_line
		(start 83.5914 -306.02174)
		(end 83.619848 -306.02174)
		(stroke
			(width 0.05715)
			(type default)
		)
		(layer "In11.Cu")
	)
	(gr_line
		(start 83.59648 -308.820058)
		(end 83.6422 -308.865778)
		(stroke
			(width 0.05715)
			(type default)
		)
		(layer "In11.Cu")
	)
	(gr_line
		(start 83.59648 -308.629558)
		(end 83.6422 -308.583838)
		(stroke
			(width 0.05715)
			(type default)
		)
		(layer "In11.Cu")
	)
	(gr_line
		(start 83.59648 -305.019964)
		(end 83.6422 -305.065684)
		(stroke
			(width 0.05715)
			(type default)
		)
		(layer "In11.Cu")
	)
	(gr_line
		(start 83.614006 -309.83174)
		(end 83.642454 -309.83174)
		(stroke
			(width 0.05715)
			(type default)
		)
		(layer "In11.Cu")
	)
	(gr_line
		(start 83.6168 -307.92674)
		(end 83.645248 -307.92674)
		(stroke
			(width 0.05715)
			(type default)
		)
		(layer "In11.Cu")
	)
	(gr_line
		(start 83.6168 -306.959)
		(end 83.645248 -306.959)
		(stroke
			(width 0.05715)
			(type default)
		)
		(layer "In11.Cu")
	)
	(gr_line
		(start 83.6168 -306.67706)
		(end 83.645248 -306.67706)
		(stroke
			(width 0.05715)
			(type default)
		)
		(layer "In11.Cu")
	)
	(gr_line
		(start 83.6422 -308.865778)
		(end 83.670648 -308.865778)
		(stroke
			(width 0.05715)
			(type default)
		)
		(layer "In11.Cu")
	)
	(gr_line
		(start 83.6422 -308.583838)
		(end 83.670648 -308.583838)
		(stroke
			(width 0.05715)
			(type default)
		)
		(layer "In11.Cu")
	)
	(gr_line
		(start 83.6422 -305.065684)
		(end 83.670648 -305.065684)
		(stroke
			(width 0.05715)
			(type default)
		)
		(layer "In11.Cu")
	)
	(gr_line
		(start 86.631018 -393.547346)
		(end 87.355172 -393.543028)
		(stroke
			(width 0.08255)
			(type default)
		)
		(layer "In11.Cu")
	)
	(gr_line
		(start 90.636598 -394.503148)
		(end 90.639392 -394.506196)
		(stroke
			(width 0.08255)
			(type default)
		)
		(layer "In11.Cu")
	)
	(gr_line
		(start 90.639392 -394.506196)
		(end 90.644472 -394.506196)
		(stroke
			(width 0.08255)
			(type default)
		)
		(layer "In11.Cu")
	)
	(gr_line
		(start 90.644472 -394.506196)
		(end 90.647012 -394.506196)
		(stroke
			(width 0.08255)
			(type default)
		)
		(layer "In11.Cu")
	)
	(gr_line
		(start 90.647012 -394.506196)
		(end 90.65006 -394.506196)
		(stroke
			(width 0.08255)
			(type default)
		)
		(layer "In11.Cu")
	)
	(gr_line
		(start 90.65006 -394.506196)
		(end 90.731086 -394.587222)
		(stroke
			(width 0.08255)
			(type default)
		)
		(layer "In11.Cu")
	)
	(gr_line
		(start 90.731086 -394.587222)
		(end 90.731086 -394.704062)
		(stroke
			(width 0.08255)
			(type default)
		)
		(layer "In11.Cu")
	)
	(gr_line
		(start 91.583002 -405.895302)
		(end 91.590622 -405.895302)
		(stroke
			(width 0.08255)
			(type default)
		)
		(layer "In11.Cu")
	)
	(gr_line
		(start 91.590622 -405.895302)
		(end 91.710002 -405.775922)
		(stroke
			(width 0.08255)
			(type default)
		)
		(layer "In11.Cu")
	)
	(gr_line
		(start 91.710002 -410.589984)
		(end 91.710002 -410.204158)
		(stroke
			(width 0.08255)
			(type default)
		)
		(layer "In11.Cu")
	)
	(gr_line
		(start 91.710002 -410.204158)
		(end 91.835732 -410.078428)
		(stroke
			(width 0.08255)
			(type default)
		)
		(layer "In11.Cu")
	)
	(gr_line
		(start 91.710002 -409.675838)
		(end 91.829382 -409.795218)
		(stroke
			(width 0.08255)
			(type default)
		)
		(layer "In11.Cu")
	)
	(gr_line
		(start 91.710002 -409.290012)
		(end 91.710002 -409.675838)
		(stroke
			(width 0.08255)
			(type default)
		)
		(layer "In11.Cu")
	)
	(gr_line
		(start 91.710002 -405.775922)
		(end 91.710002 -405.390096)
		(stroke
			(width 0.08255)
			(type default)
		)
		(layer "In11.Cu")
	)
	(gr_line
		(start 91.829382 -409.795218)
		(end 91.837002 -409.795218)
		(stroke
			(width 0.08255)
			(type default)
		)
		(layer "In11.Cu")
	)
	(gr_line
		(start 92.6719 -406.26665)
		(end 92.6719 -405.77135)
		(stroke
			(width 0.08255)
			(type default)
		)
		(layer "In11.Cu")
	)
	(gr_line
		(start 92.6719 -405.77135)
		(end 92.78493 -405.65832)
		(stroke
			(width 0.08255)
			(type default)
		)
		(layer "In11.Cu")
	)
	(gr_line
		(start 92.78493 -406.37968)
		(end 92.6719 -406.26665)
		(stroke
			(width 0.08255)
			(type default)
		)
		(layer "In11.Cu")
	)
	(gr_line
		(start 93.06814 -406.38095)
		(end 93.06814 -405.65705)
		(stroke
			(width 0.08255)
			(type default)
		)
		(layer "In11.Cu")
	)
	(gr_line
		(start 94.009464 -314.37326)
		(end 94.00921 -314.37326)
		(stroke
			(width 0.08255)
			(type default)
		)
		(layer "In11.Cu")
	)
	(gr_line
		(start 94.11716 -314.112656)
		(end 94.16923 -314.134246)
		(stroke
			(width 0.08255)
			(type default)
		)
		(layer "In11.Cu")
	)
	(gr_line
		(start 94.16923 -314.134246)
		(end 94.208854 -314.17387)
		(stroke
			(width 0.08255)
			(type default)
		)
		(layer "In11.Cu")
	)
	(gr_line
		(start 97.595944 -28.823412)
		(end 97.305114 -29.114242)
		(stroke
			(width 0.08255)
			(type default)
		)
		(layer "In11.Cu")
	)
	(gr_line
		(start 97.766124 -28.823412)
		(end 97.595944 -28.823412)
		(stroke
			(width 0.08255)
			(type default)
		)
		(layer "In11.Cu")
	)
	(gr_line
		(start 104.998774 -34.299144)
		(end 105.033572 -34.179764)
		(stroke
			(width 0.08255)
			(type default)
		)
		(layer "In11.Cu")
	)
	(gr_line
		(start 105.236518 -34.733992)
		(end 104.998774 -34.299144)
		(stroke
			(width 0.08255)
			(type default)
		)
		(layer "In11.Cu")
	)
	(gr_line
		(start 105.355644 -34.76879)
		(end 105.236518 -34.733992)
		(stroke
			(width 0.08255)
			(type default)
		)
		(layer "In11.Cu")
	)
	(gr_line
		(start 105.559098 -35.324542)
		(end 105.59415 -35.205416)
		(stroke
			(width 0.08255)
			(type default)
		)
		(layer "In11.Cu")
	)
	(gr_line
		(start 105.797096 -35.75939)
		(end 105.559098 -35.324542)
		(stroke
			(width 0.08255)
			(type default)
		)
		(layer "In11.Cu")
	)
	(gr_line
		(start 105.915968 -35.794188)
		(end 105.797096 -35.75939)
		(stroke
			(width 0.08255)
			(type default)
		)
		(layer "In11.Cu")
	)
	(gr_line
		(start 174.184056 -271.427448)
		(end 174.184056 -271.399)
		(stroke
			(width 0.05715)
			(type default)
		)
		(layer "In11.Cu")
	)
	(gr_line
		(start 174.229776 -271.473168)
		(end 174.184056 -271.427448)
		(stroke
			(width 0.05715)
			(type default)
		)
		(layer "In11.Cu")
	)
	(gr_line
		(start 174.800006 -280.699718)
		(end 174.800006 -280.434288)
		(stroke
			(width 0.05715)
			(type default)
		)
		(layer "In11.Cu")
	)
	(gr_line
		(start 174.800006 -280.434288)
		(end 174.685706 -280.319988)
		(stroke
			(width 0.05715)
			(type default)
		)
		(layer "In11.Cu")
	)
	(gr_line
		(start 213.696042 -28.823412)
		(end 213.405212 -29.114242)
		(stroke
			(width 0.08255)
			(type default)
		)
		(layer "In11.Cu")
	)
	(gr_line
		(start 213.866222 -28.823412)
		(end 213.696042 -28.823412)
		(stroke
			(width 0.08255)
			(type default)
		)
		(layer "In11.Cu")
	)
	(gr_line
		(start 220.39961 -33.019492)
		(end 220.434408 -32.900366)
		(stroke
			(width 0.08255)
			(type default)
		)
		(layer "In11.Cu")
	)
	(gr_line
		(start 220.637354 -33.454594)
		(end 220.39961 -33.019492)
		(stroke
			(width 0.08255)
			(type default)
		)
		(layer "In11.Cu")
	)
	(gr_line
		(start 220.75648 -33.489392)
		(end 220.637354 -33.454594)
		(stroke
			(width 0.08255)
			(type default)
		)
		(layer "In11.Cu")
	)
	(gr_line
		(start 220.959934 -34.045144)
		(end 220.994986 -33.926018)
		(stroke
			(width 0.08255)
			(type default)
		)
		(layer "In11.Cu")
	)
	(gr_line
		(start 221.197932 -34.479992)
		(end 220.959934 -34.045144)
		(stroke
			(width 0.08255)
			(type default)
		)
		(layer "In11.Cu")
	)
	(gr_line
		(start 221.316804 -34.51479)
		(end 221.197932 -34.479992)
		(stroke
			(width 0.08255)
			(type default)
		)
		(layer "In11.Cu")
	)
	(gr_line
		(start 271.006062 -351.611438)
		(end 271.296892 -351.902268)
		(stroke
			(width 0.08255)
			(type default)
		)
		(layer "In11.Cu")
	)
	(gr_line
		(start 271.296892 -348.29496)
		(end 271.006062 -348.58579)
		(stroke
			(width 0.08255)
			(type default)
		)
		(layer "In11.Cu")
	)
	(gr_line
		(start 271.578832 -348.29496)
		(end 271.869662 -348.58579)
		(stroke
			(width 0.08255)
			(type default)
		)
		(layer "In11.Cu")
	)
	(gr_line
		(start 271.67332 -340.770972)
		(end 271.51965 -340.72576)
		(stroke
			(width 0.08255)
			(type default)
		)
		(layer "In11.Cu")
	)
	(gr_line
		(start 271.869662 -351.611438)
		(end 271.578832 -351.902268)
		(stroke
			(width 0.08255)
			(type default)
		)
		(layer "In11.Cu")
	)
	(gr_line
		(start 272.019268 -340.131146)
		(end 271.383252 -340.477602)
		(stroke
			(width 0.08255)
			(type default)
		)
		(layer "In11.Cu")
	)
	(gr_line
		(start 272.108422 -340.533736)
		(end 271.67332 -340.770972)
		(stroke
			(width 0.08255)
			(type default)
		)
		(layer "In11.Cu")
	)
	(gr_line
		(start 272.153634 -340.380574)
		(end 272.108422 -340.533736)
		(stroke
			(width 0.08255)
			(type default)
		)
		(layer "In11.Cu")
	)
	(gr_line
		(start 272.154142 -340.37905)
		(end 272.154142 -340.378796)
		(stroke
			(width 0.08255)
			(type default)
		)
		(layer "In11.Cu")
	)
	(gr_line
		(start 272.74393 -340.188042)
		(end 272.59026 -340.14283)
		(stroke
			(width 0.08255)
			(type default)
		)
		(layer "In11.Cu")
	)
	(gr_line
		(start 273.090132 -339.548216)
		(end 272.454116 -339.894418)
		(stroke
			(width 0.08255)
			(type default)
		)
		(layer "In11.Cu")
	)
	(gr_line
		(start 273.179286 -339.950806)
		(end 272.74393 -340.188042)
		(stroke
			(width 0.08255)
			(type default)
		)
		(layer "In11.Cu")
	)
	(gr_line
		(start 273.224498 -339.79739)
		(end 273.179286 -339.950806)
		(stroke
			(width 0.08255)
			(type default)
		)
		(layer "In11.Cu")
	)
	(gr_line
		(start 273.814794 -339.604858)
		(end 273.661378 -339.559646)
		(stroke
			(width 0.08255)
			(type default)
		)
		(layer "In11.Cu")
	)
	(gr_line
		(start 274.160996 -338.965032)
		(end 273.52498 -339.311234)
		(stroke
			(width 0.08255)
			(type default)
		)
		(layer "In11.Cu")
	)
	(gr_line
		(start 274.25015 -339.367622)
		(end 273.814794 -339.604858)
		(stroke
			(width 0.08255)
			(type default)
		)
		(layer "In11.Cu")
	)
	(gr_line
		(start 274.295362 -339.214206)
		(end 274.25015 -339.367622)
		(stroke
			(width 0.08255)
			(type default)
		)
		(layer "In11.Cu")
	)
	(gr_line
		(start 274.885658 -339.021674)
		(end 274.732242 -338.976462)
		(stroke
			(width 0.08255)
			(type default)
		)
		(layer "In11.Cu")
	)
	(gr_line
		(start 275.23186 -338.381848)
		(end 274.595844 -338.728304)
		(stroke
			(width 0.08255)
			(type default)
		)
		(layer "In11.Cu")
	)
	(gr_line
		(start 275.321014 -338.784438)
		(end 274.885658 -339.021674)
		(stroke
			(width 0.08255)
			(type default)
		)
		(layer "In11.Cu")
	)
	(gr_line
		(start 275.366226 -338.631276)
		(end 275.321014 -338.784438)
		(stroke
			(width 0.08255)
			(type default)
		)
		(layer "In11.Cu")
	)
	(gr_line
		(start 277.732744 -375.88444)
		(end 277.941786 -376.33402)
		(stroke
			(width 0.08255)
			(type default)
		)
		(layer "In11.Cu")
	)
	(gr_line
		(start 277.769574 -375.784364)
		(end 277.732744 -375.88444)
		(stroke
			(width 0.08255)
			(type default)
		)
		(layer "In11.Cu")
	)
	(gr_line
		(start 277.941786 -376.33402)
		(end 278.041862 -376.370342)
		(stroke
			(width 0.08255)
			(type default)
		)
		(layer "In11.Cu")
	)
	(gr_line
		(start 278.02586 -375.664222)
		(end 278.299164 -376.251978)
		(stroke
			(width 0.08255)
			(type default)
		)
		(layer "In11.Cu")
	)
	(gr_line
		(start 278.214582 -376.921014)
		(end 278.423624 -377.370594)
		(stroke
			(width 0.08255)
			(type default)
		)
		(layer "In11.Cu")
	)
	(gr_line
		(start 278.251158 -376.820938)
		(end 278.214582 -376.921014)
		(stroke
			(width 0.08255)
			(type default)
		)
		(layer "In11.Cu")
	)
	(gr_line
		(start 278.423624 -377.370594)
		(end 278.5237 -377.406916)
		(stroke
			(width 0.08255)
			(type default)
		)
		(layer "In11.Cu")
	)
	(gr_line
		(start 278.507698 -376.70105)
		(end 278.780748 -377.288298)
		(stroke
			(width 0.08255)
			(type default)
		)
		(layer "In11.Cu")
	)
	(gr_line
		(start 284.967426 -392.014964)
		(end 285.028386 -392.163046)
		(stroke
			(width 0.08255)
			(type default)
		)
		(layer "In11.Cu")
	)
	(gr_line
		(start 285.028386 -392.163046)
		(end 285.486094 -392.352784)
		(stroke
			(width 0.08255)
			(type default)
		)
		(layer "In11.Cu")
	)
	(gr_line
		(start 285.074614 -391.752836)
		(end 285.74365 -392.030458)
		(stroke
			(width 0.08255)
			(type default)
		)
		(layer "In11.Cu")
	)
	(gr_line
		(start 285.486094 -392.352784)
		(end 285.634176 -392.29157)
		(stroke
			(width 0.08255)
			(type default)
		)
		(layer "In11.Cu")
	)
	(gr_line
		(start 286.093408 -392.48207)
		(end 286.154622 -392.630406)
		(stroke
			(width 0.08255)
			(type default)
		)
		(layer "In11.Cu")
	)
	(gr_line
		(start 286.154622 -392.630406)
		(end 286.61233 -392.820144)
		(stroke
			(width 0.08255)
			(type default)
		)
		(layer "In11.Cu")
	)
	(gr_line
		(start 286.201104 -392.220196)
		(end 286.869886 -392.497564)
		(stroke
			(width 0.08255)
			(type default)
		)
		(layer "In11.Cu")
	)
	(gr_line
		(start 286.61233 -392.820144)
		(end 286.760412 -392.758676)
		(stroke
			(width 0.08255)
			(type default)
		)
		(layer "In11.Cu")
	)
	(gr_line
		(start 287.219644 -392.94943)
		(end 287.280858 -393.097512)
		(stroke
			(width 0.08255)
			(type default)
		)
		(layer "In11.Cu")
	)
	(gr_line
		(start 287.280858 -393.097512)
		(end 287.738566 -393.28725)
		(stroke
			(width 0.08255)
			(type default)
		)
		(layer "In11.Cu")
	)
	(gr_line
		(start 287.32734 -392.687302)
		(end 287.995868 -392.96467)
		(stroke
			(width 0.08255)
			(type default)
		)
		(layer "In11.Cu")
	)
	(gr_line
		(start 287.738566 -393.28725)
		(end 287.886394 -393.225782)
		(stroke
			(width 0.08255)
			(type default)
		)
		(layer "In11.Cu")
	)
	(gr_line
		(start 289.577018 -361.92206)
		(end 289.776916 -362.37545)
		(stroke
			(width 0.08255)
			(type default)
		)
		(layer "In11.Cu")
	)
	(gr_line
		(start 289.63493 -361.772454)
		(end 289.577018 -361.92206)
		(stroke
			(width 0.08255)
			(type default)
		)
		(layer "In11.Cu")
	)
	(gr_line
		(start 289.659822 -351.611438)
		(end 289.950652 -351.902268)
		(stroke
			(width 0.08255)
			(type default)
		)
		(layer "In11.Cu")
	)
	(gr_line
		(start 289.689794 -398.50822)
		(end 289.689794 -398.890236)
		(stroke
			(width 0.08255)
			(type default)
		)
		(layer "In11.Cu")
	)
	(gr_line
		(start 289.689794 -397.97228)
		(end 289.689794 -397.59001)
		(stroke
			(width 0.08255)
			(type default)
		)
		(layer "In11.Cu")
	)
	(gr_line
		(start 289.776916 -362.37545)
		(end 289.926522 -362.433362)
		(stroke
			(width 0.08255)
			(type default)
		)
		(layer "In11.Cu")
	)
	(gr_line
		(start 289.816794 -398.38122)
		(end 289.689794 -398.50822)
		(stroke
			(width 0.08255)
			(type default)
		)
		(layer "In11.Cu")
	)
	(gr_line
		(start 289.816794 -398.09928)
		(end 289.689794 -397.97228)
		(stroke
			(width 0.08255)
			(type default)
		)
		(layer "In11.Cu")
	)
	(gr_line
		(start 289.817048 -395.033754)
		(end 290.096194 -395.443456)
		(stroke
			(width 0.08255)
			(type default)
		)
		(layer "In11.Cu")
	)
	(gr_line
		(start 289.846766 -394.876528)
		(end 289.817048 -395.033754)
		(stroke
			(width 0.08255)
			(type default)
		)
		(layer "In11.Cu")
	)
	(gr_line
		(start 289.950652 -348.29496)
		(end 289.659822 -348.58579)
		(stroke
			(width 0.08255)
			(type default)
		)
		(layer "In11.Cu")
	)
	(gr_line
		(start 290.06927 -363.037628)
		(end 290.269168 -363.491018)
		(stroke
			(width 0.08255)
			(type default)
		)
		(layer "In11.Cu")
	)
	(gr_line
		(start 290.080192 -394.716)
		(end 290.488116 -395.314678)
		(stroke
			(width 0.08255)
			(type default)
		)
		(layer "In11.Cu")
	)
	(gr_line
		(start 290.096194 -395.443456)
		(end 290.25342 -395.473174)
		(stroke
			(width 0.08255)
			(type default)
		)
		(layer "In11.Cu")
	)
	(gr_line
		(start 290.127182 -362.888276)
		(end 290.06927 -363.037628)
		(stroke
			(width 0.08255)
			(type default)
		)
		(layer "In11.Cu")
	)
	(gr_line
		(start 290.269168 -363.491018)
		(end 290.418774 -363.54893)
		(stroke
			(width 0.08255)
			(type default)
		)
		(layer "In11.Cu")
	)
	(gr_line
		(start 290.561522 -364.153196)
		(end 290.76142 -364.606586)
		(stroke
			(width 0.08255)
			(type default)
		)
		(layer "In11.Cu")
	)
	(gr_line
		(start 290.619434 -364.003844)
		(end 290.561522 -364.153196)
		(stroke
			(width 0.08255)
			(type default)
		)
		(layer "In11.Cu")
	)
	(gr_line
		(start 290.76142 -364.606586)
		(end 290.910772 -364.664498)
		(stroke
			(width 0.08255)
			(type default)
		)
		(layer "In11.Cu")
	)
	(gr_line
		(start 291.053774 -365.268764)
		(end 291.253672 -365.722154)
		(stroke
			(width 0.08255)
			(type default)
		)
		(layer "In11.Cu")
	)
	(gr_line
		(start 291.111686 -365.119666)
		(end 291.053774 -365.268764)
		(stroke
			(width 0.08255)
			(type default)
		)
		(layer "In11.Cu")
	)
	(gr_line
		(start 291.253672 -365.722154)
		(end 291.403024 -365.780066)
		(stroke
			(width 0.08255)
			(type default)
		)
		(layer "In11.Cu")
	)
	(gr_line
		(start 291.546026 -366.384332)
		(end 291.745924 -366.837722)
		(stroke
			(width 0.08255)
			(type default)
		)
		(layer "In11.Cu")
	)
	(gr_line
		(start 291.603938 -366.235234)
		(end 291.546026 -366.384332)
		(stroke
			(width 0.08255)
			(type default)
		)
		(layer "In11.Cu")
	)
	(gr_line
		(start 291.745924 -366.837722)
		(end 291.895022 -366.89538)
		(stroke
			(width 0.08255)
			(type default)
		)
		(layer "In11.Cu")
	)
	(gr_line
		(start 291.889942 -370.872258)
		(end 291.889942 -370.489988)
		(stroke
			(width 0.08255)
			(type default)
		)
		(layer "In11.Cu")
	)
	(gr_line
		(start 291.8968 -366.896142)
		(end 291.992812 -367.113566)
		(stroke
			(width 0.08255)
			(type default)
		)
		(layer "In11.Cu")
	)
	(gr_line
		(start 292.016942 -370.999258)
		(end 291.889942 -370.872258)
		(stroke
			(width 0.08255)
			(type default)
		)
		(layer "In11.Cu")
	)
	(gr_line
		(start 292.038024 -367.4999)
		(end 292.238176 -367.95329)
		(stroke
			(width 0.08255)
			(type default)
		)
		(layer "In11.Cu")
	)
	(gr_line
		(start 292.095936 -367.351056)
		(end 292.038024 -367.4999)
		(stroke
			(width 0.08255)
			(type default)
		)
		(layer "In11.Cu")
	)
	(gr_line
		(start 292.238176 -367.95329)
		(end 292.387274 -368.010948)
		(stroke
			(width 0.08255)
			(type default)
		)
		(layer "In11.Cu")
	)
	(gr_line
		(start 292.388798 -368.01171)
		(end 292.389052 -368.01171)
		(stroke
			(width 0.08255)
			(type default)
		)
		(layer "In11.Cu")
	)
	(gr_line
		(start 292.768782 -357.75773)
		(end 293.059612 -358.04856)
		(stroke
			(width 0.08255)
			(type default)
		)
		(layer "In11.Cu")
	)
	(gr_line
		(start 293.059612 -354.441252)
		(end 292.768782 -354.732082)
		(stroke
			(width 0.08255)
			(type default)
		)
		(layer "In11.Cu")
	)
	(gr_line
		(start 293.78402 -360.820208)
		(end 294.006016 -361.361736)
		(stroke
			(width 0.08255)
			(type default)
		)
		(layer "In11.Cu")
	)
	(gr_line
		(start 293.821358 -360.731054)
		(end 293.78402 -360.820208)
		(stroke
			(width 0.08255)
			(type default)
		)
		(layer "In11.Cu")
	)
	(gr_line
		(start 294.006016 -361.361736)
		(end 294.09517 -361.399074)
		(stroke
			(width 0.08255)
			(type default)
		)
		(layer "In11.Cu")
	)
	(gr_line
		(start 294.22217 -362.006896)
		(end 294.41013 -362.465366)
		(stroke
			(width 0.08255)
			(type default)
		)
		(layer "In11.Cu")
	)
	(gr_line
		(start 294.284146 -361.859068)
		(end 294.22217 -362.006896)
		(stroke
			(width 0.08255)
			(type default)
		)
		(layer "In11.Cu")
	)
	(gr_line
		(start 294.41013 -362.465366)
		(end 294.557958 -362.527088)
		(stroke
			(width 0.08255)
			(type default)
		)
		(layer "In11.Cu")
	)
	(gr_line
		(start 294.684958 -363.13491)
		(end 294.872918 -363.59338)
		(stroke
			(width 0.08255)
			(type default)
		)
		(layer "In11.Cu")
	)
	(gr_line
		(start 294.746934 -362.987336)
		(end 294.684958 -363.13491)
		(stroke
			(width 0.08255)
			(type default)
		)
		(layer "In11.Cu")
	)
	(gr_line
		(start 294.872918 -363.59338)
		(end 295.020746 -363.655102)
		(stroke
			(width 0.08255)
			(type default)
		)
		(layer "In11.Cu")
	)
	(gr_line
		(start 295.147746 -364.262924)
		(end 295.335706 -364.721394)
		(stroke
			(width 0.08255)
			(type default)
		)
		(layer "In11.Cu")
	)
	(gr_line
		(start 295.209722 -364.11535)
		(end 295.147746 -364.262924)
		(stroke
			(width 0.08255)
			(type default)
		)
		(layer "In11.Cu")
	)
	(gr_line
		(start 295.28008 -341.05977)
		(end 295.280334 -341.05977)
		(stroke
			(width 0.08255)
			(type default)
		)
		(layer "In11.Cu")
	)
	(gr_line
		(start 295.310052 -340.90102)
		(end 295.280588 -341.057992)
		(stroke
			(width 0.08255)
			(type default)
		)
		(layer "In11.Cu")
	)
	(gr_line
		(start 295.335706 -364.721394)
		(end 295.483534 -364.783116)
		(stroke
			(width 0.08255)
			(type default)
		)
		(layer "In11.Cu")
	)
	(gr_line
		(start 295.610534 -365.390938)
		(end 295.798494 -365.849408)
		(stroke
			(width 0.08255)
			(type default)
		)
		(layer "In11.Cu")
	)
	(gr_line
		(start 295.67251 -365.243364)
		(end 295.610534 -365.390938)
		(stroke
			(width 0.08255)
			(type default)
		)
		(layer "In11.Cu")
	)
	(gr_line
		(start 295.719246 -340.621112)
		(end 295.310052 -340.90102)
		(stroke
			(width 0.08255)
			(type default)
		)
		(layer "In11.Cu")
	)
	(gr_line
		(start 295.798494 -365.849408)
		(end 295.946322 -365.91113)
		(stroke
			(width 0.08255)
			(type default)
		)
		(layer "In11.Cu")
	)
	(gr_line
		(start 295.876472 -340.65083)
		(end 295.719246 -340.621112)
		(stroke
			(width 0.08255)
			(type default)
		)
		(layer "In11.Cu")
	)
	(gr_line
		(start 296.073322 -366.518952)
		(end 296.261282 -366.977422)
		(stroke
			(width 0.08255)
			(type default)
		)
		(layer "In11.Cu")
	)
	(gr_line
		(start 296.135298 -366.371378)
		(end 296.073322 -366.518952)
		(stroke
			(width 0.08255)
			(type default)
		)
		(layer "In11.Cu")
	)
	(gr_line
		(start 296.261282 -366.977422)
		(end 296.40911 -367.039144)
		(stroke
			(width 0.08255)
			(type default)
		)
		(layer "In11.Cu")
	)
	(gr_line
		(start 296.289984 -370.872258)
		(end 296.289984 -370.489988)
		(stroke
			(width 0.08255)
			(type default)
		)
		(layer "In11.Cu")
	)
	(gr_line
		(start 296.416984 -370.999258)
		(end 296.289984 -370.872258)
		(stroke
			(width 0.08255)
			(type default)
		)
		(layer "In11.Cu")
	)
	(gr_line
		(start 296.536364 -367.646966)
		(end 296.724324 -368.105436)
		(stroke
			(width 0.08255)
			(type default)
		)
		(layer "In11.Cu")
	)
	(gr_line
		(start 296.598086 -367.499392)
		(end 296.536364 -367.646966)
		(stroke
			(width 0.08255)
			(type default)
		)
		(layer "In11.Cu")
	)
	(gr_line
		(start 296.616374 -337.821778)
		(end 296.558462 -337.97113)
		(stroke
			(width 0.08255)
			(type default)
		)
		(layer "In11.Cu")
	)
	(gr_line
		(start 296.724324 -368.105436)
		(end 296.871898 -368.166904)
		(stroke
			(width 0.08255)
			(type default)
		)
		(layer "In11.Cu")
	)
	(gr_line
		(start 296.873422 -368.167666)
		(end 296.873676 -368.167666)
		(stroke
			(width 0.08255)
			(type default)
		)
		(layer "In11.Cu")
	)
	(gr_line
		(start 297.070018 -337.622134)
		(end 296.616374 -337.821778)
		(stroke
			(width 0.08255)
			(type default)
		)
		(layer "In11.Cu")
	)
	(gr_line
		(start 297.21937 -337.6803)
		(end 297.070018 -337.622134)
		(stroke
			(width 0.08255)
			(type default)
		)
		(layer "In11.Cu")
	)
	(gr_line
		(start 297.723306 -337.354418)
		(end 297.674284 -337.480148)
		(stroke
			(width 0.08255)
			(type default)
		)
		(layer "In11.Cu")
	)
	(gr_line
		(start 298.20997 -337.140296)
		(end 297.723306 -337.354418)
		(stroke
			(width 0.08255)
			(type default)
		)
		(layer "In11.Cu")
	)
	(gr_line
		(start 298.315126 -360.685588)
		(end 298.493688 -361.148122)
		(stroke
			(width 0.08255)
			(type default)
		)
		(layer "In11.Cu")
	)
	(gr_line
		(start 298.335446 -337.189064)
		(end 298.20997 -337.140296)
		(stroke
			(width 0.08255)
			(type default)
		)
		(layer "In11.Cu")
	)
	(gr_line
		(start 298.358306 -360.588052)
		(end 298.315126 -360.685588)
		(stroke
			(width 0.08255)
			(type default)
		)
		(layer "In11.Cu")
	)
	(gr_line
		(start 298.493688 -361.148122)
		(end 298.590716 -361.191302)
		(stroke
			(width 0.08255)
			(type default)
		)
		(layer "In11.Cu")
	)
	(gr_line
		(start 298.704254 -361.80141)
		(end 298.882562 -362.263944)
		(stroke
			(width 0.08255)
			(type default)
		)
		(layer "In11.Cu")
	)
	(gr_line
		(start 298.769532 -361.654852)
		(end 298.704254 -361.80141)
		(stroke
			(width 0.08255)
			(type default)
		)
		(layer "In11.Cu")
	)
	(gr_line
		(start 298.882562 -362.263944)
		(end 299.029374 -362.328968)
		(stroke
			(width 0.08255)
			(type default)
		)
		(layer "In11.Cu")
	)
	(gr_line
		(start 298.986702 -345.465146)
		(end 299.277532 -345.755976)
		(stroke
			(width 0.08255)
			(type default)
		)
		(layer "In11.Cu")
	)
	(gr_line
		(start 299.142912 -362.939076)
		(end 299.32122 -363.40161)
		(stroke
			(width 0.08255)
			(type default)
		)
		(layer "In11.Cu")
	)
	(gr_line
		(start 299.207936 -362.792518)
		(end 299.142912 -362.939076)
		(stroke
			(width 0.08255)
			(type default)
		)
		(layer "In11.Cu")
	)
	(gr_line
		(start 299.277532 -342.148668)
		(end 298.986702 -342.439498)
		(stroke
			(width 0.08255)
			(type default)
		)
		(layer "In11.Cu")
	)
	(gr_line
		(start 299.32122 -363.40161)
		(end 299.468032 -363.466634)
		(stroke
			(width 0.08255)
			(type default)
		)
		(layer "In11.Cu")
	)
	(gr_line
		(start 299.58157 -364.076742)
		(end 299.759624 -364.539276)
		(stroke
			(width 0.08255)
			(type default)
		)
		(layer "In11.Cu")
	)
	(gr_line
		(start 299.646594 -363.930184)
		(end 299.58157 -364.076742)
		(stroke
			(width 0.08255)
			(type default)
		)
		(layer "In11.Cu")
	)
	(gr_line
		(start 299.759624 -364.539276)
		(end 299.906436 -364.6043)
		(stroke
			(width 0.08255)
			(type default)
		)
		(layer "In11.Cu")
	)
	(gr_line
		(start 300.020228 -365.214408)
		(end 300.198282 -365.676942)
		(stroke
			(width 0.08255)
			(type default)
		)
		(layer "In11.Cu")
	)
	(gr_line
		(start 300.085252 -365.068104)
		(end 300.020228 -365.214408)
		(stroke
			(width 0.08255)
			(type default)
		)
		(layer "In11.Cu")
	)
	(gr_line
		(start 300.198282 -365.676942)
		(end 300.345094 -365.741966)
		(stroke
			(width 0.08255)
			(type default)
		)
		(layer "In11.Cu")
	)
	(gr_line
		(start 300.44644 -340.866476)
		(end 300.30166 -340.928706)
		(stroke
			(width 0.08255)
			(type default)
		)
		(layer "In11.Cu")
	)
	(gr_line
		(start 300.458886 -366.352074)
		(end 300.63694 -366.814608)
		(stroke
			(width 0.08255)
			(type default)
		)
		(layer "In11.Cu")
	)
	(gr_line
		(start 300.506384 -340.716108)
		(end 300.447202 -340.864698)
		(stroke
			(width 0.08255)
			(type default)
		)
		(layer "In11.Cu")
	)
	(gr_line
		(start 300.52391 -366.20577)
		(end 300.458886 -366.352074)
		(stroke
			(width 0.08255)
			(type default)
		)
		(layer "In11.Cu")
	)
	(gr_line
		(start 300.63694 -366.814608)
		(end 300.783498 -366.879378)
		(stroke
			(width 0.08255)
			(type default)
		)
		(layer "In11.Cu")
	)
	(gr_line
		(start 300.689772 -370.872258)
		(end 300.689772 -370.489988)
		(stroke
			(width 0.08255)
			(type default)
		)
		(layer "In11.Cu")
	)
	(gr_line
		(start 300.816772 -370.999258)
		(end 300.689772 -370.872258)
		(stroke
			(width 0.08255)
			(type default)
		)
		(layer "In11.Cu")
	)
	(gr_line
		(start 300.897544 -367.48974)
		(end 301.075598 -367.952274)
		(stroke
			(width 0.08255)
			(type default)
		)
		(layer "In11.Cu")
	)
	(gr_line
		(start 300.961806 -340.520528)
		(end 300.506384 -340.716108)
		(stroke
			(width 0.08255)
			(type default)
		)
		(layer "In11.Cu")
	)
	(gr_line
		(start 300.962314 -367.34369)
		(end 300.897544 -367.48974)
		(stroke
			(width 0.08255)
			(type default)
		)
		(layer "In11.Cu")
	)
	(gr_line
		(start 301.075598 -367.952274)
		(end 301.222156 -368.017044)
		(stroke
			(width 0.08255)
			(type default)
		)
		(layer "In11.Cu")
	)
	(gr_line
		(start 301.11065 -340.57971)
		(end 300.961806 -340.520528)
		(stroke
			(width 0.08255)
			(type default)
		)
		(layer "In11.Cu")
	)
	(gr_line
		(start 301.22368 -368.017806)
		(end 301.270162 -368.138202)
		(stroke
			(width 0.08255)
			(type default)
		)
		(layer "In11.Cu")
	)
	(gr_line
		(start 306.433982 -320.051938)
		(end 306.433982 -320.074036)
		(stroke
			(width 0.05715)
			(type default)
		)
		(layer "In11.Cu")
	)
	(gr_line
		(start 306.479702 -320.006218)
		(end 306.433982 -320.051938)
		(stroke
			(width 0.05715)
			(type default)
		)
		(layer "In11.Cu")
	)
	(gr_line
		(start 306.670202 -320.006218)
		(end 306.715922 -320.051938)
		(stroke
			(width 0.05715)
			(type default)
		)
		(layer "In11.Cu")
	)
	(gr_line
		(start 306.715922 -320.051938)
		(end 306.715922 -320.074036)
		(stroke
			(width 0.05715)
			(type default)
		)
		(layer "In11.Cu")
	)
	(gr_line
		(start 307.049932 -313.949842)
		(end 307.049932 -313.684412)
		(stroke
			(width 0.05715)
			(type default)
		)
		(layer "In11.Cu")
	)
	(gr_line
		(start 307.049932 -313.684412)
		(end 306.935632 -313.570112)
		(stroke
			(width 0.05715)
			(type default)
		)
		(layer "In11.Cu")
	)
	(gr_line
		(start 307.049932 -313.265312)
		(end 306.935632 -313.379612)
		(stroke
			(width 0.05715)
			(type default)
		)
		(layer "In11.Cu")
	)
	(gr_line
		(start 307.049932 -312.999882)
		(end 307.049932 -313.265312)
		(stroke
			(width 0.05715)
			(type default)
		)
		(layer "In11.Cu")
	)
	(gr_line
		(start 308.949852 -309.199788)
		(end 309.215282 -309.199788)
		(stroke
			(width 0.05715)
			(type default)
		)
		(layer "In11.Cu")
	)
	(gr_line
		(start 308.949852 -307.299868)
		(end 309.215282 -307.299868)
		(stroke
			(width 0.05715)
			(type default)
		)
		(layer "In11.Cu")
	)
	(gr_line
		(start 308.949852 -305.399948)
		(end 309.215282 -305.399948)
		(stroke
			(width 0.05715)
			(type default)
		)
		(layer "In11.Cu")
	)
	(gr_line
		(start 309.215282 -309.199788)
		(end 309.329582 -309.314088)
		(stroke
			(width 0.05715)
			(type default)
		)
		(layer "In11.Cu")
	)
	(gr_line
		(start 309.215282 -307.299868)
		(end 309.33898 -307.423566)
		(stroke
			(width 0.05715)
			(type default)
		)
		(layer "In11.Cu")
	)
	(gr_line
		(start 309.215282 -305.399948)
		(end 309.33898 -305.523646)
		(stroke
			(width 0.05715)
			(type default)
		)
		(layer "In11.Cu")
	)
	(gr_line
		(start 315.791596 -305.97602)
		(end 315.837316 -306.02174)
		(stroke
			(width 0.05715)
			(type default)
		)
		(layer "In11.Cu")
	)
	(gr_line
		(start 315.80328 -309.770018)
		(end 315.849 -309.815738)
		(stroke
			(width 0.05715)
			(type default)
		)
		(layer "In11.Cu")
	)
	(gr_line
		(start 315.82868 -307.870098)
		(end 315.8744 -307.915818)
		(stroke
			(width 0.05715)
			(type default)
		)
		(layer "In11.Cu")
	)
	(gr_line
		(start 315.837316 -306.02174)
		(end 315.865764 -306.02174)
		(stroke
			(width 0.05715)
			(type default)
		)
		(layer "In11.Cu")
	)
	(gr_line
		(start 315.849 -309.815738)
		(end 315.877448 -309.815738)
		(stroke
			(width 0.05715)
			(type default)
		)
		(layer "In11.Cu")
	)
	(gr_line
		(start 315.8744 -307.915818)
		(end 315.902848 -307.915818)
		(stroke
			(width 0.05715)
			(type default)
		)
		(layer "In11.Cu")
	)
	(gr_line
		(start 327.01484 -320.18097)
		(end 327.014586 -320.180716)
		(stroke
			(width 0.08255)
			(type default)
		)
		(layer "In11.Cu")
	)
	(gr_line
		(start 328.97572 -319.696846)
		(end 328.975466 -319.696592)
		(stroke
			(width 0.08255)
			(type default)
		)
		(layer "In11.Cu")
	)
	(gr_line
		(start 330.301854 -317.65748)
		(end 330.301854 -317.657734)
		(stroke
			(width 0.08255)
			(type default)
		)
		(layer "In11.Cu")
	)
	(gr_line
		(start 330.916026 -319.140586)
		(end 330.91628 -319.14084)
		(stroke
			(width 0.08255)
			(type default)
		)
		(layer "In11.Cu")
	)
	(gr_line
		(start 0 -416.589972)
		(end 0 -246.488458)
		(stroke
			(width 0.05)
			(type default)
		)
		(layer "Edge.Cuts")
	)
	(gr_arc
		(start 0 -416.589972)
		(mid 0.585785 -418.004183)
		(end 1.999996 -418.589968)
		(stroke
			(width 0.05)
			(type default)
		)
		(layer "Edge.Cuts")
	)
	(gr_line
		(start 0 -82.131662)
		(end 0 -1.999996)
		(stroke
			(width 0.05)
			(type default)
		)
		(layer "Edge.Cuts")
	)
	(gr_arc
		(start 0 -82.131662)
		(mid 0.152239 -82.89692)
		(end 0.585724 -83.54568)
		(stroke
			(width 0.05)
			(type default)
		)
		(layer "Edge.Cuts")
	)
	(gr_arc
		(start 0.585724 -245.074186)
		(mid 0.152244 -245.723085)
		(end 0 -246.488458)
		(stroke
			(width 0.05)
			(type default)
		)
		(layer "Edge.Cuts")
	)
	(gr_line
		(start 0.585724 -245.074186)
		(end 3.214116 -242.445794)
		(stroke
			(width 0.05)
			(type default)
		)
		(layer "Edge.Cuts")
	)
	(gr_arc
		(start 1.999996 0)
		(mid 0.585785 -0.585785)
		(end 0 -1.999996)
		(stroke
			(width 0.05)
			(type default)
		)
		(layer "Edge.Cuts")
	)
	(gr_line
		(start 1.999996 0)
		(end 5.964936 0)
		(stroke
			(width 0.05)
			(type default)
		)
		(layer "Edge.Cuts")
	)
	(gr_arc
		(start 3.214116 -242.445794)
		(mid 3.647762 -241.796936)
		(end 3.800094 -241.031522)
		(stroke
			(width 0.05)
			(type default)
		)
		(layer "Edge.Cuts")
	)
	(gr_line
		(start 3.214116 -86.174326)
		(end 0.585724 -83.54568)
		(stroke
			(width 0.05)
			(type default)
		)
		(layer "Edge.Cuts")
	)
	(gr_line
		(start 3.800094 -241.031522)
		(end 3.800094 -87.588344)
		(stroke
			(width 0.05)
			(type default)
		)
		(layer "Edge.Cuts")
	)
	(gr_arc
		(start 3.800094 -87.588344)
		(mid 3.647755 -86.823047)
		(end 3.214116 -86.174326)
		(stroke
			(width 0.05)
			(type default)
		)
		(layer "Edge.Cuts")
	)
	(gr_arc
		(start 7.964932 -11.850116)
		(mid 8.257825 -12.557221)
		(end 8.96493 -12.850114)
		(stroke
			(width 0.05)
			(type default)
		)
		(layer "Edge.Cuts")
	)
	(gr_arc
		(start 7.964932 -1.999996)
		(mid 7.379145 -0.585789)
		(end 5.964936 0)
		(stroke
			(width 0.05)
			(type default)
		)
		(layer "Edge.Cuts")
	)
	(gr_line
		(start 7.964932 -1.999996)
		(end 7.964932 -11.850116)
		(stroke
			(width 0.05)
			(type default)
		)
		(layer "Edge.Cuts")
	)
	(gr_line
		(start 8.96493 -12.850114)
		(end 16.964914 -12.850114)
		(stroke
			(width 0.05)
			(type default)
		)
		(layer "Edge.Cuts")
	)
	(gr_arc
		(start 16.964914 -12.850114)
		(mid 17.672019 -12.557221)
		(end 17.964912 -11.850116)
		(stroke
			(width 0.05)
			(type default)
		)
		(layer "Edge.Cuts")
	)
	(gr_line
		(start 17.964912 -11.850116)
		(end 17.964912 -1.999996)
		(stroke
			(width 0.05)
			(type default)
		)
		(layer "Edge.Cuts")
	)
	(gr_arc
		(start 19.964908 0)
		(mid 18.550691 -0.585782)
		(end 17.964912 -1.999996)
		(stroke
			(width 0.05)
			(type default)
		)
		(layer "Edge.Cuts")
	)
	(gr_line
		(start 19.964908 0)
		(end 31.964884 0)
		(stroke
			(width 0.05)
			(type default)
		)
		(layer "Edge.Cuts")
	)
	(gr_arc
		(start 33.96488 -11.850116)
		(mid 34.257773 -12.557221)
		(end 34.964878 -12.850114)
		(stroke
			(width 0.05)
			(type default)
		)
		(layer "Edge.Cuts")
	)
	(gr_arc
		(start 33.96488 -1.999996)
		(mid 33.379092 -0.585794)
		(end 31.964884 0)
		(stroke
			(width 0.05)
			(type default)
		)
		(layer "Edge.Cuts")
	)
	(gr_line
		(start 33.96488 -1.999996)
		(end 33.96488 -11.850116)
		(stroke
			(width 0.05)
			(type default)
		)
		(layer "Edge.Cuts")
	)
	(gr_line
		(start 34.964878 -12.850114)
		(end 42.965116 -12.850114)
		(stroke
			(width 0.05)
			(type default)
		)
		(layer "Edge.Cuts")
	)
	(gr_arc
		(start 42.965116 -12.850114)
		(mid 43.672221 -12.557221)
		(end 43.965114 -11.850116)
		(stroke
			(width 0.05)
			(type default)
		)
		(layer "Edge.Cuts")
	)
	(gr_line
		(start 43.965114 -11.850116)
		(end 43.965114 -1.999996)
		(stroke
			(width 0.05)
			(type default)
		)
		(layer "Edge.Cuts")
	)
	(gr_arc
		(start 45.96511 0)
		(mid 44.550891 -0.585781)
		(end 43.965114 -1.999996)
		(stroke
			(width 0.05)
			(type default)
		)
		(layer "Edge.Cuts")
	)
	(gr_line
		(start 45.96511 0)
		(end 57.965086 0)
		(stroke
			(width 0.05)
			(type default)
		)
		(layer "Edge.Cuts")
	)
	(gr_arc
		(start 59.965082 -11.850116)
		(mid 60.257975 -12.557221)
		(end 60.96508 -12.850114)
		(stroke
			(width 0.05)
			(type default)
		)
		(layer "Edge.Cuts")
	)
	(gr_arc
		(start 59.965082 -1.999996)
		(mid 59.379294 -0.585793)
		(end 57.965086 0)
		(stroke
			(width 0.05)
			(type default)
		)
		(layer "Edge.Cuts")
	)
	(gr_line
		(start 59.965082 -1.999996)
		(end 59.965082 -11.850116)
		(stroke
			(width 0.05)
			(type default)
		)
		(layer "Edge.Cuts")
	)
	(gr_line
		(start 60.96508 -12.850114)
		(end 68.965064 -12.850114)
		(stroke
			(width 0.05)
			(type default)
		)
		(layer "Edge.Cuts")
	)
	(gr_arc
		(start 68.965064 -12.850114)
		(mid 69.672169 -12.557221)
		(end 69.965062 -11.850116)
		(stroke
			(width 0.05)
			(type default)
		)
		(layer "Edge.Cuts")
	)
	(gr_line
		(start 69.965062 -11.850116)
		(end 69.965062 -1.999996)
		(stroke
			(width 0.05)
			(type default)
		)
		(layer "Edge.Cuts")
	)
	(gr_arc
		(start 71.965058 0)
		(mid 70.550873 -0.5858)
		(end 69.965062 -1.999996)
		(stroke
			(width 0.05)
			(type default)
		)
		(layer "Edge.Cuts")
	)
	(gr_line
		(start 71.965058 0)
		(end 83.965034 0)
		(stroke
			(width 0.05)
			(type default)
		)
		(layer "Edge.Cuts")
	)
	(gr_arc
		(start 85.96503 -11.850116)
		(mid 86.257923 -12.557221)
		(end 86.965028 -12.850114)
		(stroke
			(width 0.05)
			(type default)
		)
		(layer "Edge.Cuts")
	)
	(gr_arc
		(start 85.96503 -1.999996)
		(mid 85.379245 -0.585776)
		(end 83.965034 0)
		(stroke
			(width 0.05)
			(type default)
		)
		(layer "Edge.Cuts")
	)
	(gr_line
		(start 85.96503 -1.999996)
		(end 85.96503 -11.850116)
		(stroke
			(width 0.05)
			(type default)
		)
		(layer "Edge.Cuts")
	)
	(gr_line
		(start 86.965028 -12.850114)
		(end 94.965012 -12.850114)
		(stroke
			(width 0.05)
			(type default)
		)
		(layer "Edge.Cuts")
	)
	(gr_arc
		(start 94.965012 -12.850114)
		(mid 95.672117 -12.557221)
		(end 95.96501 -11.850116)
		(stroke
			(width 0.05)
			(type default)
		)
		(layer "Edge.Cuts")
	)
	(gr_line
		(start 95.96501 -11.850116)
		(end 95.96501 -1.999996)
		(stroke
			(width 0.05)
			(type default)
		)
		(layer "Edge.Cuts")
	)
	(gr_arc
		(start 97.965006 0)
		(mid 96.55079 -0.585783)
		(end 95.96501 -1.999996)
		(stroke
			(width 0.05)
			(type default)
		)
		(layer "Edge.Cuts")
	)
	(gr_line
		(start 97.965006 0)
		(end 122.065034 0)
		(stroke
			(width 0.05)
			(type default)
		)
		(layer "Edge.Cuts")
	)
	(gr_arc
		(start 124.06503 -11.850116)
		(mid 124.357923 -12.557221)
		(end 125.065028 -12.850114)
		(stroke
			(width 0.05)
			(type default)
		)
		(layer "Edge.Cuts")
	)
	(gr_arc
		(start 124.06503 -1.999996)
		(mid 123.479245 -0.585776)
		(end 122.065034 0)
		(stroke
			(width 0.05)
			(type default)
		)
		(layer "Edge.Cuts")
	)
	(gr_line
		(start 124.06503 -1.999996)
		(end 124.06503 -11.850116)
		(stroke
			(width 0.05)
			(type default)
		)
		(layer "Edge.Cuts")
	)
	(gr_line
		(start 125.065028 -12.850114)
		(end 133.065012 -12.850114)
		(stroke
			(width 0.05)
			(type default)
		)
		(layer "Edge.Cuts")
	)
	(gr_arc
		(start 133.065012 -12.850114)
		(mid 133.772117 -12.557221)
		(end 134.06501 -11.850116)
		(stroke
			(width 0.05)
			(type default)
		)
		(layer "Edge.Cuts")
	)
	(gr_line
		(start 134.06501 -11.850116)
		(end 134.06501 -1.999996)
		(stroke
			(width 0.05)
			(type default)
		)
		(layer "Edge.Cuts")
	)
	(gr_arc
		(start 136.065006 0)
		(mid 134.65079 -0.585783)
		(end 134.06501 -1.999996)
		(stroke
			(width 0.05)
			(type default)
		)
		(layer "Edge.Cuts")
	)
	(gr_line
		(start 136.065006 0)
		(end 148.064982 0)
		(stroke
			(width 0.05)
			(type default)
		)
		(layer "Edge.Cuts")
	)
	(gr_arc
		(start 150.064978 -11.850116)
		(mid 150.357871 -12.557221)
		(end 151.064976 -12.850114)
		(stroke
			(width 0.05)
			(type default)
		)
		(layer "Edge.Cuts")
	)
	(gr_arc
		(start 150.064978 -1.999996)
		(mid 149.47919 -0.585794)
		(end 148.064982 0)
		(stroke
			(width 0.05)
			(type default)
		)
		(layer "Edge.Cuts")
	)
	(gr_line
		(start 150.064978 -1.999996)
		(end 150.064978 -11.850116)
		(stroke
			(width 0.05)
			(type default)
		)
		(layer "Edge.Cuts")
	)
	(gr_line
		(start 151.064976 -12.850114)
		(end 159.06496 -12.850114)
		(stroke
			(width 0.05)
			(type default)
		)
		(layer "Edge.Cuts")
	)
	(gr_arc
		(start 159.06496 -12.850114)
		(mid 159.772065 -12.557221)
		(end 160.064958 -11.850116)
		(stroke
			(width 0.05)
			(type default)
		)
		(layer "Edge.Cuts")
	)
	(gr_line
		(start 160.064958 -11.850116)
		(end 160.064958 -1.999996)
		(stroke
			(width 0.05)
			(type default)
		)
		(layer "Edge.Cuts")
	)
	(gr_arc
		(start 162.064954 0)
		(mid 160.650772 -0.585801)
		(end 160.064958 -1.999996)
		(stroke
			(width 0.05)
			(type default)
		)
		(layer "Edge.Cuts")
	)
	(gr_line
		(start 162.064954 0)
		(end 174.06493 0)
		(stroke
			(width 0.05)
			(type default)
		)
		(layer "Edge.Cuts")
	)
	(gr_arc
		(start 176.064926 -11.850116)
		(mid 176.357819 -12.557221)
		(end 177.064924 -12.850114)
		(stroke
			(width 0.05)
			(type default)
		)
		(layer "Edge.Cuts")
	)
	(gr_arc
		(start 176.064926 -1.999996)
		(mid 175.479141 -0.585777)
		(end 174.06493 0)
		(stroke
			(width 0.05)
			(type default)
		)
		(layer "Edge.Cuts")
	)
	(gr_line
		(start 176.064926 -1.999996)
		(end 176.064926 -11.850116)
		(stroke
			(width 0.05)
			(type default)
		)
		(layer "Edge.Cuts")
	)
	(gr_line
		(start 177.064924 -12.850114)
		(end 185.064908 -12.850114)
		(stroke
			(width 0.05)
			(type default)
		)
		(layer "Edge.Cuts")
	)
	(gr_arc
		(start 185.064908 -12.850114)
		(mid 185.772013 -12.557221)
		(end 186.064906 -11.850116)
		(stroke
			(width 0.05)
			(type default)
		)
		(layer "Edge.Cuts")
	)
	(gr_line
		(start 186.064906 -11.850116)
		(end 186.064906 -1.999996)
		(stroke
			(width 0.05)
			(type default)
		)
		(layer "Edge.Cuts")
	)
	(gr_arc
		(start 188.064902 0)
		(mid 186.650689 -0.585784)
		(end 186.064906 -1.999996)
		(stroke
			(width 0.05)
			(type default)
		)
		(layer "Edge.Cuts")
	)
	(gr_line
		(start 188.064902 0)
		(end 200.064878 0)
		(stroke
			(width 0.05)
			(type default)
		)
		(layer "Edge.Cuts")
	)
	(gr_line
		(start 200.481184 -418.589968)
		(end 1.999996 -418.589968)
		(stroke
			(width 0.05)
			(type default)
		)
		(layer "Edge.Cuts")
	)
	(gr_arc
		(start 200.481184 -418.589968)
		(mid 201.291806 -418.418339)
		(end 201.963274 -417.93287)
		(stroke
			(width 0.05)
			(type default)
		)
		(layer "Edge.Cuts")
	)
	(gr_arc
		(start 202.064874 -11.850116)
		(mid 202.357841 -12.557401)
		(end 203.065126 -12.850114)
		(stroke
			(width 0.05)
			(type default)
		)
		(layer "Edge.Cuts")
	)
	(gr_arc
		(start 202.064874 -1.999996)
		(mid 201.479086 -0.585796)
		(end 200.064878 0)
		(stroke
			(width 0.05)
			(type default)
		)
		(layer "Edge.Cuts")
	)
	(gr_line
		(start 202.064874 -1.999996)
		(end 202.064874 -11.850116)
		(stroke
			(width 0.05)
			(type default)
		)
		(layer "Edge.Cuts")
	)
	(gr_line
		(start 203.065126 -12.850114)
		(end 211.06511 -12.850114)
		(stroke
			(width 0.05)
			(type default)
		)
		(layer "Edge.Cuts")
	)
	(gr_arc
		(start 203.445364 -417.276026)
		(mid 202.634777 -417.447541)
		(end 201.963274 -417.93287)
		(stroke
			(width 0.05)
			(type default)
		)
		(layer "Edge.Cuts")
	)
	(gr_arc
		(start 211.06511 -12.850114)
		(mid 211.772215 -12.557221)
		(end 212.065108 -11.850116)
		(stroke
			(width 0.05)
			(type default)
		)
		(layer "Edge.Cuts")
	)
	(gr_line
		(start 212.065108 -11.850116)
		(end 212.065108 -1.999996)
		(stroke
			(width 0.05)
			(type default)
		)
		(layer "Edge.Cuts")
	)
	(gr_arc
		(start 214.065104 0)
		(mid 212.650889 -0.585784)
		(end 212.065108 -1.999996)
		(stroke
			(width 0.05)
			(type default)
		)
		(layer "Edge.Cuts")
	)
	(gr_line
		(start 214.065104 0)
		(end 238.164878 0)
		(stroke
			(width 0.05)
			(type default)
		)
		(layer "Edge.Cuts")
	)
	(gr_arc
		(start 240.164874 -11.850116)
		(mid 240.457841 -12.557401)
		(end 241.165126 -12.850114)
		(stroke
			(width 0.05)
			(type default)
		)
		(layer "Edge.Cuts")
	)
	(gr_arc
		(start 240.164874 -1.999996)
		(mid 239.579086 -0.585796)
		(end 238.164878 0)
		(stroke
			(width 0.05)
			(type default)
		)
		(layer "Edge.Cuts")
	)
	(gr_line
		(start 240.164874 -1.999996)
		(end 240.164874 -11.850116)
		(stroke
			(width 0.05)
			(type default)
		)
		(layer "Edge.Cuts")
	)
	(gr_line
		(start 241.165126 -12.850114)
		(end 249.16511 -12.850114)
		(stroke
			(width 0.05)
			(type default)
		)
		(layer "Edge.Cuts")
	)
	(gr_arc
		(start 249.16511 -12.850114)
		(mid 249.872215 -12.557221)
		(end 250.165108 -11.850116)
		(stroke
			(width 0.05)
			(type default)
		)
		(layer "Edge.Cuts")
	)
	(gr_line
		(start 250.165108 -11.850116)
		(end 250.165108 -1.999996)
		(stroke
			(width 0.05)
			(type default)
		)
		(layer "Edge.Cuts")
	)
	(gr_arc
		(start 252.165104 0)
		(mid 250.750889 -0.585784)
		(end 250.165108 -1.999996)
		(stroke
			(width 0.05)
			(type default)
		)
		(layer "Edge.Cuts")
	)
	(gr_line
		(start 252.165104 0)
		(end 264.16508 0)
		(stroke
			(width 0.05)
			(type default)
		)
		(layer "Edge.Cuts")
	)
	(gr_arc
		(start 266.165076 -11.850116)
		(mid 266.457969 -12.557221)
		(end 267.165074 -12.850114)
		(stroke
			(width 0.05)
			(type default)
		)
		(layer "Edge.Cuts")
	)
	(gr_arc
		(start 266.165076 -1.999996)
		(mid 265.579288 -0.585795)
		(end 264.16508 0)
		(stroke
			(width 0.05)
			(type default)
		)
		(layer "Edge.Cuts")
	)
	(gr_line
		(start 266.165076 -1.999996)
		(end 266.165076 -11.850116)
		(stroke
			(width 0.05)
			(type default)
		)
		(layer "Edge.Cuts")
	)
	(gr_line
		(start 267.165074 -12.850114)
		(end 275.165058 -12.850114)
		(stroke
			(width 0.05)
			(type default)
		)
		(layer "Edge.Cuts")
	)
	(gr_line
		(start 271.794478 -417.276026)
		(end 203.445364 -417.276026)
		(stroke
			(width 0.05)
			(type default)
		)
		(layer "Edge.Cuts")
	)
	(gr_arc
		(start 273.276568 -417.93287)
		(mid 272.605056 -417.447561)
		(end 271.794478 -417.276026)
		(stroke
			(width 0.05)
			(type default)
		)
		(layer "Edge.Cuts")
	)
	(gr_arc
		(start 273.276568 -417.93287)
		(mid 273.948042 -418.418346)
		(end 274.758658 -418.589968)
		(stroke
			(width 0.05)
			(type default)
		)
		(layer "Edge.Cuts")
	)
	(gr_arc
		(start 275.165058 -12.850114)
		(mid 275.872163 -12.557221)
		(end 276.165056 -11.850116)
		(stroke
			(width 0.05)
			(type default)
		)
		(layer "Edge.Cuts")
	)
	(gr_line
		(start 276.165056 -11.850116)
		(end 276.165056 -1.999996)
		(stroke
			(width 0.05)
			(type default)
		)
		(layer "Edge.Cuts")
	)
	(gr_arc
		(start 278.165052 0)
		(mid 276.750871 -0.585802)
		(end 276.165056 -1.999996)
		(stroke
			(width 0.05)
			(type default)
		)
		(layer "Edge.Cuts")
	)
	(gr_line
		(start 278.165052 0)
		(end 290.165028 0)
		(stroke
			(width 0.05)
			(type default)
		)
		(layer "Edge.Cuts")
	)
	(gr_arc
		(start 292.165024 -11.850116)
		(mid 292.457917 -12.557221)
		(end 293.165022 -12.850114)
		(stroke
			(width 0.05)
			(type default)
		)
		(layer "Edge.Cuts")
	)
	(gr_arc
		(start 292.165024 -1.999996)
		(mid 291.579239 -0.585778)
		(end 290.165028 0)
		(stroke
			(width 0.05)
			(type default)
		)
		(layer "Edge.Cuts")
	)
	(gr_line
		(start 292.165024 -1.999996)
		(end 292.165024 -11.850116)
		(stroke
			(width 0.05)
			(type default)
		)
		(layer "Edge.Cuts")
	)
	(gr_line
		(start 293.165022 -12.850114)
		(end 301.165006 -12.850114)
		(stroke
			(width 0.05)
			(type default)
		)
		(layer "Edge.Cuts")
	)
	(gr_arc
		(start 301.165006 -12.850114)
		(mid 301.872111 -12.557221)
		(end 302.165004 -11.850116)
		(stroke
			(width 0.05)
			(type default)
		)
		(layer "Edge.Cuts")
	)
	(gr_line
		(start 302.165004 -11.850116)
		(end 302.165004 -1.999996)
		(stroke
			(width 0.05)
			(type default)
		)
		(layer "Edge.Cuts")
	)
	(gr_arc
		(start 304.165 0)
		(mid 302.750788 -0.585785)
		(end 302.165004 -1.999996)
		(stroke
			(width 0.05)
			(type default)
		)
		(layer "Edge.Cuts")
	)
	(gr_line
		(start 304.165 0)
		(end 316.164976 0)
		(stroke
			(width 0.05)
			(type default)
		)
		(layer "Edge.Cuts")
	)
	(gr_arc
		(start 318.164972 -11.850116)
		(mid 318.457865 -12.557221)
		(end 319.16497 -12.850114)
		(stroke
			(width 0.05)
			(type default)
		)
		(layer "Edge.Cuts")
	)
	(gr_arc
		(start 318.164972 -1.999996)
		(mid 317.579184 -0.585796)
		(end 316.164976 0)
		(stroke
			(width 0.05)
			(type default)
		)
		(layer "Edge.Cuts")
	)
	(gr_line
		(start 318.164972 -1.999996)
		(end 318.164972 -11.850116)
		(stroke
			(width 0.05)
			(type default)
		)
		(layer "Edge.Cuts")
	)
	(gr_line
		(start 319.16497 -12.850114)
		(end 327.164954 -12.850114)
		(stroke
			(width 0.05)
			(type default)
		)
		(layer "Edge.Cuts")
	)
	(gr_arc
		(start 327.164954 -12.850114)
		(mid 327.872059 -12.557221)
		(end 328.164952 -11.850116)
		(stroke
			(width 0.05)
			(type default)
		)
		(layer "Edge.Cuts")
	)
	(gr_line
		(start 328.164952 -11.850116)
		(end 328.164952 -1.999996)
		(stroke
			(width 0.05)
			(type default)
		)
		(layer "Edge.Cuts")
	)
	(gr_arc
		(start 330.164948 0)
		(mid 328.750705 -0.585768)
		(end 328.164952 -1.999996)
		(stroke
			(width 0.05)
			(type default)
		)
		(layer "Edge.Cuts")
	)
	(gr_line
		(start 330.164948 0)
		(end 354.264976 0)
		(stroke
			(width 0.05)
			(type default)
		)
		(layer "Edge.Cuts")
	)
	(gr_arc
		(start 356.264972 -11.850116)
		(mid 356.557865 -12.557221)
		(end 357.26497 -12.850114)
		(stroke
			(width 0.05)
			(type default)
		)
		(layer "Edge.Cuts")
	)
	(gr_arc
		(start 356.264972 -1.999996)
		(mid 355.679184 -0.585796)
		(end 354.264976 0)
		(stroke
			(width 0.05)
			(type default)
		)
		(layer "Edge.Cuts")
	)
	(gr_line
		(start 356.264972 -1.999996)
		(end 356.264972 -11.850116)
		(stroke
			(width 0.05)
			(type default)
		)
		(layer "Edge.Cuts")
	)
	(gr_line
		(start 357.26497 -12.850114)
		(end 365.264954 -12.850114)
		(stroke
			(width 0.05)
			(type default)
		)
		(layer "Edge.Cuts")
	)
	(gr_arc
		(start 365.264954 -12.850114)
		(mid 365.972059 -12.557221)
		(end 366.264952 -11.850116)
		(stroke
			(width 0.05)
			(type default)
		)
		(layer "Edge.Cuts")
	)
	(gr_line
		(start 366.264952 -11.850116)
		(end 366.264952 -1.999996)
		(stroke
			(width 0.05)
			(type default)
		)
		(layer "Edge.Cuts")
	)
	(gr_arc
		(start 368.264948 0)
		(mid 366.850705 -0.585768)
		(end 366.264952 -1.999996)
		(stroke
			(width 0.05)
			(type default)
		)
		(layer "Edge.Cuts")
	)
	(gr_line
		(start 368.264948 0)
		(end 380.264924 0)
		(stroke
			(width 0.05)
			(type default)
		)
		(layer "Edge.Cuts")
	)
	(gr_arc
		(start 382.26492 -11.850116)
		(mid 382.557813 -12.557221)
		(end 383.264918 -12.850114)
		(stroke
			(width 0.05)
			(type default)
		)
		(layer "Edge.Cuts")
	)
	(gr_arc
		(start 382.26492 -1.999996)
		(mid 381.679135 -0.585779)
		(end 380.264924 0)
		(stroke
			(width 0.05)
			(type default)
		)
		(layer "Edge.Cuts")
	)
	(gr_line
		(start 382.26492 -1.999996)
		(end 382.26492 -11.850116)
		(stroke
			(width 0.05)
			(type default)
		)
		(layer "Edge.Cuts")
	)
	(gr_line
		(start 383.264918 -12.850114)
		(end 391.264902 -12.850114)
		(stroke
			(width 0.05)
			(type default)
		)
		(layer "Edge.Cuts")
	)
	(gr_arc
		(start 391.264902 -12.850114)
		(mid 391.972007 -12.557221)
		(end 392.2649 -11.850116)
		(stroke
			(width 0.05)
			(type default)
		)
		(layer "Edge.Cuts")
	)
	(gr_line
		(start 392.2649 -11.850116)
		(end 392.2649 -1.999996)
		(stroke
			(width 0.05)
			(type default)
		)
		(layer "Edge.Cuts")
	)
	(gr_arc
		(start 394.264896 0)
		(mid 392.850686 -0.585786)
		(end 392.2649 -1.999996)
		(stroke
			(width 0.05)
			(type default)
		)
		(layer "Edge.Cuts")
	)
	(gr_line
		(start 394.264896 0)
		(end 406.265126 0)
		(stroke
			(width 0.05)
			(type default)
		)
		(layer "Edge.Cuts")
	)
	(gr_arc
		(start 408.265122 -11.850116)
		(mid 408.558015 -12.557221)
		(end 409.26512 -12.850114)
		(stroke
			(width 0.05)
			(type default)
		)
		(layer "Edge.Cuts")
	)
	(gr_arc
		(start 408.265122 -1.999996)
		(mid 407.679337 -0.585779)
		(end 406.265126 0)
		(stroke
			(width 0.05)
			(type default)
		)
		(layer "Edge.Cuts")
	)
	(gr_line
		(start 408.265122 -1.999996)
		(end 408.265122 -11.850116)
		(stroke
			(width 0.05)
			(type default)
		)
		(layer "Edge.Cuts")
	)
	(gr_line
		(start 409.26512 -12.850114)
		(end 417.265104 -12.850114)
		(stroke
			(width 0.05)
			(type default)
		)
		(layer "Edge.Cuts")
	)
	(gr_arc
		(start 417.265104 -12.850114)
		(mid 417.972209 -12.557221)
		(end 418.265102 -11.850116)
		(stroke
			(width 0.05)
			(type default)
		)
		(layer "Edge.Cuts")
	)
	(gr_line
		(start 418.265102 -11.850116)
		(end 418.265102 -1.999996)
		(stroke
			(width 0.05)
			(type default)
		)
		(layer "Edge.Cuts")
	)
	(gr_arc
		(start 420.265098 0)
		(mid 418.850887 -0.585786)
		(end 418.265102 -1.999996)
		(stroke
			(width 0.05)
			(type default)
		)
		(layer "Edge.Cuts")
	)
	(gr_line
		(start 420.265098 0)
		(end 432.265074 0)
		(stroke
			(width 0.05)
			(type default)
		)
		(layer "Edge.Cuts")
	)
	(gr_arc
		(start 434.26507 -11.850116)
		(mid 434.557963 -12.557221)
		(end 435.265068 -12.850114)
		(stroke
			(width 0.05)
			(type default)
		)
		(layer "Edge.Cuts")
	)
	(gr_arc
		(start 434.26507 -1.999996)
		(mid 433.679282 -0.585797)
		(end 432.265074 0)
		(stroke
			(width 0.05)
			(type default)
		)
		(layer "Edge.Cuts")
	)
	(gr_line
		(start 434.26507 -1.999996)
		(end 434.26507 -11.850116)
		(stroke
			(width 0.05)
			(type default)
		)
		(layer "Edge.Cuts")
	)
	(gr_line
		(start 435.265068 -12.850114)
		(end 443.265052 -12.850114)
		(stroke
			(width 0.05)
			(type default)
		)
		(layer "Edge.Cuts")
	)
	(gr_arc
		(start 443.265052 -12.850114)
		(mid 443.972157 -12.557221)
		(end 444.26505 -11.850116)
		(stroke
			(width 0.05)
			(type default)
		)
		(layer "Edge.Cuts")
	)
	(gr_line
		(start 444.26505 -11.850116)
		(end 444.26505 -1.999996)
		(stroke
			(width 0.05)
			(type default)
		)
		(layer "Edge.Cuts")
	)
	(gr_arc
		(start 446.265046 0)
		(mid 444.850804 -0.585769)
		(end 444.26505 -1.999996)
		(stroke
			(width 0.05)
			(type default)
		)
		(layer "Edge.Cuts")
	)
	(gr_line
		(start 446.265046 0)
		(end 465.600034 0)
		(stroke
			(width 0.05)
			(type default)
		)
		(layer "Edge.Cuts")
	)
	(gr_arc
		(start 463.799936 -241.031522)
		(mid 463.952279 -241.796931)
		(end 464.385914 -242.445794)
		(stroke
			(width 0.05)
			(type default)
		)
		(layer "Edge.Cuts")
	)
	(gr_line
		(start 463.799936 -87.588344)
		(end 463.799936 -241.031522)
		(stroke
			(width 0.05)
			(type default)
		)
		(layer "Edge.Cuts")
	)
	(gr_line
		(start 464.385914 -242.445794)
		(end 467.014306 -245.074186)
		(stroke
			(width 0.05)
			(type default)
		)
		(layer "Edge.Cuts")
	)
	(gr_arc
		(start 464.385914 -86.174326)
		(mid 463.952292 -86.823054)
		(end 463.799936 -87.588344)
		(stroke
			(width 0.05)
			(type default)
		)
		(layer "Edge.Cuts")
	)
	(gr_line
		(start 465.600034 -418.589968)
		(end 274.758658 -418.589968)
		(stroke
			(width 0.05)
			(type default)
		)
		(layer "Edge.Cuts")
	)
	(gr_arc
		(start 465.600034 -418.589968)
		(mid 467.014213 -418.004169)
		(end 467.60003 -416.589972)
		(stroke
			(width 0.05)
			(type default)
		)
		(layer "Edge.Cuts")
	)
	(gr_line
		(start 467.014306 -83.54568)
		(end 464.385914 -86.174326)
		(stroke
			(width 0.05)
			(type default)
		)
		(layer "Edge.Cuts")
	)
	(gr_arc
		(start 467.014306 -83.54568)
		(mid 467.447803 -82.896927)
		(end 467.60003 -82.131662)
		(stroke
			(width 0.05)
			(type default)
		)
		(layer "Edge.Cuts")
	)
	(gr_arc
		(start 467.60003 -246.488458)
		(mid 467.447879 -245.723043)
		(end 467.014306 -245.074186)
		(stroke
			(width 0.05)
			(type default)
		)
		(layer "Edge.Cuts")
	)
	(gr_line
		(start 467.60003 -246.488458)
		(end 467.60003 -416.589972)
		(stroke
			(width 0.05)
			(type default)
		)
		(layer "Edge.Cuts")
	)
	(gr_arc
		(start 467.60003 -1.999996)
		(mid 467.014245 -0.585776)
		(end 465.600034 0)
		(stroke
			(width 0.05)
			(type default)
		)
		(layer "Edge.Cuts")
	)
	(gr_line
		(start 467.60003 -1.999996)
		(end 467.60003 -82.131662)
		(stroke
			(width 0.05)
			(type default)
		)
		(layer "Edge.Cuts")
	)
	(gr_poly
		(pts
			(arc
				(start 265.615928 -377.679966)
				(mid 265.635451 -377.676065)
				(end 265.651996 -377.66498)
			)
			(arc
				(start 265.851386 -377.46559)
				(mid 265.862497 -377.449056)
				(end 265.866372 -377.429522)
			)
			(arc
				(start 265.866372 -368.884962)
				(mid 265.862471 -368.865439)
				(end 265.851386 -368.848894)
			)
			(arc
				(start 265.514582 -368.51209)
				(mid 265.498048 -368.500979)
				(end 265.478514 -368.497104)
			)
			(arc
				(start 242.901216 -368.497104)
				(mid 242.881693 -368.501005)
				(end 242.865148 -368.51209)
			)
			(arc
				(start 242.760754 -368.616484)
				(mid 242.749643 -368.633018)
				(end 242.745768 -368.652552)
			)
			(arc
				(start 242.745768 -377.268994)
				(mid 242.749669 -377.288517)
				(end 242.760754 -377.305062)
			)
			(arc
				(start 243.120672 -377.66498)
				(mid 243.137206 -377.676091)
				(end 243.15674 -377.679966)
			)
		)
		(stroke
			(width 0)
			(type solid)
		)
		(fill yes)
		(layer "In12.Cu")
		(net "P12V_STBY_R2")
	)
	(gr_poly
		(pts
			(arc
				(start 43.702986 -312.049922)
				(mid 43.296586 -312.049922)
				(end 43.702986 -312.049922)
			)
		)
		(stroke
			(width 0)
			(type solid)
		)
		(fill yes)
		(layer "In12.Cu")
		(net "P5E_PEX0_STN6_TX_DN<111>")
	)
	(gr_poly
		(pts
			(arc
				(start 43.702986 -311.099962)
				(mid 43.296586 -311.099962)
				(end 43.702986 -311.099962)
			)
		)
		(stroke
			(width 0)
			(type solid)
		)
		(fill yes)
		(layer "In12.Cu")
		(net "P5E_PEX0_STN6_TX_DP<111>")
	)
	(gr_poly
		(pts
			(arc
				(start 44.652946 -313.949842)
				(mid 44.246546 -313.949842)
				(end 44.652946 -313.949842)
			)
		)
		(stroke
			(width 0)
			(type solid)
		)
		(fill yes)
		(layer "In12.Cu")
		(net "P5E_PEX0_STN6_TX_DN<110>")
	)
	(gr_poly
		(pts
			(arc
				(start 44.652946 -312.999882)
				(mid 44.246546 -312.999882)
				(end 44.652946 -312.999882)
			)
		)
		(stroke
			(width 0)
			(type solid)
		)
		(fill yes)
		(layer "In12.Cu")
		(net "P5E_PEX0_STN6_TX_DP<110>")
	)
	(gr_poly
		(pts
			(arc
				(start 45.60316 -312.049922)
				(mid 45.19676 -312.049922)
				(end 45.60316 -312.049922)
			)
		)
		(stroke
			(width 0)
			(type solid)
		)
		(fill yes)
		(layer "In12.Cu")
		(net "P5E_PEX0_STN6_TX_DN<109>")
	)
	(gr_poly
		(pts
			(arc
				(start 45.60316 -311.099962)
				(mid 45.19676 -311.099962)
				(end 45.60316 -311.099962)
			)
		)
		(stroke
			(width 0)
			(type solid)
		)
		(fill yes)
		(layer "In12.Cu")
		(net "P5E_PEX0_STN6_TX_DP<109>")
	)
	(gr_poly
		(pts
			(arc
				(start 46.55312 -313.949842)
				(mid 46.14672 -313.949842)
				(end 46.55312 -313.949842)
			)
		)
		(stroke
			(width 0)
			(type solid)
		)
		(fill yes)
		(layer "In12.Cu")
		(net "P5E_PEX0_STN6_TX_DN<108>")
	)
	(gr_poly
		(pts
			(arc
				(start 46.55312 -312.999882)
				(mid 46.14672 -312.999882)
				(end 46.55312 -312.999882)
			)
		)
		(stroke
			(width 0)
			(type solid)
		)
		(fill yes)
		(layer "In12.Cu")
		(net "P5E_PEX0_STN6_TX_DP<108>")
	)
	(gr_poly
		(pts
			(arc
				(start 47.50308 -312.049922)
				(mid 47.09668 -312.049922)
				(end 47.50308 -312.049922)
			)
		)
		(stroke
			(width 0)
			(type solid)
		)
		(fill yes)
		(layer "In12.Cu")
		(net "P5E_PEX0_STN6_TX_DN<107>")
	)
	(gr_poly
		(pts
			(arc
				(start 47.50308 -311.099962)
				(mid 47.09668 -311.099962)
				(end 47.50308 -311.099962)
			)
		)
		(stroke
			(width 0)
			(type solid)
		)
		(fill yes)
		(layer "In12.Cu")
		(net "P5E_PEX0_STN6_TX_DP<107>")
	)
	(gr_poly
		(pts
			(arc
				(start 48.45304 -313.949842)
				(mid 48.04664 -313.949842)
				(end 48.45304 -313.949842)
			)
		)
		(stroke
			(width 0)
			(type solid)
		)
		(fill yes)
		(layer "In12.Cu")
		(net "P5E_PEX0_STN6_TX_DN<106>")
	)
	(gr_poly
		(pts
			(arc
				(start 48.45304 -312.999882)
				(mid 48.04664 -312.999882)
				(end 48.45304 -312.999882)
			)
		)
		(stroke
			(width 0)
			(type solid)
		)
		(fill yes)
		(layer "In12.Cu")
		(net "P5E_PEX0_STN6_TX_DP<106>")
	)
	(gr_poly
		(pts
			(arc
				(start 49.403 -312.049922)
				(mid 48.9966 -312.049922)
				(end 49.403 -312.049922)
			)
		)
		(stroke
			(width 0)
			(type solid)
		)
		(fill yes)
		(layer "In12.Cu")
		(net "P5E_PEX0_STN6_TX_DN<105>")
	)
	(gr_poly
		(pts
			(arc
				(start 49.403 -311.099962)
				(mid 48.9966 -311.099962)
				(end 49.403 -311.099962)
			)
		)
		(stroke
			(width 0)
			(type solid)
		)
		(fill yes)
		(layer "In12.Cu")
		(net "P5E_PEX0_STN6_TX_DP<105>")
	)
	(gr_poly
		(pts
			(arc
				(start 50.35296 -313.949842)
				(mid 49.94656 -313.949842)
				(end 50.35296 -313.949842)
			)
		)
		(stroke
			(width 0)
			(type solid)
		)
		(fill yes)
		(layer "In12.Cu")
		(net "P5E_PEX0_STN6_TX_DN<104>")
	)
	(gr_poly
		(pts
			(arc
				(start 50.35296 -312.999882)
				(mid 49.94656 -312.999882)
				(end 50.35296 -312.999882)
			)
		)
		(stroke
			(width 0)
			(type solid)
		)
		(fill yes)
		(layer "In12.Cu")
		(net "P5E_PEX0_STN6_TX_DP<104>")
	)
	(gr_poly
		(pts
			(arc
				(start 51.303174 -312.049922)
				(mid 50.896774 -312.049922)
				(end 51.303174 -312.049922)
			)
		)
		(stroke
			(width 0)
			(type solid)
		)
		(fill yes)
		(layer "In12.Cu")
		(net "P5E_PEX0_STN6_TX_DN<103>")
	)
	(gr_poly
		(pts
			(arc
				(start 51.303174 -311.099962)
				(mid 50.896774 -311.099962)
				(end 51.303174 -311.099962)
			)
		)
		(stroke
			(width 0)
			(type solid)
		)
		(fill yes)
		(layer "In12.Cu")
		(net "P5E_PEX0_STN6_TX_DP<103>")
	)
	(gr_poly
		(pts
			(arc
				(start 52.253134 -313.949842)
				(mid 51.846734 -313.949842)
				(end 52.253134 -313.949842)
			)
		)
		(stroke
			(width 0)
			(type solid)
		)
		(fill yes)
		(layer "In12.Cu")
		(net "P5E_PEX0_STN6_TX_DN<102>")
	)
	(gr_poly
		(pts
			(arc
				(start 52.253134 -312.999882)
				(mid 51.846734 -312.999882)
				(end 52.253134 -312.999882)
			)
		)
		(stroke
			(width 0)
			(type solid)
		)
		(fill yes)
		(layer "In12.Cu")
		(net "P5E_PEX0_STN6_TX_DP<102>")
	)
	(gr_poly
		(pts
			(arc
				(start 53.203094 -312.049922)
				(mid 52.796694 -312.049922)
				(end 53.203094 -312.049922)
			)
		)
		(stroke
			(width 0)
			(type solid)
		)
		(fill yes)
		(layer "In12.Cu")
		(net "P5E_PEX0_STN6_TX_DN<101>")
	)
	(gr_poly
		(pts
			(arc
				(start 53.203094 -311.099962)
				(mid 52.796694 -311.099962)
				(end 53.203094 -311.099962)
			)
		)
		(stroke
			(width 0)
			(type solid)
		)
		(fill yes)
		(layer "In12.Cu")
		(net "P5E_PEX0_STN6_TX_DP<101>")
	)
	(gr_poly
		(pts
			(arc
				(start 54.153054 -313.949842)
				(mid 53.746654 -313.949842)
				(end 54.153054 -313.949842)
			)
		)
		(stroke
			(width 0)
			(type solid)
		)
		(fill yes)
		(layer "In12.Cu")
		(net "P5E_PEX0_STN6_TX_DN<100>")
	)
	(gr_poly
		(pts
			(arc
				(start 54.153054 -312.999882)
				(mid 53.746654 -312.999882)
				(end 54.153054 -312.999882)
			)
		)
		(stroke
			(width 0)
			(type solid)
		)
		(fill yes)
		(layer "In12.Cu")
		(net "P5E_PEX0_STN6_TX_DP<100>")
	)
	(gr_poly
		(pts
			(arc
				(start 55.103014 -312.049922)
				(mid 54.696614 -312.049922)
				(end 55.103014 -312.049922)
			)
		)
		(stroke
			(width 0)
			(type solid)
		)
		(fill yes)
		(layer "In12.Cu")
		(net "P5E_PEX0_STN6_TX_DN<99>")
	)
	(gr_poly
		(pts
			(arc
				(start 55.103014 -311.099962)
				(mid 54.696614 -311.099962)
				(end 55.103014 -311.099962)
			)
		)
		(stroke
			(width 0)
			(type solid)
		)
		(fill yes)
		(layer "In12.Cu")
		(net "P5E_PEX0_STN6_TX_DP<99>")
	)
	(gr_poly
		(pts
			(arc
				(start 56.052974 -313.949842)
				(mid 55.646574 -313.949842)
				(end 56.052974 -313.949842)
			)
		)
		(stroke
			(width 0)
			(type solid)
		)
		(fill yes)
		(layer "In12.Cu")
		(net "P5E_PEX0_STN6_TX_DN<98>")
	)
	(gr_poly
		(pts
			(arc
				(start 56.052974 -312.999882)
				(mid 55.646574 -312.999882)
				(end 56.052974 -312.999882)
			)
		)
		(stroke
			(width 0)
			(type solid)
		)
		(fill yes)
		(layer "In12.Cu")
		(net "P5E_PEX0_STN6_TX_DP<98>")
	)
	(gr_poly
		(pts
			(arc
				(start 57.003188 -312.049922)
				(mid 56.596788 -312.049922)
				(end 57.003188 -312.049922)
			)
		)
		(stroke
			(width 0)
			(type solid)
		)
		(fill yes)
		(layer "In12.Cu")
		(net "P5E_PEX0_STN6_TX_DN<97>")
	)
	(gr_poly
		(pts
			(arc
				(start 57.003188 -311.099962)
				(mid 56.596788 -311.099962)
				(end 57.003188 -311.099962)
			)
		)
		(stroke
			(width 0)
			(type solid)
		)
		(fill yes)
		(layer "In12.Cu")
		(net "P5E_PEX0_STN6_TX_DP<97>")
	)
	(gr_poly
		(pts
			(arc
				(start 57.953148 -313.949842)
				(mid 57.546748 -313.949842)
				(end 57.953148 -313.949842)
			)
		)
		(stroke
			(width 0)
			(type solid)
		)
		(fill yes)
		(layer "In12.Cu")
		(net "P5E_PEX0_STN6_TX_DN<96>")
	)
	(gr_poly
		(pts
			(arc
				(start 57.953148 -312.999882)
				(mid 57.546748 -312.999882)
				(end 57.953148 -312.999882)
			)
		)
		(stroke
			(width 0)
			(type solid)
		)
		(fill yes)
		(layer "In12.Cu")
		(net "P5E_PEX0_STN6_TX_DP<96>")
	)
	(gr_poly
		(pts
			(arc
				(start 74.102976 -316.799722)
				(mid 73.696576 -316.799722)
				(end 74.102976 -316.799722)
			)
		)
		(stroke
			(width 0)
			(type solid)
		)
		(fill yes)
		(layer "In12.Cu")
		(net "P5E_PEX0_STN4_RX_DN<79>")
	)
	(gr_poly
		(pts
			(arc
				(start 74.102976 -315.849762)
				(mid 73.696576 -315.849762)
				(end 74.102976 -315.849762)
			)
		)
		(stroke
			(width 0)
			(type solid)
		)
		(fill yes)
		(layer "In12.Cu")
		(net "P5E_PEX0_STN4_RX_DP<79>")
	)
	(gr_poly
		(pts
			(arc
				(start 75.05319 -318.699896)
				(mid 74.64679 -318.699896)
				(end 75.05319 -318.699896)
			)
		)
		(stroke
			(width 0)
			(type solid)
		)
		(fill yes)
		(layer "In12.Cu")
		(net "P5E_PEX0_STN4_RX_DN<78>")
	)
	(gr_poly
		(pts
			(arc
				(start 75.05319 -317.749936)
				(mid 74.64679 -317.749936)
				(end 75.05319 -317.749936)
			)
		)
		(stroke
			(width 0)
			(type solid)
		)
		(fill yes)
		(layer "In12.Cu")
		(net "P5E_PEX0_STN4_RX_DP<78>")
	)
	(gr_poly
		(pts
			(arc
				(start 76.00315 -316.799722)
				(mid 75.59675 -316.799722)
				(end 76.00315 -316.799722)
			)
		)
		(stroke
			(width 0)
			(type solid)
		)
		(fill yes)
		(layer "In12.Cu")
		(net "P5E_PEX0_STN4_RX_DN<77>")
	)
	(gr_poly
		(pts
			(arc
				(start 76.00315 -315.849762)
				(mid 75.59675 -315.849762)
				(end 76.00315 -315.849762)
			)
		)
		(stroke
			(width 0)
			(type solid)
		)
		(fill yes)
		(layer "In12.Cu")
		(net "P5E_PEX0_STN4_RX_DP<77>")
	)
	(gr_poly
		(pts
			(arc
				(start 76.95311 -318.699896)
				(mid 76.54671 -318.699896)
				(end 76.95311 -318.699896)
			)
		)
		(stroke
			(width 0)
			(type solid)
		)
		(fill yes)
		(layer "In12.Cu")
		(net "P5E_PEX0_STN4_RX_DN<76>")
	)
	(gr_poly
		(pts
			(arc
				(start 76.95311 -317.749936)
				(mid 76.54671 -317.749936)
				(end 76.95311 -317.749936)
			)
		)
		(stroke
			(width 0)
			(type solid)
		)
		(fill yes)
		(layer "In12.Cu")
		(net "P5E_PEX0_STN4_RX_DP<76>")
	)
	(gr_poly
		(pts
			(arc
				(start 77.90307 -316.799722)
				(mid 77.49667 -316.799722)
				(end 77.90307 -316.799722)
			)
		)
		(stroke
			(width 0)
			(type solid)
		)
		(fill yes)
		(layer "In12.Cu")
		(net "P5E_PEX0_STN4_RX_DN<75>")
	)
	(gr_poly
		(pts
			(arc
				(start 77.90307 -315.849762)
				(mid 77.49667 -315.849762)
				(end 77.90307 -315.849762)
			)
		)
		(stroke
			(width 0)
			(type solid)
		)
		(fill yes)
		(layer "In12.Cu")
		(net "P5E_PEX0_STN4_RX_DP<75>")
	)
	(gr_poly
		(pts
			(arc
				(start 78.85303 -318.699896)
				(mid 78.44663 -318.699896)
				(end 78.85303 -318.699896)
			)
		)
		(stroke
			(width 0)
			(type solid)
		)
		(fill yes)
		(layer "In12.Cu")
		(net "P5E_PEX0_STN4_RX_DN<74>")
	)
	(gr_poly
		(pts
			(arc
				(start 78.85303 -317.749936)
				(mid 78.44663 -317.749936)
				(end 78.85303 -317.749936)
			)
		)
		(stroke
			(width 0)
			(type solid)
		)
		(fill yes)
		(layer "In12.Cu")
		(net "P5E_PEX0_STN4_RX_DP<74>")
	)
	(gr_poly
		(pts
			(arc
				(start 79.80299 -316.799722)
				(mid 79.39659 -316.799722)
				(end 79.80299 -316.799722)
			)
		)
		(stroke
			(width 0)
			(type solid)
		)
		(fill yes)
		(layer "In12.Cu")
		(net "P5E_PEX0_STN4_RX_DN<73>")
	)
	(gr_poly
		(pts
			(arc
				(start 79.80299 -315.849762)
				(mid 79.39659 -315.849762)
				(end 79.80299 -315.849762)
			)
		)
		(stroke
			(width 0)
			(type solid)
		)
		(fill yes)
		(layer "In12.Cu")
		(net "P5E_PEX0_STN4_RX_DP<73>")
	)
	(gr_poly
		(pts
			(arc
				(start 79.80299 -309.199788)
				(mid 79.39659 -309.199788)
				(end 79.80299 -309.199788)
			)
		)
		(stroke
			(width 0)
			(type solid)
		)
		(fill yes)
		(layer "In12.Cu")
		(net "P5E_PEX0_STN4_RX_DP<69>")
	)
	(gr_poly
		(pts
			(arc
				(start 79.80299 -307.299868)
				(mid 79.39659 -307.299868)
				(end 79.80299 -307.299868)
			)
		)
		(stroke
			(width 0)
			(type solid)
		)
		(fill yes)
		(layer "In12.Cu")
		(net "P5E_PEX0_STN4_RX_DP<67>")
	)
	(gr_poly
		(pts
			(arc
				(start 79.80299 -305.399948)
				(mid 79.39659 -305.399948)
				(end 79.80299 -305.399948)
			)
		)
		(stroke
			(width 0)
			(type solid)
		)
		(fill yes)
		(layer "In12.Cu")
		(net "P5E_PEX0_STN4_RX_DP<65>")
	)
	(gr_poly
		(pts
			(arc
				(start 80.75295 -318.699896)
				(mid 80.34655 -318.699896)
				(end 80.75295 -318.699896)
			)
		)
		(stroke
			(width 0)
			(type solid)
		)
		(fill yes)
		(layer "In12.Cu")
		(net "P5E_PEX0_STN4_RX_DN<72>")
	)
	(gr_poly
		(pts
			(arc
				(start 80.75295 -317.749936)
				(mid 80.34655 -317.749936)
				(end 80.75295 -317.749936)
			)
		)
		(stroke
			(width 0)
			(type solid)
		)
		(fill yes)
		(layer "In12.Cu")
		(net "P5E_PEX0_STN4_RX_DP<72>")
	)
	(gr_poly
		(pts
			(arc
				(start 80.75295 -309.199788)
				(mid 80.34655 -309.199788)
				(end 80.75295 -309.199788)
			)
		)
		(stroke
			(width 0)
			(type solid)
		)
		(fill yes)
		(layer "In12.Cu")
		(net "P5E_PEX0_STN4_RX_DN<69>")
	)
	(gr_poly
		(pts
			(arc
				(start 80.75295 -307.299868)
				(mid 80.34655 -307.299868)
				(end 80.75295 -307.299868)
			)
		)
		(stroke
			(width 0)
			(type solid)
		)
		(fill yes)
		(layer "In12.Cu")
		(net "P5E_PEX0_STN4_RX_DN<67>")
	)
	(gr_poly
		(pts
			(arc
				(start 80.75295 -305.399948)
				(mid 80.34655 -305.399948)
				(end 80.75295 -305.399948)
			)
		)
		(stroke
			(width 0)
			(type solid)
		)
		(fill yes)
		(layer "In12.Cu")
		(net "P5E_PEX0_STN4_RX_DN<65>")
	)
	(gr_poly
		(pts
			(arc
				(start 81.703164 -316.799722)
				(mid 81.296764 -316.799722)
				(end 81.703164 -316.799722)
			)
		)
		(stroke
			(width 0)
			(type solid)
		)
		(fill yes)
		(layer "In12.Cu")
		(net "P5E_PEX0_STN4_RX_DP<71>")
	)
	(gr_poly
		(pts
			(arc
				(start 81.703164 -310.149748)
				(mid 81.296764 -310.149748)
				(end 81.703164 -310.149748)
			)
		)
		(stroke
			(width 0)
			(type solid)
		)
		(fill yes)
		(layer "In12.Cu")
		(net "P5E_PEX0_STN4_RX_DP<70>")
	)
	(gr_poly
		(pts
			(arc
				(start 81.703164 -308.249828)
				(mid 81.296764 -308.249828)
				(end 81.703164 -308.249828)
			)
		)
		(stroke
			(width 0)
			(type solid)
		)
		(fill yes)
		(layer "In12.Cu")
		(net "P5E_PEX0_STN4_RX_DP<68>")
	)
	(gr_poly
		(pts
			(arc
				(start 81.703164 -306.349908)
				(mid 81.296764 -306.349908)
				(end 81.703164 -306.349908)
			)
		)
		(stroke
			(width 0)
			(type solid)
		)
		(fill yes)
		(layer "In12.Cu")
		(net "P5E_PEX0_STN4_RX_DP<66>")
	)
	(gr_poly
		(pts
			(arc
				(start 81.703164 -304.449734)
				(mid 81.296764 -304.449734)
				(end 81.703164 -304.449734)
			)
		)
		(stroke
			(width 0)
			(type solid)
		)
		(fill yes)
		(layer "In12.Cu")
		(net "P5E_PEX0_STN4_RX_DP<64>")
	)
	(gr_poly
		(pts
			(arc
				(start 82.653124 -316.799722)
				(mid 82.246724 -316.799722)
				(end 82.653124 -316.799722)
			)
		)
		(stroke
			(width 0)
			(type solid)
		)
		(fill yes)
		(layer "In12.Cu")
		(net "P5E_PEX0_STN4_RX_DN<71>")
	)
	(gr_poly
		(pts
			(arc
				(start 82.653124 -310.149748)
				(mid 82.246724 -310.149748)
				(end 82.653124 -310.149748)
			)
		)
		(stroke
			(width 0)
			(type solid)
		)
		(fill yes)
		(layer "In12.Cu")
		(net "P5E_PEX0_STN4_RX_DN<70>")
	)
	(gr_poly
		(pts
			(arc
				(start 82.653124 -308.249828)
				(mid 82.246724 -308.249828)
				(end 82.653124 -308.249828)
			)
		)
		(stroke
			(width 0)
			(type solid)
		)
		(fill yes)
		(layer "In12.Cu")
		(net "P5E_PEX0_STN4_RX_DN<68>")
	)
	(gr_poly
		(pts
			(arc
				(start 82.653124 -306.349908)
				(mid 82.246724 -306.349908)
				(end 82.653124 -306.349908)
			)
		)
		(stroke
			(width 0)
			(type solid)
		)
		(fill yes)
		(layer "In12.Cu")
		(net "P5E_PEX0_STN4_RX_DN<66>")
	)
	(gr_poly
		(pts
			(arc
				(start 82.653124 -304.449734)
				(mid 82.246724 -304.449734)
				(end 82.653124 -304.449734)
			)
		)
		(stroke
			(width 0)
			(type solid)
		)
		(fill yes)
		(layer "In12.Cu")
		(net "P5E_PEX0_STN4_RX_DN<64>")
	)
	(gr_poly
		(pts
			(arc
				(start 159.803084 -316.799722)
				(mid 159.396684 -316.799722)
				(end 159.803084 -316.799722)
			)
		)
		(stroke
			(width 0)
			(type solid)
		)
		(fill yes)
		(layer "In12.Cu")
		(net "P5E_PEX1_STN6_RX_DN<111>")
	)
	(gr_poly
		(pts
			(arc
				(start 159.803084 -315.849762)
				(mid 159.396684 -315.849762)
				(end 159.803084 -315.849762)
			)
		)
		(stroke
			(width 0)
			(type solid)
		)
		(fill yes)
		(layer "In12.Cu")
		(net "P5E_PEX1_STN6_RX_DP<111>")
	)
	(gr_poly
		(pts
			(arc
				(start 159.803084 -312.049922)
				(mid 159.396684 -312.049922)
				(end 159.803084 -312.049922)
			)
		)
		(stroke
			(width 0)
			(type solid)
		)
		(fill yes)
		(layer "In12.Cu")
		(net "P5E_PEX1_STN6_TX_DN<111>")
	)
	(gr_poly
		(pts
			(arc
				(start 159.803084 -311.099962)
				(mid 159.396684 -311.099962)
				(end 159.803084 -311.099962)
			)
		)
		(stroke
			(width 0)
			(type solid)
		)
		(fill yes)
		(layer "In12.Cu")
		(net "P5E_PEX1_STN6_TX_DP<111>")
	)
	(gr_poly
		(pts
			(arc
				(start 160.753044 -318.699896)
				(mid 160.346644 -318.699896)
				(end 160.753044 -318.699896)
			)
		)
		(stroke
			(width 0)
			(type solid)
		)
		(fill yes)
		(layer "In12.Cu")
		(net "P5E_PEX1_STN6_RX_DN<110>")
	)
	(gr_poly
		(pts
			(arc
				(start 160.753044 -317.749936)
				(mid 160.346644 -317.749936)
				(end 160.753044 -317.749936)
			)
		)
		(stroke
			(width 0)
			(type solid)
		)
		(fill yes)
		(layer "In12.Cu")
		(net "P5E_PEX1_STN6_RX_DP<110>")
	)
	(gr_poly
		(pts
			(arc
				(start 160.753044 -313.949842)
				(mid 160.346644 -313.949842)
				(end 160.753044 -313.949842)
			)
		)
		(stroke
			(width 0)
			(type solid)
		)
		(fill yes)
		(layer "In12.Cu")
		(net "P5E_PEX1_STN6_TX_DN<110>")
	)
	(gr_poly
		(pts
			(arc
				(start 160.753044 -312.999882)
				(mid 160.346644 -312.999882)
				(end 160.753044 -312.999882)
			)
		)
		(stroke
			(width 0)
			(type solid)
		)
		(fill yes)
		(layer "In12.Cu")
		(net "P5E_PEX1_STN6_TX_DP<110>")
	)
	(gr_poly
		(pts
			(arc
				(start 161.703258 -316.799722)
				(mid 161.296858 -316.799722)
				(end 161.703258 -316.799722)
			)
		)
		(stroke
			(width 0)
			(type solid)
		)
		(fill yes)
		(layer "In12.Cu")
		(net "P5E_PEX1_STN6_RX_DN<109>")
	)
	(gr_poly
		(pts
			(arc
				(start 161.703258 -315.849762)
				(mid 161.296858 -315.849762)
				(end 161.703258 -315.849762)
			)
		)
		(stroke
			(width 0)
			(type solid)
		)
		(fill yes)
		(layer "In12.Cu")
		(net "P5E_PEX1_STN6_RX_DP<109>")
	)
	(gr_poly
		(pts
			(arc
				(start 161.703258 -312.049922)
				(mid 161.296858 -312.049922)
				(end 161.703258 -312.049922)
			)
		)
		(stroke
			(width 0)
			(type solid)
		)
		(fill yes)
		(layer "In12.Cu")
		(net "P5E_PEX1_STN6_TX_DN<109>")
	)
	(gr_poly
		(pts
			(arc
				(start 161.703258 -311.099962)
				(mid 161.296858 -311.099962)
				(end 161.703258 -311.099962)
			)
		)
		(stroke
			(width 0)
			(type solid)
		)
		(fill yes)
		(layer "In12.Cu")
		(net "P5E_PEX1_STN6_TX_DP<109>")
	)
	(gr_poly
		(pts
			(arc
				(start 162.653218 -318.699896)
				(mid 162.246818 -318.699896)
				(end 162.653218 -318.699896)
			)
		)
		(stroke
			(width 0)
			(type solid)
		)
		(fill yes)
		(layer "In12.Cu")
		(net "P5E_PEX1_STN6_RX_DN<108>")
	)
	(gr_poly
		(pts
			(arc
				(start 162.653218 -317.749936)
				(mid 162.246818 -317.749936)
				(end 162.653218 -317.749936)
			)
		)
		(stroke
			(width 0)
			(type solid)
		)
		(fill yes)
		(layer "In12.Cu")
		(net "P5E_PEX1_STN6_RX_DP<108>")
	)
	(gr_poly
		(pts
			(arc
				(start 162.653218 -313.949842)
				(mid 162.246818 -313.949842)
				(end 162.653218 -313.949842)
			)
		)
		(stroke
			(width 0)
			(type solid)
		)
		(fill yes)
		(layer "In12.Cu")
		(net "P5E_PEX1_STN6_TX_DN<108>")
	)
	(gr_poly
		(pts
			(arc
				(start 162.653218 -312.999882)
				(mid 162.246818 -312.999882)
				(end 162.653218 -312.999882)
			)
		)
		(stroke
			(width 0)
			(type solid)
		)
		(fill yes)
		(layer "In12.Cu")
		(net "P5E_PEX1_STN6_TX_DP<108>")
	)
	(gr_poly
		(pts
			(arc
				(start 163.603178 -316.799722)
				(mid 163.196778 -316.799722)
				(end 163.603178 -316.799722)
			)
		)
		(stroke
			(width 0)
			(type solid)
		)
		(fill yes)
		(layer "In12.Cu")
		(net "P5E_PEX1_STN6_RX_DN<107>")
	)
	(gr_poly
		(pts
			(arc
				(start 163.603178 -315.849762)
				(mid 163.196778 -315.849762)
				(end 163.603178 -315.849762)
			)
		)
		(stroke
			(width 0)
			(type solid)
		)
		(fill yes)
		(layer "In12.Cu")
		(net "P5E_PEX1_STN6_RX_DP<107>")
	)
	(gr_poly
		(pts
			(arc
				(start 163.603178 -312.049922)
				(mid 163.196778 -312.049922)
				(end 163.603178 -312.049922)
			)
		)
		(stroke
			(width 0)
			(type solid)
		)
		(fill yes)
		(layer "In12.Cu")
		(net "P5E_PEX1_STN6_TX_DN<107>")
	)
	(gr_poly
		(pts
			(arc
				(start 163.603178 -311.099962)
				(mid 163.196778 -311.099962)
				(end 163.603178 -311.099962)
			)
		)
		(stroke
			(width 0)
			(type solid)
		)
		(fill yes)
		(layer "In12.Cu")
		(net "P5E_PEX1_STN6_TX_DP<107>")
	)
	(gr_poly
		(pts
			(arc
				(start 164.553138 -318.699896)
				(mid 164.146738 -318.699896)
				(end 164.553138 -318.699896)
			)
		)
		(stroke
			(width 0)
			(type solid)
		)
		(fill yes)
		(layer "In12.Cu")
		(net "P5E_PEX1_STN6_RX_DN<106>")
	)
	(gr_poly
		(pts
			(arc
				(start 164.553138 -317.749936)
				(mid 164.146738 -317.749936)
				(end 164.553138 -317.749936)
			)
		)
		(stroke
			(width 0)
			(type solid)
		)
		(fill yes)
		(layer "In12.Cu")
		(net "P5E_PEX1_STN6_RX_DP<106>")
	)
	(gr_poly
		(pts
			(arc
				(start 164.553138 -313.949842)
				(mid 164.146738 -313.949842)
				(end 164.553138 -313.949842)
			)
		)
		(stroke
			(width 0)
			(type solid)
		)
		(fill yes)
		(layer "In12.Cu")
		(net "P5E_PEX1_STN6_TX_DN<106>")
	)
	(gr_poly
		(pts
			(arc
				(start 164.553138 -312.999882)
				(mid 164.146738 -312.999882)
				(end 164.553138 -312.999882)
			)
		)
		(stroke
			(width 0)
			(type solid)
		)
		(fill yes)
		(layer "In12.Cu")
		(net "P5E_PEX1_STN6_TX_DP<106>")
	)
	(gr_poly
		(pts
			(arc
				(start 165.503098 -316.799722)
				(mid 165.096698 -316.799722)
				(end 165.503098 -316.799722)
			)
		)
		(stroke
			(width 0)
			(type solid)
		)
		(fill yes)
		(layer "In12.Cu")
		(net "P5E_PEX1_STN6_RX_DN<105>")
	)
	(gr_poly
		(pts
			(arc
				(start 165.503098 -315.849762)
				(mid 165.096698 -315.849762)
				(end 165.503098 -315.849762)
			)
		)
		(stroke
			(width 0)
			(type solid)
		)
		(fill yes)
		(layer "In12.Cu")
		(net "P5E_PEX1_STN6_RX_DP<105>")
	)
	(gr_poly
		(pts
			(arc
				(start 165.503098 -312.049922)
				(mid 165.096698 -312.049922)
				(end 165.503098 -312.049922)
			)
		)
		(stroke
			(width 0)
			(type solid)
		)
		(fill yes)
		(layer "In12.Cu")
		(net "P5E_PEX1_STN6_TX_DN<105>")
	)
	(gr_poly
		(pts
			(arc
				(start 165.503098 -311.099962)
				(mid 165.096698 -311.099962)
				(end 165.503098 -311.099962)
			)
		)
		(stroke
			(width 0)
			(type solid)
		)
		(fill yes)
		(layer "In12.Cu")
		(net "P5E_PEX1_STN6_TX_DP<105>")
	)
	(gr_poly
		(pts
			(arc
				(start 166.453058 -318.699896)
				(mid 166.046658 -318.699896)
				(end 166.453058 -318.699896)
			)
		)
		(stroke
			(width 0)
			(type solid)
		)
		(fill yes)
		(layer "In12.Cu")
		(net "P5E_PEX1_STN6_RX_DN<104>")
	)
	(gr_poly
		(pts
			(arc
				(start 166.453058 -317.749936)
				(mid 166.046658 -317.749936)
				(end 166.453058 -317.749936)
			)
		)
		(stroke
			(width 0)
			(type solid)
		)
		(fill yes)
		(layer "In12.Cu")
		(net "P5E_PEX1_STN6_RX_DP<104>")
	)
	(gr_poly
		(pts
			(arc
				(start 166.453058 -313.949842)
				(mid 166.046658 -313.949842)
				(end 166.453058 -313.949842)
			)
		)
		(stroke
			(width 0)
			(type solid)
		)
		(fill yes)
		(layer "In12.Cu")
		(net "P5E_PEX1_STN6_TX_DN<104>")
	)
	(gr_poly
		(pts
			(arc
				(start 166.453058 -312.999882)
				(mid 166.046658 -312.999882)
				(end 166.453058 -312.999882)
			)
		)
		(stroke
			(width 0)
			(type solid)
		)
		(fill yes)
		(layer "In12.Cu")
		(net "P5E_PEX1_STN6_TX_DP<104>")
	)
	(gr_poly
		(pts
			(arc
				(start 182.60314 -316.799722)
				(mid 182.19674 -316.799722)
				(end 182.60314 -316.799722)
			)
		)
		(stroke
			(width 0)
			(type solid)
		)
		(fill yes)
		(layer "In12.Cu")
		(net "P5E_PEX1_STN5_RX_DN<88>")
	)
	(gr_poly
		(pts
			(arc
				(start 182.60314 -315.849762)
				(mid 182.19674 -315.849762)
				(end 182.60314 -315.849762)
			)
		)
		(stroke
			(width 0)
			(type solid)
		)
		(fill yes)
		(layer "In12.Cu")
		(net "P5E_PEX1_STN5_RX_DP<88>")
	)
	(gr_poly
		(pts
			(arc
				(start 182.60314 -312.049922)
				(mid 182.19674 -312.049922)
				(end 182.60314 -312.049922)
			)
		)
		(stroke
			(width 0)
			(type solid)
		)
		(fill yes)
		(layer "In12.Cu")
		(net "P5E_PEX1_STN5_TX_DN<88>")
	)
	(gr_poly
		(pts
			(arc
				(start 182.60314 -311.099962)
				(mid 182.19674 -311.099962)
				(end 182.60314 -311.099962)
			)
		)
		(stroke
			(width 0)
			(type solid)
		)
		(fill yes)
		(layer "In12.Cu")
		(net "P5E_PEX1_STN5_TX_DP<88>")
	)
	(gr_poly
		(pts
			(arc
				(start 183.5531 -318.699896)
				(mid 183.1467 -318.699896)
				(end 183.5531 -318.699896)
			)
		)
		(stroke
			(width 0)
			(type solid)
		)
		(fill yes)
		(layer "In12.Cu")
		(net "P5E_PEX1_STN5_RX_DN<89>")
	)
	(gr_poly
		(pts
			(arc
				(start 183.5531 -317.749936)
				(mid 183.1467 -317.749936)
				(end 183.5531 -317.749936)
			)
		)
		(stroke
			(width 0)
			(type solid)
		)
		(fill yes)
		(layer "In12.Cu")
		(net "P5E_PEX1_STN5_RX_DP<89>")
	)
	(gr_poly
		(pts
			(arc
				(start 183.5531 -313.949842)
				(mid 183.1467 -313.949842)
				(end 183.5531 -313.949842)
			)
		)
		(stroke
			(width 0)
			(type solid)
		)
		(fill yes)
		(layer "In12.Cu")
		(net "P5E_PEX1_STN5_TX_DN<89>")
	)
	(gr_poly
		(pts
			(arc
				(start 183.5531 -312.999882)
				(mid 183.1467 -312.999882)
				(end 183.5531 -312.999882)
			)
		)
		(stroke
			(width 0)
			(type solid)
		)
		(fill yes)
		(layer "In12.Cu")
		(net "P5E_PEX1_STN5_TX_DP<89>")
	)
	(gr_poly
		(pts
			(arc
				(start 184.50306 -316.799722)
				(mid 184.09666 -316.799722)
				(end 184.50306 -316.799722)
			)
		)
		(stroke
			(width 0)
			(type solid)
		)
		(fill yes)
		(layer "In12.Cu")
		(net "P5E_PEX1_STN5_RX_DN<90>")
	)
	(gr_poly
		(pts
			(arc
				(start 184.50306 -315.849762)
				(mid 184.09666 -315.849762)
				(end 184.50306 -315.849762)
			)
		)
		(stroke
			(width 0)
			(type solid)
		)
		(fill yes)
		(layer "In12.Cu")
		(net "P5E_PEX1_STN5_RX_DP<90>")
	)
	(gr_poly
		(pts
			(arc
				(start 184.50306 -312.049922)
				(mid 184.09666 -312.049922)
				(end 184.50306 -312.049922)
			)
		)
		(stroke
			(width 0)
			(type solid)
		)
		(fill yes)
		(layer "In12.Cu")
		(net "P5E_PEX1_STN5_TX_DN<90>")
	)
	(gr_poly
		(pts
			(arc
				(start 184.50306 -311.099962)
				(mid 184.09666 -311.099962)
				(end 184.50306 -311.099962)
			)
		)
		(stroke
			(width 0)
			(type solid)
		)
		(fill yes)
		(layer "In12.Cu")
		(net "P5E_PEX1_STN5_TX_DP<90>")
	)
	(gr_poly
		(pts
			(arc
				(start 185.453274 -318.699896)
				(mid 185.046874 -318.699896)
				(end 185.453274 -318.699896)
			)
		)
		(stroke
			(width 0)
			(type solid)
		)
		(fill yes)
		(layer "In12.Cu")
		(net "P5E_PEX1_STN5_RX_DN<91>")
	)
	(gr_poly
		(pts
			(arc
				(start 185.453274 -317.749936)
				(mid 185.046874 -317.749936)
				(end 185.453274 -317.749936)
			)
		)
		(stroke
			(width 0)
			(type solid)
		)
		(fill yes)
		(layer "In12.Cu")
		(net "P5E_PEX1_STN5_RX_DP<91>")
	)
	(gr_poly
		(pts
			(arc
				(start 185.453274 -313.949842)
				(mid 185.046874 -313.949842)
				(end 185.453274 -313.949842)
			)
		)
		(stroke
			(width 0)
			(type solid)
		)
		(fill yes)
		(layer "In12.Cu")
		(net "P5E_PEX1_STN5_TX_DN<91>")
	)
	(gr_poly
		(pts
			(arc
				(start 185.453274 -312.999882)
				(mid 185.046874 -312.999882)
				(end 185.453274 -312.999882)
			)
		)
		(stroke
			(width 0)
			(type solid)
		)
		(fill yes)
		(layer "In12.Cu")
		(net "P5E_PEX1_STN5_TX_DP<91>")
	)
	(gr_poly
		(pts
			(arc
				(start 186.403234 -316.799722)
				(mid 185.996834 -316.799722)
				(end 186.403234 -316.799722)
			)
		)
		(stroke
			(width 0)
			(type solid)
		)
		(fill yes)
		(layer "In12.Cu")
		(net "P5E_PEX1_STN5_RX_DN<92>")
	)
	(gr_poly
		(pts
			(arc
				(start 186.403234 -315.849762)
				(mid 185.996834 -315.849762)
				(end 186.403234 -315.849762)
			)
		)
		(stroke
			(width 0)
			(type solid)
		)
		(fill yes)
		(layer "In12.Cu")
		(net "P5E_PEX1_STN5_RX_DP<92>")
	)
	(gr_poly
		(pts
			(arc
				(start 186.403234 -312.049922)
				(mid 185.996834 -312.049922)
				(end 186.403234 -312.049922)
			)
		)
		(stroke
			(width 0)
			(type solid)
		)
		(fill yes)
		(layer "In12.Cu")
		(net "P5E_PEX1_STN5_TX_DN<92>")
	)
	(gr_poly
		(pts
			(arc
				(start 186.403234 -311.099962)
				(mid 185.996834 -311.099962)
				(end 186.403234 -311.099962)
			)
		)
		(stroke
			(width 0)
			(type solid)
		)
		(fill yes)
		(layer "In12.Cu")
		(net "P5E_PEX1_STN5_TX_DP<92>")
	)
	(gr_poly
		(pts
			(arc
				(start 187.353194 -318.699896)
				(mid 186.946794 -318.699896)
				(end 187.353194 -318.699896)
			)
		)
		(stroke
			(width 0)
			(type solid)
		)
		(fill yes)
		(layer "In12.Cu")
		(net "P5E_PEX1_STN5_RX_DN<93>")
	)
	(gr_poly
		(pts
			(arc
				(start 187.353194 -317.749936)
				(mid 186.946794 -317.749936)
				(end 187.353194 -317.749936)
			)
		)
		(stroke
			(width 0)
			(type solid)
		)
		(fill yes)
		(layer "In12.Cu")
		(net "P5E_PEX1_STN5_RX_DP<93>")
	)
	(gr_poly
		(pts
			(arc
				(start 187.353194 -313.949842)
				(mid 186.946794 -313.949842)
				(end 187.353194 -313.949842)
			)
		)
		(stroke
			(width 0)
			(type solid)
		)
		(fill yes)
		(layer "In12.Cu")
		(net "P5E_PEX1_STN5_TX_DN<93>")
	)
	(gr_poly
		(pts
			(arc
				(start 187.353194 -312.999882)
				(mid 186.946794 -312.999882)
				(end 187.353194 -312.999882)
			)
		)
		(stroke
			(width 0)
			(type solid)
		)
		(fill yes)
		(layer "In12.Cu")
		(net "P5E_PEX1_STN5_TX_DP<93>")
	)
	(gr_poly
		(pts
			(arc
				(start 188.303154 -316.799722)
				(mid 187.896754 -316.799722)
				(end 188.303154 -316.799722)
			)
		)
		(stroke
			(width 0)
			(type solid)
		)
		(fill yes)
		(layer "In12.Cu")
		(net "P5E_PEX1_STN5_RX_DN<94>")
	)
	(gr_poly
		(pts
			(arc
				(start 188.303154 -315.849762)
				(mid 187.896754 -315.849762)
				(end 188.303154 -315.849762)
			)
		)
		(stroke
			(width 0)
			(type solid)
		)
		(fill yes)
		(layer "In12.Cu")
		(net "P5E_PEX1_STN5_RX_DP<94>")
	)
	(gr_poly
		(pts
			(arc
				(start 188.303154 -312.049922)
				(mid 187.896754 -312.049922)
				(end 188.303154 -312.049922)
			)
		)
		(stroke
			(width 0)
			(type solid)
		)
		(fill yes)
		(layer "In12.Cu")
		(net "P5E_PEX1_STN5_TX_DN<94>")
	)
	(gr_poly
		(pts
			(arc
				(start 188.303154 -311.099962)
				(mid 187.896754 -311.099962)
				(end 188.303154 -311.099962)
			)
		)
		(stroke
			(width 0)
			(type solid)
		)
		(fill yes)
		(layer "In12.Cu")
		(net "P5E_PEX1_STN5_TX_DP<94>")
	)
	(gr_poly
		(pts
			(arc
				(start 189.253114 -318.699896)
				(mid 188.846714 -318.699896)
				(end 189.253114 -318.699896)
			)
		)
		(stroke
			(width 0)
			(type solid)
		)
		(fill yes)
		(layer "In12.Cu")
		(net "P5E_PEX1_STN5_RX_DN<95>")
	)
	(gr_poly
		(pts
			(arc
				(start 189.253114 -317.749936)
				(mid 188.846714 -317.749936)
				(end 189.253114 -317.749936)
			)
		)
		(stroke
			(width 0)
			(type solid)
		)
		(fill yes)
		(layer "In12.Cu")
		(net "P5E_PEX1_STN5_RX_DP<95>")
	)
	(gr_poly
		(pts
			(arc
				(start 189.253114 -313.949842)
				(mid 188.846714 -313.949842)
				(end 189.253114 -313.949842)
			)
		)
		(stroke
			(width 0)
			(type solid)
		)
		(fill yes)
		(layer "In12.Cu")
		(net "P5E_PEX1_STN5_TX_DN<95>")
	)
	(gr_poly
		(pts
			(arc
				(start 189.253114 -312.999882)
				(mid 188.846714 -312.999882)
				(end 189.253114 -312.999882)
			)
		)
		(stroke
			(width 0)
			(type solid)
		)
		(fill yes)
		(layer "In12.Cu")
		(net "P5E_PEX1_STN5_TX_DP<95>")
	)
	(gr_poly
		(pts
			(arc
				(start 275.902928 -312.049922)
				(mid 275.496528 -312.049922)
				(end 275.902928 -312.049922)
			)
		)
		(stroke
			(width 0)
			(type solid)
		)
		(fill yes)
		(layer "In12.Cu")
		(net "P5E_PEX2_STN6_TX_DN<111>")
	)
	(gr_poly
		(pts
			(arc
				(start 275.902928 -311.099962)
				(mid 275.496528 -311.099962)
				(end 275.902928 -311.099962)
			)
		)
		(stroke
			(width 0)
			(type solid)
		)
		(fill yes)
		(layer "In12.Cu")
		(net "P5E_PEX2_STN6_TX_DP<111>")
	)
	(gr_poly
		(pts
			(arc
				(start 276.852888 -313.949842)
				(mid 276.446488 -313.949842)
				(end 276.852888 -313.949842)
			)
		)
		(stroke
			(width 0)
			(type solid)
		)
		(fill yes)
		(layer "In12.Cu")
		(net "P5E_PEX2_STN6_TX_DN<110>")
	)
	(gr_poly
		(pts
			(arc
				(start 276.852888 -312.999882)
				(mid 276.446488 -312.999882)
				(end 276.852888 -312.999882)
			)
		)
		(stroke
			(width 0)
			(type solid)
		)
		(fill yes)
		(layer "In12.Cu")
		(net "P5E_PEX2_STN6_TX_DP<110>")
	)
	(gr_poly
		(pts
			(arc
				(start 277.803102 -312.049922)
				(mid 277.396702 -312.049922)
				(end 277.803102 -312.049922)
			)
		)
		(stroke
			(width 0)
			(type solid)
		)
		(fill yes)
		(layer "In12.Cu")
		(net "P5E_PEX2_STN6_TX_DN<109>")
	)
	(gr_poly
		(pts
			(arc
				(start 277.803102 -311.099962)
				(mid 277.396702 -311.099962)
				(end 277.803102 -311.099962)
			)
		)
		(stroke
			(width 0)
			(type solid)
		)
		(fill yes)
		(layer "In12.Cu")
		(net "P5E_PEX2_STN6_TX_DP<109>")
	)
	(gr_poly
		(pts
			(arc
				(start 278.753062 -313.949842)
				(mid 278.346662 -313.949842)
				(end 278.753062 -313.949842)
			)
		)
		(stroke
			(width 0)
			(type solid)
		)
		(fill yes)
		(layer "In12.Cu")
		(net "P5E_PEX2_STN6_TX_DN<108>")
	)
	(gr_poly
		(pts
			(arc
				(start 278.753062 -312.999882)
				(mid 278.346662 -312.999882)
				(end 278.753062 -312.999882)
			)
		)
		(stroke
			(width 0)
			(type solid)
		)
		(fill yes)
		(layer "In12.Cu")
		(net "P5E_PEX2_STN6_TX_DP<108>")
	)
	(gr_poly
		(pts
			(arc
				(start 279.703022 -312.049922)
				(mid 279.296622 -312.049922)
				(end 279.703022 -312.049922)
			)
		)
		(stroke
			(width 0)
			(type solid)
		)
		(fill yes)
		(layer "In12.Cu")
		(net "P5E_PEX2_STN6_TX_DN<107>")
	)
	(gr_poly
		(pts
			(arc
				(start 279.703022 -311.099962)
				(mid 279.296622 -311.099962)
				(end 279.703022 -311.099962)
			)
		)
		(stroke
			(width 0)
			(type solid)
		)
		(fill yes)
		(layer "In12.Cu")
		(net "P5E_PEX2_STN6_TX_DP<107>")
	)
	(gr_poly
		(pts
			(arc
				(start 280.652982 -313.949842)
				(mid 280.246582 -313.949842)
				(end 280.652982 -313.949842)
			)
		)
		(stroke
			(width 0)
			(type solid)
		)
		(fill yes)
		(layer "In12.Cu")
		(net "P5E_PEX2_STN6_TX_DN<106>")
	)
	(gr_poly
		(pts
			(arc
				(start 280.652982 -312.999882)
				(mid 280.246582 -312.999882)
				(end 280.652982 -312.999882)
			)
		)
		(stroke
			(width 0)
			(type solid)
		)
		(fill yes)
		(layer "In12.Cu")
		(net "P5E_PEX2_STN6_TX_DP<106>")
	)
	(gr_poly
		(pts
			(arc
				(start 281.602942 -312.049922)
				(mid 281.196542 -312.049922)
				(end 281.602942 -312.049922)
			)
		)
		(stroke
			(width 0)
			(type solid)
		)
		(fill yes)
		(layer "In12.Cu")
		(net "P5E_PEX2_STN6_TX_DN<105>")
	)
	(gr_poly
		(pts
			(arc
				(start 281.602942 -311.099962)
				(mid 281.196542 -311.099962)
				(end 281.602942 -311.099962)
			)
		)
		(stroke
			(width 0)
			(type solid)
		)
		(fill yes)
		(layer "In12.Cu")
		(net "P5E_PEX2_STN6_TX_DP<105>")
	)
	(gr_poly
		(pts
			(arc
				(start 282.552902 -313.949842)
				(mid 282.146502 -313.949842)
				(end 282.552902 -313.949842)
			)
		)
		(stroke
			(width 0)
			(type solid)
		)
		(fill yes)
		(layer "In12.Cu")
		(net "P5E_PEX2_STN6_TX_DN<104>")
	)
	(gr_poly
		(pts
			(arc
				(start 282.552902 -312.999882)
				(mid 282.146502 -312.999882)
				(end 282.552902 -312.999882)
			)
		)
		(stroke
			(width 0)
			(type solid)
		)
		(fill yes)
		(layer "In12.Cu")
		(net "P5E_PEX2_STN6_TX_DP<104>")
	)
	(gr_poly
		(pts
			(arc
				(start 283.503116 -312.049922)
				(mid 283.096716 -312.049922)
				(end 283.503116 -312.049922)
			)
		)
		(stroke
			(width 0)
			(type solid)
		)
		(fill yes)
		(layer "In12.Cu")
		(net "P5E_PEX2_STN6_TX_DN<103>")
	)
	(gr_poly
		(pts
			(arc
				(start 283.503116 -311.099962)
				(mid 283.096716 -311.099962)
				(end 283.503116 -311.099962)
			)
		)
		(stroke
			(width 0)
			(type solid)
		)
		(fill yes)
		(layer "In12.Cu")
		(net "P5E_PEX2_STN6_TX_DP<103>")
	)
	(gr_poly
		(pts
			(arc
				(start 284.453076 -313.949842)
				(mid 284.046676 -313.949842)
				(end 284.453076 -313.949842)
			)
		)
		(stroke
			(width 0)
			(type solid)
		)
		(fill yes)
		(layer "In12.Cu")
		(net "P5E_PEX2_STN6_TX_DN<102>")
	)
	(gr_poly
		(pts
			(arc
				(start 284.453076 -312.999882)
				(mid 284.046676 -312.999882)
				(end 284.453076 -312.999882)
			)
		)
		(stroke
			(width 0)
			(type solid)
		)
		(fill yes)
		(layer "In12.Cu")
		(net "P5E_PEX2_STN6_TX_DP<102>")
	)
	(gr_poly
		(pts
			(arc
				(start 285.403036 -312.049922)
				(mid 284.996636 -312.049922)
				(end 285.403036 -312.049922)
			)
		)
		(stroke
			(width 0)
			(type solid)
		)
		(fill yes)
		(layer "In12.Cu")
		(net "P5E_PEX2_STN6_TX_DN<101>")
	)
	(gr_poly
		(pts
			(arc
				(start 285.403036 -311.099962)
				(mid 284.996636 -311.099962)
				(end 285.403036 -311.099962)
			)
		)
		(stroke
			(width 0)
			(type solid)
		)
		(fill yes)
		(layer "In12.Cu")
		(net "P5E_PEX2_STN6_TX_DP<101>")
	)
	(gr_poly
		(pts
			(arc
				(start 286.352996 -313.949842)
				(mid 285.946596 -313.949842)
				(end 286.352996 -313.949842)
			)
		)
		(stroke
			(width 0)
			(type solid)
		)
		(fill yes)
		(layer "In12.Cu")
		(net "P5E_PEX2_STN6_TX_DN<100>")
	)
	(gr_poly
		(pts
			(arc
				(start 286.352996 -312.999882)
				(mid 285.946596 -312.999882)
				(end 286.352996 -312.999882)
			)
		)
		(stroke
			(width 0)
			(type solid)
		)
		(fill yes)
		(layer "In12.Cu")
		(net "P5E_PEX2_STN6_TX_DP<100>")
	)
	(gr_poly
		(pts
			(arc
				(start 287.302956 -312.049922)
				(mid 286.896556 -312.049922)
				(end 287.302956 -312.049922)
			)
		)
		(stroke
			(width 0)
			(type solid)
		)
		(fill yes)
		(layer "In12.Cu")
		(net "P5E_PEX2_STN6_TX_DN<99>")
	)
	(gr_poly
		(pts
			(arc
				(start 287.302956 -311.099962)
				(mid 286.896556 -311.099962)
				(end 287.302956 -311.099962)
			)
		)
		(stroke
			(width 0)
			(type solid)
		)
		(fill yes)
		(layer "In12.Cu")
		(net "P5E_PEX2_STN6_TX_DP<99>")
	)
	(gr_poly
		(pts
			(arc
				(start 288.252916 -313.949842)
				(mid 287.846516 -313.949842)
				(end 288.252916 -313.949842)
			)
		)
		(stroke
			(width 0)
			(type solid)
		)
		(fill yes)
		(layer "In12.Cu")
		(net "P5E_PEX2_STN6_TX_DN<98>")
	)
	(gr_poly
		(pts
			(arc
				(start 288.252916 -312.999882)
				(mid 287.846516 -312.999882)
				(end 288.252916 -312.999882)
			)
		)
		(stroke
			(width 0)
			(type solid)
		)
		(fill yes)
		(layer "In12.Cu")
		(net "P5E_PEX2_STN6_TX_DP<98>")
	)
	(gr_poly
		(pts
			(arc
				(start 289.20313 -312.049922)
				(mid 288.79673 -312.049922)
				(end 289.20313 -312.049922)
			)
		)
		(stroke
			(width 0)
			(type solid)
		)
		(fill yes)
		(layer "In12.Cu")
		(net "P5E_PEX2_STN6_TX_DN<97>")
	)
	(gr_poly
		(pts
			(arc
				(start 289.20313 -311.099962)
				(mid 288.79673 -311.099962)
				(end 289.20313 -311.099962)
			)
		)
		(stroke
			(width 0)
			(type solid)
		)
		(fill yes)
		(layer "In12.Cu")
		(net "P5E_PEX2_STN6_TX_DP<97>")
	)
	(gr_poly
		(pts
			(arc
				(start 290.15309 -313.949842)
				(mid 289.74669 -313.949842)
				(end 290.15309 -313.949842)
			)
		)
		(stroke
			(width 0)
			(type solid)
		)
		(fill yes)
		(layer "In12.Cu")
		(net "P5E_PEX2_STN6_TX_DN<96>")
	)
	(gr_poly
		(pts
			(arc
				(start 290.15309 -312.999882)
				(mid 289.74669 -312.999882)
				(end 290.15309 -312.999882)
			)
		)
		(stroke
			(width 0)
			(type solid)
		)
		(fill yes)
		(layer "In12.Cu")
		(net "P5E_PEX2_STN6_TX_DP<96>")
	)
	(gr_poly
		(pts
			(arc
				(start 306.302918 -316.799722)
				(mid 305.896518 -316.799722)
				(end 306.302918 -316.799722)
			)
		)
		(stroke
			(width 0)
			(type solid)
		)
		(fill yes)
		(layer "In12.Cu")
		(net "P5E_PEX2_STN4_RX_DN<79>")
	)
	(gr_poly
		(pts
			(arc
				(start 306.302918 -315.849762)
				(mid 305.896518 -315.849762)
				(end 306.302918 -315.849762)
			)
		)
		(stroke
			(width 0)
			(type solid)
		)
		(fill yes)
		(layer "In12.Cu")
		(net "P5E_PEX2_STN4_RX_DP<79>")
	)
	(gr_poly
		(pts
			(arc
				(start 307.253132 -318.699896)
				(mid 306.846732 -318.699896)
				(end 307.253132 -318.699896)
			)
		)
		(stroke
			(width 0)
			(type solid)
		)
		(fill yes)
		(layer "In12.Cu")
		(net "P5E_PEX2_STN4_RX_DN<78>")
	)
	(gr_poly
		(pts
			(arc
				(start 307.253132 -317.749936)
				(mid 306.846732 -317.749936)
				(end 307.253132 -317.749936)
			)
		)
		(stroke
			(width 0)
			(type solid)
		)
		(fill yes)
		(layer "In12.Cu")
		(net "P5E_PEX2_STN4_RX_DP<78>")
	)
	(gr_poly
		(pts
			(arc
				(start 308.203092 -316.799722)
				(mid 307.796692 -316.799722)
				(end 308.203092 -316.799722)
			)
		)
		(stroke
			(width 0)
			(type solid)
		)
		(fill yes)
		(layer "In12.Cu")
		(net "P5E_PEX2_STN4_RX_DN<77>")
	)
	(gr_poly
		(pts
			(arc
				(start 308.203092 -315.849762)
				(mid 307.796692 -315.849762)
				(end 308.203092 -315.849762)
			)
		)
		(stroke
			(width 0)
			(type solid)
		)
		(fill yes)
		(layer "In12.Cu")
		(net "P5E_PEX2_STN4_RX_DP<77>")
	)
	(gr_poly
		(pts
			(arc
				(start 309.153052 -318.699896)
				(mid 308.746652 -318.699896)
				(end 309.153052 -318.699896)
			)
		)
		(stroke
			(width 0)
			(type solid)
		)
		(fill yes)
		(layer "In12.Cu")
		(net "P5E_PEX2_STN4_RX_DN<76>")
	)
	(gr_poly
		(pts
			(arc
				(start 309.153052 -317.749936)
				(mid 308.746652 -317.749936)
				(end 309.153052 -317.749936)
			)
		)
		(stroke
			(width 0)
			(type solid)
		)
		(fill yes)
		(layer "In12.Cu")
		(net "P5E_PEX2_STN4_RX_DP<76>")
	)
	(gr_poly
		(pts
			(arc
				(start 310.103012 -316.799722)
				(mid 309.696612 -316.799722)
				(end 310.103012 -316.799722)
			)
		)
		(stroke
			(width 0)
			(type solid)
		)
		(fill yes)
		(layer "In12.Cu")
		(net "P5E_PEX2_STN4_RX_DN<75>")
	)
	(gr_poly
		(pts
			(arc
				(start 310.103012 -315.849762)
				(mid 309.696612 -315.849762)
				(end 310.103012 -315.849762)
			)
		)
		(stroke
			(width 0)
			(type solid)
		)
		(fill yes)
		(layer "In12.Cu")
		(net "P5E_PEX2_STN4_RX_DP<75>")
	)
	(gr_poly
		(pts
			(arc
				(start 311.052972 -318.699896)
				(mid 310.646572 -318.699896)
				(end 311.052972 -318.699896)
			)
		)
		(stroke
			(width 0)
			(type solid)
		)
		(fill yes)
		(layer "In12.Cu")
		(net "P5E_PEX2_STN4_RX_DN<74>")
	)
	(gr_poly
		(pts
			(arc
				(start 311.052972 -317.749936)
				(mid 310.646572 -317.749936)
				(end 311.052972 -317.749936)
			)
		)
		(stroke
			(width 0)
			(type solid)
		)
		(fill yes)
		(layer "In12.Cu")
		(net "P5E_PEX2_STN4_RX_DP<74>")
	)
	(gr_poly
		(pts
			(arc
				(start 312.002932 -316.799722)
				(mid 311.596532 -316.799722)
				(end 312.002932 -316.799722)
			)
		)
		(stroke
			(width 0)
			(type solid)
		)
		(fill yes)
		(layer "In12.Cu")
		(net "P5E_PEX2_STN4_RX_DN<73>")
	)
	(gr_poly
		(pts
			(arc
				(start 312.002932 -315.849762)
				(mid 311.596532 -315.849762)
				(end 312.002932 -315.849762)
			)
		)
		(stroke
			(width 0)
			(type solid)
		)
		(fill yes)
		(layer "In12.Cu")
		(net "P5E_PEX2_STN4_RX_DP<73>")
	)
	(gr_poly
		(pts
			(arc
				(start 312.002932 -309.199788)
				(mid 311.596532 -309.199788)
				(end 312.002932 -309.199788)
			)
		)
		(stroke
			(width 0)
			(type solid)
		)
		(fill yes)
		(layer "In12.Cu")
		(net "P5E_PEX2_STN4_RX_DP<69>")
	)
	(gr_poly
		(pts
			(arc
				(start 312.002932 -307.299868)
				(mid 311.596532 -307.299868)
				(end 312.002932 -307.299868)
			)
		)
		(stroke
			(width 0)
			(type solid)
		)
		(fill yes)
		(layer "In12.Cu")
		(net "P5E_PEX2_STN4_RX_DP<67>")
	)
	(gr_poly
		(pts
			(arc
				(start 312.002932 -305.399948)
				(mid 311.596532 -305.399948)
				(end 312.002932 -305.399948)
			)
		)
		(stroke
			(width 0)
			(type solid)
		)
		(fill yes)
		(layer "In12.Cu")
		(net "P5E_PEX2_STN4_RX_DP<65>")
	)
	(gr_poly
		(pts
			(arc
				(start 312.952892 -318.699896)
				(mid 312.546492 -318.699896)
				(end 312.952892 -318.699896)
			)
		)
		(stroke
			(width 0)
			(type solid)
		)
		(fill yes)
		(layer "In12.Cu")
		(net "P5E_PEX2_STN4_RX_DN<72>")
	)
	(gr_poly
		(pts
			(arc
				(start 312.952892 -317.749936)
				(mid 312.546492 -317.749936)
				(end 312.952892 -317.749936)
			)
		)
		(stroke
			(width 0)
			(type solid)
		)
		(fill yes)
		(layer "In12.Cu")
		(net "P5E_PEX2_STN4_RX_DP<72>")
	)
	(gr_poly
		(pts
			(arc
				(start 312.952892 -309.199788)
				(mid 312.546492 -309.199788)
				(end 312.952892 -309.199788)
			)
		)
		(stroke
			(width 0)
			(type solid)
		)
		(fill yes)
		(layer "In12.Cu")
		(net "P5E_PEX2_STN4_RX_DN<69>")
	)
	(gr_poly
		(pts
			(arc
				(start 312.952892 -307.299868)
				(mid 312.546492 -307.299868)
				(end 312.952892 -307.299868)
			)
		)
		(stroke
			(width 0)
			(type solid)
		)
		(fill yes)
		(layer "In12.Cu")
		(net "P5E_PEX2_STN4_RX_DN<67>")
	)
	(gr_poly
		(pts
			(arc
				(start 312.952892 -305.399948)
				(mid 312.546492 -305.399948)
				(end 312.952892 -305.399948)
			)
		)
		(stroke
			(width 0)
			(type solid)
		)
		(fill yes)
		(layer "In12.Cu")
		(net "P5E_PEX2_STN4_RX_DN<65>")
	)
	(gr_poly
		(pts
			(arc
				(start 313.903106 -316.799722)
				(mid 313.496706 -316.799722)
				(end 313.903106 -316.799722)
			)
		)
		(stroke
			(width 0)
			(type solid)
		)
		(fill yes)
		(layer "In12.Cu")
		(net "P5E_PEX2_STN4_RX_DP<71>")
	)
	(gr_poly
		(pts
			(arc
				(start 313.903106 -310.149748)
				(mid 313.496706 -310.149748)
				(end 313.903106 -310.149748)
			)
		)
		(stroke
			(width 0)
			(type solid)
		)
		(fill yes)
		(layer "In12.Cu")
		(net "P5E_PEX2_STN4_RX_DP<70>")
	)
	(gr_poly
		(pts
			(arc
				(start 313.903106 -308.249828)
				(mid 313.496706 -308.249828)
				(end 313.903106 -308.249828)
			)
		)
		(stroke
			(width 0)
			(type solid)
		)
		(fill yes)
		(layer "In12.Cu")
		(net "P5E_PEX2_STN4_RX_DP<68>")
	)
	(gr_poly
		(pts
			(arc
				(start 313.903106 -306.349908)
				(mid 313.496706 -306.349908)
				(end 313.903106 -306.349908)
			)
		)
		(stroke
			(width 0)
			(type solid)
		)
		(fill yes)
		(layer "In12.Cu")
		(net "P5E_PEX2_STN4_RX_DP<66>")
	)
	(gr_poly
		(pts
			(arc
				(start 313.903106 -304.449734)
				(mid 313.496706 -304.449734)
				(end 313.903106 -304.449734)
			)
		)
		(stroke
			(width 0)
			(type solid)
		)
		(fill yes)
		(layer "In12.Cu")
		(net "P5E_PEX2_STN4_RX_DP<64>")
	)
	(gr_poly
		(pts
			(arc
				(start 314.853066 -316.799722)
				(mid 314.446666 -316.799722)
				(end 314.853066 -316.799722)
			)
		)
		(stroke
			(width 0)
			(type solid)
		)
		(fill yes)
		(layer "In12.Cu")
		(net "P5E_PEX2_STN4_RX_DN<71>")
	)
	(gr_poly
		(pts
			(arc
				(start 314.853066 -310.149748)
				(mid 314.446666 -310.149748)
				(end 314.853066 -310.149748)
			)
		)
		(stroke
			(width 0)
			(type solid)
		)
		(fill yes)
		(layer "In12.Cu")
		(net "P5E_PEX2_STN4_RX_DN<70>")
	)
	(gr_poly
		(pts
			(arc
				(start 314.853066 -308.249828)
				(mid 314.446666 -308.249828)
				(end 314.853066 -308.249828)
			)
		)
		(stroke
			(width 0)
			(type solid)
		)
		(fill yes)
		(layer "In12.Cu")
		(net "P5E_PEX2_STN4_RX_DN<68>")
	)
	(gr_poly
		(pts
			(arc
				(start 314.853066 -306.349908)
				(mid 314.446666 -306.349908)
				(end 314.853066 -306.349908)
			)
		)
		(stroke
			(width 0)
			(type solid)
		)
		(fill yes)
		(layer "In12.Cu")
		(net "P5E_PEX2_STN4_RX_DN<66>")
	)
	(gr_poly
		(pts
			(arc
				(start 314.853066 -304.449734)
				(mid 314.446666 -304.449734)
				(end 314.853066 -304.449734)
			)
		)
		(stroke
			(width 0)
			(type solid)
		)
		(fill yes)
		(layer "In12.Cu")
		(net "P5E_PEX2_STN4_RX_DN<64>")
	)
	(gr_poly
		(pts
			(arc
				(start 392.003026 -316.799722)
				(mid 391.596626 -316.799722)
				(end 392.003026 -316.799722)
			)
		)
		(stroke
			(width 0)
			(type solid)
		)
		(fill yes)
		(layer "In12.Cu")
		(net "P5E_PEX3_STN6_RX_DN<111>")
	)
	(gr_poly
		(pts
			(arc
				(start 392.003026 -315.849762)
				(mid 391.596626 -315.849762)
				(end 392.003026 -315.849762)
			)
		)
		(stroke
			(width 0)
			(type solid)
		)
		(fill yes)
		(layer "In12.Cu")
		(net "P5E_PEX3_STN6_RX_DP<111>")
	)
	(gr_poly
		(pts
			(arc
				(start 392.003026 -312.049922)
				(mid 391.596626 -312.049922)
				(end 392.003026 -312.049922)
			)
		)
		(stroke
			(width 0)
			(type solid)
		)
		(fill yes)
		(layer "In12.Cu")
		(net "P5E_PEX3_STN6_TX_DN<111>")
	)
	(gr_poly
		(pts
			(arc
				(start 392.003026 -311.099962)
				(mid 391.596626 -311.099962)
				(end 392.003026 -311.099962)
			)
		)
		(stroke
			(width 0)
			(type solid)
		)
		(fill yes)
		(layer "In12.Cu")
		(net "P5E_PEX3_STN6_TX_DP<111>")
	)
	(gr_poly
		(pts
			(arc
				(start 392.952986 -318.699896)
				(mid 392.546586 -318.699896)
				(end 392.952986 -318.699896)
			)
		)
		(stroke
			(width 0)
			(type solid)
		)
		(fill yes)
		(layer "In12.Cu")
		(net "P5E_PEX3_STN6_RX_DN<110>")
	)
	(gr_poly
		(pts
			(arc
				(start 392.952986 -317.749936)
				(mid 392.546586 -317.749936)
				(end 392.952986 -317.749936)
			)
		)
		(stroke
			(width 0)
			(type solid)
		)
		(fill yes)
		(layer "In12.Cu")
		(net "P5E_PEX3_STN6_RX_DP<110>")
	)
	(gr_poly
		(pts
			(arc
				(start 392.952986 -313.949842)
				(mid 392.546586 -313.949842)
				(end 392.952986 -313.949842)
			)
		)
		(stroke
			(width 0)
			(type solid)
		)
		(fill yes)
		(layer "In12.Cu")
		(net "P5E_PEX3_STN6_TX_DN<110>")
	)
	(gr_poly
		(pts
			(arc
				(start 392.952986 -312.999882)
				(mid 392.546586 -312.999882)
				(end 392.952986 -312.999882)
			)
		)
		(stroke
			(width 0)
			(type solid)
		)
		(fill yes)
		(layer "In12.Cu")
		(net "P5E_PEX3_STN6_TX_DP<110>")
	)
	(gr_poly
		(pts
			(arc
				(start 393.9032 -316.799722)
				(mid 393.4968 -316.799722)
				(end 393.9032 -316.799722)
			)
		)
		(stroke
			(width 0)
			(type solid)
		)
		(fill yes)
		(layer "In12.Cu")
		(net "P5E_PEX3_STN6_RX_DN<109>")
	)
	(gr_poly
		(pts
			(arc
				(start 393.9032 -315.849762)
				(mid 393.4968 -315.849762)
				(end 393.9032 -315.849762)
			)
		)
		(stroke
			(width 0)
			(type solid)
		)
		(fill yes)
		(layer "In12.Cu")
		(net "P5E_PEX3_STN6_RX_DP<109>")
	)
	(gr_poly
		(pts
			(arc
				(start 393.9032 -312.049922)
				(mid 393.4968 -312.049922)
				(end 393.9032 -312.049922)
			)
		)
		(stroke
			(width 0)
			(type solid)
		)
		(fill yes)
		(layer "In12.Cu")
		(net "P5E_PEX3_STN6_TX_DN<109>")
	)
	(gr_poly
		(pts
			(arc
				(start 393.9032 -311.099962)
				(mid 393.4968 -311.099962)
				(end 393.9032 -311.099962)
			)
		)
		(stroke
			(width 0)
			(type solid)
		)
		(fill yes)
		(layer "In12.Cu")
		(net "P5E_PEX3_STN6_TX_DP<109>")
	)
	(gr_poly
		(pts
			(arc
				(start 394.85316 -318.699896)
				(mid 394.44676 -318.699896)
				(end 394.85316 -318.699896)
			)
		)
		(stroke
			(width 0)
			(type solid)
		)
		(fill yes)
		(layer "In12.Cu")
		(net "P5E_PEX3_STN6_RX_DN<108>")
	)
	(gr_poly
		(pts
			(arc
				(start 394.85316 -317.749936)
				(mid 394.44676 -317.749936)
				(end 394.85316 -317.749936)
			)
		)
		(stroke
			(width 0)
			(type solid)
		)
		(fill yes)
		(layer "In12.Cu")
		(net "P5E_PEX3_STN6_RX_DP<108>")
	)
	(gr_poly
		(pts
			(arc
				(start 394.85316 -313.949842)
				(mid 394.44676 -313.949842)
				(end 394.85316 -313.949842)
			)
		)
		(stroke
			(width 0)
			(type solid)
		)
		(fill yes)
		(layer "In12.Cu")
		(net "P5E_PEX3_STN6_TX_DN<108>")
	)
	(gr_poly
		(pts
			(arc
				(start 394.85316 -312.999882)
				(mid 394.44676 -312.999882)
				(end 394.85316 -312.999882)
			)
		)
		(stroke
			(width 0)
			(type solid)
		)
		(fill yes)
		(layer "In12.Cu")
		(net "P5E_PEX3_STN6_TX_DP<108>")
	)
	(gr_poly
		(pts
			(arc
				(start 395.80312 -316.799722)
				(mid 395.39672 -316.799722)
				(end 395.80312 -316.799722)
			)
		)
		(stroke
			(width 0)
			(type solid)
		)
		(fill yes)
		(layer "In12.Cu")
		(net "P5E_PEX3_STN6_RX_DN<107>")
	)
	(gr_poly
		(pts
			(arc
				(start 395.80312 -315.849762)
				(mid 395.39672 -315.849762)
				(end 395.80312 -315.849762)
			)
		)
		(stroke
			(width 0)
			(type solid)
		)
		(fill yes)
		(layer "In12.Cu")
		(net "P5E_PEX3_STN6_RX_DP<107>")
	)
	(gr_poly
		(pts
			(arc
				(start 395.80312 -312.049922)
				(mid 395.39672 -312.049922)
				(end 395.80312 -312.049922)
			)
		)
		(stroke
			(width 0)
			(type solid)
		)
		(fill yes)
		(layer "In12.Cu")
		(net "P5E_PEX3_STN6_TX_DN<107>")
	)
	(gr_poly
		(pts
			(arc
				(start 395.80312 -311.099962)
				(mid 395.39672 -311.099962)
				(end 395.80312 -311.099962)
			)
		)
		(stroke
			(width 0)
			(type solid)
		)
		(fill yes)
		(layer "In12.Cu")
		(net "P5E_PEX3_STN6_TX_DP<107>")
	)
	(gr_poly
		(pts
			(arc
				(start 396.75308 -318.699896)
				(mid 396.34668 -318.699896)
				(end 396.75308 -318.699896)
			)
		)
		(stroke
			(width 0)
			(type solid)
		)
		(fill yes)
		(layer "In12.Cu")
		(net "P5E_PEX3_STN6_RX_DN<106>")
	)
	(gr_poly
		(pts
			(arc
				(start 396.75308 -317.749936)
				(mid 396.34668 -317.749936)
				(end 396.75308 -317.749936)
			)
		)
		(stroke
			(width 0)
			(type solid)
		)
		(fill yes)
		(layer "In12.Cu")
		(net "P5E_PEX3_STN6_RX_DP<106>")
	)
	(gr_poly
		(pts
			(arc
				(start 396.75308 -313.949842)
				(mid 396.34668 -313.949842)
				(end 396.75308 -313.949842)
			)
		)
		(stroke
			(width 0)
			(type solid)
		)
		(fill yes)
		(layer "In12.Cu")
		(net "P5E_PEX3_STN6_TX_DN<106>")
	)
	(gr_poly
		(pts
			(arc
				(start 396.75308 -312.999882)
				(mid 396.34668 -312.999882)
				(end 396.75308 -312.999882)
			)
		)
		(stroke
			(width 0)
			(type solid)
		)
		(fill yes)
		(layer "In12.Cu")
		(net "P5E_PEX3_STN6_TX_DP<106>")
	)
	(gr_poly
		(pts
			(arc
				(start 397.70304 -316.799722)
				(mid 397.29664 -316.799722)
				(end 397.70304 -316.799722)
			)
		)
		(stroke
			(width 0)
			(type solid)
		)
		(fill yes)
		(layer "In12.Cu")
		(net "P5E_PEX3_STN6_RX_DN<105>")
	)
	(gr_poly
		(pts
			(arc
				(start 397.70304 -315.849762)
				(mid 397.29664 -315.849762)
				(end 397.70304 -315.849762)
			)
		)
		(stroke
			(width 0)
			(type solid)
		)
		(fill yes)
		(layer "In12.Cu")
		(net "P5E_PEX3_STN6_RX_DP<105>")
	)
	(gr_poly
		(pts
			(arc
				(start 397.70304 -312.049922)
				(mid 397.29664 -312.049922)
				(end 397.70304 -312.049922)
			)
		)
		(stroke
			(width 0)
			(type solid)
		)
		(fill yes)
		(layer "In12.Cu")
		(net "P5E_PEX3_STN6_TX_DN<105>")
	)
	(gr_poly
		(pts
			(arc
				(start 397.70304 -311.099962)
				(mid 397.29664 -311.099962)
				(end 397.70304 -311.099962)
			)
		)
		(stroke
			(width 0)
			(type solid)
		)
		(fill yes)
		(layer "In12.Cu")
		(net "P5E_PEX3_STN6_TX_DP<105>")
	)
	(gr_poly
		(pts
			(arc
				(start 398.653 -318.699896)
				(mid 398.2466 -318.699896)
				(end 398.653 -318.699896)
			)
		)
		(stroke
			(width 0)
			(type solid)
		)
		(fill yes)
		(layer "In12.Cu")
		(net "P5E_PEX3_STN6_RX_DN<104>")
	)
	(gr_poly
		(pts
			(arc
				(start 398.653 -317.749936)
				(mid 398.2466 -317.749936)
				(end 398.653 -317.749936)
			)
		)
		(stroke
			(width 0)
			(type solid)
		)
		(fill yes)
		(layer "In12.Cu")
		(net "P5E_PEX3_STN6_RX_DP<104>")
	)
	(gr_poly
		(pts
			(arc
				(start 398.653 -313.949842)
				(mid 398.2466 -313.949842)
				(end 398.653 -313.949842)
			)
		)
		(stroke
			(width 0)
			(type solid)
		)
		(fill yes)
		(layer "In12.Cu")
		(net "P5E_PEX3_STN6_TX_DN<104>")
	)
	(gr_poly
		(pts
			(arc
				(start 398.653 -312.999882)
				(mid 398.2466 -312.999882)
				(end 398.653 -312.999882)
			)
		)
		(stroke
			(width 0)
			(type solid)
		)
		(fill yes)
		(layer "In12.Cu")
		(net "P5E_PEX3_STN6_TX_DP<104>")
	)
	(gr_poly
		(pts
			(arc
				(start 414.803082 -316.799722)
				(mid 414.396682 -316.799722)
				(end 414.803082 -316.799722)
			)
		)
		(stroke
			(width 0)
			(type solid)
		)
		(fill yes)
		(layer "In12.Cu")
		(net "P5E_PEX3_STN5_RX_DN<88>")
	)
	(gr_poly
		(pts
			(arc
				(start 414.803082 -315.849762)
				(mid 414.396682 -315.849762)
				(end 414.803082 -315.849762)
			)
		)
		(stroke
			(width 0)
			(type solid)
		)
		(fill yes)
		(layer "In12.Cu")
		(net "P5E_PEX3_STN5_RX_DP<88>")
	)
	(gr_poly
		(pts
			(arc
				(start 414.803082 -312.049922)
				(mid 414.396682 -312.049922)
				(end 414.803082 -312.049922)
			)
		)
		(stroke
			(width 0)
			(type solid)
		)
		(fill yes)
		(layer "In12.Cu")
		(net "P5E_PEX3_STN5_TX_DN<88>")
	)
	(gr_poly
		(pts
			(arc
				(start 414.803082 -311.099962)
				(mid 414.396682 -311.099962)
				(end 414.803082 -311.099962)
			)
		)
		(stroke
			(width 0)
			(type solid)
		)
		(fill yes)
		(layer "In12.Cu")
		(net "P5E_PEX3_STN5_TX_DP<88>")
	)
	(gr_poly
		(pts
			(arc
				(start 415.753042 -318.699896)
				(mid 415.346642 -318.699896)
				(end 415.753042 -318.699896)
			)
		)
		(stroke
			(width 0)
			(type solid)
		)
		(fill yes)
		(layer "In12.Cu")
		(net "P5E_PEX3_STN5_RX_DN<89>")
	)
	(gr_poly
		(pts
			(arc
				(start 415.753042 -317.749936)
				(mid 415.346642 -317.749936)
				(end 415.753042 -317.749936)
			)
		)
		(stroke
			(width 0)
			(type solid)
		)
		(fill yes)
		(layer "In12.Cu")
		(net "P5E_PEX3_STN5_RX_DP<89>")
	)
	(gr_poly
		(pts
			(arc
				(start 415.753042 -313.949842)
				(mid 415.346642 -313.949842)
				(end 415.753042 -313.949842)
			)
		)
		(stroke
			(width 0)
			(type solid)
		)
		(fill yes)
		(layer "In12.Cu")
		(net "P5E_PEX3_STN5_TX_DN<89>")
	)
	(gr_poly
		(pts
			(arc
				(start 415.753042 -312.999882)
				(mid 415.346642 -312.999882)
				(end 415.753042 -312.999882)
			)
		)
		(stroke
			(width 0)
			(type solid)
		)
		(fill yes)
		(layer "In12.Cu")
		(net "P5E_PEX3_STN5_TX_DP<89>")
	)
	(gr_poly
		(pts
			(arc
				(start 416.703002 -316.799722)
				(mid 416.296602 -316.799722)
				(end 416.703002 -316.799722)
			)
		)
		(stroke
			(width 0)
			(type solid)
		)
		(fill yes)
		(layer "In12.Cu")
		(net "P5E_PEX3_STN5_RX_DN<90>")
	)
	(gr_poly
		(pts
			(arc
				(start 416.703002 -315.849762)
				(mid 416.296602 -315.849762)
				(end 416.703002 -315.849762)
			)
		)
		(stroke
			(width 0)
			(type solid)
		)
		(fill yes)
		(layer "In12.Cu")
		(net "P5E_PEX3_STN5_RX_DP<90>")
	)
	(gr_poly
		(pts
			(arc
				(start 416.703002 -312.049922)
				(mid 416.296602 -312.049922)
				(end 416.703002 -312.049922)
			)
		)
		(stroke
			(width 0)
			(type solid)
		)
		(fill yes)
		(layer "In12.Cu")
		(net "P5E_PEX3_STN5_TX_DN<90>")
	)
	(gr_poly
		(pts
			(arc
				(start 416.703002 -311.099962)
				(mid 416.296602 -311.099962)
				(end 416.703002 -311.099962)
			)
		)
		(stroke
			(width 0)
			(type solid)
		)
		(fill yes)
		(layer "In12.Cu")
		(net "P5E_PEX3_STN5_TX_DP<90>")
	)
	(gr_poly
		(pts
			(arc
				(start 417.653216 -318.699896)
				(mid 417.246816 -318.699896)
				(end 417.653216 -318.699896)
			)
		)
		(stroke
			(width 0)
			(type solid)
		)
		(fill yes)
		(layer "In12.Cu")
		(net "P5E_PEX3_STN5_RX_DN<91>")
	)
	(gr_poly
		(pts
			(arc
				(start 417.653216 -317.749936)
				(mid 417.246816 -317.749936)
				(end 417.653216 -317.749936)
			)
		)
		(stroke
			(width 0)
			(type solid)
		)
		(fill yes)
		(layer "In12.Cu")
		(net "P5E_PEX3_STN5_RX_DP<91>")
	)
	(gr_poly
		(pts
			(arc
				(start 417.653216 -313.949842)
				(mid 417.246816 -313.949842)
				(end 417.653216 -313.949842)
			)
		)
		(stroke
			(width 0)
			(type solid)
		)
		(fill yes)
		(layer "In12.Cu")
		(net "P5E_PEX3_STN5_TX_DN<91>")
	)
	(gr_poly
		(pts
			(arc
				(start 417.653216 -312.999882)
				(mid 417.246816 -312.999882)
				(end 417.653216 -312.999882)
			)
		)
		(stroke
			(width 0)
			(type solid)
		)
		(fill yes)
		(layer "In12.Cu")
		(net "P5E_PEX3_STN5_TX_DP<91>")
	)
	(gr_poly
		(pts
			(arc
				(start 418.603176 -316.799722)
				(mid 418.196776 -316.799722)
				(end 418.603176 -316.799722)
			)
		)
		(stroke
			(width 0)
			(type solid)
		)
		(fill yes)
		(layer "In12.Cu")
		(net "P5E_PEX3_STN5_RX_DN<92>")
	)
	(gr_poly
		(pts
			(arc
				(start 418.603176 -315.849762)
				(mid 418.196776 -315.849762)
				(end 418.603176 -315.849762)
			)
		)
		(stroke
			(width 0)
			(type solid)
		)
		(fill yes)
		(layer "In12.Cu")
		(net "P5E_PEX3_STN5_RX_DP<92>")
	)
	(gr_poly
		(pts
			(arc
				(start 418.603176 -312.049922)
				(mid 418.196776 -312.049922)
				(end 418.603176 -312.049922)
			)
		)
		(stroke
			(width 0)
			(type solid)
		)
		(fill yes)
		(layer "In12.Cu")
		(net "P5E_PEX3_STN5_TX_DN<92>")
	)
	(gr_poly
		(pts
			(arc
				(start 418.603176 -311.099962)
				(mid 418.196776 -311.099962)
				(end 418.603176 -311.099962)
			)
		)
		(stroke
			(width 0)
			(type solid)
		)
		(fill yes)
		(layer "In12.Cu")
		(net "P5E_PEX3_STN5_TX_DP<92>")
	)
	(gr_poly
		(pts
			(arc
				(start 419.553136 -318.699896)
				(mid 419.146736 -318.699896)
				(end 419.553136 -318.699896)
			)
		)
		(stroke
			(width 0)
			(type solid)
		)
		(fill yes)
		(layer "In12.Cu")
		(net "P5E_PEX3_STN5_RX_DN<93>")
	)
	(gr_poly
		(pts
			(arc
				(start 419.553136 -317.749936)
				(mid 419.146736 -317.749936)
				(end 419.553136 -317.749936)
			)
		)
		(stroke
			(width 0)
			(type solid)
		)
		(fill yes)
		(layer "In12.Cu")
		(net "P5E_PEX3_STN5_RX_DP<93>")
	)
	(gr_poly
		(pts
			(arc
				(start 419.553136 -313.949842)
				(mid 419.146736 -313.949842)
				(end 419.553136 -313.949842)
			)
		)
		(stroke
			(width 0)
			(type solid)
		)
		(fill yes)
		(layer "In12.Cu")
		(net "P5E_PEX3_STN5_TX_DN<93>")
	)
	(gr_poly
		(pts
			(arc
				(start 419.553136 -312.999882)
				(mid 419.146736 -312.999882)
				(end 419.553136 -312.999882)
			)
		)
		(stroke
			(width 0)
			(type solid)
		)
		(fill yes)
		(layer "In12.Cu")
		(net "P5E_PEX3_STN5_TX_DP<93>")
	)
	(gr_poly
		(pts
			(arc
				(start 420.503096 -316.799722)
				(mid 420.096696 -316.799722)
				(end 420.503096 -316.799722)
			)
		)
		(stroke
			(width 0)
			(type solid)
		)
		(fill yes)
		(layer "In12.Cu")
		(net "P5E_PEX3_STN5_RX_DN<94>")
	)
	(gr_poly
		(pts
			(arc
				(start 420.503096 -315.849762)
				(mid 420.096696 -315.849762)
				(end 420.503096 -315.849762)
			)
		)
		(stroke
			(width 0)
			(type solid)
		)
		(fill yes)
		(layer "In12.Cu")
		(net "P5E_PEX3_STN5_RX_DP<94>")
	)
	(gr_poly
		(pts
			(arc
				(start 420.503096 -312.049922)
				(mid 420.096696 -312.049922)
				(end 420.503096 -312.049922)
			)
		)
		(stroke
			(width 0)
			(type solid)
		)
		(fill yes)
		(layer "In12.Cu")
		(net "P5E_PEX3_STN5_TX_DN<94>")
	)
	(gr_poly
		(pts
			(arc
				(start 420.503096 -311.099962)
				(mid 420.096696 -311.099962)
				(end 420.503096 -311.099962)
			)
		)
		(stroke
			(width 0)
			(type solid)
		)
		(fill yes)
		(layer "In12.Cu")
		(net "P5E_PEX3_STN5_TX_DP<94>")
	)
	(gr_poly
		(pts
			(arc
				(start 421.453056 -318.699896)
				(mid 421.046656 -318.699896)
				(end 421.453056 -318.699896)
			)
		)
		(stroke
			(width 0)
			(type solid)
		)
		(fill yes)
		(layer "In12.Cu")
		(net "P5E_PEX3_STN5_RX_DN<95>")
	)
	(gr_poly
		(pts
			(arc
				(start 421.453056 -317.749936)
				(mid 421.046656 -317.749936)
				(end 421.453056 -317.749936)
			)
		)
		(stroke
			(width 0)
			(type solid)
		)
		(fill yes)
		(layer "In12.Cu")
		(net "P5E_PEX3_STN5_RX_DP<95>")
	)
	(gr_poly
		(pts
			(arc
				(start 421.453056 -313.949842)
				(mid 421.046656 -313.949842)
				(end 421.453056 -313.949842)
			)
		)
		(stroke
			(width 0)
			(type solid)
		)
		(fill yes)
		(layer "In12.Cu")
		(net "P5E_PEX3_STN5_TX_DN<95>")
	)
	(gr_poly
		(pts
			(arc
				(start 421.453056 -312.999882)
				(mid 421.046656 -312.999882)
				(end 421.453056 -312.999882)
			)
		)
		(stroke
			(width 0)
			(type solid)
		)
		(fill yes)
		(layer "In12.Cu")
		(net "P5E_PEX3_STN5_TX_DP<95>")
	)
	(gr_poly
		(pts
			(arc
				(start 241.741198 -376.399806)
				(mid 241.763367 -376.39459)
				(end 241.781076 -376.380248)
			)
			(arc
				(start 241.781076 -376.380248)
				(mid 241.793461 -376.365378)
				(end 241.80673 -376.351292)
			)
			(xy 242.08994 -376.068082)
			(arc
				(start 242.09502 -376.063002)
				(mid 242.106647 -376.046325)
				(end 242.110768 -376.026426)
			)
			(arc
				(start 242.110768 -368.666268)
				(mid 242.106867 -368.646745)
				(end 242.095782 -368.6302)
			)
			(arc
				(start 241.977672 -368.51209)
				(mid 241.961138 -368.500979)
				(end 241.941604 -368.497104)
			)
			(arc
				(start 236.370368 -368.497104)
				(mid 236.350845 -368.501005)
				(end 236.3343 -368.51209)
			)
			(arc
				(start 236.123734 -368.722656)
				(mid 236.112623 -368.73919)
				(end 236.108748 -368.758724)
			)
			(arc
				(start 236.108748 -376.146314)
				(mid 236.112649 -376.165837)
				(end 236.123734 -376.182382)
			)
			(arc
				(start 236.326172 -376.38482)
				(mid 236.342706 -376.395931)
				(end 236.36224 -376.399806)
			)
		)
		(stroke
			(width 0)
			(type solid)
		)
		(fill yes)
		(layer "In12.Cu")
		(net "P12V_STBY_R1")
	)
	(gr_poly
		(pts
			(arc
				(start 235.60151 -413.087058)
				(mid 235.621033 -413.083157)
				(end 235.637578 -413.072072)
			)
			(arc
				(start 236.756956 -411.952694)
				(mid 236.768067 -411.93616)
				(end 236.771942 -411.916626)
			)
			(arc
				(start 236.771942 -402.84527)
				(mid 236.796095 -402.723754)
				(end 236.864906 -402.620734)
			)
			(arc
				(start 238.766604 -400.719036)
				(mid 238.869636 -400.650255)
				(end 238.99114 -400.626072)
			)
			(arc
				(start 242.910868 -400.626072)
				(mid 242.930391 -400.622171)
				(end 242.946936 -400.611086)
			)
			(arc
				(start 243.79682 -399.761202)
				(mid 243.807931 -399.744668)
				(end 243.811806 -399.725134)
			)
			(arc
				(start 243.811806 -392.09472)
				(mid 243.835959 -391.973204)
				(end 243.90477 -391.870184)
			)
			(arc
				(start 244.93093 -390.844024)
				(mid 245.033962 -390.775243)
				(end 245.155466 -390.75106)
			)
			(arc
				(start 259.056124 -390.75106)
				(mid 259.075647 -390.747159)
				(end 259.092192 -390.736074)
			)
			(arc
				(start 262.00481 -387.823456)
				(mid 262.015921 -387.806922)
				(end 262.019796 -387.787388)
			)
			(arc
				(start 262.019796 -379.197616)
				(mid 262.015895 -379.178093)
				(end 262.00481 -379.161548)
			)
			(arc
				(start 261.967472 -379.12421)
				(mid 261.950938 -379.113099)
				(end 261.931404 -379.109224)
			)
			(arc
				(start 240.584482 -379.109224)
				(mid 240.564959 -379.113125)
				(end 240.548414 -379.12421)
			)
			(arc
				(start 239.998504 -379.67412)
				(mid 239.895472 -379.742901)
				(end 239.773968 -379.767084)
			)
			(arc
				(start 237.129066 -379.767084)
				(mid 237.00755 -379.742931)
				(end 236.90453 -379.67412)
			)
			(arc
				(start 232.953814 -375.723404)
				(mid 232.885033 -375.620372)
				(end 232.86085 -375.498868)
			)
			(arc
				(start 232.86085 -372.11508)
				(mid 232.856949 -372.095557)
				(end 232.845864 -372.079012)
			)
			(arc
				(start 232.203752 -371.4369)
				(mid 232.134971 -371.333868)
				(end 232.110788 -371.212364)
			)
			(arc
				(start 232.110788 -371.075712)
				(mid 232.106887 -371.056189)
				(end 232.095802 -371.039644)
			)
			(arc
				(start 232.035858 -370.9797)
				(mid 231.967077 -370.876668)
				(end 231.942894 -370.755164)
			)
			(arc
				(start 231.942894 -367.397792)
				(mid 231.938993 -367.378269)
				(end 231.927908 -367.361724)
			)
			(arc
				(start 231.89057 -367.324386)
				(mid 231.874036 -367.313275)
				(end 231.854502 -367.3094)
			)
			(arc
				(start 228.741986 -367.3094)
				(mid 228.722463 -367.313301)
				(end 228.705918 -367.324386)
			)
			(arc
				(start 228.66858 -367.361724)
				(mid 228.657469 -367.378258)
				(end 228.653594 -367.397792)
			)
			(arc
				(start 228.653594 -370.74856)
				(mid 228.629441 -370.870076)
				(end 228.56063 -370.973096)
			)
			(arc
				(start 228.481128 -371.052598)
				(mid 228.470017 -371.069132)
				(end 228.466142 -371.088666)
			)
			(arc
				(start 228.466142 -371.354096)
				(mid 228.441989 -371.475612)
				(end 228.373178 -371.578632)
			)
			(arc
				(start 227.178362 -372.773448)
				(mid 227.167251 -372.789982)
				(end 227.163376 -372.809516)
			)
			(arc
				(start 227.163376 -374.166384)
				(mid 227.139223 -374.2879)
				(end 227.070412 -374.39092)
			)
			(arc
				(start 225.794062 -375.66727)
				(mid 225.69103 -375.736051)
				(end 225.569526 -375.760234)
			)
			(arc
				(start 223.648016 -375.760234)
				(mid 223.5265 -375.736081)
				(end 223.42348 -375.66727)
			)
			(arc
				(start 221.55531 -373.7991)
				(mid 221.486529 -373.696068)
				(end 221.462346 -373.574564)
			)
			(arc
				(start 221.462346 -371.091714)
				(mid 221.458445 -371.072191)
				(end 221.44736 -371.055646)
			)
			(arc
				(start 221.361508 -370.969794)
				(mid 221.292727 -370.866762)
				(end 221.268544 -370.745258)
			)
			(arc
				(start 221.268544 -367.391442)
				(mid 221.264643 -367.371919)
				(end 221.253558 -367.355374)
			)
			(arc
				(start 221.225872 -367.327688)
				(mid 221.209338 -367.316577)
				(end 221.189804 -367.312702)
			)
			(arc
				(start 218.110308 -367.312702)
				(mid 218.090785 -367.316603)
				(end 218.07424 -367.327688)
			)
			(arc
				(start 217.967306 -367.434622)
				(mid 217.956195 -367.451156)
				(end 217.95232 -367.47069)
			)
			(arc
				(start 217.95232 -370.719096)
				(mid 217.928167 -370.840612)
				(end 217.859356 -370.943632)
			)
			(arc
				(start 216.82964 -371.973348)
				(mid 216.726608 -372.042129)
				(end 216.605104 -372.066312)
			)
			(arc
				(start 210.424014 -372.066312)
				(mid 210.302498 -372.042159)
				(end 210.199478 -371.973348)
			)
			(arc
				(start 210.067906 -371.841776)
				(mid 209.999125 -371.738744)
				(end 209.974942 -371.61724)
			)
			(arc
				(start 209.974942 -371.309138)
				(mid 209.971041 -371.289615)
				(end 209.959956 -371.27307)
			)
			(arc
				(start 209.949034 -371.262148)
				(mid 209.9325 -371.251037)
				(end 209.912966 -371.247162)
			)
			(arc
				(start 209.559144 -371.247162)
				(mid 209.437628 -371.223009)
				(end 209.334608 -371.154198)
			)
			(arc
				(start 208.669382 -370.488972)
				(mid 208.652848 -370.477861)
				(end 208.633314 -370.473986)
			)
			(arc
				(start 208.394554 -370.473986)
				(mid 208.273038 -370.449833)
				(end 208.170018 -370.381022)
			)
			(arc
				(start 208.11744 -370.328444)
				(mid 208.048659 -370.225412)
				(end 208.024476 -370.103908)
			)
			(arc
				(start 208.024476 -367.401348)
				(mid 208.020575 -367.381825)
				(end 208.00949 -367.36528)
			)
			(arc
				(start 207.981804 -367.337594)
				(mid 207.96527 -367.326483)
				(end 207.945736 -367.322608)
			)
			(arc
				(start 204.823822 -367.322608)
				(mid 204.804299 -367.326509)
				(end 204.787754 -367.337594)
			)
			(arc
				(start 204.740002 -367.385346)
				(mid 204.728891 -367.40188)
				(end 204.725016 -367.421414)
			)
			(arc
				(start 204.725016 -370.796312)
				(mid 204.728917 -370.815835)
				(end 204.740002 -370.83238)
			)
			(arc
				(start 204.77353 -370.865908)
				(mid 204.842311 -370.96894)
				(end 204.866494 -371.090444)
			)
			(arc
				(start 204.866494 -374.47474)
				(mid 204.870058 -374.493432)
				(end 204.88021 -374.509538)
			)
			(arc
				(start 204.88021 -374.509538)
				(mid 204.94326 -374.609679)
				(end 204.9653 -374.725946)
			)
			(arc
				(start 204.9653 -387.02361)
				(mid 204.969201 -387.043133)
				(end 204.980286 -387.059678)
			)
			(arc
				(start 207.47482 -389.554212)
				(mid 207.543601 -389.657244)
				(end 207.567784 -389.778748)
			)
			(arc
				(start 207.567784 -411.696662)
				(mid 207.571685 -411.716185)
				(end 207.58277 -411.73273)
			)
			(arc
				(start 208.922112 -413.072072)
				(mid 208.938646 -413.083183)
				(end 208.95818 -413.087058)
			)
		)
		(stroke
			(width 0)
			(type solid)
		)
		(fill yes)
		(layer "In12.Cu")
		(net "P12V_STBY")
	)
	(gr_poly
		(pts
			(xy 465.600034 -461.99552) (xy 465.655841 -461.994997) (xy 465.767141 -461.986654) (xy 465.877508 -461.970017)
			(xy 465.986322 -461.945179) (xy 466.092976 -461.912278) (xy 466.196873 -461.8715) (xy 466.297432 -461.823072)
			(xy 466.394091 -461.767264) (xy 466.48631 -461.70439) (xy 466.573572 -461.6348) (xy 466.65539 -461.558883)
			(xy 466.731306 -461.477065) (xy 466.800896 -461.389802) (xy 466.86377 -461.297583) (xy 466.919577 -461.200923)
			(xy 466.968004 -461.100364) (xy 467.008782 -460.996466) (xy 467.041681 -460.889812) (xy 467.066519 -460.780998)
			(xy 467.083155 -460.670631) (xy 467.091497 -460.559331) (xy 467.09203 -460.503524) (xy 467.09203 -422.58996)
			(xy 467.091507 -422.534153) (xy 467.083163 -422.422853) (xy 467.066526 -422.312487) (xy 467.041687 -422.203672)
			(xy 467.008787 -422.097019) (xy 466.968009 -421.993121) (xy 466.91958 -421.892562) (xy 466.863773 -421.795903)
			(xy 466.800898 -421.703684) (xy 466.731308 -421.616422) (xy 466.655392 -421.534604) (xy 466.573573 -421.458688)
			(xy 466.486311 -421.389098) (xy 466.394092 -421.326224) (xy 466.297433 -421.270417) (xy 466.196873 -421.221989)
			(xy 466.092976 -421.181211) (xy 465.986322 -421.148311) (xy 465.877508 -421.123473) (xy 465.767141 -421.106836)
			(xy 465.655841 -421.098493) (xy 465.600034 -421.097964) (xy 447.939922 -421.097964) (xy 447.884114 -421.098485)
			(xy 447.77281 -421.106824) (xy 447.66244 -421.123458) (xy 447.553622 -421.148293) (xy 447.446964 -421.181191)
			(xy 447.343062 -421.221967) (xy 447.242499 -421.270394) (xy 447.145835 -421.3262) (xy 447.053613 -421.389074)
			(xy 446.966346 -421.458664) (xy 446.884524 -421.53458) (xy 446.808604 -421.616399) (xy 446.739011 -421.703663)
			(xy 446.676133 -421.795883) (xy 446.620323 -421.892544) (xy 446.571892 -421.993106) (xy 446.531111 -422.097005)
			(xy 446.498209 -422.203662) (xy 446.47337 -422.312479) (xy 446.456731 -422.422848) (xy 446.448387 -422.534152)
			(xy 446.447926 -422.58996) (xy 446.447926 -429.090074) (xy 446.447433 -429.160429) (xy 446.439545 -429.300916)
			(xy 446.423792 -429.440741) (xy 446.400224 -429.579462) (xy 446.368915 -429.716643) (xy 446.329963 -429.851854)
			(xy 446.283491 -429.984667) (xy 446.229646 -430.114666) (xy 446.168596 -430.241441) (xy 446.100533 -430.364593)
			(xy 446.025673 -430.483736) (xy 445.94425 -430.598494) (xy 445.856521 -430.708505) (xy 445.762761 -430.813425)
			(xy 445.663266 -430.912922) (xy 445.558348 -431.006684) (xy 445.448338 -431.094416) (xy 445.333582 -431.175842)
			(xy 445.214442 -431.250705) (xy 445.091291 -431.31877) (xy 444.964517 -431.379823) (xy 444.834519 -431.433671)
			(xy 444.701707 -431.480146) (xy 444.566498 -431.519101) (xy 444.429317 -431.550413) (xy 444.290596 -431.573985)
			(xy 444.150772 -431.589741) (xy 444.010285 -431.597632) (xy 443.93993 -431.59807) (xy 371.24005 -431.59807)
			(xy 371.169695 -431.597587) (xy 371.029207 -431.5897) (xy 370.889383 -431.573948) (xy 370.750661 -431.550381)
			(xy 370.613479 -431.519072) (xy 370.478269 -431.480121) (xy 370.345455 -431.433649) (xy 370.215456 -431.379804)
			(xy 370.088681 -431.318754) (xy 369.965528 -431.250691) (xy 369.846385 -431.175831) (xy 369.731628 -431.094407)
			(xy 369.621616 -431.006677) (xy 369.516697 -430.912917) (xy 369.4172 -430.813421) (xy 369.323438 -430.708502)
			(xy 369.235707 -430.598492) (xy 369.154283 -430.483735) (xy 369.079421 -430.364593) (xy 369.011357 -430.241441)
			(xy 368.950306 -430.114666) (xy 368.896459 -429.984667) (xy 368.849986 -429.851854) (xy 368.811034 -429.716644)
			(xy 368.779724 -429.579463) (xy 368.756155 -429.440741) (xy 368.740402 -429.300917) (xy 368.732514 -429.160429)
			(xy 368.732054 -429.090074) (xy 368.732054 -422.58996) (xy 368.731543 -422.534154) (xy 368.7232 -422.422854)
			(xy 368.706562 -422.31249) (xy 368.681723 -422.203677) (xy 368.648822 -422.097024) (xy 368.608042 -421.993129)
			(xy 368.559613 -421.892571) (xy 368.503804 -421.795914) (xy 368.440929 -421.703697) (xy 368.371337 -421.616438)
			(xy 368.29542 -421.534622) (xy 368.2136 -421.458709) (xy 368.126337 -421.389123) (xy 368.034117 -421.326252)
			(xy 367.937456 -421.270449) (xy 367.836896 -421.222025) (xy 367.732998 -421.181251) (xy 367.626344 -421.148356)
			(xy 367.51753 -421.123523) (xy 367.407164 -421.106891) (xy 367.295864 -421.098554) (xy 367.240058 -421.097964)
			(xy 359.940098 -421.097964) (xy 359.88429 -421.098486) (xy 359.772988 -421.106827) (xy 359.662619 -421.123462)
			(xy 359.553802 -421.148298) (xy 359.447146 -421.181197) (xy 359.343246 -421.221974) (xy 359.242684 -421.270401)
			(xy 359.146022 -421.326208) (xy 359.053801 -421.389082) (xy 358.966536 -421.458672) (xy 358.884716 -421.534589)
			(xy 358.808797 -421.616407) (xy 358.739205 -421.70367) (xy 358.676328 -421.79589) (xy 358.620519 -421.892551)
			(xy 358.572089 -421.993111) (xy 358.53131 -422.09701) (xy 358.498408 -422.203666) (xy 358.473569 -422.312482)
			(xy 358.456931 -422.42285) (xy 358.448587 -422.534152) (xy 358.448102 -422.58996) (xy 358.448102 -429.090074)
			(xy 358.447618 -429.160429) (xy 358.43973 -429.300916) (xy 358.423977 -429.440741) (xy 358.400409 -429.579462)
			(xy 358.369099 -429.716643) (xy 358.330147 -429.851853) (xy 358.283675 -429.984667) (xy 358.229829 -430.114665)
			(xy 358.168779 -430.24144) (xy 358.100716 -430.364593) (xy 358.025856 -430.483735) (xy 357.944432 -430.598492)
			(xy 357.856702 -430.708504) (xy 357.762942 -430.813423) (xy 357.663446 -430.91292) (xy 357.558528 -431.006682)
			(xy 357.448518 -431.094413) (xy 357.333762 -431.175838) (xy 357.21462 -431.2507) (xy 357.091469 -431.318764)
			(xy 356.964695 -431.379816) (xy 356.834697 -431.433664) (xy 356.701884 -431.480138) (xy 356.566674 -431.519091)
			(xy 356.429493 -431.550403) (xy 356.290772 -431.573973) (xy 356.150948 -431.589728) (xy 356.010461 -431.597618)
			(xy 355.940106 -431.59807) (xy 283.239972 -431.59807) (xy 283.169619 -431.597576) (xy 283.029135 -431.589685)
			(xy 282.889313 -431.573929) (xy 282.750596 -431.550359) (xy 282.613418 -431.519047) (xy 282.478212 -431.480093)
			(xy 282.345402 -431.43362) (xy 282.215407 -431.379772) (xy 282.088636 -431.318721) (xy 281.965488 -431.250657)
			(xy 281.84635 -431.175796) (xy 281.731596 -431.094372) (xy 281.621589 -431.006642) (xy 281.516674 -430.912882)
			(xy 281.417181 -430.813387) (xy 281.323423 -430.70847) (xy 281.235695 -430.598461) (xy 281.154274 -430.483705)
			(xy 281.079415 -430.364565) (xy 281.011354 -430.241416) (xy 280.950306 -430.114643) (xy 280.896461 -429.984647)
			(xy 280.84999 -429.851837) (xy 280.811039 -429.71663) (xy 280.779731 -429.579451) (xy 280.756163 -429.440733)
			(xy 280.740411 -429.300912) (xy 280.732523 -429.160427) (xy 280.731976 -429.090074) (xy 280.731976 -422.58996)
			(xy 280.731453 -422.534154) (xy 280.723109 -422.422855) (xy 280.706471 -422.31249) (xy 280.681633 -422.203678)
			(xy 280.648732 -422.097025) (xy 280.607953 -421.99313) (xy 280.559525 -421.892573) (xy 280.503717 -421.795915)
			(xy 280.440842 -421.703699) (xy 280.371251 -421.616439) (xy 280.295334 -421.534623) (xy 280.213516 -421.45871)
			(xy 280.126253 -421.389123) (xy 280.034034 -421.326251) (xy 279.937374 -421.270447) (xy 279.836815 -421.222023)
			(xy 279.732918 -421.181248) (xy 279.626264 -421.148352) (xy 279.517451 -421.123517) (xy 279.407085 -421.106884)
			(xy 279.295786 -421.098545) (xy 279.23998 -421.097964) (xy 276.880066 -421.097964) (xy 276.824259 -421.098487)
			(xy 276.712958 -421.10683) (xy 276.602591 -421.123467) (xy 276.493777 -421.148305) (xy 276.387122 -421.181205)
			(xy 276.283225 -421.221984) (xy 276.182665 -421.270412) (xy 276.086005 -421.326219) (xy 275.993786 -421.389094)
			(xy 275.906523 -421.458684) (xy 275.824704 -421.5346) (xy 275.748787 -421.616418) (xy 275.679197 -421.703681)
			(xy 275.616322 -421.7959) (xy 275.560514 -421.892559) (xy 275.512086 -421.993119) (xy 275.471307 -422.097017)
			(xy 275.438407 -422.203671) (xy 275.413568 -422.312485) (xy 275.396931 -422.422852) (xy 275.388587 -422.534153)
			(xy 275.38807 -422.58996) (xy 275.38807 -430.55794) (xy 275.387576 -430.628293) (xy 275.379684 -430.768777)
			(xy 275.363928 -430.908597) (xy 275.340357 -431.047314) (xy 275.309045 -431.184492) (xy 275.27009 -431.319698)
			(xy 275.223616 -431.452506) (xy 275.169769 -431.582501) (xy 275.108717 -431.709271) (xy 275.040653 -431.832419)
			(xy 274.965792 -431.951557) (xy 274.884368 -432.066309) (xy 274.796638 -432.176316) (xy 274.702878 -432.281231)
			(xy 274.603383 -432.380723) (xy 274.498466 -432.474481) (xy 274.388457 -432.562208) (xy 274.273702 -432.643629)
			(xy 274.154562 -432.718487) (xy 274.031412 -432.786547) (xy 273.90464 -432.847596) (xy 273.774645 -432.90144)
			(xy 273.641835 -432.94791) (xy 273.506628 -432.986861) (xy 273.36945 -433.018169) (xy 273.230732 -433.041737)
			(xy 273.090911 -433.05749) (xy 272.950427 -433.065377) (xy 272.880074 -433.065936) (xy 202.360022 -433.065936)
			(xy 202.289667 -433.065443) (xy 202.14918 -433.057555) (xy 202.009355 -433.041802) (xy 201.870634 -433.018234)
			(xy 201.733452 -432.986924) (xy 201.598242 -432.947972) (xy 201.465429 -432.9015) (xy 201.33543 -432.847655)
			(xy 201.208655 -432.786605) (xy 201.085502 -432.718542) (xy 200.96636 -432.643682) (xy 200.851602 -432.562259)
			(xy 200.74159 -432.47453) (xy 200.63667 -432.38077) (xy 200.537173 -432.281275) (xy 200.44341 -432.176357)
			(xy 200.355678 -432.066348) (xy 200.274252 -431.951592) (xy 200.199389 -431.832451) (xy 200.131324 -431.7093)
			(xy 200.070271 -431.582527) (xy 200.016422 -431.452529) (xy 199.969947 -431.319717) (xy 199.930991 -431.184508)
			(xy 199.899679 -431.047327) (xy 199.876107 -430.908606) (xy 199.86035 -430.768782) (xy 199.852458 -430.628295)
			(xy 199.852026 -430.55794) (xy 199.852026 -422.58996) (xy 199.851503 -422.534154) (xy 199.843159 -422.422853)
			(xy 199.826522 -422.312487) (xy 199.801683 -422.203673) (xy 199.768783 -422.097019) (xy 199.728004 -421.993122)
			(xy 199.679576 -421.892563) (xy 199.623769 -421.795904) (xy 199.560894 -421.703685) (xy 199.491304 -421.616423)
			(xy 199.415387 -421.534606) (xy 199.333569 -421.45869) (xy 199.246306 -421.3891) (xy 199.154088 -421.326226)
			(xy 199.057428 -421.270419) (xy 198.956869 -421.221992) (xy 198.852972 -421.181214) (xy 198.746318 -421.148314)
			(xy 198.637503 -421.123476) (xy 198.527137 -421.10684) (xy 198.415836 -421.098497) (xy 198.36003 -421.097964)
			(xy 188.36005 -421.097964) (xy 188.304244 -421.098488) (xy 188.192943 -421.106832) (xy 188.082578 -421.12347)
			(xy 187.973764 -421.148309) (xy 187.86711 -421.18121) (xy 187.763214 -421.221988) (xy 187.662655 -421.270417)
			(xy 187.565996 -421.326225) (xy 187.473778 -421.389099) (xy 187.386516 -421.458689) (xy 187.304699 -421.534606)
			(xy 187.228783 -421.616424) (xy 187.159193 -421.703686) (xy 187.096319 -421.795905) (xy 187.040512 -421.892564)
			(xy 186.992084 -421.993123) (xy 186.951306 -422.09702) (xy 186.918406 -422.203673) (xy 186.893568 -422.312487)
			(xy 186.876931 -422.422853) (xy 186.868587 -422.534154) (xy 186.868054 -422.58996) (xy 186.868054 -429.090074)
			(xy 186.86757 -429.160428) (xy 186.859682 -429.300915) (xy 186.843929 -429.440738) (xy 186.820361 -429.579458)
			(xy 186.789051 -429.716639) (xy 186.750099 -429.851848) (xy 186.703626 -429.98466) (xy 186.64978 -430.114658)
			(xy 186.58873 -430.241431) (xy 186.520667 -430.364582) (xy 186.445806 -430.483723) (xy 186.364382 -430.598479)
			(xy 186.276652 -430.708489) (xy 186.182891 -430.813407) (xy 186.083395 -430.912902) (xy 185.978477 -431.006662)
			(xy 185.868467 -431.094392) (xy 185.75371 -431.175815) (xy 185.634569 -431.250675) (xy 185.511417 -431.318737)
			(xy 185.384643 -431.379787) (xy 185.254645 -431.433632) (xy 185.121833 -431.480104) (xy 184.986623 -431.519055)
			(xy 184.849443 -431.550364) (xy 184.710722 -431.573931) (xy 184.570899 -431.589684) (xy 184.430412 -431.597571)
			(xy 184.360058 -431.59807) (xy 111.660178 -431.59807) (xy 111.589825 -431.597585) (xy 111.449339 -431.589694)
			(xy 111.309518 -431.573939) (xy 111.170799 -431.550369) (xy 111.033621 -431.519057) (xy 110.898414 -431.480103)
			(xy 110.765603 -431.43363) (xy 110.635608 -431.379782) (xy 110.508836 -431.318731) (xy 110.385687 -431.250667)
			(xy 110.266548 -431.175806) (xy 110.151794 -431.094382) (xy 110.041786 -431.006651) (xy 109.93687 -430.912891)
			(xy 109.837376 -430.813395) (xy 109.743618 -430.708478) (xy 109.65589 -430.598468) (xy 109.574468 -430.483712)
			(xy 109.499608 -430.364572) (xy 109.431547 -430.241421) (xy 109.370498 -430.114648) (xy 109.316653 -429.984652)
			(xy 109.270182 -429.851841) (xy 109.231231 -429.716633) (xy 109.199922 -429.579454) (xy 109.176354 -429.440735)
			(xy 109.160602 -429.300913) (xy 109.152714 -429.160427) (xy 109.152182 -429.090074) (xy 109.152182 -422.58996)
			(xy 109.151659 -422.534154) (xy 109.143315 -422.422855) (xy 109.126678 -422.31249) (xy 109.101839 -422.203677)
			(xy 109.068938 -422.097025) (xy 109.02816 -421.993129) (xy 108.979731 -421.892571) (xy 108.923923 -421.795914)
			(xy 108.861048 -421.703697) (xy 108.791457 -421.616437) (xy 108.715541 -421.534621) (xy 108.633722 -421.458707)
			(xy 108.546459 -421.38912) (xy 108.45424 -421.326248) (xy 108.357581 -421.270444) (xy 108.257021 -421.222019)
			(xy 108.153124 -421.181244) (xy 108.046471 -421.148347) (xy 107.937657 -421.123512) (xy 107.827292 -421.106879)
			(xy 107.715992 -421.098539) (xy 107.660186 -421.097964) (xy 100.359972 -421.097964) (xy 100.304165 -421.098487)
			(xy 100.192864 -421.106829) (xy 100.082497 -421.123466) (xy 99.973681 -421.148304) (xy 99.867027 -421.181204)
			(xy 99.763129 -421.221982) (xy 99.662568 -421.27041) (xy 99.565908 -421.326217) (xy 99.473689 -421.389091)
			(xy 99.386425 -421.458681) (xy 99.304606 -421.534598) (xy 99.228689 -421.616416) (xy 99.159099 -421.703679)
			(xy 99.096223 -421.795898) (xy 99.040415 -421.892558) (xy 98.991987 -421.993118) (xy 98.951208 -422.097015)
			(xy 98.918307 -422.20367) (xy 98.893468 -422.312485) (xy 98.876831 -422.422852) (xy 98.868487 -422.534153)
			(xy 98.867976 -422.58996) (xy 98.867976 -429.090074) (xy 98.867492 -429.160428) (xy 98.859604 -429.300915)
			(xy 98.843851 -429.440739) (xy 98.820283 -429.57946) (xy 98.788973 -429.716641) (xy 98.750021 -429.85185)
			(xy 98.703549 -429.984663) (xy 98.649703 -430.114661) (xy 98.588652 -430.241435) (xy 98.520589 -430.364587)
			(xy 98.445729 -430.483729) (xy 98.364305 -430.598485) (xy 98.276575 -430.708496) (xy 98.182814 -430.813414)
			(xy 98.083319 -430.91291) (xy 97.9784 -431.006671) (xy 97.86839 -431.094401) (xy 97.753634 -431.175825)
			(xy 97.634492 -431.250686) (xy 97.511341 -431.31875) (xy 97.384567 -431.3798) (xy 97.254569 -431.433647)
			(xy 97.121756 -431.480119) (xy 96.986547 -431.519072) (xy 96.849366 -431.550382) (xy 96.710645 -431.57395)
			(xy 96.570821 -431.589704) (xy 96.430334 -431.597592) (xy 96.35998 -431.59807) (xy 23.6601 -431.59807)
			(xy 23.589746 -431.597586) (xy 23.44926 -431.589696) (xy 23.309437 -431.573942) (xy 23.170718 -431.550372)
			(xy 23.033539 -431.519062) (xy 22.89833 -431.480109) (xy 22.765519 -431.433636) (xy 22.635522 -431.379789)
			(xy 22.50875 -431.318738) (xy 22.385599 -431.250675) (xy 22.266459 -431.175813) (xy 22.151704 -431.094389)
			(xy 22.041695 -431.006659) (xy 21.936778 -430.912899) (xy 21.837283 -430.813403) (xy 21.743524 -430.708485)
			(xy 21.655795 -430.598475) (xy 21.574372 -430.483719) (xy 21.499512 -430.364578) (xy 21.43145 -430.241427)
			(xy 21.370401 -430.114654) (xy 21.316555 -429.984657) (xy 21.270083 -429.851845) (xy 21.231132 -429.716636)
			(xy 21.199823 -429.579456) (xy 21.176255 -429.440737) (xy 21.160502 -429.300914) (xy 21.152614 -429.160428)
			(xy 21.152104 -429.090074) (xy 21.152104 -422.58996) (xy 21.151595 -422.534153) (xy 21.143254 -422.42285)
			(xy 21.126618 -422.312481) (xy 21.101782 -422.203665) (xy 21.068883 -422.097009) (xy 21.028105 -421.993109)
			(xy 20.979677 -421.892548) (xy 20.92387 -421.795886) (xy 20.860995 -421.703666) (xy 20.791404 -421.616402)
			(xy 20.715486 -421.534582) (xy 20.633667 -421.458665) (xy 20.546403 -421.389074) (xy 20.454182 -421.326199)
			(xy 20.357521 -421.270392) (xy 20.256959 -421.221964) (xy 20.153059 -421.181187) (xy 20.046403 -421.148288)
			(xy 19.937587 -421.123451) (xy 19.827218 -421.106816) (xy 19.715915 -421.098475) (xy 19.660108 -421.097964)
			(xy 1.999996 -421.097964) (xy 1.944189 -421.098486) (xy 1.832887 -421.106827) (xy 1.72252 -421.123463)
			(xy 1.613705 -421.148299) (xy 1.50705 -421.181198) (xy 1.403151 -421.221976) (xy 1.302591 -421.270403)
			(xy 1.20593 -421.32621) (xy 1.113711 -421.389085) (xy 1.026448 -421.458675) (xy 0.944629 -421.534592)
			(xy 0.868712 -421.616411) (xy 0.799122 -421.703674) (xy 0.736248 -421.795894) (xy 0.680441 -421.892554)
			(xy 0.632014 -421.993115) (xy 0.591237 -422.097013) (xy 0.558338 -422.203669) (xy 0.533502 -422.312484)
			(xy 0.516867 -422.422851) (xy 0.508526 -422.534153) (xy 0.508 -422.58996) (xy 0.508 -457.5681) (xy 2.904225 -457.5681)
			(xy 2.904225 -457.43896) (xy 2.912175 -457.310065) (xy 2.928045 -457.181905) (xy 2.951774 -457.054964)
			(xy 2.983273 -456.929725) (xy 3.022422 -456.806662) (xy 3.069073 -456.686243) (xy 3.123048 -456.568924)
			(xy 3.184143 -456.45515) (xy 3.252126 -456.345353) (xy 3.32674 -456.23995) (xy 3.407701 -456.13934)
			(xy 3.494701 -456.043905) (xy 3.587412 -455.954006) (xy 3.685482 -455.869985) (xy 3.788537 -455.792161)
			(xy 3.896188 -455.720829) (xy 4.008027 -455.656259) (xy 4.123628 -455.598697) (xy 4.242553 -455.54836)
			(xy 4.364352 -455.50544) (xy 4.488562 -455.470099) (xy 4.614711 -455.442472) (xy 4.742323 -455.422663)
			(xy 4.870912 -455.410747) (xy 4.99999 -455.406771) (xy 5.129068 -455.410747) (xy 5.257657 -455.422663)
			(xy 5.385269 -455.442472) (xy 5.511418 -455.470099) (xy 5.635628 -455.50544) (xy 5.757427 -455.54836)
			(xy 5.876352 -455.598697) (xy 5.991953 -455.656259) (xy 6.103792 -455.720829) (xy 6.211443 -455.792161)
			(xy 6.314498 -455.869985) (xy 6.412568 -455.954006) (xy 6.505279 -456.043905) (xy 6.592279 -456.13934)
			(xy 6.67324 -456.23995) (xy 6.747854 -456.345353) (xy 6.815837 -456.45515) (xy 6.876932 -456.568924)
			(xy 6.930907 -456.686243) (xy 6.977558 -456.806662) (xy 7.016707 -456.929725) (xy 7.048206 -457.054964)
			(xy 7.071935 -457.181905) (xy 7.087805 -457.310065) (xy 7.095755 -457.43896) (xy 7.096252 -457.50353)
			(xy 7.095755 -457.5681) (xy 460.504275 -457.5681) (xy 460.504275 -457.43896) (xy 460.512225 -457.310065)
			(xy 460.528095 -457.181905) (xy 460.551824 -457.054964) (xy 460.583323 -456.929725) (xy 460.622472 -456.806662)
			(xy 460.669123 -456.686243) (xy 460.723098 -456.568924) (xy 460.784193 -456.45515) (xy 460.852176 -456.345353)
			(xy 460.92679 -456.23995) (xy 461.007751 -456.13934) (xy 461.094751 -456.043905) (xy 461.187462 -455.954006)
			(xy 461.285532 -455.869985) (xy 461.388587 -455.792161) (xy 461.496238 -455.720829) (xy 461.608077 -455.656259)
			(xy 461.723678 -455.598697) (xy 461.842603 -455.54836) (xy 461.964402 -455.50544) (xy 462.088612 -455.470099)
			(xy 462.214761 -455.442472) (xy 462.342373 -455.422663) (xy 462.470962 -455.410747) (xy 462.60004 -455.406771)
			(xy 462.729118 -455.410747) (xy 462.857707 -455.422663) (xy 462.985319 -455.442472) (xy 463.111468 -455.470099)
			(xy 463.235678 -455.50544) (xy 463.357477 -455.54836) (xy 463.476402 -455.598697) (xy 463.592003 -455.656259)
			(xy 463.703842 -455.720829) (xy 463.811493 -455.792161) (xy 463.914548 -455.869985) (xy 464.012618 -455.954006)
			(xy 464.105329 -456.043905) (xy 464.192329 -456.13934) (xy 464.27329 -456.23995) (xy 464.347904 -456.345353)
			(xy 464.415887 -456.45515) (xy 464.476982 -456.568924) (xy 464.530957 -456.686243) (xy 464.577608 -456.806662)
			(xy 464.616757 -456.929725) (xy 464.648256 -457.054964) (xy 464.671985 -457.181905) (xy 464.687855 -457.310065)
			(xy 464.695805 -457.43896) (xy 464.696302 -457.50353) (xy 464.695805 -457.5681) (xy 464.687855 -457.696995)
			(xy 464.671985 -457.825155) (xy 464.648256 -457.952096) (xy 464.616757 -458.077335) (xy 464.577608 -458.200398)
			(xy 464.530957 -458.320817) (xy 464.476982 -458.438136) (xy 464.415887 -458.55191) (xy 464.347904 -458.661707)
			(xy 464.27329 -458.76711) (xy 464.192329 -458.86772) (xy 464.105329 -458.963155) (xy 464.012618 -459.053054)
			(xy 463.914548 -459.137075) (xy 463.811493 -459.214899) (xy 463.703842 -459.286231) (xy 463.592003 -459.350801)
			(xy 463.476402 -459.408363) (xy 463.357477 -459.4587) (xy 463.235678 -459.50162) (xy 463.111468 -459.536961)
			(xy 462.985319 -459.564588) (xy 462.857707 -459.584397) (xy 462.729118 -459.596313) (xy 462.60004 -459.60029)
			(xy 462.470962 -459.596313) (xy 462.342373 -459.584397) (xy 462.214761 -459.564588) (xy 462.088612 -459.536961)
			(xy 461.964402 -459.50162) (xy 461.842603 -459.4587) (xy 461.723678 -459.408363) (xy 461.608077 -459.350801)
			(xy 461.496238 -459.286231) (xy 461.388587 -459.214899) (xy 461.285532 -459.137075) (xy 461.187462 -459.053054)
			(xy 461.094751 -458.963155) (xy 461.007751 -458.86772) (xy 460.92679 -458.76711) (xy 460.852176 -458.661707)
			(xy 460.784193 -458.55191) (xy 460.723098 -458.438136) (xy 460.669123 -458.320817) (xy 460.622472 -458.200398)
			(xy 460.583323 -458.077335) (xy 460.551824 -457.952096) (xy 460.528095 -457.825155) (xy 460.512225 -457.696995)
			(xy 460.504275 -457.5681) (xy 7.095755 -457.5681) (xy 7.087805 -457.696995) (xy 7.071935 -457.825155)
			(xy 7.048206 -457.952096) (xy 7.016707 -458.077335) (xy 6.977558 -458.200398) (xy 6.930907 -458.320817)
			(xy 6.876932 -458.438136) (xy 6.815837 -458.55191) (xy 6.747854 -458.661707) (xy 6.67324 -458.76711)
			(xy 6.592279 -458.86772) (xy 6.505279 -458.963155) (xy 6.412568 -459.053054) (xy 6.314498 -459.137075)
			(xy 6.211443 -459.214899) (xy 6.103792 -459.286231) (xy 5.991953 -459.350801) (xy 5.876352 -459.408363)
			(xy 5.757427 -459.4587) (xy 5.635628 -459.50162) (xy 5.511418 -459.536961) (xy 5.385269 -459.564588)
			(xy 5.257657 -459.584397) (xy 5.129068 -459.596313) (xy 4.99999 -459.60029) (xy 4.870912 -459.596313)
			(xy 4.742323 -459.584397) (xy 4.614711 -459.564588) (xy 4.488562 -459.536961) (xy 4.364352 -459.50162)
			(xy 4.242553 -459.4587) (xy 4.123628 -459.408363) (xy 4.008027 -459.350801) (xy 3.896188 -459.286231)
			(xy 3.788537 -459.214899) (xy 3.685482 -459.137075) (xy 3.587412 -459.053054) (xy 3.494701 -458.963155)
			(xy 3.407701 -458.86772) (xy 3.32674 -458.76711) (xy 3.252126 -458.661707) (xy 3.184143 -458.55191)
			(xy 3.123048 -458.438136) (xy 3.069073 -458.320817) (xy 3.022422 -458.200398) (xy 2.983273 -458.077335)
			(xy 2.951774 -457.952096) (xy 2.928045 -457.825155) (xy 2.912175 -457.696995) (xy 2.904225 -457.5681)
			(xy 0.508 -457.5681) (xy 0.508 -460.503524) (xy 0.508522 -460.559331) (xy 0.516863 -460.670633) (xy 0.533498 -460.781)
			(xy 0.558335 -460.889816) (xy 0.591234 -460.996471) (xy 0.632011 -461.10037) (xy 0.680438 -461.20093)
			(xy 0.736246 -461.297591) (xy 0.79912 -461.389811) (xy 0.86871 -461.477074) (xy 0.944627 -461.558893)
			(xy 1.026446 -461.63481) (xy 1.113709 -461.7044) (xy 1.205929 -461.767274) (xy 1.30259 -461.823082)
			(xy 1.40315 -461.871509) (xy 1.507049 -461.912286) (xy 1.613704 -461.945185) (xy 1.72252 -461.970022)
			(xy 1.832887 -461.986657) (xy 1.944189 -461.994998) (xy 1.999996 -461.99552)
		)
		(stroke
			(width 0)
			(type solid)
		)
		(fill yes)
		(layer "In12.Cu")
		(net "COUPON_GND1")
	)
	(gr_poly
		(pts
			(xy 13.96492 -10.342118) (xy 14.020727 -10.341596) (xy 14.132028 -10.333253) (xy 14.242395 -10.316617)
			(xy 14.35121 -10.29178) (xy 14.457865 -10.25888) (xy 14.561763 -10.218102) (xy 14.662323 -10.169674)
			(xy 14.758983 -10.113867) (xy 14.851203 -10.050993) (xy 14.938466 -9.981402) (xy 15.020284 -9.905486)
			(xy 15.096201 -9.823667) (xy 15.165791 -9.736404) (xy 15.228666 -9.644185) (xy 15.284473 -9.547525)
			(xy 15.332901 -9.446965) (xy 15.373679 -9.343067) (xy 15.406579 -9.236412) (xy 15.431417 -9.127597)
			(xy 15.448053 -9.01723) (xy 15.456395 -8.905929) (xy 15.456916 -8.850122) (xy 15.456916 0) (xy 15.4574 0.070354)
			(xy 15.46529 0.21084) (xy 15.481044 0.350663) (xy 15.504614 0.489383) (xy 15.535924 0.626563) (xy 15.574877 0.761771)
			(xy 15.62135 0.894583) (xy 15.675197 1.02458) (xy 15.736248 1.151353) (xy 15.804311 1.274504) (xy 15.879172 1.393644)
			(xy 15.960596 1.5084) (xy 16.048326 1.618409) (xy 16.142086 1.723327) (xy 16.241582 1.822822) (xy 16.3465 1.916582)
			(xy 16.45651 2.004311) (xy 16.571266 2.085734) (xy 16.690407 2.160595) (xy 16.813558 2.228658) (xy 16.940331 2.289708)
			(xy 17.070328 2.343554) (xy 17.20314 2.390026) (xy 17.338349 2.428979) (xy 17.475529 2.460289) (xy 17.614249 2.483858)
			(xy 17.754072 2.499611) (xy 17.894558 2.5075) (xy 17.964912 2.507996) (xy 33.96488 2.507996) (xy 34.035234 2.507512)
			(xy 34.175722 2.499624) (xy 34.315546 2.48387) (xy 34.454267 2.460302) (xy 34.591448 2.428992) (xy 34.726657 2.39004)
			(xy 34.85947 2.343568) (xy 34.989468 2.289721) (xy 35.116243 2.228671) (xy 35.239395 2.160608) (xy 35.358537 2.085747)
			(xy 35.473294 2.004324) (xy 35.583304 1.916594) (xy 35.688223 1.822833) (xy 35.78772 1.723338) (xy 35.881481 1.61842)
			(xy 35.969212 1.50841) (xy 36.050636 1.393653) (xy 36.125498 1.274512) (xy 36.193562 1.151361) (xy 36.254613 1.024587)
			(xy 36.30846 0.894589) (xy 36.354934 0.761776) (xy 36.393887 0.626567) (xy 36.425198 0.489386) (xy 36.448768 0.350666)
			(xy 36.464522 0.210842) (xy 36.472412 0.070354) (xy 36.472876 0) (xy 36.472876 -8.850122) (xy 36.473399 -8.905929)
			(xy 36.481741 -9.01723) (xy 36.498377 -9.127597) (xy 36.523215 -9.236413) (xy 36.556114 -9.343067)
			(xy 36.596892 -9.446965) (xy 36.64532 -9.547526) (xy 36.701127 -9.644186) (xy 36.764002 -9.736405)
			(xy 36.833592 -9.823668) (xy 36.909508 -9.905487) (xy 36.991327 -9.981404) (xy 37.07859 -10.050995)
			(xy 37.170809 -10.113869) (xy 37.267469 -10.169677) (xy 37.368029 -10.218105) (xy 37.471927 -10.258884)
			(xy 37.578582 -10.291784) (xy 37.687397 -10.316622) (xy 37.797764 -10.333258) (xy 37.909065 -10.341601)
			(xy 37.964872 -10.342118) (xy 39.965122 -10.342118) (xy 40.020929 -10.341595) (xy 40.13223 -10.333253)
			(xy 40.242597 -10.316617) (xy 40.351412 -10.291779) (xy 40.458067 -10.258879) (xy 40.561964 -10.218102)
			(xy 40.662525 -10.169674) (xy 40.759184 -10.113866) (xy 40.851404 -10.050992) (xy 40.938667 -9.981402)
			(xy 41.020485 -9.905485) (xy 41.096402 -9.823667) (xy 41.165992 -9.736404) (xy 41.228866 -9.644184)
			(xy 41.284674 -9.547525) (xy 41.333102 -9.446964) (xy 41.373879 -9.343067) (xy 41.406779 -9.236412)
			(xy 41.431617 -9.127597) (xy 41.448253 -9.01723) (xy 41.456595 -8.905929) (xy 41.457118 -8.850122)
			(xy 41.457118 0) (xy 41.457602 0.070354) (xy 41.465492 0.21084) (xy 41.481246 0.350663) (xy 41.504816 0.489383)
			(xy 41.536126 0.626563) (xy 41.575079 0.761771) (xy 41.621552 0.894583) (xy 41.675399 1.02458) (xy 41.73645 1.151353)
			(xy 41.804513 1.274503) (xy 41.879374 1.393644) (xy 41.960798 1.508399) (xy 42.048528 1.618409) (xy 42.142288 1.723326)
			(xy 42.241784 1.822821) (xy 42.346702 1.916581) (xy 42.456712 2.00431) (xy 42.571468 2.085733) (xy 42.690609 2.160594)
			(xy 42.81376 2.228657) (xy 42.940533 2.289707) (xy 43.07053 2.343553) (xy 43.203342 2.390025) (xy 43.338551 2.428977)
			(xy 43.475731 2.460287) (xy 43.614451 2.483856) (xy 43.754274 2.499609) (xy 43.89476 2.507498) (xy 43.965114 2.507996)
			(xy 59.965082 2.507996) (xy 60.035436 2.507512) (xy 60.175924 2.499624) (xy 60.315748 2.48387) (xy 60.454468 2.460301)
			(xy 60.591649 2.428992) (xy 60.726859 2.390039) (xy 60.859672 2.343567) (xy 60.98967 2.289721) (xy 61.116444 2.22867)
			(xy 61.239596 2.160607) (xy 61.358738 2.085747) (xy 61.473495 2.004323) (xy 61.583505 1.916593) (xy 61.688424 1.822833)
			(xy 61.78792 1.723337) (xy 61.881681 1.618419) (xy 61.969412 1.508409) (xy 62.050837 1.393653) (xy 62.125698 1.274512)
			(xy 62.193762 1.15136) (xy 62.254813 1.024586) (xy 62.308661 0.894588) (xy 62.355134 0.761776) (xy 62.394087 0.626567)
			(xy 62.425398 0.489386) (xy 62.448968 0.350665) (xy 62.464722 0.210842) (xy 62.472612 0.070354) (xy 62.473078 0)
			(xy 62.473078 -8.850122) (xy 62.473601 -8.905929) (xy 62.481943 -9.01723) (xy 62.498579 -9.127597)
			(xy 62.523417 -9.236412) (xy 62.556316 -9.343067) (xy 62.597094 -9.446965) (xy 62.645522 -9.547525)
			(xy 62.701329 -9.644185) (xy 62.764204 -9.736405) (xy 62.833794 -9.823668) (xy 62.909711 -9.905487)
			(xy 62.991529 -9.981403) (xy 63.078792 -10.050994) (xy 63.171011 -10.113868) (xy 63.267671 -10.169676)
			(xy 63.368231 -10.218104) (xy 63.472129 -10.258882) (xy 63.578784 -10.291782) (xy 63.687599 -10.31662)
			(xy 63.797966 -10.333257) (xy 63.909267 -10.341599) (xy 63.965074 -10.342118) (xy 65.96507 -10.342118)
			(xy 66.020879 -10.34161) (xy 66.132184 -10.333271) (xy 66.242554 -10.316637) (xy 66.351373 -10.291802)
			(xy 66.458032 -10.258905) (xy 66.561934 -10.218128) (xy 66.662499 -10.169702) (xy 66.759163 -10.113895)
			(xy 66.851386 -10.05102) (xy 66.938653 -9.98143) (xy 67.020476 -9.905512) (xy 67.096396 -9.823693)
			(xy 67.165989 -9.736428) (xy 67.228867 -9.644207) (xy 67.284677 -9.547545) (xy 67.333108 -9.446982)
			(xy 67.373888 -9.343081) (xy 67.406789 -9.236424) (xy 67.431628 -9.127605) (xy 67.448265 -9.017235)
			(xy 67.456608 -8.905931) (xy 67.457066 -8.850122) (xy 67.457066 0) (xy 67.457559 0.070354) (xy 67.465449 0.210841)
			(xy 67.481203 0.350665) (xy 67.504772 0.489385) (xy 67.536082 0.626565) (xy 67.575035 0.761774) (xy 67.621508 0.894587)
			(xy 67.675354 1.024584) (xy 67.736404 1.151358) (xy 67.804467 1.27451) (xy 67.879328 1.393651) (xy 67.960751 1.508408)
			(xy 68.04848 1.618419) (xy 68.14224 1.723337) (xy 68.241735 1.822834) (xy 68.346652 1.916595) (xy 68.456662 2.004326)
			(xy 68.571417 2.085751) (xy 68.690557 2.160614) (xy 68.813708 2.228678) (xy 68.940481 2.289731) (xy 69.070478 2.343579)
			(xy 69.203289 2.390053) (xy 69.338498 2.429008) (xy 69.475678 2.46032) (xy 69.614398 2.483892) (xy 69.754221 2.499648)
			(xy 69.894708 2.50754) (xy 69.965062 2.507996) (xy 85.96503 2.507996) (xy 86.035383 2.507502) (xy 86.175868 2.499611)
			(xy 86.31569 2.483855) (xy 86.454408 2.460284) (xy 86.591586 2.428973) (xy 86.726793 2.390019) (xy 86.859603 2.343545)
			(xy 86.989598 2.289698) (xy 87.11637 2.228647) (xy 87.239519 2.160584) (xy 87.358658 2.085722) (xy 87.473412 2.004299)
			(xy 87.58342 1.916569) (xy 87.688336 1.822809) (xy 87.78783 1.723314) (xy 87.881588 1.618397) (xy 87.969317 1.508388)
			(xy 88.050739 1.393633) (xy 88.125599 1.274493) (xy 88.193661 1.151343) (xy 88.254711 1.024571) (xy 88.308556 0.894575)
			(xy 88.355028 0.761764) (xy 88.39398 0.626557) (xy 88.42529 0.489378) (xy 88.448859 0.35066) (xy 88.464613 0.210838)
			(xy 88.472503 0.070353) (xy 88.473026 0) (xy 88.473026 -8.850122) (xy 88.473549 -8.905928) (xy 88.481891 -9.017228)
			(xy 88.498528 -9.127594) (xy 88.523365 -9.236408) (xy 88.556265 -9.343061) (xy 88.597043 -9.446957)
			(xy 88.645472 -9.547516) (xy 88.701279 -9.644174) (xy 88.764154 -9.736392) (xy 88.833745 -9.823653)
			(xy 88.909662 -9.90547) (xy 88.99148 -9.981384) (xy 89.078743 -10.050972) (xy 89.170963 -10.113844)
			(xy 89.267623 -10.169649) (xy 89.368183 -10.218074) (xy 89.472081 -10.258849) (xy 89.578735 -10.291746)
			(xy 89.687549 -10.316581) (xy 89.797915 -10.333214) (xy 89.909216 -10.341553) (xy 89.965022 -10.342118)
			(xy 91.965018 -10.342118) (xy 92.020825 -10.341596) (xy 92.132127 -10.333254) (xy 92.242494 -10.316617)
			(xy 92.351309 -10.29178) (xy 92.457964 -10.258881) (xy 92.561862 -10.218103) (xy 92.662422 -10.169675)
			(xy 92.759082 -10.113868) (xy 92.851302 -10.050993) (xy 92.938565 -9.981403) (xy 93.020384 -9.905487)
			(xy 93.096301 -9.823668) (xy 93.165891 -9.736405) (xy 93.228766 -9.644186) (xy 93.284573 -9.547526)
			(xy 93.333001 -9.446965) (xy 93.373779 -9.343067) (xy 93.406679 -9.236413) (xy 93.431517 -9.127597)
			(xy 93.448153 -9.01723) (xy 93.456495 -8.905929) (xy 93.457014 -8.850122) (xy 93.457014 0) (xy 93.457498 0.070354)
			(xy 93.465388 0.21084) (xy 93.481142 0.350663) (xy 93.504712 0.489383) (xy 93.536022 0.626563) (xy 93.574975 0.761771)
			(xy 93.621448 0.894583) (xy 93.675295 1.02458) (xy 93.736346 1.151353) (xy 93.804409 1.274504) (xy 93.87927 1.393645)
			(xy 93.960694 1.5084) (xy 94.048424 1.61841) (xy 94.142184 1.723327) (xy 94.24168 1.822823) (xy 94.346598 1.916583)
			(xy 94.456608 2.004312) (xy 94.571364 2.085735) (xy 94.690505 2.160596) (xy 94.813655 2.228659) (xy 94.940429 2.289709)
			(xy 95.070426 2.343555) (xy 95.203238 2.390028) (xy 95.338447 2.42898) (xy 95.475627 2.46029) (xy 95.614347 2.483859)
			(xy 95.75417 2.499613) (xy 95.894656 2.507502) (xy 95.96501 2.507996) (xy 124.06503 2.507996) (xy 124.135383 2.507502)
			(xy 124.275868 2.499611) (xy 124.41569 2.483855) (xy 124.554408 2.460284) (xy 124.691586 2.428973)
			(xy 124.826793 2.390019) (xy 124.959603 2.343545) (xy 125.089598 2.289698) (xy 125.21637 2.228647)
			(xy 125.339519 2.160584) (xy 125.458658 2.085722) (xy 125.573412 2.004299) (xy 125.68342 1.916569)
			(xy 125.788336 1.822809) (xy 125.88783 1.723314) (xy 125.981588 1.618397) (xy 126.069317 1.508388)
			(xy 126.150739 1.393633) (xy 126.225599 1.274493) (xy 126.293661 1.151343) (xy 126.354711 1.024571)
			(xy 126.408556 0.894575) (xy 126.455028 0.761764) (xy 126.49398 0.626557) (xy 126.52529 0.489378)
			(xy 126.548859 0.35066) (xy 126.564613 0.210838) (xy 126.572503 0.070353) (xy 126.573026 0) (xy 126.573026 -8.850122)
			(xy 126.573549 -8.905928) (xy 126.581891 -9.017228) (xy 126.598528 -9.127594) (xy 126.623365 -9.236408)
			(xy 126.656265 -9.343061) (xy 126.697043 -9.446957) (xy 126.745472 -9.547516) (xy 126.801279 -9.644174)
			(xy 126.864154 -9.736392) (xy 126.933745 -9.823653) (xy 127.009662 -9.90547) (xy 127.09148 -9.981384)
			(xy 127.178743 -10.050972) (xy 127.270963 -10.113844) (xy 127.367623 -10.169649) (xy 127.468183 -10.218074)
			(xy 127.572081 -10.258849) (xy 127.678735 -10.291746) (xy 127.787549 -10.316581) (xy 127.897915 -10.333214)
			(xy 128.009216 -10.341553) (xy 128.065022 -10.342118) (xy 130.065018 -10.342118) (xy 130.120825 -10.341596)
			(xy 130.232127 -10.333254) (xy 130.342494 -10.316617) (xy 130.451309 -10.29178) (xy 130.557964 -10.258881)
			(xy 130.661862 -10.218103) (xy 130.762422 -10.169675) (xy 130.859082 -10.113868) (xy 130.951302 -10.050993)
			(xy 131.038565 -9.981403) (xy 131.120384 -9.905487) (xy 131.196301 -9.823668) (xy 131.265891 -9.736405)
			(xy 131.328766 -9.644186) (xy 131.384573 -9.547526) (xy 131.433001 -9.446965) (xy 131.473779 -9.343067)
			(xy 131.506679 -9.236413) (xy 131.531517 -9.127597) (xy 131.548153 -9.01723) (xy 131.556495 -8.905929)
			(xy 131.557014 -8.850122) (xy 131.557014 0) (xy 131.557498 0.070354) (xy 131.565388 0.21084) (xy 131.581142 0.350663)
			(xy 131.604712 0.489383) (xy 131.636022 0.626563) (xy 131.674975 0.761771) (xy 131.721448 0.894583)
			(xy 131.775295 1.02458) (xy 131.836346 1.151353) (xy 131.904409 1.274504) (xy 131.97927 1.393645)
			(xy 132.060694 1.5084) (xy 132.148424 1.61841) (xy 132.242184 1.723327) (xy 132.34168 1.822823) (xy 132.446598 1.916583)
			(xy 132.556608 2.004312) (xy 132.671364 2.085735) (xy 132.790505 2.160596) (xy 132.913655 2.228659)
			(xy 133.040429 2.289709) (xy 133.170426 2.343555) (xy 133.303238 2.390028) (xy 133.438447 2.42898)
			(xy 133.575627 2.46029) (xy 133.714347 2.483859) (xy 133.85417 2.499613) (xy 133.994656 2.507502)
			(xy 134.06501 2.507996) (xy 150.064978 2.507996) (xy 150.135332 2.507512) (xy 150.27582 2.499624)
			(xy 150.415644 2.483871) (xy 150.554365 2.460302) (xy 150.691546 2.428993) (xy 150.826756 2.39004)
			(xy 150.959569 2.343568) (xy 151.089567 2.289722) (xy 151.216342 2.228672) (xy 151.339494 2.160609)
			(xy 151.458636 2.085748) (xy 151.573393 2.004324) (xy 151.683404 1.916594) (xy 151.788322 1.822834)
			(xy 151.887819 1.723338) (xy 151.98158 1.61842) (xy 152.069311 1.50841) (xy 152.150736 1.393654)
			(xy 152.225598 1.274513) (xy 152.293661 1.151361) (xy 152.354713 1.024587) (xy 152.40856 0.894589)
			(xy 152.455034 0.761777) (xy 152.493987 0.626567) (xy 152.525298 0.489386) (xy 152.548868 0.350666)
			(xy 152.564622 0.210842) (xy 152.572512 0.070354) (xy 152.572974 0) (xy 152.572974 -8.850122) (xy 152.573497 -8.905929)
			(xy 152.581839 -9.017231) (xy 152.598475 -9.127598) (xy 152.623313 -9.236413) (xy 152.656212 -9.343068)
			(xy 152.69699 -9.446966) (xy 152.745418 -9.547526) (xy 152.801225 -9.644186) (xy 152.8641 -9.736406)
			(xy 152.93369 -9.823669) (xy 153.009606 -9.905488) (xy 153.091425 -9.981405) (xy 153.178688 -10.050995)
			(xy 153.270907 -10.11387) (xy 153.367567 -10.169678) (xy 153.468127 -10.218107) (xy 153.572025 -10.258885)
			(xy 153.67868 -10.291785) (xy 153.787495 -10.316623) (xy 153.897862 -10.33326) (xy 154.009163 -10.341603)
			(xy 154.06497 -10.342118) (xy 156.064966 -10.342118) (xy 156.120775 -10.34161) (xy 156.23208 -10.333271)
			(xy 156.342451 -10.316638) (xy 156.45127 -10.291803) (xy 156.557929 -10.258906) (xy 156.661832 -10.21813)
			(xy 156.762396 -10.169703) (xy 156.859061 -10.113896) (xy 156.951284 -10.051022) (xy 157.038552 -9.981431)
			(xy 157.120374 -9.905514) (xy 157.196295 -9.823694) (xy 157.265888 -9.736429) (xy 157.328766 -9.644208)
			(xy 157.384577 -9.547546) (xy 157.433007 -9.446983) (xy 157.473787 -9.343082) (xy 157.506689 -9.236424)
			(xy 157.531528 -9.127606) (xy 157.548165 -9.017236) (xy 157.556508 -8.905931) (xy 157.556962 -8.850122)
			(xy 157.556962 0) (xy 157.557455 0.070354) (xy 157.565345 0.210841) (xy 157.581099 0.350665) (xy 157.604668 0.489385)
			(xy 157.635978 0.626566) (xy 157.674931 0.761775) (xy 157.721404 0.894587) (xy 157.77525 1.024585)
			(xy 157.8363 1.151359) (xy 157.904363 1.274511) (xy 157.979224 1.393652) (xy 158.060647 1.508409)
			(xy 158.148376 1.61842) (xy 158.242136 1.723339) (xy 158.341631 1.822835) (xy 158.446548 1.916597)
			(xy 158.556557 2.004328) (xy 158.671313 2.085753) (xy 158.790453 2.160616) (xy 158.913604 2.22868)
			(xy 159.040377 2.289733) (xy 159.170374 2.343581) (xy 159.303185 2.390056) (xy 159.438394 2.429011)
			(xy 159.575574 2.460324) (xy 159.714294 2.483895) (xy 159.854117 2.499652) (xy 159.994604 2.507544)
			(xy 160.064958 2.507996) (xy 176.064926 2.507996) (xy 176.135279 2.507502) (xy 176.275764 2.499611)
			(xy 176.415586 2.483856) (xy 176.554304 2.460285) (xy 176.691483 2.428974) (xy 176.82669 2.39002)
			(xy 176.9595 2.343547) (xy 177.089496 2.289699) (xy 177.216267 2.228648) (xy 177.339416 2.160585)
			(xy 177.458556 2.085724) (xy 177.57331 2.0043) (xy 177.683318 1.91657) (xy 177.788234 1.822811) (xy 177.887728 1.723315)
			(xy 177.981487 1.618398) (xy 178.069216 1.508389) (xy 178.150638 1.393634) (xy 178.225498 1.274494)
			(xy 178.29356 1.151344) (xy 178.35461 1.024572) (xy 178.408456 0.894576) (xy 178.454928 0.761765)
			(xy 178.49388 0.626558) (xy 178.52519 0.489379) (xy 178.548759 0.35066) (xy 178.564513 0.210838)
			(xy 178.572403 0.070353) (xy 178.572922 0) (xy 178.572922 -8.850122) (xy 178.573445 -8.905928) (xy 178.581787 -9.017229)
			(xy 178.598424 -9.127594) (xy 178.623261 -9.236408) (xy 178.656161 -9.343061) (xy 178.696939 -9.446958)
			(xy 178.745367 -9.547517) (xy 178.801175 -9.644175) (xy 178.86405 -9.736393) (xy 178.93364 -9.823654)
			(xy 179.009557 -9.905471) (xy 179.091376 -9.981386) (xy 179.178639 -10.050974) (xy 179.270859 -10.113846)
			(xy 179.367519 -10.169651) (xy 179.468079 -10.218077) (xy 179.571976 -10.258852) (xy 179.678631 -10.291749)
			(xy 179.787445 -10.316584) (xy 179.897811 -10.333218) (xy 180.009112 -10.341557) (xy 180.064918 -10.342118)
			(xy 182.064914 -10.342118) (xy 182.120721 -10.341596) (xy 182.232023 -10.333254) (xy 182.34239 -10.316618)
			(xy 182.451206 -10.291781) (xy 182.557861 -10.258882) (xy 182.661759 -10.218104) (xy 182.76232 -10.169676)
			(xy 182.85898 -10.113869) (xy 182.9512 -10.050995) (xy 183.038463 -9.981405) (xy 183.120282 -9.905488)
			(xy 183.196199 -9.823669) (xy 183.26579 -9.736406) (xy 183.328665 -9.644187) (xy 183.384473 -9.547527)
			(xy 183.432901 -9.446966) (xy 183.473679 -9.343068) (xy 183.506579 -9.236413) (xy 183.531416 -9.127598)
			(xy 183.548053 -9.017231) (xy 183.556395 -8.905929) (xy 183.55691 -8.850122) (xy 183.55691 0) (xy 183.557394 0.070354)
			(xy 183.565284 0.21084) (xy 183.581038 0.350664) (xy 183.604608 0.489383) (xy 183.635918 0.626563)
			(xy 183.674871 0.761772) (xy 183.721344 0.894584) (xy 183.775191 1.024581) (xy 183.836242 1.151354)
			(xy 183.904305 1.274505) (xy 183.979166 1.393646) (xy 184.06059 1.508401) (xy 184.14832 1.618411)
			(xy 184.24208 1.723329) (xy 184.341576 1.822824) (xy 184.446493 1.916584) (xy 184.556503 2.004314)
			(xy 184.671259 2.085737) (xy 184.7904 2.160598) (xy 184.913551 2.228661) (xy 185.040325 2.289712)
			(xy 185.170322 2.343558) (xy 185.303134 2.390031) (xy 185.438342 2.428983) (xy 185.575523 2.460294)
			(xy 185.714242 2.483863) (xy 185.854066 2.499617) (xy 185.994552 2.507506) (xy 186.064906 2.507996)
			(xy 202.064874 2.507996) (xy 202.135228 2.507512) (xy 202.275716 2.499624) (xy 202.41554 2.483871)
			(xy 202.554261 2.460303) (xy 202.691443 2.428993) (xy 202.826653 2.390041) (xy 202.959466 2.343569)
			(xy 203.089464 2.289723) (xy 203.216239 2.228673) (xy 203.339391 2.16061) (xy 203.458534 2.085749)
			(xy 203.573291 2.004326) (xy 203.683302 1.916596) (xy 203.788221 1.822836) (xy 203.887718 1.72334)
			(xy 203.981479 1.618422) (xy 204.06921 1.508412) (xy 204.150635 1.393655) (xy 204.225497 1.274514)
			(xy 204.293561 1.151362) (xy 204.354613 1.024588) (xy 204.40846 0.89459) (xy 204.454933 0.761778)
			(xy 204.493887 0.626568) (xy 204.525198 0.489387) (xy 204.548768 0.350666) (xy 204.564522 0.210842)
			(xy 204.572412 0.070354) (xy 204.57287 0) (xy 204.57287 -8.850122) (xy 204.573393 -8.905929) (xy 204.581735 -9.017231)
			(xy 204.598371 -9.127598) (xy 204.623209 -9.236413) (xy 204.656108 -9.343068) (xy 204.696886 -9.446966)
			(xy 204.745314 -9.547527) (xy 204.801121 -9.644187) (xy 204.863996 -9.736407) (xy 204.933586 -9.82367)
			(xy 205.009502 -9.905489) (xy 205.091321 -9.981407) (xy 205.178583 -10.050997) (xy 205.270803 -10.113872)
			(xy 205.367463 -10.16968) (xy 205.468023 -10.218109) (xy 205.571921 -10.258888) (xy 205.678575 -10.291788)
			(xy 205.78739 -10.316626) (xy 205.897757 -10.333264) (xy 206.009059 -10.341607) (xy 206.064866 -10.342118)
			(xy 208.065116 -10.342118) (xy 208.120923 -10.341596) (xy 208.232225 -10.333254) (xy 208.342592 -10.316618)
			(xy 208.451407 -10.29178) (xy 208.558062 -10.258881) (xy 208.66196 -10.218103) (xy 208.762521 -10.169676)
			(xy 208.859181 -10.113868) (xy 208.951401 -10.050994) (xy 209.038664 -9.981404) (xy 209.120483 -9.905487)
			(xy 209.1964 -9.823669) (xy 209.26599 -9.736406) (xy 209.328865 -9.644186) (xy 209.384673 -9.547526)
			(xy 209.433101 -9.446966) (xy 209.473879 -9.343068) (xy 209.506779 -9.236413) (xy 209.531617 -9.127598)
			(xy 209.548253 -9.017231) (xy 209.556595 -8.905929) (xy 209.557112 -8.850122) (xy 209.557112 0) (xy 209.557596 0.070354)
			(xy 209.565486 0.21084) (xy 209.58124 0.350663) (xy 209.60481 0.489383) (xy 209.63612 0.626563) (xy 209.675073 0.761772)
			(xy 209.721546 0.894583) (xy 209.775393 1.02458) (xy 209.836444 1.151354) (xy 209.904507 1.274505)
			(xy 209.979368 1.393645) (xy 210.060792 1.508401) (xy 210.148522 1.618411) (xy 210.242282 1.723328)
			(xy 210.341778 1.822823) (xy 210.446696 1.916583) (xy 210.556706 2.004313) (xy 210.671462 2.085736)
			(xy 210.790602 2.160597) (xy 210.913753 2.22866) (xy 211.040527 2.289711) (xy 211.170524 2.343557)
			(xy 211.303336 2.390029) (xy 211.438545 2.428982) (xy 211.575725 2.460292) (xy 211.714444 2.483861)
			(xy 211.854268 2.499615) (xy 211.994754 2.507504) (xy 212.065108 2.507996) (xy 240.164874 2.507996)
			(xy 240.235228 2.507512) (xy 240.375716 2.499624) (xy 240.51554 2.483871) (xy 240.654261 2.460303)
			(xy 240.791443 2.428993) (xy 240.926653 2.390041) (xy 241.059466 2.343569) (xy 241.189464 2.289723)
			(xy 241.316239 2.228673) (xy 241.439391 2.16061) (xy 241.558534 2.085749) (xy 241.673291 2.004326)
			(xy 241.783302 1.916596) (xy 241.888221 1.822836) (xy 241.987718 1.72334) (xy 242.081479 1.618422)
			(xy 242.16921 1.508412) (xy 242.250635 1.393655) (xy 242.325497 1.274514) (xy 242.393561 1.151362)
			(xy 242.454613 1.024588) (xy 242.50846 0.89459) (xy 242.554933 0.761778) (xy 242.593887 0.626568)
			(xy 242.625198 0.489387) (xy 242.648768 0.350666) (xy 242.664522 0.210842) (xy 242.672412 0.070354)
			(xy 242.67287 0) (xy 242.67287 -8.850122) (xy 242.673393 -8.905929) (xy 242.681735 -9.017231) (xy 242.698371 -9.127598)
			(xy 242.723209 -9.236413) (xy 242.756108 -9.343068) (xy 242.796886 -9.446966) (xy 242.845314 -9.547527)
			(xy 242.901121 -9.644187) (xy 242.963996 -9.736407) (xy 243.033586 -9.82367) (xy 243.109502 -9.905489)
			(xy 243.191321 -9.981407) (xy 243.278583 -10.050997) (xy 243.370803 -10.113872) (xy 243.467463 -10.16968)
			(xy 243.568023 -10.218109) (xy 243.671921 -10.258888) (xy 243.778575 -10.291788) (xy 243.88739 -10.316626)
			(xy 243.997757 -10.333264) (xy 244.109059 -10.341607) (xy 244.164866 -10.342118) (xy 246.165116 -10.342118)
			(xy 246.220923 -10.341596) (xy 246.332225 -10.333254) (xy 246.442592 -10.316618) (xy 246.551407 -10.29178)
			(xy 246.658062 -10.258881) (xy 246.76196 -10.218103) (xy 246.862521 -10.169676) (xy 246.959181 -10.113868)
			(xy 247.051401 -10.050994) (xy 247.138664 -9.981404) (xy 247.220483 -9.905487) (xy 247.2964 -9.823669)
			(xy 247.36599 -9.736406) (xy 247.428865 -9.644186) (xy 247.484673 -9.547526) (xy 247.533101 -9.446966)
			(xy 247.573879 -9.343068) (xy 247.606779 -9.236413) (xy 247.631617 -9.127598) (xy 247.648253 -9.017231)
			(xy 247.656595 -8.905929) (xy 247.657112 -8.850122) (xy 247.657112 0) (xy 247.657596 0.070354) (xy 247.665486 0.21084)
			(xy 247.68124 0.350663) (xy 247.70481 0.489383) (xy 247.73612 0.626563) (xy 247.775073 0.761772)
			(xy 247.821546 0.894583) (xy 247.875393 1.02458) (xy 247.936444 1.151354) (xy 248.004507 1.274505)
			(xy 248.079368 1.393645) (xy 248.160792 1.508401) (xy 248.248522 1.618411) (xy 248.342282 1.723328)
			(xy 248.441778 1.822823) (xy 248.546696 1.916583) (xy 248.656706 2.004313) (xy 248.771462 2.085736)
			(xy 248.890602 2.160597) (xy 249.013753 2.22866) (xy 249.140527 2.289711) (xy 249.270524 2.343557)
			(xy 249.403336 2.390029) (xy 249.538545 2.428982) (xy 249.675725 2.460292) (xy 249.814444 2.483861)
			(xy 249.954268 2.499615) (xy 250.094754 2.507504) (xy 250.165108 2.507996) (xy 266.165076 2.507996)
			(xy 266.23543 2.507512) (xy 266.375918 2.499624) (xy 266.515742 2.483871) (xy 266.654463 2.460303)
			(xy 266.791644 2.428993) (xy 266.926854 2.390041) (xy 267.059667 2.343569) (xy 267.189666 2.289723)
			(xy 267.31644 2.228672) (xy 267.439593 2.160609) (xy 267.558735 2.085749) (xy 267.673492 2.004325)
			(xy 267.783503 1.916595) (xy 267.888422 1.822835) (xy 267.987918 1.723339) (xy 268.08168 1.618421)
			(xy 268.169411 1.508411) (xy 268.250835 1.393655) (xy 268.325697 1.274513) (xy 268.393761 1.151362)
			(xy 268.454813 1.024588) (xy 268.50866 0.89459) (xy 268.555134 0.761777) (xy 268.594087 0.626568)
			(xy 268.625398 0.489387) (xy 268.648968 0.350666) (xy 268.664722 0.210842) (xy 268.672612 0.070354)
			(xy 268.673072 0) (xy 268.673072 -8.850122) (xy 268.673595 -8.905929) (xy 268.681937 -9.017231) (xy 268.698573 -9.127598)
			(xy 268.723411 -9.236413) (xy 268.75631 -9.343068) (xy 268.797088 -9.446966) (xy 268.845516 -9.547526)
			(xy 268.901323 -9.644187) (xy 268.964198 -9.736406) (xy 269.033788 -9.82367) (xy 269.109704 -9.905489)
			(xy 269.191523 -9.981406) (xy 269.278786 -10.050996) (xy 269.371005 -10.113871) (xy 269.467665 -10.169679)
			(xy 269.568225 -10.218108) (xy 269.672123 -10.258886) (xy 269.778777 -10.291787) (xy 269.887592 -10.316625)
			(xy 269.997959 -10.333262) (xy 270.109261 -10.341605) (xy 270.165068 -10.342118) (xy 272.165064 -10.342118)
			(xy 272.220873 -10.34161) (xy 272.332178 -10.333272) (xy 272.442549 -10.316638) (xy 272.551368 -10.291804)
			(xy 272.658028 -10.258906) (xy 272.76193 -10.21813) (xy 272.862495 -10.169703) (xy 272.95916 -10.113897)
			(xy 273.051383 -10.051022) (xy 273.138651 -9.981432) (xy 273.220473 -9.905515) (xy 273.296394 -9.823695)
			(xy 273.365988 -9.73643) (xy 273.428866 -9.644209) (xy 273.484676 -9.547546) (xy 273.533107 -9.446983)
			(xy 273.573887 -9.343082) (xy 273.606789 -9.236425) (xy 273.631628 -9.127606) (xy 273.648265 -9.017236)
			(xy 273.656608 -8.905931) (xy 273.65706 -8.850122) (xy 273.65706 0) (xy 273.657553 0.070354) (xy 273.665443 0.210841)
			(xy 273.681197 0.350665) (xy 273.704766 0.489385) (xy 273.736076 0.626566) (xy 273.775029 0.761775)
			(xy 273.821502 0.894588) (xy 273.875348 1.024585) (xy 273.936398 1.15136) (xy 274.004461 1.274511)
			(xy 274.079321 1.393653) (xy 274.160745 1.50841) (xy 274.248474 1.618421) (xy 274.342234 1.723339)
			(xy 274.441729 1.822836) (xy 274.546646 1.916598) (xy 274.656655 2.004329) (xy 274.771411 2.085754)
			(xy 274.890551 2.160617) (xy 275.013701 2.228682) (xy 275.140474 2.289734) (xy 275.270471 2.343583)
			(xy 275.403283 2.390058) (xy 275.538492 2.429013) (xy 275.675672 2.460325) (xy 275.814392 2.483897)
			(xy 275.954215 2.499654) (xy 276.094702 2.507545) (xy 276.165056 2.507996) (xy 292.165024 2.507996)
			(xy 292.235377 2.507502) (xy 292.375862 2.499611) (xy 292.515684 2.483856) (xy 292.654403 2.460285)
			(xy 292.791581 2.428974) (xy 292.926788 2.390021) (xy 293.059599 2.343547) (xy 293.189594 2.2897)
			(xy 293.316366 2.228649) (xy 293.439515 2.160586) (xy 293.558655 2.085724) (xy 293.673409 2.004301)
			(xy 293.783417 1.916571) (xy 293.888334 1.822811) (xy 293.987828 1.723316) (xy 294.081587 1.618399)
			(xy 294.169315 1.50839) (xy 294.250738 1.393635) (xy 294.325598 1.274495) (xy 294.39366 1.151345)
			(xy 294.45471 1.024572) (xy 294.508556 0.894576) (xy 294.555028 0.761765) (xy 294.59398 0.626558)
			(xy 294.62529 0.489379) (xy 294.648859 0.35066) (xy 294.664613 0.210839) (xy 294.672503 0.070353)
			(xy 294.67302 0) (xy 294.67302 -8.850122) (xy 294.673543 -8.905928) (xy 294.681885 -9.017229) (xy 294.698522 -9.127594)
			(xy 294.723359 -9.236408) (xy 294.756259 -9.343062) (xy 294.797037 -9.446958) (xy 294.845465 -9.547517)
			(xy 294.901273 -9.644176) (xy 294.964148 -9.736394) (xy 295.033738 -9.823655) (xy 295.109655 -9.905472)
			(xy 295.191474 -9.981387) (xy 295.278737 -10.050975) (xy 295.370956 -10.113847) (xy 295.467616 -10.169652)
			(xy 295.568176 -10.218078) (xy 295.672074 -10.258853) (xy 295.778728 -10.291751) (xy 295.887543 -10.316586)
			(xy 295.997909 -10.333219) (xy 296.10921 -10.341559) (xy 296.165016 -10.342118) (xy 298.165012 -10.342118)
			(xy 298.220819 -10.341596) (xy 298.332121 -10.333254) (xy 298.442488 -10.316618) (xy 298.551304 -10.291781)
			(xy 298.657959 -10.258882) (xy 298.761858 -10.218105) (xy 298.862418 -10.169677) (xy 298.959079 -10.11387)
			(xy 299.051299 -10.050995) (xy 299.138562 -9.981405) (xy 299.220382 -9.905489) (xy 299.296299 -9.82367)
			(xy 299.365889 -9.736407) (xy 299.428764 -9.644188) (xy 299.484572 -9.547527) (xy 299.533001 -9.446967)
			(xy 299.573779 -9.343069) (xy 299.606679 -9.236414) (xy 299.631516 -9.127598) (xy 299.648153 -9.017231)
			(xy 299.656495 -8.905929) (xy 299.657008 -8.850122) (xy 299.657008 0) (xy 299.657492 0.070354) (xy 299.665382 0.21084)
			(xy 299.681136 0.350664) (xy 299.704706 0.489383) (xy 299.736016 0.626564) (xy 299.774969 0.761772)
			(xy 299.821442 0.894584) (xy 299.875289 1.024581) (xy 299.93634 1.151355) (xy 300.004403 1.274505)
			(xy 300.079264 1.393646) (xy 300.160688 1.508402) (xy 300.248418 1.618412) (xy 300.342178 1.723329)
			(xy 300.441673 1.822825) (xy 300.546591 1.916585) (xy 300.656601 2.004315) (xy 300.771357 2.085738)
			(xy 300.890498 2.160599) (xy 301.013649 2.228662) (xy 301.140423 2.289713) (xy 301.27042 2.343559)
			(xy 301.403232 2.390032) (xy 301.53844 2.428985) (xy 301.67562 2.460295) (xy 301.81434 2.483864)
			(xy 301.954163 2.499618) (xy 302.09465 2.507508) (xy 302.165004 2.507996) (xy 318.164972 2.507996)
			(xy 318.235326 2.507512) (xy 318.375814 2.499624) (xy 318.515639 2.483871) (xy 318.65436 2.460303)
			(xy 318.791541 2.428994) (xy 318.926751 2.390042) (xy 319.059564 2.34357) (xy 319.189563 2.289724)
			(xy 319.316338 2.228673) (xy 319.43949 2.160611) (xy 319.558633 2.08575) (xy 319.67339 2.004327)
			(xy 319.783401 1.916597) (xy 319.88832 1.822836) (xy 319.987817 1.723341) (xy 320.081579 1.618423)
			(xy 320.16931 1.508412) (xy 320.250734 1.393656) (xy 320.325597 1.274514) (xy 320.393661 1.151363)
			(xy 320.454712 1.024589) (xy 320.50856 0.894591) (xy 320.555033 0.761778) (xy 320.593987 0.626568)
			(xy 320.625298 0.489387) (xy 320.648868 0.350666) (xy 320.664622 0.210842) (xy 320.672512 0.070354)
			(xy 320.672968 0) (xy 320.672968 -8.850122) (xy 320.673491 -8.905929) (xy 320.681833 -9.017231) (xy 320.698469 -9.127598)
			(xy 320.723307 -9.236413) (xy 320.756206 -9.343068) (xy 320.796984 -9.446967) (xy 320.845412 -9.547527)
			(xy 320.901219 -9.644188) (xy 320.964093 -9.736408) (xy 321.033684 -9.823671) (xy 321.1096 -9.90549)
			(xy 321.191418 -9.981407) (xy 321.278681 -10.050998) (xy 321.3709 -10.113873) (xy 321.46756 -10.169682)
			(xy 321.56812 -10.21811) (xy 321.672018 -10.258889) (xy 321.778673 -10.29179) (xy 321.887488 -10.316628)
			(xy 321.997855 -10.333266) (xy 322.109157 -10.341609) (xy 322.164964 -10.342118) (xy 324.16496 -10.342118)
			(xy 324.220769 -10.34161) (xy 324.332074 -10.333272) (xy 324.442446 -10.316639) (xy 324.551265 -10.291805)
			(xy 324.657925 -10.258907) (xy 324.761827 -10.218131) (xy 324.862393 -10.169705) (xy 324.959057 -10.113898)
			(xy 325.051281 -10.051024) (xy 325.138549 -9.981433) (xy 325.220372 -9.905516) (xy 325.296293 -9.823696)
			(xy 325.365887 -9.736431) (xy 325.428765 -9.64421) (xy 325.484576 -9.547547) (xy 325.533007 -9.446984)
			(xy 325.573787 -9.343083) (xy 325.606689 -9.236425) (xy 325.631528 -9.127607) (xy 325.648165 -9.017236)
			(xy 325.656508 -8.905931) (xy 325.656956 -8.850122) (xy 325.656956 0) (xy 325.657449 0.070354) (xy 325.665339 0.210841)
			(xy 325.681093 0.350665) (xy 325.704662 0.489386) (xy 325.735972 0.626566) (xy 325.774925 0.761776)
			(xy 325.821398 0.894588) (xy 325.875244 1.024586) (xy 325.936294 1.15136) (xy 326.004357 1.274512)
			(xy 326.079217 1.393654) (xy 326.16064 1.508411) (xy 326.24837 1.618422) (xy 326.342129 1.723341)
			(xy 326.441624 1.822838) (xy 326.546542 1.916599) (xy 326.656551 2.004331) (xy 326.771306 2.085756)
			(xy 326.890447 2.160619) (xy 327.013597 2.228684) (xy 327.14037 2.289737) (xy 327.270367 2.343585)
			(xy 327.403179 2.39006) (xy 327.538387 2.429016) (xy 327.675567 2.460328) (xy 327.814287 2.4839)
			(xy 327.954111 2.499657) (xy 328.094598 2.507549) (xy 328.164952 2.507996) (xy 356.264972 2.507996)
			(xy 356.335326 2.507512) (xy 356.475814 2.499624) (xy 356.615639 2.483871) (xy 356.75436 2.460303)
			(xy 356.891541 2.428994) (xy 357.026751 2.390042) (xy 357.159564 2.34357) (xy 357.289563 2.289724)
			(xy 357.416338 2.228673) (xy 357.53949 2.160611) (xy 357.658633 2.08575) (xy 357.77339 2.004327)
			(xy 357.883401 1.916597) (xy 357.98832 1.822836) (xy 358.087817 1.723341) (xy 358.181579 1.618423)
			(xy 358.26931 1.508412) (xy 358.350734 1.393656) (xy 358.425597 1.274514) (xy 358.493661 1.151363)
			(xy 358.554712 1.024589) (xy 358.60856 0.894591) (xy 358.655033 0.761778) (xy 358.693987 0.626568)
			(xy 358.725298 0.489387) (xy 358.748868 0.350666) (xy 358.764622 0.210842) (xy 358.772512 0.070354)
			(xy 358.772968 0) (xy 358.772968 -8.850122) (xy 358.773491 -8.905929) (xy 358.781833 -9.017231) (xy 358.798469 -9.127598)
			(xy 358.823307 -9.236413) (xy 358.856206 -9.343068) (xy 358.896984 -9.446967) (xy 358.945412 -9.547527)
			(xy 359.001219 -9.644188) (xy 359.064093 -9.736408) (xy 359.133684 -9.823671) (xy 359.2096 -9.90549)
			(xy 359.291418 -9.981407) (xy 359.378681 -10.050998) (xy 359.4709 -10.113873) (xy 359.56756 -10.169682)
			(xy 359.66812 -10.21811) (xy 359.772018 -10.258889) (xy 359.878673 -10.29179) (xy 359.987488 -10.316628)
			(xy 360.097855 -10.333266) (xy 360.209157 -10.341609) (xy 360.264964 -10.342118) (xy 362.26496 -10.342118)
			(xy 362.320769 -10.34161) (xy 362.432074 -10.333272) (xy 362.542446 -10.316639) (xy 362.651265 -10.291805)
			(xy 362.757925 -10.258907) (xy 362.861827 -10.218131) (xy 362.962393 -10.169705) (xy 363.059057 -10.113898)
			(xy 363.151281 -10.051024) (xy 363.238549 -9.981433) (xy 363.320372 -9.905516) (xy 363.396293 -9.823696)
			(xy 363.465887 -9.736431) (xy 363.528765 -9.64421) (xy 363.584576 -9.547547) (xy 363.633007 -9.446984)
			(xy 363.673787 -9.343083) (xy 363.706689 -9.236425) (xy 363.731528 -9.127607) (xy 363.748165 -9.017236)
			(xy 363.756508 -8.905931) (xy 363.756956 -8.850122) (xy 363.756956 0) (xy 363.757449 0.070354) (xy 363.765339 0.210841)
			(xy 363.781093 0.350665) (xy 363.804662 0.489386) (xy 363.835972 0.626566) (xy 363.874925 0.761776)
			(xy 363.921398 0.894588) (xy 363.975244 1.024586) (xy 364.036294 1.15136) (xy 364.104357 1.274512)
			(xy 364.179217 1.393654) (xy 364.26064 1.508411) (xy 364.34837 1.618422) (xy 364.442129 1.723341)
			(xy 364.541624 1.822838) (xy 364.646542 1.916599) (xy 364.756551 2.004331) (xy 364.871306 2.085756)
			(xy 364.990447 2.160619) (xy 365.113597 2.228684) (xy 365.24037 2.289737) (xy 365.370367 2.343585)
			(xy 365.503179 2.39006) (xy 365.638387 2.429016) (xy 365.775567 2.460328) (xy 365.914287 2.4839)
			(xy 366.054111 2.499657) (xy 366.194598 2.507549) (xy 366.264952 2.507996) (xy 382.26492 2.507996)
			(xy 382.335273 2.507502) (xy 382.475759 2.499612) (xy 382.615581 2.483856) (xy 382.754299 2.460286)
			(xy 382.891478 2.428975) (xy 383.026685 2.390022) (xy 383.159496 2.343548) (xy 383.289491 2.289701)
			(xy 383.416264 2.22865) (xy 383.539413 2.160587) (xy 383.658552 2.085726) (xy 383.773307 2.004302)
			(xy 383.883316 1.916573) (xy 383.988232 1.822813) (xy 384.087726 1.723318) (xy 384.181485 1.6184)
			(xy 384.269214 1.508391) (xy 384.350637 1.393636) (xy 384.425497 1.274496) (xy 384.493559 1.151346)
			(xy 384.554609 1.024573) (xy 384.608455 0.894577) (xy 384.654928 0.761766) (xy 384.69388 0.626559)
			(xy 384.72519 0.48938) (xy 384.748759 0.350661) (xy 384.764513 0.210839) (xy 384.772403 0.070353)
			(xy 384.772916 0) (xy 384.772916 -8.850122) (xy 384.773439 -8.905928) (xy 384.781781 -9.017229) (xy 384.798418 -9.127595)
			(xy 384.823255 -9.236409) (xy 384.856155 -9.343062) (xy 384.896933 -9.446959) (xy 384.945361 -9.547518)
			(xy 385.001169 -9.644177) (xy 385.064044 -9.736395) (xy 385.133634 -9.823656) (xy 385.209551 -9.905473)
			(xy 385.29137 -9.981388) (xy 385.378633 -10.050977) (xy 385.470852 -10.113849) (xy 385.567512 -10.169655)
			(xy 385.668072 -10.218081) (xy 385.77197 -10.258856) (xy 385.878624 -10.291754) (xy 385.987439 -10.316589)
			(xy 386.097805 -10.333223) (xy 386.209106 -10.341563) (xy 386.264912 -10.342118) (xy 388.264908 -10.342118)
			(xy 388.320715 -10.341596) (xy 388.432017 -10.333255) (xy 388.542385 -10.316619) (xy 388.651201 -10.291782)
			(xy 388.757856 -10.258883) (xy 388.861755 -10.218106) (xy 388.962316 -10.169678) (xy 389.058977 -10.113871)
			(xy 389.151197 -10.050997) (xy 389.238461 -9.981407) (xy 389.32028 -9.90549) (xy 389.396198 -9.823671)
			(xy 389.465789 -9.736408) (xy 389.528664 -9.644189) (xy 389.584472 -9.547528) (xy 389.6329 -9.446968)
			(xy 389.673678 -9.343069) (xy 389.706579 -9.236414) (xy 389.731416 -9.127599) (xy 389.748053 -9.017231)
			(xy 389.756395 -8.905929) (xy 389.756904 -8.850122) (xy 389.756904 0) (xy 389.757397 0.070354) (xy 389.765287 0.21084)
			(xy 389.781041 0.350663) (xy 389.80461 0.489382) (xy 389.835921 0.626562) (xy 389.874874 0.76177)
			(xy 389.921346 0.894581) (xy 389.975193 1.024578) (xy 390.036243 1.151351) (xy 390.104306 1.274502)
			(xy 390.179167 1.393642) (xy 390.260591 1.508398) (xy 390.34832 1.618407) (xy 390.44208 1.723325)
			(xy 390.541575 1.82282) (xy 390.646493 1.91658) (xy 390.756502 2.004309) (xy 390.871258 2.085733)
			(xy 390.990398 2.160594) (xy 391.113549 2.228657) (xy 391.240322 2.289707) (xy 391.370319 2.343554)
			(xy 391.50313 2.390026) (xy 391.638338 2.428979) (xy 391.775518 2.46029) (xy 391.914237 2.483859)
			(xy 392.05406 2.499613) (xy 392.194546 2.507503) (xy 392.2649 2.507996) (xy 408.265122 2.507996)
			(xy 408.335475 2.507502) (xy 408.475961 2.499611) (xy 408.615782 2.483856) (xy 408.754501 2.460286)
			(xy 408.89168 2.428975) (xy 409.026887 2.390021) (xy 409.159697 2.343548) (xy 409.289693 2.289701)
			(xy 409.416465 2.22865) (xy 409.539614 2.160586) (xy 409.658754 2.085725) (xy 409.773508 2.004302)
			(xy 409.883516 1.916572) (xy 409.988433 1.822812) (xy 410.087927 1.723317) (xy 410.181686 1.6184)
			(xy 410.269415 1.50839) (xy 410.350837 1.393635) (xy 410.425697 1.274495) (xy 410.49376 1.151345)
			(xy 410.55481 1.024573) (xy 410.608655 0.894577) (xy 410.655128 0.761766) (xy 410.69408 0.626558)
			(xy 410.72539 0.489379) (xy 410.748959 0.350661) (xy 410.764713 0.210839) (xy 410.772603 0.070353)
			(xy 410.773118 0) (xy 410.773118 -8.850122) (xy 410.773641 -8.905928) (xy 410.781983 -9.017229) (xy 410.79862 -9.127595)
			(xy 410.823457 -9.236408) (xy 410.856357 -9.343062) (xy 410.897135 -9.446959) (xy 410.945563 -9.547518)
			(xy 411.001371 -9.644176) (xy 411.064246 -9.736394) (xy 411.133836 -9.823656) (xy 411.209753 -9.905472)
			(xy 411.291572 -9.981387) (xy 411.378835 -10.050976) (xy 411.471054 -10.113848) (xy 411.567714 -10.169653)
			(xy 411.668274 -10.218079) (xy 411.772172 -10.258855) (xy 411.878826 -10.291752) (xy 411.987641 -10.316587)
			(xy 412.098007 -10.333221) (xy 412.209308 -10.341561) (xy 412.265114 -10.342118) (xy 414.26511 -10.342118)
			(xy 414.320917 -10.341596) (xy 414.432219 -10.333254) (xy 414.542587 -10.316619) (xy 414.651402 -10.291782)
			(xy 414.758058 -10.258883) (xy 414.861956 -10.218105) (xy 414.962517 -10.169678) (xy 415.059178 -10.11387)
			(xy 415.151398 -10.050996) (xy 415.238662 -9.981406) (xy 415.320481 -9.905489) (xy 415.396398 -9.823671)
			(xy 415.465989 -9.736408) (xy 415.528864 -9.644188) (xy 415.584672 -9.547528) (xy 415.6331 -9.446967)
			(xy 415.673879 -9.343069) (xy 415.706779 -9.236414) (xy 415.731616 -9.127598) (xy 415.748253 -9.017231)
			(xy 415.756595 -8.905929) (xy 415.757106 -8.850122) (xy 415.757106 0) (xy 415.75759 0.070354) (xy 415.76548 0.210841)
			(xy 415.781234 0.350664) (xy 415.804804 0.489384) (xy 415.836114 0.626564) (xy 415.875067 0.761772)
			(xy 415.92154 0.894584) (xy 415.975387 1.024581) (xy 416.036438 1.151355) (xy 416.104501 1.274506)
			(xy 416.179362 1.393647) (xy 416.260785 1.508402) (xy 416.348515 1.618412) (xy 416.442276 1.72333)
			(xy 416.541771 1.822826) (xy 416.646689 1.916586) (xy 416.756699 2.004316) (xy 416.871455 2.085739)
			(xy 416.990596 2.1606) (xy 417.113747 2.228663) (xy 417.24052 2.289714) (xy 417.370518 2.343561)
			(xy 417.503329 2.390034) (xy 417.638538 2.428986) (xy 417.775718 2.460297) (xy 417.914438 2.483866)
			(xy 418.054261 2.49962) (xy 418.194748 2.50751) (xy 418.265102 2.507996) (xy 434.26507 2.507996)
			(xy 434.335425 2.507513) (xy 434.475912 2.499625) (xy 434.615737 2.483872) (xy 434.754458 2.460304)
			(xy 434.89164 2.428994) (xy 435.02685 2.390042) (xy 435.159663 2.34357) (xy 435.289662 2.289724)
			(xy 435.416437 2.228674) (xy 435.539589 2.160612) (xy 435.658732 2.085751) (xy 435.773489 2.004327)
			(xy 435.8835 1.916597) (xy 435.988419 1.822837) (xy 436.087916 1.723341) (xy 436.181678 1.618423)
			(xy 436.269409 1.508413) (xy 436.350834 1.393656) (xy 436.425696 1.274515) (xy 436.49376 1.151363)
			(xy 436.554812 1.024589) (xy 436.60866 0.894591) (xy 436.655133 0.761778) (xy 436.694087 0.626569)
			(xy 436.725398 0.489387) (xy 436.748967 0.350667) (xy 436.764722 0.210842) (xy 436.772612 0.070355)
			(xy 436.773066 0) (xy 436.773066 -8.850122) (xy 436.773589 -8.905929) (xy 436.781931 -9.017231) (xy 436.798567 -9.127598)
			(xy 436.823405 -9.236414) (xy 436.856304 -9.343069) (xy 436.897082 -9.446967) (xy 436.94551 -9.547528)
			(xy 437.001317 -9.644188) (xy 437.064191 -9.736408) (xy 437.133781 -9.823672) (xy 437.209698 -9.905491)
			(xy 437.291516 -9.981408) (xy 437.378779 -10.050999) (xy 437.470998 -10.113874) (xy 437.567658 -10.169683)
			(xy 437.668218 -10.218112) (xy 437.772116 -10.25889) (xy 437.878771 -10.291791) (xy 437.987586 -10.31663)
			(xy 438.097953 -10.333267) (xy 438.209255 -10.341611) (xy 438.265062 -10.342118) (xy 440.265058 -10.342118)
			(xy 440.320867 -10.34161) (xy 440.432173 -10.333272) (xy 440.542544 -10.316639) (xy 440.651364 -10.291805)
			(xy 440.758023 -10.258908) (xy 440.861926 -10.218132) (xy 440.962491 -10.169705) (xy 441.059156 -10.113899)
			(xy 441.151381 -10.051025) (xy 441.238648 -9.981434) (xy 441.320471 -9.905517) (xy 441.396392 -9.823697)
			(xy 441.465987 -9.736432) (xy 441.528865 -9.64421) (xy 441.584675 -9.547548) (xy 441.633106 -9.446985)
			(xy 441.673887 -9.343084) (xy 441.706788 -9.236425) (xy 441.731628 -9.127607) (xy 441.748265 -9.017236)
			(xy 441.756608 -8.905931) (xy 441.757054 -8.850122) (xy 441.757054 0) (xy 441.757538 0.070353) (xy 441.765428 0.210839)
			(xy 441.781182 0.350661) (xy 441.804752 0.48938) (xy 441.836062 0.626559) (xy 441.875016 0.761767)
			(xy 441.921489 0.894578) (xy 441.975336 1.024574) (xy 442.036387 1.151346) (xy 442.10445 1.274495)
			(xy 442.179312 1.393635) (xy 442.260736 1.508389) (xy 442.348466 1.618398) (xy 442.442227 1.723314)
			(xy 442.541722 1.822808) (xy 442.64664 1.916566) (xy 442.756651 2.004294) (xy 442.871407 2.085716)
			(xy 442.990548 2.160575) (xy 443.113699 2.228636) (xy 443.240472 2.289685) (xy 443.370469 2.343529)
			(xy 443.503281 2.39) (xy 443.638489 2.42895) (xy 443.775669 2.460258) (xy 443.914388 2.483825) (xy 444.054211 2.499576)
			(xy 444.194697 2.507463) (xy 444.26505 2.507996) (xy 465.600034 2.507996) (xy 465.65584 2.508519)
			(xy 465.767141 2.516862) (xy 465.877506 2.533499) (xy 465.98632 2.558338) (xy 466.092974 2.591238)
			(xy 466.19687 2.632016) (xy 466.297429 2.680445) (xy 466.394088 2.736252) (xy 466.486306 2.799127)
			(xy 466.573567 2.868717) (xy 466.655384 2.944634) (xy 466.7313 3.026452) (xy 466.800888 3.113715)
			(xy 466.863762 3.205934) (xy 466.919568 3.302594) (xy 466.967994 3.403154) (xy 467.008771 3.507051)
			(xy 467.041669 3.613705) (xy 467.066505 3.722519) (xy 467.083141 3.832885) (xy 467.091482 3.944186)
			(xy 467.09203 3.999992) (xy 467.09203 24.157686) (xy 467.091509 24.213494) (xy 467.083169 24.324797)
			(xy 467.066535 24.435167) (xy 467.041699 24.543984) (xy 467.008801 24.650641) (xy 466.968025 24.754542)
			(xy 466.919598 24.855105) (xy 466.863791 24.951768) (xy 466.800917 25.04399) (xy 466.731327 25.131255)
			(xy 466.655411 25.213077) (xy 466.573592 25.288996) (xy 466.486328 25.358589) (xy 466.394108 25.421466)
			(xy 466.297447 25.477275) (xy 466.196886 25.525705) (xy 466.092987 25.566485) (xy 465.986331 25.599387)
			(xy 465.877514 25.624226) (xy 465.767145 25.640863) (xy 465.655842 25.649207) (xy 465.600034 25.649682)
			(xy 160.11398 25.649682) (xy 160.058174 25.64916) (xy 159.946873 25.640817) (xy 159.836507 25.624181)
			(xy 159.727693 25.599343) (xy 159.62104 25.566443) (xy 159.517143 25.525665) (xy 159.416584 25.477237)
			(xy 159.319925 25.42143) (xy 159.227707 25.358555) (xy 159.140445 25.288965) (xy 159.058628 25.213048)
			(xy 158.982713 25.131229) (xy 158.913125 25.043966) (xy 158.850252 24.951746) (xy 158.794447 24.855086)
			(xy 158.746021 24.754526) (xy 158.705245 24.650628) (xy 158.672348 24.543974) (xy 158.647513 24.435159)
			(xy 158.630879 24.324793) (xy 158.622539 24.213492) (xy 158.621984 24.157686) (xy 158.621984 21.802649)
			(xy 269.304757 21.802649) (xy 269.304757 21.888399) (xy 269.312669 21.973782) (xy 269.328425 22.058072)
			(xy 269.351892 22.140548) (xy 269.382868 22.220507) (xy 269.42109 22.297267) (xy 269.466231 22.370173)
			(xy 269.517907 22.438602) (xy 269.575676 22.501972) (xy 269.639046 22.559741) (xy 269.707475 22.611417)
			(xy 269.780381 22.656558) (xy 269.857141 22.69478) (xy 269.9371 22.725756) (xy 270.019576 22.749223)
			(xy 270.103866 22.764979) (xy 270.189249 22.772891) (xy 270.274999 22.772891) (xy 270.360382 22.764979)
			(xy 270.444672 22.749223) (xy 270.527148 22.725756) (xy 270.607107 22.69478) (xy 270.683867 22.656558)
			(xy 270.756773 22.611417) (xy 270.825202 22.559741) (xy 270.888572 22.501972) (xy 270.946341 22.438602)
			(xy 270.998017 22.370173) (xy 271.043158 22.297267) (xy 271.08138 22.220507) (xy 271.112356 22.140548)
			(xy 271.135823 22.058072) (xy 271.151579 21.973782) (xy 271.159491 21.888399) (xy 271.159986 21.845524)
			(xy 271.159491 21.802649) (xy 275.654757 21.802649) (xy 275.654757 21.888399) (xy 275.662669 21.973782)
			(xy 275.678425 22.058072) (xy 275.701892 22.140548) (xy 275.732868 22.220507) (xy 275.77109 22.297267)
			(xy 275.816231 22.370173) (xy 275.867907 22.438602) (xy 275.925676 22.501972) (xy 275.989046 22.559741)
			(xy 276.057475 22.611417) (xy 276.130381 22.656558) (xy 276.207141 22.69478) (xy 276.2871 22.725756)
			(xy 276.369576 22.749223) (xy 276.453866 22.764979) (xy 276.539249 22.772891) (xy 276.624999 22.772891)
			(xy 276.710382 22.764979) (xy 276.794672 22.749223) (xy 276.877148 22.725756) (xy 276.957107 22.69478)
			(xy 277.033867 22.656558) (xy 277.106773 22.611417) (xy 277.175202 22.559741) (xy 277.238572 22.501972)
			(xy 277.296341 22.438602) (xy 277.348017 22.370173) (xy 277.393158 22.297267) (xy 277.43138 22.220507)
			(xy 277.462356 22.140548) (xy 277.485823 22.058072) (xy 277.501579 21.973782) (xy 277.509491 21.888399)
			(xy 277.509986 21.845524) (xy 277.509491 21.802649) (xy 277.508832 21.795537) (xy 308.364877 21.795537)
			(xy 308.364877 21.881287) (xy 308.372789 21.96667) (xy 308.388545 22.05096) (xy 308.412012 22.133436)
			(xy 308.442988 22.213395) (xy 308.48121 22.290155) (xy 308.526351 22.363061) (xy 308.578027 22.43149)
			(xy 308.635796 22.49486) (xy 308.699166 22.552629) (xy 308.767595 22.604305) (xy 308.840501 22.649446)
			(xy 308.917261 22.687668) (xy 308.99722 22.718644) (xy 309.079696 22.742111) (xy 309.163986 22.757867)
			(xy 309.249369 22.765779) (xy 309.335119 22.765779) (xy 309.420502 22.757867) (xy 309.504792 22.742111)
			(xy 309.587268 22.718644) (xy 309.667227 22.687668) (xy 309.743987 22.649446) (xy 309.816893 22.604305)
			(xy 309.885322 22.552629) (xy 309.948692 22.49486) (xy 310.006461 22.43149) (xy 310.058137 22.363061)
			(xy 310.103278 22.290155) (xy 310.1415 22.213395) (xy 310.172476 22.133436) (xy 310.195943 22.05096)
			(xy 310.211699 21.96667) (xy 310.219611 21.881287) (xy 310.220106 21.838412) (xy 310.219611 21.795537)
			(xy 314.714877 21.795537) (xy 314.714877 21.881287) (xy 314.722789 21.96667) (xy 314.738545 22.05096)
			(xy 314.762012 22.133436) (xy 314.792988 22.213395) (xy 314.83121 22.290155) (xy 314.876351 22.363061)
			(xy 314.928027 22.43149) (xy 314.985796 22.49486) (xy 315.049166 22.552629) (xy 315.117595 22.604305)
			(xy 315.190501 22.649446) (xy 315.267261 22.687668) (xy 315.34722 22.718644) (xy 315.429696 22.742111)
			(xy 315.513986 22.757867) (xy 315.599369 22.765779) (xy 315.685119 22.765779) (xy 315.770502 22.757867)
			(xy 315.854792 22.742111) (xy 315.937268 22.718644) (xy 316.017227 22.687668) (xy 316.093987 22.649446)
			(xy 316.166893 22.604305) (xy 316.235322 22.552629) (xy 316.298692 22.49486) (xy 316.356461 22.43149)
			(xy 316.408137 22.363061) (xy 316.453278 22.290155) (xy 316.4915 22.213395) (xy 316.522476 22.133436)
			(xy 316.545943 22.05096) (xy 316.561699 21.96667) (xy 316.569611 21.881287) (xy 316.570106 21.838412)
			(xy 316.569693 21.802649) (xy 334.455757 21.802649) (xy 334.455757 21.888399) (xy 334.463669 21.973782)
			(xy 334.479425 22.058072) (xy 334.502892 22.140548) (xy 334.533868 22.220507) (xy 334.57209 22.297267)
			(xy 334.617231 22.370173) (xy 334.668907 22.438602) (xy 334.726676 22.501972) (xy 334.790046 22.559741)
			(xy 334.858475 22.611417) (xy 334.931381 22.656558) (xy 335.008141 22.69478) (xy 335.0881 22.725756)
			(xy 335.170576 22.749223) (xy 335.254866 22.764979) (xy 335.340249 22.772891) (xy 335.425999 22.772891)
			(xy 335.511382 22.764979) (xy 335.595672 22.749223) (xy 335.678148 22.725756) (xy 335.758107 22.69478)
			(xy 335.834867 22.656558) (xy 335.907773 22.611417) (xy 335.976202 22.559741) (xy 336.039572 22.501972)
			(xy 336.097341 22.438602) (xy 336.149017 22.370173) (xy 336.194158 22.297267) (xy 336.23238 22.220507)
			(xy 336.263356 22.140548) (xy 336.286823 22.058072) (xy 336.302579 21.973782) (xy 336.310491 21.888399)
			(xy 336.310986 21.845524) (xy 336.310491 21.802649) (xy 340.805757 21.802649) (xy 340.805757 21.888399)
			(xy 340.813669 21.973782) (xy 340.829425 22.058072) (xy 340.852892 22.140548) (xy 340.883868 22.220507)
			(xy 340.92209 22.297267) (xy 340.967231 22.370173) (xy 341.018907 22.438602) (xy 341.076676 22.501972)
			(xy 341.140046 22.559741) (xy 341.208475 22.611417) (xy 341.281381 22.656558) (xy 341.358141 22.69478)
			(xy 341.4381 22.725756) (xy 341.520576 22.749223) (xy 341.604866 22.764979) (xy 341.690249 22.772891)
			(xy 341.775999 22.772891) (xy 341.861382 22.764979) (xy 341.945672 22.749223) (xy 342.028148 22.725756)
			(xy 342.108107 22.69478) (xy 342.184867 22.656558) (xy 342.257773 22.611417) (xy 342.326202 22.559741)
			(xy 342.389572 22.501972) (xy 342.447341 22.438602) (xy 342.499017 22.370173) (xy 342.544158 22.297267)
			(xy 342.58238 22.220507) (xy 342.613356 22.140548) (xy 342.636823 22.058072) (xy 342.652579 21.973782)
			(xy 342.660491 21.888399) (xy 342.660986 21.845524) (xy 342.660491 21.802649) (xy 342.659832 21.795537)
			(xy 373.515877 21.795537) (xy 373.515877 21.881287) (xy 373.523789 21.96667) (xy 373.539545 22.05096)
			(xy 373.563012 22.133436) (xy 373.593988 22.213395) (xy 373.63221 22.290155) (xy 373.677351 22.363061)
			(xy 373.729027 22.43149) (xy 373.786796 22.49486) (xy 373.850166 22.552629) (xy 373.918595 22.604305)
			(xy 373.991501 22.649446) (xy 374.068261 22.687668) (xy 374.14822 22.718644) (xy 374.230696 22.742111)
			(xy 374.314986 22.757867) (xy 374.400369 22.765779) (xy 374.486119 22.765779) (xy 374.571502 22.757867)
			(xy 374.655792 22.742111) (xy 374.738268 22.718644) (xy 374.818227 22.687668) (xy 374.894987 22.649446)
			(xy 374.967893 22.604305) (xy 375.036322 22.552629) (xy 375.099692 22.49486) (xy 375.157461 22.43149)
			(xy 375.209137 22.363061) (xy 375.254278 22.290155) (xy 375.2925 22.213395) (xy 375.323476 22.133436)
			(xy 375.346943 22.05096) (xy 375.362699 21.96667) (xy 375.370611 21.881287) (xy 375.371106 21.838412)
			(xy 375.370611 21.795537) (xy 379.865877 21.795537) (xy 379.865877 21.881287) (xy 379.873789 21.96667)
			(xy 379.889545 22.05096) (xy 379.913012 22.133436) (xy 379.943988 22.213395) (xy 379.98221 22.290155)
			(xy 380.027351 22.363061) (xy 380.079027 22.43149) (xy 380.136796 22.49486) (xy 380.200166 22.552629)
			(xy 380.268595 22.604305) (xy 380.341501 22.649446) (xy 380.418261 22.687668) (xy 380.49822 22.718644)
			(xy 380.580696 22.742111) (xy 380.664986 22.757867) (xy 380.750369 22.765779) (xy 380.836119 22.765779)
			(xy 380.921502 22.757867) (xy 381.005792 22.742111) (xy 381.088268 22.718644) (xy 381.168227 22.687668)
			(xy 381.244987 22.649446) (xy 381.317893 22.604305) (xy 381.386322 22.552629) (xy 381.449692 22.49486)
			(xy 381.507461 22.43149) (xy 381.559137 22.363061) (xy 381.604278 22.290155) (xy 381.6425 22.213395)
			(xy 381.673476 22.133436) (xy 381.696943 22.05096) (xy 381.712699 21.96667) (xy 381.720611 21.881287)
			(xy 381.721106 21.838412) (xy 381.720693 21.802649) (xy 399.098757 21.802649) (xy 399.098757 21.888399)
			(xy 399.106669 21.973782) (xy 399.122425 22.058072) (xy 399.145892 22.140548) (xy 399.176868 22.220507)
			(xy 399.21509 22.297267) (xy 399.260231 22.370173) (xy 399.311907 22.438602) (xy 399.369676 22.501972)
			(xy 399.433046 22.559741) (xy 399.501475 22.611417) (xy 399.574381 22.656558) (xy 399.651141 22.69478)
			(xy 399.7311 22.725756) (xy 399.813576 22.749223) (xy 399.897866 22.764979) (xy 399.983249 22.772891)
			(xy 400.068999 22.772891) (xy 400.154382 22.764979) (xy 400.238672 22.749223) (xy 400.321148 22.725756)
			(xy 400.401107 22.69478) (xy 400.477867 22.656558) (xy 400.550773 22.611417) (xy 400.619202 22.559741)
			(xy 400.682572 22.501972) (xy 400.740341 22.438602) (xy 400.792017 22.370173) (xy 400.837158 22.297267)
			(xy 400.87538 22.220507) (xy 400.906356 22.140548) (xy 400.929823 22.058072) (xy 400.945579 21.973782)
			(xy 400.953491 21.888399) (xy 400.953986 21.845524) (xy 400.953491 21.802649) (xy 405.448757 21.802649)
			(xy 405.448757 21.888399) (xy 405.456669 21.973782) (xy 405.472425 22.058072) (xy 405.495892 22.140548)
			(xy 405.526868 22.220507) (xy 405.56509 22.297267) (xy 405.610231 22.370173) (xy 405.661907 22.438602)
			(xy 405.719676 22.501972) (xy 405.783046 22.559741) (xy 405.851475 22.611417) (xy 405.924381 22.656558)
			(xy 406.001141 22.69478) (xy 406.0811 22.725756) (xy 406.163576 22.749223) (xy 406.247866 22.764979)
			(xy 406.333249 22.772891) (xy 406.418999 22.772891) (xy 406.504382 22.764979) (xy 406.588672 22.749223)
			(xy 406.671148 22.725756) (xy 406.751107 22.69478) (xy 406.827867 22.656558) (xy 406.900773 22.611417)
			(xy 406.969202 22.559741) (xy 407.032572 22.501972) (xy 407.090341 22.438602) (xy 407.142017 22.370173)
			(xy 407.187158 22.297267) (xy 407.22538 22.220507) (xy 407.256356 22.140548) (xy 407.279823 22.058072)
			(xy 407.295579 21.973782) (xy 407.303491 21.888399) (xy 407.303986 21.845524) (xy 407.303491 21.802649)
			(xy 407.302832 21.795537) (xy 438.158877 21.795537) (xy 438.158877 21.881287) (xy 438.166789 21.96667)
			(xy 438.182545 22.05096) (xy 438.206012 22.133436) (xy 438.236988 22.213395) (xy 438.27521 22.290155)
			(xy 438.320351 22.363061) (xy 438.372027 22.43149) (xy 438.429796 22.49486) (xy 438.493166 22.552629)
			(xy 438.561595 22.604305) (xy 438.634501 22.649446) (xy 438.711261 22.687668) (xy 438.79122 22.718644)
			(xy 438.873696 22.742111) (xy 438.957986 22.757867) (xy 439.043369 22.765779) (xy 439.129119 22.765779)
			(xy 439.214502 22.757867) (xy 439.298792 22.742111) (xy 439.381268 22.718644) (xy 439.461227 22.687668)
			(xy 439.537987 22.649446) (xy 439.610893 22.604305) (xy 439.679322 22.552629) (xy 439.742692 22.49486)
			(xy 439.800461 22.43149) (xy 439.852137 22.363061) (xy 439.897278 22.290155) (xy 439.9355 22.213395)
			(xy 439.966476 22.133436) (xy 439.989943 22.05096) (xy 440.005699 21.96667) (xy 440.013611 21.881287)
			(xy 440.014106 21.838412) (xy 440.013611 21.795537) (xy 444.508877 21.795537) (xy 444.508877 21.881287)
			(xy 444.516789 21.96667) (xy 444.532545 22.05096) (xy 444.556012 22.133436) (xy 444.586988 22.213395)
			(xy 444.62521 22.290155) (xy 444.670351 22.363061) (xy 444.722027 22.43149) (xy 444.779796 22.49486)
			(xy 444.843166 22.552629) (xy 444.911595 22.604305) (xy 444.984501 22.649446) (xy 445.061261 22.687668)
			(xy 445.14122 22.718644) (xy 445.223696 22.742111) (xy 445.307986 22.757867) (xy 445.393369 22.765779)
			(xy 445.479119 22.765779) (xy 445.564502 22.757867) (xy 445.648792 22.742111) (xy 445.731268 22.718644)
			(xy 445.811227 22.687668) (xy 445.887987 22.649446) (xy 445.960893 22.604305) (xy 446.029322 22.552629)
			(xy 446.092692 22.49486) (xy 446.150461 22.43149) (xy 446.202137 22.363061) (xy 446.247278 22.290155)
			(xy 446.2855 22.213395) (xy 446.316476 22.133436) (xy 446.339943 22.05096) (xy 446.355699 21.96667)
			(xy 446.363611 21.881287) (xy 446.364106 21.838412) (xy 446.363611 21.795537) (xy 446.355699 21.710154)
			(xy 446.339943 21.625864) (xy 446.316476 21.543388) (xy 446.2855 21.463429) (xy 446.247278 21.386669)
			(xy 446.202137 21.313763) (xy 446.150461 21.245334) (xy 446.092692 21.181964) (xy 446.029322 21.124195)
			(xy 445.988175 21.093122) (xy 460.504275 21.093122) (xy 460.504275 21.222262) (xy 460.512225 21.351157)
			(xy 460.528095 21.479317) (xy 460.551824 21.606258) (xy 460.583323 21.731497) (xy 460.622472 21.85456)
			(xy 460.669123 21.974979) (xy 460.723098 22.092298) (xy 460.784193 22.206072) (xy 460.852176 22.315869)
			(xy 460.92679 22.421272) (xy 461.007751 22.521882) (xy 461.094751 22.617317) (xy 461.187462 22.707216)
			(xy 461.285532 22.791237) (xy 461.388587 22.869061) (xy 461.496238 22.940393) (xy 461.608077 23.004963)
			(xy 461.723678 23.062525) (xy 461.842603 23.112862) (xy 461.964402 23.155782) (xy 462.088612 23.191123)
			(xy 462.214761 23.21875) (xy 462.342373 23.238559) (xy 462.470962 23.250475) (xy 462.60004 23.254452)
			(xy 462.729118 23.250475) (xy 462.857707 23.238559) (xy 462.985319 23.21875) (xy 463.111468 23.191123)
			(xy 463.235678 23.155782) (xy 463.357477 23.112862) (xy 463.476402 23.062525) (xy 463.592003 23.004963)
			(xy 463.703842 22.940393) (xy 463.811493 22.869061) (xy 463.914548 22.791237) (xy 464.012618 22.707216)
			(xy 464.105329 22.617317) (xy 464.192329 22.521882) (xy 464.27329 22.421272) (xy 464.347904 22.315869)
			(xy 464.415887 22.206072) (xy 464.476982 22.092298) (xy 464.530957 21.974979) (xy 464.577608 21.85456)
			(xy 464.616757 21.731497) (xy 464.648256 21.606258) (xy 464.671985 21.479317) (xy 464.687855 21.351157)
			(xy 464.695805 21.222262) (xy 464.696302 21.157692) (xy 464.695805 21.093122) (xy 464.687855 20.964227)
			(xy 464.671985 20.836067) (xy 464.648256 20.709126) (xy 464.616757 20.583887) (xy 464.577608 20.460824)
			(xy 464.530957 20.340405) (xy 464.476982 20.223086) (xy 464.415887 20.109312) (xy 464.347904 19.999515)
			(xy 464.27329 19.894112) (xy 464.192329 19.793502) (xy 464.105329 19.698067) (xy 464.012618 19.608168)
			(xy 463.914548 19.524147) (xy 463.811493 19.446323) (xy 463.703842 19.374991) (xy 463.592003 19.310421)
			(xy 463.476402 19.252859) (xy 463.357477 19.202522) (xy 463.235678 19.159602) (xy 463.111468 19.124261)
			(xy 462.985319 19.096634) (xy 462.857707 19.076825) (xy 462.729118 19.064909) (xy 462.60004 19.060933)
			(xy 462.470962 19.064909) (xy 462.342373 19.076825) (xy 462.214761 19.096634) (xy 462.088612 19.124261)
			(xy 461.964402 19.159602) (xy 461.842603 19.202522) (xy 461.723678 19.252859) (xy 461.608077 19.310421)
			(xy 461.496238 19.374991) (xy 461.388587 19.446323) (xy 461.285532 19.524147) (xy 461.187462 19.608168)
			(xy 461.094751 19.698067) (xy 461.007751 19.793502) (xy 460.92679 19.894112) (xy 460.852176 19.999515)
			(xy 460.784193 20.109312) (xy 460.723098 20.223086) (xy 460.669123 20.340405) (xy 460.622472 20.460824)
			(xy 460.583323 20.583887) (xy 460.551824 20.709126) (xy 460.528095 20.836067) (xy 460.512225 20.964227)
			(xy 460.504275 21.093122) (xy 445.988175 21.093122) (xy 445.960893 21.072519) (xy 445.887987 21.027378)
			(xy 445.811227 20.989156) (xy 445.731268 20.95818) (xy 445.648792 20.934713) (xy 445.564502 20.918957)
			(xy 445.479119 20.911045) (xy 445.393369 20.911045) (xy 445.307986 20.918957) (xy 445.223696 20.934713)
			(xy 445.14122 20.95818) (xy 445.061261 20.989156) (xy 444.984501 21.027378) (xy 444.911595 21.072519)
			(xy 444.843166 21.124195) (xy 444.779796 21.181964) (xy 444.722027 21.245334) (xy 444.670351 21.313763)
			(xy 444.62521 21.386669) (xy 444.586988 21.463429) (xy 444.556012 21.543388) (xy 444.532545 21.625864)
			(xy 444.516789 21.710154) (xy 444.508877 21.795537) (xy 440.013611 21.795537) (xy 440.005699 21.710154)
			(xy 439.989943 21.625864) (xy 439.966476 21.543388) (xy 439.9355 21.463429) (xy 439.897278 21.386669)
			(xy 439.852137 21.313763) (xy 439.800461 21.245334) (xy 439.742692 21.181964) (xy 439.679322 21.124195)
			(xy 439.610893 21.072519) (xy 439.537987 21.027378) (xy 439.461227 20.989156) (xy 439.381268 20.95818)
			(xy 439.298792 20.934713) (xy 439.214502 20.918957) (xy 439.129119 20.911045) (xy 439.043369 20.911045)
			(xy 438.957986 20.918957) (xy 438.873696 20.934713) (xy 438.79122 20.95818) (xy 438.711261 20.989156)
			(xy 438.634501 21.027378) (xy 438.561595 21.072519) (xy 438.493166 21.124195) (xy 438.429796 21.181964)
			(xy 438.372027 21.245334) (xy 438.320351 21.313763) (xy 438.27521 21.386669) (xy 438.236988 21.463429)
			(xy 438.206012 21.543388) (xy 438.182545 21.625864) (xy 438.166789 21.710154) (xy 438.158877 21.795537)
			(xy 407.302832 21.795537) (xy 407.295579 21.717266) (xy 407.279823 21.632976) (xy 407.256356 21.5505)
			(xy 407.22538 21.470541) (xy 407.187158 21.393781) (xy 407.142017 21.320875) (xy 407.090341 21.252446)
			(xy 407.032572 21.189076) (xy 406.969202 21.131307) (xy 406.900773 21.079631) (xy 406.827867 21.03449)
			(xy 406.751107 20.996268) (xy 406.671148 20.965292) (xy 406.588672 20.941825) (xy 406.504382 20.926069)
			(xy 406.418999 20.918157) (xy 406.333249 20.918157) (xy 406.247866 20.926069) (xy 406.163576 20.941825)
			(xy 406.0811 20.965292) (xy 406.001141 20.996268) (xy 405.924381 21.03449) (xy 405.851475 21.079631)
			(xy 405.783046 21.131307) (xy 405.719676 21.189076) (xy 405.661907 21.252446) (xy 405.610231 21.320875)
			(xy 405.56509 21.393781) (xy 405.526868 21.470541) (xy 405.495892 21.5505) (xy 405.472425 21.632976)
			(xy 405.456669 21.717266) (xy 405.448757 21.802649) (xy 400.953491 21.802649) (xy 400.945579 21.717266)
			(xy 400.929823 21.632976) (xy 400.906356 21.5505) (xy 400.87538 21.470541) (xy 400.837158 21.393781)
			(xy 400.792017 21.320875) (xy 400.740341 21.252446) (xy 400.682572 21.189076) (xy 400.619202 21.131307)
			(xy 400.550773 21.079631) (xy 400.477867 21.03449) (xy 400.401107 20.996268) (xy 400.321148 20.965292)
			(xy 400.238672 20.941825) (xy 400.154382 20.926069) (xy 400.068999 20.918157) (xy 399.983249 20.918157)
			(xy 399.897866 20.926069) (xy 399.813576 20.941825) (xy 399.7311 20.965292) (xy 399.651141 20.996268)
			(xy 399.574381 21.03449) (xy 399.501475 21.079631) (xy 399.433046 21.131307) (xy 399.369676 21.189076)
			(xy 399.311907 21.252446) (xy 399.260231 21.320875) (xy 399.21509 21.393781) (xy 399.176868 21.470541)
			(xy 399.145892 21.5505) (xy 399.122425 21.632976) (xy 399.106669 21.717266) (xy 399.098757 21.802649)
			(xy 381.720693 21.802649) (xy 381.720611 21.795537) (xy 381.712699 21.710154) (xy 381.696943 21.625864)
			(xy 381.673476 21.543388) (xy 381.6425 21.463429) (xy 381.604278 21.386669) (xy 381.559137 21.313763)
			(xy 381.507461 21.245334) (xy 381.449692 21.181964) (xy 381.386322 21.124195) (xy 381.317893 21.072519)
			(xy 381.244987 21.027378) (xy 381.168227 20.989156) (xy 381.088268 20.95818) (xy 381.005792 20.934713)
			(xy 380.921502 20.918957) (xy 380.836119 20.911045) (xy 380.750369 20.911045) (xy 380.664986 20.918957)
			(xy 380.580696 20.934713) (xy 380.49822 20.95818) (xy 380.418261 20.989156) (xy 380.341501 21.027378)
			(xy 380.268595 21.072519) (xy 380.200166 21.124195) (xy 380.136796 21.181964) (xy 380.079027 21.245334)
			(xy 380.027351 21.313763) (xy 379.98221 21.386669) (xy 379.943988 21.463429) (xy 379.913012 21.543388)
			(xy 379.889545 21.625864) (xy 379.873789 21.710154) (xy 379.865877 21.795537) (xy 375.370611 21.795537)
			(xy 375.362699 21.710154) (xy 375.346943 21.625864) (xy 375.323476 21.543388) (xy 375.2925 21.463429)
			(xy 375.254278 21.386669) (xy 375.209137 21.313763) (xy 375.157461 21.245334) (xy 375.099692 21.181964)
			(xy 375.036322 21.124195) (xy 374.967893 21.072519) (xy 374.894987 21.027378) (xy 374.818227 20.989156)
			(xy 374.738268 20.95818) (xy 374.655792 20.934713) (xy 374.571502 20.918957) (xy 374.486119 20.911045)
			(xy 374.400369 20.911045) (xy 374.314986 20.918957) (xy 374.230696 20.934713) (xy 374.14822 20.95818)
			(xy 374.068261 20.989156) (xy 373.991501 21.027378) (xy 373.918595 21.072519) (xy 373.850166 21.124195)
			(xy 373.786796 21.181964) (xy 373.729027 21.245334) (xy 373.677351 21.313763) (xy 373.63221 21.386669)
			(xy 373.593988 21.463429) (xy 373.563012 21.543388) (xy 373.539545 21.625864) (xy 373.523789 21.710154)
			(xy 373.515877 21.795537) (xy 342.659832 21.795537) (xy 342.652579 21.717266) (xy 342.636823 21.632976)
			(xy 342.613356 21.5505) (xy 342.58238 21.470541) (xy 342.544158 21.393781) (xy 342.499017 21.320875)
			(xy 342.447341 21.252446) (xy 342.389572 21.189076) (xy 342.326202 21.131307) (xy 342.257773 21.079631)
			(xy 342.184867 21.03449) (xy 342.108107 20.996268) (xy 342.028148 20.965292) (xy 341.945672 20.941825)
			(xy 341.861382 20.926069) (xy 341.775999 20.918157) (xy 341.690249 20.918157) (xy 341.604866 20.926069)
			(xy 341.520576 20.941825) (xy 341.4381 20.965292) (xy 341.358141 20.996268) (xy 341.281381 21.03449)
			(xy 341.208475 21.079631) (xy 341.140046 21.131307) (xy 341.076676 21.189076) (xy 341.018907 21.252446)
			(xy 340.967231 21.320875) (xy 340.92209 21.393781) (xy 340.883868 21.470541) (xy 340.852892 21.5505)
			(xy 340.829425 21.632976) (xy 340.813669 21.717266) (xy 340.805757 21.802649) (xy 336.310491 21.802649)
			(xy 336.302579 21.717266) (xy 336.286823 21.632976) (xy 336.263356 21.5505) (xy 336.23238 21.470541)
			(xy 336.194158 21.393781) (xy 336.149017 21.320875) (xy 336.097341 21.252446) (xy 336.039572 21.189076)
			(xy 335.976202 21.131307) (xy 335.907773 21.079631) (xy 335.834867 21.03449) (xy 335.758107 20.996268)
			(xy 335.678148 20.965292) (xy 335.595672 20.941825) (xy 335.511382 20.926069) (xy 335.425999 20.918157)
			(xy 335.340249 20.918157) (xy 335.254866 20.926069) (xy 335.170576 20.941825) (xy 335.0881 20.965292)
			(xy 335.008141 20.996268) (xy 334.931381 21.03449) (xy 334.858475 21.079631) (xy 334.790046 21.131307)
			(xy 334.726676 21.189076) (xy 334.668907 21.252446) (xy 334.617231 21.320875) (xy 334.57209 21.393781)
			(xy 334.533868 21.470541) (xy 334.502892 21.5505) (xy 334.479425 21.632976) (xy 334.463669 21.717266)
			(xy 334.455757 21.802649) (xy 316.569693 21.802649) (xy 316.569611 21.795537) (xy 316.561699 21.710154)
			(xy 316.545943 21.625864) (xy 316.522476 21.543388) (xy 316.4915 21.463429) (xy 316.453278 21.386669)
			(xy 316.408137 21.313763) (xy 316.356461 21.245334) (xy 316.298692 21.181964) (xy 316.235322 21.124195)
			(xy 316.166893 21.072519) (xy 316.093987 21.027378) (xy 316.017227 20.989156) (xy 315.937268 20.95818)
			(xy 315.854792 20.934713) (xy 315.770502 20.918957) (xy 315.685119 20.911045) (xy 315.599369 20.911045)
			(xy 315.513986 20.918957) (xy 315.429696 20.934713) (xy 315.34722 20.95818) (xy 315.267261 20.989156)
			(xy 315.190501 21.027378) (xy 315.117595 21.072519) (xy 315.049166 21.124195) (xy 314.985796 21.181964)
			(xy 314.928027 21.245334) (xy 314.876351 21.313763) (xy 314.83121 21.386669) (xy 314.792988 21.463429)
			(xy 314.762012 21.543388) (xy 314.738545 21.625864) (xy 314.722789 21.710154) (xy 314.714877 21.795537)
			(xy 310.219611 21.795537) (xy 310.211699 21.710154) (xy 310.195943 21.625864) (xy 310.172476 21.543388)
			(xy 310.1415 21.463429) (xy 310.103278 21.386669) (xy 310.058137 21.313763) (xy 310.006461 21.245334)
			(xy 309.948692 21.181964) (xy 309.885322 21.124195) (xy 309.816893 21.072519) (xy 309.743987 21.027378)
			(xy 309.667227 20.989156) (xy 309.587268 20.95818) (xy 309.504792 20.934713) (xy 309.420502 20.918957)
			(xy 309.335119 20.911045) (xy 309.249369 20.911045) (xy 309.163986 20.918957) (xy 309.079696 20.934713)
			(xy 308.99722 20.95818) (xy 308.917261 20.989156) (xy 308.840501 21.027378) (xy 308.767595 21.072519)
			(xy 308.699166 21.124195) (xy 308.635796 21.181964) (xy 308.578027 21.245334) (xy 308.526351 21.313763)
			(xy 308.48121 21.386669) (xy 308.442988 21.463429) (xy 308.412012 21.543388) (xy 308.388545 21.625864)
			(xy 308.372789 21.710154) (xy 308.364877 21.795537) (xy 277.508832 21.795537) (xy 277.501579 21.717266)
			(xy 277.485823 21.632976) (xy 277.462356 21.5505) (xy 277.43138 21.470541) (xy 277.393158 21.393781)
			(xy 277.348017 21.320875) (xy 277.296341 21.252446) (xy 277.238572 21.189076) (xy 277.175202 21.131307)
			(xy 277.106773 21.079631) (xy 277.033867 21.03449) (xy 276.957107 20.996268) (xy 276.877148 20.965292)
			(xy 276.794672 20.941825) (xy 276.710382 20.926069) (xy 276.624999 20.918157) (xy 276.539249 20.918157)
			(xy 276.453866 20.926069) (xy 276.369576 20.941825) (xy 276.2871 20.965292) (xy 276.207141 20.996268)
			(xy 276.130381 21.03449) (xy 276.057475 21.079631) (xy 275.989046 21.131307) (xy 275.925676 21.189076)
			(xy 275.867907 21.252446) (xy 275.816231 21.320875) (xy 275.77109 21.393781) (xy 275.732868 21.470541)
			(xy 275.701892 21.5505) (xy 275.678425 21.632976) (xy 275.662669 21.717266) (xy 275.654757 21.802649)
			(xy 271.159491 21.802649) (xy 271.151579 21.717266) (xy 271.135823 21.632976) (xy 271.112356 21.5505)
			(xy 271.08138 21.470541) (xy 271.043158 21.393781) (xy 270.998017 21.320875) (xy 270.946341 21.252446)
			(xy 270.888572 21.189076) (xy 270.825202 21.131307) (xy 270.756773 21.079631) (xy 270.683867 21.03449)
			(xy 270.607107 20.996268) (xy 270.527148 20.965292) (xy 270.444672 20.941825) (xy 270.360382 20.926069)
			(xy 270.274999 20.918157) (xy 270.189249 20.918157) (xy 270.103866 20.926069) (xy 270.019576 20.941825)
			(xy 269.9371 20.965292) (xy 269.857141 20.996268) (xy 269.780381 21.03449) (xy 269.707475 21.079631)
			(xy 269.639046 21.131307) (xy 269.575676 21.189076) (xy 269.517907 21.252446) (xy 269.466231 21.320875)
			(xy 269.42109 21.393781) (xy 269.382868 21.470541) (xy 269.351892 21.5505) (xy 269.328425 21.632976)
			(xy 269.312669 21.717266) (xy 269.304757 21.802649) (xy 158.621984 21.802649) (xy 158.621984 19.262649)
			(xy 209.995757 19.262649) (xy 209.995757 19.348399) (xy 210.003669 19.433782) (xy 210.019425 19.518072)
			(xy 210.042892 19.600548) (xy 210.073868 19.680507) (xy 210.11209 19.757267) (xy 210.157231 19.830173)
			(xy 210.208907 19.898602) (xy 210.266676 19.961972) (xy 210.330046 20.019741) (xy 210.398475 20.071417)
			(xy 210.471381 20.116558) (xy 210.548141 20.15478) (xy 210.6281 20.185756) (xy 210.710576 20.209223)
			(xy 210.794866 20.224979) (xy 210.880249 20.232891) (xy 210.965999 20.232891) (xy 211.051382 20.224979)
			(xy 211.135672 20.209223) (xy 211.218148 20.185756) (xy 211.298107 20.15478) (xy 211.374867 20.116558)
			(xy 211.447773 20.071417) (xy 211.516202 20.019741) (xy 211.579572 19.961972) (xy 211.637341 19.898602)
			(xy 211.689017 19.830173) (xy 211.734158 19.757267) (xy 211.77238 19.680507) (xy 211.803356 19.600548)
			(xy 211.826823 19.518072) (xy 211.842579 19.433782) (xy 211.850491 19.348399) (xy 211.850986 19.305524)
			(xy 211.850491 19.262649) (xy 216.345757 19.262649) (xy 216.345757 19.348399) (xy 216.353669 19.433782)
			(xy 216.369425 19.518072) (xy 216.392892 19.600548) (xy 216.423868 19.680507) (xy 216.46209 19.757267)
			(xy 216.507231 19.830173) (xy 216.558907 19.898602) (xy 216.616676 19.961972) (xy 216.680046 20.019741)
			(xy 216.748475 20.071417) (xy 216.821381 20.116558) (xy 216.898141 20.15478) (xy 216.9781 20.185756)
			(xy 217.060576 20.209223) (xy 217.144866 20.224979) (xy 217.230249 20.232891) (xy 217.315999 20.232891)
			(xy 217.401382 20.224979) (xy 217.485672 20.209223) (xy 217.568148 20.185756) (xy 217.648107 20.15478)
			(xy 217.724867 20.116558) (xy 217.797773 20.071417) (xy 217.866202 20.019741) (xy 217.929572 19.961972)
			(xy 217.987341 19.898602) (xy 218.039017 19.830173) (xy 218.084158 19.757267) (xy 218.12238 19.680507)
			(xy 218.153356 19.600548) (xy 218.176823 19.518072) (xy 218.192579 19.433782) (xy 218.200491 19.348399)
			(xy 218.200986 19.305524) (xy 218.200491 19.262649) (xy 218.199832 19.255537) (xy 244.026677 19.255537)
			(xy 244.026677 19.341287) (xy 244.034589 19.42667) (xy 244.050345 19.51096) (xy 244.073812 19.593436)
			(xy 244.104788 19.673395) (xy 244.14301 19.750155) (xy 244.188151 19.823061) (xy 244.239827 19.89149)
			(xy 244.297596 19.95486) (xy 244.360966 20.012629) (xy 244.429395 20.064305) (xy 244.502301 20.109446)
			(xy 244.579061 20.147668) (xy 244.65902 20.178644) (xy 244.741496 20.202111) (xy 244.825786 20.217867)
			(xy 244.911169 20.225779) (xy 244.996919 20.225779) (xy 245.082302 20.217867) (xy 245.166592 20.202111)
			(xy 245.249068 20.178644) (xy 245.329027 20.147668) (xy 245.405787 20.109446) (xy 245.478693 20.064305)
			(xy 245.547122 20.012629) (xy 245.610492 19.95486) (xy 245.668261 19.89149) (xy 245.719937 19.823061)
			(xy 245.765078 19.750155) (xy 245.8033 19.673395) (xy 245.834276 19.593436) (xy 245.857743 19.51096)
			(xy 245.873499 19.42667) (xy 245.881411 19.341287) (xy 245.881906 19.298412) (xy 245.881411 19.255537)
			(xy 250.376677 19.255537) (xy 250.376677 19.341287) (xy 250.384589 19.42667) (xy 250.400345 19.51096)
			(xy 250.423812 19.593436) (xy 250.454788 19.673395) (xy 250.49301 19.750155) (xy 250.538151 19.823061)
			(xy 250.589827 19.89149) (xy 250.647596 19.95486) (xy 250.710966 20.012629) (xy 250.779395 20.064305)
			(xy 250.852301 20.109446) (xy 250.929061 20.147668) (xy 251.00902 20.178644) (xy 251.091496 20.202111)
			(xy 251.175786 20.217867) (xy 251.261169 20.225779) (xy 251.346919 20.225779) (xy 251.432302 20.217867)
			(xy 251.516592 20.202111) (xy 251.599068 20.178644) (xy 251.679027 20.147668) (xy 251.755787 20.109446)
			(xy 251.828693 20.064305) (xy 251.897122 20.012629) (xy 251.960492 19.95486) (xy 252.018261 19.89149)
			(xy 252.069937 19.823061) (xy 252.115078 19.750155) (xy 252.1533 19.673395) (xy 252.184276 19.593436)
			(xy 252.207743 19.51096) (xy 252.223499 19.42667) (xy 252.231411 19.341287) (xy 252.231906 19.298412)
			(xy 252.231493 19.262649) (xy 269.304757 19.262649) (xy 269.304757 19.348399) (xy 269.312669 19.433782)
			(xy 269.328425 19.518072) (xy 269.351892 19.600548) (xy 269.382868 19.680507) (xy 269.42109 19.757267)
			(xy 269.466231 19.830173) (xy 269.517907 19.898602) (xy 269.575676 19.961972) (xy 269.639046 20.019741)
			(xy 269.707475 20.071417) (xy 269.780381 20.116558) (xy 269.857141 20.15478) (xy 269.9371 20.185756)
			(xy 270.019576 20.209223) (xy 270.103866 20.224979) (xy 270.189249 20.232891) (xy 270.274999 20.232891)
			(xy 270.360382 20.224979) (xy 270.444672 20.209223) (xy 270.527148 20.185756) (xy 270.607107 20.15478)
			(xy 270.62931 20.143724) (xy 274.239736 20.143724) (xy 274.239736 21.007324) (xy 274.240222 21.034593)
			(xy 274.247984 21.088577) (xy 274.263349 21.140907) (xy 274.286006 21.190517) (xy 274.315492 21.236398)
			(xy 274.351207 21.277615) (xy 274.392424 21.31333) (xy 274.438305 21.342816) (xy 274.487915 21.365473)
			(xy 274.540245 21.380838) (xy 274.594229 21.3886) (xy 274.648767 21.3886) (xy 274.702751 21.380838)
			(xy 274.755081 21.365473) (xy 274.804691 21.342816) (xy 274.850572 21.31333) (xy 274.891789 21.277615)
			(xy 274.927504 21.236398) (xy 274.95699 21.190517) (xy 274.979647 21.140907) (xy 274.995012 21.088577)
			(xy 275.002774 21.034593) (xy 275.00326 21.007324) (xy 275.00326 20.143724) (xy 275.002774 20.116455)
			(xy 274.995012 20.062471) (xy 274.979647 20.010141) (xy 274.95699 19.960531) (xy 274.927504 19.91465)
			(xy 274.891789 19.873433) (xy 274.850572 19.837718) (xy 274.804691 19.808232) (xy 274.755081 19.785575)
			(xy 274.702751 19.77021) (xy 274.648767 19.762448) (xy 274.594229 19.762448) (xy 274.540245 19.77021)
			(xy 274.487915 19.785575) (xy 274.438305 19.808232) (xy 274.392424 19.837718) (xy 274.351207 19.873433)
			(xy 274.315492 19.91465) (xy 274.286006 19.960531) (xy 274.263349 20.010141) (xy 274.247984 20.062471)
			(xy 274.240222 20.116455) (xy 274.239736 20.143724) (xy 270.62931 20.143724) (xy 270.683867 20.116558)
			(xy 270.756773 20.071417) (xy 270.825202 20.019741) (xy 270.888572 19.961972) (xy 270.946341 19.898602)
			(xy 270.998017 19.830173) (xy 271.043158 19.757267) (xy 271.08138 19.680507) (xy 271.112356 19.600548)
			(xy 271.135823 19.518072) (xy 271.151579 19.433782) (xy 271.159491 19.348399) (xy 271.159986 19.305524)
			(xy 271.159491 19.262649) (xy 275.654757 19.262649) (xy 275.654757 19.348399) (xy 275.662669 19.433782)
			(xy 275.678425 19.518072) (xy 275.701892 19.600548) (xy 275.732868 19.680507) (xy 275.77109 19.757267)
			(xy 275.816231 19.830173) (xy 275.867907 19.898602) (xy 275.925676 19.961972) (xy 275.989046 20.019741)
			(xy 276.057475 20.071417) (xy 276.130381 20.116558) (xy 276.207141 20.15478) (xy 276.2871 20.185756)
			(xy 276.369576 20.209223) (xy 276.453866 20.224979) (xy 276.539249 20.232891) (xy 276.624999 20.232891)
			(xy 276.710382 20.224979) (xy 276.794672 20.209223) (xy 276.877148 20.185756) (xy 276.957107 20.15478)
			(xy 277.033867 20.116558) (xy 277.106773 20.071417) (xy 277.175202 20.019741) (xy 277.238572 19.961972)
			(xy 277.296341 19.898602) (xy 277.348017 19.830173) (xy 277.393158 19.757267) (xy 277.43138 19.680507)
			(xy 277.462356 19.600548) (xy 277.485823 19.518072) (xy 277.501579 19.433782) (xy 277.509491 19.348399)
			(xy 277.509986 19.305524) (xy 277.509491 19.262649) (xy 277.508832 19.255537) (xy 308.364877 19.255537)
			(xy 308.364877 19.341287) (xy 308.372789 19.42667) (xy 308.388545 19.51096) (xy 308.412012 19.593436)
			(xy 308.442988 19.673395) (xy 308.48121 19.750155) (xy 308.526351 19.823061) (xy 308.578027 19.89149)
			(xy 308.635796 19.95486) (xy 308.699166 20.012629) (xy 308.767595 20.064305) (xy 308.840501 20.109446)
			(xy 308.917261 20.147668) (xy 308.99722 20.178644) (xy 309.079696 20.202111) (xy 309.163986 20.217867)
			(xy 309.249369 20.225779) (xy 309.335119 20.225779) (xy 309.420502 20.217867) (xy 309.504792 20.202111)
			(xy 309.587268 20.178644) (xy 309.667227 20.147668) (xy 309.68943 20.136612) (xy 310.871108 20.136612)
			(xy 310.871108 21.000212) (xy 310.871594 21.027481) (xy 310.879356 21.081465) (xy 310.894721 21.133795)
			(xy 310.917378 21.183405) (xy 310.946864 21.229286) (xy 310.982579 21.270503) (xy 311.023796 21.306218)
			(xy 311.069677 21.335704) (xy 311.119287 21.358361) (xy 311.171617 21.373726) (xy 311.225601 21.381488)
			(xy 311.280139 21.381488) (xy 311.334123 21.373726) (xy 311.386453 21.358361) (xy 311.436063 21.335704)
			(xy 311.481944 21.306218) (xy 311.523161 21.270503) (xy 311.558876 21.229286) (xy 311.588362 21.183405)
			(xy 311.611019 21.133795) (xy 311.626384 21.081465) (xy 311.634146 21.027481) (xy 311.634632 21.000212)
			(xy 311.634632 20.136612) (xy 311.634146 20.109343) (xy 311.626384 20.055359) (xy 311.611019 20.003029)
			(xy 311.588362 19.953419) (xy 311.558876 19.907538) (xy 311.523161 19.866321) (xy 311.481944 19.830606)
			(xy 311.436063 19.80112) (xy 311.386453 19.778463) (xy 311.334123 19.763098) (xy 311.280139 19.755336)
			(xy 311.225601 19.755336) (xy 311.171617 19.763098) (xy 311.119287 19.778463) (xy 311.069677 19.80112)
			(xy 311.023796 19.830606) (xy 310.982579 19.866321) (xy 310.946864 19.907538) (xy 310.917378 19.953419)
			(xy 310.894721 20.003029) (xy 310.879356 20.055359) (xy 310.871594 20.109343) (xy 310.871108 20.136612)
			(xy 309.68943 20.136612) (xy 309.743987 20.109446) (xy 309.816893 20.064305) (xy 309.885322 20.012629)
			(xy 309.948692 19.95486) (xy 310.006461 19.89149) (xy 310.058137 19.823061) (xy 310.103278 19.750155)
			(xy 310.1415 19.673395) (xy 310.172476 19.593436) (xy 310.195943 19.51096) (xy 310.211699 19.42667)
			(xy 310.219611 19.341287) (xy 310.220106 19.298412) (xy 310.219611 19.255537) (xy 314.714877 19.255537)
			(xy 314.714877 19.341287) (xy 314.722789 19.42667) (xy 314.738545 19.51096) (xy 314.762012 19.593436)
			(xy 314.792988 19.673395) (xy 314.83121 19.750155) (xy 314.876351 19.823061) (xy 314.928027 19.89149)
			(xy 314.985796 19.95486) (xy 315.049166 20.012629) (xy 315.117595 20.064305) (xy 315.190501 20.109446)
			(xy 315.267261 20.147668) (xy 315.34722 20.178644) (xy 315.429696 20.202111) (xy 315.513986 20.217867)
			(xy 315.599369 20.225779) (xy 315.685119 20.225779) (xy 315.770502 20.217867) (xy 315.854792 20.202111)
			(xy 315.937268 20.178644) (xy 316.017227 20.147668) (xy 316.093987 20.109446) (xy 316.166893 20.064305)
			(xy 316.235322 20.012629) (xy 316.298692 19.95486) (xy 316.356461 19.89149) (xy 316.408137 19.823061)
			(xy 316.453278 19.750155) (xy 316.4915 19.673395) (xy 316.522476 19.593436) (xy 316.545943 19.51096)
			(xy 316.561699 19.42667) (xy 316.569611 19.341287) (xy 316.570106 19.298412) (xy 316.569693 19.262649)
			(xy 334.455757 19.262649) (xy 334.455757 19.348399) (xy 334.463669 19.433782) (xy 334.479425 19.518072)
			(xy 334.502892 19.600548) (xy 334.533868 19.680507) (xy 334.57209 19.757267) (xy 334.617231 19.830173)
			(xy 334.668907 19.898602) (xy 334.726676 19.961972) (xy 334.790046 20.019741) (xy 334.858475 20.071417)
			(xy 334.931381 20.116558) (xy 335.008141 20.15478) (xy 335.0881 20.185756) (xy 335.170576 20.209223)
			(xy 335.254866 20.224979) (xy 335.340249 20.232891) (xy 335.425999 20.232891) (xy 335.511382 20.224979)
			(xy 335.595672 20.209223) (xy 335.678148 20.185756) (xy 335.758107 20.15478) (xy 335.78031 20.143724)
			(xy 339.390736 20.143724) (xy 339.390736 21.007324) (xy 339.391222 21.034593) (xy 339.398984 21.088577)
			(xy 339.414349 21.140907) (xy 339.437006 21.190517) (xy 339.466492 21.236398) (xy 339.502207 21.277615)
			(xy 339.543424 21.31333) (xy 339.589305 21.342816) (xy 339.638915 21.365473) (xy 339.691245 21.380838)
			(xy 339.745229 21.3886) (xy 339.799767 21.3886) (xy 339.853751 21.380838) (xy 339.906081 21.365473)
			(xy 339.955691 21.342816) (xy 340.001572 21.31333) (xy 340.042789 21.277615) (xy 340.078504 21.236398)
			(xy 340.10799 21.190517) (xy 340.130647 21.140907) (xy 340.146012 21.088577) (xy 340.153774 21.034593)
			(xy 340.15426 21.007324) (xy 340.15426 20.143724) (xy 340.153774 20.116455) (xy 340.146012 20.062471)
			(xy 340.130647 20.010141) (xy 340.10799 19.960531) (xy 340.078504 19.91465) (xy 340.042789 19.873433)
			(xy 340.001572 19.837718) (xy 339.955691 19.808232) (xy 339.906081 19.785575) (xy 339.853751 19.77021)
			(xy 339.799767 19.762448) (xy 339.745229 19.762448) (xy 339.691245 19.77021) (xy 339.638915 19.785575)
			(xy 339.589305 19.808232) (xy 339.543424 19.837718) (xy 339.502207 19.873433) (xy 339.466492 19.91465)
			(xy 339.437006 19.960531) (xy 339.414349 20.010141) (xy 339.398984 20.062471) (xy 339.391222 20.116455)
			(xy 339.390736 20.143724) (xy 335.78031 20.143724) (xy 335.834867 20.116558) (xy 335.907773 20.071417)
			(xy 335.976202 20.019741) (xy 336.039572 19.961972) (xy 336.097341 19.898602) (xy 336.149017 19.830173)
			(xy 336.194158 19.757267) (xy 336.23238 19.680507) (xy 336.263356 19.600548) (xy 336.286823 19.518072)
			(xy 336.302579 19.433782) (xy 336.310491 19.348399) (xy 336.310986 19.305524) (xy 336.310491 19.262649)
			(xy 340.805757 19.262649) (xy 340.805757 19.348399) (xy 340.813669 19.433782) (xy 340.829425 19.518072)
			(xy 340.852892 19.600548) (xy 340.883868 19.680507) (xy 340.92209 19.757267) (xy 340.967231 19.830173)
			(xy 341.018907 19.898602) (xy 341.076676 19.961972) (xy 341.140046 20.019741) (xy 341.208475 20.071417)
			(xy 341.281381 20.116558) (xy 341.358141 20.15478) (xy 341.4381 20.185756) (xy 341.520576 20.209223)
			(xy 341.604866 20.224979) (xy 341.690249 20.232891) (xy 341.775999 20.232891) (xy 341.861382 20.224979)
			(xy 341.945672 20.209223) (xy 342.028148 20.185756) (xy 342.108107 20.15478) (xy 342.184867 20.116558)
			(xy 342.257773 20.071417) (xy 342.326202 20.019741) (xy 342.389572 19.961972) (xy 342.447341 19.898602)
			(xy 342.499017 19.830173) (xy 342.544158 19.757267) (xy 342.58238 19.680507) (xy 342.613356 19.600548)
			(xy 342.636823 19.518072) (xy 342.652579 19.433782) (xy 342.660491 19.348399) (xy 342.660986 19.305524)
			(xy 342.660491 19.262649) (xy 342.659832 19.255537) (xy 373.515877 19.255537) (xy 373.515877 19.341287)
			(xy 373.523789 19.42667) (xy 373.539545 19.51096) (xy 373.563012 19.593436) (xy 373.593988 19.673395)
			(xy 373.63221 19.750155) (xy 373.677351 19.823061) (xy 373.729027 19.89149) (xy 373.786796 19.95486)
			(xy 373.850166 20.012629) (xy 373.918595 20.064305) (xy 373.991501 20.109446) (xy 374.068261 20.147668)
			(xy 374.14822 20.178644) (xy 374.230696 20.202111) (xy 374.314986 20.217867) (xy 374.400369 20.225779)
			(xy 374.486119 20.225779) (xy 374.571502 20.217867) (xy 374.655792 20.202111) (xy 374.738268 20.178644)
			(xy 374.818227 20.147668) (xy 374.84043 20.136612) (xy 376.022108 20.136612) (xy 376.022108 21.000212)
			(xy 376.022594 21.027481) (xy 376.030356 21.081465) (xy 376.045721 21.133795) (xy 376.068378 21.183405)
			(xy 376.097864 21.229286) (xy 376.133579 21.270503) (xy 376.174796 21.306218) (xy 376.220677 21.335704)
			(xy 376.270287 21.358361) (xy 376.322617 21.373726) (xy 376.376601 21.381488) (xy 376.431139 21.381488)
			(xy 376.485123 21.373726) (xy 376.537453 21.358361) (xy 376.587063 21.335704) (xy 376.632944 21.306218)
			(xy 376.674161 21.270503) (xy 376.709876 21.229286) (xy 376.739362 21.183405) (xy 376.762019 21.133795)
			(xy 376.777384 21.081465) (xy 376.785146 21.027481) (xy 376.785632 21.000212) (xy 376.785632 20.136612)
			(xy 376.785146 20.109343) (xy 376.777384 20.055359) (xy 376.762019 20.003029) (xy 376.739362 19.953419)
			(xy 376.709876 19.907538) (xy 376.674161 19.866321) (xy 376.632944 19.830606) (xy 376.587063 19.80112)
			(xy 376.537453 19.778463) (xy 376.485123 19.763098) (xy 376.431139 19.755336) (xy 376.376601 19.755336)
			(xy 376.322617 19.763098) (xy 376.270287 19.778463) (xy 376.220677 19.80112) (xy 376.174796 19.830606)
			(xy 376.133579 19.866321) (xy 376.097864 19.907538) (xy 376.068378 19.953419) (xy 376.045721 20.003029)
			(xy 376.030356 20.055359) (xy 376.022594 20.109343) (xy 376.022108 20.136612) (xy 374.84043 20.136612)
			(xy 374.894987 20.109446) (xy 374.967893 20.064305) (xy 375.036322 20.012629) (xy 375.099692 19.95486)
			(xy 375.157461 19.89149) (xy 375.209137 19.823061) (xy 375.254278 19.750155) (xy 375.2925 19.673395)
			(xy 375.323476 19.593436) (xy 375.346943 19.51096) (xy 375.362699 19.42667) (xy 375.370611 19.341287)
			(xy 375.371106 19.298412) (xy 375.370611 19.255537) (xy 379.865877 19.255537) (xy 379.865877 19.341287)
			(xy 379.873789 19.42667) (xy 379.889545 19.51096) (xy 379.913012 19.593436) (xy 379.943988 19.673395)
			(xy 379.98221 19.750155) (xy 380.027351 19.823061) (xy 380.079027 19.89149) (xy 380.136796 19.95486)
			(xy 380.200166 20.012629) (xy 380.268595 20.064305) (xy 380.341501 20.109446) (xy 380.418261 20.147668)
			(xy 380.49822 20.178644) (xy 380.580696 20.202111) (xy 380.664986 20.217867) (xy 380.750369 20.225779)
			(xy 380.836119 20.225779) (xy 380.921502 20.217867) (xy 381.005792 20.202111) (xy 381.088268 20.178644)
			(xy 381.168227 20.147668) (xy 381.244987 20.109446) (xy 381.317893 20.064305) (xy 381.386322 20.012629)
			(xy 381.449692 19.95486) (xy 381.507461 19.89149) (xy 381.559137 19.823061) (xy 381.604278 19.750155)
			(xy 381.6425 19.673395) (xy 381.673476 19.593436) (xy 381.696943 19.51096) (xy 381.712699 19.42667)
			(xy 381.720611 19.341287) (xy 381.721106 19.298412) (xy 381.720693 19.262649) (xy 399.098757 19.262649)
			(xy 399.098757 19.348399) (xy 399.106669 19.433782) (xy 399.122425 19.518072) (xy 399.145892 19.600548)
			(xy 399.176868 19.680507) (xy 399.21509 19.757267) (xy 399.260231 19.830173) (xy 399.311907 19.898602)
			(xy 399.369676 19.961972) (xy 399.433046 20.019741) (xy 399.501475 20.071417) (xy 399.574381 20.116558)
			(xy 399.651141 20.15478) (xy 399.7311 20.185756) (xy 399.813576 20.209223) (xy 399.897866 20.224979)
			(xy 399.983249 20.232891) (xy 400.068999 20.232891) (xy 400.154382 20.224979) (xy 400.238672 20.209223)
			(xy 400.321148 20.185756) (xy 400.401107 20.15478) (xy 400.42331 20.143724) (xy 404.033736 20.143724)
			(xy 404.033736 21.007324) (xy 404.034222 21.034593) (xy 404.041984 21.088577) (xy 404.057349 21.140907)
			(xy 404.080006 21.190517) (xy 404.109492 21.236398) (xy 404.145207 21.277615) (xy 404.186424 21.31333)
			(xy 404.232305 21.342816) (xy 404.281915 21.365473) (xy 404.334245 21.380838) (xy 404.388229 21.3886)
			(xy 404.442767 21.3886) (xy 404.496751 21.380838) (xy 404.549081 21.365473) (xy 404.598691 21.342816)
			(xy 404.644572 21.31333) (xy 404.685789 21.277615) (xy 404.721504 21.236398) (xy 404.75099 21.190517)
			(xy 404.773647 21.140907) (xy 404.789012 21.088577) (xy 404.796774 21.034593) (xy 404.79726 21.007324)
			(xy 404.79726 20.143724) (xy 404.796774 20.116455) (xy 404.789012 20.062471) (xy 404.773647 20.010141)
			(xy 404.75099 19.960531) (xy 404.721504 19.91465) (xy 404.685789 19.873433) (xy 404.644572 19.837718)
			(xy 404.598691 19.808232) (xy 404.549081 19.785575) (xy 404.496751 19.77021) (xy 404.442767 19.762448)
			(xy 404.388229 19.762448) (xy 404.334245 19.77021) (xy 404.281915 19.785575) (xy 404.232305 19.808232)
			(xy 404.186424 19.837718) (xy 404.145207 19.873433) (xy 404.109492 19.91465) (xy 404.080006 19.960531)
			(xy 404.057349 20.010141) (xy 404.041984 20.062471) (xy 404.034222 20.116455) (xy 404.033736 20.143724)
			(xy 400.42331 20.143724) (xy 400.477867 20.116558) (xy 400.550773 20.071417) (xy 400.619202 20.019741)
			(xy 400.682572 19.961972) (xy 400.740341 19.898602) (xy 400.792017 19.830173) (xy 400.837158 19.757267)
			(xy 400.87538 19.680507) (xy 400.906356 19.600548) (xy 400.929823 19.518072) (xy 400.945579 19.433782)
			(xy 400.953491 19.348399) (xy 400.953986 19.305524) (xy 400.953491 19.262649) (xy 405.448757 19.262649)
			(xy 405.448757 19.348399) (xy 405.456669 19.433782) (xy 405.472425 19.518072) (xy 405.495892 19.600548)
			(xy 405.526868 19.680507) (xy 405.56509 19.757267) (xy 405.610231 19.830173) (xy 405.661907 19.898602)
			(xy 405.719676 19.961972) (xy 405.783046 20.019741) (xy 405.851475 20.071417) (xy 405.924381 20.116558)
			(xy 406.001141 20.15478) (xy 406.0811 20.185756) (xy 406.163576 20.209223) (xy 406.247866 20.224979)
			(xy 406.333249 20.232891) (xy 406.418999 20.232891) (xy 406.504382 20.224979) (xy 406.588672 20.209223)
			(xy 406.671148 20.185756) (xy 406.751107 20.15478) (xy 406.827867 20.116558) (xy 406.900773 20.071417)
			(xy 406.969202 20.019741) (xy 407.032572 19.961972) (xy 407.090341 19.898602) (xy 407.142017 19.830173)
			(xy 407.187158 19.757267) (xy 407.22538 19.680507) (xy 407.256356 19.600548) (xy 407.279823 19.518072)
			(xy 407.295579 19.433782) (xy 407.303491 19.348399) (xy 407.303986 19.305524) (xy 407.303491 19.262649)
			(xy 407.302832 19.255537) (xy 438.158877 19.255537) (xy 438.158877 19.341287) (xy 438.166789 19.42667)
			(xy 438.182545 19.51096) (xy 438.206012 19.593436) (xy 438.236988 19.673395) (xy 438.27521 19.750155)
			(xy 438.320351 19.823061) (xy 438.372027 19.89149) (xy 438.429796 19.95486) (xy 438.493166 20.012629)
			(xy 438.561595 20.064305) (xy 438.634501 20.109446) (xy 438.711261 20.147668) (xy 438.79122 20.178644)
			(xy 438.873696 20.202111) (xy 438.957986 20.217867) (xy 439.043369 20.225779) (xy 439.129119 20.225779)
			(xy 439.214502 20.217867) (xy 439.298792 20.202111) (xy 439.381268 20.178644) (xy 439.461227 20.147668)
			(xy 439.48343 20.136612) (xy 440.665108 20.136612) (xy 440.665108 21.000212) (xy 440.665594 21.027481)
			(xy 440.673356 21.081465) (xy 440.688721 21.133795) (xy 440.711378 21.183405) (xy 440.740864 21.229286)
			(xy 440.776579 21.270503) (xy 440.817796 21.306218) (xy 440.863677 21.335704) (xy 440.913287 21.358361)
			(xy 440.965617 21.373726) (xy 441.019601 21.381488) (xy 441.074139 21.381488) (xy 441.128123 21.373726)
			(xy 441.180453 21.358361) (xy 441.230063 21.335704) (xy 441.275944 21.306218) (xy 441.317161 21.270503)
			(xy 441.352876 21.229286) (xy 441.382362 21.183405) (xy 441.405019 21.133795) (xy 441.420384 21.081465)
			(xy 441.428146 21.027481) (xy 441.428632 21.000212) (xy 441.428632 20.136612) (xy 441.428146 20.109343)
			(xy 441.420384 20.055359) (xy 441.405019 20.003029) (xy 441.382362 19.953419) (xy 441.352876 19.907538)
			(xy 441.317161 19.866321) (xy 441.275944 19.830606) (xy 441.230063 19.80112) (xy 441.180453 19.778463)
			(xy 441.128123 19.763098) (xy 441.074139 19.755336) (xy 441.019601 19.755336) (xy 440.965617 19.763098)
			(xy 440.913287 19.778463) (xy 440.863677 19.80112) (xy 440.817796 19.830606) (xy 440.776579 19.866321)
			(xy 440.740864 19.907538) (xy 440.711378 19.953419) (xy 440.688721 20.003029) (xy 440.673356 20.055359)
			(xy 440.665594 20.109343) (xy 440.665108 20.136612) (xy 439.48343 20.136612) (xy 439.537987 20.109446)
			(xy 439.610893 20.064305) (xy 439.679322 20.012629) (xy 439.742692 19.95486) (xy 439.800461 19.89149)
			(xy 439.852137 19.823061) (xy 439.897278 19.750155) (xy 439.9355 19.673395) (xy 439.966476 19.593436)
			(xy 439.989943 19.51096) (xy 440.005699 19.42667) (xy 440.013611 19.341287) (xy 440.014106 19.298412)
			(xy 440.013611 19.255537) (xy 444.508877 19.255537) (xy 444.508877 19.341287) (xy 444.516789 19.42667)
			(xy 444.532545 19.51096) (xy 444.556012 19.593436) (xy 444.586988 19.673395) (xy 444.62521 19.750155)
			(xy 444.670351 19.823061) (xy 444.722027 19.89149) (xy 444.779796 19.95486) (xy 444.843166 20.012629)
			(xy 444.911595 20.064305) (xy 444.984501 20.109446) (xy 445.061261 20.147668) (xy 445.14122 20.178644)
			(xy 445.223696 20.202111) (xy 445.307986 20.217867) (xy 445.393369 20.225779) (xy 445.479119 20.225779)
			(xy 445.564502 20.217867) (xy 445.648792 20.202111) (xy 445.731268 20.178644) (xy 445.811227 20.147668)
			(xy 445.887987 20.109446) (xy 445.960893 20.064305) (xy 446.029322 20.012629) (xy 446.092692 19.95486)
			(xy 446.150461 19.89149) (xy 446.202137 19.823061) (xy 446.247278 19.750155) (xy 446.2855 19.673395)
			(xy 446.316476 19.593436) (xy 446.339943 19.51096) (xy 446.355699 19.42667) (xy 446.363611 19.341287)
			(xy 446.364106 19.298412) (xy 446.363611 19.255537) (xy 446.355699 19.170154) (xy 446.339943 19.085864)
			(xy 446.316476 19.003388) (xy 446.2855 18.923429) (xy 446.247278 18.846669) (xy 446.202137 18.773763)
			(xy 446.150461 18.705334) (xy 446.092692 18.641964) (xy 446.029322 18.584195) (xy 445.960893 18.532519)
			(xy 445.887987 18.487378) (xy 445.811227 18.449156) (xy 445.731268 18.41818) (xy 445.648792 18.394713)
			(xy 445.564502 18.378957) (xy 445.479119 18.371045) (xy 445.393369 18.371045) (xy 445.307986 18.378957)
			(xy 445.223696 18.394713) (xy 445.14122 18.41818) (xy 445.061261 18.449156) (xy 444.984501 18.487378)
			(xy 444.911595 18.532519) (xy 444.843166 18.584195) (xy 444.779796 18.641964) (xy 444.722027 18.705334)
			(xy 444.670351 18.773763) (xy 444.62521 18.846669) (xy 444.586988 18.923429) (xy 444.556012 19.003388)
			(xy 444.532545 19.085864) (xy 444.516789 19.170154) (xy 444.508877 19.255537) (xy 440.013611 19.255537)
			(xy 440.005699 19.170154) (xy 439.989943 19.085864) (xy 439.966476 19.003388) (xy 439.9355 18.923429)
			(xy 439.897278 18.846669) (xy 439.852137 18.773763) (xy 439.800461 18.705334) (xy 439.742692 18.641964)
			(xy 439.679322 18.584195) (xy 439.610893 18.532519) (xy 439.537987 18.487378) (xy 439.461227 18.449156)
			(xy 439.381268 18.41818) (xy 439.298792 18.394713) (xy 439.214502 18.378957) (xy 439.129119 18.371045)
			(xy 439.043369 18.371045) (xy 438.957986 18.378957) (xy 438.873696 18.394713) (xy 438.79122 18.41818)
			(xy 438.711261 18.449156) (xy 438.634501 18.487378) (xy 438.561595 18.532519) (xy 438.493166 18.584195)
			(xy 438.429796 18.641964) (xy 438.372027 18.705334) (xy 438.320351 18.773763) (xy 438.27521 18.846669)
			(xy 438.236988 18.923429) (xy 438.206012 19.003388) (xy 438.182545 19.085864) (xy 438.166789 19.170154)
			(xy 438.158877 19.255537) (xy 407.302832 19.255537) (xy 407.295579 19.177266) (xy 407.279823 19.092976)
			(xy 407.256356 19.0105) (xy 407.22538 18.930541) (xy 407.187158 18.853781) (xy 407.142017 18.780875)
			(xy 407.090341 18.712446) (xy 407.032572 18.649076) (xy 406.969202 18.591307) (xy 406.900773 18.539631)
			(xy 406.827867 18.49449) (xy 406.751107 18.456268) (xy 406.671148 18.425292) (xy 406.588672 18.401825)
			(xy 406.504382 18.386069) (xy 406.418999 18.378157) (xy 406.333249 18.378157) (xy 406.247866 18.386069)
			(xy 406.163576 18.401825) (xy 406.0811 18.425292) (xy 406.001141 18.456268) (xy 405.924381 18.49449)
			(xy 405.851475 18.539631) (xy 405.783046 18.591307) (xy 405.719676 18.649076) (xy 405.661907 18.712446)
			(xy 405.610231 18.780875) (xy 405.56509 18.853781) (xy 405.526868 18.930541) (xy 405.495892 19.0105)
			(xy 405.472425 19.092976) (xy 405.456669 19.177266) (xy 405.448757 19.262649) (xy 400.953491 19.262649)
			(xy 400.945579 19.177266) (xy 400.929823 19.092976) (xy 400.906356 19.0105) (xy 400.87538 18.930541)
			(xy 400.837158 18.853781) (xy 400.792017 18.780875) (xy 400.740341 18.712446) (xy 400.682572 18.649076)
			(xy 400.619202 18.591307) (xy 400.550773 18.539631) (xy 400.477867 18.49449) (xy 400.401107 18.456268)
			(xy 400.321148 18.425292) (xy 400.238672 18.401825) (xy 400.154382 18.386069) (xy 400.068999 18.378157)
			(xy 399.983249 18.378157) (xy 399.897866 18.386069) (xy 399.813576 18.401825) (xy 399.7311 18.425292)
			(xy 399.651141 18.456268) (xy 399.574381 18.49449) (xy 399.501475 18.539631) (xy 399.433046 18.591307)
			(xy 399.369676 18.649076) (xy 399.311907 18.712446) (xy 399.260231 18.780875) (xy 399.21509 18.853781)
			(xy 399.176868 18.930541) (xy 399.145892 19.0105) (xy 399.122425 19.092976) (xy 399.106669 19.177266)
			(xy 399.098757 19.262649) (xy 381.720693 19.262649) (xy 381.720611 19.255537) (xy 381.712699 19.170154)
			(xy 381.696943 19.085864) (xy 381.673476 19.003388) (xy 381.6425 18.923429) (xy 381.604278 18.846669)
			(xy 381.559137 18.773763) (xy 381.507461 18.705334) (xy 381.449692 18.641964) (xy 381.386322 18.584195)
			(xy 381.317893 18.532519) (xy 381.244987 18.487378) (xy 381.168227 18.449156) (xy 381.088268 18.41818)
			(xy 381.005792 18.394713) (xy 380.921502 18.378957) (xy 380.836119 18.371045) (xy 380.750369 18.371045)
			(xy 380.664986 18.378957) (xy 380.580696 18.394713) (xy 380.49822 18.41818) (xy 380.418261 18.449156)
			(xy 380.341501 18.487378) (xy 380.268595 18.532519) (xy 380.200166 18.584195) (xy 380.136796 18.641964)
			(xy 380.079027 18.705334) (xy 380.027351 18.773763) (xy 379.98221 18.846669) (xy 379.943988 18.923429)
			(xy 379.913012 19.003388) (xy 379.889545 19.085864) (xy 379.873789 19.170154) (xy 379.865877 19.255537)
			(xy 375.370611 19.255537) (xy 375.362699 19.170154) (xy 375.346943 19.085864) (xy 375.323476 19.003388)
			(xy 375.2925 18.923429) (xy 375.254278 18.846669) (xy 375.209137 18.773763) (xy 375.157461 18.705334)
			(xy 375.099692 18.641964) (xy 375.036322 18.584195) (xy 374.967893 18.532519) (xy 374.894987 18.487378)
			(xy 374.818227 18.449156) (xy 374.738268 18.41818) (xy 374.655792 18.394713) (xy 374.571502 18.378957)
			(xy 374.486119 18.371045) (xy 374.400369 18.371045) (xy 374.314986 18.378957) (xy 374.230696 18.394713)
			(xy 374.14822 18.41818) (xy 374.068261 18.449156) (xy 373.991501 18.487378) (xy 373.918595 18.532519)
			(xy 373.850166 18.584195) (xy 373.786796 18.641964) (xy 373.729027 18.705334) (xy 373.677351 18.773763)
			(xy 373.63221 18.846669) (xy 373.593988 18.923429) (xy 373.563012 19.003388) (xy 373.539545 19.085864)
			(xy 373.523789 19.170154) (xy 373.515877 19.255537) (xy 342.659832 19.255537) (xy 342.652579 19.177266)
			(xy 342.636823 19.092976) (xy 342.613356 19.0105) (xy 342.58238 18.930541) (xy 342.544158 18.853781)
			(xy 342.499017 18.780875) (xy 342.447341 18.712446) (xy 342.389572 18.649076) (xy 342.326202 18.591307)
			(xy 342.257773 18.539631) (xy 342.184867 18.49449) (xy 342.108107 18.456268) (xy 342.028148 18.425292)
			(xy 341.945672 18.401825) (xy 341.861382 18.386069) (xy 341.775999 18.378157) (xy 341.690249 18.378157)
			(xy 341.604866 18.386069) (xy 341.520576 18.401825) (xy 341.4381 18.425292) (xy 341.358141 18.456268)
			(xy 341.281381 18.49449) (xy 341.208475 18.539631) (xy 341.140046 18.591307) (xy 341.076676 18.649076)
			(xy 341.018907 18.712446) (xy 340.967231 18.780875) (xy 340.92209 18.853781) (xy 340.883868 18.930541)
			(xy 340.852892 19.0105) (xy 340.829425 19.092976) (xy 340.813669 19.177266) (xy 340.805757 19.262649)
			(xy 336.310491 19.262649) (xy 336.302579 19.177266) (xy 336.286823 19.092976) (xy 336.263356 19.0105)
			(xy 336.23238 18.930541) (xy 336.194158 18.853781) (xy 336.149017 18.780875) (xy 336.097341 18.712446)
			(xy 336.039572 18.649076) (xy 335.976202 18.591307) (xy 335.907773 18.539631) (xy 335.834867 18.49449)
			(xy 335.758107 18.456268) (xy 335.678148 18.425292) (xy 335.595672 18.401825) (xy 335.511382 18.386069)
			(xy 335.425999 18.378157) (xy 335.340249 18.378157) (xy 335.254866 18.386069) (xy 335.170576 18.401825)
			(xy 335.0881 18.425292) (xy 335.008141 18.456268) (xy 334.931381 18.49449) (xy 334.858475 18.539631)
			(xy 334.790046 18.591307) (xy 334.726676 18.649076) (xy 334.668907 18.712446) (xy 334.617231 18.780875)
			(xy 334.57209 18.853781) (xy 334.533868 18.930541) (xy 334.502892 19.0105) (xy 334.479425 19.092976)
			(xy 334.463669 19.177266) (xy 334.455757 19.262649) (xy 316.569693 19.262649) (xy 316.569611 19.255537)
			(xy 316.561699 19.170154) (xy 316.545943 19.085864) (xy 316.522476 19.003388) (xy 316.4915 18.923429)
			(xy 316.453278 18.846669) (xy 316.408137 18.773763) (xy 316.356461 18.705334) (xy 316.298692 18.641964)
			(xy 316.235322 18.584195) (xy 316.166893 18.532519) (xy 316.093987 18.487378) (xy 316.017227 18.449156)
			(xy 315.937268 18.41818) (xy 315.854792 18.394713) (xy 315.770502 18.378957) (xy 315.685119 18.371045)
			(xy 315.599369 18.371045) (xy 315.513986 18.378957) (xy 315.429696 18.394713) (xy 315.34722 18.41818)
			(xy 315.267261 18.449156) (xy 315.190501 18.487378) (xy 315.117595 18.532519) (xy 315.049166 18.584195)
			(xy 314.985796 18.641964) (xy 314.928027 18.705334) (xy 314.876351 18.773763) (xy 314.83121 18.846669)
			(xy 314.792988 18.923429) (xy 314.762012 19.003388) (xy 314.738545 19.085864) (xy 314.722789 19.170154)
			(xy 314.714877 19.255537) (xy 310.219611 19.255537) (xy 310.211699 19.170154) (xy 310.195943 19.085864)
			(xy 310.172476 19.003388) (xy 310.1415 18.923429) (xy 310.103278 18.846669) (xy 310.058137 18.773763)
			(xy 310.006461 18.705334) (xy 309.948692 18.641964) (xy 309.885322 18.584195) (xy 309.816893 18.532519)
			(xy 309.743987 18.487378) (xy 309.667227 18.449156) (xy 309.587268 18.41818) (xy 309.504792 18.394713)
			(xy 309.420502 18.378957) (xy 309.335119 18.371045) (xy 309.249369 18.371045) (xy 309.163986 18.378957)
			(xy 309.079696 18.394713) (xy 308.99722 18.41818) (xy 308.917261 18.449156) (xy 308.840501 18.487378)
			(xy 308.767595 18.532519) (xy 308.699166 18.584195) (xy 308.635796 18.641964) (xy 308.578027 18.705334)
			(xy 308.526351 18.773763) (xy 308.48121 18.846669) (xy 308.442988 18.923429) (xy 308.412012 19.003388)
			(xy 308.388545 19.085864) (xy 308.372789 19.170154) (xy 308.364877 19.255537) (xy 277.508832 19.255537)
			(xy 277.501579 19.177266) (xy 277.485823 19.092976) (xy 277.462356 19.0105) (xy 277.43138 18.930541)
			(xy 277.393158 18.853781) (xy 277.348017 18.780875) (xy 277.296341 18.712446) (xy 277.238572 18.649076)
			(xy 277.175202 18.591307) (xy 277.106773 18.539631) (xy 277.033867 18.49449) (xy 276.957107 18.456268)
			(xy 276.877148 18.425292) (xy 276.794672 18.401825) (xy 276.710382 18.386069) (xy 276.624999 18.378157)
			(xy 276.539249 18.378157) (xy 276.453866 18.386069) (xy 276.369576 18.401825) (xy 276.2871 18.425292)
			(xy 276.207141 18.456268) (xy 276.130381 18.49449) (xy 276.057475 18.539631) (xy 275.989046 18.591307)
			(xy 275.925676 18.649076) (xy 275.867907 18.712446) (xy 275.816231 18.780875) (xy 275.77109 18.853781)
			(xy 275.732868 18.930541) (xy 275.701892 19.0105) (xy 275.678425 19.092976) (xy 275.662669 19.177266)
			(xy 275.654757 19.262649) (xy 271.159491 19.262649) (xy 271.151579 19.177266) (xy 271.135823 19.092976)
			(xy 271.112356 19.0105) (xy 271.08138 18.930541) (xy 271.043158 18.853781) (xy 270.998017 18.780875)
			(xy 270.946341 18.712446) (xy 270.888572 18.649076) (xy 270.825202 18.591307) (xy 270.756773 18.539631)
			(xy 270.683867 18.49449) (xy 270.607107 18.456268) (xy 270.527148 18.425292) (xy 270.444672 18.401825)
			(xy 270.360382 18.386069) (xy 270.274999 18.378157) (xy 270.189249 18.378157) (xy 270.103866 18.386069)
			(xy 270.019576 18.401825) (xy 269.9371 18.425292) (xy 269.857141 18.456268) (xy 269.780381 18.49449)
			(xy 269.707475 18.539631) (xy 269.639046 18.591307) (xy 269.575676 18.649076) (xy 269.517907 18.712446)
			(xy 269.466231 18.780875) (xy 269.42109 18.853781) (xy 269.382868 18.930541) (xy 269.351892 19.0105)
			(xy 269.328425 19.092976) (xy 269.312669 19.177266) (xy 269.304757 19.262649) (xy 252.231493 19.262649)
			(xy 252.231411 19.255537) (xy 252.223499 19.170154) (xy 252.207743 19.085864) (xy 252.184276 19.003388)
			(xy 252.1533 18.923429) (xy 252.115078 18.846669) (xy 252.069937 18.773763) (xy 252.018261 18.705334)
			(xy 251.960492 18.641964) (xy 251.897122 18.584195) (xy 251.828693 18.532519) (xy 251.755787 18.487378)
			(xy 251.679027 18.449156) (xy 251.599068 18.41818) (xy 251.516592 18.394713) (xy 251.432302 18.378957)
			(xy 251.346919 18.371045) (xy 251.261169 18.371045) (xy 251.175786 18.378957) (xy 251.091496 18.394713)
			(xy 251.00902 18.41818) (xy 250.929061 18.449156) (xy 250.852301 18.487378) (xy 250.779395 18.532519)
			(xy 250.710966 18.584195) (xy 250.647596 18.641964) (xy 250.589827 18.705334) (xy 250.538151 18.773763)
			(xy 250.49301 18.846669) (xy 250.454788 18.923429) (xy 250.423812 19.003388) (xy 250.400345 19.085864)
			(xy 250.384589 19.170154) (xy 250.376677 19.255537) (xy 245.881411 19.255537) (xy 245.873499 19.170154)
			(xy 245.857743 19.085864) (xy 245.834276 19.003388) (xy 245.8033 18.923429) (xy 245.765078 18.846669)
			(xy 245.719937 18.773763) (xy 245.668261 18.705334) (xy 245.610492 18.641964) (xy 245.547122 18.584195)
			(xy 245.478693 18.532519) (xy 245.405787 18.487378) (xy 245.329027 18.449156) (xy 245.249068 18.41818)
			(xy 245.166592 18.394713) (xy 245.082302 18.378957) (xy 244.996919 18.371045) (xy 244.911169 18.371045)
			(xy 244.825786 18.378957) (xy 244.741496 18.394713) (xy 244.65902 18.41818) (xy 244.579061 18.449156)
			(xy 244.502301 18.487378) (xy 244.429395 18.532519) (xy 244.360966 18.584195) (xy 244.297596 18.641964)
			(xy 244.239827 18.705334) (xy 244.188151 18.773763) (xy 244.14301 18.846669) (xy 244.104788 18.923429)
			(xy 244.073812 19.003388) (xy 244.050345 19.085864) (xy 244.034589 19.170154) (xy 244.026677 19.255537)
			(xy 218.199832 19.255537) (xy 218.192579 19.177266) (xy 218.176823 19.092976) (xy 218.153356 19.0105)
			(xy 218.12238 18.930541) (xy 218.084158 18.853781) (xy 218.039017 18.780875) (xy 217.987341 18.712446)
			(xy 217.929572 18.649076) (xy 217.866202 18.591307) (xy 217.797773 18.539631) (xy 217.724867 18.49449)
			(xy 217.648107 18.456268) (xy 217.568148 18.425292) (xy 217.485672 18.401825) (xy 217.401382 18.386069)
			(xy 217.315999 18.378157) (xy 217.230249 18.378157) (xy 217.144866 18.386069) (xy 217.060576 18.401825)
			(xy 216.9781 18.425292) (xy 216.898141 18.456268) (xy 216.821381 18.49449) (xy 216.748475 18.539631)
			(xy 216.680046 18.591307) (xy 216.616676 18.649076) (xy 216.558907 18.712446) (xy 216.507231 18.780875)
			(xy 216.46209 18.853781) (xy 216.423868 18.930541) (xy 216.392892 19.0105) (xy 216.369425 19.092976)
			(xy 216.353669 19.177266) (xy 216.345757 19.262649) (xy 211.850491 19.262649) (xy 211.842579 19.177266)
			(xy 211.826823 19.092976) (xy 211.803356 19.0105) (xy 211.77238 18.930541) (xy 211.734158 18.853781)
			(xy 211.689017 18.780875) (xy 211.637341 18.712446) (xy 211.579572 18.649076) (xy 211.516202 18.591307)
			(xy 211.447773 18.539631) (xy 211.374867 18.49449) (xy 211.298107 18.456268) (xy 211.218148 18.425292)
			(xy 211.135672 18.401825) (xy 211.051382 18.386069) (xy 210.965999 18.378157) (xy 210.880249 18.378157)
			(xy 210.794866 18.386069) (xy 210.710576 18.401825) (xy 210.6281 18.425292) (xy 210.548141 18.456268)
			(xy 210.471381 18.49449) (xy 210.398475 18.539631) (xy 210.330046 18.591307) (xy 210.266676 18.649076)
			(xy 210.208907 18.712446) (xy 210.157231 18.780875) (xy 210.11209 18.853781) (xy 210.073868 18.930541)
			(xy 210.042892 19.0105) (xy 210.019425 19.092976) (xy 210.003669 19.177266) (xy 209.995757 19.262649)
			(xy 158.621984 19.262649) (xy 158.621984 16.722649) (xy 209.995757 16.722649) (xy 209.995757 16.808399)
			(xy 210.003669 16.893782) (xy 210.019425 16.978072) (xy 210.042892 17.060548) (xy 210.073868 17.140507)
			(xy 210.11209 17.217267) (xy 210.157231 17.290173) (xy 210.208907 17.358602) (xy 210.266676 17.421972)
			(xy 210.330046 17.479741) (xy 210.398475 17.531417) (xy 210.471381 17.576558) (xy 210.548141 17.61478)
			(xy 210.6281 17.645756) (xy 210.710576 17.669223) (xy 210.794866 17.684979) (xy 210.880249 17.692891)
			(xy 210.965999 17.692891) (xy 211.051382 17.684979) (xy 211.135672 17.669223) (xy 211.218148 17.645756)
			(xy 211.298107 17.61478) (xy 211.374867 17.576558) (xy 211.447773 17.531417) (xy 211.516202 17.479741)
			(xy 211.579572 17.421972) (xy 211.637341 17.358602) (xy 211.689017 17.290173) (xy 211.734158 17.217267)
			(xy 211.77238 17.140507) (xy 211.803356 17.060548) (xy 211.826823 16.978072) (xy 211.842579 16.893782)
			(xy 211.850491 16.808399) (xy 211.850986 16.765524) (xy 211.850491 16.722649) (xy 216.345757 16.722649)
			(xy 216.345757 16.808399) (xy 216.353669 16.893782) (xy 216.369425 16.978072) (xy 216.392892 17.060548)
			(xy 216.423868 17.140507) (xy 216.46209 17.217267) (xy 216.507231 17.290173) (xy 216.558907 17.358602)
			(xy 216.616676 17.421972) (xy 216.680046 17.479741) (xy 216.748475 17.531417) (xy 216.821381 17.576558)
			(xy 216.898141 17.61478) (xy 216.9781 17.645756) (xy 217.060576 17.669223) (xy 217.144866 17.684979)
			(xy 217.230249 17.692891) (xy 217.315999 17.692891) (xy 217.401382 17.684979) (xy 217.485672 17.669223)
			(xy 217.568148 17.645756) (xy 217.648107 17.61478) (xy 217.724867 17.576558) (xy 217.797773 17.531417)
			(xy 217.866202 17.479741) (xy 217.929572 17.421972) (xy 217.987341 17.358602) (xy 218.039017 17.290173)
			(xy 218.084158 17.217267) (xy 218.12238 17.140507) (xy 218.153356 17.060548) (xy 218.176823 16.978072)
			(xy 218.192579 16.893782) (xy 218.200491 16.808399) (xy 218.200986 16.765524) (xy 218.200491 16.722649)
			(xy 218.199832 16.715537) (xy 244.026677 16.715537) (xy 244.026677 16.801287) (xy 244.034589 16.88667)
			(xy 244.050345 16.97096) (xy 244.073812 17.053436) (xy 244.104788 17.133395) (xy 244.14301 17.210155)
			(xy 244.188151 17.283061) (xy 244.239827 17.35149) (xy 244.297596 17.41486) (xy 244.360966 17.472629)
			(xy 244.429395 17.524305) (xy 244.502301 17.569446) (xy 244.579061 17.607668) (xy 244.65902 17.638644)
			(xy 244.741496 17.662111) (xy 244.825786 17.677867) (xy 244.911169 17.685779) (xy 244.996919 17.685779)
			(xy 245.082302 17.677867) (xy 245.166592 17.662111) (xy 245.249068 17.638644) (xy 245.329027 17.607668)
			(xy 245.405787 17.569446) (xy 245.478693 17.524305) (xy 245.547122 17.472629) (xy 245.610492 17.41486)
			(xy 245.668261 17.35149) (xy 245.719937 17.283061) (xy 245.765078 17.210155) (xy 245.8033 17.133395)
			(xy 245.834276 17.053436) (xy 245.857743 16.97096) (xy 245.873499 16.88667) (xy 245.881411 16.801287)
			(xy 245.881906 16.758412) (xy 245.881411 16.715537) (xy 250.376677 16.715537) (xy 250.376677 16.801287)
			(xy 250.384589 16.88667) (xy 250.400345 16.97096) (xy 250.423812 17.053436) (xy 250.454788 17.133395)
			(xy 250.49301 17.210155) (xy 250.538151 17.283061) (xy 250.589827 17.35149) (xy 250.647596 17.41486)
			(xy 250.710966 17.472629) (xy 250.779395 17.524305) (xy 250.852301 17.569446) (xy 250.929061 17.607668)
			(xy 251.00902 17.638644) (xy 251.091496 17.662111) (xy 251.175786 17.677867) (xy 251.261169 17.685779)
			(xy 251.346919 17.685779) (xy 251.432302 17.677867) (xy 251.516592 17.662111) (xy 251.599068 17.638644)
			(xy 251.679027 17.607668) (xy 251.755787 17.569446) (xy 251.828693 17.524305) (xy 251.897122 17.472629)
			(xy 251.960492 17.41486) (xy 252.018261 17.35149) (xy 252.069937 17.283061) (xy 252.115078 17.210155)
			(xy 252.1533 17.133395) (xy 252.184276 17.053436) (xy 252.207743 16.97096) (xy 252.223499 16.88667)
			(xy 252.231411 16.801287) (xy 252.231906 16.758412) (xy 252.231493 16.722649) (xy 269.304757 16.722649)
			(xy 269.304757 16.808399) (xy 269.312669 16.893782) (xy 269.328425 16.978072) (xy 269.351892 17.060548)
			(xy 269.382868 17.140507) (xy 269.42109 17.217267) (xy 269.466231 17.290173) (xy 269.517907 17.358602)
			(xy 269.575676 17.421972) (xy 269.639046 17.479741) (xy 269.707475 17.531417) (xy 269.780381 17.576558)
			(xy 269.857141 17.61478) (xy 269.9371 17.645756) (xy 270.019576 17.669223) (xy 270.103866 17.684979)
			(xy 270.189249 17.692891) (xy 270.274999 17.692891) (xy 270.360382 17.684979) (xy 270.444672 17.669223)
			(xy 270.527148 17.645756) (xy 270.607107 17.61478) (xy 270.62931 17.603724) (xy 274.239736 17.603724)
			(xy 274.239736 18.467324) (xy 274.240222 18.494593) (xy 274.247984 18.548577) (xy 274.263349 18.600907)
			(xy 274.286006 18.650517) (xy 274.315492 18.696398) (xy 274.351207 18.737615) (xy 274.392424 18.77333)
			(xy 274.438305 18.802816) (xy 274.487915 18.825473) (xy 274.540245 18.840838) (xy 274.594229 18.8486)
			(xy 274.648767 18.8486) (xy 274.702751 18.840838) (xy 274.755081 18.825473) (xy 274.804691 18.802816)
			(xy 274.850572 18.77333) (xy 274.891789 18.737615) (xy 274.927504 18.696398) (xy 274.95699 18.650517)
			(xy 274.979647 18.600907) (xy 274.995012 18.548577) (xy 275.002774 18.494593) (xy 275.00326 18.467324)
			(xy 275.00326 17.603724) (xy 275.002774 17.576455) (xy 274.995012 17.522471) (xy 274.979647 17.470141)
			(xy 274.95699 17.420531) (xy 274.927504 17.37465) (xy 274.891789 17.333433) (xy 274.850572 17.297718)
			(xy 274.804691 17.268232) (xy 274.755081 17.245575) (xy 274.702751 17.23021) (xy 274.648767 17.222448)
			(xy 274.594229 17.222448) (xy 274.540245 17.23021) (xy 274.487915 17.245575) (xy 274.438305 17.268232)
			(xy 274.392424 17.297718) (xy 274.351207 17.333433) (xy 274.315492 17.37465) (xy 274.286006 17.420531)
			(xy 274.263349 17.470141) (xy 274.247984 17.522471) (xy 274.240222 17.576455) (xy 274.239736 17.603724)
			(xy 270.62931 17.603724) (xy 270.683867 17.576558) (xy 270.756773 17.531417) (xy 270.825202 17.479741)
			(xy 270.888572 17.421972) (xy 270.946341 17.358602) (xy 270.998017 17.290173) (xy 271.043158 17.217267)
			(xy 271.08138 17.140507) (xy 271.112356 17.060548) (xy 271.135823 16.978072) (xy 271.151579 16.893782)
			(xy 271.159491 16.808399) (xy 271.159986 16.765524) (xy 271.159491 16.722649) (xy 275.654757 16.722649)
			(xy 275.654757 16.808399) (xy 275.662669 16.893782) (xy 275.678425 16.978072) (xy 275.701892 17.060548)
			(xy 275.732868 17.140507) (xy 275.77109 17.217267) (xy 275.816231 17.290173) (xy 275.867907 17.358602)
			(xy 275.925676 17.421972) (xy 275.989046 17.479741) (xy 276.057475 17.531417) (xy 276.130381 17.576558)
			(xy 276.207141 17.61478) (xy 276.2871 17.645756) (xy 276.369576 17.669223) (xy 276.453866 17.684979)
			(xy 276.539249 17.692891) (xy 276.624999 17.692891) (xy 276.710382 17.684979) (xy 276.794672 17.669223)
			(xy 276.877148 17.645756) (xy 276.957107 17.61478) (xy 277.033867 17.576558) (xy 277.106773 17.531417)
			(xy 277.175202 17.479741) (xy 277.238572 17.421972) (xy 277.296341 17.358602) (xy 277.348017 17.290173)
			(xy 277.393158 17.217267) (xy 277.43138 17.140507) (xy 277.462356 17.060548) (xy 277.485823 16.978072)
			(xy 277.501579 16.893782) (xy 277.509491 16.808399) (xy 277.509986 16.765524) (xy 277.509491 16.722649)
			(xy 277.508832 16.715537) (xy 308.364877 16.715537) (xy 308.364877 16.801287) (xy 308.372789 16.88667)
			(xy 308.388545 16.97096) (xy 308.412012 17.053436) (xy 308.442988 17.133395) (xy 308.48121 17.210155)
			(xy 308.526351 17.283061) (xy 308.578027 17.35149) (xy 308.635796 17.41486) (xy 308.699166 17.472629)
			(xy 308.767595 17.524305) (xy 308.840501 17.569446) (xy 308.917261 17.607668) (xy 308.99722 17.638644)
			(xy 309.079696 17.662111) (xy 309.163986 17.677867) (xy 309.249369 17.685779) (xy 309.335119 17.685779)
			(xy 309.420502 17.677867) (xy 309.504792 17.662111) (xy 309.587268 17.638644) (xy 309.667227 17.607668)
			(xy 309.68943 17.596612) (xy 310.871108 17.596612) (xy 310.871108 18.460212) (xy 310.871594 18.487481)
			(xy 310.879356 18.541465) (xy 310.894721 18.593795) (xy 310.917378 18.643405) (xy 310.946864 18.689286)
			(xy 310.982579 18.730503) (xy 311.023796 18.766218) (xy 311.069677 18.795704) (xy 311.119287 18.818361)
			(xy 311.171617 18.833726) (xy 311.225601 18.841488) (xy 311.280139 18.841488) (xy 311.334123 18.833726)
			(xy 311.386453 18.818361) (xy 311.436063 18.795704) (xy 311.481944 18.766218) (xy 311.523161 18.730503)
			(xy 311.558876 18.689286) (xy 311.588362 18.643405) (xy 311.611019 18.593795) (xy 311.626384 18.541465)
			(xy 311.634146 18.487481) (xy 311.634632 18.460212) (xy 311.634632 17.596612) (xy 311.634146 17.569343)
			(xy 311.626384 17.515359) (xy 311.611019 17.463029) (xy 311.588362 17.413419) (xy 311.558876 17.367538)
			(xy 311.523161 17.326321) (xy 311.481944 17.290606) (xy 311.436063 17.26112) (xy 311.386453 17.238463)
			(xy 311.334123 17.223098) (xy 311.280139 17.215336) (xy 311.225601 17.215336) (xy 311.171617 17.223098)
			(xy 311.119287 17.238463) (xy 311.069677 17.26112) (xy 311.023796 17.290606) (xy 310.982579 17.326321)
			(xy 310.946864 17.367538) (xy 310.917378 17.413419) (xy 310.894721 17.463029) (xy 310.879356 17.515359)
			(xy 310.871594 17.569343) (xy 310.871108 17.596612) (xy 309.68943 17.596612) (xy 309.743987 17.569446)
			(xy 309.816893 17.524305) (xy 309.885322 17.472629) (xy 309.948692 17.41486) (xy 310.006461 17.35149)
			(xy 310.058137 17.283061) (xy 310.103278 17.210155) (xy 310.1415 17.133395) (xy 310.172476 17.053436)
			(xy 310.195943 16.97096) (xy 310.211699 16.88667) (xy 310.219611 16.801287) (xy 310.220106 16.758412)
			(xy 310.219611 16.715537) (xy 314.714877 16.715537) (xy 314.714877 16.801287) (xy 314.722789 16.88667)
			(xy 314.738545 16.97096) (xy 314.762012 17.053436) (xy 314.792988 17.133395) (xy 314.83121 17.210155)
			(xy 314.876351 17.283061) (xy 314.928027 17.35149) (xy 314.985796 17.41486) (xy 315.049166 17.472629)
			(xy 315.117595 17.524305) (xy 315.190501 17.569446) (xy 315.267261 17.607668) (xy 315.34722 17.638644)
			(xy 315.429696 17.662111) (xy 315.513986 17.677867) (xy 315.599369 17.685779) (xy 315.685119 17.685779)
			(xy 315.770502 17.677867) (xy 315.854792 17.662111) (xy 315.937268 17.638644) (xy 316.017227 17.607668)
			(xy 316.093987 17.569446) (xy 316.166893 17.524305) (xy 316.235322 17.472629) (xy 316.298692 17.41486)
			(xy 316.356461 17.35149) (xy 316.408137 17.283061) (xy 316.453278 17.210155) (xy 316.4915 17.133395)
			(xy 316.522476 17.053436) (xy 316.545943 16.97096) (xy 316.561699 16.88667) (xy 316.569611 16.801287)
			(xy 316.570106 16.758412) (xy 316.569693 16.722649) (xy 334.455757 16.722649) (xy 334.455757 16.808399)
			(xy 334.463669 16.893782) (xy 334.479425 16.978072) (xy 334.502892 17.060548) (xy 334.533868 17.140507)
			(xy 334.57209 17.217267) (xy 334.617231 17.290173) (xy 334.668907 17.358602) (xy 334.726676 17.421972)
			(xy 334.790046 17.479741) (xy 334.858475 17.531417) (xy 334.931381 17.576558) (xy 335.008141 17.61478)
			(xy 335.0881 17.645756) (xy 335.170576 17.669223) (xy 335.254866 17.684979) (xy 335.340249 17.692891)
			(xy 335.425999 17.692891) (xy 335.511382 17.684979) (xy 335.595672 17.669223) (xy 335.678148 17.645756)
			(xy 335.758107 17.61478) (xy 335.78031 17.603724) (xy 339.390736 17.603724) (xy 339.390736 18.467324)
			(xy 339.391222 18.494593) (xy 339.398984 18.548577) (xy 339.414349 18.600907) (xy 339.437006 18.650517)
			(xy 339.466492 18.696398) (xy 339.502207 18.737615) (xy 339.543424 18.77333) (xy 339.589305 18.802816)
			(xy 339.638915 18.825473) (xy 339.691245 18.840838) (xy 339.745229 18.8486) (xy 339.799767 18.8486)
			(xy 339.853751 18.840838) (xy 339.906081 18.825473) (xy 339.955691 18.802816) (xy 340.001572 18.77333)
			(xy 340.042789 18.737615) (xy 340.078504 18.696398) (xy 340.10799 18.650517) (xy 340.130647 18.600907)
			(xy 340.146012 18.548577) (xy 340.153774 18.494593) (xy 340.15426 18.467324) (xy 340.15426 17.603724)
			(xy 340.153774 17.576455) (xy 340.146012 17.522471) (xy 340.130647 17.470141) (xy 340.10799 17.420531)
			(xy 340.078504 17.37465) (xy 340.042789 17.333433) (xy 340.001572 17.297718) (xy 339.955691 17.268232)
			(xy 339.906081 17.245575) (xy 339.853751 17.23021) (xy 339.799767 17.222448) (xy 339.745229 17.222448)
			(xy 339.691245 17.23021) (xy 339.638915 17.245575) (xy 339.589305 17.268232) (xy 339.543424 17.297718)
			(xy 339.502207 17.333433) (xy 339.466492 17.37465) (xy 339.437006 17.420531) (xy 339.414349 17.470141)
			(xy 339.398984 17.522471) (xy 339.391222 17.576455) (xy 339.390736 17.603724) (xy 335.78031 17.603724)
			(xy 335.834867 17.576558) (xy 335.907773 17.531417) (xy 335.976202 17.479741) (xy 336.039572 17.421972)
			(xy 336.097341 17.358602) (xy 336.149017 17.290173) (xy 336.194158 17.217267) (xy 336.23238 17.140507)
			(xy 336.263356 17.060548) (xy 336.286823 16.978072) (xy 336.302579 16.893782) (xy 336.310491 16.808399)
			(xy 336.310986 16.765524) (xy 336.310491 16.722649) (xy 340.805757 16.722649) (xy 340.805757 16.808399)
			(xy 340.813669 16.893782) (xy 340.829425 16.978072) (xy 340.852892 17.060548) (xy 340.883868 17.140507)
			(xy 340.92209 17.217267) (xy 340.967231 17.290173) (xy 341.018907 17.358602) (xy 341.076676 17.421972)
			(xy 341.140046 17.479741) (xy 341.208475 17.531417) (xy 341.281381 17.576558) (xy 341.358141 17.61478)
			(xy 341.4381 17.645756) (xy 341.520576 17.669223) (xy 341.604866 17.684979) (xy 341.690249 17.692891)
			(xy 341.775999 17.692891) (xy 341.861382 17.684979) (xy 341.945672 17.669223) (xy 342.028148 17.645756)
			(xy 342.108107 17.61478) (xy 342.184867 17.576558) (xy 342.257773 17.531417) (xy 342.326202 17.479741)
			(xy 342.389572 17.421972) (xy 342.447341 17.358602) (xy 342.499017 17.290173) (xy 342.544158 17.217267)
			(xy 342.58238 17.140507) (xy 342.613356 17.060548) (xy 342.636823 16.978072) (xy 342.652579 16.893782)
			(xy 342.660491 16.808399) (xy 342.660986 16.765524) (xy 342.660491 16.722649) (xy 342.659832 16.715537)
			(xy 373.515877 16.715537) (xy 373.515877 16.801287) (xy 373.523789 16.88667) (xy 373.539545 16.97096)
			(xy 373.563012 17.053436) (xy 373.593988 17.133395) (xy 373.63221 17.210155) (xy 373.677351 17.283061)
			(xy 373.729027 17.35149) (xy 373.786796 17.41486) (xy 373.850166 17.472629) (xy 373.918595 17.524305)
			(xy 373.991501 17.569446) (xy 374.068261 17.607668) (xy 374.14822 17.638644) (xy 374.230696 17.662111)
			(xy 374.314986 17.677867) (xy 374.400369 17.685779) (xy 374.486119 17.685779) (xy 374.571502 17.677867)
			(xy 374.655792 17.662111) (xy 374.738268 17.638644) (xy 374.818227 17.607668) (xy 374.84043 17.596612)
			(xy 376.022108 17.596612) (xy 376.022108 18.460212) (xy 376.022594 18.487481) (xy 376.030356 18.541465)
			(xy 376.045721 18.593795) (xy 376.068378 18.643405) (xy 376.097864 18.689286) (xy 376.133579 18.730503)
			(xy 376.174796 18.766218) (xy 376.220677 18.795704) (xy 376.270287 18.818361) (xy 376.322617 18.833726)
			(xy 376.376601 18.841488) (xy 376.431139 18.841488) (xy 376.485123 18.833726) (xy 376.537453 18.818361)
			(xy 376.587063 18.795704) (xy 376.632944 18.766218) (xy 376.674161 18.730503) (xy 376.709876 18.689286)
			(xy 376.739362 18.643405) (xy 376.762019 18.593795) (xy 376.777384 18.541465) (xy 376.785146 18.487481)
			(xy 376.785632 18.460212) (xy 376.785632 17.596612) (xy 376.785146 17.569343) (xy 376.777384 17.515359)
			(xy 376.762019 17.463029) (xy 376.739362 17.413419) (xy 376.709876 17.367538) (xy 376.674161 17.326321)
			(xy 376.632944 17.290606) (xy 376.587063 17.26112) (xy 376.537453 17.238463) (xy 376.485123 17.223098)
			(xy 376.431139 17.215336) (xy 376.376601 17.215336) (xy 376.322617 17.223098) (xy 376.270287 17.238463)
			(xy 376.220677 17.26112) (xy 376.174796 17.290606) (xy 376.133579 17.326321) (xy 376.097864 17.367538)
			(xy 376.068378 17.413419) (xy 376.045721 17.463029) (xy 376.030356 17.515359) (xy 376.022594 17.569343)
			(xy 376.022108 17.596612) (xy 374.84043 17.596612) (xy 374.894987 17.569446) (xy 374.967893 17.524305)
			(xy 375.036322 17.472629) (xy 375.099692 17.41486) (xy 375.157461 17.35149) (xy 375.209137 17.283061)
			(xy 375.254278 17.210155) (xy 375.2925 17.133395) (xy 375.323476 17.053436) (xy 375.346943 16.97096)
			(xy 375.362699 16.88667) (xy 375.370611 16.801287) (xy 375.371106 16.758412) (xy 375.370611 16.715537)
			(xy 379.865877 16.715537) (xy 379.865877 16.801287) (xy 379.873789 16.88667) (xy 379.889545 16.97096)
			(xy 379.913012 17.053436) (xy 379.943988 17.133395) (xy 379.98221 17.210155) (xy 380.027351 17.283061)
			(xy 380.079027 17.35149) (xy 380.136796 17.41486) (xy 380.200166 17.472629) (xy 380.268595 17.524305)
			(xy 380.341501 17.569446) (xy 380.418261 17.607668) (xy 380.49822 17.638644) (xy 380.580696 17.662111)
			(xy 380.664986 17.677867) (xy 380.750369 17.685779) (xy 380.836119 17.685779) (xy 380.921502 17.677867)
			(xy 381.005792 17.662111) (xy 381.088268 17.638644) (xy 381.168227 17.607668) (xy 381.244987 17.569446)
			(xy 381.317893 17.524305) (xy 381.386322 17.472629) (xy 381.449692 17.41486) (xy 381.507461 17.35149)
			(xy 381.559137 17.283061) (xy 381.604278 17.210155) (xy 381.6425 17.133395) (xy 381.673476 17.053436)
			(xy 381.696943 16.97096) (xy 381.712699 16.88667) (xy 381.720611 16.801287) (xy 381.721106 16.758412)
			(xy 381.720693 16.722649) (xy 399.098757 16.722649) (xy 399.098757 16.808399) (xy 399.106669 16.893782)
			(xy 399.122425 16.978072) (xy 399.145892 17.060548) (xy 399.176868 17.140507) (xy 399.21509 17.217267)
			(xy 399.260231 17.290173) (xy 399.311907 17.358602) (xy 399.369676 17.421972) (xy 399.433046 17.479741)
			(xy 399.501475 17.531417) (xy 399.574381 17.576558) (xy 399.651141 17.61478) (xy 399.7311 17.645756)
			(xy 399.813576 17.669223) (xy 399.897866 17.684979) (xy 399.983249 17.692891) (xy 400.068999 17.692891)
			(xy 400.154382 17.684979) (xy 400.238672 17.669223) (xy 400.321148 17.645756) (xy 400.401107 17.61478)
			(xy 400.42331 17.603724) (xy 404.033736 17.603724) (xy 404.033736 18.467324) (xy 404.034222 18.494593)
			(xy 404.041984 18.548577) (xy 404.057349 18.600907) (xy 404.080006 18.650517) (xy 404.109492 18.696398)
			(xy 404.145207 18.737615) (xy 404.186424 18.77333) (xy 404.232305 18.802816) (xy 404.281915 18.825473)
			(xy 404.334245 18.840838) (xy 404.388229 18.8486) (xy 404.442767 18.8486) (xy 404.496751 18.840838)
			(xy 404.549081 18.825473) (xy 404.598691 18.802816) (xy 404.644572 18.77333) (xy 404.685789 18.737615)
			(xy 404.721504 18.696398) (xy 404.75099 18.650517) (xy 404.773647 18.600907) (xy 404.789012 18.548577)
			(xy 404.796774 18.494593) (xy 404.79726 18.467324) (xy 404.79726 17.603724) (xy 404.796774 17.576455)
			(xy 404.789012 17.522471) (xy 404.773647 17.470141) (xy 404.75099 17.420531) (xy 404.721504 17.37465)
			(xy 404.685789 17.333433) (xy 404.644572 17.297718) (xy 404.598691 17.268232) (xy 404.549081 17.245575)
			(xy 404.496751 17.23021) (xy 404.442767 17.222448) (xy 404.388229 17.222448) (xy 404.334245 17.23021)
			(xy 404.281915 17.245575) (xy 404.232305 17.268232) (xy 404.186424 17.297718) (xy 404.145207 17.333433)
			(xy 404.109492 17.37465) (xy 404.080006 17.420531) (xy 404.057349 17.470141) (xy 404.041984 17.522471)
			(xy 404.034222 17.576455) (xy 404.033736 17.603724) (xy 400.42331 17.603724) (xy 400.477867 17.576558)
			(xy 400.550773 17.531417) (xy 400.619202 17.479741) (xy 400.682572 17.421972) (xy 400.740341 17.358602)
			(xy 400.792017 17.290173) (xy 400.837158 17.217267) (xy 400.87538 17.140507) (xy 400.906356 17.060548)
			(xy 400.929823 16.978072) (xy 400.945579 16.893782) (xy 400.953491 16.808399) (xy 400.953986 16.765524)
			(xy 400.953491 16.722649) (xy 405.448757 16.722649) (xy 405.448757 16.808399) (xy 405.456669 16.893782)
			(xy 405.472425 16.978072) (xy 405.495892 17.060548) (xy 405.526868 17.140507) (xy 405.56509 17.217267)
			(xy 405.610231 17.290173) (xy 405.661907 17.358602) (xy 405.719676 17.421972) (xy 405.783046 17.479741)
			(xy 405.851475 17.531417) (xy 405.924381 17.576558) (xy 406.001141 17.61478) (xy 406.0811 17.645756)
			(xy 406.163576 17.669223) (xy 406.247866 17.684979) (xy 406.333249 17.692891) (xy 406.418999 17.692891)
			(xy 406.504382 17.684979) (xy 406.588672 17.669223) (xy 406.671148 17.645756) (xy 406.751107 17.61478)
			(xy 406.827867 17.576558) (xy 406.900773 17.531417) (xy 406.969202 17.479741) (xy 407.032572 17.421972)
			(xy 407.090341 17.358602) (xy 407.142017 17.290173) (xy 407.187158 17.217267) (xy 407.22538 17.140507)
			(xy 407.256356 17.060548) (xy 407.279823 16.978072) (xy 407.295579 16.893782) (xy 407.303491 16.808399)
			(xy 407.303986 16.765524) (xy 407.303491 16.722649) (xy 407.302832 16.715537) (xy 438.158877 16.715537)
			(xy 438.158877 16.801287) (xy 438.166789 16.88667) (xy 438.182545 16.97096) (xy 438.206012 17.053436)
			(xy 438.236988 17.133395) (xy 438.27521 17.210155) (xy 438.320351 17.283061) (xy 438.372027 17.35149)
			(xy 438.429796 17.41486) (xy 438.493166 17.472629) (xy 438.561595 17.524305) (xy 438.634501 17.569446)
			(xy 438.711261 17.607668) (xy 438.79122 17.638644) (xy 438.873696 17.662111) (xy 438.957986 17.677867)
			(xy 439.043369 17.685779) (xy 439.129119 17.685779) (xy 439.214502 17.677867) (xy 439.298792 17.662111)
			(xy 439.381268 17.638644) (xy 439.461227 17.607668) (xy 439.48343 17.596612) (xy 440.665108 17.596612)
			(xy 440.665108 18.460212) (xy 440.665594 18.487481) (xy 440.673356 18.541465) (xy 440.688721 18.593795)
			(xy 440.711378 18.643405) (xy 440.740864 18.689286) (xy 440.776579 18.730503) (xy 440.817796 18.766218)
			(xy 440.863677 18.795704) (xy 440.913287 18.818361) (xy 440.965617 18.833726) (xy 441.019601 18.841488)
			(xy 441.074139 18.841488) (xy 441.128123 18.833726) (xy 441.180453 18.818361) (xy 441.230063 18.795704)
			(xy 441.275944 18.766218) (xy 441.317161 18.730503) (xy 441.352876 18.689286) (xy 441.382362 18.643405)
			(xy 441.405019 18.593795) (xy 441.420384 18.541465) (xy 441.428146 18.487481) (xy 441.428632 18.460212)
			(xy 441.428632 17.596612) (xy 441.428146 17.569343) (xy 441.420384 17.515359) (xy 441.405019 17.463029)
			(xy 441.382362 17.413419) (xy 441.352876 17.367538) (xy 441.317161 17.326321) (xy 441.275944 17.290606)
			(xy 441.230063 17.26112) (xy 441.180453 17.238463) (xy 441.128123 17.223098) (xy 441.074139 17.215336)
			(xy 441.019601 17.215336) (xy 440.965617 17.223098) (xy 440.913287 17.238463) (xy 440.863677 17.26112)
			(xy 440.817796 17.290606) (xy 440.776579 17.326321) (xy 440.740864 17.367538) (xy 440.711378 17.413419)
			(xy 440.688721 17.463029) (xy 440.673356 17.515359) (xy 440.665594 17.569343) (xy 440.665108 17.596612)
			(xy 439.48343 17.596612) (xy 439.537987 17.569446) (xy 439.610893 17.524305) (xy 439.679322 17.472629)
			(xy 439.742692 17.41486) (xy 439.800461 17.35149) (xy 439.852137 17.283061) (xy 439.897278 17.210155)
			(xy 439.9355 17.133395) (xy 439.966476 17.053436) (xy 439.989943 16.97096) (xy 440.005699 16.88667)
			(xy 440.013611 16.801287) (xy 440.014106 16.758412) (xy 440.013611 16.715537) (xy 444.508877 16.715537)
			(xy 444.508877 16.801287) (xy 444.516789 16.88667) (xy 444.532545 16.97096) (xy 444.556012 17.053436)
			(xy 444.586988 17.133395) (xy 444.62521 17.210155) (xy 444.670351 17.283061) (xy 444.722027 17.35149)
			(xy 444.779796 17.41486) (xy 444.843166 17.472629) (xy 444.911595 17.524305) (xy 444.984501 17.569446)
			(xy 445.061261 17.607668) (xy 445.14122 17.638644) (xy 445.223696 17.662111) (xy 445.307986 17.677867)
			(xy 445.393369 17.685779) (xy 445.479119 17.685779) (xy 445.564502 17.677867) (xy 445.648792 17.662111)
			(xy 445.731268 17.638644) (xy 445.811227 17.607668) (xy 445.887987 17.569446) (xy 445.960893 17.524305)
			(xy 446.029322 17.472629) (xy 446.092692 17.41486) (xy 446.150461 17.35149) (xy 446.202137 17.283061)
			(xy 446.247278 17.210155) (xy 446.2855 17.133395) (xy 446.316476 17.053436) (xy 446.339943 16.97096)
			(xy 446.355699 16.88667) (xy 446.363611 16.801287) (xy 446.364106 16.758412) (xy 446.363611 16.715537)
			(xy 446.355699 16.630154) (xy 446.339943 16.545864) (xy 446.316476 16.463388) (xy 446.2855 16.383429)
			(xy 446.247278 16.306669) (xy 446.202137 16.233763) (xy 446.150461 16.165334) (xy 446.092692 16.101964)
			(xy 446.029322 16.044195) (xy 445.960893 15.992519) (xy 445.887987 15.947378) (xy 445.811227 15.909156)
			(xy 445.731268 15.87818) (xy 445.648792 15.854713) (xy 445.564502 15.838957) (xy 445.479119 15.831045)
			(xy 445.393369 15.831045) (xy 445.307986 15.838957) (xy 445.223696 15.854713) (xy 445.14122 15.87818)
			(xy 445.061261 15.909156) (xy 444.984501 15.947378) (xy 444.911595 15.992519) (xy 444.843166 16.044195)
			(xy 444.779796 16.101964) (xy 444.722027 16.165334) (xy 444.670351 16.233763) (xy 444.62521 16.306669)
			(xy 444.586988 16.383429) (xy 444.556012 16.463388) (xy 444.532545 16.545864) (xy 444.516789 16.630154)
			(xy 444.508877 16.715537) (xy 440.013611 16.715537) (xy 440.005699 16.630154) (xy 439.989943 16.545864)
			(xy 439.966476 16.463388) (xy 439.9355 16.383429) (xy 439.897278 16.306669) (xy 439.852137 16.233763)
			(xy 439.800461 16.165334) (xy 439.742692 16.101964) (xy 439.679322 16.044195) (xy 439.610893 15.992519)
			(xy 439.537987 15.947378) (xy 439.461227 15.909156) (xy 439.381268 15.87818) (xy 439.298792 15.854713)
			(xy 439.214502 15.838957) (xy 439.129119 15.831045) (xy 439.043369 15.831045) (xy 438.957986 15.838957)
			(xy 438.873696 15.854713) (xy 438.79122 15.87818) (xy 438.711261 15.909156) (xy 438.634501 15.947378)
			(xy 438.561595 15.992519) (xy 438.493166 16.044195) (xy 438.429796 16.101964) (xy 438.372027 16.165334)
			(xy 438.320351 16.233763) (xy 438.27521 16.306669) (xy 438.236988 16.383429) (xy 438.206012 16.463388)
			(xy 438.182545 16.545864) (xy 438.166789 16.630154) (xy 438.158877 16.715537) (xy 407.302832 16.715537)
			(xy 407.295579 16.637266) (xy 407.279823 16.552976) (xy 407.256356 16.4705) (xy 407.22538 16.390541)
			(xy 407.187158 16.313781) (xy 407.142017 16.240875) (xy 407.090341 16.172446) (xy 407.032572 16.109076)
			(xy 406.969202 16.051307) (xy 406.900773 15.999631) (xy 406.827867 15.95449) (xy 406.751107 15.916268)
			(xy 406.671148 15.885292) (xy 406.588672 15.861825) (xy 406.504382 15.846069) (xy 406.418999 15.838157)
			(xy 406.333249 15.838157) (xy 406.247866 15.846069) (xy 406.163576 15.861825) (xy 406.0811 15.885292)
			(xy 406.001141 15.916268) (xy 405.924381 15.95449) (xy 405.851475 15.999631) (xy 405.783046 16.051307)
			(xy 405.719676 16.109076) (xy 405.661907 16.172446) (xy 405.610231 16.240875) (xy 405.56509 16.313781)
			(xy 405.526868 16.390541) (xy 405.495892 16.4705) (xy 405.472425 16.552976) (xy 405.456669 16.637266)
			(xy 405.448757 16.722649) (xy 400.953491 16.722649) (xy 400.945579 16.637266) (xy 400.929823 16.552976)
			(xy 400.906356 16.4705) (xy 400.87538 16.390541) (xy 400.837158 16.313781) (xy 400.792017 16.240875)
			(xy 400.740341 16.172446) (xy 400.682572 16.109076) (xy 400.619202 16.051307) (xy 400.550773 15.999631)
			(xy 400.477867 15.95449) (xy 400.401107 15.916268) (xy 400.321148 15.885292) (xy 400.238672 15.861825)
			(xy 400.154382 15.846069) (xy 400.068999 15.838157) (xy 399.983249 15.838157) (xy 399.897866 15.846069)
			(xy 399.813576 15.861825) (xy 399.7311 15.885292) (xy 399.651141 15.916268) (xy 399.574381 15.95449)
			(xy 399.501475 15.999631) (xy 399.433046 16.051307) (xy 399.369676 16.109076) (xy 399.311907 16.172446)
			(xy 399.260231 16.240875) (xy 399.21509 16.313781) (xy 399.176868 16.390541) (xy 399.145892 16.4705)
			(xy 399.122425 16.552976) (xy 399.106669 16.637266) (xy 399.098757 16.722649) (xy 381.720693 16.722649)
			(xy 381.720611 16.715537) (xy 381.712699 16.630154) (xy 381.696943 16.545864) (xy 381.673476 16.463388)
			(xy 381.6425 16.383429) (xy 381.604278 16.306669) (xy 381.559137 16.233763) (xy 381.507461 16.165334)
			(xy 381.449692 16.101964) (xy 381.386322 16.044195) (xy 381.317893 15.992519) (xy 381.244987 15.947378)
			(xy 381.168227 15.909156) (xy 381.088268 15.87818) (xy 381.005792 15.854713) (xy 380.921502 15.838957)
			(xy 380.836119 15.831045) (xy 380.750369 15.831045) (xy 380.664986 15.838957) (xy 380.580696 15.854713)
			(xy 380.49822 15.87818) (xy 380.418261 15.909156) (xy 380.341501 15.947378) (xy 380.268595 15.992519)
			(xy 380.200166 16.044195) (xy 380.136796 16.101964) (xy 380.079027 16.165334) (xy 380.027351 16.233763)
			(xy 379.98221 16.306669) (xy 379.943988 16.383429) (xy 379.913012 16.463388) (xy 379.889545 16.545864)
			(xy 379.873789 16.630154) (xy 379.865877 16.715537) (xy 375.370611 16.715537) (xy 375.362699 16.630154)
			(xy 375.346943 16.545864) (xy 375.323476 16.463388) (xy 375.2925 16.383429) (xy 375.254278 16.306669)
			(xy 375.209137 16.233763) (xy 375.157461 16.165334) (xy 375.099692 16.101964) (xy 375.036322 16.044195)
			(xy 374.967893 15.992519) (xy 374.894987 15.947378) (xy 374.818227 15.909156) (xy 374.738268 15.87818)
			(xy 374.655792 15.854713) (xy 374.571502 15.838957) (xy 374.486119 15.831045) (xy 374.400369 15.831045)
			(xy 374.314986 15.838957) (xy 374.230696 15.854713) (xy 374.14822 15.87818) (xy 374.068261 15.909156)
			(xy 373.991501 15.947378) (xy 373.918595 15.992519) (xy 373.850166 16.044195) (xy 373.786796 16.101964)
			(xy 373.729027 16.165334) (xy 373.677351 16.233763) (xy 373.63221 16.306669) (xy 373.593988 16.383429)
			(xy 373.563012 16.463388) (xy 373.539545 16.545864) (xy 373.523789 16.630154) (xy 373.515877 16.715537)
			(xy 342.659832 16.715537) (xy 342.652579 16.637266) (xy 342.636823 16.552976) (xy 342.613356 16.4705)
			(xy 342.58238 16.390541) (xy 342.544158 16.313781) (xy 342.499017 16.240875) (xy 342.447341 16.172446)
			(xy 342.389572 16.109076) (xy 342.326202 16.051307) (xy 342.257773 15.999631) (xy 342.184867 15.95449)
			(xy 342.108107 15.916268) (xy 342.028148 15.885292) (xy 341.945672 15.861825) (xy 341.861382 15.846069)
			(xy 341.775999 15.838157) (xy 341.690249 15.838157) (xy 341.604866 15.846069) (xy 341.520576 15.861825)
			(xy 341.4381 15.885292) (xy 341.358141 15.916268) (xy 341.281381 15.95449) (xy 341.208475 15.999631)
			(xy 341.140046 16.051307) (xy 341.076676 16.109076) (xy 341.018907 16.172446) (xy 340.967231 16.240875)
			(xy 340.92209 16.313781) (xy 340.883868 16.390541) (xy 340.852892 16.4705) (xy 340.829425 16.552976)
			(xy 340.813669 16.637266) (xy 340.805757 16.722649) (xy 336.310491 16.722649) (xy 336.302579 16.637266)
			(xy 336.286823 16.552976) (xy 336.263356 16.4705) (xy 336.23238 16.390541) (xy 336.194158 16.313781)
			(xy 336.149017 16.240875) (xy 336.097341 16.172446) (xy 336.039572 16.109076) (xy 335.976202 16.051307)
			(xy 335.907773 15.999631) (xy 335.834867 15.95449) (xy 335.758107 15.916268) (xy 335.678148 15.885292)
			(xy 335.595672 15.861825) (xy 335.511382 15.846069) (xy 335.425999 15.838157) (xy 335.340249 15.838157)
			(xy 335.254866 15.846069) (xy 335.170576 15.861825) (xy 335.0881 15.885292) (xy 335.008141 15.916268)
			(xy 334.931381 15.95449) (xy 334.858475 15.999631) (xy 334.790046 16.051307) (xy 334.726676 16.109076)
			(xy 334.668907 16.172446) (xy 334.617231 16.240875) (xy 334.57209 16.313781) (xy 334.533868 16.390541)
			(xy 334.502892 16.4705) (xy 334.479425 16.552976) (xy 334.463669 16.637266) (xy 334.455757 16.722649)
			(xy 316.569693 16.722649) (xy 316.569611 16.715537) (xy 316.561699 16.630154) (xy 316.545943 16.545864)
			(xy 316.522476 16.463388) (xy 316.4915 16.383429) (xy 316.453278 16.306669) (xy 316.408137 16.233763)
			(xy 316.356461 16.165334) (xy 316.298692 16.101964) (xy 316.235322 16.044195) (xy 316.166893 15.992519)
			(xy 316.093987 15.947378) (xy 316.017227 15.909156) (xy 315.937268 15.87818) (xy 315.854792 15.854713)
			(xy 315.770502 15.838957) (xy 315.685119 15.831045) (xy 315.599369 15.831045) (xy 315.513986 15.838957)
			(xy 315.429696 15.854713) (xy 315.34722 15.87818) (xy 315.267261 15.909156) (xy 315.190501 15.947378)
			(xy 315.117595 15.992519) (xy 315.049166 16.044195) (xy 314.985796 16.101964) (xy 314.928027 16.165334)
			(xy 314.876351 16.233763) (xy 314.83121 16.306669) (xy 314.792988 16.383429) (xy 314.762012 16.463388)
			(xy 314.738545 16.545864) (xy 314.722789 16.630154) (xy 314.714877 16.715537) (xy 310.219611 16.715537)
			(xy 310.211699 16.630154) (xy 310.195943 16.545864) (xy 310.172476 16.463388) (xy 310.1415 16.383429)
			(xy 310.103278 16.306669) (xy 310.058137 16.233763) (xy 310.006461 16.165334) (xy 309.948692 16.101964)
			(xy 309.885322 16.044195) (xy 309.816893 15.992519) (xy 309.743987 15.947378) (xy 309.667227 15.909156)
			(xy 309.587268 15.87818) (xy 309.504792 15.854713) (xy 309.420502 15.838957) (xy 309.335119 15.831045)
			(xy 309.249369 15.831045) (xy 309.163986 15.838957) (xy 309.079696 15.854713) (xy 308.99722 15.87818)
			(xy 308.917261 15.909156) (xy 308.840501 15.947378) (xy 308.767595 15.992519) (xy 308.699166 16.044195)
			(xy 308.635796 16.101964) (xy 308.578027 16.165334) (xy 308.526351 16.233763) (xy 308.48121 16.306669)
			(xy 308.442988 16.383429) (xy 308.412012 16.463388) (xy 308.388545 16.545864) (xy 308.372789 16.630154)
			(xy 308.364877 16.715537) (xy 277.508832 16.715537) (xy 277.501579 16.637266) (xy 277.485823 16.552976)
			(xy 277.462356 16.4705) (xy 277.43138 16.390541) (xy 277.393158 16.313781) (xy 277.348017 16.240875)
			(xy 277.296341 16.172446) (xy 277.238572 16.109076) (xy 277.175202 16.051307) (xy 277.106773 15.999631)
			(xy 277.033867 15.95449) (xy 276.957107 15.916268) (xy 276.877148 15.885292) (xy 276.794672 15.861825)
			(xy 276.710382 15.846069) (xy 276.624999 15.838157) (xy 276.539249 15.838157) (xy 276.453866 15.846069)
			(xy 276.369576 15.861825) (xy 276.2871 15.885292) (xy 276.207141 15.916268) (xy 276.130381 15.95449)
			(xy 276.057475 15.999631) (xy 275.989046 16.051307) (xy 275.925676 16.109076) (xy 275.867907 16.172446)
			(xy 275.816231 16.240875) (xy 275.77109 16.313781) (xy 275.732868 16.390541) (xy 275.701892 16.4705)
			(xy 275.678425 16.552976) (xy 275.662669 16.637266) (xy 275.654757 16.722649) (xy 271.159491 16.722649)
			(xy 271.151579 16.637266) (xy 271.135823 16.552976) (xy 271.112356 16.4705) (xy 271.08138 16.390541)
			(xy 271.043158 16.313781) (xy 270.998017 16.240875) (xy 270.946341 16.172446) (xy 270.888572 16.109076)
			(xy 270.825202 16.051307) (xy 270.756773 15.999631) (xy 270.683867 15.95449) (xy 270.607107 15.916268)
			(xy 270.527148 15.885292) (xy 270.444672 15.861825) (xy 270.360382 15.846069) (xy 270.274999 15.838157)
			(xy 270.189249 15.838157) (xy 270.103866 15.846069) (xy 270.019576 15.861825) (xy 269.9371 15.885292)
			(xy 269.857141 15.916268) (xy 269.780381 15.95449) (xy 269.707475 15.999631) (xy 269.639046 16.051307)
			(xy 269.575676 16.109076) (xy 269.517907 16.172446) (xy 269.466231 16.240875) (xy 269.42109 16.313781)
			(xy 269.382868 16.390541) (xy 269.351892 16.4705) (xy 269.328425 16.552976) (xy 269.312669 16.637266)
			(xy 269.304757 16.722649) (xy 252.231493 16.722649) (xy 252.231411 16.715537) (xy 252.223499 16.630154)
			(xy 252.207743 16.545864) (xy 252.184276 16.463388) (xy 252.1533 16.383429) (xy 252.115078 16.306669)
			(xy 252.069937 16.233763) (xy 252.018261 16.165334) (xy 251.960492 16.101964) (xy 251.897122 16.044195)
			(xy 251.828693 15.992519) (xy 251.755787 15.947378) (xy 251.679027 15.909156) (xy 251.599068 15.87818)
			(xy 251.516592 15.854713) (xy 251.432302 15.838957) (xy 251.346919 15.831045) (xy 251.261169 15.831045)
			(xy 251.175786 15.838957) (xy 251.091496 15.854713) (xy 251.00902 15.87818) (xy 250.929061 15.909156)
			(xy 250.852301 15.947378) (xy 250.779395 15.992519) (xy 250.710966 16.044195) (xy 250.647596 16.101964)
			(xy 250.589827 16.165334) (xy 250.538151 16.233763) (xy 250.49301 16.306669) (xy 250.454788 16.383429)
			(xy 250.423812 16.463388) (xy 250.400345 16.545864) (xy 250.384589 16.630154) (xy 250.376677 16.715537)
			(xy 245.881411 16.715537) (xy 245.873499 16.630154) (xy 245.857743 16.545864) (xy 245.834276 16.463388)
			(xy 245.8033 16.383429) (xy 245.765078 16.306669) (xy 245.719937 16.233763) (xy 245.668261 16.165334)
			(xy 245.610492 16.101964) (xy 245.547122 16.044195) (xy 245.478693 15.992519) (xy 245.405787 15.947378)
			(xy 245.329027 15.909156) (xy 245.249068 15.87818) (xy 245.166592 15.854713) (xy 245.082302 15.838957)
			(xy 244.996919 15.831045) (xy 244.911169 15.831045) (xy 244.825786 15.838957) (xy 244.741496 15.854713)
			(xy 244.65902 15.87818) (xy 244.579061 15.909156) (xy 244.502301 15.947378) (xy 244.429395 15.992519)
			(xy 244.360966 16.044195) (xy 244.297596 16.101964) (xy 244.239827 16.165334) (xy 244.188151 16.233763)
			(xy 244.14301 16.306669) (xy 244.104788 16.383429) (xy 244.073812 16.463388) (xy 244.050345 16.545864)
			(xy 244.034589 16.630154) (xy 244.026677 16.715537) (xy 218.199832 16.715537) (xy 218.192579 16.637266)
			(xy 218.176823 16.552976) (xy 218.153356 16.4705) (xy 218.12238 16.390541) (xy 218.084158 16.313781)
			(xy 218.039017 16.240875) (xy 217.987341 16.172446) (xy 217.929572 16.109076) (xy 217.866202 16.051307)
			(xy 217.797773 15.999631) (xy 217.724867 15.95449) (xy 217.648107 15.916268) (xy 217.568148 15.885292)
			(xy 217.485672 15.861825) (xy 217.401382 15.846069) (xy 217.315999 15.838157) (xy 217.230249 15.838157)
			(xy 217.144866 15.846069) (xy 217.060576 15.861825) (xy 216.9781 15.885292) (xy 216.898141 15.916268)
			(xy 216.821381 15.95449) (xy 216.748475 15.999631) (xy 216.680046 16.051307) (xy 216.616676 16.109076)
			(xy 216.558907 16.172446) (xy 216.507231 16.240875) (xy 216.46209 16.313781) (xy 216.423868 16.390541)
			(xy 216.392892 16.4705) (xy 216.369425 16.552976) (xy 216.353669 16.637266) (xy 216.345757 16.722649)
			(xy 211.850491 16.722649) (xy 211.842579 16.637266) (xy 211.826823 16.552976) (xy 211.803356 16.4705)
			(xy 211.77238 16.390541) (xy 211.734158 16.313781) (xy 211.689017 16.240875) (xy 211.637341 16.172446)
			(xy 211.579572 16.109076) (xy 211.516202 16.051307) (xy 211.447773 15.999631) (xy 211.374867 15.95449)
			(xy 211.298107 15.916268) (xy 211.218148 15.885292) (xy 211.135672 15.861825) (xy 211.051382 15.846069)
			(xy 210.965999 15.838157) (xy 210.880249 15.838157) (xy 210.794866 15.846069) (xy 210.710576 15.861825)
			(xy 210.6281 15.885292) (xy 210.548141 15.916268) (xy 210.471381 15.95449) (xy 210.398475 15.999631)
			(xy 210.330046 16.051307) (xy 210.266676 16.109076) (xy 210.208907 16.172446) (xy 210.157231 16.240875)
			(xy 210.11209 16.313781) (xy 210.073868 16.390541) (xy 210.042892 16.4705) (xy 210.019425 16.552976)
			(xy 210.003669 16.637266) (xy 209.995757 16.722649) (xy 158.621984 16.722649) (xy 158.621984 11.850929)
			(xy 251.524757 11.850929) (xy 251.524757 11.936679) (xy 251.532669 12.022062) (xy 251.548425 12.106352)
			(xy 251.571892 12.188828) (xy 251.602868 12.268787) (xy 251.64109 12.345547) (xy 251.686231 12.418453)
			(xy 251.737907 12.486882) (xy 251.795676 12.550252) (xy 251.859046 12.608021) (xy 251.927475 12.659697)
			(xy 252.000381 12.704838) (xy 252.077141 12.74306) (xy 252.1571 12.774036) (xy 252.239576 12.797503)
			(xy 252.323866 12.813259) (xy 252.409249 12.821171) (xy 252.494999 12.821171) (xy 252.580382 12.813259)
			(xy 252.664672 12.797503) (xy 252.747148 12.774036) (xy 252.827107 12.74306) (xy 252.903867 12.704838)
			(xy 252.976773 12.659697) (xy 253.045202 12.608021) (xy 253.108572 12.550252) (xy 253.166341 12.486882)
			(xy 253.218017 12.418453) (xy 253.263158 12.345547) (xy 253.30138 12.268787) (xy 253.332356 12.188828)
			(xy 253.355823 12.106352) (xy 253.371579 12.022062) (xy 253.379491 11.936679) (xy 253.379986 11.893804)
			(xy 253.379491 11.850929) (xy 257.874757 11.850929) (xy 257.874757 11.936679) (xy 257.882669 12.022062)
			(xy 257.898425 12.106352) (xy 257.921892 12.188828) (xy 257.952868 12.268787) (xy 257.99109 12.345547)
			(xy 258.036231 12.418453) (xy 258.087907 12.486882) (xy 258.145676 12.550252) (xy 258.209046 12.608021)
			(xy 258.277475 12.659697) (xy 258.350381 12.704838) (xy 258.427141 12.74306) (xy 258.5071 12.774036)
			(xy 258.589576 12.797503) (xy 258.673866 12.813259) (xy 258.759249 12.821171) (xy 258.844999 12.821171)
			(xy 258.930382 12.813259) (xy 259.014672 12.797503) (xy 259.097148 12.774036) (xy 259.177107 12.74306)
			(xy 259.253867 12.704838) (xy 259.326773 12.659697) (xy 259.395202 12.608021) (xy 259.458572 12.550252)
			(xy 259.516341 12.486882) (xy 259.568017 12.418453) (xy 259.613158 12.345547) (xy 259.65138 12.268787)
			(xy 259.682356 12.188828) (xy 259.705823 12.106352) (xy 259.721579 12.022062) (xy 259.729491 11.936679)
			(xy 259.729986 11.893804) (xy 259.72979 11.876837) (xy 309.725301 11.876837) (xy 309.725301 11.962587)
			(xy 309.733213 12.04797) (xy 309.748969 12.13226) (xy 309.772436 12.214736) (xy 309.803412 12.294695)
			(xy 309.841634 12.371455) (xy 309.886775 12.444361) (xy 309.938451 12.51279) (xy 309.99622 12.57616)
			(xy 310.05959 12.633929) (xy 310.128019 12.685605) (xy 310.200925 12.730746) (xy 310.277685 12.768968)
			(xy 310.357644 12.799944) (xy 310.44012 12.823411) (xy 310.52441 12.839167) (xy 310.609793 12.847079)
			(xy 310.695543 12.847079) (xy 310.780926 12.839167) (xy 310.865216 12.823411) (xy 310.947692 12.799944)
			(xy 311.027651 12.768968) (xy 311.104411 12.730746) (xy 311.177317 12.685605) (xy 311.245746 12.633929)
			(xy 311.309116 12.57616) (xy 311.366885 12.51279) (xy 311.418561 12.444361) (xy 311.463702 12.371455)
			(xy 311.501924 12.294695) (xy 311.5329 12.214736) (xy 311.556367 12.13226) (xy 311.572123 12.04797)
			(xy 311.580035 11.962587) (xy 311.58053 11.919712) (xy 311.580035 11.876837) (xy 316.075301 11.876837)
			(xy 316.075301 11.962587) (xy 316.083213 12.04797) (xy 316.098969 12.13226) (xy 316.122436 12.214736)
			(xy 316.153412 12.294695) (xy 316.191634 12.371455) (xy 316.236775 12.444361) (xy 316.288451 12.51279)
			(xy 316.34622 12.57616) (xy 316.40959 12.633929) (xy 316.478019 12.685605) (xy 316.550925 12.730746)
			(xy 316.627685 12.768968) (xy 316.707644 12.799944) (xy 316.79012 12.823411) (xy 316.87441 12.839167)
			(xy 316.959793 12.847079) (xy 317.045543 12.847079) (xy 317.130926 12.839167) (xy 317.215216 12.823411)
			(xy 317.297692 12.799944) (xy 317.377651 12.768968) (xy 317.454411 12.730746) (xy 317.527317 12.685605)
			(xy 317.595746 12.633929) (xy 317.659116 12.57616) (xy 317.716885 12.51279) (xy 317.768561 12.444361)
			(xy 317.813702 12.371455) (xy 317.851924 12.294695) (xy 317.8829 12.214736) (xy 317.906367 12.13226)
			(xy 317.922123 12.04797) (xy 317.930035 11.962587) (xy 317.93053 11.919712) (xy 317.930117 11.883949)
			(xy 324.295757 11.883949) (xy 324.295757 11.969699) (xy 324.303669 12.055082) (xy 324.319425 12.139372)
			(xy 324.342892 12.221848) (xy 324.373868 12.301807) (xy 324.41209 12.378567) (xy 324.457231 12.451473)
			(xy 324.508907 12.519902) (xy 324.566676 12.583272) (xy 324.630046 12.641041) (xy 324.698475 12.692717)
			(xy 324.771381 12.737858) (xy 324.848141 12.77608) (xy 324.9281 12.807056) (xy 325.010576 12.830523)
			(xy 325.094866 12.846279) (xy 325.180249 12.854191) (xy 325.265999 12.854191) (xy 325.351382 12.846279)
			(xy 325.435672 12.830523) (xy 325.518148 12.807056) (xy 325.598107 12.77608) (xy 325.674867 12.737858)
			(xy 325.747773 12.692717) (xy 325.816202 12.641041) (xy 325.879572 12.583272) (xy 325.937341 12.519902)
			(xy 325.989017 12.451473) (xy 326.034158 12.378567) (xy 326.07238 12.301807) (xy 326.103356 12.221848)
			(xy 326.126823 12.139372) (xy 326.142579 12.055082) (xy 326.150491 11.969699) (xy 326.150986 11.926824)
			(xy 326.150491 11.883949) (xy 330.645757 11.883949) (xy 330.645757 11.969699) (xy 330.653669 12.055082)
			(xy 330.669425 12.139372) (xy 330.692892 12.221848) (xy 330.723868 12.301807) (xy 330.76209 12.378567)
			(xy 330.807231 12.451473) (xy 330.858907 12.519902) (xy 330.916676 12.583272) (xy 330.980046 12.641041)
			(xy 331.048475 12.692717) (xy 331.121381 12.737858) (xy 331.198141 12.77608) (xy 331.2781 12.807056)
			(xy 331.360576 12.830523) (xy 331.444866 12.846279) (xy 331.530249 12.854191) (xy 331.615999 12.854191)
			(xy 331.701382 12.846279) (xy 331.785672 12.830523) (xy 331.868148 12.807056) (xy 331.948107 12.77608)
			(xy 332.024867 12.737858) (xy 332.097773 12.692717) (xy 332.166202 12.641041) (xy 332.229572 12.583272)
			(xy 332.287341 12.519902) (xy 332.339017 12.451473) (xy 332.384158 12.378567) (xy 332.42238 12.301807)
			(xy 332.453356 12.221848) (xy 332.476823 12.139372) (xy 332.492579 12.055082) (xy 332.500491 11.969699)
			(xy 332.500986 11.926824) (xy 332.50079 11.909857) (xy 382.496301 11.909857) (xy 382.496301 11.995607)
			(xy 382.504213 12.08099) (xy 382.519969 12.16528) (xy 382.543436 12.247756) (xy 382.574412 12.327715)
			(xy 382.612634 12.404475) (xy 382.657775 12.477381) (xy 382.709451 12.54581) (xy 382.76722 12.60918)
			(xy 382.83059 12.666949) (xy 382.899019 12.718625) (xy 382.971925 12.763766) (xy 383.048685 12.801988)
			(xy 383.128644 12.832964) (xy 383.21112 12.856431) (xy 383.29541 12.872187) (xy 383.380793 12.880099)
			(xy 383.466543 12.880099) (xy 383.551926 12.872187) (xy 383.636216 12.856431) (xy 383.718692 12.832964)
			(xy 383.798651 12.801988) (xy 383.875411 12.763766) (xy 383.948317 12.718625) (xy 384.016746 12.666949)
			(xy 384.080116 12.60918) (xy 384.137885 12.54581) (xy 384.189561 12.477381) (xy 384.234702 12.404475)
			(xy 384.272924 12.327715) (xy 384.3039 12.247756) (xy 384.327367 12.16528) (xy 384.343123 12.08099)
			(xy 384.351035 11.995607) (xy 384.35153 11.952732) (xy 384.351035 11.909857) (xy 388.846301 11.909857)
			(xy 388.846301 11.995607) (xy 388.854213 12.08099) (xy 388.869969 12.16528) (xy 388.893436 12.247756)
			(xy 388.924412 12.327715) (xy 388.962634 12.404475) (xy 389.007775 12.477381) (xy 389.059451 12.54581)
			(xy 389.11722 12.60918) (xy 389.18059 12.666949) (xy 389.249019 12.718625) (xy 389.321925 12.763766)
			(xy 389.398685 12.801988) (xy 389.478644 12.832964) (xy 389.56112 12.856431) (xy 389.64541 12.872187)
			(xy 389.730793 12.880099) (xy 389.816543 12.880099) (xy 389.901926 12.872187) (xy 389.986216 12.856431)
			(xy 390.068692 12.832964) (xy 390.148651 12.801988) (xy 390.225411 12.763766) (xy 390.298317 12.718625)
			(xy 390.366746 12.666949) (xy 390.430116 12.60918) (xy 390.487885 12.54581) (xy 390.539561 12.477381)
			(xy 390.584702 12.404475) (xy 390.622924 12.327715) (xy 390.6539 12.247756) (xy 390.677367 12.16528)
			(xy 390.693123 12.08099) (xy 390.701035 11.995607) (xy 390.70153 11.952732) (xy 390.701117 11.916969)
			(xy 396.558757 11.916969) (xy 396.558757 12.002719) (xy 396.566669 12.088102) (xy 396.582425 12.172392)
			(xy 396.605892 12.254868) (xy 396.636868 12.334827) (xy 396.67509 12.411587) (xy 396.720231 12.484493)
			(xy 396.771907 12.552922) (xy 396.829676 12.616292) (xy 396.893046 12.674061) (xy 396.961475 12.725737)
			(xy 397.034381 12.770878) (xy 397.111141 12.8091) (xy 397.1911 12.840076) (xy 397.273576 12.863543)
			(xy 397.357866 12.879299) (xy 397.443249 12.887211) (xy 397.528999 12.887211) (xy 397.614382 12.879299)
			(xy 397.698672 12.863543) (xy 397.781148 12.840076) (xy 397.861107 12.8091) (xy 397.937867 12.770878)
			(xy 398.010773 12.725737) (xy 398.079202 12.674061) (xy 398.142572 12.616292) (xy 398.200341 12.552922)
			(xy 398.252017 12.484493) (xy 398.297158 12.411587) (xy 398.33538 12.334827) (xy 398.366356 12.254868)
			(xy 398.389823 12.172392) (xy 398.405579 12.088102) (xy 398.413491 12.002719) (xy 398.413986 11.959844)
			(xy 398.413491 11.916969) (xy 402.908757 11.916969) (xy 402.908757 12.002719) (xy 402.916669 12.088102)
			(xy 402.932425 12.172392) (xy 402.955892 12.254868) (xy 402.986868 12.334827) (xy 403.02509 12.411587)
			(xy 403.070231 12.484493) (xy 403.121907 12.552922) (xy 403.179676 12.616292) (xy 403.243046 12.674061)
			(xy 403.311475 12.725737) (xy 403.384381 12.770878) (xy 403.461141 12.8091) (xy 403.5411 12.840076)
			(xy 403.623576 12.863543) (xy 403.707866 12.879299) (xy 403.793249 12.887211) (xy 403.878999 12.887211)
			(xy 403.964382 12.879299) (xy 404.048672 12.863543) (xy 404.131148 12.840076) (xy 404.211107 12.8091)
			(xy 404.287867 12.770878) (xy 404.360773 12.725737) (xy 404.429202 12.674061) (xy 404.492572 12.616292)
			(xy 404.550341 12.552922) (xy 404.602017 12.484493) (xy 404.647158 12.411587) (xy 404.68538 12.334827)
			(xy 404.716356 12.254868) (xy 404.739823 12.172392) (xy 404.755579 12.088102) (xy 404.763491 12.002719)
			(xy 404.763986 11.959844) (xy 404.76379 11.942877) (xy 454.759301 11.942877) (xy 454.759301 12.028627)
			(xy 454.767213 12.11401) (xy 454.782969 12.1983) (xy 454.806436 12.280776) (xy 454.837412 12.360735)
			(xy 454.875634 12.437495) (xy 454.920775 12.510401) (xy 454.972451 12.57883) (xy 455.03022 12.6422)
			(xy 455.09359 12.699969) (xy 455.162019 12.751645) (xy 455.234925 12.796786) (xy 455.311685 12.835008)
			(xy 455.391644 12.865984) (xy 455.47412 12.889451) (xy 455.55841 12.905207) (xy 455.643793 12.913119)
			(xy 455.729543 12.913119) (xy 455.814926 12.905207) (xy 455.899216 12.889451) (xy 455.981692 12.865984)
			(xy 456.061651 12.835008) (xy 456.138411 12.796786) (xy 456.211317 12.751645) (xy 456.279746 12.699969)
			(xy 456.343116 12.6422) (xy 456.400885 12.57883) (xy 456.452561 12.510401) (xy 456.497702 12.437495)
			(xy 456.535924 12.360735) (xy 456.5669 12.280776) (xy 456.590367 12.1983) (xy 456.606123 12.11401)
			(xy 456.614035 12.028627) (xy 456.61453 11.985752) (xy 456.614035 11.942877) (xy 461.109301 11.942877)
			(xy 461.109301 12.028627) (xy 461.117213 12.11401) (xy 461.132969 12.1983) (xy 461.156436 12.280776)
			(xy 461.187412 12.360735) (xy 461.225634 12.437495) (xy 461.270775 12.510401) (xy 461.322451 12.57883)
			(xy 461.38022 12.6422) (xy 461.44359 12.699969) (xy 461.512019 12.751645) (xy 461.584925 12.796786)
			(xy 461.661685 12.835008) (xy 461.741644 12.865984) (xy 461.82412 12.889451) (xy 461.90841 12.905207)
			(xy 461.993793 12.913119) (xy 462.079543 12.913119) (xy 462.164926 12.905207) (xy 462.249216 12.889451)
			(xy 462.331692 12.865984) (xy 462.411651 12.835008) (xy 462.488411 12.796786) (xy 462.561317 12.751645)
			(xy 462.629746 12.699969) (xy 462.693116 12.6422) (xy 462.750885 12.57883) (xy 462.802561 12.510401)
			(xy 462.847702 12.437495) (xy 462.885924 12.360735) (xy 462.9169 12.280776) (xy 462.940367 12.1983)
			(xy 462.956123 12.11401) (xy 462.964035 12.028627) (xy 462.96453 11.985752) (xy 462.964035 11.942877)
			(xy 462.956123 11.857494) (xy 462.940367 11.773204) (xy 462.9169 11.690728) (xy 462.885924 11.610769)
			(xy 462.847702 11.534009) (xy 462.802561 11.461103) (xy 462.750885 11.392674) (xy 462.693116 11.329304)
			(xy 462.629746 11.271535) (xy 462.561317 11.219859) (xy 462.488411 11.174718) (xy 462.411651 11.136496)
			(xy 462.331692 11.10552) (xy 462.249216 11.082053) (xy 462.164926 11.066297) (xy 462.079543 11.058385)
			(xy 461.993793 11.058385) (xy 461.90841 11.066297) (xy 461.82412 11.082053) (xy 461.741644 11.10552)
			(xy 461.661685 11.136496) (xy 461.584925 11.174718) (xy 461.512019 11.219859) (xy 461.44359 11.271535)
			(xy 461.38022 11.329304) (xy 461.322451 11.392674) (xy 461.270775 11.461103) (xy 461.225634 11.534009)
			(xy 461.187412 11.610769) (xy 461.156436 11.690728) (xy 461.132969 11.773204) (xy 461.117213 11.857494)
			(xy 461.109301 11.942877) (xy 456.614035 11.942877) (xy 456.606123 11.857494) (xy 456.590367 11.773204)
			(xy 456.5669 11.690728) (xy 456.535924 11.610769) (xy 456.497702 11.534009) (xy 456.452561 11.461103)
			(xy 456.400885 11.392674) (xy 456.343116 11.329304) (xy 456.279746 11.271535) (xy 456.211317 11.219859)
			(xy 456.138411 11.174718) (xy 456.061651 11.136496) (xy 455.981692 11.10552) (xy 455.899216 11.082053)
			(xy 455.814926 11.066297) (xy 455.729543 11.058385) (xy 455.643793 11.058385) (xy 455.55841 11.066297)
			(xy 455.47412 11.082053) (xy 455.391644 11.10552) (xy 455.311685 11.136496) (xy 455.234925 11.174718)
			(xy 455.162019 11.219859) (xy 455.09359 11.271535) (xy 455.03022 11.329304) (xy 454.972451 11.392674)
			(xy 454.920775 11.461103) (xy 454.875634 11.534009) (xy 454.837412 11.610769) (xy 454.806436 11.690728)
			(xy 454.782969 11.773204) (xy 454.767213 11.857494) (xy 454.759301 11.942877) (xy 404.76379 11.942877)
			(xy 404.763491 11.916969) (xy 404.755579 11.831586) (xy 404.739823 11.747296) (xy 404.716356 11.66482)
			(xy 404.68538 11.584861) (xy 404.647158 11.508101) (xy 404.602017 11.435195) (xy 404.550341 11.366766)
			(xy 404.492572 11.303396) (xy 404.429202 11.245627) (xy 404.360773 11.193951) (xy 404.287867 11.14881)
			(xy 404.211107 11.110588) (xy 404.131148 11.079612) (xy 404.048672 11.056145) (xy 403.964382 11.040389)
			(xy 403.878999 11.032477) (xy 403.793249 11.032477) (xy 403.707866 11.040389) (xy 403.623576 11.056145)
			(xy 403.5411 11.079612) (xy 403.461141 11.110588) (xy 403.384381 11.14881) (xy 403.311475 11.193951)
			(xy 403.243046 11.245627) (xy 403.179676 11.303396) (xy 403.121907 11.366766) (xy 403.070231 11.435195)
			(xy 403.02509 11.508101) (xy 402.986868 11.584861) (xy 402.955892 11.66482) (xy 402.932425 11.747296)
			(xy 402.916669 11.831586) (xy 402.908757 11.916969) (xy 398.413491 11.916969) (xy 398.405579 11.831586)
			(xy 398.389823 11.747296) (xy 398.366356 11.66482) (xy 398.33538 11.584861) (xy 398.297158 11.508101)
			(xy 398.252017 11.435195) (xy 398.200341 11.366766) (xy 398.142572 11.303396) (xy 398.079202 11.245627)
			(xy 398.010773 11.193951) (xy 397.937867 11.14881) (xy 397.861107 11.110588) (xy 397.781148 11.079612)
			(xy 397.698672 11.056145) (xy 397.614382 11.040389) (xy 397.528999 11.032477) (xy 397.443249 11.032477)
			(xy 397.357866 11.040389) (xy 397.273576 11.056145) (xy 397.1911 11.079612) (xy 397.111141 11.110588)
			(xy 397.034381 11.14881) (xy 396.961475 11.193951) (xy 396.893046 11.245627) (xy 396.829676 11.303396)
			(xy 396.771907 11.366766) (xy 396.720231 11.435195) (xy 396.67509 11.508101) (xy 396.636868 11.584861)
			(xy 396.605892 11.66482) (xy 396.582425 11.747296) (xy 396.566669 11.831586) (xy 396.558757 11.916969)
			(xy 390.701117 11.916969) (xy 390.701035 11.909857) (xy 390.693123 11.824474) (xy 390.677367 11.740184)
			(xy 390.6539 11.657708) (xy 390.622924 11.577749) (xy 390.584702 11.500989) (xy 390.539561 11.428083)
			(xy 390.487885 11.359654) (xy 390.430116 11.296284) (xy 390.366746 11.238515) (xy 390.298317 11.186839)
			(xy 390.225411 11.141698) (xy 390.148651 11.103476) (xy 390.068692 11.0725) (xy 389.986216 11.049033)
			(xy 389.901926 11.033277) (xy 389.816543 11.025365) (xy 389.730793 11.025365) (xy 389.64541 11.033277)
			(xy 389.56112 11.049033) (xy 389.478644 11.0725) (xy 389.398685 11.103476) (xy 389.321925 11.141698)
			(xy 389.249019 11.186839) (xy 389.18059 11.238515) (xy 389.11722 11.296284) (xy 389.059451 11.359654)
			(xy 389.007775 11.428083) (xy 388.962634 11.500989) (xy 388.924412 11.577749) (xy 388.893436 11.657708)
			(xy 388.869969 11.740184) (xy 388.854213 11.824474) (xy 388.846301 11.909857) (xy 384.351035 11.909857)
			(xy 384.343123 11.824474) (xy 384.327367 11.740184) (xy 384.3039 11.657708) (xy 384.272924 11.577749)
			(xy 384.234702 11.500989) (xy 384.189561 11.428083) (xy 384.137885 11.359654) (xy 384.080116 11.296284)
			(xy 384.016746 11.238515) (xy 383.948317 11.186839) (xy 383.875411 11.141698) (xy 383.798651 11.103476)
			(xy 383.718692 11.0725) (xy 383.636216 11.049033) (xy 383.551926 11.033277) (xy 383.466543 11.025365)
			(xy 383.380793 11.025365) (xy 383.29541 11.033277) (xy 383.21112 11.049033) (xy 383.128644 11.0725)
			(xy 383.048685 11.103476) (xy 382.971925 11.141698) (xy 382.899019 11.186839) (xy 382.83059 11.238515)
			(xy 382.76722 11.296284) (xy 382.709451 11.359654) (xy 382.657775 11.428083) (xy 382.612634 11.500989)
			(xy 382.574412 11.577749) (xy 382.543436 11.657708) (xy 382.519969 11.740184) (xy 382.504213 11.824474)
			(xy 382.496301 11.909857) (xy 332.50079 11.909857) (xy 332.500491 11.883949) (xy 332.492579 11.798566)
			(xy 332.476823 11.714276) (xy 332.453356 11.6318) (xy 332.42238 11.551841) (xy 332.384158 11.475081)
			(xy 332.339017 11.402175) (xy 332.287341 11.333746) (xy 332.229572 11.270376) (xy 332.166202 11.212607)
			(xy 332.097773 11.160931) (xy 332.024867 11.11579) (xy 331.948107 11.077568) (xy 331.868148 11.046592)
			(xy 331.785672 11.023125) (xy 331.701382 11.007369) (xy 331.615999 10.999457) (xy 331.530249 10.999457)
			(xy 331.444866 11.007369) (xy 331.360576 11.023125) (xy 331.2781 11.046592) (xy 331.198141 11.077568)
			(xy 331.121381 11.11579) (xy 331.048475 11.160931) (xy 330.980046 11.212607) (xy 330.916676 11.270376)
			(xy 330.858907 11.333746) (xy 330.807231 11.402175) (xy 330.76209 11.475081) (xy 330.723868 11.551841)
			(xy 330.692892 11.6318) (xy 330.669425 11.714276) (xy 330.653669 11.798566) (xy 330.645757 11.883949)
			(xy 326.150491 11.883949) (xy 326.142579 11.798566) (xy 326.126823 11.714276) (xy 326.103356 11.6318)
			(xy 326.07238 11.551841) (xy 326.034158 11.475081) (xy 325.989017 11.402175) (xy 325.937341 11.333746)
			(xy 325.879572 11.270376) (xy 325.816202 11.212607) (xy 325.747773 11.160931) (xy 325.674867 11.11579)
			(xy 325.598107 11.077568) (xy 325.518148 11.046592) (xy 325.435672 11.023125) (xy 325.351382 11.007369)
			(xy 325.265999 10.999457) (xy 325.180249 10.999457) (xy 325.094866 11.007369) (xy 325.010576 11.023125)
			(xy 324.9281 11.046592) (xy 324.848141 11.077568) (xy 324.771381 11.11579) (xy 324.698475 11.160931)
			(xy 324.630046 11.212607) (xy 324.566676 11.270376) (xy 324.508907 11.333746) (xy 324.457231 11.402175)
			(xy 324.41209 11.475081) (xy 324.373868 11.551841) (xy 324.342892 11.6318) (xy 324.319425 11.714276)
			(xy 324.303669 11.798566) (xy 324.295757 11.883949) (xy 317.930117 11.883949) (xy 317.930035 11.876837)
			(xy 317.922123 11.791454) (xy 317.906367 11.707164) (xy 317.8829 11.624688) (xy 317.851924 11.544729)
			(xy 317.813702 11.467969) (xy 317.768561 11.395063) (xy 317.716885 11.326634) (xy 317.659116 11.263264)
			(xy 317.595746 11.205495) (xy 317.527317 11.153819) (xy 317.454411 11.108678) (xy 317.377651 11.070456)
			(xy 317.297692 11.03948) (xy 317.215216 11.016013) (xy 317.130926 11.000257) (xy 317.045543 10.992345)
			(xy 316.959793 10.992345) (xy 316.87441 11.000257) (xy 316.79012 11.016013) (xy 316.707644 11.03948)
			(xy 316.627685 11.070456) (xy 316.550925 11.108678) (xy 316.478019 11.153819) (xy 316.40959 11.205495)
			(xy 316.34622 11.263264) (xy 316.288451 11.326634) (xy 316.236775 11.395063) (xy 316.191634 11.467969)
			(xy 316.153412 11.544729) (xy 316.122436 11.624688) (xy 316.098969 11.707164) (xy 316.083213 11.791454)
			(xy 316.075301 11.876837) (xy 311.580035 11.876837) (xy 311.572123 11.791454) (xy 311.556367 11.707164)
			(xy 311.5329 11.624688) (xy 311.501924 11.544729) (xy 311.463702 11.467969) (xy 311.418561 11.395063)
			(xy 311.366885 11.326634) (xy 311.309116 11.263264) (xy 311.245746 11.205495) (xy 311.177317 11.153819)
			(xy 311.104411 11.108678) (xy 311.027651 11.070456) (xy 310.947692 11.03948) (xy 310.865216 11.016013)
			(xy 310.780926 11.000257) (xy 310.695543 10.992345) (xy 310.609793 10.992345) (xy 310.52441 11.000257)
			(xy 310.44012 11.016013) (xy 310.357644 11.03948) (xy 310.277685 11.070456) (xy 310.200925 11.108678)
			(xy 310.128019 11.153819) (xy 310.05959 11.205495) (xy 309.99622 11.263264) (xy 309.938451 11.326634)
			(xy 309.886775 11.395063) (xy 309.841634 11.467969) (xy 309.803412 11.544729) (xy 309.772436 11.624688)
			(xy 309.748969 11.707164) (xy 309.733213 11.791454) (xy 309.725301 11.876837) (xy 259.72979 11.876837)
			(xy 259.729491 11.850929) (xy 259.721579 11.765546) (xy 259.705823 11.681256) (xy 259.682356 11.59878)
			(xy 259.65138 11.518821) (xy 259.613158 11.442061) (xy 259.568017 11.369155) (xy 259.516341 11.300726)
			(xy 259.458572 11.237356) (xy 259.395202 11.179587) (xy 259.326773 11.127911) (xy 259.253867 11.08277)
			(xy 259.177107 11.044548) (xy 259.097148 11.013572) (xy 259.014672 10.990105) (xy 258.930382 10.974349)
			(xy 258.844999 10.966437) (xy 258.759249 10.966437) (xy 258.673866 10.974349) (xy 258.589576 10.990105)
			(xy 258.5071 11.013572) (xy 258.427141 11.044548) (xy 258.350381 11.08277) (xy 258.277475 11.127911)
			(xy 258.209046 11.179587) (xy 258.145676 11.237356) (xy 258.087907 11.300726) (xy 258.036231 11.369155)
			(xy 257.99109 11.442061) (xy 257.952868 11.518821) (xy 257.921892 11.59878) (xy 257.898425 11.681256)
			(xy 257.882669 11.765546) (xy 257.874757 11.850929) (xy 253.379491 11.850929) (xy 253.371579 11.765546)
			(xy 253.355823 11.681256) (xy 253.332356 11.59878) (xy 253.30138 11.518821) (xy 253.263158 11.442061)
			(xy 253.218017 11.369155) (xy 253.166341 11.300726) (xy 253.108572 11.237356) (xy 253.045202 11.179587)
			(xy 252.976773 11.127911) (xy 252.903867 11.08277) (xy 252.827107 11.044548) (xy 252.747148 11.013572)
			(xy 252.664672 10.990105) (xy 252.580382 10.974349) (xy 252.494999 10.966437) (xy 252.409249 10.966437)
			(xy 252.323866 10.974349) (xy 252.239576 10.990105) (xy 252.1571 11.013572) (xy 252.077141 11.044548)
			(xy 252.000381 11.08277) (xy 251.927475 11.127911) (xy 251.859046 11.179587) (xy 251.795676 11.237356)
			(xy 251.737907 11.300726) (xy 251.686231 11.369155) (xy 251.64109 11.442061) (xy 251.602868 11.518821)
			(xy 251.571892 11.59878) (xy 251.548425 11.681256) (xy 251.532669 11.765546) (xy 251.524757 11.850929)
			(xy 158.621984 11.850929) (xy 158.621984 9.310929) (xy 179.515757 9.310929) (xy 179.515757 9.396679)
			(xy 179.523669 9.482062) (xy 179.539425 9.566352) (xy 179.562892 9.648828) (xy 179.593868 9.728787)
			(xy 179.63209 9.805547) (xy 179.677231 9.878453) (xy 179.728907 9.946882) (xy 179.786676 10.010252)
			(xy 179.850046 10.068021) (xy 179.918475 10.119697) (xy 179.991381 10.164838) (xy 180.068141 10.20306)
			(xy 180.1481 10.234036) (xy 180.230576 10.257503) (xy 180.314866 10.273259) (xy 180.400249 10.281171)
			(xy 180.485999 10.281171) (xy 180.571382 10.273259) (xy 180.655672 10.257503) (xy 180.738148 10.234036)
			(xy 180.818107 10.20306) (xy 180.894867 10.164838) (xy 180.967773 10.119697) (xy 181.036202 10.068021)
			(xy 181.099572 10.010252) (xy 181.157341 9.946882) (xy 181.209017 9.878453) (xy 181.254158 9.805547)
			(xy 181.29238 9.728787) (xy 181.323356 9.648828) (xy 181.346823 9.566352) (xy 181.362579 9.482062)
			(xy 181.370491 9.396679) (xy 181.370986 9.353804) (xy 181.370491 9.310929) (xy 185.865757 9.310929)
			(xy 185.865757 9.396679) (xy 185.873669 9.482062) (xy 185.889425 9.566352) (xy 185.912892 9.648828)
			(xy 185.943868 9.728787) (xy 185.98209 9.805547) (xy 186.027231 9.878453) (xy 186.078907 9.946882)
			(xy 186.136676 10.010252) (xy 186.200046 10.068021) (xy 186.268475 10.119697) (xy 186.341381 10.164838)
			(xy 186.418141 10.20306) (xy 186.4981 10.234036) (xy 186.580576 10.257503) (xy 186.664866 10.273259)
			(xy 186.750249 10.281171) (xy 186.835999 10.281171) (xy 186.921382 10.273259) (xy 187.005672 10.257503)
			(xy 187.088148 10.234036) (xy 187.168107 10.20306) (xy 187.244867 10.164838) (xy 187.317773 10.119697)
			(xy 187.386202 10.068021) (xy 187.449572 10.010252) (xy 187.507341 9.946882) (xy 187.559017 9.878453)
			(xy 187.604158 9.805547) (xy 187.64238 9.728787) (xy 187.673356 9.648828) (xy 187.696823 9.566352)
			(xy 187.712579 9.482062) (xy 187.720491 9.396679) (xy 187.720986 9.353804) (xy 187.720491 9.310929)
			(xy 187.719832 9.303817) (xy 237.716301 9.303817) (xy 237.716301 9.389567) (xy 237.724213 9.47495)
			(xy 237.739969 9.55924) (xy 237.763436 9.641716) (xy 237.794412 9.721675) (xy 237.832634 9.798435)
			(xy 237.877775 9.871341) (xy 237.929451 9.93977) (xy 237.98722 10.00314) (xy 238.05059 10.060909)
			(xy 238.119019 10.112585) (xy 238.191925 10.157726) (xy 238.268685 10.195948) (xy 238.348644 10.226924)
			(xy 238.43112 10.250391) (xy 238.51541 10.266147) (xy 238.600793 10.274059) (xy 238.686543 10.274059)
			(xy 238.771926 10.266147) (xy 238.856216 10.250391) (xy 238.938692 10.226924) (xy 239.018651 10.195948)
			(xy 239.095411 10.157726) (xy 239.168317 10.112585) (xy 239.236746 10.060909) (xy 239.300116 10.00314)
			(xy 239.357885 9.93977) (xy 239.409561 9.871341) (xy 239.454702 9.798435) (xy 239.492924 9.721675)
			(xy 239.5239 9.641716) (xy 239.547367 9.55924) (xy 239.563123 9.47495) (xy 239.571035 9.389567) (xy 239.57153 9.346692)
			(xy 239.571035 9.303817) (xy 244.066301 9.303817) (xy 244.066301 9.389567) (xy 244.074213 9.47495)
			(xy 244.089969 9.55924) (xy 244.113436 9.641716) (xy 244.144412 9.721675) (xy 244.182634 9.798435)
			(xy 244.227775 9.871341) (xy 244.279451 9.93977) (xy 244.33722 10.00314) (xy 244.40059 10.060909)
			(xy 244.469019 10.112585) (xy 244.541925 10.157726) (xy 244.618685 10.195948) (xy 244.698644 10.226924)
			(xy 244.78112 10.250391) (xy 244.86541 10.266147) (xy 244.950793 10.274059) (xy 245.036543 10.274059)
			(xy 245.121926 10.266147) (xy 245.206216 10.250391) (xy 245.288692 10.226924) (xy 245.368651 10.195948)
			(xy 245.445411 10.157726) (xy 245.518317 10.112585) (xy 245.586746 10.060909) (xy 245.650116 10.00314)
			(xy 245.707885 9.93977) (xy 245.759561 9.871341) (xy 245.804702 9.798435) (xy 245.842924 9.721675)
			(xy 245.8739 9.641716) (xy 245.897367 9.55924) (xy 245.913123 9.47495) (xy 245.921035 9.389567) (xy 245.92153 9.346692)
			(xy 245.921117 9.310929) (xy 251.524757 9.310929) (xy 251.524757 9.396679) (xy 251.532669 9.482062)
			(xy 251.548425 9.566352) (xy 251.571892 9.648828) (xy 251.602868 9.728787) (xy 251.64109 9.805547)
			(xy 251.686231 9.878453) (xy 251.737907 9.946882) (xy 251.795676 10.010252) (xy 251.859046 10.068021)
			(xy 251.927475 10.119697) (xy 252.000381 10.164838) (xy 252.077141 10.20306) (xy 252.1571 10.234036)
			(xy 252.239576 10.257503) (xy 252.323866 10.273259) (xy 252.409249 10.281171) (xy 252.494999 10.281171)
			(xy 252.580382 10.273259) (xy 252.664672 10.257503) (xy 252.747148 10.234036) (xy 252.827107 10.20306)
			(xy 252.84931 10.192004) (xy 256.459736 10.192004) (xy 256.459736 11.055604) (xy 256.460222 11.082873)
			(xy 256.467984 11.136857) (xy 256.483349 11.189187) (xy 256.506006 11.238797) (xy 256.535492 11.284678)
			(xy 256.571207 11.325895) (xy 256.612424 11.36161) (xy 256.658305 11.391096) (xy 256.707915 11.413753)
			(xy 256.760245 11.429118) (xy 256.814229 11.43688) (xy 256.868767 11.43688) (xy 256.922751 11.429118)
			(xy 256.975081 11.413753) (xy 257.024691 11.391096) (xy 257.070572 11.36161) (xy 257.111789 11.325895)
			(xy 257.147504 11.284678) (xy 257.17699 11.238797) (xy 257.199647 11.189187) (xy 257.215012 11.136857)
			(xy 257.222774 11.082873) (xy 257.22326 11.055604) (xy 257.22326 10.192004) (xy 257.222774 10.164735)
			(xy 257.215012 10.110751) (xy 257.199647 10.058421) (xy 257.17699 10.008811) (xy 257.147504 9.96293)
			(xy 257.111789 9.921713) (xy 257.070572 9.885998) (xy 257.024691 9.856512) (xy 256.975081 9.833855)
			(xy 256.922751 9.81849) (xy 256.868767 9.810728) (xy 256.814229 9.810728) (xy 256.760245 9.81849)
			(xy 256.707915 9.833855) (xy 256.658305 9.856512) (xy 256.612424 9.885998) (xy 256.571207 9.921713)
			(xy 256.535492 9.96293) (xy 256.506006 10.008811) (xy 256.483349 10.058421) (xy 256.467984 10.110751)
			(xy 256.460222 10.164735) (xy 256.459736 10.192004) (xy 252.84931 10.192004) (xy 252.903867 10.164838)
			(xy 252.976773 10.119697) (xy 253.045202 10.068021) (xy 253.108572 10.010252) (xy 253.166341 9.946882)
			(xy 253.218017 9.878453) (xy 253.263158 9.805547) (xy 253.30138 9.728787) (xy 253.332356 9.648828)
			(xy 253.355823 9.566352) (xy 253.371579 9.482062) (xy 253.379491 9.396679) (xy 253.379986 9.353804)
			(xy 253.379491 9.310929) (xy 257.874757 9.310929) (xy 257.874757 9.396679) (xy 257.882669 9.482062)
			(xy 257.898425 9.566352) (xy 257.921892 9.648828) (xy 257.952868 9.728787) (xy 257.99109 9.805547)
			(xy 258.036231 9.878453) (xy 258.087907 9.946882) (xy 258.145676 10.010252) (xy 258.209046 10.068021)
			(xy 258.277475 10.119697) (xy 258.350381 10.164838) (xy 258.427141 10.20306) (xy 258.5071 10.234036)
			(xy 258.589576 10.257503) (xy 258.673866 10.273259) (xy 258.759249 10.281171) (xy 258.844999 10.281171)
			(xy 258.930382 10.273259) (xy 259.014672 10.257503) (xy 259.097148 10.234036) (xy 259.177107 10.20306)
			(xy 259.253867 10.164838) (xy 259.326773 10.119697) (xy 259.395202 10.068021) (xy 259.458572 10.010252)
			(xy 259.516341 9.946882) (xy 259.568017 9.878453) (xy 259.613158 9.805547) (xy 259.65138 9.728787)
			(xy 259.682356 9.648828) (xy 259.705823 9.566352) (xy 259.721579 9.482062) (xy 259.729491 9.396679)
			(xy 259.729986 9.353804) (xy 259.72979 9.336837) (xy 309.725301 9.336837) (xy 309.725301 9.422587)
			(xy 309.733213 9.50797) (xy 309.748969 9.59226) (xy 309.772436 9.674736) (xy 309.803412 9.754695)
			(xy 309.841634 9.831455) (xy 309.886775 9.904361) (xy 309.938451 9.97279) (xy 309.99622 10.03616)
			(xy 310.05959 10.093929) (xy 310.128019 10.145605) (xy 310.200925 10.190746) (xy 310.277685 10.228968)
			(xy 310.357644 10.259944) (xy 310.44012 10.283411) (xy 310.52441 10.299167) (xy 310.609793 10.307079)
			(xy 310.695543 10.307079) (xy 310.780926 10.299167) (xy 310.865216 10.283411) (xy 310.947692 10.259944)
			(xy 311.027651 10.228968) (xy 311.049854 10.217912) (xy 312.231532 10.217912) (xy 312.231532 11.081512)
			(xy 312.232018 11.108781) (xy 312.23978 11.162765) (xy 312.255145 11.215095) (xy 312.277802 11.264705)
			(xy 312.307288 11.310586) (xy 312.343003 11.351803) (xy 312.38422 11.387518) (xy 312.430101 11.417004)
			(xy 312.479711 11.439661) (xy 312.532041 11.455026) (xy 312.586025 11.462788) (xy 312.640563 11.462788)
			(xy 312.694547 11.455026) (xy 312.746877 11.439661) (xy 312.796487 11.417004) (xy 312.842368 11.387518)
			(xy 312.883585 11.351803) (xy 312.9193 11.310586) (xy 312.948786 11.264705) (xy 312.971443 11.215095)
			(xy 312.986808 11.162765) (xy 312.99457 11.108781) (xy 312.995056 11.081512) (xy 312.995056 10.217912)
			(xy 312.99457 10.190643) (xy 312.986808 10.136659) (xy 312.971443 10.084329) (xy 312.948786 10.034719)
			(xy 312.9193 9.988838) (xy 312.883585 9.947621) (xy 312.842368 9.911906) (xy 312.796487 9.88242)
			(xy 312.746877 9.859763) (xy 312.694547 9.844398) (xy 312.640563 9.836636) (xy 312.586025 9.836636)
			(xy 312.532041 9.844398) (xy 312.479711 9.859763) (xy 312.430101 9.88242) (xy 312.38422 9.911906)
			(xy 312.343003 9.947621) (xy 312.307288 9.988838) (xy 312.277802 10.034719) (xy 312.255145 10.084329)
			(xy 312.23978 10.136659) (xy 312.232018 10.190643) (xy 312.231532 10.217912) (xy 311.049854 10.217912)
			(xy 311.104411 10.190746) (xy 311.177317 10.145605) (xy 311.245746 10.093929) (xy 311.309116 10.03616)
			(xy 311.366885 9.97279) (xy 311.418561 9.904361) (xy 311.463702 9.831455) (xy 311.501924 9.754695)
			(xy 311.5329 9.674736) (xy 311.556367 9.59226) (xy 311.572123 9.50797) (xy 311.580035 9.422587) (xy 311.58053 9.379712)
			(xy 311.580035 9.336837) (xy 316.075301 9.336837) (xy 316.075301 9.422587) (xy 316.083213 9.50797)
			(xy 316.098969 9.59226) (xy 316.122436 9.674736) (xy 316.153412 9.754695) (xy 316.191634 9.831455)
			(xy 316.236775 9.904361) (xy 316.288451 9.97279) (xy 316.34622 10.03616) (xy 316.40959 10.093929)
			(xy 316.478019 10.145605) (xy 316.550925 10.190746) (xy 316.627685 10.228968) (xy 316.707644 10.259944)
			(xy 316.79012 10.283411) (xy 316.87441 10.299167) (xy 316.959793 10.307079) (xy 317.045543 10.307079)
			(xy 317.130926 10.299167) (xy 317.215216 10.283411) (xy 317.297692 10.259944) (xy 317.377651 10.228968)
			(xy 317.454411 10.190746) (xy 317.527317 10.145605) (xy 317.595746 10.093929) (xy 317.659116 10.03616)
			(xy 317.716885 9.97279) (xy 317.768561 9.904361) (xy 317.813702 9.831455) (xy 317.851924 9.754695)
			(xy 317.8829 9.674736) (xy 317.906367 9.59226) (xy 317.922123 9.50797) (xy 317.930035 9.422587) (xy 317.93053 9.379712)
			(xy 317.930117 9.343949) (xy 324.295757 9.343949) (xy 324.295757 9.429699) (xy 324.303669 9.515082)
			(xy 324.319425 9.599372) (xy 324.342892 9.681848) (xy 324.373868 9.761807) (xy 324.41209 9.838567)
			(xy 324.457231 9.911473) (xy 324.508907 9.979902) (xy 324.566676 10.043272) (xy 324.630046 10.101041)
			(xy 324.698475 10.152717) (xy 324.771381 10.197858) (xy 324.848141 10.23608) (xy 324.9281 10.267056)
			(xy 325.010576 10.290523) (xy 325.094866 10.306279) (xy 325.180249 10.314191) (xy 325.265999 10.314191)
			(xy 325.351382 10.306279) (xy 325.435672 10.290523) (xy 325.518148 10.267056) (xy 325.598107 10.23608)
			(xy 325.62031 10.225024) (xy 329.230736 10.225024) (xy 329.230736 11.088624) (xy 329.231222 11.115893)
			(xy 329.238984 11.169877) (xy 329.254349 11.222207) (xy 329.277006 11.271817) (xy 329.306492 11.317698)
			(xy 329.342207 11.358915) (xy 329.383424 11.39463) (xy 329.429305 11.424116) (xy 329.478915 11.446773)
			(xy 329.531245 11.462138) (xy 329.585229 11.4699) (xy 329.639767 11.4699) (xy 329.693751 11.462138)
			(xy 329.746081 11.446773) (xy 329.795691 11.424116) (xy 329.841572 11.39463) (xy 329.882789 11.358915)
			(xy 329.918504 11.317698) (xy 329.94799 11.271817) (xy 329.970647 11.222207) (xy 329.986012 11.169877)
			(xy 329.993774 11.115893) (xy 329.99426 11.088624) (xy 329.99426 10.225024) (xy 329.993774 10.197755)
			(xy 329.986012 10.143771) (xy 329.970647 10.091441) (xy 329.94799 10.041831) (xy 329.918504 9.99595)
			(xy 329.882789 9.954733) (xy 329.841572 9.919018) (xy 329.795691 9.889532) (xy 329.746081 9.866875)
			(xy 329.693751 9.85151) (xy 329.639767 9.843748) (xy 329.585229 9.843748) (xy 329.531245 9.85151)
			(xy 329.478915 9.866875) (xy 329.429305 9.889532) (xy 329.383424 9.919018) (xy 329.342207 9.954733)
			(xy 329.306492 9.99595) (xy 329.277006 10.041831) (xy 329.254349 10.091441) (xy 329.238984 10.143771)
			(xy 329.231222 10.197755) (xy 329.230736 10.225024) (xy 325.62031 10.225024) (xy 325.674867 10.197858)
			(xy 325.747773 10.152717) (xy 325.816202 10.101041) (xy 325.879572 10.043272) (xy 325.937341 9.979902)
			(xy 325.989017 9.911473) (xy 326.034158 9.838567) (xy 326.07238 9.761807) (xy 326.103356 9.681848)
			(xy 326.126823 9.599372) (xy 326.142579 9.515082) (xy 326.150491 9.429699) (xy 326.150986 9.386824)
			(xy 326.150491 9.343949) (xy 330.645757 9.343949) (xy 330.645757 9.429699) (xy 330.653669 9.515082)
			(xy 330.669425 9.599372) (xy 330.692892 9.681848) (xy 330.723868 9.761807) (xy 330.76209 9.838567)
			(xy 330.807231 9.911473) (xy 330.858907 9.979902) (xy 330.916676 10.043272) (xy 330.980046 10.101041)
			(xy 331.048475 10.152717) (xy 331.121381 10.197858) (xy 331.198141 10.23608) (xy 331.2781 10.267056)
			(xy 331.360576 10.290523) (xy 331.444866 10.306279) (xy 331.530249 10.314191) (xy 331.615999 10.314191)
			(xy 331.701382 10.306279) (xy 331.785672 10.290523) (xy 331.868148 10.267056) (xy 331.948107 10.23608)
			(xy 332.024867 10.197858) (xy 332.097773 10.152717) (xy 332.166202 10.101041) (xy 332.229572 10.043272)
			(xy 332.287341 9.979902) (xy 332.339017 9.911473) (xy 332.384158 9.838567) (xy 332.42238 9.761807)
			(xy 332.453356 9.681848) (xy 332.476823 9.599372) (xy 332.492579 9.515082) (xy 332.500491 9.429699)
			(xy 332.500986 9.386824) (xy 332.50079 9.369857) (xy 382.496301 9.369857) (xy 382.496301 9.455607)
			(xy 382.504213 9.54099) (xy 382.519969 9.62528) (xy 382.543436 9.707756) (xy 382.574412 9.787715)
			(xy 382.612634 9.864475) (xy 382.657775 9.937381) (xy 382.709451 10.00581) (xy 382.76722 10.06918)
			(xy 382.83059 10.126949) (xy 382.899019 10.178625) (xy 382.971925 10.223766) (xy 383.048685 10.261988)
			(xy 383.128644 10.292964) (xy 383.21112 10.316431) (xy 383.29541 10.332187) (xy 383.380793 10.340099)
			(xy 383.466543 10.340099) (xy 383.551926 10.332187) (xy 383.636216 10.316431) (xy 383.718692 10.292964)
			(xy 383.798651 10.261988) (xy 383.820854 10.250932) (xy 385.002532 10.250932) (xy 385.002532 11.114532)
			(xy 385.003018 11.141801) (xy 385.01078 11.195785) (xy 385.026145 11.248115) (xy 385.048802 11.297725)
			(xy 385.078288 11.343606) (xy 385.114003 11.384823) (xy 385.15522 11.420538) (xy 385.201101 11.450024)
			(xy 385.250711 11.472681) (xy 385.303041 11.488046) (xy 385.357025 11.495808) (xy 385.411563 11.495808)
			(xy 385.465547 11.488046) (xy 385.517877 11.472681) (xy 385.567487 11.450024) (xy 385.613368 11.420538)
			(xy 385.654585 11.384823) (xy 385.6903 11.343606) (xy 385.719786 11.297725) (xy 385.742443 11.248115)
			(xy 385.757808 11.195785) (xy 385.76557 11.141801) (xy 385.766056 11.114532) (xy 385.766056 10.250932)
			(xy 385.76557 10.223663) (xy 385.757808 10.169679) (xy 385.742443 10.117349) (xy 385.719786 10.067739)
			(xy 385.6903 10.021858) (xy 385.654585 9.980641) (xy 385.613368 9.944926) (xy 385.567487 9.91544)
			(xy 385.517877 9.892783) (xy 385.465547 9.877418) (xy 385.411563 9.869656) (xy 385.357025 9.869656)
			(xy 385.303041 9.877418) (xy 385.250711 9.892783) (xy 385.201101 9.91544) (xy 385.15522 9.944926)
			(xy 385.114003 9.980641) (xy 385.078288 10.021858) (xy 385.048802 10.067739) (xy 385.026145 10.117349)
			(xy 385.01078 10.169679) (xy 385.003018 10.223663) (xy 385.002532 10.250932) (xy 383.820854 10.250932)
			(xy 383.875411 10.223766) (xy 383.948317 10.178625) (xy 384.016746 10.126949) (xy 384.080116 10.06918)
			(xy 384.137885 10.00581) (xy 384.189561 9.937381) (xy 384.234702 9.864475) (xy 384.272924 9.787715)
			(xy 384.3039 9.707756) (xy 384.327367 9.62528) (xy 384.343123 9.54099) (xy 384.351035 9.455607) (xy 384.35153 9.412732)
			(xy 384.351035 9.369857) (xy 388.846301 9.369857) (xy 388.846301 9.455607) (xy 388.854213 9.54099)
			(xy 388.869969 9.62528) (xy 388.893436 9.707756) (xy 388.924412 9.787715) (xy 388.962634 9.864475)
			(xy 389.007775 9.937381) (xy 389.059451 10.00581) (xy 389.11722 10.06918) (xy 389.18059 10.126949)
			(xy 389.249019 10.178625) (xy 389.321925 10.223766) (xy 389.398685 10.261988) (xy 389.478644 10.292964)
			(xy 389.56112 10.316431) (xy 389.64541 10.332187) (xy 389.730793 10.340099) (xy 389.816543 10.340099)
			(xy 389.901926 10.332187) (xy 389.986216 10.316431) (xy 390.068692 10.292964) (xy 390.148651 10.261988)
			(xy 390.225411 10.223766) (xy 390.298317 10.178625) (xy 390.366746 10.126949) (xy 390.430116 10.06918)
			(xy 390.487885 10.00581) (xy 390.539561 9.937381) (xy 390.584702 9.864475) (xy 390.622924 9.787715)
			(xy 390.6539 9.707756) (xy 390.677367 9.62528) (xy 390.693123 9.54099) (xy 390.701035 9.455607) (xy 390.70153 9.412732)
			(xy 390.701117 9.376969) (xy 396.558757 9.376969) (xy 396.558757 9.462719) (xy 396.566669 9.548102)
			(xy 396.582425 9.632392) (xy 396.605892 9.714868) (xy 396.636868 9.794827) (xy 396.67509 9.871587)
			(xy 396.720231 9.944493) (xy 396.771907 10.012922) (xy 396.829676 10.076292) (xy 396.893046 10.134061)
			(xy 396.961475 10.185737) (xy 397.034381 10.230878) (xy 397.111141 10.2691) (xy 397.1911 10.300076)
			(xy 397.273576 10.323543) (xy 397.357866 10.339299) (xy 397.443249 10.347211) (xy 397.528999 10.347211)
			(xy 397.614382 10.339299) (xy 397.698672 10.323543) (xy 397.781148 10.300076) (xy 397.861107 10.2691)
			(xy 397.88331 10.258044) (xy 401.493736 10.258044) (xy 401.493736 11.121644) (xy 401.494222 11.148913)
			(xy 401.501984 11.202897) (xy 401.517349 11.255227) (xy 401.540006 11.304837) (xy 401.569492 11.350718)
			(xy 401.605207 11.391935) (xy 401.646424 11.42765) (xy 401.692305 11.457136) (xy 401.741915 11.479793)
			(xy 401.794245 11.495158) (xy 401.848229 11.50292) (xy 401.902767 11.50292) (xy 401.956751 11.495158)
			(xy 402.009081 11.479793) (xy 402.058691 11.457136) (xy 402.104572 11.42765) (xy 402.145789 11.391935)
			(xy 402.181504 11.350718) (xy 402.21099 11.304837) (xy 402.233647 11.255227) (xy 402.249012 11.202897)
			(xy 402.256774 11.148913) (xy 402.25726 11.121644) (xy 402.25726 10.258044) (xy 402.256774 10.230775)
			(xy 402.249012 10.176791) (xy 402.233647 10.124461) (xy 402.21099 10.074851) (xy 402.181504 10.02897)
			(xy 402.145789 9.987753) (xy 402.104572 9.952038) (xy 402.058691 9.922552) (xy 402.009081 9.899895)
			(xy 401.956751 9.88453) (xy 401.902767 9.876768) (xy 401.848229 9.876768) (xy 401.794245 9.88453)
			(xy 401.741915 9.899895) (xy 401.692305 9.922552) (xy 401.646424 9.952038) (xy 401.605207 9.987753)
			(xy 401.569492 10.02897) (xy 401.540006 10.074851) (xy 401.517349 10.124461) (xy 401.501984 10.176791)
			(xy 401.494222 10.230775) (xy 401.493736 10.258044) (xy 397.88331 10.258044) (xy 397.937867 10.230878)
			(xy 398.010773 10.185737) (xy 398.079202 10.134061) (xy 398.142572 10.076292) (xy 398.200341 10.012922)
			(xy 398.252017 9.944493) (xy 398.297158 9.871587) (xy 398.33538 9.794827) (xy 398.366356 9.714868)
			(xy 398.389823 9.632392) (xy 398.405579 9.548102) (xy 398.413491 9.462719) (xy 398.413986 9.419844)
			(xy 398.413491 9.376969) (xy 402.908757 9.376969) (xy 402.908757 9.462719) (xy 402.916669 9.548102)
			(xy 402.932425 9.632392) (xy 402.955892 9.714868) (xy 402.986868 9.794827) (xy 403.02509 9.871587)
			(xy 403.070231 9.944493) (xy 403.121907 10.012922) (xy 403.179676 10.076292) (xy 403.243046 10.134061)
			(xy 403.311475 10.185737) (xy 403.384381 10.230878) (xy 403.461141 10.2691) (xy 403.5411 10.300076)
			(xy 403.623576 10.323543) (xy 403.707866 10.339299) (xy 403.793249 10.347211) (xy 403.878999 10.347211)
			(xy 403.964382 10.339299) (xy 404.048672 10.323543) (xy 404.131148 10.300076) (xy 404.211107 10.2691)
			(xy 404.287867 10.230878) (xy 404.360773 10.185737) (xy 404.429202 10.134061) (xy 404.492572 10.076292)
			(xy 404.550341 10.012922) (xy 404.602017 9.944493) (xy 404.647158 9.871587) (xy 404.68538 9.794827)
			(xy 404.716356 9.714868) (xy 404.739823 9.632392) (xy 404.755579 9.548102) (xy 404.763491 9.462719)
			(xy 404.763986 9.419844) (xy 404.76379 9.402877) (xy 454.759301 9.402877) (xy 454.759301 9.488627)
			(xy 454.767213 9.57401) (xy 454.782969 9.6583) (xy 454.806436 9.740776) (xy 454.837412 9.820735)
			(xy 454.875634 9.897495) (xy 454.920775 9.970401) (xy 454.972451 10.03883) (xy 455.03022 10.1022)
			(xy 455.09359 10.159969) (xy 455.162019 10.211645) (xy 455.234925 10.256786) (xy 455.311685 10.295008)
			(xy 455.391644 10.325984) (xy 455.47412 10.349451) (xy 455.55841 10.365207) (xy 455.643793 10.373119)
			(xy 455.729543 10.373119) (xy 455.814926 10.365207) (xy 455.899216 10.349451) (xy 455.981692 10.325984)
			(xy 456.061651 10.295008) (xy 456.083854 10.283952) (xy 457.265532 10.283952) (xy 457.265532 11.147552)
			(xy 457.266018 11.174821) (xy 457.27378 11.228805) (xy 457.289145 11.281135) (xy 457.311802 11.330745)
			(xy 457.341288 11.376626) (xy 457.377003 11.417843) (xy 457.41822 11.453558) (xy 457.464101 11.483044)
			(xy 457.513711 11.505701) (xy 457.566041 11.521066) (xy 457.620025 11.528828) (xy 457.674563 11.528828)
			(xy 457.728547 11.521066) (xy 457.780877 11.505701) (xy 457.830487 11.483044) (xy 457.876368 11.453558)
			(xy 457.917585 11.417843) (xy 457.9533 11.376626) (xy 457.982786 11.330745) (xy 458.005443 11.281135)
			(xy 458.020808 11.228805) (xy 458.02857 11.174821) (xy 458.029056 11.147552) (xy 458.029056 10.283952)
			(xy 458.02857 10.256683) (xy 458.020808 10.202699) (xy 458.005443 10.150369) (xy 457.982786 10.100759)
			(xy 457.9533 10.054878) (xy 457.917585 10.013661) (xy 457.876368 9.977946) (xy 457.830487 9.94846)
			(xy 457.780877 9.925803) (xy 457.728547 9.910438) (xy 457.674563 9.902676) (xy 457.620025 9.902676)
			(xy 457.566041 9.910438) (xy 457.513711 9.925803) (xy 457.464101 9.94846) (xy 457.41822 9.977946)
			(xy 457.377003 10.013661) (xy 457.341288 10.054878) (xy 457.311802 10.100759) (xy 457.289145 10.150369)
			(xy 457.27378 10.202699) (xy 457.266018 10.256683) (xy 457.265532 10.283952) (xy 456.083854 10.283952)
			(xy 456.138411 10.256786) (xy 456.211317 10.211645) (xy 456.279746 10.159969) (xy 456.343116 10.1022)
			(xy 456.400885 10.03883) (xy 456.452561 9.970401) (xy 456.497702 9.897495) (xy 456.535924 9.820735)
			(xy 456.5669 9.740776) (xy 456.590367 9.6583) (xy 456.606123 9.57401) (xy 456.614035 9.488627) (xy 456.61453 9.445752)
			(xy 456.614035 9.402877) (xy 461.109301 9.402877) (xy 461.109301 9.488627) (xy 461.117213 9.57401)
			(xy 461.132969 9.6583) (xy 461.156436 9.740776) (xy 461.187412 9.820735) (xy 461.225634 9.897495)
			(xy 461.270775 9.970401) (xy 461.322451 10.03883) (xy 461.38022 10.1022) (xy 461.44359 10.159969)
			(xy 461.512019 10.211645) (xy 461.584925 10.256786) (xy 461.661685 10.295008) (xy 461.741644 10.325984)
			(xy 461.82412 10.349451) (xy 461.90841 10.365207) (xy 461.993793 10.373119) (xy 462.079543 10.373119)
			(xy 462.164926 10.365207) (xy 462.249216 10.349451) (xy 462.331692 10.325984) (xy 462.411651 10.295008)
			(xy 462.488411 10.256786) (xy 462.561317 10.211645) (xy 462.629746 10.159969) (xy 462.693116 10.1022)
			(xy 462.750885 10.03883) (xy 462.802561 9.970401) (xy 462.847702 9.897495) (xy 462.885924 9.820735)
			(xy 462.9169 9.740776) (xy 462.940367 9.6583) (xy 462.956123 9.57401) (xy 462.964035 9.488627) (xy 462.96453 9.445752)
			(xy 462.964035 9.402877) (xy 462.956123 9.317494) (xy 462.940367 9.233204) (xy 462.9169 9.150728)
			(xy 462.885924 9.070769) (xy 462.847702 8.994009) (xy 462.802561 8.921103) (xy 462.750885 8.852674)
			(xy 462.693116 8.789304) (xy 462.629746 8.731535) (xy 462.561317 8.679859) (xy 462.488411 8.634718)
			(xy 462.411651 8.596496) (xy 462.331692 8.56552) (xy 462.249216 8.542053) (xy 462.164926 8.526297)
			(xy 462.079543 8.518385) (xy 461.993793 8.518385) (xy 461.90841 8.526297) (xy 461.82412 8.542053)
			(xy 461.741644 8.56552) (xy 461.661685 8.596496) (xy 461.584925 8.634718) (xy 461.512019 8.679859)
			(xy 461.44359 8.731535) (xy 461.38022 8.789304) (xy 461.322451 8.852674) (xy 461.270775 8.921103)
			(xy 461.225634 8.994009) (xy 461.187412 9.070769) (xy 461.156436 9.150728) (xy 461.132969 9.233204)
			(xy 461.117213 9.317494) (xy 461.109301 9.402877) (xy 456.614035 9.402877) (xy 456.606123 9.317494)
			(xy 456.590367 9.233204) (xy 456.5669 9.150728) (xy 456.535924 9.070769) (xy 456.497702 8.994009)
			(xy 456.452561 8.921103) (xy 456.400885 8.852674) (xy 456.343116 8.789304) (xy 456.279746 8.731535)
			(xy 456.211317 8.679859) (xy 456.138411 8.634718) (xy 456.061651 8.596496) (xy 455.981692 8.56552)
			(xy 455.899216 8.542053) (xy 455.814926 8.526297) (xy 455.729543 8.518385) (xy 455.643793 8.518385)
			(xy 455.55841 8.526297) (xy 455.47412 8.542053) (xy 455.391644 8.56552) (xy 455.311685 8.596496)
			(xy 455.234925 8.634718) (xy 455.162019 8.679859) (xy 455.09359 8.731535) (xy 455.03022 8.789304)
			(xy 454.972451 8.852674) (xy 454.920775 8.921103) (xy 454.875634 8.994009) (xy 454.837412 9.070769)
			(xy 454.806436 9.150728) (xy 454.782969 9.233204) (xy 454.767213 9.317494) (xy 454.759301 9.402877)
			(xy 404.76379 9.402877) (xy 404.763491 9.376969) (xy 404.755579 9.291586) (xy 404.739823 9.207296)
			(xy 404.716356 9.12482) (xy 404.68538 9.044861) (xy 404.647158 8.968101) (xy 404.602017 8.895195)
			(xy 404.550341 8.826766) (xy 404.492572 8.763396) (xy 404.429202 8.705627) (xy 404.360773 8.653951)
			(xy 404.287867 8.60881) (xy 404.211107 8.570588) (xy 404.131148 8.539612) (xy 404.048672 8.516145)
			(xy 403.964382 8.500389) (xy 403.878999 8.492477) (xy 403.793249 8.492477) (xy 403.707866 8.500389)
			(xy 403.623576 8.516145) (xy 403.5411 8.539612) (xy 403.461141 8.570588) (xy 403.384381 8.60881)
			(xy 403.311475 8.653951) (xy 403.243046 8.705627) (xy 403.179676 8.763396) (xy 403.121907 8.826766)
			(xy 403.070231 8.895195) (xy 403.02509 8.968101) (xy 402.986868 9.044861) (xy 402.955892 9.12482)
			(xy 402.932425 9.207296) (xy 402.916669 9.291586) (xy 402.908757 9.376969) (xy 398.413491 9.376969)
			(xy 398.405579 9.291586) (xy 398.389823 9.207296) (xy 398.366356 9.12482) (xy 398.33538 9.044861)
			(xy 398.297158 8.968101) (xy 398.252017 8.895195) (xy 398.200341 8.826766) (xy 398.142572 8.763396)
			(xy 398.079202 8.705627) (xy 398.010773 8.653951) (xy 397.937867 8.60881) (xy 397.861107 8.570588)
			(xy 397.781148 8.539612) (xy 397.698672 8.516145) (xy 397.614382 8.500389) (xy 397.528999 8.492477)
			(xy 397.443249 8.492477) (xy 397.357866 8.500389) (xy 397.273576 8.516145) (xy 397.1911 8.539612)
			(xy 397.111141 8.570588) (xy 397.034381 8.60881) (xy 396.961475 8.653951) (xy 396.893046 8.705627)
			(xy 396.829676 8.763396) (xy 396.771907 8.826766) (xy 396.720231 8.895195) (xy 396.67509 8.968101)
			(xy 396.636868 9.044861) (xy 396.605892 9.12482) (xy 396.582425 9.207296) (xy 396.566669 9.291586)
			(xy 396.558757 9.376969) (xy 390.701117 9.376969) (xy 390.701035 9.369857) (xy 390.693123 9.284474)
			(xy 390.677367 9.200184) (xy 390.6539 9.117708) (xy 390.622924 9.037749) (xy 390.584702 8.960989)
			(xy 390.539561 8.888083) (xy 390.487885 8.819654) (xy 390.430116 8.756284) (xy 390.366746 8.698515)
			(xy 390.298317 8.646839) (xy 390.225411 8.601698) (xy 390.148651 8.563476) (xy 390.068692 8.5325)
			(xy 389.986216 8.509033) (xy 389.901926 8.493277) (xy 389.816543 8.485365) (xy 389.730793 8.485365)
			(xy 389.64541 8.493277) (xy 389.56112 8.509033) (xy 389.478644 8.5325) (xy 389.398685 8.563476) (xy 389.321925 8.601698)
			(xy 389.249019 8.646839) (xy 389.18059 8.698515) (xy 389.11722 8.756284) (xy 389.059451 8.819654)
			(xy 389.007775 8.888083) (xy 388.962634 8.960989) (xy 388.924412 9.037749) (xy 388.893436 9.117708)
			(xy 388.869969 9.200184) (xy 388.854213 9.284474) (xy 388.846301 9.369857) (xy 384.351035 9.369857)
			(xy 384.343123 9.284474) (xy 384.327367 9.200184) (xy 384.3039 9.117708) (xy 384.272924 9.037749)
			(xy 384.234702 8.960989) (xy 384.189561 8.888083) (xy 384.137885 8.819654) (xy 384.080116 8.756284)
			(xy 384.016746 8.698515) (xy 383.948317 8.646839) (xy 383.875411 8.601698) (xy 383.798651 8.563476)
			(xy 383.718692 8.5325) (xy 383.636216 8.509033) (xy 383.551926 8.493277) (xy 383.466543 8.485365)
			(xy 383.380793 8.485365) (xy 383.29541 8.493277) (xy 383.21112 8.509033) (xy 383.128644 8.5325) (xy 383.048685 8.563476)
			(xy 382.971925 8.601698) (xy 382.899019 8.646839) (xy 382.83059 8.698515) (xy 382.76722 8.756284)
			(xy 382.709451 8.819654) (xy 382.657775 8.888083) (xy 382.612634 8.960989) (xy 382.574412 9.037749)
			(xy 382.543436 9.117708) (xy 382.519969 9.200184) (xy 382.504213 9.284474) (xy 382.496301 9.369857)
			(xy 332.50079 9.369857) (xy 332.500491 9.343949) (xy 332.492579 9.258566) (xy 332.476823 9.174276)
			(xy 332.453356 9.0918) (xy 332.42238 9.011841) (xy 332.384158 8.935081) (xy 332.339017 8.862175)
			(xy 332.287341 8.793746) (xy 332.229572 8.730376) (xy 332.166202 8.672607) (xy 332.097773 8.620931)
			(xy 332.024867 8.57579) (xy 331.948107 8.537568) (xy 331.868148 8.506592) (xy 331.785672 8.483125)
			(xy 331.701382 8.467369) (xy 331.615999 8.459457) (xy 331.530249 8.459457) (xy 331.444866 8.467369)
			(xy 331.360576 8.483125) (xy 331.2781 8.506592) (xy 331.198141 8.537568) (xy 331.121381 8.57579)
			(xy 331.048475 8.620931) (xy 330.980046 8.672607) (xy 330.916676 8.730376) (xy 330.858907 8.793746)
			(xy 330.807231 8.862175) (xy 330.76209 8.935081) (xy 330.723868 9.011841) (xy 330.692892 9.0918)
			(xy 330.669425 9.174276) (xy 330.653669 9.258566) (xy 330.645757 9.343949) (xy 326.150491 9.343949)
			(xy 326.142579 9.258566) (xy 326.126823 9.174276) (xy 326.103356 9.0918) (xy 326.07238 9.011841)
			(xy 326.034158 8.935081) (xy 325.989017 8.862175) (xy 325.937341 8.793746) (xy 325.879572 8.730376)
			(xy 325.816202 8.672607) (xy 325.747773 8.620931) (xy 325.674867 8.57579) (xy 325.598107 8.537568)
			(xy 325.518148 8.506592) (xy 325.435672 8.483125) (xy 325.351382 8.467369) (xy 325.265999 8.459457)
			(xy 325.180249 8.459457) (xy 325.094866 8.467369) (xy 325.010576 8.483125) (xy 324.9281 8.506592)
			(xy 324.848141 8.537568) (xy 324.771381 8.57579) (xy 324.698475 8.620931) (xy 324.630046 8.672607)
			(xy 324.566676 8.730376) (xy 324.508907 8.793746) (xy 324.457231 8.862175) (xy 324.41209 8.935081)
			(xy 324.373868 9.011841) (xy 324.342892 9.0918) (xy 324.319425 9.174276) (xy 324.303669 9.258566)
			(xy 324.295757 9.343949) (xy 317.930117 9.343949) (xy 317.930035 9.336837) (xy 317.922123 9.251454)
			(xy 317.906367 9.167164) (xy 317.8829 9.084688) (xy 317.851924 9.004729) (xy 317.813702 8.927969)
			(xy 317.768561 8.855063) (xy 317.716885 8.786634) (xy 317.659116 8.723264) (xy 317.595746 8.665495)
			(xy 317.527317 8.613819) (xy 317.454411 8.568678) (xy 317.377651 8.530456) (xy 317.297692 8.49948)
			(xy 317.215216 8.476013) (xy 317.130926 8.460257) (xy 317.045543 8.452345) (xy 316.959793 8.452345)
			(xy 316.87441 8.460257) (xy 316.79012 8.476013) (xy 316.707644 8.49948) (xy 316.627685 8.530456)
			(xy 316.550925 8.568678) (xy 316.478019 8.613819) (xy 316.40959 8.665495) (xy 316.34622 8.723264)
			(xy 316.288451 8.786634) (xy 316.236775 8.855063) (xy 316.191634 8.927969) (xy 316.153412 9.004729)
			(xy 316.122436 9.084688) (xy 316.098969 9.167164) (xy 316.083213 9.251454) (xy 316.075301 9.336837)
			(xy 311.580035 9.336837) (xy 311.572123 9.251454) (xy 311.556367 9.167164) (xy 311.5329 9.084688)
			(xy 311.501924 9.004729) (xy 311.463702 8.927969) (xy 311.418561 8.855063) (xy 311.366885 8.786634)
			(xy 311.309116 8.723264) (xy 311.245746 8.665495) (xy 311.177317 8.613819) (xy 311.104411 8.568678)
			(xy 311.027651 8.530456) (xy 310.947692 8.49948) (xy 310.865216 8.476013) (xy 310.780926 8.460257)
			(xy 310.695543 8.452345) (xy 310.609793 8.452345) (xy 310.52441 8.460257) (xy 310.44012 8.476013)
			(xy 310.357644 8.49948) (xy 310.277685 8.530456) (xy 310.200925 8.568678) (xy 310.128019 8.613819)
			(xy 310.05959 8.665495) (xy 309.99622 8.723264) (xy 309.938451 8.786634) (xy 309.886775 8.855063)
			(xy 309.841634 8.927969) (xy 309.803412 9.004729) (xy 309.772436 9.084688) (xy 309.748969 9.167164)
			(xy 309.733213 9.251454) (xy 309.725301 9.336837) (xy 259.72979 9.336837) (xy 259.729491 9.310929)
			(xy 259.721579 9.225546) (xy 259.705823 9.141256) (xy 259.682356 9.05878) (xy 259.65138 8.978821)
			(xy 259.613158 8.902061) (xy 259.568017 8.829155) (xy 259.516341 8.760726) (xy 259.458572 8.697356)
			(xy 259.395202 8.639587) (xy 259.326773 8.587911) (xy 259.253867 8.54277) (xy 259.177107 8.504548)
			(xy 259.097148 8.473572) (xy 259.014672 8.450105) (xy 258.930382 8.434349) (xy 258.844999 8.426437)
			(xy 258.759249 8.426437) (xy 258.673866 8.434349) (xy 258.589576 8.450105) (xy 258.5071 8.473572)
			(xy 258.427141 8.504548) (xy 258.350381 8.54277) (xy 258.277475 8.587911) (xy 258.209046 8.639587)
			(xy 258.145676 8.697356) (xy 258.087907 8.760726) (xy 258.036231 8.829155) (xy 257.99109 8.902061)
			(xy 257.952868 8.978821) (xy 257.921892 9.05878) (xy 257.898425 9.141256) (xy 257.882669 9.225546)
			(xy 257.874757 9.310929) (xy 253.379491 9.310929) (xy 253.371579 9.225546) (xy 253.355823 9.141256)
			(xy 253.332356 9.05878) (xy 253.30138 8.978821) (xy 253.263158 8.902061) (xy 253.218017 8.829155)
			(xy 253.166341 8.760726) (xy 253.108572 8.697356) (xy 253.045202 8.639587) (xy 252.976773 8.587911)
			(xy 252.903867 8.54277) (xy 252.827107 8.504548) (xy 252.747148 8.473572) (xy 252.664672 8.450105)
			(xy 252.580382 8.434349) (xy 252.494999 8.426437) (xy 252.409249 8.426437) (xy 252.323866 8.434349)
			(xy 252.239576 8.450105) (xy 252.1571 8.473572) (xy 252.077141 8.504548) (xy 252.000381 8.54277)
			(xy 251.927475 8.587911) (xy 251.859046 8.639587) (xy 251.795676 8.697356) (xy 251.737907 8.760726)
			(xy 251.686231 8.829155) (xy 251.64109 8.902061) (xy 251.602868 8.978821) (xy 251.571892 9.05878)
			(xy 251.548425 9.141256) (xy 251.532669 9.225546) (xy 251.524757 9.310929) (xy 245.921117 9.310929)
			(xy 245.921035 9.303817) (xy 245.913123 9.218434) (xy 245.897367 9.134144) (xy 245.8739 9.051668)
			(xy 245.842924 8.971709) (xy 245.804702 8.894949) (xy 245.759561 8.822043) (xy 245.707885 8.753614)
			(xy 245.650116 8.690244) (xy 245.586746 8.632475) (xy 245.518317 8.580799) (xy 245.445411 8.535658)
			(xy 245.368651 8.497436) (xy 245.288692 8.46646) (xy 245.206216 8.442993) (xy 245.121926 8.427237)
			(xy 245.036543 8.419325) (xy 244.950793 8.419325) (xy 244.86541 8.427237) (xy 244.78112 8.442993)
			(xy 244.698644 8.46646) (xy 244.618685 8.497436) (xy 244.541925 8.535658) (xy 244.469019 8.580799)
			(xy 244.40059 8.632475) (xy 244.33722 8.690244) (xy 244.279451 8.753614) (xy 244.227775 8.822043)
			(xy 244.182634 8.894949) (xy 244.144412 8.971709) (xy 244.113436 9.051668) (xy 244.089969 9.134144)
			(xy 244.074213 9.218434) (xy 244.066301 9.303817) (xy 239.571035 9.303817) (xy 239.563123 9.218434)
			(xy 239.547367 9.134144) (xy 239.5239 9.051668) (xy 239.492924 8.971709) (xy 239.454702 8.894949)
			(xy 239.409561 8.822043) (xy 239.357885 8.753614) (xy 239.300116 8.690244) (xy 239.236746 8.632475)
			(xy 239.168317 8.580799) (xy 239.095411 8.535658) (xy 239.018651 8.497436) (xy 238.938692 8.46646)
			(xy 238.856216 8.442993) (xy 238.771926 8.427237) (xy 238.686543 8.419325) (xy 238.600793 8.419325)
			(xy 238.51541 8.427237) (xy 238.43112 8.442993) (xy 238.348644 8.46646) (xy 238.268685 8.497436)
			(xy 238.191925 8.535658) (xy 238.119019 8.580799) (xy 238.05059 8.632475) (xy 237.98722 8.690244)
			(xy 237.929451 8.753614) (xy 237.877775 8.822043) (xy 237.832634 8.894949) (xy 237.794412 8.971709)
			(xy 237.763436 9.051668) (xy 237.739969 9.134144) (xy 237.724213 9.218434) (xy 237.716301 9.303817)
			(xy 187.719832 9.303817) (xy 187.712579 9.225546) (xy 187.696823 9.141256) (xy 187.673356 9.05878)
			(xy 187.64238 8.978821) (xy 187.604158 8.902061) (xy 187.559017 8.829155) (xy 187.507341 8.760726)
			(xy 187.449572 8.697356) (xy 187.386202 8.639587) (xy 187.317773 8.587911) (xy 187.244867 8.54277)
			(xy 187.168107 8.504548) (xy 187.088148 8.473572) (xy 187.005672 8.450105) (xy 186.921382 8.434349)
			(xy 186.835999 8.426437) (xy 186.750249 8.426437) (xy 186.664866 8.434349) (xy 186.580576 8.450105)
			(xy 186.4981 8.473572) (xy 186.418141 8.504548) (xy 186.341381 8.54277) (xy 186.268475 8.587911)
			(xy 186.200046 8.639587) (xy 186.136676 8.697356) (xy 186.078907 8.760726) (xy 186.027231 8.829155)
			(xy 185.98209 8.902061) (xy 185.943868 8.978821) (xy 185.912892 9.05878) (xy 185.889425 9.141256)
			(xy 185.873669 9.225546) (xy 185.865757 9.310929) (xy 181.370491 9.310929) (xy 181.362579 9.225546)
			(xy 181.346823 9.141256) (xy 181.323356 9.05878) (xy 181.29238 8.978821) (xy 181.254158 8.902061)
			(xy 181.209017 8.829155) (xy 181.157341 8.760726) (xy 181.099572 8.697356) (xy 181.036202 8.639587)
			(xy 180.967773 8.587911) (xy 180.894867 8.54277) (xy 180.818107 8.504548) (xy 180.738148 8.473572)
			(xy 180.655672 8.450105) (xy 180.571382 8.434349) (xy 180.485999 8.426437) (xy 180.400249 8.426437)
			(xy 180.314866 8.434349) (xy 180.230576 8.450105) (xy 180.1481 8.473572) (xy 180.068141 8.504548)
			(xy 179.991381 8.54277) (xy 179.918475 8.587911) (xy 179.850046 8.639587) (xy 179.786676 8.697356)
			(xy 179.728907 8.760726) (xy 179.677231 8.829155) (xy 179.63209 8.902061) (xy 179.593868 8.978821)
			(xy 179.562892 9.05878) (xy 179.539425 9.141256) (xy 179.523669 9.225546) (xy 179.515757 9.310929)
			(xy 158.621984 9.310929) (xy 158.621984 8.377682) (xy 158.62149 8.307329) (xy 158.6136 8.166844)
			(xy 158.597845 8.027022) (xy 158.574274 7.888303) (xy 158.542963 7.751125) (xy 158.50401 7.615918)
			(xy 158.457537 7.483107) (xy 158.40369 7.353112) (xy 158.342638 7.22634) (xy 158.274575 7.103191)
			(xy 158.199714 6.984051) (xy 158.11829 6.869297) (xy 158.039844 6.770929) (xy 179.515757 6.770929)
			(xy 179.515757 6.856679) (xy 179.523669 6.942062) (xy 179.539425 7.026352) (xy 179.562892 7.108828)
			(xy 179.593868 7.188787) (xy 179.63209 7.265547) (xy 179.677231 7.338453) (xy 179.728907 7.406882)
			(xy 179.786676 7.470252) (xy 179.850046 7.528021) (xy 179.918475 7.579697) (xy 179.991381 7.624838)
			(xy 180.068141 7.66306) (xy 180.1481 7.694036) (xy 180.230576 7.717503) (xy 180.314866 7.733259)
			(xy 180.400249 7.741171) (xy 180.485999 7.741171) (xy 180.571382 7.733259) (xy 180.655672 7.717503)
			(xy 180.738148 7.694036) (xy 180.818107 7.66306) (xy 180.894867 7.624838) (xy 180.967773 7.579697)
			(xy 181.036202 7.528021) (xy 181.099572 7.470252) (xy 181.157341 7.406882) (xy 181.209017 7.338453)
			(xy 181.254158 7.265547) (xy 181.29238 7.188787) (xy 181.323356 7.108828) (xy 181.346823 7.026352)
			(xy 181.362579 6.942062) (xy 181.370491 6.856679) (xy 181.370986 6.813804) (xy 181.370491 6.770929)
			(xy 185.865757 6.770929) (xy 185.865757 6.856679) (xy 185.873669 6.942062) (xy 185.889425 7.026352)
			(xy 185.912892 7.108828) (xy 185.943868 7.188787) (xy 185.98209 7.265547) (xy 186.027231 7.338453)
			(xy 186.078907 7.406882) (xy 186.136676 7.470252) (xy 186.200046 7.528021) (xy 186.268475 7.579697)
			(xy 186.341381 7.624838) (xy 186.418141 7.66306) (xy 186.4981 7.694036) (xy 186.580576 7.717503)
			(xy 186.664866 7.733259) (xy 186.750249 7.741171) (xy 186.835999 7.741171) (xy 186.921382 7.733259)
			(xy 187.005672 7.717503) (xy 187.088148 7.694036) (xy 187.168107 7.66306) (xy 187.244867 7.624838)
			(xy 187.317773 7.579697) (xy 187.386202 7.528021) (xy 187.449572 7.470252) (xy 187.507341 7.406882)
			(xy 187.559017 7.338453) (xy 187.604158 7.265547) (xy 187.64238 7.188787) (xy 187.673356 7.108828)
			(xy 187.696823 7.026352) (xy 187.712579 6.942062) (xy 187.720491 6.856679) (xy 187.720986 6.813804)
			(xy 187.720491 6.770929) (xy 187.719832 6.763817) (xy 237.716301 6.763817) (xy 237.716301 6.849567)
			(xy 237.724213 6.93495) (xy 237.739969 7.01924) (xy 237.763436 7.101716) (xy 237.794412 7.181675)
			(xy 237.832634 7.258435) (xy 237.877775 7.331341) (xy 237.929451 7.39977) (xy 237.98722 7.46314)
			(xy 238.05059 7.520909) (xy 238.119019 7.572585) (xy 238.191925 7.617726) (xy 238.268685 7.655948)
			(xy 238.348644 7.686924) (xy 238.43112 7.710391) (xy 238.51541 7.726147) (xy 238.600793 7.734059)
			(xy 238.686543 7.734059) (xy 238.771926 7.726147) (xy 238.856216 7.710391) (xy 238.938692 7.686924)
			(xy 239.018651 7.655948) (xy 239.095411 7.617726) (xy 239.168317 7.572585) (xy 239.236746 7.520909)
			(xy 239.300116 7.46314) (xy 239.357885 7.39977) (xy 239.409561 7.331341) (xy 239.454702 7.258435)
			(xy 239.492924 7.181675) (xy 239.5239 7.101716) (xy 239.547367 7.01924) (xy 239.563123 6.93495) (xy 239.571035 6.849567)
			(xy 239.57153 6.806692) (xy 239.571035 6.763817) (xy 244.066301 6.763817) (xy 244.066301 6.849567)
			(xy 244.074213 6.93495) (xy 244.089969 7.01924) (xy 244.113436 7.101716) (xy 244.144412 7.181675)
			(xy 244.182634 7.258435) (xy 244.227775 7.331341) (xy 244.279451 7.39977) (xy 244.33722 7.46314)
			(xy 244.40059 7.520909) (xy 244.469019 7.572585) (xy 244.541925 7.617726) (xy 244.618685 7.655948)
			(xy 244.698644 7.686924) (xy 244.78112 7.710391) (xy 244.86541 7.726147) (xy 244.950793 7.734059)
			(xy 245.036543 7.734059) (xy 245.121926 7.726147) (xy 245.206216 7.710391) (xy 245.288692 7.686924)
			(xy 245.368651 7.655948) (xy 245.445411 7.617726) (xy 245.518317 7.572585) (xy 245.586746 7.520909)
			(xy 245.650116 7.46314) (xy 245.707885 7.39977) (xy 245.759561 7.331341) (xy 245.804702 7.258435)
			(xy 245.842924 7.181675) (xy 245.8739 7.101716) (xy 245.897367 7.01924) (xy 245.913123 6.93495) (xy 245.921035 6.849567)
			(xy 245.92153 6.806692) (xy 245.921117 6.770929) (xy 251.524757 6.770929) (xy 251.524757 6.856679)
			(xy 251.532669 6.942062) (xy 251.548425 7.026352) (xy 251.571892 7.108828) (xy 251.602868 7.188787)
			(xy 251.64109 7.265547) (xy 251.686231 7.338453) (xy 251.737907 7.406882) (xy 251.795676 7.470252)
			(xy 251.859046 7.528021) (xy 251.927475 7.579697) (xy 252.000381 7.624838) (xy 252.077141 7.66306)
			(xy 252.1571 7.694036) (xy 252.239576 7.717503) (xy 252.323866 7.733259) (xy 252.409249 7.741171)
			(xy 252.494999 7.741171) (xy 252.580382 7.733259) (xy 252.664672 7.717503) (xy 252.747148 7.694036)
			(xy 252.827107 7.66306) (xy 252.84931 7.652004) (xy 256.459736 7.652004) (xy 256.459736 8.515604)
			(xy 256.460222 8.542873) (xy 256.467984 8.596857) (xy 256.483349 8.649187) (xy 256.506006 8.698797)
			(xy 256.535492 8.744678) (xy 256.571207 8.785895) (xy 256.612424 8.82161) (xy 256.658305 8.851096)
			(xy 256.707915 8.873753) (xy 256.760245 8.889118) (xy 256.814229 8.89688) (xy 256.868767 8.89688)
			(xy 256.922751 8.889118) (xy 256.975081 8.873753) (xy 257.024691 8.851096) (xy 257.070572 8.82161)
			(xy 257.111789 8.785895) (xy 257.147504 8.744678) (xy 257.17699 8.698797) (xy 257.199647 8.649187)
			(xy 257.215012 8.596857) (xy 257.222774 8.542873) (xy 257.22326 8.515604) (xy 257.22326 7.652004)
			(xy 257.222774 7.624735) (xy 257.215012 7.570751) (xy 257.199647 7.518421) (xy 257.17699 7.468811)
			(xy 257.147504 7.42293) (xy 257.111789 7.381713) (xy 257.070572 7.345998) (xy 257.024691 7.316512)
			(xy 256.975081 7.293855) (xy 256.922751 7.27849) (xy 256.868767 7.270728) (xy 256.814229 7.270728)
			(xy 256.760245 7.27849) (xy 256.707915 7.293855) (xy 256.658305 7.316512) (xy 256.612424 7.345998)
			(xy 256.571207 7.381713) (xy 256.535492 7.42293) (xy 256.506006 7.468811) (xy 256.483349 7.518421)
			(xy 256.467984 7.570751) (xy 256.460222 7.624735) (xy 256.459736 7.652004) (xy 252.84931 7.652004)
			(xy 252.903867 7.624838) (xy 252.976773 7.579697) (xy 253.045202 7.528021) (xy 253.108572 7.470252)
			(xy 253.166341 7.406882) (xy 253.218017 7.338453) (xy 253.263158 7.265547) (xy 253.30138 7.188787)
			(xy 253.332356 7.108828) (xy 253.355823 7.026352) (xy 253.371579 6.942062) (xy 253.379491 6.856679)
			(xy 253.379986 6.813804) (xy 253.379491 6.770929) (xy 257.874757 6.770929) (xy 257.874757 6.856679)
			(xy 257.882669 6.942062) (xy 257.898425 7.026352) (xy 257.921892 7.108828) (xy 257.952868 7.188787)
			(xy 257.99109 7.265547) (xy 258.036231 7.338453) (xy 258.087907 7.406882) (xy 258.145676 7.470252)
			(xy 258.209046 7.528021) (xy 258.277475 7.579697) (xy 258.350381 7.624838) (xy 258.427141 7.66306)
			(xy 258.5071 7.694036) (xy 258.589576 7.717503) (xy 258.673866 7.733259) (xy 258.759249 7.741171)
			(xy 258.844999 7.741171) (xy 258.930382 7.733259) (xy 259.014672 7.717503) (xy 259.097148 7.694036)
			(xy 259.177107 7.66306) (xy 259.253867 7.624838) (xy 259.326773 7.579697) (xy 259.395202 7.528021)
			(xy 259.458572 7.470252) (xy 259.516341 7.406882) (xy 259.568017 7.338453) (xy 259.613158 7.265547)
			(xy 259.65138 7.188787) (xy 259.682356 7.108828) (xy 259.705823 7.026352) (xy 259.721579 6.942062)
			(xy 259.729491 6.856679) (xy 259.729986 6.813804) (xy 259.72979 6.796837) (xy 309.725301 6.796837)
			(xy 309.725301 6.882587) (xy 309.733213 6.96797) (xy 309.748969 7.05226) (xy 309.772436 7.134736)
			(xy 309.803412 7.214695) (xy 309.841634 7.291455) (xy 309.886775 7.364361) (xy 309.938451 7.43279)
			(xy 309.99622 7.49616) (xy 310.05959 7.553929) (xy 310.128019 7.605605) (xy 310.200925 7.650746)
			(xy 310.277685 7.688968) (xy 310.357644 7.719944) (xy 310.44012 7.743411) (xy 310.52441 7.759167)
			(xy 310.609793 7.767079) (xy 310.695543 7.767079) (xy 310.780926 7.759167) (xy 310.865216 7.743411)
			(xy 310.947692 7.719944) (xy 311.027651 7.688968) (xy 311.049854 7.677912) (xy 312.231532 7.677912)
			(xy 312.231532 8.541512) (xy 312.232018 8.568781) (xy 312.23978 8.622765) (xy 312.255145 8.675095)
			(xy 312.277802 8.724705) (xy 312.307288 8.770586) (xy 312.343003 8.811803) (xy 312.38422 8.847518)
			(xy 312.430101 8.877004) (xy 312.479711 8.899661) (xy 312.532041 8.915026) (xy 312.586025 8.922788)
			(xy 312.640563 8.922788) (xy 312.694547 8.915026) (xy 312.746877 8.899661) (xy 312.796487 8.877004)
			(xy 312.842368 8.847518) (xy 312.883585 8.811803) (xy 312.9193 8.770586) (xy 312.948786 8.724705)
			(xy 312.971443 8.675095) (xy 312.986808 8.622765) (xy 312.99457 8.568781) (xy 312.995056 8.541512)
			(xy 312.995056 7.677912) (xy 312.99457 7.650643) (xy 312.986808 7.596659) (xy 312.971443 7.544329)
			(xy 312.948786 7.494719) (xy 312.9193 7.448838) (xy 312.883585 7.407621) (xy 312.842368 7.371906)
			(xy 312.796487 7.34242) (xy 312.746877 7.319763) (xy 312.694547 7.304398) (xy 312.640563 7.296636)
			(xy 312.586025 7.296636) (xy 312.532041 7.304398) (xy 312.479711 7.319763) (xy 312.430101 7.34242)
			(xy 312.38422 7.371906) (xy 312.343003 7.407621) (xy 312.307288 7.448838) (xy 312.277802 7.494719)
			(xy 312.255145 7.544329) (xy 312.23978 7.596659) (xy 312.232018 7.650643) (xy 312.231532 7.677912)
			(xy 311.049854 7.677912) (xy 311.104411 7.650746) (xy 311.177317 7.605605) (xy 311.245746 7.553929)
			(xy 311.309116 7.49616) (xy 311.366885 7.43279) (xy 311.418561 7.364361) (xy 311.463702 7.291455)
			(xy 311.501924 7.214695) (xy 311.5329 7.134736) (xy 311.556367 7.05226) (xy 311.572123 6.96797) (xy 311.580035 6.882587)
			(xy 311.58053 6.839712) (xy 311.580035 6.796837) (xy 316.075301 6.796837) (xy 316.075301 6.882587)
			(xy 316.083213 6.96797) (xy 316.098969 7.05226) (xy 316.122436 7.134736) (xy 316.153412 7.214695)
			(xy 316.191634 7.291455) (xy 316.236775 7.364361) (xy 316.288451 7.43279) (xy 316.34622 7.49616)
			(xy 316.40959 7.553929) (xy 316.478019 7.605605) (xy 316.550925 7.650746) (xy 316.627685 7.688968)
			(xy 316.707644 7.719944) (xy 316.79012 7.743411) (xy 316.87441 7.759167) (xy 316.959793 7.767079)
			(xy 317.045543 7.767079) (xy 317.130926 7.759167) (xy 317.215216 7.743411) (xy 317.297692 7.719944)
			(xy 317.377651 7.688968) (xy 317.454411 7.650746) (xy 317.527317 7.605605) (xy 317.595746 7.553929)
			(xy 317.659116 7.49616) (xy 317.716885 7.43279) (xy 317.768561 7.364361) (xy 317.813702 7.291455)
			(xy 317.851924 7.214695) (xy 317.8829 7.134736) (xy 317.906367 7.05226) (xy 317.922123 6.96797) (xy 317.930035 6.882587)
			(xy 317.93053 6.839712) (xy 317.930117 6.803949) (xy 324.295757 6.803949) (xy 324.295757 6.889699)
			(xy 324.303669 6.975082) (xy 324.319425 7.059372) (xy 324.342892 7.141848) (xy 324.373868 7.221807)
			(xy 324.41209 7.298567) (xy 324.457231 7.371473) (xy 324.508907 7.439902) (xy 324.566676 7.503272)
			(xy 324.630046 7.561041) (xy 324.698475 7.612717) (xy 324.771381 7.657858) (xy 324.848141 7.69608)
			(xy 324.9281 7.727056) (xy 325.010576 7.750523) (xy 325.094866 7.766279) (xy 325.180249 7.774191)
			(xy 325.265999 7.774191) (xy 325.351382 7.766279) (xy 325.435672 7.750523) (xy 325.518148 7.727056)
			(xy 325.598107 7.69608) (xy 325.62031 7.685024) (xy 329.230736 7.685024) (xy 329.230736 8.548624)
			(xy 329.231222 8.575893) (xy 329.238984 8.629877) (xy 329.254349 8.682207) (xy 329.277006 8.731817)
			(xy 329.306492 8.777698) (xy 329.342207 8.818915) (xy 329.383424 8.85463) (xy 329.429305 8.884116)
			(xy 329.478915 8.906773) (xy 329.531245 8.922138) (xy 329.585229 8.9299) (xy 329.639767 8.9299) (xy 329.693751 8.922138)
			(xy 329.746081 8.906773) (xy 329.795691 8.884116) (xy 329.841572 8.85463) (xy 329.882789 8.818915)
			(xy 329.918504 8.777698) (xy 329.94799 8.731817) (xy 329.970647 8.682207) (xy 329.986012 8.629877)
			(xy 329.993774 8.575893) (xy 329.99426 8.548624) (xy 329.99426 7.685024) (xy 329.993774 7.657755)
			(xy 329.986012 7.603771) (xy 329.970647 7.551441) (xy 329.94799 7.501831) (xy 329.918504 7.45595)
			(xy 329.882789 7.414733) (xy 329.841572 7.379018) (xy 329.795691 7.349532) (xy 329.746081 7.326875)
			(xy 329.693751 7.31151) (xy 329.639767 7.303748) (xy 329.585229 7.303748) (xy 329.531245 7.31151)
			(xy 329.478915 7.326875) (xy 329.429305 7.349532) (xy 329.383424 7.379018) (xy 329.342207 7.414733)
			(xy 329.306492 7.45595) (xy 329.277006 7.501831) (xy 329.254349 7.551441) (xy 329.238984 7.603771)
			(xy 329.231222 7.657755) (xy 329.230736 7.685024) (xy 325.62031 7.685024) (xy 325.674867 7.657858)
			(xy 325.747773 7.612717) (xy 325.816202 7.561041) (xy 325.879572 7.503272) (xy 325.937341 7.439902)
			(xy 325.989017 7.371473) (xy 326.034158 7.298567) (xy 326.07238 7.221807) (xy 326.103356 7.141848)
			(xy 326.126823 7.059372) (xy 326.142579 6.975082) (xy 326.150491 6.889699) (xy 326.150986 6.846824)
			(xy 326.150491 6.803949) (xy 330.645757 6.803949) (xy 330.645757 6.889699) (xy 330.653669 6.975082)
			(xy 330.669425 7.059372) (xy 330.692892 7.141848) (xy 330.723868 7.221807) (xy 330.76209 7.298567)
			(xy 330.807231 7.371473) (xy 330.858907 7.439902) (xy 330.916676 7.503272) (xy 330.980046 7.561041)
			(xy 331.048475 7.612717) (xy 331.121381 7.657858) (xy 331.198141 7.69608) (xy 331.2781 7.727056)
			(xy 331.360576 7.750523) (xy 331.444866 7.766279) (xy 331.530249 7.774191) (xy 331.615999 7.774191)
			(xy 331.701382 7.766279) (xy 331.785672 7.750523) (xy 331.868148 7.727056) (xy 331.948107 7.69608)
			(xy 332.024867 7.657858) (xy 332.097773 7.612717) (xy 332.166202 7.561041) (xy 332.229572 7.503272)
			(xy 332.287341 7.439902) (xy 332.339017 7.371473) (xy 332.384158 7.298567) (xy 332.42238 7.221807)
			(xy 332.453356 7.141848) (xy 332.476823 7.059372) (xy 332.492579 6.975082) (xy 332.500491 6.889699)
			(xy 332.500986 6.846824) (xy 332.50079 6.829857) (xy 382.496301 6.829857) (xy 382.496301 6.915607)
			(xy 382.504213 7.00099) (xy 382.519969 7.08528) (xy 382.543436 7.167756) (xy 382.574412 7.247715)
			(xy 382.612634 7.324475) (xy 382.657775 7.397381) (xy 382.709451 7.46581) (xy 382.76722 7.52918)
			(xy 382.83059 7.586949) (xy 382.899019 7.638625) (xy 382.971925 7.683766) (xy 383.048685 7.721988)
			(xy 383.128644 7.752964) (xy 383.21112 7.776431) (xy 383.29541 7.792187) (xy 383.380793 7.800099)
			(xy 383.466543 7.800099) (xy 383.551926 7.792187) (xy 383.636216 7.776431) (xy 383.718692 7.752964)
			(xy 383.798651 7.721988) (xy 383.820854 7.710932) (xy 385.002532 7.710932) (xy 385.002532 8.574532)
			(xy 385.003018 8.601801) (xy 385.01078 8.655785) (xy 385.026145 8.708115) (xy 385.048802 8.757725)
			(xy 385.078288 8.803606) (xy 385.114003 8.844823) (xy 385.15522 8.880538) (xy 385.201101 8.910024)
			(xy 385.250711 8.932681) (xy 385.303041 8.948046) (xy 385.357025 8.955808) (xy 385.411563 8.955808)
			(xy 385.465547 8.948046) (xy 385.517877 8.932681) (xy 385.567487 8.910024) (xy 385.613368 8.880538)
			(xy 385.654585 8.844823) (xy 385.6903 8.803606) (xy 385.719786 8.757725) (xy 385.742443 8.708115)
			(xy 385.757808 8.655785) (xy 385.76557 8.601801) (xy 385.766056 8.574532) (xy 385.766056 7.710932)
			(xy 385.76557 7.683663) (xy 385.757808 7.629679) (xy 385.742443 7.577349) (xy 385.719786 7.527739)
			(xy 385.6903 7.481858) (xy 385.654585 7.440641) (xy 385.613368 7.404926) (xy 385.567487 7.37544)
			(xy 385.517877 7.352783) (xy 385.465547 7.337418) (xy 385.411563 7.329656) (xy 385.357025 7.329656)
			(xy 385.303041 7.337418) (xy 385.250711 7.352783) (xy 385.201101 7.37544) (xy 385.15522 7.404926)
			(xy 385.114003 7.440641) (xy 385.078288 7.481858) (xy 385.048802 7.527739) (xy 385.026145 7.577349)
			(xy 385.01078 7.629679) (xy 385.003018 7.683663) (xy 385.002532 7.710932) (xy 383.820854 7.710932)
			(xy 383.875411 7.683766) (xy 383.948317 7.638625) (xy 384.016746 7.586949) (xy 384.080116 7.52918)
			(xy 384.137885 7.46581) (xy 384.189561 7.397381) (xy 384.234702 7.324475) (xy 384.272924 7.247715)
			(xy 384.3039 7.167756) (xy 384.327367 7.08528) (xy 384.343123 7.00099) (xy 384.351035 6.915607) (xy 384.35153 6.872732)
			(xy 384.351035 6.829857) (xy 388.846301 6.829857) (xy 388.846301 6.915607) (xy 388.854213 7.00099)
			(xy 388.869969 7.08528) (xy 388.893436 7.167756) (xy 388.924412 7.247715) (xy 388.962634 7.324475)
			(xy 389.007775 7.397381) (xy 389.059451 7.46581) (xy 389.11722 7.52918) (xy 389.18059 7.586949) (xy 389.249019 7.638625)
			(xy 389.321925 7.683766) (xy 389.398685 7.721988) (xy 389.478644 7.752964) (xy 389.56112 7.776431)
			(xy 389.64541 7.792187) (xy 389.730793 7.800099) (xy 389.816543 7.800099) (xy 389.901926 7.792187)
			(xy 389.986216 7.776431) (xy 390.068692 7.752964) (xy 390.148651 7.721988) (xy 390.225411 7.683766)
			(xy 390.298317 7.638625) (xy 390.366746 7.586949) (xy 390.430116 7.52918) (xy 390.487885 7.46581)
			(xy 390.539561 7.397381) (xy 390.584702 7.324475) (xy 390.622924 7.247715) (xy 390.6539 7.167756)
			(xy 390.677367 7.08528) (xy 390.693123 7.00099) (xy 390.701035 6.915607) (xy 390.70153 6.872732)
			(xy 390.701117 6.836969) (xy 396.558757 6.836969) (xy 396.558757 6.922719) (xy 396.566669 7.008102)
			(xy 396.582425 7.092392) (xy 396.605892 7.174868) (xy 396.636868 7.254827) (xy 396.67509 7.331587)
			(xy 396.720231 7.404493) (xy 396.771907 7.472922) (xy 396.829676 7.536292) (xy 396.893046 7.594061)
			(xy 396.961475 7.645737) (xy 397.034381 7.690878) (xy 397.111141 7.7291) (xy 397.1911 7.760076) (xy 397.273576 7.783543)
			(xy 397.357866 7.799299) (xy 397.443249 7.807211) (xy 397.528999 7.807211) (xy 397.614382 7.799299)
			(xy 397.698672 7.783543) (xy 397.781148 7.760076) (xy 397.861107 7.7291) (xy 397.88331 7.718044)
			(xy 401.493736 7.718044) (xy 401.493736 8.581644) (xy 401.494222 8.608913) (xy 401.501984 8.662897)
			(xy 401.517349 8.715227) (xy 401.540006 8.764837) (xy 401.569492 8.810718) (xy 401.605207 8.851935)
			(xy 401.646424 8.88765) (xy 401.692305 8.917136) (xy 401.741915 8.939793) (xy 401.794245 8.955158)
			(xy 401.848229 8.96292) (xy 401.902767 8.96292) (xy 401.956751 8.955158) (xy 402.009081 8.939793)
			(xy 402.058691 8.917136) (xy 402.104572 8.88765) (xy 402.145789 8.851935) (xy 402.181504 8.810718)
			(xy 402.21099 8.764837) (xy 402.233647 8.715227) (xy 402.249012 8.662897) (xy 402.256774 8.608913)
			(xy 402.25726 8.581644) (xy 402.25726 7.718044) (xy 402.256774 7.690775) (xy 402.249012 7.636791)
			(xy 402.233647 7.584461) (xy 402.21099 7.534851) (xy 402.181504 7.48897) (xy 402.145789 7.447753)
			(xy 402.104572 7.412038) (xy 402.058691 7.382552) (xy 402.009081 7.359895) (xy 401.956751 7.34453)
			(xy 401.902767 7.336768) (xy 401.848229 7.336768) (xy 401.794245 7.34453) (xy 401.741915 7.359895)
			(xy 401.692305 7.382552) (xy 401.646424 7.412038) (xy 401.605207 7.447753) (xy 401.569492 7.48897)
			(xy 401.540006 7.534851) (xy 401.517349 7.584461) (xy 401.501984 7.636791) (xy 401.494222 7.690775)
			(xy 401.493736 7.718044) (xy 397.88331 7.718044) (xy 397.937867 7.690878) (xy 398.010773 7.645737)
			(xy 398.079202 7.594061) (xy 398.142572 7.536292) (xy 398.200341 7.472922) (xy 398.252017 7.404493)
			(xy 398.297158 7.331587) (xy 398.33538 7.254827) (xy 398.366356 7.174868) (xy 398.389823 7.092392)
			(xy 398.405579 7.008102) (xy 398.413491 6.922719) (xy 398.413986 6.879844) (xy 398.413491 6.836969)
			(xy 402.908757 6.836969) (xy 402.908757 6.922719) (xy 402.916669 7.008102) (xy 402.932425 7.092392)
			(xy 402.955892 7.174868) (xy 402.986868 7.254827) (xy 403.02509 7.331587) (xy 403.070231 7.404493)
			(xy 403.121907 7.472922) (xy 403.179676 7.536292) (xy 403.243046 7.594061) (xy 403.311475 7.645737)
			(xy 403.384381 7.690878) (xy 403.461141 7.7291) (xy 403.5411 7.760076) (xy 403.623576 7.783543) (xy 403.707866 7.799299)
			(xy 403.793249 7.807211) (xy 403.878999 7.807211) (xy 403.964382 7.799299) (xy 404.048672 7.783543)
			(xy 404.131148 7.760076) (xy 404.211107 7.7291) (xy 404.287867 7.690878) (xy 404.360773 7.645737)
			(xy 404.429202 7.594061) (xy 404.492572 7.536292) (xy 404.550341 7.472922) (xy 404.602017 7.404493)
			(xy 404.647158 7.331587) (xy 404.68538 7.254827) (xy 404.716356 7.174868) (xy 404.739823 7.092392)
			(xy 404.755579 7.008102) (xy 404.763491 6.922719) (xy 404.763986 6.879844) (xy 404.76379 6.862877)
			(xy 454.759301 6.862877) (xy 454.759301 6.948627) (xy 454.767213 7.03401) (xy 454.782969 7.1183)
			(xy 454.806436 7.200776) (xy 454.837412 7.280735) (xy 454.875634 7.357495) (xy 454.920775 7.430401)
			(xy 454.972451 7.49883) (xy 455.03022 7.5622) (xy 455.09359 7.619969) (xy 455.162019 7.671645) (xy 455.234925 7.716786)
			(xy 455.311685 7.755008) (xy 455.391644 7.785984) (xy 455.47412 7.809451) (xy 455.55841 7.825207)
			(xy 455.643793 7.833119) (xy 455.729543 7.833119) (xy 455.814926 7.825207) (xy 455.899216 7.809451)
			(xy 455.981692 7.785984) (xy 456.061651 7.755008) (xy 456.083854 7.743952) (xy 457.265532 7.743952)
			(xy 457.265532 8.607552) (xy 457.266018 8.634821) (xy 457.27378 8.688805) (xy 457.289145 8.741135)
			(xy 457.311802 8.790745) (xy 457.341288 8.836626) (xy 457.377003 8.877843) (xy 457.41822 8.913558)
			(xy 457.464101 8.943044) (xy 457.513711 8.965701) (xy 457.566041 8.981066) (xy 457.620025 8.988828)
			(xy 457.674563 8.988828) (xy 457.728547 8.981066) (xy 457.780877 8.965701) (xy 457.830487 8.943044)
			(xy 457.876368 8.913558) (xy 457.917585 8.877843) (xy 457.9533 8.836626) (xy 457.982786 8.790745)
			(xy 458.005443 8.741135) (xy 458.020808 8.688805) (xy 458.02857 8.634821) (xy 458.029056 8.607552)
			(xy 458.029056 7.743952) (xy 458.02857 7.716683) (xy 458.020808 7.662699) (xy 458.005443 7.610369)
			(xy 457.982786 7.560759) (xy 457.9533 7.514878) (xy 457.917585 7.473661) (xy 457.876368 7.437946)
			(xy 457.830487 7.40846) (xy 457.780877 7.385803) (xy 457.728547 7.370438) (xy 457.674563 7.362676)
			(xy 457.620025 7.362676) (xy 457.566041 7.370438) (xy 457.513711 7.385803) (xy 457.464101 7.40846)
			(xy 457.41822 7.437946) (xy 457.377003 7.473661) (xy 457.341288 7.514878) (xy 457.311802 7.560759)
			(xy 457.289145 7.610369) (xy 457.27378 7.662699) (xy 457.266018 7.716683) (xy 457.265532 7.743952)
			(xy 456.083854 7.743952) (xy 456.138411 7.716786) (xy 456.211317 7.671645) (xy 456.279746 7.619969)
			(xy 456.343116 7.5622) (xy 456.400885 7.49883) (xy 456.452561 7.430401) (xy 456.497702 7.357495)
			(xy 456.535924 7.280735) (xy 456.5669 7.200776) (xy 456.590367 7.1183) (xy 456.606123 7.03401) (xy 456.614035 6.948627)
			(xy 456.61453 6.905752) (xy 456.614035 6.862877) (xy 461.109301 6.862877) (xy 461.109301 6.948627)
			(xy 461.117213 7.03401) (xy 461.132969 7.1183) (xy 461.156436 7.200776) (xy 461.187412 7.280735)
			(xy 461.225634 7.357495) (xy 461.270775 7.430401) (xy 461.322451 7.49883) (xy 461.38022 7.5622) (xy 461.44359 7.619969)
			(xy 461.512019 7.671645) (xy 461.584925 7.716786) (xy 461.661685 7.755008) (xy 461.741644 7.785984)
			(xy 461.82412 7.809451) (xy 461.90841 7.825207) (xy 461.993793 7.833119) (xy 462.079543 7.833119)
			(xy 462.164926 7.825207) (xy 462.249216 7.809451) (xy 462.331692 7.785984) (xy 462.411651 7.755008)
			(xy 462.488411 7.716786) (xy 462.561317 7.671645) (xy 462.629746 7.619969) (xy 462.693116 7.5622)
			(xy 462.750885 7.49883) (xy 462.802561 7.430401) (xy 462.847702 7.357495) (xy 462.885924 7.280735)
			(xy 462.9169 7.200776) (xy 462.940367 7.1183) (xy 462.956123 7.03401) (xy 462.964035 6.948627) (xy 462.96453 6.905752)
			(xy 462.964035 6.862877) (xy 462.956123 6.777494) (xy 462.940367 6.693204) (xy 462.9169 6.610728)
			(xy 462.885924 6.530769) (xy 462.847702 6.454009) (xy 462.802561 6.381103) (xy 462.750885 6.312674)
			(xy 462.693116 6.249304) (xy 462.629746 6.191535) (xy 462.561317 6.139859) (xy 462.488411 6.094718)
			(xy 462.411651 6.056496) (xy 462.331692 6.02552) (xy 462.249216 6.002053) (xy 462.164926 5.986297)
			(xy 462.079543 5.978385) (xy 461.993793 5.978385) (xy 461.90841 5.986297) (xy 461.82412 6.002053)
			(xy 461.741644 6.02552) (xy 461.661685 6.056496) (xy 461.584925 6.094718) (xy 461.512019 6.139859)
			(xy 461.44359 6.191535) (xy 461.38022 6.249304) (xy 461.322451 6.312674) (xy 461.270775 6.381103)
			(xy 461.225634 6.454009) (xy 461.187412 6.530769) (xy 461.156436 6.610728) (xy 461.132969 6.693204)
			(xy 461.117213 6.777494) (xy 461.109301 6.862877) (xy 456.614035 6.862877) (xy 456.606123 6.777494)
			(xy 456.590367 6.693204) (xy 456.5669 6.610728) (xy 456.535924 6.530769) (xy 456.497702 6.454009)
			(xy 456.452561 6.381103) (xy 456.400885 6.312674) (xy 456.343116 6.249304) (xy 456.279746 6.191535)
			(xy 456.211317 6.139859) (xy 456.138411 6.094718) (xy 456.061651 6.056496) (xy 455.981692 6.02552)
			(xy 455.899216 6.002053) (xy 455.814926 5.986297) (xy 455.729543 5.978385) (xy 455.643793 5.978385)
			(xy 455.55841 5.986297) (xy 455.47412 6.002053) (xy 455.391644 6.02552) (xy 455.311685 6.056496)
			(xy 455.234925 6.094718) (xy 455.162019 6.139859) (xy 455.09359 6.191535) (xy 455.03022 6.249304)
			(xy 454.972451 6.312674) (xy 454.920775 6.381103) (xy 454.875634 6.454009) (xy 454.837412 6.530769)
			(xy 454.806436 6.610728) (xy 454.782969 6.693204) (xy 454.767213 6.777494) (xy 454.759301 6.862877)
			(xy 404.76379 6.862877) (xy 404.763491 6.836969) (xy 404.755579 6.751586) (xy 404.739823 6.667296)
			(xy 404.716356 6.58482) (xy 404.68538 6.504861) (xy 404.647158 6.428101) (xy 404.602017 6.355195)
			(xy 404.550341 6.286766) (xy 404.492572 6.223396) (xy 404.429202 6.165627) (xy 404.360773 6.113951)
			(xy 404.287867 6.06881) (xy 404.211107 6.030588) (xy 404.131148 5.999612) (xy 404.048672 5.976145)
			(xy 403.964382 5.960389) (xy 403.878999 5.952477) (xy 403.793249 5.952477) (xy 403.707866 5.960389)
			(xy 403.623576 5.976145) (xy 403.5411 5.999612) (xy 403.461141 6.030588) (xy 403.384381 6.06881)
			(xy 403.311475 6.113951) (xy 403.243046 6.165627) (xy 403.179676 6.223396) (xy 403.121907 6.286766)
			(xy 403.070231 6.355195) (xy 403.02509 6.428101) (xy 402.986868 6.504861) (xy 402.955892 6.58482)
			(xy 402.932425 6.667296) (xy 402.916669 6.751586) (xy 402.908757 6.836969) (xy 398.413491 6.836969)
			(xy 398.405579 6.751586) (xy 398.389823 6.667296) (xy 398.366356 6.58482) (xy 398.33538 6.504861)
			(xy 398.297158 6.428101) (xy 398.252017 6.355195) (xy 398.200341 6.286766) (xy 398.142572 6.223396)
			(xy 398.079202 6.165627) (xy 398.010773 6.113951) (xy 397.937867 6.06881) (xy 397.861107 6.030588)
			(xy 397.781148 5.999612) (xy 397.698672 5.976145) (xy 397.614382 5.960389) (xy 397.528999 5.952477)
			(xy 397.443249 5.952477) (xy 397.357866 5.960389) (xy 397.273576 5.976145) (xy 397.1911 5.999612)
			(xy 397.111141 6.030588) (xy 397.034381 6.06881) (xy 396.961475 6.113951) (xy 396.893046 6.165627)
			(xy 396.829676 6.223396) (xy 396.771907 6.286766) (xy 396.720231 6.355195) (xy 396.67509 6.428101)
			(xy 396.636868 6.504861) (xy 396.605892 6.58482) (xy 396.582425 6.667296) (xy 396.566669 6.751586)
			(xy 396.558757 6.836969) (xy 390.701117 6.836969) (xy 390.701035 6.829857) (xy 390.693123 6.744474)
			(xy 390.677367 6.660184) (xy 390.6539 6.577708) (xy 390.622924 6.497749) (xy 390.584702 6.420989)
			(xy 390.539561 6.348083) (xy 390.487885 6.279654) (xy 390.430116 6.216284) (xy 390.366746 6.158515)
			(xy 390.298317 6.106839) (xy 390.225411 6.061698) (xy 390.148651 6.023476) (xy 390.068692 5.9925)
			(xy 389.986216 5.969033) (xy 389.901926 5.953277) (xy 389.816543 5.945365) (xy 389.730793 5.945365)
			(xy 389.64541 5.953277) (xy 389.56112 5.969033) (xy 389.478644 5.9925) (xy 389.398685 6.023476) (xy 389.321925 6.061698)
			(xy 389.249019 6.106839) (xy 389.18059 6.158515) (xy 389.11722 6.216284) (xy 389.059451 6.279654)
			(xy 389.007775 6.348083) (xy 388.962634 6.420989) (xy 388.924412 6.497749) (xy 388.893436 6.577708)
			(xy 388.869969 6.660184) (xy 388.854213 6.744474) (xy 388.846301 6.829857) (xy 384.351035 6.829857)
			(xy 384.343123 6.744474) (xy 384.327367 6.660184) (xy 384.3039 6.577708) (xy 384.272924 6.497749)
			(xy 384.234702 6.420989) (xy 384.189561 6.348083) (xy 384.137885 6.279654) (xy 384.080116 6.216284)
			(xy 384.016746 6.158515) (xy 383.948317 6.106839) (xy 383.875411 6.061698) (xy 383.798651 6.023476)
			(xy 383.718692 5.9925) (xy 383.636216 5.969033) (xy 383.551926 5.953277) (xy 383.466543 5.945365)
			(xy 383.380793 5.945365) (xy 383.29541 5.953277) (xy 383.21112 5.969033) (xy 383.128644 5.9925) (xy 383.048685 6.023476)
			(xy 382.971925 6.061698) (xy 382.899019 6.106839) (xy 382.83059 6.158515) (xy 382.76722 6.216284)
			(xy 382.709451 6.279654) (xy 382.657775 6.348083) (xy 382.612634 6.420989) (xy 382.574412 6.497749)
			(xy 382.543436 6.577708) (xy 382.519969 6.660184) (xy 382.504213 6.744474) (xy 382.496301 6.829857)
			(xy 332.50079 6.829857) (xy 332.500491 6.803949) (xy 332.492579 6.718566) (xy 332.476823 6.634276)
			(xy 332.453356 6.5518) (xy 332.42238 6.471841) (xy 332.384158 6.395081) (xy 332.339017 6.322175)
			(xy 332.287341 6.253746) (xy 332.229572 6.190376) (xy 332.166202 6.132607) (xy 332.097773 6.080931)
			(xy 332.024867 6.03579) (xy 331.948107 5.997568) (xy 331.868148 5.966592) (xy 331.785672 5.943125)
			(xy 331.701382 5.927369) (xy 331.615999 5.919457) (xy 331.530249 5.919457) (xy 331.444866 5.927369)
			(xy 331.360576 5.943125) (xy 331.2781 5.966592) (xy 331.198141 5.997568) (xy 331.121381 6.03579)
			(xy 331.048475 6.080931) (xy 330.980046 6.132607) (xy 330.916676 6.190376) (xy 330.858907 6.253746)
			(xy 330.807231 6.322175) (xy 330.76209 6.395081) (xy 330.723868 6.471841) (xy 330.692892 6.5518)
			(xy 330.669425 6.634276) (xy 330.653669 6.718566) (xy 330.645757 6.803949) (xy 326.150491 6.803949)
			(xy 326.142579 6.718566) (xy 326.126823 6.634276) (xy 326.103356 6.5518) (xy 326.07238 6.471841)
			(xy 326.034158 6.395081) (xy 325.989017 6.322175) (xy 325.937341 6.253746) (xy 325.879572 6.190376)
			(xy 325.816202 6.132607) (xy 325.747773 6.080931) (xy 325.674867 6.03579) (xy 325.598107 5.997568)
			(xy 325.518148 5.966592) (xy 325.435672 5.943125) (xy 325.351382 5.927369) (xy 325.265999 5.919457)
			(xy 325.180249 5.919457) (xy 325.094866 5.927369) (xy 325.010576 5.943125) (xy 324.9281 5.966592)
			(xy 324.848141 5.997568) (xy 324.771381 6.03579) (xy 324.698475 6.080931) (xy 324.630046 6.132607)
			(xy 324.566676 6.190376) (xy 324.508907 6.253746) (xy 324.457231 6.322175) (xy 324.41209 6.395081)
			(xy 324.373868 6.471841) (xy 324.342892 6.5518) (xy 324.319425 6.634276) (xy 324.303669 6.718566)
			(xy 324.295757 6.803949) (xy 317.930117 6.803949) (xy 317.930035 6.796837) (xy 317.922123 6.711454)
			(xy 317.906367 6.627164) (xy 317.8829 6.544688) (xy 317.851924 6.464729) (xy 317.813702 6.387969)
			(xy 317.768561 6.315063) (xy 317.716885 6.246634) (xy 317.659116 6.183264) (xy 317.595746 6.125495)
			(xy 317.527317 6.073819) (xy 317.454411 6.028678) (xy 317.377651 5.990456) (xy 317.297692 5.95948)
			(xy 317.215216 5.936013) (xy 317.130926 5.920257) (xy 317.045543 5.912345) (xy 316.959793 5.912345)
			(xy 316.87441 5.920257) (xy 316.79012 5.936013) (xy 316.707644 5.95948) (xy 316.627685 5.990456)
			(xy 316.550925 6.028678) (xy 316.478019 6.073819) (xy 316.40959 6.125495) (xy 316.34622 6.183264)
			(xy 316.288451 6.246634) (xy 316.236775 6.315063) (xy 316.191634 6.387969) (xy 316.153412 6.464729)
			(xy 316.122436 6.544688) (xy 316.098969 6.627164) (xy 316.083213 6.711454) (xy 316.075301 6.796837)
			(xy 311.580035 6.796837) (xy 311.572123 6.711454) (xy 311.556367 6.627164) (xy 311.5329 6.544688)
			(xy 311.501924 6.464729) (xy 311.463702 6.387969) (xy 311.418561 6.315063) (xy 311.366885 6.246634)
			(xy 311.309116 6.183264) (xy 311.245746 6.125495) (xy 311.177317 6.073819) (xy 311.104411 6.028678)
			(xy 311.027651 5.990456) (xy 310.947692 5.95948) (xy 310.865216 5.936013) (xy 310.780926 5.920257)
			(xy 310.695543 5.912345) (xy 310.609793 5.912345) (xy 310.52441 5.920257) (xy 310.44012 5.936013)
			(xy 310.357644 5.95948) (xy 310.277685 5.990456) (xy 310.200925 6.028678) (xy 310.128019 6.073819)
			(xy 310.05959 6.125495) (xy 309.99622 6.183264) (xy 309.938451 6.246634) (xy 309.886775 6.315063)
			(xy 309.841634 6.387969) (xy 309.803412 6.464729) (xy 309.772436 6.544688) (xy 309.748969 6.627164)
			(xy 309.733213 6.711454) (xy 309.725301 6.796837) (xy 259.72979 6.796837) (xy 259.729491 6.770929)
			(xy 259.721579 6.685546) (xy 259.705823 6.601256) (xy 259.682356 6.51878) (xy 259.65138 6.438821)
			(xy 259.613158 6.362061) (xy 259.568017 6.289155) (xy 259.516341 6.220726) (xy 259.458572 6.157356)
			(xy 259.395202 6.099587) (xy 259.326773 6.047911) (xy 259.253867 6.00277) (xy 259.177107 5.964548)
			(xy 259.097148 5.933572) (xy 259.014672 5.910105) (xy 258.930382 5.894349) (xy 258.844999 5.886437)
			(xy 258.759249 5.886437) (xy 258.673866 5.894349) (xy 258.589576 5.910105) (xy 258.5071 5.933572)
			(xy 258.427141 5.964548) (xy 258.350381 6.00277) (xy 258.277475 6.047911) (xy 258.209046 6.099587)
			(xy 258.145676 6.157356) (xy 258.087907 6.220726) (xy 258.036231 6.289155) (xy 257.99109 6.362061)
			(xy 257.952868 6.438821) (xy 257.921892 6.51878) (xy 257.898425 6.601256) (xy 257.882669 6.685546)
			(xy 257.874757 6.770929) (xy 253.379491 6.770929) (xy 253.371579 6.685546) (xy 253.355823 6.601256)
			(xy 253.332356 6.51878) (xy 253.30138 6.438821) (xy 253.263158 6.362061) (xy 253.218017 6.289155)
			(xy 253.166341 6.220726) (xy 253.108572 6.157356) (xy 253.045202 6.099587) (xy 252.976773 6.047911)
			(xy 252.903867 6.00277) (xy 252.827107 5.964548) (xy 252.747148 5.933572) (xy 252.664672 5.910105)
			(xy 252.580382 5.894349) (xy 252.494999 5.886437) (xy 252.409249 5.886437) (xy 252.323866 5.894349)
			(xy 252.239576 5.910105) (xy 252.1571 5.933572) (xy 252.077141 5.964548) (xy 252.000381 6.00277)
			(xy 251.927475 6.047911) (xy 251.859046 6.099587) (xy 251.795676 6.157356) (xy 251.737907 6.220726)
			(xy 251.686231 6.289155) (xy 251.64109 6.362061) (xy 251.602868 6.438821) (xy 251.571892 6.51878)
			(xy 251.548425 6.601256) (xy 251.532669 6.685546) (xy 251.524757 6.770929) (xy 245.921117 6.770929)
			(xy 245.921035 6.763817) (xy 245.913123 6.678434) (xy 245.897367 6.594144) (xy 245.8739 6.511668)
			(xy 245.842924 6.431709) (xy 245.804702 6.354949) (xy 245.759561 6.282043) (xy 245.707885 6.213614)
			(xy 245.650116 6.150244) (xy 245.586746 6.092475) (xy 245.518317 6.040799) (xy 245.445411 5.995658)
			(xy 245.368651 5.957436) (xy 245.288692 5.92646) (xy 245.206216 5.902993) (xy 245.121926 5.887237)
			(xy 245.036543 5.879325) (xy 244.950793 5.879325) (xy 244.86541 5.887237) (xy 244.78112 5.902993)
			(xy 244.698644 5.92646) (xy 244.618685 5.957436) (xy 244.541925 5.995658) (xy 244.469019 6.040799)
			(xy 244.40059 6.092475) (xy 244.33722 6.150244) (xy 244.279451 6.213614) (xy 244.227775 6.282043)
			(xy 244.182634 6.354949) (xy 244.144412 6.431709) (xy 244.113436 6.511668) (xy 244.089969 6.594144)
			(xy 244.074213 6.678434) (xy 244.066301 6.763817) (xy 239.571035 6.763817) (xy 239.563123 6.678434)
			(xy 239.547367 6.594144) (xy 239.5239 6.511668) (xy 239.492924 6.431709) (xy 239.454702 6.354949)
			(xy 239.409561 6.282043) (xy 239.357885 6.213614) (xy 239.300116 6.150244) (xy 239.236746 6.092475)
			(xy 239.168317 6.040799) (xy 239.095411 5.995658) (xy 239.018651 5.957436) (xy 238.938692 5.92646)
			(xy 238.856216 5.902993) (xy 238.771926 5.887237) (xy 238.686543 5.879325) (xy 238.600793 5.879325)
			(xy 238.51541 5.887237) (xy 238.43112 5.902993) (xy 238.348644 5.92646) (xy 238.268685 5.957436)
			(xy 238.191925 5.995658) (xy 238.119019 6.040799) (xy 238.05059 6.092475) (xy 237.98722 6.150244)
			(xy 237.929451 6.213614) (xy 237.877775 6.282043) (xy 237.832634 6.354949) (xy 237.794412 6.431709)
			(xy 237.763436 6.511668) (xy 237.739969 6.594144) (xy 237.724213 6.678434) (xy 237.716301 6.763817)
			(xy 187.719832 6.763817) (xy 187.712579 6.685546) (xy 187.696823 6.601256) (xy 187.673356 6.51878)
			(xy 187.64238 6.438821) (xy 187.604158 6.362061) (xy 187.559017 6.289155) (xy 187.507341 6.220726)
			(xy 187.449572 6.157356) (xy 187.386202 6.099587) (xy 187.317773 6.047911) (xy 187.244867 6.00277)
			(xy 187.168107 5.964548) (xy 187.088148 5.933572) (xy 187.005672 5.910105) (xy 186.921382 5.894349)
			(xy 186.835999 5.886437) (xy 186.750249 5.886437) (xy 186.664866 5.894349) (xy 186.580576 5.910105)
			(xy 186.4981 5.933572) (xy 186.418141 5.964548) (xy 186.341381 6.00277) (xy 186.268475 6.047911)
			(xy 186.200046 6.099587) (xy 186.136676 6.157356) (xy 186.078907 6.220726) (xy 186.027231 6.289155)
			(xy 185.98209 6.362061) (xy 185.943868 6.438821) (xy 185.912892 6.51878) (xy 185.889425 6.601256)
			(xy 185.873669 6.685546) (xy 185.865757 6.770929) (xy 181.370491 6.770929) (xy 181.362579 6.685546)
			(xy 181.346823 6.601256) (xy 181.323356 6.51878) (xy 181.29238 6.438821) (xy 181.254158 6.362061)
			(xy 181.209017 6.289155) (xy 181.157341 6.220726) (xy 181.099572 6.157356) (xy 181.036202 6.099587)
			(xy 180.967773 6.047911) (xy 180.894867 6.00277) (xy 180.818107 5.964548) (xy 180.738148 5.933572)
			(xy 180.655672 5.910105) (xy 180.571382 5.894349) (xy 180.485999 5.886437) (xy 180.400249 5.886437)
			(xy 180.314866 5.894349) (xy 180.230576 5.910105) (xy 180.1481 5.933572) (xy 180.068141 5.964548)
			(xy 179.991381 6.00277) (xy 179.918475 6.047911) (xy 179.850046 6.099587) (xy 179.786676 6.157356)
			(xy 179.728907 6.220726) (xy 179.677231 6.289155) (xy 179.63209 6.362061) (xy 179.593868 6.438821)
			(xy 179.562892 6.51878) (xy 179.539425 6.601256) (xy 179.523669 6.685546) (xy 179.515757 6.770929)
			(xy 158.039844 6.770929) (xy 158.030561 6.759289) (xy 157.936801 6.654373) (xy 157.837306 6.554879)
			(xy 157.732388 6.46112) (xy 157.622379 6.373391) (xy 157.507624 6.291969) (xy 157.388483 6.21711)
			(xy 157.265333 6.149048) (xy 157.138561 6.087998) (xy 157.008565 6.034153) (xy 156.875754 5.987681)
			(xy 156.740546 5.948729) (xy 156.603367 5.91742) (xy 156.464649 5.893851) (xy 156.324827 5.878098)
			(xy 156.184341 5.870209) (xy 156.113988 5.869686) (xy 17.493996 5.869686) (xy 17.423642 5.870179)
			(xy 17.283156 5.878069) (xy 17.143333 5.893824) (xy 17.004613 5.917393) (xy 16.867433 5.948703) (xy 16.732225 5.987656)
			(xy 16.599413 6.034129) (xy 16.469416 6.087976) (xy 16.342643 6.149026) (xy 16.219492 6.217089) (xy 16.100351 6.29195)
			(xy 15.985596 6.373373) (xy 15.875586 6.461103) (xy 15.770668 6.554863) (xy 15.671172 6.654358) (xy 15.577412 6.759275)
			(xy 15.489682 6.869284) (xy 15.408258 6.98404) (xy 15.333396 7.10318) (xy 15.265333 7.22633) (xy 15.204281 7.353103)
			(xy 15.150434 7.4831) (xy 15.103961 7.615912) (xy 15.065007 7.75112) (xy 15.033696 7.8883) (xy 15.010125 8.027019)
			(xy 14.99437 8.166842) (xy 14.98648 8.307328) (xy 14.986 8.377682) (xy 14.986 24.157686) (xy 14.985478 24.213493)
			(xy 14.977137 24.324795) (xy 14.960501 24.435162) (xy 14.935664 24.543977) (xy 14.902765 24.650632)
			(xy 14.861988 24.754531) (xy 14.81356 24.855091) (xy 14.757753 24.951752) (xy 14.694879 25.043971)
			(xy 14.625289 25.131234) (xy 14.549372 25.213053) (xy 14.467553 25.28897) (xy 14.38029 25.35856)
			(xy 14.28807 25.421434) (xy 14.19141 25.477241) (xy 14.090849 25.525669) (xy 13.986951 25.566446)
			(xy 13.880295 25.599345) (xy 13.77148 25.624182) (xy 13.661113 25.640817) (xy 13.549811 25.649158)
			(xy 13.494004 25.649682) (xy 1.999996 25.649682) (xy 1.944189 25.64916) (xy 1.832887 25.640819) (xy 1.72252 25.624184)
			(xy 1.613704 25.599347) (xy 1.507049 25.566448) (xy 1.40315 25.525671) (xy 1.30259 25.477243) (xy 1.205929 25.421436)
			(xy 1.113709 25.358562) (xy 1.026446 25.288971) (xy 0.944627 25.213055) (xy 0.86871 25.131236) (xy 0.79912 25.043972)
			(xy 0.736245 24.951753) (xy 0.680438 24.855092) (xy 0.63201 24.754532) (xy 0.591233 24.650633) (xy 0.558334 24.543978)
			(xy 0.533497 24.435162) (xy 0.516861 24.324795) (xy 0.50852 24.213493) (xy 0.508 24.157686) (xy 0.508 21.093122)
			(xy 2.904225 21.093122) (xy 2.904225 21.222262) (xy 2.912175 21.351157) (xy 2.928045 21.479317) (xy 2.951774 21.606258)
			(xy 2.983273 21.731497) (xy 3.022422 21.85456) (xy 3.069073 21.974979) (xy 3.123048 22.092298) (xy 3.184143 22.206072)
			(xy 3.252126 22.315869) (xy 3.32674 22.421272) (xy 3.407701 22.521882) (xy 3.494701 22.617317) (xy 3.587412 22.707216)
			(xy 3.685482 22.791237) (xy 3.788537 22.869061) (xy 3.896188 22.940393) (xy 4.008027 23.004963) (xy 4.123628 23.062525)
			(xy 4.242553 23.112862) (xy 4.364352 23.155782) (xy 4.488562 23.191123) (xy 4.614711 23.21875) (xy 4.742323 23.238559)
			(xy 4.870912 23.250475) (xy 4.99999 23.254452) (xy 5.129068 23.250475) (xy 5.257657 23.238559) (xy 5.385269 23.21875)
			(xy 5.511418 23.191123) (xy 5.635628 23.155782) (xy 5.757427 23.112862) (xy 5.876352 23.062525) (xy 5.991953 23.004963)
			(xy 6.103792 22.940393) (xy 6.211443 22.869061) (xy 6.314498 22.791237) (xy 6.412568 22.707216) (xy 6.505279 22.617317)
			(xy 6.592279 22.521882) (xy 6.67324 22.421272) (xy 6.747854 22.315869) (xy 6.815837 22.206072) (xy 6.876932 22.092298)
			(xy 6.930907 21.974979) (xy 6.977558 21.85456) (xy 7.016707 21.731497) (xy 7.048206 21.606258) (xy 7.071935 21.479317)
			(xy 7.087805 21.351157) (xy 7.095755 21.222262) (xy 7.096252 21.157692) (xy 7.095755 21.093122) (xy 7.087805 20.964227)
			(xy 7.071935 20.836067) (xy 7.048206 20.709126) (xy 7.016707 20.583887) (xy 6.977558 20.460824) (xy 6.930907 20.340405)
			(xy 6.876932 20.223086) (xy 6.815837 20.109312) (xy 6.747854 19.999515) (xy 6.67324 19.894112) (xy 6.592279 19.793502)
			(xy 6.505279 19.698067) (xy 6.412568 19.608168) (xy 6.314498 19.524147) (xy 6.211443 19.446323) (xy 6.103792 19.374991)
			(xy 5.991953 19.310421) (xy 5.876352 19.252859) (xy 5.757427 19.202522) (xy 5.635628 19.159602) (xy 5.511418 19.124261)
			(xy 5.385269 19.096634) (xy 5.257657 19.076825) (xy 5.129068 19.064909) (xy 4.99999 19.060933) (xy 4.870912 19.064909)
			(xy 4.742323 19.076825) (xy 4.614711 19.096634) (xy 4.488562 19.124261) (xy 4.364352 19.159602) (xy 4.242553 19.202522)
			(xy 4.123628 19.252859) (xy 4.008027 19.310421) (xy 3.896188 19.374991) (xy 3.788537 19.446323) (xy 3.685482 19.524147)
			(xy 3.587412 19.608168) (xy 3.494701 19.698067) (xy 3.407701 19.793502) (xy 3.32674 19.894112) (xy 3.252126 19.999515)
			(xy 3.184143 20.109312) (xy 3.123048 20.223086) (xy 3.069073 20.340405) (xy 3.022422 20.460824) (xy 2.983273 20.583887)
			(xy 2.951774 20.709126) (xy 2.928045 20.836067) (xy 2.912175 20.964227) (xy 2.904225 21.093122) (xy 0.508 21.093122)
			(xy 0.508 3.999992) (xy 0.508522 3.944185) (xy 0.516863 3.832883) (xy 0.533498 3.722516) (xy 0.558335 3.6137)
			(xy 0.591234 3.507045) (xy 0.632011 3.403146) (xy 0.680438 3.302586) (xy 0.736246 3.205925) (xy 0.79912 3.113705)
			(xy 0.86871 3.026442) (xy 0.944627 2.944623) (xy 1.026446 2.868706) (xy 1.113709 2.799116) (xy 1.205929 2.736242)
			(xy 1.30259 2.680434) (xy 1.40315 2.632007) (xy 1.507049 2.59123) (xy 1.613704 2.558331) (xy 1.72252 2.533494)
			(xy 1.832887 2.516859) (xy 1.944189 2.508518) (xy 1.999996 2.507996) (xy 7.964932 2.507996) (xy 8.035286 2.507503)
			(xy 8.175772 2.499613) (xy 8.315594 2.483859) (xy 8.454314 2.460289) (xy 8.591493 2.428979) (xy 8.726701 2.390026)
			(xy 8.859513 2.343553) (xy 8.989509 2.289707) (xy 9.116282 2.228656) (xy 9.239433 2.160593) (xy 9.358573 2.085732)
			(xy 9.473329 2.004309) (xy 9.583338 1.916579) (xy 9.688255 1.822819) (xy 9.78775 1.723324) (xy 9.88151 1.618406)
			(xy 9.96924 1.508397) (xy 10.050663 1.393641) (xy 10.125524 1.274501) (xy 10.193587 1.151351) (xy 10.254637 1.024578)
			(xy 10.308484 0.894581) (xy 10.354957 0.76177) (xy 10.393909 0.626561) (xy 10.42522 0.489382) (xy 10.448789 0.350662)
			(xy 10.464543 0.21084) (xy 10.472433 0.070354) (xy 10.472928 0) (xy 10.472928 -8.850122) (xy 10.47345 -8.905929)
			(xy 10.481791 -9.017231) (xy 10.498426 -9.127599) (xy 10.523263 -9.236414) (xy 10.556162 -9.34307)
			(xy 10.596939 -9.446968) (xy 10.645366 -9.547529) (xy 10.701173 -9.64419) (xy 10.764048 -9.73641)
			(xy 10.833638 -9.823673) (xy 10.909555 -9.905492) (xy 10.991374 -9.981409) (xy 11.078637 -10.051)
			(xy 11.170857 -10.113875) (xy 11.267517 -10.169682) (xy 11.368078 -10.21811) (xy 11.471977 -10.258887)
			(xy 11.578632 -10.291786) (xy 11.687448 -10.316623) (xy 11.797815 -10.333259) (xy 11.909117 -10.3416)
			(xy 11.964924 -10.342118)
		)
		(stroke
			(width 0)
			(type solid)
		)
		(fill yes)
		(layer "In12.Cu")
		(net "COUPON_GND2")
	)
	(gr_poly
		(pts
			(xy 200.481692 -418.081968) (xy 200.538276 -418.081432) (xy 200.651116 -418.072836) (xy 200.76298 -418.055715)
			(xy 200.873227 -418.030169) (xy 200.98122 -417.996343) (xy 201.086341 -417.954433) (xy 201.187984 -417.904678)
			(xy 201.285565 -417.847366) (xy 201.378524 -417.782825) (xy 201.466326 -417.711427) (xy 201.548466 -417.633582)
			(xy 201.586846 -417.592002) (xy 201.634058 -417.54062) (xy 201.733379 -417.442584) (xy 201.837997 -417.350223)
			(xy 201.947589 -417.26382) (xy 202.061814 -417.183644) (xy 202.18032 -417.109943) (xy 202.302741 -417.042944)
			(xy 202.428697 -416.982855) (xy 202.557798 -416.929861) (xy 202.689647 -416.884127) (xy 202.823834 -416.845794)
			(xy 202.959945 -416.81498) (xy 203.097558 -416.791782) (xy 203.236248 -416.77627) (xy 203.375587 -416.768492)
			(xy 203.445364 -416.768026) (xy 271.794732 -416.768026) (xy 271.864502 -416.768512) (xy 272.003824 -416.776289)
			(xy 272.142499 -416.791801) (xy 272.280097 -416.814999) (xy 272.416192 -416.845812) (xy 272.550363 -416.884144)
			(xy 272.682195 -416.929877) (xy 272.811281 -416.982869) (xy 272.937221 -417.042957) (xy 273.059624 -417.109954)
			(xy 273.178113 -417.183654) (xy 273.292321 -417.263827) (xy 273.401895 -417.350227) (xy 273.434939 -417.379404)
			(xy 313.073796 -417.379404) (xy 313.073796 -394.27912) (xy 326.479662 -394.27912) (xy 326.525636 -394.325094)
			(xy 326.525636 -397.823826) (xy 330.929171 -397.823826) (xy 330.929175 -397.756517) (xy 330.937223 -397.689692)
			(xy 330.953201 -397.624307) (xy 330.976879 -397.561301) (xy 331.007918 -397.501576) (xy 331.045873 -397.44599)
			(xy 331.067664 -397.420338) (xy 331.073477 -397.413205) (xy 331.07998 -397.396005) (xy 331.080364 -397.38681)
			(xy 331.080364 -396.893542) (xy 331.079919 -396.884359) (xy 331.073428 -396.867175) (xy 331.067664 -396.860014)
			(xy 331.045866 -396.83437) (xy 331.007916 -396.778783) (xy 330.976881 -396.719059) (xy 330.953208 -396.656053)
			(xy 330.937235 -396.59067) (xy 330.929191 -396.523846) (xy 330.929192 -396.456539) (xy 330.937238 -396.389716)
			(xy 330.953213 -396.324333) (xy 330.976888 -396.261328) (xy 331.007923 -396.201604) (xy 331.045875 -396.146018)
			(xy 331.067664 -396.120366) (xy 331.073465 -396.113225) (xy 331.079975 -396.096031) (xy 331.080364 -396.086838)
			(xy 331.080364 -395.92885) (xy 331.080805 -395.918678) (xy 331.088579 -395.89988) (xy 331.10296 -395.885492)
			(xy 331.121755 -395.87771) (xy 331.131926 -395.877288) (xy 331.848206 -395.877288) (xy 331.858384 -395.87766)
			(xy 331.877189 -395.885456) (xy 331.891575 -395.899859) (xy 331.899351 -395.918671) (xy 331.899768 -395.92885)
			(xy 331.899768 -396.086838) (xy 331.900167 -396.096026) (xy 331.906689 -396.11321) (xy 331.912468 -396.120366)
			(xy 331.934246 -396.146026) (xy 331.972195 -396.201612) (xy 332.003228 -396.261334) (xy 332.026901 -396.324338)
			(xy 332.042874 -396.389719) (xy 332.050919 -396.45654) (xy 332.05092 -396.523845) (xy 332.042877 -396.590666)
			(xy 332.026905 -396.656048) (xy 332.003234 -396.719052) (xy 331.972202 -396.778775) (xy 331.934255 -396.834362)
			(xy 331.912468 -396.860014) (xy 331.906679 -396.867164) (xy 331.90016 -396.884351) (xy 331.899768 -396.893542)
			(xy 331.899768 -397.38681) (xy 331.90018 -397.395997) (xy 331.906693 -397.413181) (xy 331.912468 -397.420338)
			(xy 331.934218 -397.446021) (xy 331.972167 -397.501603) (xy 332.00059 -397.556296) (xy 333.128836 -397.556296)
			(xy 333.136911 -397.489358) (xy 333.152946 -397.423869) (xy 333.17671 -397.360773) (xy 333.20786 -397.300977)
			(xy 333.245948 -397.245343) (xy 333.267812 -397.219678) (xy 333.273602 -397.212528) (xy 333.28012 -397.195341)
			(xy 333.280512 -397.18615) (xy 333.280512 -397.028924) (xy 333.280936 -397.018802) (xy 333.288678 -397.000096)
			(xy 333.302993 -396.985781) (xy 333.321698 -396.978037) (xy 333.33182 -396.977616) (xy 334.0481 -396.977616)
			(xy 334.058224 -396.978016) (xy 334.076931 -396.985768) (xy 334.091246 -397.000089) (xy 334.098988 -397.018799)
			(xy 334.099408 -397.028924) (xy 334.099408 -397.18615) (xy 334.09984 -397.195335) (xy 334.106338 -397.21252)
			(xy 334.112108 -397.219678) (xy 334.133982 -397.245335) (xy 334.172069 -397.300971) (xy 334.203219 -397.360769)
			(xy 334.226982 -397.423866) (xy 334.243017 -397.489356) (xy 334.251092 -397.556295) (xy 334.251091 -397.62372)
			(xy 334.243014 -397.690658) (xy 334.226978 -397.756148) (xy 334.203213 -397.819245) (xy 334.200796 -397.823884)
			(xy 335.328964 -397.823884) (xy 335.328968 -397.756459) (xy 335.337047 -397.689518) (xy 335.353085 -397.624028)
			(xy 335.376852 -397.560929) (xy 335.408005 -397.501132) (xy 335.446095 -397.445496) (xy 335.46796 -397.41983)
			(xy 335.473776 -397.412699) (xy 335.480277 -397.395497) (xy 335.48066 -397.386302) (xy 335.48066 -396.89405)
			(xy 335.480213 -396.884867) (xy 335.473723 -396.867683) (xy 335.46796 -396.860522) (xy 335.446088 -396.834864)
			(xy 335.408002 -396.779228) (xy 335.376854 -396.71943) (xy 335.353092 -396.656332) (xy 335.337058 -396.590843)
			(xy 335.328984 -396.523904) (xy 335.328985 -396.456481) (xy 335.337061 -396.389542) (xy 335.353096 -396.324053)
			(xy 335.37686 -396.260956) (xy 335.40801 -396.201159) (xy 335.446097 -396.145524) (xy 335.46796 -396.119858)
			(xy 335.473764 -396.112719) (xy 335.480273 -396.095523) (xy 335.48066 -396.08633) (xy 335.48066 -395.92885)
			(xy 335.481168 -395.918724) (xy 335.488883 -395.9) (xy 335.503164 -395.885642) (xy 335.521845 -395.877824)
			(xy 335.531968 -395.877288) (xy 336.248248 -395.877288) (xy 336.258404 -395.877682) (xy 336.277155 -395.885491)
			(xy 336.291476 -395.899896) (xy 336.299176 -395.918692) (xy 336.299556 -395.92885) (xy 336.299556 -396.08633)
			(xy 336.299962 -396.095517) (xy 336.30648 -396.112701) (xy 336.312256 -396.119858) (xy 336.334112 -396.145531)
			(xy 336.372204 -396.201163) (xy 336.403357 -396.260958) (xy 336.427124 -396.324054) (xy 336.443161 -396.389542)
			(xy 336.451239 -396.456481) (xy 336.45124 -396.523904) (xy 336.443164 -396.590843) (xy 336.427128 -396.656332)
			(xy 336.403363 -396.719428) (xy 336.372211 -396.779224) (xy 336.334121 -396.834858) (xy 336.312256 -396.860522)
			(xy 336.306462 -396.867669) (xy 336.299947 -396.884858) (xy 336.299556 -396.89405) (xy 336.299556 -397.386302)
			(xy 336.299975 -397.395488) (xy 336.306484 -397.412672) (xy 336.312256 -397.41983) (xy 336.334084 -397.445525)
			(xy 336.372177 -397.501154) (xy 336.40094 -397.556356) (xy 337.529156 -397.556356) (xy 337.537198 -397.489535)
			(xy 337.553169 -397.424153) (xy 337.576839 -397.361149) (xy 337.607869 -397.301426) (xy 337.645814 -397.245839)
			(xy 337.6676 -397.220186) (xy 337.673385 -397.213033) (xy 337.679907 -397.195848) (xy 337.6803 -397.186658)
			(xy 337.6803 -397.028924) (xy 337.680741 -397.018771) (xy 337.688529 -397.000019) (xy 337.70292 -396.985695)
			(xy 337.721708 -396.977995) (xy 337.731862 -396.977616) (xy 338.448142 -396.977616) (xy 338.458268 -396.978091)
			(xy 338.476986 -396.985829) (xy 338.49134 -397.000118) (xy 338.499162 -397.0188) (xy 338.499704 -397.028924)
			(xy 338.499704 -397.186658) (xy 338.500133 -397.195843) (xy 338.506634 -397.213028) (xy 338.512404 -397.220186)
			(xy 338.5342 -397.245831) (xy 338.572146 -397.301419) (xy 338.603176 -397.361144) (xy 338.626847 -397.42415)
			(xy 338.642818 -397.489532) (xy 338.65086 -397.556355) (xy 338.650859 -397.62366) (xy 338.642815 -397.690483)
			(xy 338.626842 -397.755865) (xy 338.60317 -397.81887) (xy 338.600595 -397.823826) (xy 339.729259 -397.823826)
			(xy 339.729263 -397.756517) (xy 339.737311 -397.689692) (xy 339.753288 -397.624308) (xy 339.776965 -397.561301)
			(xy 339.808004 -397.501577) (xy 339.845958 -397.44599) (xy 339.867748 -397.420338) (xy 339.873559 -397.413204)
			(xy 339.880064 -397.396005) (xy 339.880448 -397.38681) (xy 339.880448 -396.893542) (xy 339.880007 -396.884358)
			(xy 339.873513 -396.867174) (xy 339.867748 -396.860014) (xy 339.84595 -396.83437) (xy 339.808001 -396.778783)
			(xy 339.776968 -396.719058) (xy 339.753295 -396.656052) (xy 339.737322 -396.590669) (xy 339.729279 -396.523845)
			(xy 339.72928 -396.456539) (xy 339.737325 -396.389716) (xy 339.753299 -396.324333) (xy 339.776974 -396.261328)
			(xy 339.808009 -396.201604) (xy 339.845959 -396.146018) (xy 339.867748 -396.120366) (xy 339.873547 -396.113223)
			(xy 339.880059 -396.096031) (xy 339.880448 -396.086838) (xy 339.880448 -395.92885) (xy 339.880905 -395.91868)
			(xy 339.888675 -395.899885) (xy 339.903051 -395.885498) (xy 339.921841 -395.877713) (xy 339.93201 -395.877288)
			(xy 340.64829 -395.877288) (xy 340.658467 -395.877673) (xy 340.677271 -395.885464) (xy 340.691658 -395.899862)
			(xy 340.699435 -395.918672) (xy 340.699852 -395.92885) (xy 340.699852 -396.086838) (xy 340.700255 -396.096026)
			(xy 340.706775 -396.113209) (xy 340.712552 -396.120366) (xy 340.73433 -396.146026) (xy 340.77228 -396.201611)
			(xy 340.803314 -396.261334) (xy 340.826988 -396.324337) (xy 340.842962 -396.389718) (xy 340.851007 -396.45654)
			(xy 340.851007 -396.523845) (xy 340.842964 -396.590667) (xy 340.826992 -396.656048) (xy 340.80332 -396.719053)
			(xy 340.772287 -396.778776) (xy 340.734339 -396.834362) (xy 340.712552 -396.860014) (xy 340.706761 -396.867163)
			(xy 340.700244 -396.884351) (xy 340.699852 -396.893542) (xy 340.699852 -397.38681) (xy 340.700268 -397.395996)
			(xy 340.706779 -397.41318) (xy 340.712552 -397.420338) (xy 340.734302 -397.446021) (xy 340.772253 -397.501603)
			(xy 340.800676 -397.556296) (xy 341.928924 -397.556296) (xy 341.936999 -397.489359) (xy 341.953033 -397.42387)
			(xy 341.976796 -397.360774) (xy 342.007946 -397.300978) (xy 342.046033 -397.245343) (xy 342.067896 -397.219678)
			(xy 342.073684 -397.212527) (xy 342.080204 -397.195341) (xy 342.080596 -397.18615) (xy 342.080596 -397.028924)
			(xy 342.081035 -397.018804) (xy 342.088775 -397.000101) (xy 342.103084 -396.985786) (xy 342.121784 -396.978039)
			(xy 342.131904 -396.977616) (xy 342.848184 -396.977616) (xy 342.858307 -396.978029) (xy 342.877014 -396.985775)
			(xy 342.891329 -397.000093) (xy 342.899072 -397.0188) (xy 342.899492 -397.028924) (xy 342.899492 -397.18615)
			(xy 342.899928 -397.195334) (xy 342.906424 -397.212519) (xy 342.912192 -397.219678) (xy 342.934066 -397.245335)
			(xy 342.972155 -397.300971) (xy 343.003306 -397.360768) (xy 343.02707 -397.423866) (xy 343.043105 -397.489356)
			(xy 343.05118 -397.556295) (xy 343.051179 -397.62372) (xy 343.043102 -397.690659) (xy 343.027065 -397.756149)
			(xy 343.0033 -397.819246) (xy 343.000914 -397.823825) (xy 344.12905 -397.823825) (xy 344.129054 -397.756517)
			(xy 344.137101 -397.689692) (xy 344.153078 -397.624308) (xy 344.176755 -397.561302) (xy 344.207793 -397.501577)
			(xy 344.245746 -397.44599) (xy 344.267536 -397.420338) (xy 344.273346 -397.413202) (xy 344.279852 -397.396004)
			(xy 344.280236 -397.38681) (xy 344.280236 -396.893542) (xy 344.279797 -396.884358) (xy 344.273303 -396.867174)
			(xy 344.267536 -396.860014) (xy 344.245738 -396.83437) (xy 344.20779 -396.778782) (xy 344.176757 -396.719058)
			(xy 344.153085 -396.656052) (xy 344.137113 -396.590669) (xy 344.12907 -396.523845) (xy 344.129071 -396.45654)
			(xy 344.137116 -396.389716) (xy 344.15309 -396.324334) (xy 344.176764 -396.261329) (xy 344.207798 -396.201605)
			(xy 344.245748 -396.146018) (xy 344.267536 -396.120366) (xy 344.273334 -396.113222) (xy 344.279847 -396.09603)
			(xy 344.280236 -396.086838) (xy 344.280236 -395.92885) (xy 344.280705 -395.918682) (xy 344.288473 -395.899889)
			(xy 344.302845 -395.885502) (xy 344.32163 -395.877715) (xy 344.331798 -395.877288) (xy 345.048078 -395.877288)
			(xy 345.058254 -395.877683) (xy 345.077058 -395.88547) (xy 345.091445 -395.899866) (xy 345.099222 -395.918673)
			(xy 345.09964 -395.92885) (xy 345.09964 -396.086838) (xy 345.100045 -396.096025) (xy 345.106564 -396.113209)
			(xy 345.11234 -396.120366) (xy 345.134118 -396.146026) (xy 345.172069 -396.201611) (xy 345.203104 -396.261333)
			(xy 345.226778 -396.324337) (xy 345.242752 -396.389718) (xy 345.250798 -396.45654) (xy 345.250798 -396.523845)
			(xy 345.242755 -396.590667) (xy 345.226782 -396.656049) (xy 345.20311 -396.719053) (xy 345.172077 -396.778776)
			(xy 345.134128 -396.834362) (xy 345.11234 -396.860014) (xy 345.106548 -396.867162) (xy 345.100032 -396.884351)
			(xy 345.09964 -396.893542) (xy 345.09964 -397.38681) (xy 345.100059 -397.395996) (xy 345.106568 -397.41318)
			(xy 345.11234 -397.420338) (xy 345.134091 -397.446021) (xy 345.172042 -397.501602) (xy 345.200497 -397.556355)
			(xy 346.32922 -397.556355) (xy 346.337264 -397.489532) (xy 346.353237 -397.42415) (xy 346.37691 -397.361146)
			(xy 346.407945 -397.301423) (xy 346.445896 -397.245838) (xy 346.467684 -397.220186) (xy 346.473467 -397.213031)
			(xy 346.47999 -397.195848) (xy 346.480384 -397.186658) (xy 346.480384 -397.028924) (xy 346.480841 -397.018773)
			(xy 346.488625 -397.000025) (xy 346.503011 -396.985701) (xy 346.521794 -396.977997) (xy 346.531946 -396.977616)
			(xy 347.248226 -396.977616) (xy 347.258351 -396.978104) (xy 347.277069 -396.985836) (xy 347.291423 -397.000121)
			(xy 347.299246 -397.018801) (xy 347.299788 -397.028924) (xy 347.299788 -397.186658) (xy 347.300221 -397.195843)
			(xy 347.306719 -397.213027) (xy 347.312488 -397.220186) (xy 347.334285 -397.24583) (xy 347.372232 -397.301419)
			(xy 347.403263 -397.361143) (xy 347.426934 -397.424149) (xy 347.442905 -397.489532) (xy 347.450948 -397.556355)
			(xy 347.450947 -397.62366) (xy 347.442903 -397.690483) (xy 347.426929 -397.755865) (xy 347.403257 -397.81887)
			(xy 347.400682 -397.823826) (xy 374.92908 -397.823826) (xy 374.929084 -397.756517) (xy 374.937132 -397.689691)
			(xy 374.95311 -397.624306) (xy 374.976789 -397.5613) (xy 375.007829 -397.501576) (xy 375.045785 -397.445989)
			(xy 375.067576 -397.420338) (xy 375.073379 -397.413197) (xy 375.07989 -397.396003) (xy 375.080276 -397.38681)
			(xy 375.080276 -396.893542) (xy 375.079851 -396.884356) (xy 375.073348 -396.867171) (xy 375.067576 -396.860014)
			(xy 375.045777 -396.83437) (xy 375.007826 -396.778784) (xy 374.976792 -396.719059) (xy 374.953118 -396.656053)
			(xy 374.937144 -396.59067) (xy 374.9291 -396.523846) (xy 374.929101 -396.456539) (xy 374.937147 -396.389715)
			(xy 374.953122 -396.324332) (xy 374.976798 -396.261327) (xy 375.007834 -396.201604) (xy 375.045787 -396.146018)
			(xy 375.067576 -396.120366) (xy 375.073367 -396.113216) (xy 375.079886 -396.096029) (xy 375.080276 -396.086838)
			(xy 375.080276 -395.92885) (xy 375.080706 -395.918677) (xy 375.088481 -395.899876) (xy 375.102866 -395.885488)
			(xy 375.121665 -395.877708) (xy 375.131838 -395.877288) (xy 375.848118 -395.877288) (xy 375.858297 -395.87765)
			(xy 375.877102 -395.885451) (xy 375.891487 -395.899856) (xy 375.899263 -395.91867) (xy 375.89968 -395.92885)
			(xy 375.89968 -396.086838) (xy 375.900076 -396.096027) (xy 375.9066 -396.113211) (xy 375.91238 -396.120366)
			(xy 375.934157 -396.146026) (xy 375.972105 -396.201612) (xy 376.003138 -396.261335) (xy 376.02681 -396.324338)
			(xy 376.042784 -396.389719) (xy 376.050828 -396.456541) (xy 376.050829 -396.523844) (xy 376.042786 -396.590666)
			(xy 376.026815 -396.656047) (xy 376.003144 -396.719051) (xy 375.972113 -396.778775) (xy 375.934167 -396.834362)
			(xy 375.91238 -396.860014) (xy 375.906593 -396.867166) (xy 375.900073 -396.884351) (xy 375.89968 -396.893542)
			(xy 375.89968 -397.38681) (xy 375.90009 -397.395997) (xy 375.906604 -397.413181) (xy 375.91238 -397.420338)
			(xy 375.93413 -397.446021) (xy 375.972078 -397.501604) (xy 376.0005 -397.556296) (xy 377.128745 -397.556296)
			(xy 377.136821 -397.489358) (xy 377.152856 -397.423869) (xy 377.17662 -397.360772) (xy 377.207771 -397.300977)
			(xy 377.24586 -397.245343) (xy 377.267724 -397.219678) (xy 377.273515 -397.212529) (xy 377.280032 -397.195341)
			(xy 377.280424 -397.18615) (xy 377.280424 -397.028924) (xy 377.280836 -397.0188) (xy 377.288581 -397.000092)
			(xy 377.302899 -396.985776) (xy 377.321608 -396.978034) (xy 377.331732 -396.977616) (xy 378.048012 -396.977616)
			(xy 378.058137 -396.978006) (xy 378.076844 -396.985761) (xy 378.091159 -397.000086) (xy 378.098901 -397.018798)
			(xy 378.09932 -397.028924) (xy 378.09932 -397.18615) (xy 378.09975 -397.195335) (xy 378.10625 -397.21252)
			(xy 378.11202 -397.219678) (xy 378.133893 -397.245335) (xy 378.17198 -397.300972) (xy 378.203129 -397.360769)
			(xy 378.226892 -397.423867) (xy 378.242926 -397.489357) (xy 378.251001 -397.556295) (xy 378.251 -397.62372)
			(xy 378.242924 -397.690658) (xy 378.226888 -397.756147) (xy 378.203123 -397.819245) (xy 378.200706 -397.823885)
			(xy 379.328873 -397.823885) (xy 379.328877 -397.756458) (xy 379.336956 -397.689518) (xy 379.352995 -397.624027)
			(xy 379.376762 -397.560929) (xy 379.407915 -397.501131) (xy 379.446007 -397.445496) (xy 379.467872 -397.41983)
			(xy 379.47369 -397.4127) (xy 379.48019 -397.395498) (xy 379.480572 -397.386302) (xy 379.480572 -396.89405)
			(xy 379.480144 -396.884865) (xy 379.473643 -396.86768) (xy 379.467872 -396.860522) (xy 379.445999 -396.834864)
			(xy 379.407913 -396.779228) (xy 379.376764 -396.719431) (xy 379.353002 -396.656333) (xy 379.336968 -396.590843)
			(xy 379.328893 -396.523904) (xy 379.328894 -396.456481) (xy 379.33697 -396.389542) (xy 379.353006 -396.324053)
			(xy 379.37677 -396.260956) (xy 379.40792 -396.201159) (xy 379.446008 -396.145524) (xy 379.467872 -396.119858)
			(xy 379.473678 -396.11272) (xy 379.480185 -396.095524) (xy 379.480572 -396.08633) (xy 379.480572 -395.92885)
			(xy 379.481069 -395.918723) (xy 379.488786 -395.899996) (xy 379.50307 -395.885637) (xy 379.521755 -395.877822)
			(xy 379.53188 -395.877288) (xy 380.24816 -395.877288) (xy 380.258278 -395.877749) (xy 380.276979 -395.885481)
			(xy 380.291294 -395.899784) (xy 380.299043 -395.918478) (xy 380.299468 -395.928596) (xy 380.299468 -396.08633)
			(xy 380.299871 -396.095518) (xy 380.30639 -396.112702) (xy 380.312168 -396.119858) (xy 380.334023 -396.145531)
			(xy 380.372114 -396.201163) (xy 380.403267 -396.260958) (xy 380.427033 -396.324054) (xy 380.443071 -396.389543)
			(xy 380.451148 -396.456481) (xy 380.451149 -396.523904) (xy 380.443073 -396.590842) (xy 380.427038 -396.656331)
			(xy 380.403273 -396.719428) (xy 380.372122 -396.779224) (xy 380.334032 -396.834857) (xy 380.312168 -396.860522)
			(xy 380.306375 -396.86767) (xy 380.299859 -396.884858) (xy 380.299468 -396.89405) (xy 380.299468 -397.386302)
			(xy 380.299884 -397.395488) (xy 380.306394 -397.412672) (xy 380.312168 -397.41983) (xy 380.333996 -397.445525)
			(xy 380.372088 -397.501155) (xy 380.40085 -397.556356) (xy 381.529065 -397.556356) (xy 381.537108 -397.489534)
			(xy 381.553079 -397.424153) (xy 381.576749 -397.361149) (xy 381.60778 -397.301425) (xy 381.645726 -397.245838)
			(xy 381.667512 -397.220186) (xy 381.673298 -397.213034) (xy 381.679819 -397.195849) (xy 381.680212 -397.186658)
			(xy 381.680212 -397.028924) (xy 381.680636 -397.018802) (xy 381.688378 -397.000096) (xy 381.702693 -396.985781)
			(xy 381.721398 -396.978037) (xy 381.73152 -396.977616) (xy 382.448054 -396.977616) (xy 382.458175 -396.978164)
			(xy 382.47689 -396.985872) (xy 382.491247 -397.000139) (xy 382.499072 -397.018806) (xy 382.499616 -397.028924)
			(xy 382.499616 -397.186658) (xy 382.500043 -397.195844) (xy 382.506544 -397.213028) (xy 382.512316 -397.220186)
			(xy 382.534115 -397.245829) (xy 382.572066 -397.301416) (xy 382.603102 -397.36114) (xy 382.626776 -397.424146)
			(xy 382.642749 -397.48953) (xy 382.650793 -397.556354) (xy 382.650793 -397.623661) (xy 382.642747 -397.690485)
			(xy 382.626771 -397.755868) (xy 382.603096 -397.818873) (xy 382.600522 -397.823826) (xy 383.729168 -397.823826)
			(xy 383.729172 -397.756517) (xy 383.73722 -397.689692) (xy 383.753198 -397.624307) (xy 383.776876 -397.561301)
			(xy 383.807914 -397.501576) (xy 383.845869 -397.44599) (xy 383.86766 -397.420338) (xy 383.873473 -397.413205)
			(xy 383.879976 -397.396005) (xy 383.88036 -397.38681) (xy 383.88036 -396.893542) (xy 383.879916 -396.884359)
			(xy 383.873425 -396.867175) (xy 383.86766 -396.860014) (xy 383.845862 -396.83437) (xy 383.807912 -396.778783)
			(xy 383.776878 -396.719058) (xy 383.753205 -396.656053) (xy 383.737232 -396.590669) (xy 383.729188 -396.523846)
			(xy 383.729189 -396.456539) (xy 383.737235 -396.389716) (xy 383.753209 -396.324333) (xy 383.776884 -396.261328)
			(xy 383.80792 -396.201604) (xy 383.845871 -396.146018) (xy 383.86766 -396.120366) (xy 383.873461 -396.113224)
			(xy 383.879971 -396.096031) (xy 383.88036 -396.086838) (xy 383.88036 -395.92885) (xy 383.880805 -395.918679)
			(xy 383.888578 -395.899881) (xy 383.902958 -395.885494) (xy 383.921751 -395.877711) (xy 383.931922 -395.877288)
			(xy 384.648202 -395.877288) (xy 384.65838 -395.877663) (xy 384.677184 -395.885458) (xy 384.691571 -395.899859)
			(xy 384.699347 -395.918672) (xy 384.699764 -395.92885) (xy 384.699764 -396.086838) (xy 384.700164 -396.096026)
			(xy 384.706686 -396.11321) (xy 384.712464 -396.120366) (xy 384.734242 -396.146026) (xy 384.772191 -396.201612)
			(xy 384.803224 -396.261334) (xy 384.826898 -396.324337) (xy 384.842871 -396.389719) (xy 384.850916 -396.45654)
			(xy 384.850917 -396.523845) (xy 384.842874 -396.590666) (xy 384.826902 -396.656048) (xy 384.803231 -396.719052)
			(xy 384.772199 -396.778776) (xy 384.734251 -396.834362) (xy 384.712464 -396.860014) (xy 384.706674 -396.867164)
			(xy 384.700156 -396.884351) (xy 384.699764 -396.893542) (xy 384.699764 -397.38681) (xy 384.700177 -397.395997)
			(xy 384.70669 -397.413181) (xy 384.712464 -397.420338) (xy 384.734214 -397.446021) (xy 384.772164 -397.501603)
			(xy 384.800587 -397.556296) (xy 385.928833 -397.556296) (xy 385.936908 -397.489358) (xy 385.952943 -397.42387)
			(xy 385.976706 -397.360773) (xy 386.007856 -397.300977) (xy 386.045944 -397.245343) (xy 386.067808 -397.219678)
			(xy 386.073597 -397.212528) (xy 386.080116 -397.195341) (xy 386.080508 -397.18615) (xy 386.080508 -397.028924)
			(xy 386.080936 -397.018802) (xy 386.088677 -397.000097) (xy 386.102991 -396.985782) (xy 386.121694 -396.978037)
			(xy 386.131816 -396.977616) (xy 386.848096 -396.977616) (xy 386.85822 -396.97802) (xy 386.876927 -396.985769)
			(xy 386.891242 -397.00009) (xy 386.898984 -397.0188) (xy 386.899404 -397.028924) (xy 386.899404 -397.18615)
			(xy 386.899837 -397.195335) (xy 386.906335 -397.212519) (xy 386.912104 -397.219678) (xy 386.933978 -397.245335)
			(xy 386.972066 -397.300971) (xy 387.003216 -397.360768) (xy 387.026979 -397.423866) (xy 387.043014 -397.489356)
			(xy 387.051089 -397.556295) (xy 387.051088 -397.62372) (xy 387.043011 -397.690659) (xy 387.026975 -397.756148)
			(xy 387.00321 -397.819245) (xy 387.000823 -397.823826) (xy 388.128959 -397.823826) (xy 388.128963 -397.756517)
			(xy 388.137011 -397.689692) (xy 388.152988 -397.624308) (xy 388.176665 -397.561301) (xy 388.207704 -397.501577)
			(xy 388.245658 -397.44599) (xy 388.267448 -397.420338) (xy 388.273259 -397.413204) (xy 388.279764 -397.396005)
			(xy 388.280148 -397.38681) (xy 388.280148 -396.893542) (xy 388.279707 -396.884358) (xy 388.273213 -396.867174)
			(xy 388.267448 -396.860014) (xy 388.24565 -396.83437) (xy 388.207701 -396.778783) (xy 388.176668 -396.719058)
			(xy 388.152995 -396.656052) (xy 388.137022 -396.590669) (xy 388.128979 -396.523845) (xy 388.12898 -396.456539)
			(xy 388.137025 -396.389716) (xy 388.152999 -396.324333) (xy 388.176674 -396.261328) (xy 388.207709 -396.201604)
			(xy 388.245659 -396.146018) (xy 388.267448 -396.120366) (xy 388.273247 -396.113223) (xy 388.279759 -396.096031)
			(xy 388.280148 -396.086838) (xy 388.280148 -395.92885) (xy 388.280605 -395.91868) (xy 388.288375 -395.899885)
			(xy 388.302751 -395.885498) (xy 388.321541 -395.877713) (xy 388.33171 -395.877288) (xy 389.04799 -395.877288)
			(xy 389.058167 -395.877673) (xy 389.076971 -395.885464) (xy 389.091358 -395.899862) (xy 389.099135 -395.918672)
			(xy 389.099552 -395.92885) (xy 389.099552 -396.086838) (xy 389.099955 -396.096026) (xy 389.106475 -396.113209)
			(xy 389.112252 -396.120366) (xy 389.13403 -396.146026) (xy 389.17198 -396.201611) (xy 389.203014 -396.261334)
			(xy 389.226688 -396.324337) (xy 389.242662 -396.389718) (xy 389.250707 -396.45654) (xy 389.250707 -396.523845)
			(xy 389.242664 -396.590667) (xy 389.226692 -396.656048) (xy 389.20302 -396.719053) (xy 389.171987 -396.778776)
			(xy 389.134039 -396.834362) (xy 389.112252 -396.860014) (xy 389.106461 -396.867163) (xy 389.099944 -396.884351)
			(xy 389.099552 -396.893542) (xy 389.099552 -397.38681) (xy 389.099968 -397.395996) (xy 389.106479 -397.41318)
			(xy 389.112252 -397.420338) (xy 389.134002 -397.446021) (xy 389.171953 -397.501603) (xy 389.200407 -397.556356)
			(xy 390.329153 -397.556356) (xy 390.337195 -397.489535) (xy 390.353166 -397.424153) (xy 390.376836 -397.36115)
			(xy 390.407865 -397.301426) (xy 390.44581 -397.245839) (xy 390.467596 -397.220186) (xy 390.473381 -397.213032)
			(xy 390.479903 -397.195848) (xy 390.480296 -397.186658) (xy 390.480296 -397.028924) (xy 390.480735 -397.018804)
			(xy 390.488475 -397.000101) (xy 390.502784 -396.985786) (xy 390.521484 -396.978039) (xy 390.531604 -396.977616)
			(xy 391.248138 -396.977616) (xy 391.258264 -396.978095) (xy 391.276982 -396.985831) (xy 391.291336 -397.000119)
			(xy 391.299158 -397.0188) (xy 391.2997 -397.028924) (xy 391.2997 -397.186658) (xy 391.30013 -397.195843)
			(xy 391.30663 -397.213028) (xy 391.3124 -397.220186) (xy 391.334196 -397.245831) (xy 391.372142 -397.301419)
			(xy 391.403173 -397.361144) (xy 391.426844 -397.424149) (xy 391.442815 -397.489532) (xy 391.450857 -397.556355)
			(xy 391.450856 -397.62366) (xy 391.442812 -397.690483) (xy 391.426839 -397.755865) (xy 391.403167 -397.81887)
			(xy 391.372135 -397.878594) (xy 391.334187 -397.934181) (xy 391.3124 -397.959834) (xy 391.306606 -397.966981)
			(xy 391.30009 -397.98417) (xy 391.2997 -397.993362) (xy 391.2997 -398.486884) (xy 391.300118 -398.49607)
			(xy 391.306626 -398.513255) (xy 391.3124 -398.520412) (xy 391.334222 -398.546036) (xy 391.372167 -398.601627)
			(xy 391.403197 -398.661355) (xy 391.426866 -398.724363) (xy 391.442835 -398.789748) (xy 391.450876 -398.856574)
			(xy 391.450872 -398.923881) (xy 391.442825 -398.990705) (xy 391.42685 -399.056089) (xy 391.403175 -399.119095)
			(xy 391.372139 -399.178819) (xy 391.334189 -399.234407) (xy 391.3124 -399.26006) (xy 391.306595 -399.2672)
			(xy 391.300086 -399.284394) (xy 391.2997 -399.293588) (xy 391.2997 -399.451576) (xy 391.299265 -399.461697)
			(xy 391.291524 -399.4804) (xy 391.277214 -399.494715) (xy 391.258513 -399.502461) (xy 391.248392 -399.502884)
			(xy 390.531858 -399.502884) (xy 390.521732 -399.502409) (xy 390.503014 -399.494671) (xy 390.48866 -399.480382)
			(xy 390.480838 -399.4617) (xy 390.480296 -399.451576) (xy 390.480296 -399.293588) (xy 390.479892 -399.2844)
			(xy 390.473374 -399.267216) (xy 390.467596 -399.26006) (xy 390.445845 -399.234378) (xy 390.407898 -399.178795)
			(xy 390.376865 -399.119075) (xy 390.353192 -399.056075) (xy 390.337218 -398.990696) (xy 390.329172 -398.923878)
			(xy 390.329169 -398.856576) (xy 390.337209 -398.789757) (xy 390.353176 -398.724377) (xy 390.376843 -398.661374)
			(xy 390.40787 -398.601652) (xy 390.445812 -398.546065) (xy 390.467596 -398.520412) (xy 390.473412 -398.51328)
			(xy 390.479915 -398.49608) (xy 390.480296 -398.486884) (xy 390.480296 -397.993362) (xy 390.479905 -397.984173)
			(xy 390.473378 -397.966988) (xy 390.467596 -397.959834) (xy 390.445819 -397.934173) (xy 390.407873 -397.878587)
			(xy 390.376842 -397.818864) (xy 390.35317 -397.755861) (xy 390.337198 -397.69048) (xy 390.329154 -397.623659)
			(xy 390.329153 -397.556356) (xy 389.200407 -397.556356) (xy 389.202988 -397.561322) (xy 389.226664 -397.624322)
			(xy 389.24264 -397.689701) (xy 389.250687 -397.75652) (xy 389.25069 -397.823823) (xy 389.24265 -397.890643)
			(xy 389.226681 -397.956023) (xy 389.203012 -398.019026) (xy 389.171982 -398.078748) (xy 389.134038 -398.134334)
			(xy 389.112252 -398.159986) (xy 389.10643 -398.167113) (xy 389.099932 -398.184318) (xy 389.099552 -398.193514)
			(xy 389.099552 -398.351502) (xy 389.099138 -398.361675) (xy 389.09135 -398.380472) (xy 389.076962 -398.394857)
			(xy 389.058163 -398.40264) (xy 389.04799 -398.403064) (xy 388.33171 -398.403064) (xy 388.321539 -398.402628)
			(xy 388.302745 -398.394847) (xy 388.28836 -398.380465) (xy 388.280574 -398.361673) (xy 388.280148 -398.351502)
			(xy 388.280148 -398.193514) (xy 388.27972 -398.184329) (xy 388.273218 -398.167145) (xy 388.267448 -398.159986)
			(xy 388.245622 -398.134365) (xy 388.207674 -398.078774) (xy 388.176642 -398.019046) (xy 388.152971 -397.956038)
			(xy 388.137 -397.890652) (xy 388.128959 -397.823826) (xy 387.000823 -397.823826) (xy 386.972058 -397.879042)
			(xy 386.933968 -397.934677) (xy 386.912104 -397.960342) (xy 386.906308 -397.967487) (xy 386.899793 -397.984678)
			(xy 386.899404 -397.99387) (xy 386.899404 -398.486376) (xy 386.899825 -398.495562) (xy 386.906331 -398.512747)
			(xy 386.912104 -398.519904) (xy 386.934003 -398.54554) (xy 386.972091 -398.601179) (xy 387.003239 -398.660979)
			(xy 387.027001 -398.72408) (xy 387.043034 -398.789572) (xy 387.051107 -398.856514) (xy 387.051104 -398.92394)
			(xy 387.043025 -398.990881) (xy 387.026985 -399.056372) (xy 387.003217 -399.11947) (xy 386.972063 -399.179268)
			(xy 386.93397 -399.234903) (xy 386.912104 -399.260568) (xy 386.906297 -399.267706) (xy 386.899788 -399.284902)
			(xy 386.899404 -399.294096) (xy 386.899404 -399.451576) (xy 386.898965 -399.461696) (xy 386.891225 -399.480399)
			(xy 386.876916 -399.494714) (xy 386.858216 -399.502461) (xy 386.848096 -399.502884) (xy 386.131816 -399.502884)
			(xy 386.121693 -399.502471) (xy 386.102986 -399.494725) (xy 386.088671 -399.480407) (xy 386.080928 -399.4617)
			(xy 386.080508 -399.451576) (xy 386.080508 -399.294096) (xy 386.080098 -399.284909) (xy 386.073584 -399.267725)
			(xy 386.067808 -399.260568) (xy 386.045979 -399.234874) (xy 386.007889 -399.179244) (xy 385.976736 -399.119451)
			(xy 385.95297 -399.056358) (xy 385.936931 -398.990873) (xy 385.928852 -398.923938) (xy 385.928849 -398.856517)
			(xy 385.936922 -398.789581) (xy 385.952954 -398.724093) (xy 385.976714 -398.660998) (xy 386.007861 -398.601203)
			(xy 386.045946 -398.545569) (xy 386.067808 -398.519904) (xy 386.073586 -398.512746) (xy 386.080112 -398.495565)
			(xy 386.080508 -398.486376) (xy 386.080508 -397.99387) (xy 386.080111 -397.984681) (xy 386.073588 -397.967497)
			(xy 386.067808 -397.960342) (xy 386.045954 -397.934669) (xy 386.007864 -397.879036) (xy 385.976712 -397.819241)
			(xy 385.952947 -397.756145) (xy 385.936911 -397.690657) (xy 385.928834 -397.623719) (xy 385.928833 -397.556296)
			(xy 384.800587 -397.556296) (xy 384.803199 -397.561322) (xy 384.826873 -397.624323) (xy 384.842849 -397.689701)
			(xy 384.850896 -397.75652) (xy 384.850899 -397.823822) (xy 384.842859 -397.890642) (xy 384.82689 -397.956022)
			(xy 384.803222 -398.019025) (xy 384.772193 -398.078748) (xy 384.734249 -398.134334) (xy 384.712464 -398.159986)
			(xy 384.706644 -398.167114) (xy 384.700144 -398.184318) (xy 384.699764 -398.193514) (xy 384.699764 -398.351502)
			(xy 384.699268 -398.36166) (xy 384.691494 -398.380428) (xy 384.677128 -398.394794) (xy 384.65836 -398.402568)
			(xy 384.648202 -398.403064) (xy 383.931922 -398.403064) (xy 383.921752 -398.402618) (xy 383.902958 -398.394841)
			(xy 383.888573 -398.380462) (xy 383.880787 -398.361672) (xy 383.88036 -398.351502) (xy 383.88036 -398.193514)
			(xy 383.87993 -398.184329) (xy 383.873429 -398.167145) (xy 383.86766 -398.159986) (xy 383.845834 -398.134365)
			(xy 383.807885 -398.078775) (xy 383.776852 -398.019047) (xy 383.753181 -397.956038) (xy 383.73721 -397.890652)
			(xy 383.729168 -397.823826) (xy 382.600522 -397.823826) (xy 382.572059 -397.878597) (xy 382.534106 -397.934182)
			(xy 382.512316 -397.959834) (xy 382.506524 -397.966983) (xy 382.500006 -397.98417) (xy 382.499616 -397.993362)
			(xy 382.499616 -398.486884) (xy 382.50003 -398.496071) (xy 382.506541 -398.513255) (xy 382.512316 -398.520412)
			(xy 382.53414 -398.546034) (xy 382.572091 -398.601624) (xy 382.603125 -398.661351) (xy 382.626798 -398.72436)
			(xy 382.64277 -398.789746) (xy 382.650812 -398.856573) (xy 382.650808 -398.923881) (xy 382.64276 -398.990707)
			(xy 382.626782 -399.056092) (xy 382.603103 -399.119098) (xy 382.572063 -399.178822) (xy 382.534107 -399.234408)
			(xy 382.512316 -399.26006) (xy 382.506513 -399.267201) (xy 382.500002 -399.284395) (xy 382.499616 -399.293588)
			(xy 382.499616 -399.451576) (xy 382.499165 -399.461695) (xy 382.491428 -399.480395) (xy 382.477122 -399.49471)
			(xy 382.458427 -399.502459) (xy 382.448308 -399.502884) (xy 381.731774 -399.502884) (xy 381.721649 -399.502396)
			(xy 381.702931 -399.494664) (xy 381.688577 -399.480379) (xy 381.680754 -399.461699) (xy 381.680212 -399.451576)
			(xy 381.680212 -399.293588) (xy 381.679805 -399.284401) (xy 381.673289 -399.267216) (xy 381.667512 -399.26006)
			(xy 381.64576 -399.234378) (xy 381.607812 -399.178796) (xy 381.576779 -399.119076) (xy 381.553105 -399.056075)
			(xy 381.537131 -398.990697) (xy 381.529084 -398.923878) (xy 381.529081 -398.856576) (xy 381.537121 -398.789757)
			(xy 381.553089 -398.724377) (xy 381.576757 -398.661374) (xy 381.607784 -398.601651) (xy 381.645727 -398.546064)
			(xy 381.667512 -398.520412) (xy 381.67333 -398.513282) (xy 381.679831 -398.49608) (xy 381.680212 -398.486884)
			(xy 381.680212 -397.993362) (xy 381.679818 -397.984173) (xy 381.673293 -397.966989) (xy 381.667512 -397.959834)
			(xy 381.645735 -397.934173) (xy 381.607788 -397.878588) (xy 381.576755 -397.818865) (xy 381.553083 -397.755862)
			(xy 381.53711 -397.690481) (xy 381.529066 -397.623659) (xy 381.529065 -397.556356) (xy 380.40085 -397.556356)
			(xy 380.403242 -397.560947) (xy 380.42701 -397.62404) (xy 380.443049 -397.689525) (xy 380.451128 -397.756461)
			(xy 380.451131 -397.823882) (xy 380.443059 -397.890818) (xy 380.427026 -397.956306) (xy 380.403265 -398.019401)
			(xy 380.372117 -398.079196) (xy 380.334031 -398.134829) (xy 380.312168 -398.160494) (xy 380.306387 -398.16765)
			(xy 380.299864 -398.184832) (xy 380.299468 -398.194022) (xy 380.299468 -398.351502) (xy 380.298975 -398.361628)
			(xy 380.291248 -398.380347) (xy 380.276964 -398.394703) (xy 380.258283 -398.402524) (xy 380.24816 -398.403064)
			(xy 379.53188 -398.403064) (xy 379.521752 -398.4027) (xy 379.503041 -398.394938) (xy 379.488726 -398.380605)
			(xy 379.480988 -398.361885) (xy 379.480572 -398.351756) (xy 379.480572 -398.194022) (xy 379.480158 -398.184835)
			(xy 379.473648 -398.16765) (xy 379.467872 -398.160494) (xy 379.445972 -398.134859) (xy 379.407886 -398.07922)
			(xy 379.376738 -398.019419) (xy 379.352978 -397.956318) (xy 379.336946 -397.890826) (xy 379.328873 -397.823885)
			(xy 378.200706 -397.823885) (xy 378.171972 -397.879041) (xy 378.133884 -397.934676) (xy 378.11202 -397.960342)
			(xy 378.106225 -397.967489) (xy 378.099709 -397.984678) (xy 378.09932 -397.99387) (xy 378.09932 -398.486376)
			(xy 378.099737 -398.495563) (xy 378.106245 -398.512747) (xy 378.11202 -398.519904) (xy 378.133919 -398.54554)
			(xy 378.172005 -398.60118) (xy 378.203153 -398.66098) (xy 378.226914 -398.724081) (xy 378.242947 -398.789573)
			(xy 378.251019 -398.856514) (xy 378.251016 -398.92394) (xy 378.242937 -398.99088) (xy 378.226898 -399.056371)
			(xy 378.203131 -399.11947) (xy 378.171977 -399.179267) (xy 378.133885 -399.234902) (xy 378.11202 -399.260568)
			(xy 378.106214 -399.267707) (xy 378.099704 -399.284902) (xy 378.09932 -399.294096) (xy 378.09932 -399.451576)
			(xy 378.098865 -399.461694) (xy 378.091128 -399.480394) (xy 378.076824 -399.494708) (xy 378.05813 -399.502458)
			(xy 378.048012 -399.502884) (xy 377.331732 -399.502884) (xy 377.32161 -399.502458) (xy 377.302903 -399.494717)
			(xy 377.288587 -399.480403) (xy 377.280844 -399.461698) (xy 377.280424 -399.451576) (xy 377.280424 -399.294096)
			(xy 377.280011 -399.284909) (xy 377.273499 -399.267725) (xy 377.267724 -399.260568) (xy 377.245895 -399.234874)
			(xy 377.207803 -399.179244) (xy 377.17665 -399.119452) (xy 377.152882 -399.056359) (xy 377.136844 -398.990873)
			(xy 377.128765 -398.923938) (xy 377.128761 -398.856516) (xy 377.136834 -398.78958) (xy 377.152866 -398.724093)
			(xy 377.176627 -398.660997) (xy 377.207775 -398.601202) (xy 377.245861 -398.545569) (xy 377.267724 -398.519904)
			(xy 377.273504 -398.512747) (xy 377.280028 -398.495565) (xy 377.280424 -398.486376) (xy 377.280424 -397.99387)
			(xy 377.280023 -397.984682) (xy 377.273502 -397.967498) (xy 377.267724 -397.960342) (xy 377.245869 -397.934669)
			(xy 377.207778 -397.879036) (xy 377.176626 -397.819241) (xy 377.15286 -397.756145) (xy 377.136823 -397.690657)
			(xy 377.128746 -397.623719) (xy 377.128745 -397.556296) (xy 376.0005 -397.556296) (xy 376.003112 -397.561323)
			(xy 376.026786 -397.624324) (xy 376.042761 -397.689702) (xy 376.050808 -397.756521) (xy 376.050811 -397.823822)
			(xy 376.042771 -397.890642) (xy 376.026803 -397.956022) (xy 376.003135 -398.019025) (xy 375.972108 -398.078747)
			(xy 375.934165 -398.134333) (xy 375.91238 -398.159986) (xy 375.906562 -398.167116) (xy 375.900061 -398.184318)
			(xy 375.89968 -398.193514) (xy 375.89968 -398.351502) (xy 375.899169 -398.361658) (xy 375.891397 -398.380423)
			(xy 375.877037 -398.394788) (xy 375.858274 -398.402565) (xy 375.848118 -398.403064) (xy 375.131838 -398.403064)
			(xy 375.121669 -398.402605) (xy 375.102876 -398.394833) (xy 375.08849 -398.380458) (xy 375.080703 -398.361671)
			(xy 375.080276 -398.351502) (xy 375.080276 -398.193514) (xy 375.079865 -398.184327) (xy 375.073352 -398.167142)
			(xy 375.067576 -398.159986) (xy 375.04575 -398.134365) (xy 375.007799 -398.078775) (xy 374.976766 -398.019048)
			(xy 374.953093 -397.956039) (xy 374.937122 -397.890652) (xy 374.92908 -397.823826) (xy 347.400682 -397.823826)
			(xy 347.372224 -397.878594) (xy 347.334276 -397.934182) (xy 347.312488 -397.959834) (xy 347.306693 -397.96698)
			(xy 347.300178 -397.98417) (xy 347.299788 -397.993362) (xy 347.299788 -398.486884) (xy 347.300209 -398.49607)
			(xy 347.306715 -398.513254) (xy 347.312488 -398.520412) (xy 347.33431 -398.546035) (xy 347.372256 -398.601627)
			(xy 347.403286 -398.661354) (xy 347.426956 -398.724363) (xy 347.442926 -398.789748) (xy 347.450967 -398.856573)
			(xy 347.450963 -398.923881) (xy 347.442916 -398.990705) (xy 347.42694 -399.056089) (xy 347.403264 -399.119095)
			(xy 347.372228 -399.17882) (xy 347.334277 -399.234407) (xy 347.312488 -399.26006) (xy 347.306682 -399.267199)
			(xy 347.300173 -399.284394) (xy 347.299788 -399.293588) (xy 347.299788 -399.451576) (xy 347.299359 -399.46173)
			(xy 347.291569 -399.480484) (xy 347.277174 -399.494809) (xy 347.258382 -399.502507) (xy 347.248226 -399.502884)
			(xy 346.531946 -399.502884) (xy 346.521825 -399.502336) (xy 346.50311 -399.494628) (xy 346.488753 -399.480361)
			(xy 346.480928 -399.461694) (xy 346.480384 -399.451576) (xy 346.480384 -399.293588) (xy 346.479983 -399.2844)
			(xy 346.473463 -399.267215) (xy 346.467684 -399.26006) (xy 346.44593 -399.234379) (xy 346.407977 -399.178798)
			(xy 346.37694 -399.119079) (xy 346.353263 -399.056078) (xy 346.337287 -398.990699) (xy 346.329239 -398.923879)
			(xy 346.329236 -398.856576) (xy 346.337277 -398.789755) (xy 346.353247 -398.724374) (xy 346.376918 -398.661371)
			(xy 346.40795 -398.601648) (xy 346.445897 -398.546064) (xy 346.467684 -398.520412) (xy 346.473499 -398.513279)
			(xy 346.480003 -398.496079) (xy 346.480384 -398.486884) (xy 346.480384 -397.993362) (xy 346.479996 -397.984172)
			(xy 346.473467 -397.966988) (xy 346.467684 -397.959834) (xy 346.445905 -397.934174) (xy 346.407953 -397.87859)
			(xy 346.376917 -397.818868) (xy 346.353241 -397.755864) (xy 346.337266 -397.690483) (xy 346.329221 -397.62366)
			(xy 346.32922 -397.556355) (xy 345.200497 -397.556355) (xy 345.203078 -397.561321) (xy 345.226754 -397.624322)
			(xy 345.24273 -397.689701) (xy 345.250778 -397.75652) (xy 345.250781 -397.823823) (xy 345.242741 -397.890643)
			(xy 345.226771 -397.956023) (xy 345.203102 -398.019026) (xy 345.172072 -398.078749) (xy 345.134126 -398.134334)
			(xy 345.11234 -398.159986) (xy 345.106517 -398.167112) (xy 345.10002 -398.184318) (xy 345.09964 -398.193514)
			(xy 345.09964 -398.351502) (xy 345.099237 -398.361676) (xy 345.091447 -398.380475) (xy 345.077055 -398.394861)
			(xy 345.058253 -398.402642) (xy 345.048078 -398.403064) (xy 344.331798 -398.403064) (xy 344.32164 -398.402568)
			(xy 344.302872 -398.394794) (xy 344.288506 -398.380428) (xy 344.280732 -398.36166) (xy 344.280236 -398.351502)
			(xy 344.280236 -398.193514) (xy 344.279811 -398.184329) (xy 344.273307 -398.167144) (xy 344.267536 -398.159986)
			(xy 344.245711 -398.134365) (xy 344.207763 -398.078774) (xy 344.176732 -398.019046) (xy 344.153061 -397.956037)
			(xy 344.137091 -397.890651) (xy 344.12905 -397.823825) (xy 343.000914 -397.823825) (xy 342.972147 -397.879042)
			(xy 342.934057 -397.934677) (xy 342.912192 -397.960342) (xy 342.906394 -397.967486) (xy 342.899881 -397.984678)
			(xy 342.899492 -397.99387) (xy 342.899492 -398.486376) (xy 342.899916 -398.495562) (xy 342.90642 -398.512746)
			(xy 342.912192 -398.519904) (xy 342.934092 -398.54554) (xy 342.97218 -398.601178) (xy 343.003329 -398.660979)
			(xy 343.027092 -398.724079) (xy 343.043125 -398.789572) (xy 343.051198 -398.856514) (xy 343.051195 -398.92394)
			(xy 343.043115 -398.990881) (xy 343.027076 -399.056372) (xy 343.003307 -399.119471) (xy 342.972152 -399.179268)
			(xy 342.934058 -399.234903) (xy 342.912192 -399.260568) (xy 342.906383 -399.267704) (xy 342.899876 -399.284902)
			(xy 342.899492 -399.294096) (xy 342.899492 -399.451576) (xy 342.899064 -399.461698) (xy 342.891323 -399.480403)
			(xy 342.877009 -399.494718) (xy 342.858306 -399.502463) (xy 342.848184 -399.502884) (xy 342.131904 -399.502884)
			(xy 342.12178 -399.50248) (xy 342.103073 -399.494731) (xy 342.088758 -399.48041) (xy 342.081016 -399.4617)
			(xy 342.080596 -399.451576) (xy 342.080596 -399.294096) (xy 342.080189 -399.284909) (xy 342.073673 -399.267724)
			(xy 342.067896 -399.260568) (xy 342.046068 -399.234874) (xy 342.007978 -399.179243) (xy 341.976826 -399.119451)
			(xy 341.95306 -399.056358) (xy 341.937022 -398.990872) (xy 341.928943 -398.923937) (xy 341.92894 -398.856517)
			(xy 341.937012 -398.789581) (xy 341.953044 -398.724094) (xy 341.976804 -398.660999) (xy 342.00795 -398.601203)
			(xy 342.046034 -398.545569) (xy 342.067896 -398.519904) (xy 342.073673 -398.512745) (xy 342.080199 -398.495565)
			(xy 342.080596 -398.486376) (xy 342.080596 -397.99387) (xy 342.080201 -397.984681) (xy 342.073677 -397.967497)
			(xy 342.067896 -397.960342) (xy 342.046042 -397.934669) (xy 342.007953 -397.879035) (xy 341.976802 -397.81924)
			(xy 341.953038 -397.756144) (xy 341.937002 -397.690656) (xy 341.928925 -397.623719) (xy 341.928924 -397.556296)
			(xy 340.800676 -397.556296) (xy 340.803288 -397.561322) (xy 340.826964 -397.624322) (xy 340.84294 -397.689701)
			(xy 340.850987 -397.75652) (xy 340.85099 -397.823823) (xy 340.84295 -397.890643) (xy 340.826981 -397.956023)
			(xy 340.803312 -398.019026) (xy 340.772282 -398.078748) (xy 340.734338 -398.134334) (xy 340.712552 -398.159986)
			(xy 340.70673 -398.167113) (xy 340.700232 -398.184318) (xy 340.699852 -398.193514) (xy 340.699852 -398.351502)
			(xy 340.699438 -398.361675) (xy 340.69165 -398.380472) (xy 340.677262 -398.394857) (xy 340.658463 -398.40264)
			(xy 340.64829 -398.403064) (xy 339.93201 -398.403064) (xy 339.921839 -398.402628) (xy 339.903045 -398.394847)
			(xy 339.88866 -398.380465) (xy 339.880874 -398.361673) (xy 339.880448 -398.351502) (xy 339.880448 -398.193514)
			(xy 339.88002 -398.184329) (xy 339.873518 -398.167145) (xy 339.867748 -398.159986) (xy 339.845922 -398.134365)
			(xy 339.807974 -398.078774) (xy 339.776942 -398.019046) (xy 339.753271 -397.956038) (xy 339.7373 -397.890652)
			(xy 339.729259 -397.823826) (xy 338.600595 -397.823826) (xy 338.572138 -397.878594) (xy 338.534191 -397.934181)
			(xy 338.512404 -397.959834) (xy 338.506611 -397.966982) (xy 338.500094 -397.98417) (xy 338.499704 -397.993362)
			(xy 338.499704 -398.486884) (xy 338.500121 -398.49607) (xy 338.50663 -398.513255) (xy 338.512404 -398.520412)
			(xy 338.534226 -398.546036) (xy 338.572171 -398.601627) (xy 338.6032 -398.661355) (xy 338.626869 -398.724363)
			(xy 338.642838 -398.789748) (xy 338.650879 -398.856574) (xy 338.650875 -398.923881) (xy 338.642828 -398.990705)
			(xy 338.626853 -399.056089) (xy 338.603178 -399.119094) (xy 338.572143 -399.178819) (xy 338.534193 -399.234407)
			(xy 338.512404 -399.26006) (xy 338.5066 -399.2672) (xy 338.50009 -399.284394) (xy 338.499704 -399.293588)
			(xy 338.499704 -399.451576) (xy 338.499259 -399.461728) (xy 338.491472 -399.480479) (xy 338.477082 -399.494803)
			(xy 338.458296 -399.502505) (xy 338.448142 -399.502884) (xy 337.731862 -399.502884) (xy 337.721736 -399.502405)
			(xy 337.703018 -399.494669) (xy 337.688664 -399.480381) (xy 337.680842 -399.4617) (xy 337.6803 -399.451576)
			(xy 337.6803 -399.293588) (xy 337.679895 -399.2844) (xy 337.673378 -399.267216) (xy 337.6676 -399.26006)
			(xy 337.645849 -399.234378) (xy 337.607901 -399.178795) (xy 337.576869 -399.119075) (xy 337.553196 -399.056075)
			(xy 337.537221 -398.990697) (xy 337.529175 -398.923878) (xy 337.529172 -398.856576) (xy 337.537212 -398.789757)
			(xy 337.55318 -398.724377) (xy 337.576847 -398.661374) (xy 337.607874 -398.601651) (xy 337.645816 -398.546065)
			(xy 337.6676 -398.520412) (xy 337.673416 -398.513281) (xy 337.679919 -398.49608) (xy 337.6803 -398.486884)
			(xy 337.6803 -397.993362) (xy 337.679908 -397.984173) (xy 337.673382 -397.966989) (xy 337.6676 -397.959834)
			(xy 337.645823 -397.934173) (xy 337.607877 -397.878587) (xy 337.576845 -397.818864) (xy 337.553174 -397.755861)
			(xy 337.537201 -397.69048) (xy 337.529157 -397.623659) (xy 337.529156 -397.556356) (xy 336.40094 -397.556356)
			(xy 336.403332 -397.560946) (xy 336.4271 -397.624039) (xy 336.443139 -397.689525) (xy 336.451219 -397.756461)
			(xy 336.451222 -397.823882) (xy 336.44315 -397.890819) (xy 336.427117 -397.956306) (xy 336.403355 -398.019402)
			(xy 336.372206 -398.079196) (xy 336.334119 -398.13483) (xy 336.312256 -398.160494) (xy 336.306474 -398.167649)
			(xy 336.299952 -398.184832) (xy 336.299556 -398.194022) (xy 336.299556 -398.351502) (xy 336.299075 -398.361629)
			(xy 336.291346 -398.380351) (xy 336.277058 -398.394708) (xy 336.258373 -398.402526) (xy 336.248248 -398.403064)
			(xy 335.531968 -398.403064) (xy 335.521807 -398.402704) (xy 335.503047 -398.394891) (xy 335.488724 -398.380475)
			(xy 335.481032 -398.361665) (xy 335.48066 -398.351502) (xy 335.48066 -398.194022) (xy 335.480226 -398.184838)
			(xy 335.473727 -398.167654) (xy 335.46796 -398.160494) (xy 335.44606 -398.134859) (xy 335.407975 -398.079219)
			(xy 335.376828 -398.019418) (xy 335.353068 -397.956318) (xy 335.337036 -397.890825) (xy 335.328964 -397.823884)
			(xy 334.200796 -397.823884) (xy 334.172062 -397.879042) (xy 334.133972 -397.934677) (xy 334.112108 -397.960342)
			(xy 334.106312 -397.967488) (xy 334.099797 -397.984678) (xy 334.099408 -397.99387) (xy 334.099408 -398.486376)
			(xy 334.099828 -398.495562) (xy 334.106335 -398.512747) (xy 334.112108 -398.519904) (xy 334.134007 -398.54554)
			(xy 334.172094 -398.601179) (xy 334.203243 -398.660979) (xy 334.227005 -398.72408) (xy 334.243037 -398.789573)
			(xy 334.25111 -398.856514) (xy 334.251107 -398.92394) (xy 334.243028 -398.990881) (xy 334.226989 -399.056372)
			(xy 334.203221 -399.11947) (xy 334.172066 -399.179267) (xy 334.133974 -399.234903) (xy 334.112108 -399.260568)
			(xy 334.106301 -399.267706) (xy 334.099792 -399.284902) (xy 334.099408 -399.294096) (xy 334.099408 -399.451576)
			(xy 334.098965 -399.461696) (xy 334.091226 -399.480398) (xy 334.076918 -399.494712) (xy 334.05822 -399.50246)
			(xy 334.0481 -399.502884) (xy 333.33182 -399.502884) (xy 333.321697 -399.502467) (xy 333.302991 -399.494723)
			(xy 333.288675 -399.480406) (xy 333.280932 -399.461699) (xy 333.280512 -399.451576) (xy 333.280512 -399.294096)
			(xy 333.280101 -399.284909) (xy 333.273587 -399.267725) (xy 333.267812 -399.260568) (xy 333.245983 -399.234874)
			(xy 333.207892 -399.179244) (xy 333.176739 -399.119452) (xy 333.152973 -399.056358) (xy 333.136934 -398.990873)
			(xy 333.128855 -398.923938) (xy 333.128852 -398.856516) (xy 333.136925 -398.78958) (xy 333.152957 -398.724093)
			(xy 333.176717 -398.660998) (xy 333.207865 -398.601203) (xy 333.24595 -398.545569) (xy 333.267812 -398.519904)
			(xy 333.273591 -398.512746) (xy 333.280116 -398.495565) (xy 333.280512 -398.486376) (xy 333.280512 -397.99387)
			(xy 333.280114 -397.984682) (xy 333.273592 -397.967497) (xy 333.267812 -397.960342) (xy 333.245957 -397.934669)
			(xy 333.207868 -397.879036) (xy 333.176716 -397.819241) (xy 333.152951 -397.756145) (xy 333.136914 -397.690657)
			(xy 333.128837 -397.623719) (xy 333.128836 -397.556296) (xy 332.00059 -397.556296) (xy 332.003202 -397.561323)
			(xy 332.026877 -397.624323) (xy 332.042852 -397.689701) (xy 332.050899 -397.75652) (xy 332.050902 -397.823822)
			(xy 332.042862 -397.890642) (xy 332.026893 -397.956022) (xy 332.003225 -398.019025) (xy 331.972197 -398.078748)
			(xy 331.934253 -398.134334) (xy 331.912468 -398.159986) (xy 331.906648 -398.167115) (xy 331.900148 -398.184318)
			(xy 331.899768 -398.193514) (xy 331.899768 -398.351502) (xy 331.899268 -398.361659) (xy 331.891494 -398.380427)
			(xy 331.877131 -398.394792) (xy 331.858363 -398.402568) (xy 331.848206 -398.403064) (xy 331.131926 -398.403064)
			(xy 331.121756 -398.402615) (xy 331.102963 -398.394839) (xy 331.088577 -398.380461) (xy 331.080791 -398.361671)
			(xy 331.080364 -398.351502) (xy 331.080364 -398.193514) (xy 331.079933 -398.184329) (xy 331.073432 -398.167146)
			(xy 331.067664 -398.159986) (xy 331.045838 -398.134365) (xy 331.007889 -398.078775) (xy 330.976856 -398.019047)
			(xy 330.953184 -397.956038) (xy 330.937213 -397.890652) (xy 330.929171 -397.823826) (xy 326.525636 -397.823826)
			(xy 326.525636 -401.723737) (xy 330.929183 -401.723737) (xy 330.929184 -401.65643) (xy 330.937231 -401.589605)
			(xy 330.953207 -401.524221) (xy 330.976884 -401.461216) (xy 331.007921 -401.401492) (xy 331.045874 -401.345906)
			(xy 331.067664 -401.320254) (xy 331.07347 -401.313116) (xy 331.079977 -401.29592) (xy 331.080364 -401.286726)
			(xy 331.080364 -400.793458) (xy 331.07996 -400.78427) (xy 331.073441 -400.767087) (xy 331.067664 -400.75993)
			(xy 331.045882 -400.734273) (xy 331.007931 -400.678688) (xy 330.976896 -400.618965) (xy 330.953222 -400.555961)
			(xy 330.937248 -400.490579) (xy 330.929203 -400.423757) (xy 330.929202 -400.356452) (xy 330.937246 -400.289629)
			(xy 330.953219 -400.224247) (xy 330.976892 -400.161243) (xy 331.007926 -400.10152) (xy 331.045876 -400.045934)
			(xy 331.067664 -400.020282) (xy 331.073459 -400.013136) (xy 331.079973 -399.995946) (xy 331.080364 -399.986754)
			(xy 331.080364 -399.828766) (xy 331.080806 -399.818603) (xy 331.088597 -399.799828) (xy 331.102978 -399.785463)
			(xy 331.121762 -399.777694) (xy 331.131926 -399.777204) (xy 331.848206 -399.777204) (xy 331.85836 -399.777728)
			(xy 331.877123 -399.785498) (xy 331.891486 -399.799854) (xy 331.899267 -399.818612) (xy 331.899768 -399.828766)
			(xy 331.899768 -399.986754) (xy 331.900208 -399.995938) (xy 331.906702 -400.013122) (xy 331.912468 -400.020282)
			(xy 331.934262 -400.045929) (xy 331.97221 -400.101517) (xy 332.003242 -400.161241) (xy 332.026915 -400.224246)
			(xy 332.042887 -400.289629) (xy 332.05093 -400.356452) (xy 332.05093 -400.423757) (xy 332.042885 -400.49058)
			(xy 332.026912 -400.555963) (xy 332.003239 -400.618967) (xy 331.972205 -400.678691) (xy 331.934256 -400.734278)
			(xy 331.912468 -400.75993) (xy 331.906672 -400.767076) (xy 331.900158 -400.784266) (xy 331.899768 -400.793458)
			(xy 331.899768 -401.286726) (xy 331.900173 -401.295914) (xy 331.906691 -401.313098) (xy 331.912468 -401.320254)
			(xy 331.934234 -401.345924) (xy 331.972183 -401.401508) (xy 332.003216 -401.461229) (xy 332.02689 -401.524231)
			(xy 332.042864 -401.589611) (xy 332.05091 -401.656432) (xy 332.050912 -401.723735) (xy 332.04287 -401.790556)
			(xy 332.0269 -401.855937) (xy 332.00323 -401.91894) (xy 331.9722 -401.978663) (xy 331.934254 -402.03425)
			(xy 331.912468 -402.059902) (xy 331.906684 -402.067056) (xy 331.900163 -402.08424) (xy 331.899768 -402.09343)
			(xy 331.899768 -402.251418) (xy 331.899282 -402.261576) (xy 331.891502 -402.280345) (xy 331.877135 -402.294709)
			(xy 331.858364 -402.302484) (xy 331.848206 -402.30298) (xy 331.131926 -402.30298) (xy 331.121758 -402.302515)
			(xy 331.102968 -402.294742) (xy 331.088583 -402.280369) (xy 331.080794 -402.261585) (xy 331.080364 -402.251418)
			(xy 331.080364 -402.09343) (xy 331.079925 -402.084246) (xy 331.07343 -402.067062) (xy 331.067664 -402.059902)
			(xy 331.045854 -402.034268) (xy 331.007904 -401.97868) (xy 330.97687 -401.918954) (xy 330.953197 -401.855947)
			(xy 330.937225 -401.790562) (xy 330.929183 -401.723737) (xy 326.525636 -401.723737) (xy 326.525636 -402.823878)
			(xy 333.128796 -402.823878) (xy 333.128801 -402.75645) (xy 333.136882 -402.689508) (xy 333.152922 -402.624016)
			(xy 333.176693 -402.560918) (xy 333.20785 -402.50112) (xy 333.245945 -402.445485) (xy 333.267812 -402.41982)
			(xy 333.273626 -402.412687) (xy 333.28013 -402.395487) (xy 333.280512 -402.386292) (xy 333.280512 -401.89404)
			(xy 333.28008 -401.884855) (xy 333.273581 -401.867671) (xy 333.267812 -401.860512) (xy 333.245928 -401.834863)
			(xy 333.207839 -401.779227) (xy 333.176689 -401.719428) (xy 333.152925 -401.656329) (xy 333.136891 -401.590838)
			(xy 333.128816 -401.523898) (xy 333.128818 -401.456472) (xy 333.136896 -401.389532) (xy 333.152934 -401.324042)
			(xy 333.176701 -401.260944) (xy 333.207855 -401.201148) (xy 333.245946 -401.145513) (xy 333.267812 -401.119848)
			(xy 333.273615 -401.112707) (xy 333.280125 -401.095513) (xy 333.280512 -401.08632) (xy 333.280512 -400.92884)
			(xy 333.280949 -400.918719) (xy 333.288686 -400.900014) (xy 333.302997 -400.885698) (xy 333.321699 -400.877953)
			(xy 333.33182 -400.877532) (xy 334.0481 -400.877532) (xy 334.058226 -400.877917) (xy 334.076936 -400.885671)
			(xy 334.091252 -400.899997) (xy 334.098991 -400.918713) (xy 334.099408 -400.92884) (xy 334.099408 -401.08632)
			(xy 334.099807 -401.095508) (xy 334.106328 -401.112693) (xy 334.112108 -401.119848) (xy 334.133952 -401.14553)
			(xy 334.172041 -401.201162) (xy 334.203192 -401.260956) (xy 334.226957 -401.324051) (xy 334.242994 -401.389538)
			(xy 334.251071 -401.456474) (xy 334.251073 -401.523896) (xy 334.242999 -401.590833) (xy 334.226966 -401.656321)
			(xy 334.203204 -401.719417) (xy 334.200923 -401.723796) (xy 335.328975 -401.723796) (xy 335.328977 -401.656371)
			(xy 335.337055 -401.589432) (xy 335.353091 -401.523942) (xy 335.376856 -401.460845) (xy 335.408007 -401.401048)
			(xy 335.446096 -401.345412) (xy 335.46796 -401.319746) (xy 335.473769 -401.31261) (xy 335.480275 -401.295412)
			(xy 335.48066 -401.286218) (xy 335.48066 -400.793966) (xy 335.480253 -400.784779) (xy 335.473735 -400.767595)
			(xy 335.46796 -400.760438) (xy 335.446103 -400.734767) (xy 335.408017 -400.679133) (xy 335.376868 -400.619337)
			(xy 335.353106 -400.556241) (xy 335.337071 -400.490753) (xy 335.328995 -400.423816) (xy 335.328995 -400.356393)
			(xy 335.337069 -400.289456) (xy 335.353103 -400.223968) (xy 335.376865 -400.160872) (xy 335.408012 -400.101075)
			(xy 335.446098 -400.04544) (xy 335.46796 -400.019774) (xy 335.473757 -400.01263) (xy 335.48027 -399.995438)
			(xy 335.48066 -399.986246) (xy 335.48066 -399.828766) (xy 335.481099 -399.818635) (xy 335.488842 -399.799909)
			(xy 335.503143 -399.785553) (xy 335.521839 -399.777739) (xy 335.531968 -399.777204) (xy 336.248248 -399.777204)
			(xy 336.258406 -399.777583) (xy 336.27716 -399.785395) (xy 336.291482 -399.799804) (xy 336.299179 -399.818606)
			(xy 336.299556 -399.828766) (xy 336.299556 -399.986246) (xy 336.300002 -399.995429) (xy 336.306492 -400.012613)
			(xy 336.312256 -400.019774) (xy 336.334127 -400.045434) (xy 336.372219 -400.101068) (xy 336.403372 -400.160864)
			(xy 336.427138 -400.223962) (xy 336.443174 -400.289452) (xy 336.45125 -400.356392) (xy 336.451249 -400.423817)
			(xy 336.443172 -400.490756) (xy 336.427135 -400.556246) (xy 336.403368 -400.619344) (xy 336.372214 -400.67914)
			(xy 336.334122 -400.734774) (xy 336.312256 -400.760438) (xy 336.306455 -400.76758) (xy 336.299944 -400.784773)
			(xy 336.299556 -400.793966) (xy 336.299556 -401.286218) (xy 336.299967 -401.295405) (xy 336.306481 -401.312589)
			(xy 336.312256 -401.319746) (xy 336.3341 -401.345428) (xy 336.372192 -401.401059) (xy 336.403346 -401.460853)
			(xy 336.427114 -401.523948) (xy 336.443152 -401.589435) (xy 336.45123 -401.656372) (xy 336.451232 -401.723795)
			(xy 336.443158 -401.790732) (xy 336.427123 -401.856221) (xy 336.40336 -401.919317) (xy 336.372209 -401.979112)
			(xy 336.33412 -402.034746) (xy 336.312256 -402.06041) (xy 336.306467 -402.06756) (xy 336.299949 -402.084747)
			(xy 336.299556 -402.093938) (xy 336.299556 -402.251418) (xy 336.299088 -402.261546) (xy 336.291354 -402.280269)
			(xy 336.277062 -402.294625) (xy 336.258374 -402.302443) (xy 336.248248 -402.30298) (xy 335.531968 -402.30298)
			(xy 335.521809 -402.302604) (xy 335.503052 -402.294794) (xy 335.488729 -402.280384) (xy 335.481034 -402.261579)
			(xy 335.48066 -402.251418) (xy 335.48066 -402.093938) (xy 335.480218 -402.084754) (xy 335.473725 -402.06757)
			(xy 335.46796 -402.06041) (xy 335.446076 -402.034762) (xy 335.40799 -401.979124) (xy 335.376843 -401.919325)
			(xy 335.353082 -401.856226) (xy 335.337049 -401.790735) (xy 335.328975 -401.723796) (xy 334.200923 -401.723796)
			(xy 334.172056 -401.779212) (xy 334.13397 -401.834847) (xy 334.112108 -401.860512) (xy 334.106325 -401.867667)
			(xy 334.099802 -401.88485) (xy 334.099408 -401.89404) (xy 334.099408 -402.386292) (xy 334.09982 -402.395479)
			(xy 334.106332 -402.412663) (xy 334.112108 -402.41982) (xy 334.133925 -402.445524) (xy 334.172014 -402.501153)
			(xy 334.203166 -402.560944) (xy 334.226933 -402.624036) (xy 334.242972 -402.68952) (xy 334.251051 -402.756454)
			(xy 334.251055 -402.823818) (xy 337.529116 -402.823818) (xy 337.52912 -402.75651) (xy 337.537169 -402.689685)
			(xy 337.553145 -402.6243) (xy 337.576822 -402.561294) (xy 337.607859 -402.501569) (xy 337.645811 -402.445981)
			(xy 337.6676 -402.420328) (xy 337.67341 -402.413192) (xy 337.679917 -402.395994) (xy 337.6803 -402.3868)
			(xy 337.6803 -401.893532) (xy 337.679874 -401.884346) (xy 337.673371 -401.867162) (xy 337.6676 -401.860004)
			(xy 337.645794 -401.834367) (xy 337.607848 -401.778778) (xy 337.576818 -401.719052) (xy 337.553148 -401.656045)
			(xy 337.537178 -401.590662) (xy 337.529136 -401.523838) (xy 337.529137 -401.456532) (xy 337.537183 -401.389709)
			(xy 337.553157 -401.324326) (xy 337.57683 -401.261321) (xy 337.607864 -401.201596) (xy 337.645812 -401.146009)
			(xy 337.6676 -401.120356) (xy 337.673398 -401.113212) (xy 337.679912 -401.09602) (xy 337.6803 -401.086828)
			(xy 337.6803 -400.92884) (xy 337.680755 -400.918688) (xy 337.688537 -400.899937) (xy 337.702924 -400.885612)
			(xy 337.721709 -400.877911) (xy 337.731862 -400.877532) (xy 338.448142 -400.877532) (xy 338.45827 -400.877992)
			(xy 338.476991 -400.885732) (xy 338.491346 -400.900026) (xy 338.499165 -400.918714) (xy 338.499704 -400.92884)
			(xy 338.499704 -401.086828) (xy 338.5001 -401.096017) (xy 338.506623 -401.113201) (xy 338.512404 -401.120356)
			(xy 338.534171 -401.146025) (xy 338.572117 -401.20161) (xy 338.603149 -401.261332) (xy 338.626821 -401.324334)
			(xy 338.642794 -401.389714) (xy 338.650839 -401.456534) (xy 338.650841 -401.523836) (xy 338.6428 -401.590657)
			(xy 338.62683 -401.656037) (xy 338.603161 -401.719041) (xy 338.600721 -401.723737) (xy 339.72927 -401.723737)
			(xy 339.729272 -401.65643) (xy 339.737319 -401.589606) (xy 339.753294 -401.524222) (xy 339.77697 -401.461217)
			(xy 339.808006 -401.401492) (xy 339.845959 -401.345906) (xy 339.867748 -401.320254) (xy 339.873553 -401.313115)
			(xy 339.880061 -401.295919) (xy 339.880448 -401.286726) (xy 339.880448 -400.793458) (xy 339.880047 -400.78427)
			(xy 339.873526 -400.767086) (xy 339.867748 -400.75993) (xy 339.845966 -400.734273) (xy 339.808017 -400.678687)
			(xy 339.776983 -400.618965) (xy 339.753309 -400.555961) (xy 339.737335 -400.490579) (xy 339.729291 -400.423757)
			(xy 339.72929 -400.356452) (xy 339.737334 -400.28963) (xy 339.753306 -400.224248) (xy 339.776979 -400.161244)
			(xy 339.808012 -400.10152) (xy 339.845961 -400.045934) (xy 339.867748 -400.020282) (xy 339.873541 -400.013134)
			(xy 339.880056 -399.995946) (xy 339.880448 -399.986754) (xy 339.880448 -399.828766) (xy 339.880906 -399.818605)
			(xy 339.888693 -399.799833) (xy 339.90307 -399.785469) (xy 339.921848 -399.777697) (xy 339.93201 -399.777204)
			(xy 340.64829 -399.777204) (xy 340.658443 -399.777741) (xy 340.677205 -399.785506) (xy 340.69157 -399.799858)
			(xy 340.699351 -399.818613) (xy 340.699852 -399.828766) (xy 340.699852 -399.986754) (xy 340.700295 -399.995937)
			(xy 340.706787 -400.013121) (xy 340.712552 -400.020282) (xy 340.734346 -400.045929) (xy 340.772295 -400.101516)
			(xy 340.803329 -400.16124) (xy 340.827002 -400.224245) (xy 340.842975 -400.289628) (xy 340.851018 -400.356452)
			(xy 340.851018 -400.423757) (xy 340.842973 -400.490581) (xy 340.826999 -400.555963) (xy 340.803325 -400.618968)
			(xy 340.772291 -400.678692) (xy 340.734341 -400.734278) (xy 340.712552 -400.75993) (xy 340.706754 -400.767074)
			(xy 340.700242 -400.784266) (xy 340.699852 -400.793458) (xy 340.699852 -401.286726) (xy 340.70026 -401.295913)
			(xy 340.706777 -401.313097) (xy 340.712552 -401.320254) (xy 340.734318 -401.345924) (xy 340.772268 -401.401508)
			(xy 340.803303 -401.461229) (xy 340.826977 -401.524231) (xy 340.842952 -401.589611) (xy 340.850998 -401.656432)
			(xy 340.851 -401.723735) (xy 340.842958 -401.790556) (xy 340.826987 -401.855937) (xy 340.803316 -401.918941)
			(xy 340.772285 -401.978664) (xy 340.734338 -402.03425) (xy 340.712552 -402.059902) (xy 340.706766 -402.067055)
			(xy 340.700246 -402.08424) (xy 340.699852 -402.09343) (xy 340.699852 -402.251418) (xy 340.699381 -402.261578)
			(xy 340.691599 -402.28035) (xy 340.677226 -402.294715) (xy 340.65845 -402.302487) (xy 340.64829 -402.30298)
			(xy 339.93201 -402.30298) (xy 339.921855 -402.302459) (xy 339.90309 -402.294691) (xy 339.888725 -402.280334)
			(xy 339.880947 -402.261573) (xy 339.880448 -402.251418) (xy 339.880448 -402.09343) (xy 339.880013 -402.084246)
			(xy 339.873515 -402.067062) (xy 339.867748 -402.059902) (xy 339.845938 -402.034268) (xy 339.807989 -401.978679)
			(xy 339.776957 -401.918953) (xy 339.753285 -401.855946) (xy 339.737313 -401.790562) (xy 339.72927 -401.723737)
			(xy 338.600721 -401.723737) (xy 338.572133 -401.778764) (xy 338.534189 -401.834351) (xy 338.512404 -401.860004)
			(xy 338.506624 -401.867161) (xy 338.500099 -401.884342) (xy 338.499704 -401.893532) (xy 338.499704 -402.3868)
			(xy 338.500113 -402.395987) (xy 338.506628 -402.413172) (xy 338.512404 -402.420328) (xy 338.534143 -402.44602)
			(xy 338.572091 -402.501601) (xy 338.603124 -402.56132) (xy 338.626797 -402.624319) (xy 338.642772 -402.689696)
			(xy 338.65082 -402.756514) (xy 338.650824 -402.823814) (xy 338.650816 -402.823878) (xy 341.928884 -402.823878)
			(xy 341.928889 -402.75645) (xy 341.936969 -402.689509) (xy 341.95301 -402.624017) (xy 341.976779 -402.560918)
			(xy 342.007935 -402.501121) (xy 342.046029 -402.445485) (xy 342.067896 -402.41982) (xy 342.073709 -402.412686)
			(xy 342.080214 -402.395487) (xy 342.080596 -402.386292) (xy 342.080596 -401.89404) (xy 342.080168 -401.884855)
			(xy 342.073667 -401.86767) (xy 342.067896 -401.860512) (xy 342.046013 -401.834863) (xy 342.007925 -401.779226)
			(xy 341.976775 -401.719428) (xy 341.953012 -401.656329) (xy 341.936978 -401.590838) (xy 341.928904 -401.523898)
			(xy 341.928906 -401.456472) (xy 341.936984 -401.389533) (xy 341.953021 -401.324043) (xy 341.976787 -401.260945)
			(xy 342.00794 -401.201148) (xy 342.046031 -401.145513) (xy 342.067896 -401.119848) (xy 342.073697 -401.112706)
			(xy 342.080209 -401.095513) (xy 342.080596 -401.08632) (xy 342.080596 -400.92884) (xy 342.081049 -400.918721)
			(xy 342.088783 -400.900019) (xy 342.103088 -400.885703) (xy 342.121785 -400.877956) (xy 342.131904 -400.877532)
			(xy 342.848184 -400.877532) (xy 342.858309 -400.87793) (xy 342.877019 -400.885679) (xy 342.891335 -400.900001)
			(xy 342.899075 -400.918714) (xy 342.899492 -400.92884) (xy 342.899492 -401.08632) (xy 342.899894 -401.095508)
			(xy 342.906413 -401.112692) (xy 342.912192 -401.119848) (xy 342.934037 -401.145529) (xy 342.972126 -401.201161)
			(xy 343.003278 -401.260955) (xy 343.027044 -401.32405) (xy 343.043081 -401.389537) (xy 343.051159 -401.456474)
			(xy 343.051161 -401.523896) (xy 343.043087 -401.590833) (xy 343.027053 -401.656321) (xy 343.003291 -401.719417)
			(xy 343.001041 -401.723737) (xy 344.129061 -401.723737) (xy 344.129063 -401.65643) (xy 344.13711 -401.589606)
			(xy 344.153085 -401.524223) (xy 344.17676 -401.461217) (xy 344.207796 -401.401493) (xy 344.245747 -401.345906)
			(xy 344.267536 -401.320254) (xy 344.273339 -401.313114) (xy 344.279849 -401.295919) (xy 344.280236 -401.286726)
			(xy 344.280236 -400.793458) (xy 344.279838 -400.78427) (xy 344.273315 -400.767086) (xy 344.267536 -400.75993)
			(xy 344.245754 -400.734273) (xy 344.207805 -400.678687) (xy 344.176772 -400.618964) (xy 344.153099 -400.55596)
			(xy 344.137126 -400.490579) (xy 344.129081 -400.423757) (xy 344.129081 -400.356452) (xy 344.137124 -400.28963)
			(xy 344.153096 -400.224248) (xy 344.176768 -400.161244) (xy 344.207801 -400.101521) (xy 344.245749 -400.045934)
			(xy 344.267536 -400.020282) (xy 344.273327 -400.013133) (xy 344.279844 -399.995945) (xy 344.280236 -399.986754)
			(xy 344.280236 -399.828766) (xy 344.280705 -399.818606) (xy 344.288491 -399.799837) (xy 344.302864 -399.785473)
			(xy 344.321638 -399.777699) (xy 344.331798 -399.777204) (xy 345.048078 -399.777204) (xy 345.05823 -399.77775)
			(xy 345.076992 -399.785511) (xy 345.091357 -399.799861) (xy 345.099139 -399.818614) (xy 345.09964 -399.828766)
			(xy 345.09964 -399.986754) (xy 345.100086 -399.995937) (xy 345.106576 -400.013121) (xy 345.11234 -400.020282)
			(xy 345.134134 -400.045929) (xy 345.172084 -400.101516) (xy 345.203118 -400.16124) (xy 345.226792 -400.224245)
			(xy 345.242765 -400.289628) (xy 345.250809 -400.356452) (xy 345.250808 -400.423757) (xy 345.242763 -400.490581)
			(xy 345.226789 -400.555964) (xy 345.203115 -400.618968) (xy 345.172079 -400.678692) (xy 345.134129 -400.734278)
			(xy 345.11234 -400.75993) (xy 345.106541 -400.767073) (xy 345.100029 -400.784265) (xy 345.09964 -400.793458)
			(xy 345.09964 -401.286726) (xy 345.100051 -401.295913) (xy 345.106566 -401.313096) (xy 345.11234 -401.320254)
			(xy 345.134107 -401.345924) (xy 345.172057 -401.401507) (xy 345.203093 -401.461228) (xy 345.226768 -401.52423)
			(xy 345.242743 -401.589611) (xy 345.250789 -401.656432) (xy 345.250791 -401.723735) (xy 345.242749 -401.790557)
			(xy 345.226778 -401.855938) (xy 345.203106 -401.918942) (xy 345.172074 -401.978664) (xy 345.134127 -402.03425)
			(xy 345.11234 -402.059902) (xy 345.106553 -402.067053) (xy 345.100034 -402.084239) (xy 345.09964 -402.09343)
			(xy 345.09964 -402.251418) (xy 345.09925 -402.261593) (xy 345.091455 -402.280393) (xy 345.077059 -402.294778)
			(xy 345.058254 -402.302558) (xy 345.048078 -402.30298) (xy 344.331798 -402.30298) (xy 344.321642 -402.302469)
			(xy 344.302877 -402.294697) (xy 344.288512 -402.280337) (xy 344.280735 -402.261574) (xy 344.280236 -402.251418)
			(xy 344.280236 -402.09343) (xy 344.279803 -402.084245) (xy 344.273304 -402.067061) (xy 344.267536 -402.059902)
			(xy 344.245727 -402.034268) (xy 344.207779 -401.978679) (xy 344.176746 -401.918953) (xy 344.153075 -401.855946)
			(xy 344.137104 -401.790561) (xy 344.129061 -401.723737) (xy 343.001041 -401.723737) (xy 342.972142 -401.779213)
			(xy 342.934055 -401.834847) (xy 342.912192 -401.860512) (xy 342.906407 -401.867665) (xy 342.899886 -401.88485)
			(xy 342.899492 -401.89404) (xy 342.899492 -402.386292) (xy 342.899908 -402.395479) (xy 342.906418 -402.412663)
			(xy 342.912192 -402.41982) (xy 342.934009 -402.445524) (xy 342.9721 -402.501153) (xy 343.003253 -402.560944)
			(xy 343.02702 -402.624035) (xy 343.043059 -402.68952) (xy 343.051139 -402.756454) (xy 343.051143 -402.823819)
			(xy 346.329179 -402.823819) (xy 346.329184 -402.756509) (xy 346.337233 -402.689682) (xy 346.353213 -402.624297)
			(xy 346.376893 -402.56129) (xy 346.407934 -402.501566) (xy 346.445892 -402.445979) (xy 346.467684 -402.420328)
			(xy 346.473492 -402.413191) (xy 346.48 -402.395994) (xy 346.480384 -402.3868) (xy 346.480384 -401.893532)
			(xy 346.479962 -401.884346) (xy 346.473457 -401.867161) (xy 346.467684 -401.860004) (xy 346.445875 -401.834369)
			(xy 346.407924 -401.778781) (xy 346.376889 -401.719055) (xy 346.353216 -401.656049) (xy 346.337243 -401.590664)
			(xy 346.3292 -401.523839) (xy 346.329201 -401.456531) (xy 346.337248 -401.389707) (xy 346.353225 -401.324323)
			(xy 346.376902 -401.261317) (xy 346.40794 -401.201593) (xy 346.445894 -401.146008) (xy 346.467684 -401.120356)
			(xy 346.47348 -401.11321) (xy 346.479995 -401.09602) (xy 346.480384 -401.086828) (xy 346.480384 -400.92884)
			(xy 346.480854 -400.91869) (xy 346.488634 -400.899942) (xy 346.503015 -400.885618) (xy 346.521795 -400.877914)
			(xy 346.531946 -400.877532) (xy 347.248226 -400.877532) (xy 347.258353 -400.878005) (xy 347.277074 -400.88574)
			(xy 347.291429 -400.90003) (xy 347.299249 -400.918715) (xy 347.299788 -400.92884) (xy 347.299788 -401.086828)
			(xy 347.300187 -401.096016) (xy 347.306709 -401.1132) (xy 347.312488 -401.120356) (xy 347.334255 -401.146025)
			(xy 347.372203 -401.201609) (xy 347.403236 -401.261331) (xy 347.426908 -401.324333) (xy 347.442882 -401.389713)
			(xy 347.450927 -401.456533) (xy 347.450929 -401.523836) (xy 347.442887 -401.590657) (xy 347.426917 -401.656038)
			(xy 347.403248 -401.719042) (xy 347.400809 -401.723737) (xy 374.929092 -401.723737) (xy 374.929094 -401.65643)
			(xy 374.937141 -401.589605) (xy 374.953117 -401.524221) (xy 374.976794 -401.461216) (xy 375.007832 -401.401492)
			(xy 375.045786 -401.345906) (xy 375.067576 -401.320254) (xy 375.073372 -401.313108) (xy 375.079888 -401.295918)
			(xy 375.080276 -401.286726) (xy 375.080276 -400.793458) (xy 375.079891 -400.784268) (xy 375.07336 -400.767084)
			(xy 375.067576 -400.75993) (xy 375.045793 -400.734273) (xy 375.007842 -400.678688) (xy 374.976806 -400.618966)
			(xy 374.953131 -400.555962) (xy 374.937157 -400.49058) (xy 374.929112 -400.423757) (xy 374.929111 -400.356452)
			(xy 374.937155 -400.289629) (xy 374.953129 -400.224247) (xy 374.976802 -400.161242) (xy 375.007837 -400.101519)
			(xy 375.045788 -400.045934) (xy 375.067576 -400.020282) (xy 375.07336 -400.013128) (xy 375.079883 -399.995944)
			(xy 375.080276 -399.986754) (xy 375.080276 -399.828766) (xy 375.080637 -399.818587) (xy 375.08844 -399.799785)
			(xy 375.102845 -399.7854) (xy 375.121659 -399.777623) (xy 375.131838 -399.777204) (xy 375.848118 -399.777204)
			(xy 375.858273 -399.777718) (xy 375.877036 -399.785492) (xy 375.891399 -399.799851) (xy 375.899179 -399.818611)
			(xy 375.89968 -399.828766) (xy 375.89968 -399.986754) (xy 375.900117 -399.995938) (xy 375.906612 -400.013123)
			(xy 375.91238 -400.020282) (xy 375.934173 -400.045929) (xy 375.972121 -400.101517) (xy 376.003152 -400.161241)
			(xy 376.026824 -400.224247) (xy 376.042796 -400.289629) (xy 376.050839 -400.356452) (xy 376.050839 -400.423757)
			(xy 376.042794 -400.49058) (xy 376.026821 -400.555962) (xy 376.003149 -400.618967) (xy 375.972116 -400.678691)
			(xy 375.934168 -400.734278) (xy 375.91238 -400.75993) (xy 375.906586 -400.767077) (xy 375.90007 -400.784266)
			(xy 375.89968 -400.793458) (xy 375.89968 -401.286726) (xy 375.900082 -401.295914) (xy 375.906602 -401.313098)
			(xy 375.91238 -401.320254) (xy 375.934146 -401.345924) (xy 375.972094 -401.401508) (xy 376.003127 -401.46123)
			(xy 376.0268 -401.524232) (xy 376.042774 -401.589612) (xy 376.05082 -401.656432) (xy 376.050822 -401.723735)
			(xy 376.04278 -401.790556) (xy 376.02681 -401.855937) (xy 376.003141 -401.91894) (xy 375.972111 -401.978663)
			(xy 375.934166 -402.03425) (xy 375.91238 -402.059902) (xy 375.906598 -402.067057) (xy 375.900075 -402.08424)
			(xy 375.89968 -402.09343) (xy 375.89968 -402.251418) (xy 375.899182 -402.261575) (xy 375.891405 -402.280341)
			(xy 375.877041 -402.294705) (xy 375.858275 -402.302482) (xy 375.848118 -402.30298) (xy 375.131838 -402.30298)
			(xy 375.121671 -402.302505) (xy 375.102881 -402.294736) (xy 375.088495 -402.280366) (xy 375.080706 -402.261584)
			(xy 375.080276 -402.251418) (xy 375.080276 -402.09343) (xy 375.079857 -402.084244) (xy 375.07335 -402.067059)
			(xy 375.067576 -402.059902) (xy 375.045766 -402.034268) (xy 375.007815 -401.97868) (xy 374.976781 -401.918954)
			(xy 374.953108 -401.855947) (xy 374.937135 -401.790562) (xy 374.929092 -401.723737) (xy 347.400809 -401.723737)
			(xy 347.372218 -401.778765) (xy 347.334274 -401.834352) (xy 347.312488 -401.860004) (xy 347.306706 -401.867159)
			(xy 347.300183 -401.884342) (xy 347.299788 -401.893532) (xy 347.299788 -402.3868) (xy 347.300201 -402.395987)
			(xy 347.306713 -402.413171) (xy 347.312488 -402.420328) (xy 347.334227 -402.44602) (xy 347.372176 -402.501601)
			(xy 347.40321 -402.561319) (xy 347.426884 -402.624319) (xy 347.442859 -402.689696) (xy 347.450907 -402.756514)
			(xy 347.450911 -402.823814) (xy 347.450903 -402.823878) (xy 377.128705 -402.823878) (xy 377.12871 -402.75645)
			(xy 377.136791 -402.689508) (xy 377.152832 -402.624016) (xy 377.176603 -402.560917) (xy 377.20776 -402.50112)
			(xy 377.245856 -402.445485) (xy 377.267724 -402.41982) (xy 377.27354 -402.412689) (xy 377.280042 -402.395487)
			(xy 377.280424 -402.386292) (xy 377.280424 -401.89404) (xy 377.279989 -401.884856) (xy 377.273492 -401.867671)
			(xy 377.267724 -401.860512) (xy 377.24584 -401.834863) (xy 377.20775 -401.779227) (xy 377.176599 -401.719429)
			(xy 377.152835 -401.65633) (xy 377.1368 -401.590838) (xy 377.128725 -401.523898) (xy 377.128727 -401.456472)
			(xy 377.136805 -401.389532) (xy 377.152843 -401.324042) (xy 377.176611 -401.260944) (xy 377.207765 -401.201147)
			(xy 377.245858 -401.145513) (xy 377.267724 -401.119848) (xy 377.273528 -401.112708) (xy 377.280037 -401.095513)
			(xy 377.280424 -401.08632) (xy 377.280424 -400.92884) (xy 377.280849 -400.918717) (xy 377.288589 -400.90001)
			(xy 377.302903 -400.885693) (xy 377.321609 -400.877951) (xy 377.331732 -400.877532) (xy 378.048012 -400.877532)
			(xy 378.058139 -400.877907) (xy 378.076849 -400.885665) (xy 378.091164 -400.899994) (xy 378.098904 -400.918712)
			(xy 378.09932 -400.92884) (xy 378.09932 -401.08632) (xy 378.099716 -401.095509) (xy 378.106239 -401.112693)
			(xy 378.11202 -401.119848) (xy 378.133864 -401.14553) (xy 378.171952 -401.201162) (xy 378.203102 -401.260957)
			(xy 378.226866 -401.324051) (xy 378.242903 -401.389538) (xy 378.25098 -401.456474) (xy 378.250982 -401.523896)
			(xy 378.242908 -401.590832) (xy 378.226875 -401.65632) (xy 378.203114 -401.719416) (xy 378.200833 -401.723796)
			(xy 379.328885 -401.723796) (xy 379.328887 -401.656371) (xy 379.336964 -401.589432) (xy 379.353001 -401.523942)
			(xy 379.376766 -401.460844) (xy 379.407918 -401.401047) (xy 379.446008 -401.345412) (xy 379.467872 -401.319746)
			(xy 379.473683 -401.312611) (xy 379.480187 -401.295412) (xy 379.480572 -401.286218) (xy 379.480572 -400.793966)
			(xy 379.480184 -400.784776) (xy 379.473656 -400.767592) (xy 379.467872 -400.760438) (xy 379.446015 -400.734767)
			(xy 379.407928 -400.679133) (xy 379.376778 -400.619337) (xy 379.353015 -400.556241) (xy 379.33698 -400.490753)
			(xy 379.328904 -400.423816) (xy 379.328904 -400.356393) (xy 379.336979 -400.289456) (xy 379.353013 -400.223967)
			(xy 379.376775 -400.160871) (xy 379.407923 -400.101075) (xy 379.446009 -400.04544) (xy 379.467872 -400.019774)
			(xy 379.473671 -400.012631) (xy 379.480182 -399.995438) (xy 379.480572 -399.986246) (xy 379.480572 -399.828766)
			(xy 379.481 -399.818633) (xy 379.488744 -399.799905) (xy 379.503049 -399.785549) (xy 379.521749 -399.777737)
			(xy 379.53188 -399.777204) (xy 380.24816 -399.777204) (xy 380.25828 -399.777649) (xy 380.276984 -399.785385)
			(xy 380.2913 -399.799693) (xy 380.299045 -399.818392) (xy 380.299468 -399.828512) (xy 380.299468 -399.986246)
			(xy 380.299911 -399.99543) (xy 380.306403 -400.012614) (xy 380.312168 -400.019774) (xy 380.334039 -400.045434)
			(xy 380.37213 -400.101068) (xy 380.403282 -400.160865) (xy 380.427047 -400.223963) (xy 380.443083 -400.289453)
			(xy 380.451159 -400.356392) (xy 380.451158 -400.423817) (xy 380.443082 -400.490756) (xy 380.427044 -400.556246)
			(xy 380.403278 -400.619343) (xy 380.372125 -400.679139) (xy 380.334033 -400.734773) (xy 380.312168 -400.760438)
			(xy 380.306369 -400.767581) (xy 380.299856 -400.784773) (xy 380.299468 -400.793966) (xy 380.299468 -401.286218)
			(xy 380.299877 -401.295405) (xy 380.306392 -401.312589) (xy 380.312168 -401.319746) (xy 380.334011 -401.345429)
			(xy 380.372103 -401.40106) (xy 380.403256 -401.460853) (xy 380.427023 -401.523948) (xy 380.443061 -401.589435)
			(xy 380.451139 -401.656372) (xy 380.451141 -401.723795) (xy 380.443067 -401.790732) (xy 380.427033 -401.85622)
			(xy 380.40327 -401.919316) (xy 380.37212 -401.979112) (xy 380.334032 -402.034745) (xy 380.312168 -402.06041)
			(xy 380.306381 -402.067562) (xy 380.299861 -402.084747) (xy 380.299468 -402.093938) (xy 380.299468 -402.251418)
			(xy 380.298989 -402.261545) (xy 380.291256 -402.280265) (xy 380.276968 -402.29462) (xy 380.258284 -402.30244)
			(xy 380.24816 -402.30298) (xy 379.53188 -402.30298) (xy 379.521754 -402.3026) (xy 379.503046 -402.294842)
			(xy 379.488731 -402.280514) (xy 379.48099 -402.261799) (xy 379.480572 -402.251672) (xy 379.480572 -402.093938)
			(xy 379.48015 -402.084752) (xy 379.473645 -402.067567) (xy 379.467872 -402.06041) (xy 379.445987 -402.034762)
			(xy 379.407901 -401.979124) (xy 379.376753 -401.919326) (xy 379.352991 -401.856227) (xy 379.336958 -401.790736)
			(xy 379.328885 -401.723796) (xy 378.200833 -401.723796) (xy 378.171967 -401.779212) (xy 378.133882 -401.834846)
			(xy 378.11202 -401.860512) (xy 378.106238 -401.867668) (xy 378.099714 -401.88485) (xy 378.09932 -401.89404)
			(xy 378.09932 -402.386292) (xy 378.099729 -402.395479) (xy 378.106243 -402.412664) (xy 378.11202 -402.41982)
			(xy 378.133836 -402.445524) (xy 378.171925 -402.501154) (xy 378.203077 -402.560945) (xy 378.226843 -402.624037)
			(xy 378.242881 -402.689521) (xy 378.25096 -402.756454) (xy 378.250965 -402.823818) (xy 381.529025 -402.823818)
			(xy 381.529029 -402.75651) (xy 381.537078 -402.689684) (xy 381.553055 -402.6243) (xy 381.576732 -402.561293)
			(xy 381.607769 -402.501568) (xy 381.645722 -402.445981) (xy 381.667512 -402.420328) (xy 381.673323 -402.413193)
			(xy 381.679829 -402.395995) (xy 381.680212 -402.3868) (xy 381.680212 -401.893532) (xy 381.679784 -401.884347)
			(xy 381.673282 -401.867162) (xy 381.667512 -401.860004) (xy 381.645705 -401.834368) (xy 381.607759 -401.778778)
			(xy 381.576728 -401.719052) (xy 381.553058 -401.656046) (xy 381.537087 -401.590662) (xy 381.529045 -401.523838)
			(xy 381.529046 -401.456532) (xy 381.537092 -401.389708) (xy 381.553066 -401.324325) (xy 381.57674 -401.26132)
			(xy 381.607774 -401.201596) (xy 381.645724 -401.146009) (xy 381.667512 -401.120356) (xy 381.673311 -401.113213)
			(xy 381.679824 -401.096021) (xy 381.680212 -401.086828) (xy 381.680212 -400.92884) (xy 381.680649 -400.918719)
			(xy 381.688386 -400.900014) (xy 381.702697 -400.885698) (xy 381.721399 -400.877953) (xy 381.73152 -400.877532)
			(xy 382.448054 -400.877532) (xy 382.458177 -400.878064) (xy 382.476895 -400.885775) (xy 382.491253 -400.900048)
			(xy 382.499075 -400.91872) (xy 382.499616 -400.92884) (xy 382.499616 -401.086828) (xy 382.500009 -401.096017)
			(xy 382.506534 -401.113201) (xy 382.512316 -401.120356) (xy 382.534085 -401.146024) (xy 382.572038 -401.201607)
			(xy 382.603074 -401.261328) (xy 382.62675 -401.32433) (xy 382.642726 -401.389711) (xy 382.650772 -401.456533)
			(xy 382.650774 -401.523837) (xy 382.642731 -401.590659) (xy 382.626759 -401.656041) (xy 382.603087 -401.719045)
			(xy 382.600649 -401.723737) (xy 383.729179 -401.723737) (xy 383.729181 -401.65643) (xy 383.737228 -401.589605)
			(xy 383.753204 -401.524222) (xy 383.77688 -401.461216) (xy 383.807917 -401.401492) (xy 383.84587 -401.345906)
			(xy 383.86766 -401.320254) (xy 383.873466 -401.313116) (xy 383.879973 -401.29592) (xy 383.88036 -401.286726)
			(xy 383.88036 -400.793458) (xy 383.879957 -400.78427) (xy 383.873437 -400.767087) (xy 383.86766 -400.75993)
			(xy 383.845878 -400.734273) (xy 383.807927 -400.678688) (xy 383.776893 -400.618965) (xy 383.753219 -400.555961)
			(xy 383.737245 -400.490579) (xy 383.7292 -400.423757) (xy 383.729199 -400.356452) (xy 383.737243 -400.28963)
			(xy 383.753216 -400.224247) (xy 383.776889 -400.161243) (xy 383.807923 -400.10152) (xy 383.845872 -400.045934)
			(xy 383.86766 -400.020282) (xy 383.873454 -400.013135) (xy 383.879969 -399.995946) (xy 383.88036 -399.986754)
			(xy 383.88036 -399.828766) (xy 383.880806 -399.818603) (xy 383.888596 -399.799829) (xy 383.902976 -399.785464)
			(xy 383.921759 -399.777695) (xy 383.931922 -399.777204) (xy 384.648202 -399.777204) (xy 384.658356 -399.777731)
			(xy 384.677118 -399.7855) (xy 384.691482 -399.799855) (xy 384.699263 -399.818613) (xy 384.699764 -399.828766)
			(xy 384.699764 -399.986754) (xy 384.700205 -399.995938) (xy 384.706698 -400.013122) (xy 384.712464 -400.020282)
			(xy 384.734258 -400.045929) (xy 384.772206 -400.101516) (xy 384.803239 -400.161241) (xy 384.826911 -400.224246)
			(xy 384.842884 -400.289629) (xy 384.850927 -400.356452) (xy 384.850927 -400.423757) (xy 384.842882 -400.49058)
			(xy 384.826909 -400.555963) (xy 384.803235 -400.618968) (xy 384.772201 -400.678691) (xy 384.734252 -400.734278)
			(xy 384.712464 -400.75993) (xy 384.706668 -400.767075) (xy 384.700154 -400.784266) (xy 384.699764 -400.793458)
			(xy 384.699764 -401.286726) (xy 384.70017 -401.295913) (xy 384.706687 -401.313097) (xy 384.712464 -401.320254)
			(xy 384.73423 -401.345924) (xy 384.772179 -401.401508) (xy 384.803213 -401.461229) (xy 384.826887 -401.524231)
			(xy 384.842861 -401.589611) (xy 384.850907 -401.656432) (xy 384.850909 -401.723735) (xy 384.842867 -401.790556)
			(xy 384.826897 -401.855937) (xy 384.803227 -401.918941) (xy 384.772196 -401.978663) (xy 384.73425 -402.03425)
			(xy 384.712464 -402.059902) (xy 384.706679 -402.067056) (xy 384.700158 -402.08424) (xy 384.699764 -402.09343)
			(xy 384.699764 -402.251418) (xy 384.699282 -402.261577) (xy 384.691502 -402.280346) (xy 384.677133 -402.294711)
			(xy 384.658361 -402.302485) (xy 384.648202 -402.30298) (xy 383.931922 -402.30298) (xy 383.921754 -402.302518)
			(xy 383.902963 -402.294744) (xy 383.888578 -402.28037) (xy 383.88079 -402.261586) (xy 383.88036 -402.251418)
			(xy 383.88036 -402.09343) (xy 383.879922 -402.084246) (xy 383.873426 -402.067062) (xy 383.86766 -402.059902)
			(xy 383.84585 -402.034268) (xy 383.8079 -401.97868) (xy 383.776867 -401.918954) (xy 383.753194 -401.855947)
			(xy 383.737222 -401.790562) (xy 383.729179 -401.723737) (xy 382.600649 -401.723737) (xy 382.572053 -401.778767)
			(xy 382.534104 -401.834352) (xy 382.512316 -401.860004) (xy 382.506537 -401.867162) (xy 382.500011 -401.884343)
			(xy 382.499616 -401.893532) (xy 382.499616 -402.3868) (xy 382.500023 -402.395988) (xy 382.506538 -402.413172)
			(xy 382.512316 -402.420328) (xy 382.534058 -402.446018) (xy 382.572011 -402.501598) (xy 382.603049 -402.561316)
			(xy 382.626726 -402.624316) (xy 382.642704 -402.689694) (xy 382.650753 -402.756513) (xy 382.650757 -402.823815)
			(xy 382.650749 -402.823878) (xy 385.928793 -402.823878) (xy 385.928798 -402.75645) (xy 385.936878 -402.689508)
			(xy 385.952919 -402.624017) (xy 385.976689 -402.560918) (xy 386.007846 -402.50112) (xy 386.045941 -402.445485)
			(xy 386.067808 -402.41982) (xy 386.073622 -402.412687) (xy 386.080126 -402.395487) (xy 386.080508 -402.386292)
			(xy 386.080508 -401.89404) (xy 386.080077 -401.884855) (xy 386.073578 -401.867671) (xy 386.067808 -401.860512)
			(xy 386.045924 -401.834863) (xy 386.007835 -401.779226) (xy 385.976685 -401.719428) (xy 385.952922 -401.656329)
			(xy 385.936887 -401.590838) (xy 385.928813 -401.523898) (xy 385.928815 -401.456472) (xy 385.936893 -401.389533)
			(xy 385.952931 -401.324042) (xy 385.976697 -401.260944) (xy 386.007851 -401.201148) (xy 386.045943 -401.145513)
			(xy 386.067808 -401.119848) (xy 386.07361 -401.112707) (xy 386.080121 -401.095513) (xy 386.080508 -401.08632)
			(xy 386.080508 -400.92884) (xy 386.080949 -400.918719) (xy 386.088686 -400.900015) (xy 386.102995 -400.885699)
			(xy 386.121695 -400.877954) (xy 386.131816 -400.877532) (xy 386.848096 -400.877532) (xy 386.858222 -400.87792)
			(xy 386.876932 -400.885673) (xy 386.891247 -400.899998) (xy 386.898987 -400.918714) (xy 386.899404 -400.92884)
			(xy 386.899404 -401.08632) (xy 386.899804 -401.095508) (xy 386.906325 -401.112692) (xy 386.912104 -401.119848)
			(xy 386.933948 -401.14553) (xy 386.972037 -401.201162) (xy 387.003189 -401.260956) (xy 387.026954 -401.324051)
			(xy 387.04299 -401.389538) (xy 387.051068 -401.456474) (xy 387.05107 -401.523896) (xy 387.042996 -401.590833)
			(xy 387.026963 -401.656321) (xy 387.003201 -401.719417) (xy 387.000951 -401.723737) (xy 388.12897 -401.723737)
			(xy 388.128972 -401.65643) (xy 388.137019 -401.589606) (xy 388.152994 -401.524222) (xy 388.17667 -401.461217)
			(xy 388.207706 -401.401492) (xy 388.245659 -401.345906) (xy 388.267448 -401.320254) (xy 388.273253 -401.313115)
			(xy 388.279761 -401.295919) (xy 388.280148 -401.286726) (xy 388.280148 -400.793458) (xy 388.279747 -400.78427)
			(xy 388.273226 -400.767086) (xy 388.267448 -400.75993) (xy 388.245666 -400.734273) (xy 388.207717 -400.678687)
			(xy 388.176683 -400.618965) (xy 388.153009 -400.555961) (xy 388.137035 -400.490579) (xy 388.128991 -400.423757)
			(xy 388.12899 -400.356452) (xy 388.137034 -400.28963) (xy 388.153006 -400.224248) (xy 388.176679 -400.161244)
			(xy 388.207712 -400.10152) (xy 388.245661 -400.045934) (xy 388.267448 -400.020282) (xy 388.273241 -400.013134)
			(xy 388.279756 -399.995946) (xy 388.280148 -399.986754) (xy 388.280148 -399.828766) (xy 388.280606 -399.818605)
			(xy 388.288393 -399.799833) (xy 388.30277 -399.785469) (xy 388.321548 -399.777697) (xy 388.33171 -399.777204)
			(xy 389.04799 -399.777204) (xy 389.058143 -399.777741) (xy 389.076905 -399.785506) (xy 389.09127 -399.799858)
			(xy 389.099051 -399.818613) (xy 389.099552 -399.828766) (xy 389.099552 -399.986754) (xy 389.099995 -399.995937)
			(xy 389.106487 -400.013121) (xy 389.112252 -400.020282) (xy 389.134046 -400.045929) (xy 389.171995 -400.101516)
			(xy 389.203029 -400.16124) (xy 389.226702 -400.224245) (xy 389.242675 -400.289628) (xy 389.250718 -400.356452)
			(xy 389.250718 -400.423757) (xy 389.242673 -400.490581) (xy 389.226699 -400.555963) (xy 389.203025 -400.618968)
			(xy 389.171991 -400.678692) (xy 389.134041 -400.734278) (xy 389.112252 -400.75993) (xy 389.106454 -400.767074)
			(xy 389.099942 -400.784266) (xy 389.099552 -400.793458) (xy 389.099552 -401.286726) (xy 389.09996 -401.295913)
			(xy 389.106477 -401.313097) (xy 389.112252 -401.320254) (xy 389.134018 -401.345924) (xy 389.171968 -401.401508)
			(xy 389.203003 -401.461229) (xy 389.226677 -401.524231) (xy 389.242652 -401.589611) (xy 389.250698 -401.656432)
			(xy 389.2507 -401.723735) (xy 389.242658 -401.790556) (xy 389.226687 -401.855937) (xy 389.203016 -401.918941)
			(xy 389.171985 -401.978664) (xy 389.134038 -402.03425) (xy 389.112252 -402.059902) (xy 389.106466 -402.067055)
			(xy 389.099946 -402.08424) (xy 389.099552 -402.09343) (xy 389.099552 -402.251418) (xy 389.099081 -402.261578)
			(xy 389.091299 -402.28035) (xy 389.076926 -402.294715) (xy 389.05815 -402.302487) (xy 389.04799 -402.30298)
			(xy 388.33171 -402.30298) (xy 388.321555 -402.302459) (xy 388.30279 -402.294691) (xy 388.288425 -402.280334)
			(xy 388.280647 -402.261573) (xy 388.280148 -402.251418) (xy 388.280148 -402.09343) (xy 388.279713 -402.084246)
			(xy 388.273215 -402.067062) (xy 388.267448 -402.059902) (xy 388.245638 -402.034268) (xy 388.207689 -401.978679)
			(xy 388.176657 -401.918953) (xy 388.152985 -401.855946) (xy 388.137013 -401.790562) (xy 388.12897 -401.723737)
			(xy 387.000951 -401.723737) (xy 386.972053 -401.779212) (xy 386.933967 -401.834847) (xy 386.912104 -401.860512)
			(xy 386.90632 -401.867666) (xy 386.899798 -401.88485) (xy 386.899404 -401.89404) (xy 386.899404 -402.386292)
			(xy 386.899817 -402.395479) (xy 386.906329 -402.412663) (xy 386.912104 -402.41982) (xy 386.933921 -402.445524)
			(xy 386.972011 -402.501153) (xy 387.003163 -402.560944) (xy 387.02693 -402.624036) (xy 387.042968 -402.68952)
			(xy 387.051048 -402.756454) (xy 387.051052 -402.823818) (xy 390.329113 -402.823818) (xy 390.329117 -402.75651)
			(xy 390.337166 -402.689685) (xy 390.353142 -402.6243) (xy 390.376819 -402.561294) (xy 390.407855 -402.501569)
			(xy 390.445807 -402.445981) (xy 390.467596 -402.420328) (xy 390.473405 -402.413192) (xy 390.479912 -402.395994)
			(xy 390.480296 -402.3868) (xy 390.480296 -401.893532) (xy 390.479871 -401.884346) (xy 390.473368 -401.867162)
			(xy 390.467596 -401.860004) (xy 390.44579 -401.834367) (xy 390.407845 -401.778778) (xy 390.376815 -401.719052)
			(xy 390.353145 -401.656045) (xy 390.337174 -401.590661) (xy 390.329133 -401.523838) (xy 390.329134 -401.456532)
			(xy 390.33718 -401.389709) (xy 390.353154 -401.324326) (xy 390.376827 -401.261321) (xy 390.40786 -401.201596)
			(xy 390.445808 -401.146009) (xy 390.467596 -401.120356) (xy 390.473393 -401.113211) (xy 390.479908 -401.09602)
			(xy 390.480296 -401.086828) (xy 390.480296 -400.92884) (xy 390.480749 -400.918721) (xy 390.488483 -400.900019)
			(xy 390.502788 -400.885703) (xy 390.521485 -400.877956) (xy 390.531604 -400.877532) (xy 391.248138 -400.877532)
			(xy 391.258266 -400.877995) (xy 391.276987 -400.885734) (xy 391.291341 -400.900027) (xy 391.299161 -400.918714)
			(xy 391.2997 -400.92884) (xy 391.2997 -401.086828) (xy 391.300096 -401.096017) (xy 391.30662 -401.113201)
			(xy 391.3124 -401.120356) (xy 391.334167 -401.146025) (xy 391.372114 -401.20161) (xy 391.403146 -401.261331)
			(xy 391.426818 -401.324334) (xy 391.442791 -401.389713) (xy 391.450836 -401.456534) (xy 391.450838 -401.523836)
			(xy 391.442797 -401.590657) (xy 391.426827 -401.656038) (xy 391.403158 -401.719041) (xy 391.372129 -401.778764)
			(xy 391.334185 -401.834351) (xy 391.3124 -401.860004) (xy 391.306619 -401.86716) (xy 391.300095 -401.884342)
			(xy 391.2997 -401.893532) (xy 391.2997 -402.3868) (xy 391.30011 -402.395987) (xy 391.306624 -402.413171)
			(xy 391.3124 -402.420328) (xy 391.334139 -402.446019) (xy 391.372087 -402.501601) (xy 391.40312 -402.56132)
			(xy 391.426794 -402.624319) (xy 391.442769 -402.689696) (xy 391.450817 -402.756514) (xy 391.450821 -402.823814)
			(xy 391.442782 -402.890633) (xy 391.426815 -402.956012) (xy 391.40315 -403.019014) (xy 391.372124 -403.078737)
			(xy 391.334184 -403.134323) (xy 391.3124 -403.159976) (xy 391.306589 -403.167111) (xy 391.300083 -403.184309)
			(xy 391.2997 -403.193504) (xy 391.2997 -403.351492) (xy 391.299277 -403.361614) (xy 391.291532 -403.380317)
			(xy 391.277217 -403.394632) (xy 391.258514 -403.402377) (xy 391.248392 -403.4028) (xy 390.531858 -403.4028)
			(xy 390.521734 -403.402309) (xy 390.503019 -403.394575) (xy 390.488666 -403.380291) (xy 390.480841 -403.361614)
			(xy 390.480296 -403.351492) (xy 390.480296 -403.193504) (xy 390.479885 -403.184317) (xy 390.473372 -403.167133)
			(xy 390.467596 -403.159976) (xy 390.445763 -403.134362) (xy 390.407818 -403.078769) (xy 390.376789 -403.01904)
			(xy 390.353121 -402.95603) (xy 390.337153 -402.890644) (xy 390.329113 -402.823818) (xy 387.051052 -402.823818)
			(xy 387.051052 -402.823874) (xy 387.042981 -402.890809) (xy 387.026951 -402.956295) (xy 387.003193 -403.01939)
			(xy 386.972048 -403.079185) (xy 386.933965 -403.134819) (xy 386.912104 -403.160484) (xy 386.90629 -403.167617)
			(xy 386.899785 -403.184817) (xy 386.899404 -403.194012) (xy 386.899404 -403.351492) (xy 386.898978 -403.361613)
			(xy 386.891233 -403.380316) (xy 386.87692 -403.394631) (xy 386.858217 -403.402377) (xy 386.848096 -403.4028)
			(xy 386.131816 -403.4028) (xy 386.121695 -403.402371) (xy 386.102991 -403.394628) (xy 386.088676 -403.380315)
			(xy 386.080931 -403.361613) (xy 386.080508 -403.351492) (xy 386.080508 -403.194012) (xy 386.08009 -403.184826)
			(xy 386.073582 -403.167641) (xy 386.067808 -403.160484) (xy 386.045897 -403.134858) (xy 386.007809 -403.079218)
			(xy 385.97666 -403.019416) (xy 385.952898 -402.956314) (xy 385.936865 -402.89082) (xy 385.928793 -402.823878)
			(xy 382.650749 -402.823878) (xy 382.642717 -402.890635) (xy 382.626748 -402.956015) (xy 382.603078 -403.019018)
			(xy 382.572048 -403.07874) (xy 382.534102 -403.134324) (xy 382.512316 -403.159976) (xy 382.506507 -403.167112)
			(xy 382.499999 -403.18431) (xy 382.499616 -403.193504) (xy 382.499616 -403.351492) (xy 382.499109 -403.361598)
			(xy 382.491377 -403.380273) (xy 382.477087 -403.394568) (xy 382.458414 -403.402306) (xy 382.448308 -403.4028)
			(xy 381.731774 -403.4028) (xy 381.721651 -403.402296) (xy 381.702936 -403.394567) (xy 381.688582 -403.380287)
			(xy 381.680757 -403.361613) (xy 381.680212 -403.351492) (xy 381.680212 -403.193504) (xy 381.679797 -403.184317)
			(xy 381.673286 -403.167133) (xy 381.667512 -403.159976) (xy 381.645678 -403.134362) (xy 381.607732 -403.07877)
			(xy 381.576703 -403.019041) (xy 381.553034 -402.956031) (xy 381.537065 -402.890644) (xy 381.529025 -402.823818)
			(xy 378.250965 -402.823818) (xy 378.250965 -402.823874) (xy 378.242894 -402.890808) (xy 378.226864 -402.956294)
			(xy 378.203106 -403.019389) (xy 378.171962 -403.079184) (xy 378.13388 -403.134818) (xy 378.11202 -403.160484)
			(xy 378.106208 -403.167618) (xy 378.099702 -403.184817) (xy 378.09932 -403.194012) (xy 378.09932 -403.351492)
			(xy 378.098809 -403.361598) (xy 378.091078 -403.380272) (xy 378.076789 -403.394566) (xy 378.058118 -403.402305)
			(xy 378.048012 -403.4028) (xy 377.331732 -403.4028) (xy 377.321612 -403.402358) (xy 377.302909 -403.39462)
			(xy 377.288593 -403.380312) (xy 377.280847 -403.361612) (xy 377.280424 -403.351492) (xy 377.280424 -403.194012)
			(xy 377.280002 -403.184826) (xy 377.273496 -403.167642) (xy 377.267724 -403.160484) (xy 377.245812 -403.134858)
			(xy 377.207723 -403.079218) (xy 377.176573 -403.019417) (xy 377.152811 -402.956315) (xy 377.136778 -402.890821)
			(xy 377.128705 -402.823878) (xy 347.450903 -402.823878) (xy 347.442872 -402.890633) (xy 347.426905 -402.956012)
			(xy 347.403239 -403.019015) (xy 347.372213 -403.078737) (xy 347.334272 -403.134323) (xy 347.312488 -403.159976)
			(xy 347.306675 -403.16711) (xy 347.300171 -403.184309) (xy 347.299788 -403.193504) (xy 347.299788 -403.351492)
			(xy 347.299372 -403.361647) (xy 347.291576 -403.380402) (xy 347.277178 -403.394726) (xy 347.258383 -403.402424)
			(xy 347.248226 -403.4028) (xy 346.531946 -403.4028) (xy 346.521827 -403.402237) (xy 346.503115 -403.394532)
			(xy 346.488758 -403.380269) (xy 346.48093 -403.361607) (xy 346.480384 -403.351492) (xy 346.480384 -403.193504)
			(xy 346.479975 -403.184317) (xy 346.473461 -403.167132) (xy 346.467684 -403.159976) (xy 346.445847 -403.134364)
			(xy 346.407897 -403.078772) (xy 346.376863 -403.019044) (xy 346.353191 -402.956034) (xy 346.33722 -402.890646)
			(xy 346.329179 -402.823819) (xy 343.051143 -402.823819) (xy 343.051143 -402.823874) (xy 343.043072 -402.890809)
			(xy 343.027042 -402.956296) (xy 343.003282 -403.019391) (xy 342.972137 -403.079185) (xy 342.934053 -403.134819)
			(xy 342.912192 -403.160484) (xy 342.906376 -403.167616) (xy 342.899873 -403.184817) (xy 342.899492 -403.194012)
			(xy 342.899492 -403.351492) (xy 342.899077 -403.361615) (xy 342.89133 -403.38032) (xy 342.877013 -403.394635)
			(xy 342.858307 -403.402379) (xy 342.848184 -403.4028) (xy 342.131904 -403.4028) (xy 342.121782 -403.402381)
			(xy 342.103078 -403.394634) (xy 342.088764 -403.380318) (xy 342.081019 -403.361614) (xy 342.080596 -403.351492)
			(xy 342.080596 -403.194012) (xy 342.080181 -403.184825) (xy 342.073671 -403.167641) (xy 342.067896 -403.160484)
			(xy 342.045985 -403.134858) (xy 342.007898 -403.079217) (xy 341.97675 -403.019416) (xy 341.952988 -402.956314)
			(xy 341.936956 -402.89082) (xy 341.928884 -402.823878) (xy 338.650816 -402.823878) (xy 338.642785 -402.890633)
			(xy 338.626819 -402.956012) (xy 338.603153 -403.019014) (xy 338.572128 -403.078737) (xy 338.534188 -403.134323)
			(xy 338.512404 -403.159976) (xy 338.506593 -403.167111) (xy 338.500087 -403.184309) (xy 338.499704 -403.193504)
			(xy 338.499704 -403.351492) (xy 338.499272 -403.361645) (xy 338.49148 -403.380397) (xy 338.477086 -403.39472)
			(xy 338.458297 -403.402421) (xy 338.448142 -403.4028) (xy 337.731862 -403.4028) (xy 337.721738 -403.402306)
			(xy 337.703023 -403.394573) (xy 337.68867 -403.38029) (xy 337.680845 -403.361614) (xy 337.6803 -403.351492)
			(xy 337.6803 -403.193504) (xy 337.679888 -403.184317) (xy 337.673375 -403.167133) (xy 337.6676 -403.159976)
			(xy 337.645766 -403.134362) (xy 337.607822 -403.078769) (xy 337.576793 -403.01904) (xy 337.553124 -402.956031)
			(xy 337.537156 -402.890644) (xy 337.529116 -402.823818) (xy 334.251055 -402.823818) (xy 334.251055 -402.823874)
			(xy 334.242984 -402.890809) (xy 334.226954 -402.956295) (xy 334.203196 -403.01939) (xy 334.172051 -403.079185)
			(xy 334.133969 -403.134819) (xy 334.112108 -403.160484) (xy 334.106294 -403.167617) (xy 334.09979 -403.184817)
			(xy 334.099408 -403.194012) (xy 334.099408 -403.351492) (xy 334.098978 -403.361613) (xy 334.091234 -403.380315)
			(xy 334.076922 -403.394629) (xy 334.058221 -403.402376) (xy 334.0481 -403.4028) (xy 333.33182 -403.4028)
			(xy 333.321699 -403.402368) (xy 333.302996 -403.394626) (xy 333.288681 -403.380315) (xy 333.280935 -403.361613)
			(xy 333.280512 -403.351492) (xy 333.280512 -403.194012) (xy 333.280093 -403.184826) (xy 333.273585 -403.167642)
			(xy 333.267812 -403.160484) (xy 333.2459 -403.134858) (xy 333.207812 -403.079218) (xy 333.176663 -403.019417)
			(xy 333.152901 -402.956315) (xy 333.136869 -402.890821) (xy 333.128796 -402.823878) (xy 326.525636 -402.823878)
			(xy 326.525636 -405.623648) (xy 330.929194 -405.623648) (xy 330.929195 -405.556343) (xy 330.93724 -405.489519)
			(xy 330.953214 -405.424136) (xy 330.976889 -405.361131) (xy 331.007924 -405.301408) (xy 331.045875 -405.245822)
			(xy 331.067664 -405.22017) (xy 331.073464 -405.213027) (xy 331.079975 -405.195835) (xy 331.080364 -405.186642)
			(xy 331.080364 -404.693374) (xy 331.079952 -404.684187) (xy 331.073438 -404.667004) (xy 331.067664 -404.659846)
			(xy 331.045897 -404.634176) (xy 331.007946 -404.578593) (xy 330.976911 -404.518872) (xy 330.953235 -404.45587)
			(xy 330.93726 -404.390489) (xy 330.929214 -404.323668) (xy 330.929212 -404.256365) (xy 330.937254 -404.189543)
			(xy 330.953226 -404.124162) (xy 330.976897 -404.061158) (xy 331.007929 -404.001435) (xy 331.045877 -403.94585)
			(xy 331.067664 -403.920198) (xy 331.073452 -403.913047) (xy 331.07997 -403.895861) (xy 331.080364 -403.88667)
			(xy 331.080364 -403.728682) (xy 331.08075 -403.718506) (xy 331.088546 -403.699706) (xy 331.102943 -403.685321)
			(xy 331.12175 -403.677541) (xy 331.131926 -403.67712) (xy 331.848206 -403.67712) (xy 331.858362 -403.677628)
			(xy 331.877128 -403.685401) (xy 331.891492 -403.699762) (xy 331.899269 -403.718526) (xy 331.899768 -403.728682)
			(xy 331.899768 -403.88667) (xy 331.9002 -403.895855) (xy 331.906699 -403.913039) (xy 331.912468 -403.920198)
			(xy 331.934277 -403.945832) (xy 331.972225 -404.001422) (xy 332.003257 -404.061148) (xy 332.026928 -404.124154)
			(xy 332.042899 -404.189539) (xy 332.050942 -404.256363) (xy 332.05094 -404.32367) (xy 332.042893 -404.390494)
			(xy 332.026918 -404.455877) (xy 332.003243 -404.518883) (xy 331.972208 -404.578607) (xy 331.934257 -404.634194)
			(xy 331.912468 -404.659846) (xy 331.906665 -404.666987) (xy 331.900155 -404.684181) (xy 331.899768 -404.693374)
			(xy 331.899768 -405.186642) (xy 331.900165 -405.19583) (xy 331.906689 -405.213014) (xy 331.912468 -405.22017)
			(xy 331.93425 -405.245827) (xy 331.972198 -405.301413) (xy 332.003231 -405.361136) (xy 332.026904 -405.42414)
			(xy 332.042877 -405.489521) (xy 332.050922 -405.556343) (xy 332.050923 -405.623648) (xy 332.042879 -405.69047)
			(xy 332.026907 -405.755852) (xy 332.003235 -405.818856) (xy 331.972203 -405.878579) (xy 331.934255 -405.934166)
			(xy 331.912468 -405.959818) (xy 331.906677 -405.966967) (xy 331.90016 -405.984155) (xy 331.899768 -405.993346)
			(xy 331.899768 -406.151334) (xy 331.899295 -406.161493) (xy 331.89151 -406.180262) (xy 331.877138 -406.194626)
			(xy 331.858365 -406.2024) (xy 331.848206 -406.202896) (xy 331.131926 -406.202896) (xy 331.121774 -406.202346)
			(xy 331.103012 -406.194587) (xy 331.088647 -406.180238) (xy 331.080865 -406.161485) (xy 331.080364 -406.151334)
			(xy 331.080364 -405.993346) (xy 331.079918 -405.984163) (xy 331.073428 -405.966979) (xy 331.067664 -405.959818)
			(xy 331.04587 -405.934171) (xy 331.007919 -405.878584) (xy 330.976885 -405.81886) (xy 330.953212 -405.755855)
			(xy 330.937238 -405.690472) (xy 330.929194 -405.623648) (xy 326.525636 -405.623648) (xy 326.525636 -406.723789)
			(xy 333.128808 -406.723789) (xy 333.128811 -406.656363) (xy 333.13689 -406.589422) (xy 333.152929 -406.523931)
			(xy 333.176697 -406.460833) (xy 333.207852 -406.401036) (xy 333.245946 -406.345401) (xy 333.267812 -406.319736)
			(xy 333.27362 -406.312599) (xy 333.280127 -406.295402) (xy 333.280512 -406.286208) (xy 333.280512 -405.793956)
			(xy 333.28012 -405.784767) (xy 333.273594 -405.767583) (xy 333.267812 -405.760428) (xy 333.245944 -405.734766)
			(xy 333.207854 -405.679131) (xy 333.176703 -405.619335) (xy 333.152939 -405.556238) (xy 333.136903 -405.490748)
			(xy 333.128827 -405.423809) (xy 333.128828 -405.356385) (xy 333.136904 -405.289446) (xy 333.15294 -405.223957)
			(xy 333.176706 -405.16086) (xy 333.207857 -405.101063) (xy 333.245947 -405.045429) (xy 333.267812 -405.019764)
			(xy 333.273608 -405.012618) (xy 333.280123 -404.995428) (xy 333.280512 -404.986236) (xy 333.280512 -404.828756)
			(xy 333.280949 -404.818643) (xy 333.288704 -404.799961) (xy 333.303015 -404.785668) (xy 333.321706 -404.777937)
			(xy 333.33182 -404.777448) (xy 334.0481 -404.777448) (xy 334.058202 -404.777984) (xy 334.076871 -404.785712)
			(xy 334.091163 -404.799993) (xy 334.098907 -404.818654) (xy 334.099408 -404.828756) (xy 334.099408 -404.986236)
			(xy 334.099799 -404.995425) (xy 334.106326 -405.01261) (xy 334.112108 -405.019764) (xy 334.133968 -405.045433)
			(xy 334.172056 -405.101067) (xy 334.203206 -405.160863) (xy 334.226971 -405.223959) (xy 334.243006 -405.289448)
			(xy 334.251082 -405.356385) (xy 334.251082 -405.423809) (xy 334.243007 -405.490746) (xy 334.226972 -405.556235)
			(xy 334.203209 -405.619332) (xy 334.20093 -405.623707) (xy 335.328987 -405.623707) (xy 335.328987 -405.556284)
			(xy 335.337063 -405.489346) (xy 335.353098 -405.423857) (xy 335.376861 -405.36076) (xy 335.40801 -405.300963)
			(xy 335.446097 -405.245328) (xy 335.46796 -405.219662) (xy 335.473763 -405.212521) (xy 335.480272 -405.195327)
			(xy 335.48066 -405.186134) (xy 335.48066 -404.693882) (xy 335.480245 -404.684696) (xy 335.473733 -404.667512)
			(xy 335.46796 -404.660354) (xy 335.446119 -404.63467) (xy 335.408032 -404.579037) (xy 335.376883 -404.519243)
			(xy 335.353119 -404.456149) (xy 335.337083 -404.390663) (xy 335.329006 -404.323727) (xy 335.329004 -404.256306)
			(xy 335.337078 -404.18937) (xy 335.353109 -404.123883) (xy 335.376869 -404.060787) (xy 335.408015 -404.000991)
			(xy 335.446099 -403.945356) (xy 335.46796 -403.91969) (xy 335.473751 -403.912541) (xy 335.480267 -403.895353)
			(xy 335.48066 -403.886162) (xy 335.48066 -403.728682) (xy 335.481112 -403.718552) (xy 335.48885 -403.699826)
			(xy 335.503147 -403.68547) (xy 335.52184 -403.677655) (xy 335.531968 -403.67712) (xy 336.248248 -403.67712)
			(xy 336.258408 -403.677483) (xy 336.277165 -403.685298) (xy 336.291487 -403.699713) (xy 336.299182 -403.71852)
			(xy 336.299556 -403.728682) (xy 336.299556 -403.886162) (xy 336.299995 -403.895346) (xy 336.30649 -403.91253)
			(xy 336.312256 -403.91969) (xy 336.334143 -403.945337) (xy 336.372234 -404.000973) (xy 336.403386 -404.060771)
			(xy 336.427151 -404.123871) (xy 336.443186 -404.189362) (xy 336.451261 -404.256303) (xy 336.451259 -404.32373)
			(xy 336.443181 -404.39067) (xy 336.427141 -404.456161) (xy 336.403373 -404.519259) (xy 336.372217 -404.579056)
			(xy 336.334123 -404.634689) (xy 336.312256 -404.660354) (xy 336.306449 -404.667491) (xy 336.299941 -404.684688)
			(xy 336.299556 -404.693882) (xy 336.299556 -405.186134) (xy 336.29996 -405.195322) (xy 336.306479 -405.212505)
			(xy 336.312256 -405.219662) (xy 336.334116 -405.245331) (xy 336.372207 -405.300964) (xy 336.403361 -405.360759)
			(xy 336.427127 -405.423856) (xy 336.443164 -405.489345) (xy 336.451242 -405.556283) (xy 336.451242 -405.623708)
			(xy 336.443166 -405.690646) (xy 336.42713 -405.756135) (xy 336.403365 -405.819232) (xy 336.372212 -405.879028)
			(xy 336.334121 -405.934662) (xy 336.312256 -405.960326) (xy 336.30646 -405.967472) (xy 336.299946 -405.984662)
			(xy 336.299556 -405.993854) (xy 336.299556 -406.151334) (xy 336.299101 -406.161463) (xy 336.291362 -406.180186)
			(xy 336.277066 -406.194541) (xy 336.258375 -406.202359) (xy 336.248248 -406.202896) (xy 335.531968 -406.202896)
			(xy 335.521811 -406.202505) (xy 335.503057 -406.194698) (xy 335.488735 -406.180292) (xy 335.481037 -406.161493)
			(xy 335.48066 -406.151334) (xy 335.48066 -405.993854) (xy 335.48021 -405.984671) (xy 335.473722 -405.967487)
			(xy 335.46796 -405.960326) (xy 335.446092 -405.934665) (xy 335.408006 -405.879029) (xy 335.376857 -405.819232)
			(xy 335.353095 -405.756134) (xy 335.337062 -405.690645) (xy 335.328987 -405.623707) (xy 334.20093 -405.623707)
			(xy 334.172059 -405.679128) (xy 334.133971 -405.734763) (xy 334.112108 -405.760428) (xy 334.106318 -405.767578)
			(xy 334.099799 -405.784765) (xy 334.099408 -405.793956) (xy 334.099408 -406.286208) (xy 334.099813 -406.295396)
			(xy 334.10633 -406.31258) (xy 334.112108 -406.319736) (xy 334.13394 -406.345427) (xy 334.172029 -406.401058)
			(xy 334.203181 -406.460851) (xy 334.226947 -406.523944) (xy 334.242984 -406.58943) (xy 334.251062 -406.656365)
			(xy 334.251065 -406.723729) (xy 337.529127 -406.723729) (xy 337.52913 -406.656423) (xy 337.537177 -406.589598)
			(xy 337.553152 -406.524215) (xy 337.576827 -406.461209) (xy 337.607861 -406.401484) (xy 337.645812 -406.345897)
			(xy 337.6676 -406.320244) (xy 337.673403 -406.313103) (xy 337.679914 -406.295909) (xy 337.6803 -406.286716)
			(xy 337.6803 -405.793448) (xy 337.679867 -405.784263) (xy 337.673369 -405.767079) (xy 337.6676 -405.75992)
			(xy 337.64581 -405.734271) (xy 337.607863 -405.678683) (xy 337.576832 -405.618958) (xy 337.553162 -405.555954)
			(xy 337.53719 -405.490572) (xy 337.529147 -405.423749) (xy 337.529147 -405.356445) (xy 337.537191 -405.289622)
			(xy 337.553163 -405.224241) (xy 337.576835 -405.161236) (xy 337.607866 -405.101512) (xy 337.645813 -405.045925)
			(xy 337.6676 -405.020272) (xy 337.673391 -405.013123) (xy 337.679909 -404.995935) (xy 337.6803 -404.986744)
			(xy 337.6803 -404.828756) (xy 337.680686 -404.818599) (xy 337.688496 -404.799846) (xy 337.702903 -404.785524)
			(xy 337.721703 -404.777826) (xy 337.731862 -404.777448) (xy 338.448142 -404.777448) (xy 338.458272 -404.777892)
			(xy 338.476996 -404.785635) (xy 338.491351 -404.799934) (xy 338.499167 -404.818628) (xy 338.499704 -404.828756)
			(xy 338.499704 -404.986744) (xy 338.500092 -404.995934) (xy 338.506621 -405.013118) (xy 338.512404 -405.020272)
			(xy 338.534186 -405.045928) (xy 338.572133 -405.101515) (xy 338.603164 -405.161238) (xy 338.626835 -405.224242)
			(xy 338.642807 -405.289624) (xy 338.650851 -405.356445) (xy 338.650851 -405.423749) (xy 338.642808 -405.490571)
			(xy 338.626837 -405.555952) (xy 338.603166 -405.618956) (xy 338.600728 -405.623648) (xy 339.729282 -405.623648)
			(xy 339.729282 -405.556343) (xy 339.737327 -405.489519) (xy 339.753301 -405.424137) (xy 339.776975 -405.361132)
			(xy 339.808009 -405.301408) (xy 339.845959 -405.245822) (xy 339.867748 -405.22017) (xy 339.873546 -405.213026)
			(xy 339.880058 -405.195834) (xy 339.880448 -405.186642) (xy 339.880448 -404.693374) (xy 339.88004 -404.684187)
			(xy 339.873523 -404.667003) (xy 339.867748 -404.659846) (xy 339.845982 -404.634176) (xy 339.808032 -404.578592)
			(xy 339.776997 -404.518871) (xy 339.753323 -404.455869) (xy 339.737348 -404.390489) (xy 339.729302 -404.323668)
			(xy 339.7293 -404.256365) (xy 339.737342 -404.189544) (xy 339.753313 -404.124163) (xy 339.776984 -404.061159)
			(xy 339.808015 -404.001436) (xy 339.845962 -403.94585) (xy 339.867748 -403.920198) (xy 339.873534 -403.913045)
			(xy 339.880054 -403.89586) (xy 339.880448 -403.88667) (xy 339.880448 -403.728682) (xy 339.880919 -403.718522)
			(xy 339.888701 -403.69975) (xy 339.903074 -403.685385) (xy 339.92185 -403.677613) (xy 339.93201 -403.67712)
			(xy 340.64829 -403.67712) (xy 340.658445 -403.677641) (xy 340.67721 -403.685409) (xy 340.691575 -403.699766)
			(xy 340.699353 -403.718527) (xy 340.699852 -403.728682) (xy 340.699852 -403.88667) (xy 340.700287 -403.895854)
			(xy 340.706785 -403.913038) (xy 340.712552 -403.920198) (xy 340.734362 -403.945832) (xy 340.772311 -404.001421)
			(xy 340.803343 -404.061147) (xy 340.827015 -404.124154) (xy 340.842987 -404.189538) (xy 340.85103 -404.256363)
			(xy 340.851028 -404.32367) (xy 340.842981 -404.390494) (xy 340.827006 -404.455878) (xy 340.80333 -404.518883)
			(xy 340.772294 -404.578608) (xy 340.734341 -404.634194) (xy 340.712552 -404.659846) (xy 340.706747 -404.666985)
			(xy 340.700239 -404.684181) (xy 340.699852 -404.693374) (xy 340.699852 -405.186642) (xy 340.700253 -405.19583)
			(xy 340.706774 -405.213014) (xy 340.712552 -405.22017) (xy 340.734334 -405.245827) (xy 340.772283 -405.301413)
			(xy 340.803317 -405.361135) (xy 340.826991 -405.424139) (xy 340.842965 -405.489521) (xy 340.851009 -405.556343)
			(xy 340.85101 -405.623648) (xy 340.842966 -405.69047) (xy 340.826994 -405.755852) (xy 340.803321 -405.818856)
			(xy 340.772288 -405.87858) (xy 340.734339 -405.934166) (xy 340.712552 -405.959818) (xy 340.706759 -405.966966)
			(xy 340.700244 -405.984154) (xy 340.699852 -405.993346) (xy 340.699852 -406.151334) (xy 340.699394 -406.161495)
			(xy 340.691607 -406.180267) (xy 340.67723 -406.194631) (xy 340.658452 -406.202403) (xy 340.64829 -406.202896)
			(xy 339.93201 -406.202896) (xy 339.921857 -406.202359) (xy 339.903095 -406.194594) (xy 339.88873 -406.180242)
			(xy 339.880949 -406.161487) (xy 339.880448 -406.151334) (xy 339.880448 -405.993346) (xy 339.880005 -405.984163)
			(xy 339.873513 -405.966979) (xy 339.867748 -405.959818) (xy 339.845954 -405.934171) (xy 339.808005 -405.878584)
			(xy 339.776971 -405.81886) (xy 339.753298 -405.755855) (xy 339.737325 -405.690472) (xy 339.729282 -405.623648)
			(xy 338.600728 -405.623648) (xy 338.572136 -405.67868) (xy 338.53419 -405.734267) (xy 338.512404 -405.75992)
			(xy 338.506617 -405.767072) (xy 338.500096 -405.784257) (xy 338.499704 -405.793448) (xy 338.499704 -406.286716)
			(xy 338.500106 -406.295904) (xy 338.506625 -406.313088) (xy 338.512404 -406.320244) (xy 338.534159 -406.345923)
			(xy 338.572106 -406.401506) (xy 338.603138 -406.461227) (xy 338.626811 -406.524228) (xy 338.642785 -406.589606)
			(xy 338.650831 -406.656425) (xy 338.650834 -406.723727) (xy 338.650827 -406.723789) (xy 341.928896 -406.723789)
			(xy 341.928898 -406.656363) (xy 341.936977 -406.589423) (xy 341.953016 -406.523932) (xy 341.976784 -406.460834)
			(xy 342.007938 -406.401036) (xy 342.04603 -406.345401) (xy 342.067896 -406.319736) (xy 342.073702 -406.312597)
			(xy 342.080211 -406.295402) (xy 342.080596 -406.286208) (xy 342.080596 -405.793956) (xy 342.080208 -405.784766)
			(xy 342.073679 -405.767582) (xy 342.067896 -405.760428) (xy 342.046028 -405.734766) (xy 342.00794 -405.679131)
			(xy 341.97679 -405.619334) (xy 341.953026 -405.556237) (xy 341.936991 -405.490748) (xy 341.928915 -405.423809)
			(xy 341.928916 -405.356385) (xy 341.936992 -405.289447) (xy 341.953028 -405.223957) (xy 341.976792 -405.16086)
			(xy 342.007943 -405.101064) (xy 342.046032 -405.045429) (xy 342.067896 -405.019764) (xy 342.07369 -405.012617)
			(xy 342.080206 -404.995428) (xy 342.080596 -404.986236) (xy 342.080596 -404.828756) (xy 342.081049 -404.818645)
			(xy 342.0888 -404.799967) (xy 342.103107 -404.785673) (xy 342.121793 -404.77794) (xy 342.131904 -404.777448)
			(xy 342.848184 -404.777448) (xy 342.858285 -404.777997) (xy 342.876953 -404.78572) (xy 342.891247 -404.799996)
			(xy 342.898991 -404.818655) (xy 342.899492 -404.828756) (xy 342.899492 -404.986236) (xy 342.899886 -404.995425)
			(xy 342.906411 -405.012609) (xy 342.912192 -405.019764) (xy 342.934052 -405.045432) (xy 342.972142 -405.101066)
			(xy 343.003293 -405.160862) (xy 343.027058 -405.223958) (xy 343.043094 -405.289447) (xy 343.05117 -405.356385)
			(xy 343.05117 -405.423809) (xy 343.043095 -405.490747) (xy 343.02706 -405.556236) (xy 343.003295 -405.619333)
			(xy 343.001047 -405.623648) (xy 344.129073 -405.623648) (xy 344.129073 -405.556343) (xy 344.137118 -405.48952)
			(xy 344.153091 -405.424137) (xy 344.176765 -405.361132) (xy 344.207799 -405.301409) (xy 344.245748 -405.245822)
			(xy 344.267536 -405.22017) (xy 344.273332 -405.213025) (xy 344.279846 -405.195834) (xy 344.280236 -405.186642)
			(xy 344.280236 -404.693374) (xy 344.27983 -404.684187) (xy 344.273313 -404.667003) (xy 344.267536 -404.659846)
			(xy 344.24577 -404.634176) (xy 344.207821 -404.578592) (xy 344.176787 -404.518871) (xy 344.153113 -404.455869)
			(xy 344.137139 -404.390489) (xy 344.129093 -404.323668) (xy 344.129091 -404.256365) (xy 344.137133 -404.189544)
			(xy 344.153103 -404.124163) (xy 344.176773 -404.061159) (xy 344.207804 -404.001437) (xy 344.24575 -403.94585)
			(xy 344.267536 -403.920198) (xy 344.273321 -403.913044) (xy 344.279842 -403.89586) (xy 344.280236 -403.88667)
			(xy 344.280236 -403.728682) (xy 344.280718 -403.718523) (xy 344.288498 -403.699754) (xy 344.302867 -403.685389)
			(xy 344.321639 -403.677615) (xy 344.331798 -403.67712) (xy 345.048078 -403.67712) (xy 345.058246 -403.677582)
			(xy 345.077037 -403.685356) (xy 345.091422 -403.69973) (xy 345.09921 -403.718514) (xy 345.09964 -403.728682)
			(xy 345.09964 -403.88667) (xy 345.100078 -403.895854) (xy 345.106574 -403.913038) (xy 345.11234 -403.920198)
			(xy 345.13415 -403.945832) (xy 345.1721 -404.00142) (xy 345.203133 -404.061146) (xy 345.226806 -404.124153)
			(xy 345.242778 -404.189538) (xy 345.250821 -404.256363) (xy 345.250819 -404.32367) (xy 345.242772 -404.390495)
			(xy 345.226796 -404.455878) (xy 345.20312 -404.518884) (xy 345.172083 -404.578608) (xy 345.13413 -404.634194)
			(xy 345.11234 -404.659846) (xy 345.106534 -404.666984) (xy 345.100027 -404.68418) (xy 345.09964 -404.693374)
			(xy 345.09964 -405.186642) (xy 345.100043 -405.19583) (xy 345.106563 -405.213013) (xy 345.11234 -405.22017)
			(xy 345.134122 -405.245827) (xy 345.172073 -405.301412) (xy 345.203107 -405.361135) (xy 345.226781 -405.424139)
			(xy 345.242755 -405.489521) (xy 345.2508 -405.556343) (xy 345.250801 -405.623648) (xy 345.242757 -405.69047)
			(xy 345.226784 -405.755853) (xy 345.203111 -405.818857) (xy 345.172077 -405.87858) (xy 345.134128 -405.934166)
			(xy 345.11234 -405.959818) (xy 345.106546 -405.966965) (xy 345.100031 -405.984154) (xy 345.09964 -405.993346)
			(xy 345.09964 -406.151334) (xy 345.099194 -406.161497) (xy 345.091404 -406.180271) (xy 345.077024 -406.194636)
			(xy 345.058241 -406.202405) (xy 345.048078 -406.202896) (xy 344.331798 -406.202896) (xy 344.321644 -406.202369)
			(xy 344.302882 -406.1946) (xy 344.288518 -406.180245) (xy 344.280737 -406.161487) (xy 344.280236 -406.151334)
			(xy 344.280236 -405.993346) (xy 344.279795 -405.984162) (xy 344.273302 -405.966978) (xy 344.267536 -405.959818)
			(xy 344.245742 -405.934171) (xy 344.207794 -405.878584) (xy 344.176761 -405.818859) (xy 344.153089 -405.755854)
			(xy 344.137116 -405.690471) (xy 344.129073 -405.623648) (xy 343.001047 -405.623648) (xy 342.972145 -405.679129)
			(xy 342.934056 -405.734763) (xy 342.912192 -405.760428) (xy 342.9064 -405.767576) (xy 342.899883 -405.784765)
			(xy 342.899492 -405.793956) (xy 342.899492 -406.286208) (xy 342.8999 -406.295395) (xy 342.906416 -406.312579)
			(xy 342.912192 -406.319736) (xy 342.934025 -406.345427) (xy 342.972115 -406.401058) (xy 343.003268 -406.46085)
			(xy 343.027034 -406.523944) (xy 343.043072 -406.58943) (xy 343.05115 -406.656365) (xy 343.051153 -406.72373)
			(xy 346.329191 -406.72373) (xy 346.329194 -406.656422) (xy 346.337242 -406.589596) (xy 346.35322 -406.524212)
			(xy 346.376898 -406.461206) (xy 346.407937 -406.401482) (xy 346.445893 -406.345896) (xy 346.467684 -406.320244)
			(xy 346.473485 -406.313102) (xy 346.479998 -406.295909) (xy 346.480384 -406.286716) (xy 346.480384 -405.793448)
			(xy 346.479955 -405.784263) (xy 346.473455 -405.767078) (xy 346.467684 -405.75992) (xy 346.445891 -405.734272)
			(xy 346.407939 -405.678686) (xy 346.376904 -405.618962) (xy 346.353229 -405.555957) (xy 346.337255 -405.490574)
			(xy 346.329211 -405.42375) (xy 346.329211 -405.356444) (xy 346.337256 -405.28962) (xy 346.353231 -405.224237)
			(xy 346.376906 -405.161232) (xy 346.407942 -405.101509) (xy 346.445895 -405.045924) (xy 346.467684 -405.020272)
			(xy 346.473473 -405.013121) (xy 346.479993 -404.995935) (xy 346.480384 -404.986744) (xy 346.480384 -404.828756)
			(xy 346.480785 -404.818601) (xy 346.488592 -404.799851) (xy 346.502995 -404.78553) (xy 346.521789 -404.777829)
			(xy 346.531946 -404.777448) (xy 347.248226 -404.777448) (xy 347.258355 -404.777905) (xy 347.277079 -404.785643)
			(xy 347.291434 -404.799938) (xy 347.299251 -404.818629) (xy 347.299788 -404.828756) (xy 347.299788 -404.986744)
			(xy 347.30018 -404.995933) (xy 347.306706 -405.013117) (xy 347.312488 -405.020272) (xy 347.334271 -405.045928)
			(xy 347.372218 -405.101514) (xy 347.40325 -405.161238) (xy 347.426922 -405.224242) (xy 347.442894 -405.289623)
			(xy 347.450938 -405.356445) (xy 347.450939 -405.423749) (xy 347.442895 -405.490571) (xy 347.426924 -405.555953)
			(xy 347.403253 -405.618957) (xy 347.400815 -405.623649) (xy 374.929103 -405.623649) (xy 374.929104 -405.556342)
			(xy 374.937149 -405.489519) (xy 374.953124 -405.424136) (xy 374.976799 -405.361131) (xy 375.007835 -405.301407)
			(xy 375.045787 -405.245822) (xy 375.067576 -405.22017) (xy 375.073365 -405.213019) (xy 375.079885 -405.195833)
			(xy 375.080276 -405.186642) (xy 375.080276 -404.693374) (xy 375.079884 -404.684185) (xy 375.073358 -404.667)
			(xy 375.067576 -404.659846) (xy 375.045809 -404.634177) (xy 375.007857 -404.578593) (xy 374.976821 -404.518873)
			(xy 374.953145 -404.45587) (xy 374.937169 -404.39049) (xy 374.929123 -404.323669) (xy 374.929121 -404.256365)
			(xy 374.937164 -404.189543) (xy 374.953135 -404.124161) (xy 374.976807 -404.061158) (xy 375.00784 -404.001435)
			(xy 375.045789 -403.94585) (xy 375.067576 -403.920198) (xy 375.073353 -403.913039) (xy 375.07988 -403.895859)
			(xy 375.080276 -403.88667) (xy 375.080276 -403.728682) (xy 375.08065 -403.718505) (xy 375.088448 -403.699702)
			(xy 375.102849 -403.685317) (xy 375.12166 -403.677539) (xy 375.131838 -403.67712) (xy 375.848118 -403.67712)
			(xy 375.858275 -403.677618) (xy 375.877041 -403.685395) (xy 375.891405 -403.699759) (xy 375.899182 -403.718525)
			(xy 375.89968 -403.728682) (xy 375.89968 -403.88667) (xy 375.900109 -403.895855) (xy 375.90661 -403.913039)
			(xy 375.91238 -403.920198) (xy 375.934189 -403.945833) (xy 375.972136 -404.001422) (xy 376.003167 -404.061148)
			(xy 376.026838 -404.124155) (xy 376.042809 -404.189539) (xy 376.050851 -404.256363) (xy 376.050849 -404.32367)
			(xy 376.042803 -404.390494) (xy 376.026828 -404.455877) (xy 376.003154 -404.518882) (xy 375.972119 -404.578606)
			(xy 375.934169 -404.634194) (xy 375.91238 -404.659846) (xy 375.906579 -404.666988) (xy 375.900068 -404.684181)
			(xy 375.89968 -404.693374) (xy 375.89968 -405.186642) (xy 375.900074 -405.195831) (xy 375.9066 -405.213015)
			(xy 375.91238 -405.22017) (xy 375.934161 -405.245827) (xy 375.972109 -405.301413) (xy 376.003142 -405.361136)
			(xy 376.026814 -405.42414) (xy 376.042787 -405.489522) (xy 376.050831 -405.556343) (xy 376.050832 -405.623648)
			(xy 376.042788 -405.690469) (xy 376.026817 -405.755851) (xy 376.003145 -405.818855) (xy 375.972114 -405.878579)
			(xy 375.934167 -405.934166) (xy 375.91238 -405.959818) (xy 375.906591 -405.966968) (xy 375.900072 -405.984155)
			(xy 375.89968 -405.993346) (xy 375.89968 -406.151334) (xy 375.899195 -406.161492) (xy 375.891413 -406.180258)
			(xy 375.877045 -406.194622) (xy 375.858276 -406.202398) (xy 375.848118 -406.202896) (xy 375.131838 -406.202896)
			(xy 375.121673 -406.202406) (xy 375.102886 -406.19464) (xy 375.088501 -406.180275) (xy 375.080708 -406.161498)
			(xy 375.080276 -406.151334) (xy 375.080276 -405.993346) (xy 375.079849 -405.984161) (xy 375.073347 -405.966976)
			(xy 375.067576 -405.959818) (xy 375.045781 -405.934171) (xy 375.00783 -405.878585) (xy 374.976795 -405.818861)
			(xy 374.953121 -405.755856) (xy 374.937148 -405.690472) (xy 374.929103 -405.623649) (xy 347.400815 -405.623649)
			(xy 347.372221 -405.678681) (xy 347.334275 -405.734268) (xy 347.312488 -405.75992) (xy 347.306699 -405.767071)
			(xy 347.30018 -405.784257) (xy 347.299788 -405.793448) (xy 347.299788 -406.286716) (xy 347.300193 -406.295904)
			(xy 347.30671 -406.313088) (xy 347.312488 -406.320244) (xy 347.334244 -406.345922) (xy 347.372192 -406.401506)
			(xy 347.403225 -406.461226) (xy 347.426898 -406.524227) (xy 347.442873 -406.589606) (xy 347.450919 -406.656425)
			(xy 347.450922 -406.723727) (xy 347.450915 -406.723789) (xy 377.128717 -406.723789) (xy 377.12872 -406.656363)
			(xy 377.136799 -406.589422) (xy 377.152839 -406.523931) (xy 377.176607 -406.460832) (xy 377.207763 -406.401035)
			(xy 377.245857 -406.345401) (xy 377.267724 -406.319736) (xy 377.273533 -406.3126) (xy 377.280039 -406.295402)
			(xy 377.280424 -406.286208) (xy 377.280424 -405.793956) (xy 377.28003 -405.784767) (xy 377.273504 -405.767583)
			(xy 377.267724 -405.760428) (xy 377.245855 -405.734766) (xy 377.207765 -405.679132) (xy 377.176613 -405.619335)
			(xy 377.152848 -405.556238) (xy 377.136812 -405.490748) (xy 377.128736 -405.423809) (xy 377.128737 -405.356385)
			(xy 377.136813 -405.289446) (xy 377.15285 -405.223956) (xy 377.176616 -405.160859) (xy 377.207768 -405.101063)
			(xy 377.245859 -405.045429) (xy 377.267724 -405.019764) (xy 377.273521 -405.012619) (xy 377.280035 -404.995428)
			(xy 377.280424 -404.986236) (xy 377.280424 -404.828756) (xy 377.28085 -404.818641) (xy 377.288606 -404.799958)
			(xy 377.302922 -404.785664) (xy 377.321617 -404.777935) (xy 377.331732 -404.777448) (xy 378.048012 -404.777448)
			(xy 378.058115 -404.777974) (xy 378.076783 -404.785706) (xy 378.091076 -404.79999) (xy 378.098819 -404.818653)
			(xy 378.09932 -404.828756) (xy 378.09932 -404.986236) (xy 378.099709 -404.995426) (xy 378.106237 -405.01261)
			(xy 378.11202 -405.019764) (xy 378.133879 -405.045433) (xy 378.171967 -405.101067) (xy 378.203117 -405.160863)
			(xy 378.22688 -405.22396) (xy 378.242915 -405.289448) (xy 378.250991 -405.356386) (xy 378.250992 -405.423808)
			(xy 378.242916 -405.490746) (xy 378.226882 -405.556235) (xy 378.203119 -405.619331) (xy 378.200839 -405.623707)
			(xy 379.328896 -405.623707) (xy 379.328896 -405.556284) (xy 379.336972 -405.489346) (xy 379.353008 -405.423856)
			(xy 379.376771 -405.360759) (xy 379.407921 -405.300963) (xy 379.446009 -405.245328) (xy 379.467872 -405.219662)
			(xy 379.473676 -405.212522) (xy 379.480184 -405.195327) (xy 379.480572 -405.186134) (xy 379.480572 -404.693882)
			(xy 379.480177 -404.684693) (xy 379.473653 -404.667509) (xy 379.467872 -404.660354) (xy 379.446031 -404.63467)
			(xy 379.407943 -404.579038) (xy 379.376793 -404.519244) (xy 379.353029 -404.45615) (xy 379.336993 -404.390663)
			(xy 379.328915 -404.323727) (xy 379.328913 -404.256306) (xy 379.336987 -404.18937) (xy 379.353019 -404.123882)
			(xy 379.376779 -404.060786) (xy 379.407926 -404.00099) (xy 379.44601 -403.945356) (xy 379.467872 -403.91969)
			(xy 379.473664 -403.912542) (xy 379.480179 -403.895353) (xy 379.480572 -403.886162) (xy 379.480572 -403.728682)
			(xy 379.481013 -403.71855) (xy 379.488752 -403.699822) (xy 379.503053 -403.685466) (xy 379.52175 -403.677653)
			(xy 379.53188 -403.67712) (xy 380.24816 -403.67712) (xy 380.258282 -403.677549) (xy 380.276989 -403.685288)
			(xy 380.291305 -403.699601) (xy 380.299048 -403.718306) (xy 380.299468 -403.728428) (xy 380.299468 -403.886162)
			(xy 380.299904 -403.895346) (xy 380.306401 -403.91253) (xy 380.312168 -403.91969) (xy 380.334055 -403.945337)
			(xy 380.372145 -404.000973) (xy 380.403296 -404.060772) (xy 380.427061 -404.123871) (xy 380.443096 -404.189363)
			(xy 380.45117 -404.256303) (xy 380.451168 -404.32373) (xy 380.44309 -404.39067) (xy 380.427051 -404.456161)
			(xy 380.403283 -404.519259) (xy 380.372128 -404.579055) (xy 380.334034 -404.634689) (xy 380.312168 -404.660354)
			(xy 380.306362 -404.667492) (xy 380.299854 -404.684688) (xy 380.299468 -404.693882) (xy 380.299468 -405.186134)
			(xy 380.299869 -405.195322) (xy 380.30639 -405.212506) (xy 380.312168 -405.219662) (xy 380.334027 -405.245332)
			(xy 380.372118 -405.300965) (xy 380.403271 -405.36076) (xy 380.427037 -405.423856) (xy 380.443074 -405.489345)
			(xy 380.451151 -405.556284) (xy 380.451151 -405.623707) (xy 380.443075 -405.690646) (xy 380.42704 -405.756135)
			(xy 380.403275 -405.819232) (xy 380.372123 -405.879028) (xy 380.334033 -405.934661) (xy 380.312168 -405.960326)
			(xy 380.306374 -405.967473) (xy 380.299858 -405.984662) (xy 380.299468 -405.993854) (xy 380.299468 -406.151334)
			(xy 380.299002 -406.161462) (xy 380.291264 -406.180182) (xy 380.276972 -406.194537) (xy 380.258286 -406.202357)
			(xy 380.24816 -406.202896) (xy 379.53188 -406.202896) (xy 379.521769 -406.202431) (xy 379.50309 -406.194686)
			(xy 379.488796 -406.180383) (xy 379.481062 -406.161699) (xy 379.480572 -406.151588) (xy 379.480572 -405.993854)
			(xy 379.480142 -405.984669) (xy 379.473643 -405.967484) (xy 379.467872 -405.960326) (xy 379.446003 -405.934665)
			(xy 379.407916 -405.879029) (xy 379.376768 -405.819232) (xy 379.353005 -405.756135) (xy 379.336971 -405.690646)
			(xy 379.328896 -405.623707) (xy 378.200839 -405.623707) (xy 378.17197 -405.679128) (xy 378.133883 -405.734762)
			(xy 378.11202 -405.760428) (xy 378.106231 -405.767579) (xy 378.099711 -405.784765) (xy 378.09932 -405.793956)
			(xy 378.09932 -406.286208) (xy 378.099722 -406.295396) (xy 378.106241 -406.312581) (xy 378.11202 -406.319736)
			(xy 378.133852 -406.345428) (xy 378.17194 -406.401059) (xy 378.203091 -406.460852) (xy 378.226856 -406.523945)
			(xy 378.242893 -406.589431) (xy 378.250971 -406.656366) (xy 378.250974 -406.723729) (xy 381.529036 -406.723729)
			(xy 381.529039 -406.656422) (xy 381.537086 -406.589598) (xy 381.553062 -406.524214) (xy 381.576737 -406.461209)
			(xy 381.607772 -406.401484) (xy 381.645723 -406.345897) (xy 381.667512 -406.320244) (xy 381.673316 -406.313104)
			(xy 381.679826 -406.29591) (xy 381.680212 -406.286716) (xy 381.680212 -405.793448) (xy 381.679776 -405.784264)
			(xy 381.67328 -405.767079) (xy 381.667512 -405.75992) (xy 381.645721 -405.734271) (xy 381.607774 -405.678683)
			(xy 381.576743 -405.618959) (xy 381.553071 -405.555954) (xy 381.537099 -405.490572) (xy 381.529056 -405.423749)
			(xy 381.529056 -405.356445) (xy 381.5371 -405.289622) (xy 381.553073 -405.22424) (xy 381.576745 -405.161235)
			(xy 381.607777 -405.101512) (xy 381.645725 -405.045924) (xy 381.667512 -405.020272) (xy 381.673304 -405.013124)
			(xy 381.679821 -404.995936) (xy 381.680212 -404.986744) (xy 381.680212 -404.828756) (xy 381.680649 -404.818643)
			(xy 381.688404 -404.799961) (xy 381.702715 -404.785668) (xy 381.721406 -404.777937) (xy 381.73152 -404.777448)
			(xy 382.448054 -404.777448) (xy 382.458179 -404.777965) (xy 382.4769 -404.785679) (xy 382.491258 -404.799956)
			(xy 382.499078 -404.818634) (xy 382.499616 -404.828756) (xy 382.499616 -404.986744) (xy 382.500001 -404.995934)
			(xy 382.506532 -405.013118) (xy 382.512316 -405.020272) (xy 382.534101 -405.045927) (xy 382.572053 -405.101512)
			(xy 382.603089 -405.161235) (xy 382.626764 -405.224239) (xy 382.642738 -405.289621) (xy 382.650784 -405.356444)
			(xy 382.650784 -405.42375) (xy 382.64274 -405.490573) (xy 382.626766 -405.555955) (xy 382.603091 -405.61896)
			(xy 382.600655 -405.623648) (xy 383.729191 -405.623648) (xy 383.729192 -405.556343) (xy 383.737237 -405.489519)
			(xy 383.753211 -405.424136) (xy 383.776885 -405.361132) (xy 383.807921 -405.301408) (xy 383.845871 -405.245822)
			(xy 383.86766 -405.22017) (xy 383.873459 -405.213027) (xy 383.879971 -405.195835) (xy 383.88036 -405.186642)
			(xy 383.88036 -404.693374) (xy 383.879949 -404.684187) (xy 383.873434 -404.667004) (xy 383.86766 -404.659846)
			(xy 383.845893 -404.634176) (xy 383.807943 -404.578593) (xy 383.776907 -404.518872) (xy 383.753232 -404.45587)
			(xy 383.737257 -404.390489) (xy 383.729211 -404.323668) (xy 383.729209 -404.256365) (xy 383.737251 -404.189543)
			(xy 383.753222 -404.124162) (xy 383.776894 -404.061158) (xy 383.807926 -404.001436) (xy 383.845873 -403.94585)
			(xy 383.86766 -403.920198) (xy 383.873447 -403.913047) (xy 383.879966 -403.895861) (xy 383.88036 -403.88667)
			(xy 383.88036 -403.728682) (xy 383.88075 -403.718507) (xy 383.888545 -403.699707) (xy 383.902941 -403.685322)
			(xy 383.921746 -403.677542) (xy 383.931922 -403.67712) (xy 384.648202 -403.67712) (xy 384.658358 -403.677631)
			(xy 384.677123 -403.685403) (xy 384.691488 -403.699763) (xy 384.699265 -403.718526) (xy 384.699764 -403.728682)
			(xy 384.699764 -403.88667) (xy 384.700197 -403.895855) (xy 384.706696 -403.913039) (xy 384.712464 -403.920198)
			(xy 384.734273 -403.945832) (xy 384.772221 -404.001421) (xy 384.803254 -404.061147) (xy 384.826925 -404.124154)
			(xy 384.842896 -404.189539) (xy 384.850939 -404.256363) (xy 384.850937 -404.32367) (xy 384.84289 -404.390494)
			(xy 384.826915 -404.455877) (xy 384.80324 -404.518883) (xy 384.772204 -404.578607) (xy 384.734253 -404.634194)
			(xy 384.712464 -404.659846) (xy 384.706661 -404.666986) (xy 384.700151 -404.684181) (xy 384.699764 -404.693374)
			(xy 384.699764 -405.186642) (xy 384.700162 -405.19583) (xy 384.706685 -405.213014) (xy 384.712464 -405.22017)
			(xy 384.734246 -405.245827) (xy 384.772195 -405.301413) (xy 384.803228 -405.361136) (xy 384.826901 -405.42414)
			(xy 384.842874 -405.489521) (xy 384.850919 -405.556343) (xy 384.850919 -405.623648) (xy 384.842876 -405.69047)
			(xy 384.826904 -405.755852) (xy 384.803232 -405.818856) (xy 384.772199 -405.878579) (xy 384.734251 -405.934166)
			(xy 384.712464 -405.959818) (xy 384.706673 -405.966967) (xy 384.700156 -405.984155) (xy 384.699764 -405.993346)
			(xy 384.699764 -406.151334) (xy 384.699295 -406.161494) (xy 384.691509 -406.180263) (xy 384.677136 -406.194627)
			(xy 384.658362 -406.202401) (xy 384.648202 -406.202896) (xy 383.931922 -406.202896) (xy 383.92177 -406.20235)
			(xy 383.903008 -406.194589) (xy 383.888643 -406.180239) (xy 383.880861 -406.161486) (xy 383.88036 -406.151334)
			(xy 383.88036 -405.993346) (xy 383.879914 -405.984163) (xy 383.873424 -405.966979) (xy 383.86766 -405.959818)
			(xy 383.845866 -405.934171) (xy 383.807916 -405.878584) (xy 383.776882 -405.81886) (xy 383.753208 -405.755855)
			(xy 383.737235 -405.690472) (xy 383.729191 -405.623648) (xy 382.600655 -405.623648) (xy 382.572056 -405.678683)
			(xy 382.534105 -405.734268) (xy 382.512316 -405.75992) (xy 382.50653 -405.767073) (xy 382.500009 -405.784257)
			(xy 382.499616 -405.793448) (xy 382.499616 -406.286716) (xy 382.500015 -406.295904) (xy 382.506536 -406.313089)
			(xy 382.512316 -406.320244) (xy 382.534074 -406.345921) (xy 382.572026 -406.401503) (xy 382.603063 -406.461223)
			(xy 382.62674 -406.524224) (xy 382.642717 -406.589604) (xy 382.650764 -406.656424) (xy 382.650767 -406.723728)
			(xy 382.65076 -406.723789) (xy 385.928805 -406.723789) (xy 385.928807 -406.656363) (xy 385.936887 -406.589422)
			(xy 385.952926 -406.523931) (xy 385.976694 -406.460833) (xy 386.007849 -406.401036) (xy 386.045942 -406.345401)
			(xy 386.067808 -406.319736) (xy 386.073615 -406.312598) (xy 386.080123 -406.295402) (xy 386.080508 -406.286208)
			(xy 386.080508 -405.793956) (xy 386.080117 -405.784767) (xy 386.07359 -405.767583) (xy 386.067808 -405.760428)
			(xy 386.04594 -405.734766) (xy 386.007851 -405.679131) (xy 385.9767 -405.619335) (xy 385.952935 -405.556237)
			(xy 385.9369 -405.490748) (xy 385.928824 -405.423809) (xy 385.928825 -405.356385) (xy 385.936901 -405.289446)
			(xy 385.952937 -405.223957) (xy 385.976702 -405.16086) (xy 386.007854 -405.101064) (xy 386.045944 -405.045429)
			(xy 386.067808 -405.019764) (xy 386.073603 -405.012618) (xy 386.080118 -404.995428) (xy 386.080508 -404.986236)
			(xy 386.080508 -404.828756) (xy 386.080949 -404.818643) (xy 386.088703 -404.799963) (xy 386.103013 -404.785669)
			(xy 386.121703 -404.777938) (xy 386.131816 -404.777448) (xy 386.848096 -404.777448) (xy 386.858198 -404.777987)
			(xy 386.876866 -404.785714) (xy 386.891159 -404.799993) (xy 386.898903 -404.818654) (xy 386.899404 -404.828756)
			(xy 386.899404 -404.986236) (xy 386.899796 -404.995425) (xy 386.906322 -405.012609) (xy 386.912104 -405.019764)
			(xy 386.933964 -405.045433) (xy 386.972052 -405.101067) (xy 387.003203 -405.160862) (xy 387.026967 -405.223959)
			(xy 387.043003 -405.289448) (xy 387.051079 -405.356385) (xy 387.051079 -405.423809) (xy 387.043004 -405.490747)
			(xy 387.026969 -405.556235) (xy 387.003206 -405.619332) (xy 387.000958 -405.623648) (xy 388.128982 -405.623648)
			(xy 388.128982 -405.556343) (xy 388.137027 -405.489519) (xy 388.153001 -405.424137) (xy 388.176675 -405.361132)
			(xy 388.207709 -405.301408) (xy 388.245659 -405.245822) (xy 388.267448 -405.22017) (xy 388.273246 -405.213026)
			(xy 388.279758 -405.195834) (xy 388.280148 -405.186642) (xy 388.280148 -404.693374) (xy 388.27974 -404.684187)
			(xy 388.273223 -404.667003) (xy 388.267448 -404.659846) (xy 388.245682 -404.634176) (xy 388.207732 -404.578592)
			(xy 388.176697 -404.518871) (xy 388.153023 -404.455869) (xy 388.137048 -404.390489) (xy 388.129002 -404.323668)
			(xy 388.129 -404.256365) (xy 388.137042 -404.189544) (xy 388.153013 -404.124163) (xy 388.176684 -404.061159)
			(xy 388.207715 -404.001436) (xy 388.245662 -403.94585) (xy 388.267448 -403.920198) (xy 388.273234 -403.913045)
			(xy 388.279754 -403.89586) (xy 388.280148 -403.88667) (xy 388.280148 -403.728682) (xy 388.280619 -403.718522)
			(xy 388.288401 -403.69975) (xy 388.302774 -403.685385) (xy 388.32155 -403.677613) (xy 388.33171 -403.67712)
			(xy 389.04799 -403.67712) (xy 389.058145 -403.677641) (xy 389.07691 -403.685409) (xy 389.091275 -403.699766)
			(xy 389.099053 -403.718527) (xy 389.099552 -403.728682) (xy 389.099552 -403.88667) (xy 389.099987 -403.895854)
			(xy 389.106485 -403.913038) (xy 389.112252 -403.920198) (xy 389.134062 -403.945832) (xy 389.172011 -404.001421)
			(xy 389.203043 -404.061147) (xy 389.226715 -404.124154) (xy 389.242687 -404.189538) (xy 389.25073 -404.256363)
			(xy 389.250728 -404.32367) (xy 389.242681 -404.390494) (xy 389.226706 -404.455878) (xy 389.20303 -404.518883)
			(xy 389.171994 -404.578608) (xy 389.134041 -404.634194) (xy 389.112252 -404.659846) (xy 389.106447 -404.666985)
			(xy 389.099939 -404.684181) (xy 389.099552 -404.693374) (xy 389.099552 -405.186642) (xy 389.099953 -405.19583)
			(xy 389.106474 -405.213014) (xy 389.112252 -405.22017) (xy 389.134034 -405.245827) (xy 389.171983 -405.301413)
			(xy 389.203017 -405.361135) (xy 389.226691 -405.424139) (xy 389.242665 -405.489521) (xy 389.250709 -405.556343)
			(xy 389.25071 -405.623648) (xy 389.242666 -405.69047) (xy 389.226694 -405.755852) (xy 389.203021 -405.818856)
			(xy 389.171988 -405.87858) (xy 389.134039 -405.934166) (xy 389.112252 -405.959818) (xy 389.106459 -405.966966)
			(xy 389.099944 -405.984154) (xy 389.099552 -405.993346) (xy 389.099552 -406.151334) (xy 389.099094 -406.161495)
			(xy 389.091307 -406.180267) (xy 389.07693 -406.194631) (xy 389.058152 -406.202403) (xy 389.04799 -406.202896)
			(xy 388.33171 -406.202896) (xy 388.321557 -406.202359) (xy 388.302795 -406.194594) (xy 388.28843 -406.180242)
			(xy 388.280649 -406.161487) (xy 388.280148 -406.151334) (xy 388.280148 -405.993346) (xy 388.279705 -405.984163)
			(xy 388.273213 -405.966979) (xy 388.267448 -405.959818) (xy 388.245654 -405.934171) (xy 388.207705 -405.878584)
			(xy 388.176671 -405.81886) (xy 388.152998 -405.755855) (xy 388.137025 -405.690472) (xy 388.128982 -405.623648)
			(xy 387.000958 -405.623648) (xy 386.972056 -405.679128) (xy 386.933968 -405.734763) (xy 386.912104 -405.760428)
			(xy 386.906314 -405.767578) (xy 386.899795 -405.784765) (xy 386.899404 -405.793956) (xy 386.899404 -406.286208)
			(xy 386.89981 -406.295396) (xy 386.906326 -406.31258) (xy 386.912104 -406.319736) (xy 386.933936 -406.345427)
			(xy 386.972026 -406.401058) (xy 387.003178 -406.460851) (xy 387.026943 -406.523944) (xy 387.042981 -406.58943)
			(xy 387.051059 -406.656365) (xy 387.051062 -406.723729) (xy 390.329124 -406.723729) (xy 390.329127 -406.656423)
			(xy 390.337174 -406.589599) (xy 390.353149 -406.524215) (xy 390.376823 -406.461209) (xy 390.407858 -406.401485)
			(xy 390.445808 -406.345897) (xy 390.467596 -406.320244) (xy 390.473398 -406.313103) (xy 390.47991 -406.295909)
			(xy 390.480296 -406.286716) (xy 390.480296 -405.793448) (xy 390.479864 -405.784263) (xy 390.473366 -405.767078)
			(xy 390.467596 -405.75992) (xy 390.445806 -405.73427) (xy 390.40786 -405.678683) (xy 390.376829 -405.618958)
			(xy 390.353158 -405.555954) (xy 390.337187 -405.490571) (xy 390.329144 -405.423749) (xy 390.329144 -405.356445)
			(xy 390.337188 -405.289623) (xy 390.35316 -405.224241) (xy 390.376832 -405.161236) (xy 390.407863 -405.101512)
			(xy 390.445809 -405.045925) (xy 390.467596 -405.020272) (xy 390.473386 -405.013122) (xy 390.479905 -404.995935)
			(xy 390.480296 -404.986744) (xy 390.480296 -404.828756) (xy 390.480749 -404.818645) (xy 390.4885 -404.799967)
			(xy 390.502807 -404.785673) (xy 390.521493 -404.77794) (xy 390.531604 -404.777448) (xy 391.248138 -404.777448)
			(xy 391.258268 -404.777896) (xy 391.276992 -404.785637) (xy 391.291347 -404.799935) (xy 391.299163 -404.818628)
			(xy 391.2997 -404.828756) (xy 391.2997 -404.986744) (xy 391.300089 -404.995933) (xy 391.306617 -405.013118)
			(xy 391.3124 -405.020272) (xy 391.334183 -405.045928) (xy 391.372129 -405.101515) (xy 391.40316 -405.161238)
			(xy 391.426832 -405.224242) (xy 391.442804 -405.289623) (xy 391.450848 -405.356445) (xy 391.450848 -405.423749)
			(xy 391.442805 -405.490571) (xy 391.426833 -405.555952) (xy 391.403163 -405.618956) (xy 391.372132 -405.67868)
			(xy 391.334186 -405.734267) (xy 391.3124 -405.75992) (xy 391.306612 -405.767072) (xy 391.300092 -405.784257)
			(xy 391.2997 -405.793448) (xy 391.2997 -406.286716) (xy 391.300103 -406.295904) (xy 391.306622 -406.313088)
			(xy 391.3124 -406.320244) (xy 391.334155 -406.345923) (xy 391.372102 -406.401506) (xy 391.403135 -406.461226)
			(xy 391.426808 -406.524227) (xy 391.442782 -406.589606) (xy 391.450828 -406.656425) (xy 391.450831 -406.723727)
			(xy 391.44279 -406.790547) (xy 391.426822 -406.855927) (xy 391.403154 -406.91893) (xy 391.372127 -406.978653)
			(xy 391.334185 -407.034239) (xy 391.3124 -407.059892) (xy 391.306624 -407.067052) (xy 391.300097 -407.084231)
			(xy 391.2997 -407.09342) (xy 391.2997 -407.251408) (xy 391.299221 -407.261517) (xy 391.291481 -407.280196)
			(xy 391.277182 -407.29449) (xy 391.258501 -407.302224) (xy 391.248392 -407.302716) (xy 390.531858 -407.302716)
			(xy 390.521723 -407.302307) (xy 390.502993 -407.294557) (xy 390.488636 -407.280247) (xy 390.480826 -407.261541)
			(xy 390.480296 -407.251408) (xy 390.480296 -407.09342) (xy 390.479877 -407.084234) (xy 390.47337 -407.067049)
			(xy 390.467596 -407.059892) (xy 390.445778 -407.034265) (xy 390.407833 -406.978674) (xy 390.376804 -406.918947)
			(xy 390.353135 -406.855939) (xy 390.337165 -406.790554) (xy 390.329124 -406.723729) (xy 387.051062 -406.723729)
			(xy 387.051062 -406.723787) (xy 387.04299 -406.790723) (xy 387.026958 -406.85621) (xy 387.003197 -406.919305)
			(xy 386.972051 -406.979101) (xy 386.933966 -407.034735) (xy 386.912104 -407.0604) (xy 386.906325 -407.067558)
			(xy 386.8998 -407.084739) (xy 386.899404 -407.093928) (xy 386.899404 -407.251408) (xy 386.898921 -407.261517)
			(xy 386.891182 -407.280194) (xy 386.876884 -407.294489) (xy 386.858205 -407.302224) (xy 386.848096 -407.302716)
			(xy 386.131816 -407.302716) (xy 386.121697 -407.302271) (xy 386.102996 -407.294531) (xy 386.088682 -407.280224)
			(xy 386.080933 -407.261527) (xy 386.080508 -407.251408) (xy 386.080508 -407.093928) (xy 386.080083 -407.084742)
			(xy 386.073579 -407.067558) (xy 386.067808 -407.0604) (xy 386.045912 -407.034761) (xy 386.007824 -406.979123)
			(xy 385.976674 -406.919323) (xy 385.952912 -406.856223) (xy 385.936878 -406.79073) (xy 385.928805 -406.723789)
			(xy 382.65076 -406.723789) (xy 382.642725 -406.790549) (xy 382.626754 -406.85593) (xy 382.603083 -406.918933)
			(xy 382.572051 -406.978655) (xy 382.534103 -407.03424) (xy 382.512316 -407.059892) (xy 382.506542 -407.067053)
			(xy 382.500013 -407.084231) (xy 382.499616 -407.09342) (xy 382.499616 -407.251408) (xy 382.499122 -407.261515)
			(xy 382.491384 -407.28019) (xy 382.47709 -407.294484) (xy 382.458415 -407.302222) (xy 382.448308 -407.302716)
			(xy 381.731774 -407.302716) (xy 381.72164 -407.302294) (xy 381.70291 -407.294549) (xy 381.688553 -407.280243)
			(xy 381.680743 -407.26154) (xy 381.680212 -407.251408) (xy 381.680212 -407.09342) (xy 381.679789 -407.084234)
			(xy 381.673284 -407.06705) (xy 381.667512 -407.059892) (xy 381.645694 -407.034265) (xy 381.607748 -406.978675)
			(xy 381.576717 -406.918947) (xy 381.553047 -406.855939) (xy 381.537077 -406.790554) (xy 381.529036 -406.723729)
			(xy 378.250974 -406.723729) (xy 378.250974 -406.723786) (xy 378.242902 -406.790722) (xy 378.226871 -406.856209)
			(xy 378.203111 -406.919305) (xy 378.171965 -406.9791) (xy 378.133881 -407.034734) (xy 378.11202 -407.0604)
			(xy 378.106243 -407.067559) (xy 378.099716 -407.084739) (xy 378.09932 -407.093928) (xy 378.09932 -407.251408)
			(xy 378.098822 -407.261515) (xy 378.091085 -407.280189) (xy 378.076793 -407.294483) (xy 378.058119 -407.302221)
			(xy 378.048012 -407.302716) (xy 377.331732 -407.302716) (xy 377.321614 -407.302258) (xy 377.302914 -407.294524)
			(xy 377.288599 -407.28022) (xy 377.280849 -407.261526) (xy 377.280424 -407.251408) (xy 377.280424 -407.093928)
			(xy 377.279995 -407.084743) (xy 377.273494 -407.067559) (xy 377.267724 -407.0604) (xy 377.245828 -407.034761)
			(xy 377.207738 -406.979123) (xy 377.176588 -406.919324) (xy 377.152824 -406.856223) (xy 377.13679 -406.790731)
			(xy 377.128717 -406.723789) (xy 347.450915 -406.723789) (xy 347.442881 -406.790547) (xy 347.426912 -406.855927)
			(xy 347.403244 -406.91893) (xy 347.372216 -406.978653) (xy 347.334273 -407.03424) (xy 347.312488 -407.059892)
			(xy 347.306711 -407.067051) (xy 347.300185 -407.084231) (xy 347.299788 -407.09342) (xy 347.299788 -407.251408)
			(xy 347.299385 -407.261564) (xy 347.291584 -407.280319) (xy 347.277182 -407.294642) (xy 347.258384 -407.30234)
			(xy 347.248226 -407.302716) (xy 346.531946 -407.302716) (xy 346.521817 -407.302234) (xy 346.503088 -407.294514)
			(xy 346.488729 -407.280225) (xy 346.480916 -407.261535) (xy 346.480384 -407.251408) (xy 346.480384 -407.09342)
			(xy 346.479968 -407.084233) (xy 346.473459 -407.067049) (xy 346.467684 -407.059892) (xy 346.445864 -407.034266)
			(xy 346.407913 -406.978677) (xy 346.376878 -406.91895) (xy 346.353205 -406.855942) (xy 346.337233 -406.790556)
			(xy 346.329191 -406.72373) (xy 343.051153 -406.72373) (xy 343.051153 -406.723787) (xy 343.04308 -406.790723)
			(xy 343.027048 -406.85621) (xy 343.003287 -406.919306) (xy 342.97214 -406.979101) (xy 342.934054 -407.034735)
			(xy 342.912192 -407.0604) (xy 342.906412 -407.067557) (xy 342.899888 -407.084738) (xy 342.899492 -407.093928)
			(xy 342.899492 -407.251408) (xy 342.89909 -407.261532) (xy 342.891338 -407.280237) (xy 342.877017 -407.294551)
			(xy 342.858308 -407.302295) (xy 342.848184 -407.302716) (xy 342.131904 -407.302716) (xy 342.121798 -407.302212)
			(xy 342.103122 -407.294479) (xy 342.088828 -407.280188) (xy 342.08109 -407.261514) (xy 342.080596 -407.251408)
			(xy 342.080596 -407.093928) (xy 342.080173 -407.084742) (xy 342.073668 -407.067558) (xy 342.067896 -407.0604)
			(xy 342.046001 -407.034761) (xy 342.007913 -406.979122) (xy 341.976764 -406.919322) (xy 341.953002 -406.856222)
			(xy 341.936969 -406.79073) (xy 341.928896 -406.723789) (xy 338.650827 -406.723789) (xy 338.642793 -406.790546)
			(xy 338.626825 -406.855926) (xy 338.603158 -406.918929) (xy 338.572131 -406.978652) (xy 338.534188 -407.034239)
			(xy 338.512404 -407.059892) (xy 338.506629 -407.067052) (xy 338.500101 -407.084231) (xy 338.499704 -407.09342)
			(xy 338.499704 -407.251408) (xy 338.499285 -407.261562) (xy 338.491487 -407.280314) (xy 338.47709 -407.294637)
			(xy 338.458298 -407.302337) (xy 338.448142 -407.302716) (xy 337.731862 -407.302716) (xy 337.721727 -407.302303)
			(xy 337.702997 -407.294555) (xy 337.688641 -407.280246) (xy 337.68083 -407.261541) (xy 337.6803 -407.251408)
			(xy 337.6803 -407.09342) (xy 337.67988 -407.084234) (xy 337.673373 -407.067049) (xy 337.6676 -407.059892)
			(xy 337.645782 -407.034265) (xy 337.607837 -406.978674) (xy 337.576807 -406.918947) (xy 337.553138 -406.855939)
			(xy 337.537168 -406.790554) (xy 337.529127 -406.723729) (xy 334.251065 -406.723729) (xy 334.251065 -406.723786)
			(xy 334.242993 -406.790722) (xy 334.226961 -406.85621) (xy 334.203201 -406.919305) (xy 334.172054 -406.9791)
			(xy 334.13397 -407.034735) (xy 334.112108 -407.0604) (xy 334.10633 -407.067558) (xy 334.099804 -407.084739)
			(xy 334.099408 -407.093928) (xy 334.099408 -407.251408) (xy 334.098921 -407.261516) (xy 334.091183 -407.280193)
			(xy 334.076886 -407.294487) (xy 334.058208 -407.302223) (xy 334.0481 -407.302716) (xy 333.33182 -407.302716)
			(xy 333.321701 -407.302268) (xy 333.303001 -407.29453) (xy 333.288686 -407.280223) (xy 333.280937 -407.261527)
			(xy 333.280512 -407.251408) (xy 333.280512 -407.093928) (xy 333.280086 -407.084743) (xy 333.273583 -407.067558)
			(xy 333.267812 -407.0604) (xy 333.245916 -407.034761) (xy 333.207828 -406.979123) (xy 333.176678 -406.919323)
			(xy 333.152915 -406.856223) (xy 333.136881 -406.790731) (xy 333.128808 -406.723789) (xy 326.525636 -406.723789)
			(xy 326.525636 -409.523827) (xy 330.929173 -409.523827) (xy 330.929176 -409.456519) (xy 330.937224 -409.389693)
			(xy 330.953202 -409.324309) (xy 330.976879 -409.261303) (xy 331.007918 -409.201578) (xy 331.045873 -409.145992)
			(xy 331.067664 -409.12034) (xy 331.073476 -409.113206) (xy 331.07998 -409.096007) (xy 331.080364 -409.086812)
			(xy 331.080364 -408.593544) (xy 331.079919 -408.584361) (xy 331.073428 -408.567177) (xy 331.067664 -408.560016)
			(xy 331.045868 -408.534371) (xy 331.007918 -408.478784) (xy 330.976883 -408.419059) (xy 330.95321 -408.356054)
			(xy 330.937237 -408.290671) (xy 330.929193 -408.223847) (xy 330.929194 -408.156541) (xy 330.937239 -408.089717)
			(xy 330.953213 -408.024334) (xy 330.976888 -407.96133) (xy 331.007924 -407.901606) (xy 331.045875 -407.84602)
			(xy 331.067664 -407.820368) (xy 331.073464 -407.813226) (xy 331.079975 -407.796033) (xy 331.080364 -407.78684)
			(xy 331.080364 -407.628852) (xy 331.080782 -407.618699) (xy 331.088586 -407.599953) (xy 331.102983 -407.585633)
			(xy 331.121771 -407.577928) (xy 331.131926 -407.577544) (xy 331.848206 -407.577544) (xy 331.858334 -407.578022)
			(xy 331.877056 -407.585752) (xy 331.891412 -407.600041) (xy 331.89923 -407.618727) (xy 331.899768 -407.628852)
			(xy 331.899768 -407.78684) (xy 331.900166 -407.796028) (xy 331.906689 -407.813212) (xy 331.912468 -407.820368)
			(xy 331.934248 -407.846027) (xy 331.972196 -407.901612) (xy 332.00323 -407.961335) (xy 332.026903 -408.024339)
			(xy 332.042876 -408.08972) (xy 332.050921 -408.156542) (xy 332.050921 -408.223846) (xy 332.042878 -408.290668)
			(xy 332.026906 -408.35605) (xy 332.003235 -408.419054) (xy 331.972203 -408.478777) (xy 331.934255 -408.534364)
			(xy 331.912468 -408.560016) (xy 331.906678 -408.567166) (xy 331.90016 -408.584353) (xy 331.899768 -408.593544)
			(xy 331.899768 -409.086812) (xy 331.900179 -409.095999) (xy 331.906693 -409.113183) (xy 331.912468 -409.12034)
			(xy 331.93422 -409.146022) (xy 331.972169 -409.201604) (xy 332.003204 -409.261323) (xy 332.026878 -409.324324)
			(xy 332.042853 -409.389703) (xy 332.0509 -409.456522) (xy 332.050904 -409.523824) (xy 332.042863 -409.590644)
			(xy 332.026894 -409.656024) (xy 332.003226 -409.719027) (xy 331.972197 -409.77875) (xy 331.934253 -409.834336)
			(xy 331.912468 -409.859988) (xy 331.906647 -409.867116) (xy 331.900148 -409.88432) (xy 331.899768 -409.893516)
			(xy 331.899768 -410.051504) (xy 331.899381 -410.061662) (xy 331.891578 -410.080421) (xy 331.87717 -410.094745)
			(xy 331.858367 -410.102439) (xy 331.848206 -410.102812) (xy 331.131926 -410.102812) (xy 331.121807 -410.102254)
			(xy 331.103097 -410.094544) (xy 331.088741 -410.08028) (xy 331.080912 -410.061619) (xy 331.080364 -410.051504)
			(xy 331.080364 -409.893516) (xy 331.079932 -409.884331) (xy 331.073432 -409.867148) (xy 331.067664 -409.859988)
			(xy 331.04584 -409.834365) (xy 331.007891 -409.778775) (xy 330.976857 -409.719048) (xy 330.953186 -409.656039)
			(xy 330.937214 -409.590653) (xy 330.929173 -409.523827) (xy 326.525636 -409.523827) (xy 326.525636 -410.623701)
			(xy 333.128819 -410.623701) (xy 333.12882 -410.556275) (xy 333.136898 -410.489336) (xy 333.152936 -410.423846)
			(xy 333.176702 -410.360748) (xy 333.207855 -410.300952) (xy 333.245947 -410.245317) (xy 333.267812 -410.219652)
			(xy 333.273613 -410.21251) (xy 333.280125 -410.195317) (xy 333.280512 -410.186124) (xy 333.280512 -409.693872)
			(xy 333.280113 -409.684684) (xy 333.273591 -409.6675) (xy 333.267812 -409.660344) (xy 333.245959 -409.634669)
			(xy 333.20787 -409.579036) (xy 333.176718 -409.519242) (xy 333.152952 -409.456146) (xy 333.136916 -409.390658)
			(xy 333.128839 -409.32372) (xy 333.128837 -409.256298) (xy 333.136912 -409.18936) (xy 333.152947 -409.123871)
			(xy 333.17671 -409.060775) (xy 333.20786 -409.000979) (xy 333.245948 -408.945345) (xy 333.267812 -408.91968)
			(xy 333.273601 -408.912529) (xy 333.28012 -408.895343) (xy 333.280512 -408.886152) (xy 333.280512 -408.728672)
			(xy 333.280962 -408.71856) (xy 333.288711 -408.699879) (xy 333.303019 -408.685585) (xy 333.321708 -408.677853)
			(xy 333.33182 -408.677364) (xy 334.0481 -408.677364) (xy 334.058204 -408.677884) (xy 334.076876 -408.685615)
			(xy 334.091169 -408.699901) (xy 334.09891 -408.718568) (xy 334.099408 -408.728672) (xy 334.099408 -408.886152)
			(xy 334.099839 -408.895337) (xy 334.106338 -408.912522) (xy 334.112108 -408.91968) (xy 334.133983 -408.945336)
			(xy 334.172071 -409.000972) (xy 334.203221 -409.060769) (xy 334.226984 -409.123867) (xy 334.243019 -409.189358)
			(xy 334.251093 -409.256297) (xy 334.251092 -409.323721) (xy 334.243015 -409.39066) (xy 334.226979 -409.45615)
			(xy 334.203214 -409.519247) (xy 334.200797 -409.523886) (xy 335.328966 -409.523886) (xy 335.328969 -409.45646)
			(xy 335.337048 -409.38952) (xy 335.353086 -409.32403) (xy 335.376852 -409.260931) (xy 335.408005 -409.201134)
			(xy 335.446095 -409.145498) (xy 335.46796 -409.119832) (xy 335.473775 -409.1127) (xy 335.480277 -409.095499)
			(xy 335.48066 -409.086304) (xy 335.48066 -408.594052) (xy 335.480211 -408.584869) (xy 335.473723 -408.567685)
			(xy 335.46796 -408.560524) (xy 335.44609 -408.534865) (xy 335.408004 -408.479228) (xy 335.376856 -408.419431)
			(xy 335.353094 -408.356333) (xy 335.33706 -408.290844) (xy 335.328985 -408.223906) (xy 335.328986 -408.156482)
			(xy 335.337062 -408.089544) (xy 335.353097 -408.024055) (xy 335.376861 -407.960958) (xy 335.40801 -407.901161)
			(xy 335.446097 -407.845526) (xy 335.46796 -407.81986) (xy 335.473763 -407.81272) (xy 335.480272 -407.795525)
			(xy 335.48066 -407.786332) (xy 335.48066 -407.628852) (xy 335.481145 -407.618745) (xy 335.488891 -407.600074)
			(xy 335.503187 -407.585782) (xy 335.521861 -407.578042) (xy 335.531968 -407.577544) (xy 336.248248 -407.577544)
			(xy 336.258353 -407.578045) (xy 336.277021 -407.585788) (xy 336.291312 -407.600079) (xy 336.299055 -407.618747)
			(xy 336.299556 -407.628852) (xy 336.299556 -407.786332) (xy 336.299961 -407.79552) (xy 336.306479 -407.812703)
			(xy 336.312256 -407.81986) (xy 336.334114 -407.845531) (xy 336.372205 -407.901164) (xy 336.403359 -407.960959)
			(xy 336.427126 -408.024055) (xy 336.443163 -408.089544) (xy 336.45124 -408.156482) (xy 336.451241 -408.223906)
			(xy 336.443165 -408.290844) (xy 336.427129 -408.356334) (xy 336.403364 -408.41943) (xy 336.372212 -408.479226)
			(xy 336.334121 -408.53486) (xy 336.312256 -408.560524) (xy 336.306461 -408.56767) (xy 336.299947 -408.58486)
			(xy 336.299556 -408.594052) (xy 336.299556 -409.086304) (xy 336.299974 -409.09549) (xy 336.306483 -409.112674)
			(xy 336.312256 -409.119832) (xy 336.334086 -409.145526) (xy 336.372179 -409.201155) (xy 336.403334 -409.260947)
			(xy 336.427102 -409.32404) (xy 336.443141 -409.389526) (xy 336.45122 -409.456462) (xy 336.451224 -409.523884)
			(xy 336.443151 -409.59082) (xy 336.427118 -409.656308) (xy 336.403356 -409.719404) (xy 336.372207 -409.779198)
			(xy 336.334119 -409.834832) (xy 336.312256 -409.860496) (xy 336.306473 -409.867651) (xy 336.299951 -409.884834)
			(xy 336.299556 -409.894024) (xy 336.299556 -410.051504) (xy 336.299019 -410.061606) (xy 336.291291 -410.080274)
			(xy 336.277011 -410.094566) (xy 336.25835 -410.102311) (xy 336.248248 -410.102812) (xy 335.531968 -410.102812)
			(xy 335.521859 -410.102341) (xy 335.503182 -410.094595) (xy 335.488889 -410.080294) (xy 335.481153 -410.061614)
			(xy 335.48066 -410.051504) (xy 335.48066 -409.894024) (xy 335.480225 -409.88484) (xy 335.473727 -409.867656)
			(xy 335.46796 -409.860496) (xy 335.446062 -409.834859) (xy 335.407977 -409.77922) (xy 335.37683 -409.719419)
			(xy 335.35307 -409.656319) (xy 335.337038 -409.590827) (xy 335.328966 -409.523886) (xy 334.200797 -409.523886)
			(xy 334.172062 -409.579044) (xy 334.133972 -409.634679) (xy 334.112108 -409.660344) (xy 334.106311 -409.667489)
			(xy 334.099796 -409.68468) (xy 334.099408 -409.693872) (xy 334.099408 -410.186124) (xy 334.099805 -410.195313)
			(xy 334.106328 -410.212497) (xy 334.112108 -410.219652) (xy 334.133956 -410.24533) (xy 334.172045 -410.300963)
			(xy 334.203196 -410.360758) (xy 334.22696 -410.423853) (xy 334.242997 -410.48934) (xy 334.251074 -410.556277)
			(xy 334.251075 -410.623641) (xy 337.529138 -410.623641) (xy 337.52914 -410.556335) (xy 337.537185 -410.489512)
			(xy 337.553158 -410.42413) (xy 337.576831 -410.361125) (xy 337.607864 -410.3014) (xy 337.645813 -410.245813)
			(xy 337.6676 -410.22016) (xy 337.673396 -410.213014) (xy 337.679911 -410.195824) (xy 337.6803 -410.186632)
			(xy 337.6803 -409.693364) (xy 337.679907 -409.684175) (xy 337.673382 -409.666991) (xy 337.6676 -409.659836)
			(xy 337.645825 -409.634174) (xy 337.607879 -409.578588) (xy 337.576847 -409.518865) (xy 337.553175 -409.455862)
			(xy 337.537203 -409.390482) (xy 337.529158 -409.323661) (xy 337.529157 -409.256357) (xy 337.537199 -409.189536)
			(xy 337.55317 -409.124155) (xy 337.57684 -409.061151) (xy 337.607869 -409.001428) (xy 337.645814 -408.945841)
			(xy 337.6676 -408.920188) (xy 337.673384 -408.913034) (xy 337.679906 -408.89585) (xy 337.6803 -408.88666)
			(xy 337.6803 -408.728672) (xy 337.680699 -408.718516) (xy 337.688503 -408.699763) (xy 337.702907 -408.685441)
			(xy 337.721704 -408.677742) (xy 337.731862 -408.677364) (xy 338.448142 -408.677364) (xy 338.458274 -408.677793)
			(xy 338.477001 -408.685539) (xy 338.491357 -408.699843) (xy 338.49917 -408.718542) (xy 338.499704 -408.728672)
			(xy 338.499704 -408.88666) (xy 338.500132 -408.895845) (xy 338.506633 -408.91303) (xy 338.512404 -408.920188)
			(xy 338.534202 -408.945831) (xy 338.572148 -409.00142) (xy 338.603178 -409.061145) (xy 338.626848 -409.124151)
			(xy 338.642819 -409.189534) (xy 338.650862 -409.256356) (xy 338.650861 -409.323662) (xy 338.642816 -409.390484)
			(xy 338.626843 -409.455867) (xy 338.603171 -409.518871) (xy 338.600596 -409.523827) (xy 339.729261 -409.523827)
			(xy 339.729264 -409.456519) (xy 339.737312 -409.389694) (xy 339.753289 -409.324309) (xy 339.776966 -409.261303)
			(xy 339.808004 -409.201579) (xy 339.845958 -409.145992) (xy 339.867748 -409.12034) (xy 339.873559 -409.113205)
			(xy 339.880064 -409.096006) (xy 339.880448 -409.086812) (xy 339.880448 -408.593544) (xy 339.880006 -408.58436)
			(xy 339.873513 -408.567176) (xy 339.867748 -408.560016) (xy 339.845952 -408.534371) (xy 339.808003 -408.478783)
			(xy 339.776969 -408.419059) (xy 339.753297 -408.356054) (xy 339.737324 -408.29067) (xy 339.72928 -408.223847)
			(xy 339.729281 -408.156541) (xy 339.737326 -408.089718) (xy 339.7533 -408.024335) (xy 339.776974 -407.96133)
			(xy 339.808009 -407.901606) (xy 339.845959 -407.84602) (xy 339.867748 -407.820368) (xy 339.873547 -407.813224)
			(xy 339.880059 -407.796032) (xy 339.880448 -407.78684) (xy 339.880448 -407.628852) (xy 339.880881 -407.618701)
			(xy 339.888683 -407.599958) (xy 339.903075 -407.585638) (xy 339.921857 -407.577931) (xy 339.93201 -407.577544)
			(xy 340.64829 -407.577544) (xy 340.658417 -407.578035) (xy 340.677138 -407.58576) (xy 340.691495 -407.600045)
			(xy 340.699314 -407.618728) (xy 340.699852 -407.628852) (xy 340.699852 -407.78684) (xy 340.700254 -407.796028)
			(xy 340.706775 -407.813211) (xy 340.712552 -407.820368) (xy 340.734332 -407.846027) (xy 340.772282 -407.901612)
			(xy 340.803316 -407.961335) (xy 340.826989 -408.024338) (xy 340.842963 -408.08972) (xy 340.851008 -408.156542)
			(xy 340.851009 -408.223846) (xy 340.842965 -408.290668) (xy 340.826993 -408.35605) (xy 340.803321 -408.419054)
			(xy 340.772288 -408.478778) (xy 340.734339 -408.534364) (xy 340.712552 -408.560016) (xy 340.70676 -408.567164)
			(xy 340.700244 -408.584353) (xy 340.699852 -408.593544) (xy 340.699852 -409.086812) (xy 340.700267 -409.095998)
			(xy 340.706779 -409.113182) (xy 340.712552 -409.12034) (xy 340.734304 -409.146021) (xy 340.772255 -409.201603)
			(xy 340.80329 -409.261323) (xy 340.826965 -409.324323) (xy 340.842941 -409.389702) (xy 340.850988 -409.456522)
			(xy 340.850992 -409.523824) (xy 340.842951 -409.590644) (xy 340.826981 -409.656025) (xy 340.803312 -409.719028)
			(xy 340.772283 -409.77875) (xy 340.734338 -409.834336) (xy 340.712552 -409.859988) (xy 340.70673 -409.867115)
			(xy 340.700232 -409.88432) (xy 340.699852 -409.893516) (xy 340.699852 -410.051504) (xy 340.699383 -410.061652)
			(xy 340.691595 -410.080394) (xy 340.677214 -410.094716) (xy 340.65844 -410.102424) (xy 340.64829 -410.102812)
			(xy 339.93201 -410.102812) (xy 339.92189 -410.102267) (xy 339.903179 -410.094552) (xy 339.888824 -410.080284)
			(xy 339.880996 -410.061621) (xy 339.880448 -410.051504) (xy 339.880448 -409.893516) (xy 339.88002 -409.884331)
			(xy 339.873517 -409.867147) (xy 339.867748 -409.859988) (xy 339.845924 -409.834365) (xy 339.807976 -409.778775)
			(xy 339.776944 -409.719047) (xy 339.753273 -409.656039) (xy 339.737302 -409.590653) (xy 339.729261 -409.523827)
			(xy 338.600596 -409.523827) (xy 338.572139 -409.578596) (xy 338.534191 -409.634183) (xy 338.512404 -409.659836)
			(xy 338.50661 -409.666983) (xy 338.500094 -409.684172) (xy 338.499704 -409.693364) (xy 338.499704 -410.186632)
			(xy 338.500098 -410.195821) (xy 338.506623 -410.213005) (xy 338.512404 -410.22016) (xy 338.534175 -410.245826)
			(xy 338.572121 -410.301411) (xy 338.603153 -410.361133) (xy 338.626825 -410.424136) (xy 338.642797 -410.489516)
			(xy 338.650842 -410.556336) (xy 338.650844 -410.623639) (xy 338.650837 -410.6237) (xy 341.928907 -410.6237)
			(xy 341.928908 -410.556276) (xy 341.936986 -410.489336) (xy 341.953023 -410.423846) (xy 341.976789 -410.360749)
			(xy 342.007941 -410.300952) (xy 342.046031 -410.245317) (xy 342.067896 -410.219652) (xy 342.073695 -410.212508)
			(xy 342.080208 -410.195317) (xy 342.080596 -410.186124) (xy 342.080596 -409.693872) (xy 342.0802 -409.684683)
			(xy 342.073677 -409.667499) (xy 342.067896 -409.660344) (xy 342.046044 -409.634669) (xy 342.007955 -409.579036)
			(xy 341.976804 -409.519241) (xy 341.953039 -409.456145) (xy 341.937003 -409.390657) (xy 341.928927 -409.32372)
			(xy 341.928925 -409.256298) (xy 341.937 -409.18936) (xy 341.953034 -409.123872) (xy 341.976797 -409.060776)
			(xy 342.007946 -409.00098) (xy 342.046033 -408.945345) (xy 342.067896 -408.91968) (xy 342.073683 -408.912528)
			(xy 342.080204 -408.895343) (xy 342.080596 -408.886152) (xy 342.080596 -408.728672) (xy 342.081062 -408.718562)
			(xy 342.088808 -408.699884) (xy 342.103111 -408.68559) (xy 342.121794 -408.677856) (xy 342.131904 -408.677364)
			(xy 342.848184 -408.677364) (xy 342.858287 -408.677897) (xy 342.876958 -408.685623) (xy 342.891252 -408.699905)
			(xy 342.898994 -408.718569) (xy 342.899492 -408.728672) (xy 342.899492 -408.886152) (xy 342.899927 -408.895337)
			(xy 342.906424 -408.912521) (xy 342.912192 -408.91968) (xy 342.934068 -408.945335) (xy 342.972157 -409.000971)
			(xy 343.003308 -409.060769) (xy 343.027071 -409.123867) (xy 343.043106 -409.189357) (xy 343.051181 -409.256297)
			(xy 343.05118 -409.323721) (xy 343.043103 -409.390661) (xy 343.027066 -409.45615) (xy 343.0033 -409.519248)
			(xy 343.000914 -409.523827) (xy 344.129052 -409.523827) (xy 344.129055 -409.456519) (xy 344.137102 -409.389694)
			(xy 344.153079 -409.32431) (xy 344.176756 -409.261304) (xy 344.207793 -409.201579) (xy 344.245746 -409.145992)
			(xy 344.267536 -409.12034) (xy 344.273345 -409.113204) (xy 344.279851 -409.096006) (xy 344.280236 -409.086812)
			(xy 344.280236 -408.593544) (xy 344.279796 -408.58436) (xy 344.273302 -408.567176) (xy 344.267536 -408.560016)
			(xy 344.24574 -408.53437) (xy 344.207792 -408.478783) (xy 344.176759 -408.419058) (xy 344.153087 -408.356053)
			(xy 344.137115 -408.29067) (xy 344.129071 -408.223847) (xy 344.129072 -408.156541) (xy 344.137117 -408.089718)
			(xy 344.153091 -408.024335) (xy 344.176764 -407.961331) (xy 344.207798 -407.901607) (xy 344.245748 -407.84602)
			(xy 344.267536 -407.820368) (xy 344.273333 -407.813223) (xy 344.279847 -407.796032) (xy 344.280236 -407.78684)
			(xy 344.280236 -407.628852) (xy 344.280583 -407.61869) (xy 344.288401 -407.59993) (xy 344.302821 -407.585607)
			(xy 344.321634 -407.577916) (xy 344.331798 -407.577544) (xy 345.048078 -407.577544) (xy 345.058204 -407.578045)
			(xy 345.076925 -407.585766) (xy 345.091283 -407.600048) (xy 345.099102 -407.618729) (xy 345.09964 -407.628852)
			(xy 345.09964 -407.78684) (xy 345.100044 -407.796028) (xy 345.106563 -407.813211) (xy 345.11234 -407.820368)
			(xy 345.13412 -407.846026) (xy 345.172071 -407.901611) (xy 345.203106 -407.961334) (xy 345.22678 -408.024338)
			(xy 345.242754 -408.089719) (xy 345.250799 -408.156542) (xy 345.2508 -408.223846) (xy 345.242756 -408.290669)
			(xy 345.226783 -408.356051) (xy 345.20311 -408.419055) (xy 345.172077 -408.478778) (xy 345.134128 -408.534364)
			(xy 345.11234 -408.560016) (xy 345.106547 -408.567163) (xy 345.100032 -408.584352) (xy 345.09964 -408.593544)
			(xy 345.09964 -409.086812) (xy 345.100058 -409.095998) (xy 345.106568 -409.113182) (xy 345.11234 -409.12034)
			(xy 345.134093 -409.146021) (xy 345.172044 -409.201603) (xy 345.20308 -409.261322) (xy 345.226756 -409.324323)
			(xy 345.242732 -409.389702) (xy 345.250779 -409.456522) (xy 345.250783 -409.523824) (xy 345.242742 -409.590645)
			(xy 345.226772 -409.656025) (xy 345.203102 -409.719028) (xy 345.172072 -409.778751) (xy 345.134126 -409.834336)
			(xy 345.11234 -409.859988) (xy 345.106516 -409.867114) (xy 345.100019 -409.884319) (xy 345.09964 -409.893516)
			(xy 345.09964 -410.051504) (xy 345.099182 -410.061653) (xy 345.091393 -410.080398) (xy 345.077008 -410.09472)
			(xy 345.058229 -410.102427) (xy 345.048078 -410.102812) (xy 344.331798 -410.102812) (xy 344.321678 -410.102277)
			(xy 344.302966 -410.094558) (xy 344.288612 -410.080287) (xy 344.280784 -410.061621) (xy 344.280236 -410.051504)
			(xy 344.280236 -409.893516) (xy 344.27981 -409.884331) (xy 344.273307 -409.867146) (xy 344.267536 -409.859988)
			(xy 344.245713 -409.834365) (xy 344.207765 -409.778774) (xy 344.176734 -409.719047) (xy 344.153063 -409.656038)
			(xy 344.137093 -409.590653) (xy 344.129052 -409.523827) (xy 343.000914 -409.523827) (xy 342.972148 -409.579044)
			(xy 342.934057 -409.634679) (xy 342.912192 -409.660344) (xy 342.906393 -409.667488) (xy 342.89988 -409.684679)
			(xy 342.899492 -409.693872) (xy 342.899492 -410.186124) (xy 342.899892 -410.195312) (xy 342.906413 -410.212496)
			(xy 342.912192 -410.219652) (xy 342.934041 -410.24533) (xy 342.97213 -410.300963) (xy 343.003282 -410.360757)
			(xy 343.027048 -410.423852) (xy 343.043084 -410.48934) (xy 343.051162 -410.556277) (xy 343.051163 -410.623642)
			(xy 346.329202 -410.623642) (xy 346.329204 -410.556334) (xy 346.33725 -410.48951) (xy 346.353226 -410.424126)
			(xy 346.376903 -410.361121) (xy 346.40794 -410.301397) (xy 346.445894 -410.245812) (xy 346.467684 -410.22016)
			(xy 346.473478 -410.213013) (xy 346.479995 -410.195824) (xy 346.480384 -410.186632) (xy 346.480384 -409.693364)
			(xy 346.479995 -409.684175) (xy 346.473467 -409.66699) (xy 346.467684 -409.659836) (xy 346.445907 -409.634175)
			(xy 346.407955 -409.578591) (xy 346.376918 -409.518869) (xy 346.353243 -409.455865) (xy 346.337268 -409.390484)
			(xy 346.329222 -409.323661) (xy 346.329221 -409.256357) (xy 346.337265 -409.189534) (xy 346.353238 -409.124152)
			(xy 346.376911 -409.061148) (xy 346.407945 -409.001425) (xy 346.445896 -408.94584) (xy 346.467684 -408.920188)
			(xy 346.473466 -408.913033) (xy 346.47999 -408.89585) (xy 346.480384 -408.88666) (xy 346.480384 -408.728672)
			(xy 346.480798 -408.718518) (xy 346.4886 -408.699768) (xy 346.502999 -408.685446) (xy 346.52179 -408.677745)
			(xy 346.531946 -408.677364) (xy 347.248226 -408.677364) (xy 347.258357 -408.677806) (xy 347.277084 -408.685547)
			(xy 347.29144 -408.699847) (xy 347.299254 -408.718543) (xy 347.299788 -408.728672) (xy 347.299788 -408.88666)
			(xy 347.30022 -408.895845) (xy 347.306719 -408.913029) (xy 347.312488 -408.920188) (xy 347.334287 -408.945831)
			(xy 347.372233 -409.001419) (xy 347.403265 -409.061144) (xy 347.426936 -409.12415) (xy 347.442907 -409.189533)
			(xy 347.45095 -409.256356) (xy 347.450949 -409.323662) (xy 347.442904 -409.390485) (xy 347.42693 -409.455867)
			(xy 347.403257 -409.518872) (xy 347.400682 -409.523827) (xy 374.929082 -409.523827) (xy 374.929085 -409.456519)
			(xy 374.937133 -409.389693) (xy 374.953111 -409.324308) (xy 374.97679 -409.261302) (xy 375.007829 -409.201578)
			(xy 375.045785 -409.145991) (xy 375.067576 -409.12034) (xy 375.073378 -409.113198) (xy 375.07989 -409.096005)
			(xy 375.080276 -409.086812) (xy 375.080276 -408.593544) (xy 375.07985 -408.584358) (xy 375.073348 -408.567174)
			(xy 375.067576 -408.560016) (xy 375.045779 -408.534371) (xy 375.007828 -408.478784) (xy 374.976793 -408.41906)
			(xy 374.953119 -408.356055) (xy 374.937146 -408.290671) (xy 374.929102 -408.223847) (xy 374.929103 -408.156541)
			(xy 374.937148 -408.089717) (xy 374.953123 -408.024334) (xy 374.976798 -407.961329) (xy 375.007835 -407.901605)
			(xy 375.045787 -407.84602) (xy 375.067576 -407.820368) (xy 375.073366 -407.813218) (xy 375.079885 -407.796031)
			(xy 375.080276 -407.78684) (xy 375.080276 -407.628852) (xy 375.080682 -407.618698) (xy 375.088489 -407.599949)
			(xy 375.10289 -407.585628) (xy 375.121682 -407.577926) (xy 375.131838 -407.577544) (xy 375.848118 -407.577544)
			(xy 375.858246 -407.578012) (xy 375.876969 -407.585746) (xy 375.891325 -407.600038) (xy 375.899143 -407.618726)
			(xy 375.89968 -407.628852) (xy 375.89968 -407.78684) (xy 375.900075 -407.796029) (xy 375.9066 -407.813213)
			(xy 375.91238 -407.820368) (xy 375.934159 -407.846027) (xy 375.972107 -407.901613) (xy 376.00314 -407.961336)
			(xy 376.026812 -408.024339) (xy 376.042785 -408.08972) (xy 376.05083 -408.156542) (xy 376.05083 -408.223846)
			(xy 376.042787 -408.290668) (xy 376.026816 -408.356049) (xy 376.003145 -408.419053) (xy 375.972113 -408.478777)
			(xy 375.934167 -408.534364) (xy 375.91238 -408.560016) (xy 375.906592 -408.567167) (xy 375.900073 -408.584353)
			(xy 375.89968 -408.593544) (xy 375.89968 -409.086812) (xy 375.900089 -409.095999) (xy 375.906604 -409.113183)
			(xy 375.91238 -409.12034) (xy 375.934131 -409.146022) (xy 375.97208 -409.201604) (xy 376.003114 -409.261324)
			(xy 376.026788 -409.324325) (xy 376.042763 -409.389703) (xy 376.050809 -409.456522) (xy 376.050813 -409.523824)
			(xy 376.042772 -409.590644) (xy 376.026804 -409.656024) (xy 376.003136 -409.719026) (xy 375.972108 -409.778749)
			(xy 375.934165 -409.834335) (xy 375.91238 -409.859988) (xy 375.906561 -409.867117) (xy 375.90006 -409.88432)
			(xy 375.89968 -409.893516) (xy 375.89968 -410.051504) (xy 375.899281 -410.061661) (xy 375.891481 -410.080417)
			(xy 375.877077 -410.094741) (xy 375.858277 -410.102437) (xy 375.848118 -410.102812) (xy 375.131838 -410.102812)
			(xy 375.12172 -410.102244) (xy 375.10301 -410.094538) (xy 375.088654 -410.080277) (xy 375.080824 -410.061618)
			(xy 375.080276 -410.051504) (xy 375.080276 -409.893516) (xy 375.079864 -409.884329) (xy 375.073352 -409.867144)
			(xy 375.067576 -409.859988) (xy 375.045751 -409.834366) (xy 375.007801 -409.778776) (xy 374.976768 -409.719048)
			(xy 374.953095 -409.65604) (xy 374.937124 -409.590654) (xy 374.929082 -409.523827) (xy 347.400682 -409.523827)
			(xy 347.372224 -409.578596) (xy 347.334276 -409.634184) (xy 347.312488 -409.659836) (xy 347.306692 -409.666982)
			(xy 347.300177 -409.684172) (xy 347.299788 -409.693364) (xy 347.299788 -410.186632) (xy 347.300185 -410.195821)
			(xy 347.306708 -410.213005) (xy 347.312488 -410.22016) (xy 347.334259 -410.245825) (xy 347.372207 -410.301411)
			(xy 347.403239 -410.361133) (xy 347.426912 -410.424135) (xy 347.442885 -410.489516) (xy 347.45093 -410.556336)
			(xy 347.450931 -410.62364) (xy 347.450924 -410.623701) (xy 377.128728 -410.623701) (xy 377.128729 -410.556275)
			(xy 377.136807 -410.489335) (xy 377.152845 -410.423845) (xy 377.176612 -410.360748) (xy 377.207766 -410.300951)
			(xy 377.245858 -410.245317) (xy 377.267724 -410.219652) (xy 377.273526 -410.212511) (xy 377.280037 -410.195317)
			(xy 377.280424 -410.186124) (xy 377.280424 -409.693872) (xy 377.280022 -409.684684) (xy 377.273502 -409.6675)
			(xy 377.267724 -409.660344) (xy 377.245871 -409.634669) (xy 377.20778 -409.579037) (xy 377.176628 -409.519242)
			(xy 377.152862 -409.456146) (xy 377.136825 -409.390658) (xy 377.128748 -409.323721) (xy 377.128747 -409.256297)
			(xy 377.136822 -409.18936) (xy 377.152857 -409.123871) (xy 377.17662 -409.060774) (xy 377.207771 -409.000979)
			(xy 377.24586 -408.945345) (xy 377.267724 -408.91968) (xy 377.273514 -408.912531) (xy 377.280032 -408.895343)
			(xy 377.280424 -408.886152) (xy 377.280424 -408.728672) (xy 377.280794 -408.718545) (xy 377.288555 -408.699836)
			(xy 377.302886 -408.685522) (xy 377.321604 -408.677782) (xy 377.331732 -408.677364) (xy 378.048012 -408.677364)
			(xy 378.058117 -408.677875) (xy 378.076789 -408.685609) (xy 378.091082 -408.699898) (xy 378.098822 -408.718567)
			(xy 378.09932 -408.728672) (xy 378.09932 -408.886152) (xy 378.099749 -408.895337) (xy 378.106249 -408.912522)
			(xy 378.11202 -408.91968) (xy 378.133895 -408.945336) (xy 378.171982 -409.000972) (xy 378.203131 -409.06077)
			(xy 378.226894 -409.123868) (xy 378.242928 -409.189358) (xy 378.251002 -409.256297) (xy 378.251001 -409.323721)
			(xy 378.242925 -409.39066) (xy 378.226888 -409.456149) (xy 378.203124 -409.519247) (xy 378.200707 -409.523886)
			(xy 379.328875 -409.523886) (xy 379.328878 -409.45646) (xy 379.336957 -409.38952) (xy 379.352995 -409.324029)
			(xy 379.376762 -409.260931) (xy 379.407916 -409.201133) (xy 379.446007 -409.145498) (xy 379.467872 -409.119832)
			(xy 379.473689 -409.112701) (xy 379.480189 -409.095499) (xy 379.480572 -409.086304) (xy 379.480572 -408.594052)
			(xy 379.480143 -408.584867) (xy 379.473643 -408.567682) (xy 379.467872 -408.560524) (xy 379.446001 -408.534865)
			(xy 379.407915 -408.479229) (xy 379.376766 -408.419431) (xy 379.353003 -408.356334) (xy 379.336969 -408.290844)
			(xy 379.328894 -408.223906) (xy 379.328895 -408.156482) (xy 379.336971 -408.089544) (xy 379.353007 -408.024055)
			(xy 379.376771 -407.960958) (xy 379.407921 -407.901161) (xy 379.446009 -407.845526) (xy 379.467872 -407.81986)
			(xy 379.473677 -407.812721) (xy 379.480185 -407.795525) (xy 379.480572 -407.786332) (xy 379.480572 -407.628852)
			(xy 379.481045 -407.618744) (xy 379.488793 -407.60007) (xy 379.503093 -407.585778) (xy 379.521771 -407.57804)
			(xy 379.53188 -407.577544) (xy 380.24816 -407.577544) (xy 380.258259 -407.578117) (xy 380.276926 -407.585831)
			(xy 380.29122 -407.6001) (xy 380.298966 -407.618754) (xy 380.299468 -407.628852) (xy 380.299468 -407.786332)
			(xy 380.29987 -407.79552) (xy 380.30639 -407.812704) (xy 380.312168 -407.81986) (xy 380.334025 -407.845531)
			(xy 380.372116 -407.901164) (xy 380.403269 -407.960959) (xy 380.427035 -408.024055) (xy 380.443072 -408.089544)
			(xy 380.451149 -408.156482) (xy 380.45115 -408.223906) (xy 380.443074 -408.290844) (xy 380.427039 -408.356333)
			(xy 380.403274 -408.41943) (xy 380.372122 -408.479226) (xy 380.334033 -408.534859) (xy 380.312168 -408.560524)
			(xy 380.306375 -408.567671) (xy 380.299859 -408.58486) (xy 380.299468 -408.594052) (xy 380.299468 -409.086304)
			(xy 380.299883 -409.09549) (xy 380.306394 -409.112675) (xy 380.312168 -409.119832) (xy 380.333998 -409.145526)
			(xy 380.37209 -409.201156) (xy 380.403244 -409.260947) (xy 380.427011 -409.324041) (xy 380.44305 -409.389527)
			(xy 380.451129 -409.456462) (xy 380.451133 -409.523884) (xy 380.44306 -409.59082) (xy 380.427027 -409.656308)
			(xy 380.403266 -409.719403) (xy 380.372117 -409.779198) (xy 380.334031 -409.834831) (xy 380.312168 -409.860496)
			(xy 380.306386 -409.867652) (xy 380.299864 -409.884834) (xy 380.299468 -409.894024) (xy 380.299468 -410.051504)
			(xy 380.299086 -410.061631) (xy 380.291331 -410.08034) (xy 380.277003 -410.094656) (xy 380.258287 -410.102395)
			(xy 380.24816 -410.102812) (xy 379.53188 -410.102812) (xy 379.521771 -410.102332) (xy 379.503095 -410.09459)
			(xy 379.488801 -410.080292) (xy 379.481065 -410.061613) (xy 379.480572 -410.051504) (xy 379.480572 -409.894024)
			(xy 379.480157 -409.884837) (xy 379.473647 -409.867652) (xy 379.467872 -409.860496) (xy 379.445974 -409.834859)
			(xy 379.407888 -409.77922) (xy 379.37674 -409.71942) (xy 379.352979 -409.656319) (xy 379.336947 -409.590827)
			(xy 379.328875 -409.523886) (xy 378.200707 -409.523886) (xy 378.171973 -409.579043) (xy 378.133884 -409.634678)
			(xy 378.11202 -409.660344) (xy 378.106225 -409.66749) (xy 378.099709 -409.68468) (xy 378.09932 -409.693872)
			(xy 378.09932 -410.186124) (xy 378.099714 -410.195313) (xy 378.106239 -410.212497) (xy 378.11202 -410.219652)
			(xy 378.133868 -410.245331) (xy 378.171955 -410.300964) (xy 378.203106 -410.360758) (xy 378.22687 -410.423853)
			(xy 378.242906 -410.48934) (xy 378.250983 -410.556277) (xy 378.250984 -410.623641) (xy 381.529047 -410.623641)
			(xy 381.529049 -410.556335) (xy 381.537094 -410.489512) (xy 381.553068 -410.424129) (xy 381.576742 -410.361124)
			(xy 381.607775 -410.3014) (xy 381.645724 -410.245812) (xy 381.667512 -410.22016) (xy 381.673309 -410.213015)
			(xy 381.679823 -410.195824) (xy 381.680212 -410.186632) (xy 381.680212 -409.693364) (xy 381.679817 -409.684175)
			(xy 381.673292 -409.666991) (xy 381.667512 -409.659836) (xy 381.645737 -409.634174) (xy 381.607789 -409.578588)
			(xy 381.576757 -409.518866) (xy 381.553085 -409.455863) (xy 381.537112 -409.390482) (xy 381.529067 -409.323661)
			(xy 381.529066 -409.256357) (xy 381.537109 -409.189536) (xy 381.553079 -409.124155) (xy 381.57675 -409.061151)
			(xy 381.60778 -409.001427) (xy 381.645726 -408.94584) (xy 381.667512 -408.920188) (xy 381.673298 -408.913035)
			(xy 381.679818 -408.89585) (xy 381.680212 -408.88666) (xy 381.680212 -408.728672) (xy 381.680662 -408.71856)
			(xy 381.688411 -408.699879) (xy 381.702719 -408.685585) (xy 381.721408 -408.677853) (xy 381.73152 -408.677364)
			(xy 382.448054 -408.677364) (xy 382.458181 -408.677865) (xy 382.476905 -408.685582) (xy 382.491264 -408.699865)
			(xy 382.499081 -408.718548) (xy 382.499616 -408.728672) (xy 382.499616 -408.88666) (xy 382.500042 -408.895846)
			(xy 382.506544 -408.91303) (xy 382.512316 -408.920188) (xy 382.534117 -408.94583) (xy 382.572068 -409.001417)
			(xy 382.603103 -409.061141) (xy 382.626778 -409.124147) (xy 382.642751 -409.189531) (xy 382.650795 -409.256356)
			(xy 382.650794 -409.323662) (xy 382.642748 -409.390487) (xy 382.626772 -409.45587) (xy 382.603096 -409.518875)
			(xy 382.600523 -409.523827) (xy 383.72917 -409.523827) (xy 383.729173 -409.456519) (xy 383.737221 -409.389693)
			(xy 383.753198 -409.324309) (xy 383.776876 -409.261303) (xy 383.807915 -409.201578) (xy 383.845869 -409.145992)
			(xy 383.86766 -409.12034) (xy 383.873472 -409.113206) (xy 383.879976 -409.096007) (xy 383.88036 -409.086812)
			(xy 383.88036 -408.593544) (xy 383.879915 -408.584361) (xy 383.873424 -408.567177) (xy 383.86766 -408.560016)
			(xy 383.845864 -408.53437) (xy 383.807914 -408.478784) (xy 383.77688 -408.419059) (xy 383.753207 -408.356054)
			(xy 383.737234 -408.290671) (xy 383.72919 -408.223847) (xy 383.729191 -408.156541) (xy 383.737236 -408.089717)
			(xy 383.75321 -408.024335) (xy 383.776885 -407.96133) (xy 383.80792 -407.901606) (xy 383.845871 -407.84602)
			(xy 383.86766 -407.820368) (xy 383.87346 -407.813226) (xy 383.879971 -407.796033) (xy 383.88036 -407.78684)
			(xy 383.88036 -407.628852) (xy 383.880845 -407.618745) (xy 383.888591 -407.600074) (xy 383.902887 -407.585782)
			(xy 383.921561 -407.578042) (xy 383.931668 -407.577544) (xy 384.648202 -407.577544) (xy 384.658329 -407.578025)
			(xy 384.677051 -407.585754) (xy 384.691408 -407.600042) (xy 384.699226 -407.618727) (xy 384.699764 -407.628852)
			(xy 384.699764 -407.78684) (xy 384.700163 -407.796028) (xy 384.706685 -407.813212) (xy 384.712464 -407.820368)
			(xy 384.734244 -407.846027) (xy 384.772193 -407.901612) (xy 384.803226 -407.961335) (xy 384.826899 -408.024339)
			(xy 384.842873 -408.08972) (xy 384.850918 -408.156542) (xy 384.850918 -408.223846) (xy 384.842875 -408.290668)
			(xy 384.826903 -408.35605) (xy 384.803231 -408.419054) (xy 384.772199 -408.478778) (xy 384.734251 -408.534364)
			(xy 384.712464 -408.560016) (xy 384.706674 -408.567165) (xy 384.700156 -408.584353) (xy 384.699764 -408.593544)
			(xy 384.699764 -409.086812) (xy 384.700176 -409.095999) (xy 384.706689 -409.113183) (xy 384.712464 -409.12034)
			(xy 384.734216 -409.146021) (xy 384.772166 -409.201604) (xy 384.8032 -409.261323) (xy 384.826875 -409.324324)
			(xy 384.84285 -409.389703) (xy 384.850897 -409.456522) (xy 384.850901 -409.523824) (xy 384.84286 -409.590644)
			(xy 384.826891 -409.656024) (xy 384.803222 -409.719027) (xy 384.772194 -409.77875) (xy 384.734249 -409.834336)
			(xy 384.712464 -409.859988) (xy 384.706643 -409.867116) (xy 384.700144 -409.88432) (xy 384.699764 -409.893516)
			(xy 384.699764 -410.051504) (xy 384.699386 -410.061631) (xy 384.69163 -410.080342) (xy 384.677301 -410.094657)
			(xy 384.658584 -410.102396) (xy 384.648456 -410.102812) (xy 383.931922 -410.102812) (xy 383.921803 -410.102257)
			(xy 383.903092 -410.094546) (xy 383.888737 -410.080281) (xy 383.880908 -410.06162) (xy 383.88036 -410.051504)
			(xy 383.88036 -409.893516) (xy 383.879929 -409.884331) (xy 383.873428 -409.867147) (xy 383.86766 -409.859988)
			(xy 383.845836 -409.834365) (xy 383.807887 -409.778775) (xy 383.776854 -409.719048) (xy 383.753182 -409.656039)
			(xy 383.737211 -409.590653) (xy 383.72917 -409.523827) (xy 382.600523 -409.523827) (xy 382.572059 -409.578599)
			(xy 382.534106 -409.634184) (xy 382.512316 -409.659836) (xy 382.506523 -409.666984) (xy 382.500006 -409.684172)
			(xy 382.499616 -409.693364) (xy 382.499616 -410.186632) (xy 382.500007 -410.195821) (xy 382.506534 -410.213006)
			(xy 382.512316 -410.22016) (xy 382.534089 -410.245824) (xy 382.572042 -410.301408) (xy 382.603078 -410.36113)
			(xy 382.626754 -410.424133) (xy 382.642729 -410.489514) (xy 382.650775 -410.556336) (xy 382.650777 -410.62364)
			(xy 382.65077 -410.623701) (xy 385.928816 -410.623701) (xy 385.928817 -410.556275) (xy 385.936895 -410.489336)
			(xy 385.952932 -410.423846) (xy 385.976699 -410.360748) (xy 386.007852 -410.300952) (xy 386.045943 -410.245317)
			(xy 386.067808 -410.219652) (xy 386.073608 -410.21251) (xy 386.080121 -410.195317) (xy 386.080508 -410.186124)
			(xy 386.080508 -409.693872) (xy 386.08011 -409.684684) (xy 386.073588 -409.667499) (xy 386.067808 -409.660344)
			(xy 386.045956 -409.634669) (xy 386.007866 -409.579036) (xy 385.976714 -409.519241) (xy 385.952949 -409.456146)
			(xy 385.936913 -409.390658) (xy 385.928836 -409.32372) (xy 385.928834 -409.256298) (xy 385.936909 -409.18936)
			(xy 385.952944 -409.123871) (xy 385.976707 -409.060775) (xy 386.007857 -409.000979) (xy 386.045944 -408.945345)
			(xy 386.067808 -408.91968) (xy 386.073596 -408.912529) (xy 386.080116 -408.895343) (xy 386.080508 -408.886152)
			(xy 386.080508 -408.728672) (xy 386.080962 -408.71856) (xy 386.088711 -408.69988) (xy 386.103017 -408.685586)
			(xy 386.121704 -408.677854) (xy 386.131816 -408.677364) (xy 386.848096 -408.677364) (xy 386.8582 -408.677888)
			(xy 386.876871 -408.685617) (xy 386.891165 -408.699902) (xy 386.898906 -408.718568) (xy 386.899404 -408.728672)
			(xy 386.899404 -408.886152) (xy 386.899836 -408.895337) (xy 386.906334 -408.912522) (xy 386.912104 -408.91968)
			(xy 386.93398 -408.945336) (xy 386.972068 -409.000972) (xy 387.003218 -409.060769) (xy 387.026981 -409.123867)
			(xy 387.043016 -409.189357) (xy 387.05109 -409.256297) (xy 387.051089 -409.323721) (xy 387.043012 -409.39066)
			(xy 387.026976 -409.45615) (xy 387.00321 -409.519247) (xy 387.000824 -409.523827) (xy 388.128961 -409.523827)
			(xy 388.128964 -409.456519) (xy 388.137012 -409.389694) (xy 388.152989 -409.324309) (xy 388.176666 -409.261303)
			(xy 388.207704 -409.201579) (xy 388.245658 -409.145992) (xy 388.267448 -409.12034) (xy 388.273259 -409.113205)
			(xy 388.279764 -409.096006) (xy 388.280148 -409.086812) (xy 388.280148 -408.593544) (xy 388.279706 -408.58436)
			(xy 388.273213 -408.567176) (xy 388.267448 -408.560016) (xy 388.245652 -408.534371) (xy 388.207703 -408.478783)
			(xy 388.176669 -408.419059) (xy 388.152997 -408.356054) (xy 388.137024 -408.29067) (xy 388.12898 -408.223847)
			(xy 388.128981 -408.156541) (xy 388.137026 -408.089718) (xy 388.153 -408.024335) (xy 388.176674 -407.96133)
			(xy 388.207709 -407.901606) (xy 388.245659 -407.84602) (xy 388.267448 -407.820368) (xy 388.273247 -407.813224)
			(xy 388.279759 -407.796032) (xy 388.280148 -407.78684) (xy 388.280148 -407.628852) (xy 388.280645 -407.618747)
			(xy 388.288388 -407.600077) (xy 388.302681 -407.585786) (xy 388.321351 -407.578044) (xy 388.331456 -407.577544)
			(xy 389.04799 -407.577544) (xy 389.058117 -407.578035) (xy 389.076838 -407.58576) (xy 389.091195 -407.600045)
			(xy 389.099014 -407.618728) (xy 389.099552 -407.628852) (xy 389.099552 -407.78684) (xy 389.099954 -407.796028)
			(xy 389.106475 -407.813211) (xy 389.112252 -407.820368) (xy 389.134032 -407.846027) (xy 389.171982 -407.901612)
			(xy 389.203016 -407.961335) (xy 389.226689 -408.024338) (xy 389.242663 -408.08972) (xy 389.250708 -408.156542)
			(xy 389.250709 -408.223846) (xy 389.242665 -408.290668) (xy 389.226693 -408.35605) (xy 389.203021 -408.419054)
			(xy 389.171988 -408.478778) (xy 389.134039 -408.534364) (xy 389.112252 -408.560016) (xy 389.10646 -408.567164)
			(xy 389.099944 -408.584353) (xy 389.099552 -408.593544) (xy 389.099552 -409.086812) (xy 389.099967 -409.095998)
			(xy 389.106479 -409.113182) (xy 389.112252 -409.12034) (xy 389.134004 -409.146021) (xy 389.171955 -409.201603)
			(xy 389.20299 -409.261323) (xy 389.226665 -409.324323) (xy 389.242641 -409.389702) (xy 389.250688 -409.456522)
			(xy 389.250692 -409.523824) (xy 389.242651 -409.590644) (xy 389.226681 -409.656025) (xy 389.203012 -409.719028)
			(xy 389.171983 -409.77875) (xy 389.134038 -409.834336) (xy 389.112252 -409.859988) (xy 389.10643 -409.867115)
			(xy 389.099932 -409.88432) (xy 389.099552 -409.893516) (xy 389.099552 -410.051504) (xy 389.099019 -410.061607)
			(xy 389.09129 -410.080275) (xy 389.077008 -410.094568) (xy 389.058346 -410.102311) (xy 389.048244 -410.102812)
			(xy 388.33171 -410.102812) (xy 388.32159 -410.102267) (xy 388.302879 -410.094552) (xy 388.288524 -410.080284)
			(xy 388.280696 -410.061621) (xy 388.280148 -410.051504) (xy 388.280148 -409.893516) (xy 388.27972 -409.884331)
			(xy 388.273217 -409.867147) (xy 388.267448 -409.859988) (xy 388.245624 -409.834365) (xy 388.207676 -409.778775)
			(xy 388.176644 -409.719047) (xy 388.152973 -409.656039) (xy 388.137002 -409.590653) (xy 388.128961 -409.523827)
			(xy 387.000824 -409.523827) (xy 386.972058 -409.579044) (xy 386.933969 -409.634679) (xy 386.912104 -409.660344)
			(xy 386.906307 -409.667489) (xy 386.899792 -409.68468) (xy 386.899404 -409.693872) (xy 386.899404 -410.186124)
			(xy 386.899801 -410.195313) (xy 386.906324 -410.212497) (xy 386.912104 -410.219652) (xy 386.933952 -410.24533)
			(xy 386.972041 -410.300963) (xy 387.003192 -410.360757) (xy 387.026957 -410.423853) (xy 387.042994 -410.48934)
			(xy 387.051071 -410.556277) (xy 387.051072 -410.623641) (xy 390.329135 -410.623641) (xy 390.329137 -410.556335)
			(xy 390.337182 -410.489512) (xy 390.353155 -410.42413) (xy 390.376828 -410.361125) (xy 390.407861 -410.3014)
			(xy 390.445809 -410.245813) (xy 390.467596 -410.22016) (xy 390.473392 -410.213014) (xy 390.479907 -410.195824)
			(xy 390.480296 -410.186632) (xy 390.480296 -409.693364) (xy 390.479904 -409.684175) (xy 390.473378 -409.666991)
			(xy 390.467596 -409.659836) (xy 390.445821 -409.634174) (xy 390.407875 -409.578588) (xy 390.376844 -409.518865)
			(xy 390.353172 -409.455862) (xy 390.3372 -409.390481) (xy 390.329155 -409.323661) (xy 390.329154 -409.256357)
			(xy 390.337196 -409.189536) (xy 390.353167 -409.124155) (xy 390.376836 -409.061151) (xy 390.407866 -409.001428)
			(xy 390.44581 -408.945841) (xy 390.467596 -408.920188) (xy 390.47338 -408.913034) (xy 390.479902 -408.89585)
			(xy 390.480296 -408.88666) (xy 390.480296 -408.728672) (xy 390.480762 -408.718562) (xy 390.488508 -408.699884)
			(xy 390.502811 -408.68559) (xy 390.521494 -408.677856) (xy 390.531604 -408.677364) (xy 391.248138 -408.677364)
			(xy 391.25827 -408.677796) (xy 391.276997 -408.685541) (xy 391.291352 -408.699844) (xy 391.299166 -408.718542)
			(xy 391.2997 -408.728672) (xy 391.2997 -408.88666) (xy 391.300129 -408.895845) (xy 391.30663 -408.91303)
			(xy 391.3124 -408.920188) (xy 391.334198 -408.945831) (xy 391.372144 -409.00142) (xy 391.403175 -409.061145)
			(xy 391.426845 -409.12415) (xy 391.442816 -409.189533) (xy 391.450859 -409.256356) (xy 391.450858 -409.323662)
			(xy 391.442813 -409.390484) (xy 391.42684 -409.455867) (xy 391.403167 -409.518872) (xy 391.372135 -409.578596)
			(xy 391.334187 -409.634183) (xy 391.3124 -409.659836) (xy 391.306606 -409.666983) (xy 391.30009 -409.684172)
			(xy 391.2997 -409.693364) (xy 391.2997 -410.186632) (xy 391.300095 -410.195821) (xy 391.306619 -410.213005)
			(xy 391.3124 -410.22016) (xy 391.334171 -410.245826) (xy 391.372118 -410.301411) (xy 391.403149 -410.361133)
			(xy 391.426821 -410.424136) (xy 391.442794 -410.489516) (xy 391.450839 -410.556336) (xy 391.450841 -410.623639)
			(xy 391.442799 -410.69046) (xy 391.426828 -410.755841) (xy 391.403159 -410.818845) (xy 391.37213 -410.878568)
			(xy 391.334186 -410.934155) (xy 391.3124 -410.959808) (xy 391.306618 -410.966963) (xy 391.300094 -410.984146)
			(xy 391.2997 -410.993336) (xy 391.2997 -411.151324) (xy 391.299235 -411.161434) (xy 391.291489 -411.180113)
			(xy 391.277186 -411.194407) (xy 391.258503 -411.202141) (xy 391.248392 -411.202632) (xy 390.531858 -411.202632)
			(xy 390.521725 -411.202207) (xy 390.502998 -411.19446) (xy 390.488642 -411.180155) (xy 390.480829 -411.161455)
			(xy 390.480296 -411.151324) (xy 390.480296 -410.993336) (xy 390.479869 -410.984151) (xy 390.473367 -410.966966)
			(xy 390.467596 -410.959808) (xy 390.445794 -410.934168) (xy 390.407848 -410.878579) (xy 390.376818 -410.818853)
			(xy 390.353148 -410.755847) (xy 390.337178 -410.690464) (xy 390.329135 -410.623641) (xy 387.051072 -410.623641)
			(xy 387.051072 -410.623699) (xy 387.042998 -410.690636) (xy 387.026964 -410.756124) (xy 387.003202 -410.819221)
			(xy 386.972053 -410.879016) (xy 386.933967 -410.934651) (xy 386.912104 -410.960316) (xy 386.906319 -410.967469)
			(xy 386.899797 -410.984654) (xy 386.899404 -410.993844) (xy 386.899404 -411.151324) (xy 386.898935 -411.161434)
			(xy 386.89119 -411.180112) (xy 386.876888 -411.194406) (xy 386.858206 -411.20214) (xy 386.848096 -411.202632)
			(xy 386.131816 -411.202632) (xy 386.121712 -411.202103) (xy 386.10304 -411.194376) (xy 386.088746 -411.180093)
			(xy 386.081005 -411.161427) (xy 386.080508 -411.151324) (xy 386.080508 -410.993844) (xy 386.080075 -410.984659)
			(xy 386.073577 -410.967475) (xy 386.067808 -410.960316) (xy 386.045928 -410.934664) (xy 386.007839 -410.879028)
			(xy 385.976689 -410.81923) (xy 385.952925 -410.756131) (xy 385.936891 -410.69064) (xy 385.928816 -410.623701)
			(xy 382.65077 -410.623701) (xy 382.642733 -410.690463) (xy 382.626761 -410.755844) (xy 382.603088 -410.818848)
			(xy 382.572054 -410.878571) (xy 382.534104 -410.934156) (xy 382.512316 -410.959808) (xy 382.506535 -410.966965)
			(xy 382.500011 -410.984146) (xy 382.499616 -410.993336) (xy 382.499616 -411.151324) (xy 382.499135 -411.161432)
			(xy 382.491392 -411.180108) (xy 382.477095 -411.194401) (xy 382.458416 -411.202138) (xy 382.448308 -411.202632)
			(xy 381.731774 -411.202632) (xy 381.721642 -411.202194) (xy 381.702915 -411.194453) (xy 381.688559 -411.180151)
			(xy 381.680745 -411.161454) (xy 381.680212 -411.151324) (xy 381.680212 -410.993336) (xy 381.679782 -410.984151)
			(xy 381.673282 -410.966967) (xy 381.667512 -410.959808) (xy 381.645709 -410.934168) (xy 381.607763 -410.87858)
			(xy 381.576732 -410.818854) (xy 381.553061 -410.755848) (xy 381.53709 -410.690464) (xy 381.529047 -410.623641)
			(xy 378.250984 -410.623641) (xy 378.250984 -410.623699) (xy 378.24291 -410.690636) (xy 378.226877 -410.756124)
			(xy 378.203116 -410.81922) (xy 378.171968 -410.879016) (xy 378.133882 -410.93465) (xy 378.11202 -410.960316)
			(xy 378.106236 -410.967471) (xy 378.099713 -410.984654) (xy 378.09932 -410.993844) (xy 378.09932 -411.151324)
			(xy 378.098835 -411.161432) (xy 378.091093 -411.180107) (xy 378.076797 -411.1944) (xy 378.05812 -411.202138)
			(xy 378.048012 -411.202632) (xy 377.331732 -411.202632) (xy 377.321615 -411.202159) (xy 377.302919 -411.194427)
			(xy 377.288604 -411.180128) (xy 377.280852 -411.16144) (xy 377.280424 -411.151324) (xy 377.280424 -410.993844)
			(xy 377.279987 -410.98466) (xy 377.273491 -410.967475) (xy 377.267724 -410.960316) (xy 377.245843 -410.934664)
			(xy 377.207754 -410.879028) (xy 377.176602 -410.81923) (xy 377.152838 -410.756132) (xy 377.136803 -410.690641)
			(xy 377.128728 -410.623701) (xy 347.450924 -410.623701) (xy 347.442889 -410.690461) (xy 347.426919 -410.755842)
			(xy 347.403249 -410.818845) (xy 347.372219 -410.878569) (xy 347.334274 -410.934156) (xy 347.312488 -410.959808)
			(xy 347.306704 -410.966962) (xy 347.300182 -410.984146) (xy 347.299788 -410.993336) (xy 347.299788 -411.151324)
			(xy 347.299398 -411.161481) (xy 347.291592 -411.180236) (xy 347.277186 -411.194559) (xy 347.258386 -411.202256)
			(xy 347.248226 -411.202632) (xy 346.531946 -411.202632) (xy 346.521819 -411.202135) (xy 346.503093 -411.194417)
			(xy 346.488735 -411.180133) (xy 346.480919 -411.161449) (xy 346.480384 -411.151324) (xy 346.480384 -410.993336)
			(xy 346.47996 -410.98415) (xy 346.473456 -410.966965) (xy 346.467684 -410.959808) (xy 346.445879 -410.934169)
			(xy 346.407928 -410.878582) (xy 346.376893 -410.818857) (xy 346.353219 -410.755851) (xy 346.337246 -410.690466)
			(xy 346.329202 -410.623642) (xy 343.051163 -410.623642) (xy 343.051163 -410.623699) (xy 343.043089 -410.690637)
			(xy 343.027055 -410.756125) (xy 343.003292 -410.819221) (xy 342.972143 -410.879017) (xy 342.934055 -410.934651)
			(xy 342.912192 -410.960316) (xy 342.906405 -410.967468) (xy 342.899885 -410.984653) (xy 342.899492 -410.993844)
			(xy 342.899492 -411.151324) (xy 342.899034 -411.161435) (xy 342.891287 -411.180116) (xy 342.876982 -411.19441)
			(xy 342.858296 -411.202142) (xy 342.848184 -411.202632) (xy 342.131904 -411.202632) (xy 342.121799 -411.202112)
			(xy 342.103128 -411.194382) (xy 342.088834 -411.180096) (xy 342.081093 -411.161428) (xy 342.080596 -411.151324)
			(xy 342.080596 -410.993844) (xy 342.080166 -410.984659) (xy 342.073666 -410.967474) (xy 342.067896 -410.960316)
			(xy 342.046016 -410.934664) (xy 342.007928 -410.879027) (xy 341.976779 -410.819229) (xy 341.953016 -410.756131)
			(xy 341.936981 -410.69064) (xy 341.928907 -410.6237) (xy 338.650837 -410.6237) (xy 338.642802 -410.69046)
			(xy 338.626832 -410.755841) (xy 338.603163 -410.818845) (xy 338.572134 -410.878568) (xy 338.534189 -410.934155)
			(xy 338.512404 -410.959808) (xy 338.506622 -410.966964) (xy 338.500098 -410.984146) (xy 338.499704 -410.993336)
			(xy 338.499704 -411.151324) (xy 338.499298 -411.161479) (xy 338.491495 -411.180231) (xy 338.477094 -411.194554)
			(xy 338.458299 -411.202253) (xy 338.448142 -411.202632) (xy 337.731862 -411.202632) (xy 337.721729 -411.202204)
			(xy 337.703002 -411.194458) (xy 337.688646 -411.180154) (xy 337.680833 -411.161455) (xy 337.6803 -411.151324)
			(xy 337.6803 -410.993336) (xy 337.679873 -410.984151) (xy 337.673371 -410.966966) (xy 337.6676 -410.959808)
			(xy 337.645798 -410.934168) (xy 337.607852 -410.878579) (xy 337.576822 -410.818853) (xy 337.553151 -410.755847)
			(xy 337.537181 -410.690464) (xy 337.529138 -410.623641) (xy 334.251075 -410.623641) (xy 334.251075 -410.623699)
			(xy 334.243001 -410.690636) (xy 334.226967 -410.756124) (xy 334.203205 -410.81922) (xy 334.172057 -410.879016)
			(xy 334.133971 -410.934651) (xy 334.112108 -410.960316) (xy 334.106323 -410.96747) (xy 334.099801 -410.984654)
			(xy 334.099408 -410.993844) (xy 334.099408 -411.151324) (xy 334.098935 -411.161433) (xy 334.091191 -411.180111)
			(xy 334.07689 -411.194404) (xy 334.05821 -411.20214) (xy 334.0481 -411.202632) (xy 333.33182 -411.202632)
			(xy 333.321716 -411.202099) (xy 333.303045 -411.194374) (xy 333.28875 -411.180092) (xy 333.281009 -411.161427)
			(xy 333.280512 -411.151324) (xy 333.280512 -410.993844) (xy 333.280078 -410.984659) (xy 333.273581 -410.967475)
			(xy 333.267812 -410.960316) (xy 333.245932 -410.934664) (xy 333.207843 -410.879028) (xy 333.176692 -410.81923)
			(xy 333.152928 -410.756131) (xy 333.136894 -410.69064) (xy 333.128819 -410.623701) (xy 326.525636 -410.623701)
			(xy 326.525636 -417.379404) (xy 326.525636 -417.533836) (xy 401.074128 -417.533836) (xy 401.074128 -417.366196)
			(xy 401.074128 -394.27912) (xy 414.451292 -394.27912) (xy 414.525968 -394.353542) (xy 414.525968 -397.823826)
			(xy 418.92899 -397.823826) (xy 418.928993 -397.756517) (xy 418.937042 -397.689691) (xy 418.95302 -397.624306)
			(xy 418.9767 -397.5613) (xy 419.00774 -397.501575) (xy 419.045697 -397.44599) (xy 419.067488 -397.420338)
			(xy 419.073292 -397.413198) (xy 419.079803 -397.396004) (xy 419.080188 -397.38681) (xy 419.080188 -396.893542)
			(xy 419.07976 -396.884357) (xy 419.073259 -396.867172) (xy 419.067488 -396.860014) (xy 419.045689 -396.834371)
			(xy 419.007737 -396.778784) (xy 418.976702 -396.71906) (xy 418.953027 -396.656054) (xy 418.937054 -396.59067)
			(xy 418.92901 -396.523846) (xy 418.92901 -396.456539) (xy 418.937056 -396.389715) (xy 418.953032 -396.324332)
			(xy 418.976708 -396.261327) (xy 419.007745 -396.201603) (xy 419.045698 -396.146018) (xy 419.067488 -396.120366)
			(xy 419.07328 -396.113218) (xy 419.079798 -396.09603) (xy 419.080188 -396.086838) (xy 419.080188 -395.92885)
			(xy 419.080606 -395.918675) (xy 419.088384 -395.899872) (xy 419.102772 -395.885484) (xy 419.121575 -395.877706)
			(xy 419.13175 -395.877288) (xy 419.84803 -395.877288) (xy 419.85821 -395.87764) (xy 419.877015 -395.885445)
			(xy 419.8914 -395.899852) (xy 419.899175 -395.91867) (xy 419.899592 -395.92885) (xy 419.899592 -396.086838)
			(xy 419.899986 -396.096027) (xy 419.906511 -396.113211) (xy 419.912292 -396.120366) (xy 419.934069 -396.146027)
			(xy 419.972016 -396.201613) (xy 420.003048 -396.261335) (xy 420.02672 -396.324339) (xy 420.042693 -396.389719)
			(xy 420.050737 -396.456541) (xy 420.050738 -396.523844) (xy 420.042695 -396.590666) (xy 420.026725 -396.656047)
			(xy 420.003054 -396.719051) (xy 419.972024 -396.778774) (xy 419.934078 -396.834361) (xy 419.912292 -396.860014)
			(xy 419.906506 -396.867167) (xy 419.899985 -396.884351) (xy 419.899592 -396.893542) (xy 419.899592 -397.38681)
			(xy 419.899999 -397.395998) (xy 419.906515 -397.413182) (xy 419.912292 -397.420338) (xy 419.934041 -397.446021)
			(xy 419.971989 -397.501604) (xy 420.00041 -397.556296) (xy 421.128654 -397.556296) (xy 421.13673 -397.489357)
			(xy 421.152765 -397.423869) (xy 421.17653 -397.360772) (xy 421.207681 -397.300976) (xy 421.245771 -397.245343)
			(xy 421.267636 -397.219678) (xy 421.273429 -397.21253) (xy 421.279945 -397.195342) (xy 421.280336 -397.18615)
			(xy 421.280336 -397.028924) (xy 421.280736 -397.018799) (xy 421.288483 -397.000089) (xy 421.302805 -396.985772)
			(xy 421.321518 -396.978032) (xy 421.331644 -396.977616) (xy 422.047924 -396.977616) (xy 422.058036 -396.978066)
			(xy 422.076718 -396.985814) (xy 422.091013 -397.000122) (xy 422.098744 -397.018811) (xy 422.099232 -397.028924)
			(xy 422.099232 -397.18615) (xy 422.099681 -397.195333) (xy 422.106169 -397.212517) (xy 422.111932 -397.219678)
			(xy 422.133805 -397.245336) (xy 422.171891 -397.300972) (xy 422.203039 -397.36077) (xy 422.226802 -397.423867)
			(xy 422.242835 -397.489357) (xy 422.25091 -397.556296) (xy 422.250909 -397.623719) (xy 422.242833 -397.690658)
			(xy 422.226797 -397.756147) (xy 422.203033 -397.819244) (xy 422.200615 -397.823885) (xy 423.328782 -397.823885)
			(xy 423.328786 -397.756458) (xy 423.336865 -397.689518) (xy 423.352904 -397.624027) (xy 423.376672 -397.560928)
			(xy 423.407826 -397.501131) (xy 423.445918 -397.445496) (xy 423.467784 -397.41983) (xy 423.473591 -397.412692)
			(xy 423.4801 -397.395496) (xy 423.480484 -397.386302) (xy 423.480484 -396.89405) (xy 423.480054 -396.884865)
			(xy 423.473554 -396.86768) (xy 423.467784 -396.860522) (xy 423.445911 -396.834865) (xy 423.407823 -396.779229)
			(xy 423.376674 -396.719431) (xy 423.352911 -396.656333) (xy 423.336877 -396.590843) (xy 423.328802 -396.523905)
			(xy 423.328803 -396.45648) (xy 423.33688 -396.389542) (xy 423.352916 -396.324052) (xy 423.37668 -396.260955)
			(xy 423.407831 -396.201159) (xy 423.44592 -396.145524) (xy 423.467784 -396.119858) (xy 423.473579 -396.112712)
			(xy 423.480095 -396.095522) (xy 423.480484 -396.08633) (xy 423.480484 -395.92885) (xy 423.480969 -395.918721)
			(xy 423.488688 -395.899993) (xy 423.502976 -395.885633) (xy 423.521666 -395.87782) (xy 423.531792 -395.877288)
			(xy 424.248072 -395.877288) (xy 424.258223 -395.877744) (xy 424.276972 -395.885528) (xy 424.291296 -395.899914)
			(xy 424.298999 -395.918697) (xy 424.29938 -395.92885) (xy 424.29938 -396.08633) (xy 424.29978 -396.095518)
			(xy 424.306301 -396.112702) (xy 424.31208 -396.119858) (xy 424.333935 -396.145531) (xy 424.372025 -396.201164)
			(xy 424.403177 -396.260959) (xy 424.426943 -396.324055) (xy 424.44298 -396.389543) (xy 424.451057 -396.456481)
			(xy 424.451058 -396.523904) (xy 424.442983 -396.590842) (xy 424.426948 -396.656331) (xy 424.403184 -396.719427)
			(xy 424.372033 -396.779223) (xy 424.333944 -396.834857) (xy 424.31208 -396.860522) (xy 424.306289 -396.867671)
			(xy 424.299772 -396.884859) (xy 424.29938 -396.89405) (xy 424.29938 -397.386302) (xy 424.299793 -397.395489)
			(xy 424.306305 -397.412673) (xy 424.31208 -397.41983) (xy 424.333907 -397.445526) (xy 424.371998 -397.501155)
			(xy 424.40076 -397.556356) (xy 425.528974 -397.556356) (xy 425.537017 -397.489534) (xy 425.552988 -397.424152)
			(xy 425.576659 -397.361148) (xy 425.607691 -397.301425) (xy 425.645637 -397.245838) (xy 425.667424 -397.220186)
			(xy 425.673212 -397.213035) (xy 425.679731 -397.195849) (xy 425.680124 -397.186658) (xy 425.680124 -397.028924)
			(xy 425.680542 -397.018768) (xy 425.688334 -397.000012) (xy 425.702732 -396.985687) (xy 425.721528 -396.97799)
			(xy 425.731686 -396.977616) (xy 426.447966 -396.977616) (xy 426.458088 -396.978154) (xy 426.476803 -396.985866)
			(xy 426.49116 -397.000137) (xy 426.498984 -397.018806) (xy 426.499528 -397.028924) (xy 426.499528 -397.186658)
			(xy 426.499952 -397.195844) (xy 426.506456 -397.213029) (xy 426.512228 -397.220186) (xy 426.534026 -397.24583)
			(xy 426.571977 -397.301417) (xy 426.603012 -397.361141) (xy 426.626685 -397.424147) (xy 426.642659 -397.48953)
			(xy 426.650703 -397.556354) (xy 426.650702 -397.623661) (xy 426.642656 -397.690485) (xy 426.626681 -397.755868)
			(xy 426.603006 -397.818873) (xy 426.600432 -397.823826) (xy 427.729077 -397.823826) (xy 427.729081 -397.756517)
			(xy 427.737129 -397.689691) (xy 427.753107 -397.624307) (xy 427.776786 -397.5613) (xy 427.807825 -397.501576)
			(xy 427.845781 -397.44599) (xy 427.867572 -397.420338) (xy 427.873386 -397.413206) (xy 427.879888 -397.396005)
			(xy 427.880272 -397.38681) (xy 427.880272 -396.893542) (xy 427.879848 -396.884356) (xy 427.873344 -396.867171)
			(xy 427.867572 -396.860014) (xy 427.845774 -396.83437) (xy 427.807823 -396.778783) (xy 427.776788 -396.719059)
			(xy 427.753115 -396.656053) (xy 427.737141 -396.59067) (xy 427.729097 -396.523846) (xy 427.729098 -396.456539)
			(xy 427.737144 -396.389715) (xy 427.753119 -396.324332) (xy 427.776794 -396.261327) (xy 427.807831 -396.201604)
			(xy 427.845783 -396.146018) (xy 427.867572 -396.120366) (xy 427.873374 -396.113225) (xy 427.879883 -396.096031)
			(xy 427.880272 -396.086838) (xy 427.880272 -395.92885) (xy 427.880706 -395.918677) (xy 427.88848 -395.899877)
			(xy 427.902864 -395.885489) (xy 427.921662 -395.877709) (xy 427.931834 -395.877288) (xy 428.648114 -395.877288)
			(xy 428.658293 -395.877654) (xy 428.677097 -395.885453) (xy 428.691483 -395.899857) (xy 428.699259 -395.918671)
			(xy 428.699676 -395.92885) (xy 428.699676 -396.086838) (xy 428.700073 -396.096026) (xy 428.706596 -396.11321)
			(xy 428.712376 -396.120366) (xy 428.734154 -396.146026) (xy 428.772102 -396.201612) (xy 428.803135 -396.261335)
			(xy 428.826807 -396.324338) (xy 428.84278 -396.389719) (xy 428.850825 -396.45654) (xy 428.850826 -396.523844)
			(xy 428.842783 -396.590666) (xy 428.826812 -396.656048) (xy 428.803141 -396.719052) (xy 428.772109 -396.778775)
			(xy 428.734163 -396.834362) (xy 428.712376 -396.860014) (xy 428.706588 -396.867165) (xy 428.700069 -396.884351)
			(xy 428.699676 -396.893542) (xy 428.699676 -397.38681) (xy 428.700087 -397.395997) (xy 428.7066 -397.413181)
			(xy 428.712376 -397.420338) (xy 428.734126 -397.446021) (xy 428.772075 -397.501604) (xy 428.800497 -397.556296)
			(xy 429.928742 -397.556296) (xy 429.936817 -397.489358) (xy 429.952852 -397.423869) (xy 429.976616 -397.360773)
			(xy 430.007767 -397.300977) (xy 430.045856 -397.245343) (xy 430.06772 -397.219678) (xy 430.073511 -397.212529)
			(xy 430.080028 -397.195341) (xy 430.08042 -397.18615) (xy 430.08042 -397.028924) (xy 430.080836 -397.018801)
			(xy 430.08858 -397.000094) (xy 430.102897 -396.985778) (xy 430.121605 -396.978035) (xy 430.131728 -396.977616)
			(xy 430.848008 -396.977616) (xy 430.858133 -396.97801) (xy 430.87684 -396.985764) (xy 430.891154 -397.000087)
			(xy 430.898896 -397.018799) (xy 430.899316 -397.028924) (xy 430.899316 -397.18615) (xy 430.899746 -397.195335)
			(xy 430.906246 -397.21252) (xy 430.912016 -397.219678) (xy 430.933889 -397.245335) (xy 430.971977 -397.300971)
			(xy 431.003126 -397.360769) (xy 431.026889 -397.423867) (xy 431.042923 -397.489357) (xy 431.050998 -397.556295)
			(xy 431.050997 -397.62372) (xy 431.04292 -397.690658) (xy 431.026884 -397.756148) (xy 431.00312 -397.819245)
			(xy 431.000734 -397.823826) (xy 432.128868 -397.823826) (xy 432.128872 -397.756517) (xy 432.13692 -397.689692)
			(xy 432.152898 -397.624307) (xy 432.176576 -397.561301) (xy 432.207614 -397.501576) (xy 432.245569 -397.44599)
			(xy 432.26736 -397.420338) (xy 432.273173 -397.413205) (xy 432.279676 -397.396005) (xy 432.28006 -397.38681)
			(xy 432.28006 -396.893542) (xy 432.279616 -396.884359) (xy 432.273125 -396.867175) (xy 432.26736 -396.860014)
			(xy 432.245562 -396.83437) (xy 432.207612 -396.778783) (xy 432.176578 -396.719058) (xy 432.152905 -396.656053)
			(xy 432.136932 -396.590669) (xy 432.128888 -396.523846) (xy 432.128889 -396.456539) (xy 432.136935 -396.389716)
			(xy 432.152909 -396.324333) (xy 432.176584 -396.261328) (xy 432.20762 -396.201604) (xy 432.245571 -396.146018)
			(xy 432.26736 -396.120366) (xy 432.273161 -396.113224) (xy 432.279671 -396.096031) (xy 432.28006 -396.086838)
			(xy 432.28006 -395.92885) (xy 432.280505 -395.918679) (xy 432.288278 -395.899881) (xy 432.302658 -395.885494)
			(xy 432.321451 -395.877711) (xy 432.331622 -395.877288) (xy 433.047902 -395.877288) (xy 433.05808 -395.877663)
			(xy 433.076884 -395.885458) (xy 433.091271 -395.899859) (xy 433.099047 -395.918672) (xy 433.099464 -395.92885)
			(xy 433.099464 -396.086838) (xy 433.099864 -396.096026) (xy 433.106386 -396.11321) (xy 433.112164 -396.120366)
			(xy 433.133942 -396.146026) (xy 433.171891 -396.201612) (xy 433.202924 -396.261334) (xy 433.226598 -396.324337)
			(xy 433.242571 -396.389719) (xy 433.250616 -396.45654) (xy 433.250617 -396.523845) (xy 433.242574 -396.590666)
			(xy 433.226602 -396.656048) (xy 433.202931 -396.719052) (xy 433.171899 -396.778776) (xy 433.133951 -396.834362)
			(xy 433.112164 -396.860014) (xy 433.106374 -396.867164) (xy 433.099856 -396.884351) (xy 433.099464 -396.893542)
			(xy 433.099464 -397.38681) (xy 433.099877 -397.395997) (xy 433.10639 -397.413181) (xy 433.112164 -397.420338)
			(xy 433.133914 -397.446021) (xy 433.171864 -397.501603) (xy 433.200318 -397.556356) (xy 434.329062 -397.556356)
			(xy 434.337105 -397.489534) (xy 434.353075 -397.424153) (xy 434.376746 -397.361149) (xy 434.407776 -397.301426)
			(xy 434.445722 -397.245839) (xy 434.467508 -397.220186) (xy 434.473294 -397.213033) (xy 434.479815 -397.195849)
			(xy 434.480208 -397.186658) (xy 434.480208 -397.028924) (xy 434.480641 -397.01877) (xy 434.48843 -397.000017)
			(xy 434.502824 -396.985692) (xy 434.521614 -396.977993) (xy 434.53177 -396.977616) (xy 435.24805 -396.977616)
			(xy 435.258171 -396.978167) (xy 435.276886 -396.985874) (xy 435.291243 -397.00014) (xy 435.299068 -397.018807)
			(xy 435.299612 -397.028924) (xy 435.299612 -397.186658) (xy 435.30004 -397.195843) (xy 435.306541 -397.213028)
			(xy 435.312312 -397.220186) (xy 435.334111 -397.245829) (xy 435.372063 -397.301416) (xy 435.403098 -397.36114)
			(xy 435.426773 -397.424146) (xy 435.442746 -397.48953) (xy 435.45079 -397.556354) (xy 435.45079 -397.623661)
			(xy 435.442744 -397.690485) (xy 435.426768 -397.755868) (xy 435.403092 -397.818873) (xy 435.372055 -397.878597)
			(xy 435.334102 -397.934182) (xy 435.312312 -397.959834) (xy 435.30652 -397.966982) (xy 435.300002 -397.98417)
			(xy 435.299612 -397.993362) (xy 435.299612 -398.100042) (xy 459.541382 -398.100042) (xy 459.545364 -397.972056)
			(xy 459.557296 -397.844565) (xy 459.57713 -397.718062) (xy 459.604791 -397.593037) (xy 459.640171 -397.469974)
			(xy 459.683133 -397.349348) (xy 459.733511 -397.231627) (xy 459.791111 -397.117265) (xy 459.855709 -397.006706)
			(xy 459.927056 -396.900376) (xy 460.004875 -396.798688) (xy 460.088865 -396.702034) (xy 460.178702 -396.610789)
			(xy 460.274038 -396.525306) (xy 460.374503 -396.445915) (xy 460.479711 -396.372923) (xy 460.589252 -396.306614)
			(xy 460.702704 -396.247243) (xy 460.819628 -396.195039) (xy 460.939571 -396.150206) (xy 461.062069 -396.112917)
			(xy 461.186649 -396.083315) (xy 461.312827 -396.061516) (xy 461.440117 -396.047603) (xy 461.568026 -396.041631)
			(xy 461.696059 -396.043622) (xy 461.82372 -396.05357) (xy 461.950516 -396.071434) (xy 462.075955 -396.097147)
			(xy 462.199554 -396.130609) (xy 462.320833 -396.17169) (xy 462.439324 -396.220232) (xy 462.554568 -396.276046)
			(xy 462.666118 -396.338917) (xy 462.773545 -396.408601) (xy 462.876431 -396.484829) (xy 462.974379 -396.567306)
			(xy 463.06701 -396.655713) (xy 463.153966 -396.749708) (xy 463.23491 -396.848927) (xy 463.309529 -396.952986)
			(xy 463.377534 -397.061483) (xy 463.438662 -397.173998) (xy 463.492677 -397.290096) (xy 463.53937 -397.409327)
			(xy 463.57856 -397.531231) (xy 463.610096 -397.655335) (xy 463.633855 -397.781159) (xy 463.649745 -397.908218)
			(xy 463.657706 -398.036018) (xy 463.658204 -398.100042) (xy 463.657706 -398.164066) (xy 463.649745 -398.291866)
			(xy 463.633855 -398.418925) (xy 463.610096 -398.544749) (xy 463.57856 -398.668853) (xy 463.53937 -398.790757)
			(xy 463.492677 -398.909988) (xy 463.438662 -399.026086) (xy 463.377534 -399.138601) (xy 463.309529 -399.247098)
			(xy 463.23491 -399.351157) (xy 463.153966 -399.450376) (xy 463.06701 -399.544371) (xy 462.974379 -399.632778)
			(xy 462.876431 -399.715255) (xy 462.773545 -399.791483) (xy 462.666118 -399.861167) (xy 462.554568 -399.924038)
			(xy 462.439324 -399.979852) (xy 462.320833 -400.028394) (xy 462.199554 -400.069475) (xy 462.075955 -400.102937)
			(xy 461.950516 -400.12865) (xy 461.82372 -400.146514) (xy 461.696059 -400.156462) (xy 461.568026 -400.158453)
			(xy 461.440117 -400.152481) (xy 461.312827 -400.138568) (xy 461.186649 -400.116769) (xy 461.062069 -400.087167)
			(xy 460.939571 -400.049878) (xy 460.819628 -400.005045) (xy 460.702704 -399.952841) (xy 460.589252 -399.89347)
			(xy 460.479711 -399.827161) (xy 460.374503 -399.754169) (xy 460.274038 -399.674778) (xy 460.178702 -399.589295)
			(xy 460.088865 -399.49805) (xy 460.004875 -399.401396) (xy 459.927056 -399.299708) (xy 459.855709 -399.193378)
			(xy 459.791111 -399.082819) (xy 459.733511 -398.968457) (xy 459.683133 -398.850736) (xy 459.640171 -398.73011)
			(xy 459.604791 -398.607047) (xy 459.57713 -398.482022) (xy 459.557296 -398.355519) (xy 459.545364 -398.228028)
			(xy 459.541382 -398.100042) (xy 435.299612 -398.100042) (xy 435.299612 -398.486884) (xy 435.300027 -398.496071)
			(xy 435.306537 -398.513255) (xy 435.312312 -398.520412) (xy 435.334137 -398.546034) (xy 435.372087 -398.601624)
			(xy 435.403122 -398.661351) (xy 435.426795 -398.72436) (xy 435.442767 -398.789746) (xy 435.450809 -398.856573)
			(xy 435.450805 -398.923881) (xy 435.442757 -398.990707) (xy 435.426779 -399.056092) (xy 435.4031 -399.119098)
			(xy 435.37206 -399.178823) (xy 435.334103 -399.234408) (xy 435.312312 -399.26006) (xy 435.306509 -399.267201)
			(xy 435.299998 -399.284395) (xy 435.299612 -399.293588) (xy 435.299612 -399.451576) (xy 435.299159 -399.461727)
			(xy 435.291374 -399.480477) (xy 435.276987 -399.494801) (xy 435.258203 -399.502503) (xy 435.24805 -399.502884)
			(xy 434.53177 -399.502884) (xy 434.521644 -399.502399) (xy 434.502927 -399.494666) (xy 434.488573 -399.480379)
			(xy 434.48075 -399.461699) (xy 434.480208 -399.451576) (xy 434.480208 -399.293588) (xy 434.479802 -399.2844)
			(xy 434.473285 -399.267216) (xy 434.467508 -399.26006) (xy 434.445757 -399.234378) (xy 434.407809 -399.178795)
			(xy 434.376776 -399.119076) (xy 434.353102 -399.056075) (xy 434.337128 -398.990697) (xy 434.329081 -398.923878)
			(xy 434.329078 -398.856576) (xy 434.337118 -398.789757) (xy 434.353086 -398.724377) (xy 434.376753 -398.661374)
			(xy 434.407781 -398.601651) (xy 434.445723 -398.546064) (xy 434.467508 -398.520412) (xy 434.473325 -398.513282)
			(xy 434.479827 -398.49608) (xy 434.480208 -398.486884) (xy 434.480208 -397.993362) (xy 434.479814 -397.984173)
			(xy 434.473289 -397.966989) (xy 434.467508 -397.959834) (xy 434.445731 -397.934173) (xy 434.407784 -397.878587)
			(xy 434.376752 -397.818865) (xy 434.35308 -397.755861) (xy 434.337107 -397.690481) (xy 434.329063 -397.623659)
			(xy 434.329062 -397.556356) (xy 433.200318 -397.556356) (xy 433.202899 -397.561322) (xy 433.226573 -397.624323)
			(xy 433.242549 -397.689701) (xy 433.250596 -397.75652) (xy 433.250599 -397.823822) (xy 433.242559 -397.890642)
			(xy 433.22659 -397.956022) (xy 433.202922 -398.019025) (xy 433.171893 -398.078748) (xy 433.133949 -398.134334)
			(xy 433.112164 -398.159986) (xy 433.106344 -398.167114) (xy 433.099844 -398.184318) (xy 433.099464 -398.193514)
			(xy 433.099464 -398.351502) (xy 433.098968 -398.36166) (xy 433.091194 -398.380428) (xy 433.076828 -398.394794)
			(xy 433.05806 -398.402568) (xy 433.047902 -398.403064) (xy 432.331622 -398.403064) (xy 432.321452 -398.402618)
			(xy 432.302658 -398.394841) (xy 432.288273 -398.380462) (xy 432.280487 -398.361672) (xy 432.28006 -398.351502)
			(xy 432.28006 -398.193514) (xy 432.27963 -398.184329) (xy 432.273129 -398.167145) (xy 432.26736 -398.159986)
			(xy 432.245534 -398.134365) (xy 432.207585 -398.078775) (xy 432.176552 -398.019047) (xy 432.152881 -397.956038)
			(xy 432.13691 -397.890652) (xy 432.128868 -397.823826) (xy 431.000734 -397.823826) (xy 430.971969 -397.879041)
			(xy 430.93388 -397.934676) (xy 430.912016 -397.960342) (xy 430.906221 -397.967488) (xy 430.899705 -397.984678)
			(xy 430.899316 -397.99387) (xy 430.899316 -398.486376) (xy 430.899734 -398.495562) (xy 430.906242 -398.512747)
			(xy 430.912016 -398.519904) (xy 430.933915 -398.54554) (xy 430.972001 -398.601179) (xy 431.00315 -398.66098)
			(xy 431.026911 -398.72408) (xy 431.042944 -398.789573) (xy 431.051016 -398.856514) (xy 431.051013 -398.92394)
			(xy 431.042934 -398.990881) (xy 431.026895 -399.056371) (xy 431.003128 -399.11947) (xy 430.971974 -399.179267)
			(xy 430.933882 -399.234902) (xy 430.912016 -399.260568) (xy 430.90621 -399.267707) (xy 430.8997 -399.284902)
			(xy 430.899316 -399.294096) (xy 430.899316 -399.451576) (xy 430.898865 -399.461695) (xy 430.891128 -399.480395)
			(xy 430.876822 -399.49471) (xy 430.858127 -399.502459) (xy 430.848008 -399.502884) (xy 430.131728 -399.502884)
			(xy 430.121605 -399.502461) (xy 430.102899 -399.494719) (xy 430.088583 -399.480404) (xy 430.08084 -399.461699)
			(xy 430.08042 -399.451576) (xy 430.08042 -399.294096) (xy 430.080008 -399.284909) (xy 430.073495 -399.267725)
			(xy 430.06772 -399.260568) (xy 430.045891 -399.234874) (xy 430.0078 -399.179244) (xy 429.976646 -399.119452)
			(xy 429.952879 -399.056359) (xy 429.936841 -398.990873) (xy 429.928761 -398.923938) (xy 429.928758 -398.856516)
			(xy 429.936831 -398.78958) (xy 429.952863 -398.724093) (xy 429.976624 -398.660997) (xy 430.007772 -398.601202)
			(xy 430.045857 -398.545569) (xy 430.06772 -398.519904) (xy 430.0735 -398.512747) (xy 430.080024 -398.495565)
			(xy 430.08042 -398.486376) (xy 430.08042 -397.99387) (xy 430.08002 -397.984682) (xy 430.073499 -397.967498)
			(xy 430.06772 -397.960342) (xy 430.045865 -397.934669) (xy 430.007775 -397.879036) (xy 429.976623 -397.819241)
			(xy 429.952857 -397.756145) (xy 429.93682 -397.690657) (xy 429.928743 -397.623719) (xy 429.928742 -397.556296)
			(xy 428.800497 -397.556296) (xy 428.803109 -397.561323) (xy 428.826783 -397.624323) (xy 428.842758 -397.689702)
			(xy 428.850805 -397.756521) (xy 428.850808 -397.823822) (xy 428.842768 -397.890642) (xy 428.8268 -397.956022)
			(xy 428.803132 -398.019025) (xy 428.772104 -398.078747) (xy 428.734161 -398.134333) (xy 428.712376 -398.159986)
			(xy 428.706558 -398.167116) (xy 428.700057 -398.184318) (xy 428.699676 -398.193514) (xy 428.699676 -398.351502)
			(xy 428.699169 -398.361658) (xy 428.691396 -398.380425) (xy 428.677035 -398.394789) (xy 428.65827 -398.402566)
			(xy 428.648114 -398.403064) (xy 427.931834 -398.403064) (xy 427.921665 -398.402608) (xy 427.902871 -398.394835)
			(xy 427.888485 -398.380459) (xy 427.880699 -398.361671) (xy 427.880272 -398.351502) (xy 427.880272 -398.193514)
			(xy 427.879861 -398.184327) (xy 427.873349 -398.167142) (xy 427.867572 -398.159986) (xy 427.845746 -398.134365)
			(xy 427.807796 -398.078775) (xy 427.776762 -398.019047) (xy 427.75309 -397.956039) (xy 427.737119 -397.890652)
			(xy 427.729077 -397.823826) (xy 426.600432 -397.823826) (xy 426.571969 -397.878596) (xy 426.534017 -397.934182)
			(xy 426.512228 -397.959834) (xy 426.506426 -397.966975) (xy 426.499917 -397.984169) (xy 426.499528 -397.993362)
			(xy 426.499528 -398.486884) (xy 426.499939 -398.496071) (xy 426.506451 -398.513256) (xy 426.512228 -398.520412)
			(xy 426.534052 -398.546034) (xy 426.572002 -398.601624) (xy 426.603036 -398.661352) (xy 426.626708 -398.72436)
			(xy 426.64268 -398.789746) (xy 426.650721 -398.856573) (xy 426.650718 -398.923881) (xy 426.64267 -398.990707)
			(xy 426.626692 -399.056092) (xy 426.603014 -399.119098) (xy 426.571974 -399.178822) (xy 426.534019 -399.234408)
			(xy 426.512228 -399.26006) (xy 426.506415 -399.267193) (xy 426.499912 -399.284393) (xy 426.499528 -399.293588)
			(xy 426.499528 -399.451576) (xy 426.499059 -399.461725) (xy 426.491277 -399.480472) (xy 426.476895 -399.494795)
			(xy 426.458117 -399.502501) (xy 426.447966 -399.502884) (xy 425.731686 -399.502884) (xy 425.721561 -399.502385)
			(xy 425.702845 -399.494657) (xy 425.68849 -399.480375) (xy 425.680667 -399.461698) (xy 425.680124 -399.451576)
			(xy 425.680124 -399.293588) (xy 425.679714 -399.284401) (xy 425.6732 -399.267217) (xy 425.667424 -399.26006)
			(xy 425.645672 -399.234378) (xy 425.607723 -399.178796) (xy 425.576689 -399.119076) (xy 425.553015 -399.056076)
			(xy 425.53704 -398.990697) (xy 425.528994 -398.923878) (xy 425.52899 -398.856576) (xy 425.537031 -398.789756)
			(xy 425.552999 -398.724376) (xy 425.576667 -398.661373) (xy 425.607696 -398.601651) (xy 425.645639 -398.546065)
			(xy 425.667424 -398.520412) (xy 425.673243 -398.513283) (xy 425.679744 -398.49608) (xy 425.680124 -398.486884)
			(xy 425.680124 -397.993362) (xy 425.679727 -397.984174) (xy 425.673204 -397.96699) (xy 425.667424 -397.959834)
			(xy 425.645646 -397.934174) (xy 425.607698 -397.878588) (xy 425.576665 -397.818865) (xy 425.552993 -397.755862)
			(xy 425.53702 -397.690481) (xy 425.528975 -397.62366) (xy 425.528974 -397.556356) (xy 424.40076 -397.556356)
			(xy 424.403152 -397.560947) (xy 424.426919 -397.62404) (xy 424.442958 -397.689526) (xy 424.451037 -397.756461)
			(xy 424.451041 -397.823882) (xy 424.442968 -397.890818) (xy 424.426936 -397.956305) (xy 424.403175 -398.019401)
			(xy 424.372028 -398.079196) (xy 424.333942 -398.134829) (xy 424.31208 -398.160494) (xy 424.306301 -398.167652)
			(xy 424.299777 -398.184833) (xy 424.29938 -398.194022) (xy 424.29938 -398.351502) (xy 424.298876 -398.361626)
			(xy 424.291151 -398.380344) (xy 424.27687 -398.394699) (xy 424.258194 -398.402522) (xy 424.248072 -398.403064)
			(xy 423.531792 -398.403064) (xy 423.521633 -398.402684) (xy 423.502873 -398.394879) (xy 423.488549 -398.380469)
			(xy 423.480856 -398.361663) (xy 423.480484 -398.351502) (xy 423.480484 -398.194022) (xy 423.480067 -398.184835)
			(xy 423.473558 -398.167651) (xy 423.467784 -398.160494) (xy 423.445883 -398.134859) (xy 423.407797 -398.07922)
			(xy 423.376649 -398.019419) (xy 423.352887 -397.956319) (xy 423.336855 -397.890826) (xy 423.328782 -397.823885)
			(xy 422.200615 -397.823885) (xy 422.171883 -397.879041) (xy 422.133795 -397.934676) (xy 422.111932 -397.960342)
			(xy 422.106127 -397.967481) (xy 422.099619 -397.984676) (xy 422.099232 -397.99387) (xy 422.099232 -398.486376)
			(xy 422.099669 -398.49556) (xy 422.106166 -398.512744) (xy 422.111932 -398.519904) (xy 422.13383 -398.545541)
			(xy 422.171916 -398.60118) (xy 422.203063 -398.66098) (xy 422.226824 -398.724081) (xy 422.242856 -398.789573)
			(xy 422.250928 -398.856514) (xy 422.250925 -398.92394) (xy 422.242846 -398.99088) (xy 422.226808 -399.056371)
			(xy 422.203041 -399.119469) (xy 422.171888 -399.179266) (xy 422.133797 -399.234902) (xy 422.111932 -399.260568)
			(xy 422.106116 -399.267699) (xy 422.099615 -399.284901) (xy 422.099232 -399.294096) (xy 422.099232 -399.451576)
			(xy 422.098696 -399.461679) (xy 422.090972 -399.480351) (xy 422.076691 -399.494645) (xy 422.058027 -399.502387)
			(xy 422.047924 -399.502884) (xy 421.331644 -399.502884) (xy 421.321522 -399.502447) (xy 421.302817 -399.494711)
			(xy 421.2885 -399.4804) (xy 421.280756 -399.461697) (xy 421.280336 -399.451576) (xy 421.280336 -399.294096)
			(xy 421.27992 -399.28491) (xy 421.27341 -399.267726) (xy 421.267636 -399.260568) (xy 421.245806 -399.234874)
			(xy 421.207714 -399.179245) (xy 421.17656 -399.119453) (xy 421.152792 -399.056359) (xy 421.136753 -398.990873)
			(xy 421.128674 -398.923938) (xy 421.12867 -398.856516) (xy 421.136743 -398.78958) (xy 421.152776 -398.724092)
			(xy 421.176538 -398.660997) (xy 421.207686 -398.601202) (xy 421.245773 -398.545569) (xy 421.267636 -398.519904)
			(xy 421.273418 -398.512749) (xy 421.27994 -398.495566) (xy 421.280336 -398.486376) (xy 421.280336 -397.99387)
			(xy 421.279932 -397.984682) (xy 421.273413 -397.967498) (xy 421.267636 -397.960342) (xy 421.245781 -397.934669)
			(xy 421.207689 -397.879037) (xy 421.176536 -397.819242) (xy 421.15277 -397.756146) (xy 421.136732 -397.690657)
			(xy 421.128655 -397.623719) (xy 421.128654 -397.556296) (xy 420.00041 -397.556296) (xy 420.003023 -397.561324)
			(xy 420.026696 -397.624324) (xy 420.042671 -397.689702) (xy 420.050718 -397.756521) (xy 420.050721 -397.823822)
			(xy 420.042681 -397.890642) (xy 420.026713 -397.956021) (xy 420.003046 -398.019024) (xy 419.972019 -398.078747)
			(xy 419.934077 -398.134334) (xy 419.912292 -398.159986) (xy 419.906475 -398.167117) (xy 419.899973 -398.184318)
			(xy 419.899592 -398.193514) (xy 419.899592 -398.351502) (xy 419.899069 -398.361656) (xy 419.891299 -398.38042)
			(xy 419.876943 -398.394784) (xy 419.858184 -398.402563) (xy 419.84803 -398.403064) (xy 419.13175 -398.403064)
			(xy 419.121582 -398.402595) (xy 419.102789 -398.394827) (xy 419.088402 -398.380455) (xy 419.080615 -398.36167)
			(xy 419.080188 -398.351502) (xy 419.080188 -398.193514) (xy 419.079774 -398.184327) (xy 419.073263 -398.167143)
			(xy 419.067488 -398.159986) (xy 419.045661 -398.134365) (xy 419.007711 -398.078775) (xy 418.976676 -398.019048)
			(xy 418.953004 -397.956039) (xy 418.937032 -397.890653) (xy 418.92899 -397.823826) (xy 414.525968 -397.823826)
			(xy 414.525968 -401.723737) (xy 418.929001 -401.723737) (xy 418.929003 -401.65643) (xy 418.93705 -401.589605)
			(xy 418.953027 -401.524221) (xy 418.976704 -401.461215) (xy 419.007743 -401.401491) (xy 419.045697 -401.345906)
			(xy 419.067488 -401.320254) (xy 419.073285 -401.313109) (xy 419.0798 -401.295918) (xy 419.080188 -401.286726)
			(xy 419.080188 -400.793458) (xy 419.079801 -400.784268) (xy 419.073272 -400.767084) (xy 419.067488 -400.75993)
			(xy 419.045705 -400.734274) (xy 419.007752 -400.678689) (xy 418.976716 -400.618966) (xy 418.953041 -400.555962)
			(xy 418.937066 -400.49058) (xy 418.929021 -400.423757) (xy 418.92902 -400.356452) (xy 418.937065 -400.289629)
			(xy 418.953038 -400.224246) (xy 418.976713 -400.161242) (xy 419.007748 -400.101519) (xy 419.045699 -400.045933)
			(xy 419.067488 -400.020282) (xy 419.073273 -400.013129) (xy 419.079795 -399.995944) (xy 419.080188 -399.986754)
			(xy 419.080188 -399.828766) (xy 419.080537 -399.818586) (xy 419.088343 -399.799781) (xy 419.102752 -399.785395)
			(xy 419.121569 -399.777621) (xy 419.13175 -399.777204) (xy 419.84803 -399.777204) (xy 419.858186 -399.777708)
			(xy 419.876949 -399.785486) (xy 419.891312 -399.799848) (xy 419.899091 -399.818611) (xy 419.899592 -399.828766)
			(xy 419.899592 -399.986754) (xy 419.900026 -399.995939) (xy 419.906523 -400.013123) (xy 419.912292 -400.020282)
			(xy 419.934085 -400.04593) (xy 419.972031 -400.101518) (xy 420.003063 -400.161242) (xy 420.026734 -400.224247)
			(xy 420.042705 -400.289629) (xy 420.050749 -400.356452) (xy 420.050748 -400.423757) (xy 420.042704 -400.490579)
			(xy 420.026731 -400.555962) (xy 420.003059 -400.618966) (xy 419.972027 -400.67869) (xy 419.934079 -400.734277)
			(xy 419.912292 -400.75993) (xy 419.906499 -400.767078) (xy 419.899983 -400.784266) (xy 419.899592 -400.793458)
			(xy 419.899592 -401.286726) (xy 419.899991 -401.295914) (xy 419.906513 -401.313099) (xy 419.912292 -401.320254)
			(xy 419.934057 -401.345924) (xy 419.972005 -401.401509) (xy 420.003037 -401.46123) (xy 420.02671 -401.524232)
			(xy 420.042683 -401.589612) (xy 420.050729 -401.656432) (xy 420.050731 -401.723735) (xy 420.042689 -401.790555)
			(xy 420.02672 -401.855936) (xy 420.003051 -401.918939) (xy 419.972022 -401.978663) (xy 419.934077 -402.034249)
			(xy 419.912292 -402.059902) (xy 419.906511 -402.067058) (xy 419.899987 -402.08424) (xy 419.899592 -402.09343)
			(xy 419.899592 -402.251418) (xy 419.899082 -402.261573) (xy 419.891308 -402.280337) (xy 419.876947 -402.294701)
			(xy 419.858185 -402.30248) (xy 419.84803 -402.30298) (xy 419.13175 -402.30298) (xy 419.121584 -402.302496)
			(xy 419.102794 -402.29473) (xy 419.088408 -402.280363) (xy 419.080618 -402.261584) (xy 419.080188 -402.251418)
			(xy 419.080188 -402.09343) (xy 419.079766 -402.084244) (xy 419.073261 -402.067059) (xy 419.067488 -402.059902)
			(xy 419.045677 -402.034268) (xy 419.007726 -401.97868) (xy 418.976691 -401.918955) (xy 418.953017 -401.855948)
			(xy 418.937044 -401.790563) (xy 418.929001 -401.723737) (xy 414.525968 -401.723737) (xy 414.525968 -402.823878)
			(xy 421.128614 -402.823878) (xy 421.128619 -402.75645) (xy 421.1367 -402.689508) (xy 421.152742 -402.624016)
			(xy 421.176513 -402.560916) (xy 421.207671 -402.501119) (xy 421.245768 -402.445485) (xy 421.267636 -402.41982)
			(xy 421.273454 -402.41269) (xy 421.279955 -402.395488) (xy 421.280336 -402.386292) (xy 421.280336 -401.89404)
			(xy 421.279898 -401.884856) (xy 421.273403 -401.867672) (xy 421.267636 -401.860512) (xy 421.245751 -401.834864)
			(xy 421.207661 -401.779227) (xy 421.176509 -401.719429) (xy 421.152744 -401.65633) (xy 421.136709 -401.590839)
			(xy 421.128634 -401.523898) (xy 421.128636 -401.456472) (xy 421.136714 -401.389532) (xy 421.152753 -401.324041)
			(xy 421.176521 -401.260943) (xy 421.207676 -401.201147) (xy 421.24577 -401.145513) (xy 421.267636 -401.119848)
			(xy 421.273442 -401.112709) (xy 421.27995 -401.095514) (xy 421.280336 -401.08632) (xy 421.280336 -400.92884)
			(xy 421.28075 -400.918716) (xy 421.288491 -400.900006) (xy 421.302809 -400.885689) (xy 421.32152 -400.877949)
			(xy 421.331644 -400.877532) (xy 422.047924 -400.877532) (xy 422.058052 -400.877897) (xy 422.076762 -400.885659)
			(xy 422.091077 -400.899991) (xy 422.098816 -400.918711) (xy 422.099232 -400.92884) (xy 422.099232 -401.08632)
			(xy 422.099648 -401.095506) (xy 422.106159 -401.11269) (xy 422.111932 -401.119848) (xy 422.133775 -401.14553)
			(xy 422.171862 -401.201163) (xy 422.203012 -401.260957) (xy 422.226776 -401.324052) (xy 422.242812 -401.389538)
			(xy 422.250889 -401.456474) (xy 422.250891 -401.523896) (xy 422.242817 -401.590832) (xy 422.226785 -401.65632)
			(xy 422.203024 -401.719415) (xy 422.200742 -401.723796) (xy 423.328794 -401.723796) (xy 423.328796 -401.656371)
			(xy 423.336873 -401.589431) (xy 423.352911 -401.523941) (xy 423.376677 -401.460844) (xy 423.407829 -401.401047)
			(xy 423.445919 -401.345412) (xy 423.467784 -401.319746) (xy 423.473584 -401.312603) (xy 423.480097 -401.295411)
			(xy 423.480484 -401.286218) (xy 423.480484 -400.793966) (xy 423.480094 -400.784777) (xy 423.473566 -400.767592)
			(xy 423.467784 -400.760438) (xy 423.445926 -400.734768) (xy 423.407839 -400.679133) (xy 423.376689 -400.619338)
			(xy 423.352925 -400.556242) (xy 423.336889 -400.490753) (xy 423.328813 -400.423816) (xy 423.328813 -400.356393)
			(xy 423.336888 -400.289455) (xy 423.352922 -400.223967) (xy 423.376685 -400.16087) (xy 423.407834 -400.101074)
			(xy 423.445921 -400.045439) (xy 423.467784 -400.019774) (xy 423.473572 -400.012623) (xy 423.480092 -399.995437)
			(xy 423.480484 -399.986246) (xy 423.480484 -399.828766) (xy 423.4809 -399.818632) (xy 423.488647 -399.799901)
			(xy 423.502955 -399.785545) (xy 423.521659 -399.777735) (xy 423.531792 -399.777204) (xy 424.248072 -399.777204)
			(xy 424.258225 -399.777644) (xy 424.276977 -399.785431) (xy 424.291302 -399.799823) (xy 424.299002 -399.818611)
			(xy 424.29938 -399.828766) (xy 424.29938 -399.986246) (xy 424.299821 -399.99543) (xy 424.306314 -400.012614)
			(xy 424.31208 -400.019774) (xy 424.333951 -400.045434) (xy 424.37204 -400.101069) (xy 424.403192 -400.160866)
			(xy 424.426957 -400.223963) (xy 424.442992 -400.289453) (xy 424.451068 -400.356392) (xy 424.451068 -400.423817)
			(xy 424.442991 -400.490756) (xy 424.426954 -400.556245) (xy 424.403188 -400.619343) (xy 424.372036 -400.679139)
			(xy 424.333945 -400.734773) (xy 424.31208 -400.760438) (xy 424.306282 -400.767582) (xy 424.299769 -400.784774)
			(xy 424.29938 -400.793966) (xy 424.29938 -401.286218) (xy 424.299786 -401.295406) (xy 424.306303 -401.31259)
			(xy 424.31208 -401.319746) (xy 424.333923 -401.345429) (xy 424.372014 -401.40106) (xy 424.403167 -401.460854)
			(xy 424.426933 -401.523949) (xy 424.44297 -401.589436) (xy 424.451048 -401.656372) (xy 424.45105 -401.723795)
			(xy 424.442976 -401.790732) (xy 424.426943 -401.85622) (xy 424.40318 -401.919316) (xy 424.372031 -401.979111)
			(xy 424.333943 -402.034745) (xy 424.31208 -402.06041) (xy 424.306294 -402.067563) (xy 424.299774 -402.084748)
			(xy 424.29938 -402.093938) (xy 424.29938 -402.251418) (xy 424.298889 -402.261543) (xy 424.291159 -402.280261)
			(xy 424.276874 -402.294616) (xy 424.258195 -402.302438) (xy 424.248072 -402.30298) (xy 423.531792 -402.30298)
			(xy 423.521635 -402.302584) (xy 423.502879 -402.294782) (xy 423.488555 -402.280378) (xy 423.480859 -402.261577)
			(xy 423.480484 -402.251418) (xy 423.480484 -402.093938) (xy 423.480059 -402.084752) (xy 423.473556 -402.067568)
			(xy 423.467784 -402.06041) (xy 423.445899 -402.034762) (xy 423.407812 -401.979125) (xy 423.376663 -401.919326)
			(xy 423.352901 -401.856227) (xy 423.336867 -401.790736) (xy 423.328794 -401.723796) (xy 422.200742 -401.723796)
			(xy 422.171878 -401.779211) (xy 422.133794 -401.834846) (xy 422.111932 -401.860512) (xy 422.10614 -401.86766)
			(xy 422.099624 -401.884849) (xy 422.099232 -401.89404) (xy 422.099232 -402.386292) (xy 422.099661 -402.395477)
			(xy 422.106163 -402.412661) (xy 422.111932 -402.41982) (xy 422.133748 -402.445525) (xy 422.171836 -402.501154)
			(xy 422.202987 -402.560945) (xy 422.226752 -402.624037) (xy 422.24279 -402.689521) (xy 422.250869 -402.756454)
			(xy 422.250874 -402.823818) (xy 425.528934 -402.823818) (xy 425.528938 -402.75651) (xy 425.536987 -402.689684)
			(xy 425.552965 -402.624299) (xy 425.576642 -402.561293) (xy 425.60768 -402.501568) (xy 425.645634 -402.44598)
			(xy 425.667424 -402.420328) (xy 425.673236 -402.413194) (xy 425.679741 -402.395995) (xy 425.680124 -402.3868)
			(xy 425.680124 -401.893532) (xy 425.679693 -401.884347) (xy 425.673193 -401.867163) (xy 425.667424 -401.860004)
			(xy 425.645617 -401.834368) (xy 425.60767 -401.778779) (xy 425.576638 -401.719053) (xy 425.552967 -401.656046)
			(xy 425.536996 -401.590662) (xy 425.528954 -401.523838) (xy 425.528956 -401.456532) (xy 425.537001 -401.389708)
			(xy 425.552976 -401.324325) (xy 425.57665 -401.26132) (xy 425.607685 -401.201595) (xy 425.645635 -401.146008)
			(xy 425.667424 -401.120356) (xy 425.673225 -401.113214) (xy 425.679736 -401.096021) (xy 425.680124 -401.086828)
			(xy 425.680124 -400.92884) (xy 425.680555 -400.918686) (xy 425.688342 -400.899929) (xy 425.702736 -400.885604)
			(xy 425.72153 -400.877907) (xy 425.731686 -400.877532) (xy 426.447966 -400.877532) (xy 426.45809 -400.878054)
			(xy 426.476808 -400.88577) (xy 426.491165 -400.900045) (xy 426.498987 -400.918719) (xy 426.499528 -400.92884)
			(xy 426.499528 -401.086828) (xy 426.499918 -401.096017) (xy 426.506445 -401.113202) (xy 426.512228 -401.120356)
			(xy 426.533997 -401.146024) (xy 426.571949 -401.201607) (xy 426.602985 -401.261328) (xy 426.62666 -401.324331)
			(xy 426.642635 -401.389712) (xy 426.650681 -401.456533) (xy 426.650683 -401.523837) (xy 426.642641 -401.590659)
			(xy 426.626669 -401.65604) (xy 426.602997 -401.719044) (xy 426.600558 -401.723737) (xy 427.729089 -401.723737)
			(xy 427.729091 -401.65643) (xy 427.737138 -401.589605) (xy 427.753114 -401.524221) (xy 427.776791 -401.461216)
			(xy 427.807828 -401.401492) (xy 427.845782 -401.345906) (xy 427.867572 -401.320254) (xy 427.873379 -401.313117)
			(xy 427.879886 -401.29592) (xy 427.880272 -401.286726) (xy 427.880272 -400.793458) (xy 427.879888 -400.784268)
			(xy 427.873357 -400.767084) (xy 427.867572 -400.75993) (xy 427.845789 -400.734273) (xy 427.807838 -400.678688)
			(xy 427.776803 -400.618966) (xy 427.753128 -400.555962) (xy 427.737154 -400.49058) (xy 427.729109 -400.423757)
			(xy 427.729108 -400.356452) (xy 427.737152 -400.289629) (xy 427.753126 -400.224247) (xy 427.776799 -400.161243)
			(xy 427.807833 -400.101519) (xy 427.845784 -400.045934) (xy 427.867572 -400.020282) (xy 427.873367 -400.013136)
			(xy 427.879881 -399.995946) (xy 427.880272 -399.986754) (xy 427.880272 -399.828766) (xy 427.880706 -399.818602)
			(xy 427.888498 -399.799825) (xy 427.902883 -399.78546) (xy 427.921669 -399.777693) (xy 427.931834 -399.777204)
			(xy 428.648114 -399.777204) (xy 428.658268 -399.777721) (xy 428.677031 -399.785494) (xy 428.691395 -399.799852)
			(xy 428.699175 -399.818612) (xy 428.699676 -399.828766) (xy 428.699676 -399.986754) (xy 428.700114 -399.995938)
			(xy 428.706609 -400.013122) (xy 428.712376 -400.020282) (xy 428.734169 -400.045929) (xy 428.772117 -400.101517)
			(xy 428.803149 -400.161241) (xy 428.826821 -400.224246) (xy 428.842793 -400.289629) (xy 428.850836 -400.356452)
			(xy 428.850836 -400.423757) (xy 428.842791 -400.49058) (xy 428.826818 -400.555962) (xy 428.803145 -400.618967)
			(xy 428.772112 -400.678691) (xy 428.734164 -400.734278) (xy 428.712376 -400.75993) (xy 428.706581 -400.767076)
			(xy 428.700066 -400.784266) (xy 428.699676 -400.793458) (xy 428.699676 -401.286726) (xy 428.700079 -401.295914)
			(xy 428.706598 -401.313098) (xy 428.712376 -401.320254) (xy 428.734142 -401.345924) (xy 428.77209 -401.401508)
			(xy 428.803124 -401.46123) (xy 428.826797 -401.524232) (xy 428.842771 -401.589612) (xy 428.850817 -401.656432)
			(xy 428.850819 -401.723735) (xy 428.842777 -401.790556) (xy 428.826807 -401.855937) (xy 428.803137 -401.91894)
			(xy 428.772107 -401.978663) (xy 428.734162 -402.03425) (xy 428.712376 -402.059902) (xy 428.706593 -402.067057)
			(xy 428.700071 -402.08424) (xy 428.699676 -402.09343) (xy 428.699676 -402.251418) (xy 428.699182 -402.261575)
			(xy 428.691404 -402.280342) (xy 428.677039 -402.294706) (xy 428.658271 -402.302483) (xy 428.648114 -402.30298)
			(xy 427.931834 -402.30298) (xy 427.921667 -402.302509) (xy 427.902876 -402.294738) (xy 427.888491 -402.280367)
			(xy 427.880702 -402.261585) (xy 427.880272 -402.251418) (xy 427.880272 -402.09343) (xy 427.879854 -402.084244)
			(xy 427.873347 -402.067059) (xy 427.867572 -402.059902) (xy 427.845762 -402.034268) (xy 427.807811 -401.97868)
			(xy 427.776777 -401.918954) (xy 427.753104 -401.855947) (xy 427.737132 -401.790562) (xy 427.729089 -401.723737)
			(xy 426.600558 -401.723737) (xy 426.571964 -401.778767) (xy 426.534015 -401.834352) (xy 426.512228 -401.860004)
			(xy 426.506438 -401.867154) (xy 426.499922 -401.884341) (xy 426.499528 -401.893532) (xy 426.499528 -402.3868)
			(xy 426.499932 -402.395988) (xy 426.506449 -402.413173) (xy 426.512228 -402.420328) (xy 426.53397 -402.446019)
			(xy 426.571922 -402.501599) (xy 426.602959 -402.561317) (xy 426.626636 -402.624316) (xy 426.642613 -402.689694)
			(xy 426.650662 -402.756513) (xy 426.650666 -402.823815) (xy 426.650658 -402.823878) (xy 429.928702 -402.823878)
			(xy 429.928707 -402.75645) (xy 429.936788 -402.689508) (xy 429.952829 -402.624016) (xy 429.976599 -402.560917)
			(xy 430.007757 -402.50112) (xy 430.045852 -402.445485) (xy 430.06772 -402.41982) (xy 430.073535 -402.412688)
			(xy 430.080038 -402.395487) (xy 430.08042 -402.386292) (xy 430.08042 -401.89404) (xy 430.079986 -401.884855)
			(xy 430.073488 -401.867671) (xy 430.06772 -401.860512) (xy 430.045836 -401.834863) (xy 430.007746 -401.779227)
			(xy 429.976595 -401.719429) (xy 429.952831 -401.656329) (xy 429.936797 -401.590838) (xy 429.928722 -401.523898)
			(xy 429.928724 -401.456472) (xy 429.936802 -401.389532) (xy 429.95284 -401.324042) (xy 429.976608 -401.260944)
			(xy 430.007762 -401.201147) (xy 430.045854 -401.145513) (xy 430.06772 -401.119848) (xy 430.073523 -401.112708)
			(xy 430.080033 -401.095513) (xy 430.08042 -401.08632) (xy 430.08042 -400.92884) (xy 430.080849 -400.918718)
			(xy 430.088588 -400.900011) (xy 430.102901 -400.885695) (xy 430.121606 -400.877952) (xy 430.131728 -400.877532)
			(xy 430.848008 -400.877532) (xy 430.858135 -400.87791) (xy 430.876845 -400.885667) (xy 430.89116 -400.899996)
			(xy 430.898899 -400.918713) (xy 430.899316 -400.92884) (xy 430.899316 -401.08632) (xy 430.899713 -401.095509)
			(xy 430.906236 -401.112693) (xy 430.912016 -401.119848) (xy 430.93386 -401.14553) (xy 430.971948 -401.201162)
			(xy 431.003099 -401.260956) (xy 431.026863 -401.324051) (xy 431.0429 -401.389538) (xy 431.050977 -401.456474)
			(xy 431.050979 -401.523896) (xy 431.042905 -401.590832) (xy 431.026872 -401.65632) (xy 431.003111 -401.719416)
			(xy 431.00086 -401.723737) (xy 432.128879 -401.723737) (xy 432.128881 -401.65643) (xy 432.136928 -401.589605)
			(xy 432.152904 -401.524222) (xy 432.17658 -401.461216) (xy 432.207617 -401.401492) (xy 432.24557 -401.345906)
			(xy 432.26736 -401.320254) (xy 432.273166 -401.313116) (xy 432.279673 -401.29592) (xy 432.28006 -401.286726)
			(xy 432.28006 -400.793458) (xy 432.279657 -400.78427) (xy 432.273137 -400.767087) (xy 432.26736 -400.75993)
			(xy 432.245578 -400.734273) (xy 432.207627 -400.678688) (xy 432.176593 -400.618965) (xy 432.152919 -400.555961)
			(xy 432.136945 -400.490579) (xy 432.1289 -400.423757) (xy 432.128899 -400.356452) (xy 432.136943 -400.28963)
			(xy 432.152916 -400.224247) (xy 432.176589 -400.161243) (xy 432.207623 -400.10152) (xy 432.245572 -400.045934)
			(xy 432.26736 -400.020282) (xy 432.273154 -400.013135) (xy 432.279669 -399.995946) (xy 432.28006 -399.986754)
			(xy 432.28006 -399.828766) (xy 432.280506 -399.818603) (xy 432.288296 -399.799829) (xy 432.302676 -399.785464)
			(xy 432.321459 -399.777695) (xy 432.331622 -399.777204) (xy 433.047902 -399.777204) (xy 433.058056 -399.777731)
			(xy 433.076818 -399.7855) (xy 433.091182 -399.799855) (xy 433.098963 -399.818613) (xy 433.099464 -399.828766)
			(xy 433.099464 -399.986754) (xy 433.099905 -399.995938) (xy 433.106398 -400.013122) (xy 433.112164 -400.020282)
			(xy 433.133958 -400.045929) (xy 433.171906 -400.101516) (xy 433.202939 -400.161241) (xy 433.226611 -400.224246)
			(xy 433.242584 -400.289629) (xy 433.250627 -400.356452) (xy 433.250627 -400.423757) (xy 433.242582 -400.49058)
			(xy 433.226609 -400.555963) (xy 433.202935 -400.618968) (xy 433.171901 -400.678691) (xy 433.133952 -400.734278)
			(xy 433.112164 -400.75993) (xy 433.106368 -400.767075) (xy 433.099854 -400.784266) (xy 433.099464 -400.793458)
			(xy 433.099464 -401.286726) (xy 433.09987 -401.295913) (xy 433.106387 -401.313097) (xy 433.112164 -401.320254)
			(xy 433.13393 -401.345924) (xy 433.171879 -401.401508) (xy 433.202913 -401.461229) (xy 433.226587 -401.524231)
			(xy 433.242561 -401.589611) (xy 433.250607 -401.656432) (xy 433.250609 -401.723735) (xy 433.242567 -401.790556)
			(xy 433.226597 -401.855937) (xy 433.202927 -401.918941) (xy 433.171896 -401.978663) (xy 433.13395 -402.03425)
			(xy 433.112164 -402.059902) (xy 433.106379 -402.067056) (xy 433.099858 -402.08424) (xy 433.099464 -402.09343)
			(xy 433.099464 -402.251418) (xy 433.098982 -402.261577) (xy 433.091202 -402.280346) (xy 433.076833 -402.294711)
			(xy 433.058061 -402.302485) (xy 433.047902 -402.30298) (xy 432.331622 -402.30298) (xy 432.321454 -402.302518)
			(xy 432.302663 -402.294744) (xy 432.288278 -402.28037) (xy 432.28049 -402.261586) (xy 432.28006 -402.251418)
			(xy 432.28006 -402.09343) (xy 432.279622 -402.084246) (xy 432.273126 -402.067062) (xy 432.26736 -402.059902)
			(xy 432.24555 -402.034268) (xy 432.2076 -401.97868) (xy 432.176567 -401.918954) (xy 432.152894 -401.855947)
			(xy 432.136922 -401.790562) (xy 432.128879 -401.723737) (xy 431.00086 -401.723737) (xy 430.971963 -401.779212)
			(xy 430.933878 -401.834847) (xy 430.912016 -401.860512) (xy 430.906234 -401.867667) (xy 430.89971 -401.88485)
			(xy 430.899316 -401.89404) (xy 430.899316 -402.386292) (xy 430.899726 -402.395479) (xy 430.90624 -402.412664)
			(xy 430.912016 -402.41982) (xy 430.933832 -402.445524) (xy 430.971921 -402.501154) (xy 431.003073 -402.560945)
			(xy 431.026839 -402.624036) (xy 431.042878 -402.68952) (xy 431.050957 -402.756454) (xy 431.050962 -402.823818)
			(xy 434.329022 -402.823818) (xy 434.329026 -402.75651) (xy 434.337075 -402.689684) (xy 434.353052 -402.6243)
			(xy 434.376729 -402.561294) (xy 434.407766 -402.501568) (xy 434.445718 -402.445981) (xy 434.467508 -402.420328)
			(xy 434.473319 -402.413193) (xy 434.479825 -402.395995) (xy 434.480208 -402.3868) (xy 434.480208 -401.893532)
			(xy 434.479781 -401.884347) (xy 434.473279 -401.867162) (xy 434.467508 -401.860004) (xy 434.445702 -401.834368)
			(xy 434.407755 -401.778778) (xy 434.376725 -401.719052) (xy 434.353054 -401.656046) (xy 434.337084 -401.590662)
			(xy 434.329042 -401.523838) (xy 434.329043 -401.456532) (xy 434.337089 -401.389709) (xy 434.353063 -401.324326)
			(xy 434.376737 -401.26132) (xy 434.407771 -401.201596) (xy 434.44572 -401.146009) (xy 434.467508 -401.120356)
			(xy 434.473307 -401.113212) (xy 434.47982 -401.096021) (xy 434.480208 -401.086828) (xy 434.480208 -400.92884)
			(xy 434.480655 -400.918688) (xy 434.488438 -400.899934) (xy 434.502828 -400.885609) (xy 434.521616 -400.87791)
			(xy 434.53177 -400.877532) (xy 435.24805 -400.877532) (xy 435.258173 -400.878067) (xy 435.276891 -400.885777)
			(xy 435.291249 -400.900049) (xy 435.299071 -400.918721) (xy 435.299612 -400.92884) (xy 435.299612 -401.086828)
			(xy 435.300006 -401.096017) (xy 435.306531 -401.113201) (xy 435.312312 -401.120356) (xy 435.334082 -401.146024)
			(xy 435.372034 -401.201607) (xy 435.403071 -401.261328) (xy 435.426747 -401.32433) (xy 435.442723 -401.389711)
			(xy 435.450769 -401.456533) (xy 435.450771 -401.523837) (xy 435.442728 -401.590659) (xy 435.426756 -401.656041)
			(xy 435.403083 -401.719045) (xy 435.37205 -401.778767) (xy 435.3341 -401.834353) (xy 435.312312 -401.860004)
			(xy 435.306533 -401.867161) (xy 435.300007 -401.884343) (xy 435.299612 -401.893532) (xy 435.299612 -402.3868)
			(xy 435.30002 -402.395988) (xy 435.306535 -402.413172) (xy 435.312312 -402.420328) (xy 435.334054 -402.446018)
			(xy 435.372008 -402.501598) (xy 435.403046 -402.561316) (xy 435.426723 -402.624316) (xy 435.442701 -402.689694)
			(xy 435.45075 -402.756513) (xy 435.450754 -402.823815) (xy 435.442714 -402.890635) (xy 435.426745 -402.956015)
			(xy 435.403075 -403.019018) (xy 435.372045 -403.07874) (xy 435.334098 -403.134325) (xy 435.312312 -403.159976)
			(xy 435.306502 -403.167112) (xy 435.299995 -403.184309) (xy 435.299612 -403.193504) (xy 435.299612 -403.351492)
			(xy 435.299172 -403.361644) (xy 435.291381 -403.380394) (xy 435.27699 -403.394717) (xy 435.258204 -403.402419)
			(xy 435.24805 -403.4028) (xy 434.53177 -403.4028) (xy 434.521646 -403.402299) (xy 434.502932 -403.394569)
			(xy 434.488578 -403.380288) (xy 434.480753 -403.361613) (xy 434.480208 -403.351492) (xy 434.480208 -403.193504)
			(xy 434.479794 -403.184317) (xy 434.473283 -403.167133) (xy 434.467508 -403.159976) (xy 434.445674 -403.134362)
			(xy 434.407729 -403.07877) (xy 434.376699 -403.01904) (xy 434.353031 -402.956031) (xy 434.337062 -402.890644)
			(xy 434.329022 -402.823818) (xy 431.050962 -402.823818) (xy 431.050962 -402.823874) (xy 431.042891 -402.890808)
			(xy 431.026861 -402.956295) (xy 431.003103 -403.019389) (xy 430.971958 -403.079184) (xy 430.933877 -403.134819)
			(xy 430.912016 -403.160484) (xy 430.906203 -403.167618) (xy 430.899698 -403.184817) (xy 430.899316 -403.194012)
			(xy 430.899316 -403.351492) (xy 430.898809 -403.361598) (xy 430.891077 -403.380273) (xy 430.876787 -403.394568)
			(xy 430.858114 -403.402306) (xy 430.848008 -403.4028) (xy 430.131728 -403.4028) (xy 430.121607 -403.402361)
			(xy 430.102904 -403.394622) (xy 430.088589 -403.380313) (xy 430.080843 -403.361613) (xy 430.08042 -403.351492)
			(xy 430.08042 -403.194012) (xy 430.079999 -403.184826) (xy 430.073492 -403.167642) (xy 430.06772 -403.160484)
			(xy 430.045808 -403.134858) (xy 430.00772 -403.079218) (xy 429.97657 -403.019417) (xy 429.952807 -402.956315)
			(xy 429.936775 -402.890821) (xy 429.928702 -402.823878) (xy 426.650658 -402.823878) (xy 426.642626 -402.890635)
			(xy 426.626657 -402.956015) (xy 426.602989 -403.019017) (xy 426.571959 -403.078739) (xy 426.534014 -403.134324)
			(xy 426.512228 -403.159976) (xy 426.506408 -403.167104) (xy 426.499909 -403.184308) (xy 426.499528 -403.193504)
			(xy 426.499528 -403.351492) (xy 426.499072 -403.361642) (xy 426.491285 -403.380389) (xy 426.476899 -403.394712)
			(xy 426.458118 -403.402417) (xy 426.447966 -403.4028) (xy 425.731686 -403.4028) (xy 425.721563 -403.402286)
			(xy 425.70285 -403.394561) (xy 425.688495 -403.380284) (xy 425.68067 -403.361612) (xy 425.680124 -403.351492)
			(xy 425.680124 -403.193504) (xy 425.679707 -403.184318) (xy 425.673198 -403.167133) (xy 425.667424 -403.159976)
			(xy 425.64559 -403.134362) (xy 425.607643 -403.07877) (xy 425.576613 -403.019041) (xy 425.552943 -402.956032)
			(xy 425.536974 -402.890645) (xy 425.528934 -402.823818) (xy 422.250874 -402.823818) (xy 422.250874 -402.823874)
			(xy 422.242803 -402.890808) (xy 422.226774 -402.956294) (xy 422.203016 -403.019389) (xy 422.171873 -403.079184)
			(xy 422.133792 -403.134818) (xy 422.111932 -403.160484) (xy 422.106109 -403.16761) (xy 422.099612 -403.184816)
			(xy 422.099232 -403.194012) (xy 422.099232 -403.351492) (xy 422.098709 -403.361596) (xy 422.09098 -403.380268)
			(xy 422.076695 -403.394562) (xy 422.058028 -403.402303) (xy 422.047924 -403.4028) (xy 421.331644 -403.4028)
			(xy 421.321524 -403.402348) (xy 421.302822 -403.394614) (xy 421.288506 -403.380308) (xy 421.280759 -403.361611)
			(xy 421.280336 -403.351492) (xy 421.280336 -403.194012) (xy 421.279912 -403.184826) (xy 421.273407 -403.167642)
			(xy 421.267636 -403.160484) (xy 421.245724 -403.134858) (xy 421.207634 -403.079219) (xy 421.176483 -403.019418)
			(xy 421.15272 -402.956315) (xy 421.136687 -402.890821) (xy 421.128614 -402.823878) (xy 414.525968 -402.823878)
			(xy 414.525968 -405.623649) (xy 418.929012 -405.623649) (xy 418.929013 -405.556342) (xy 418.937058 -405.489518)
			(xy 418.953033 -405.424135) (xy 418.976709 -405.36113) (xy 419.007746 -405.301407) (xy 419.045698 -405.245822)
			(xy 419.067488 -405.22017) (xy 419.073278 -405.21302) (xy 419.079797 -405.195833) (xy 419.080188 -405.186642)
			(xy 419.080188 -404.693374) (xy 419.079793 -404.684185) (xy 419.073269 -404.667001) (xy 419.067488 -404.659846)
			(xy 419.04572 -404.634177) (xy 419.007768 -404.578594) (xy 418.976731 -404.518873) (xy 418.953055 -404.455871)
			(xy 418.937079 -404.39049) (xy 418.929032 -404.323669) (xy 418.92903 -404.256364) (xy 418.937073 -404.189542)
			(xy 418.953045 -404.124161) (xy 418.976717 -404.061157) (xy 419.007751 -404.001435) (xy 419.0457 -403.945849)
			(xy 419.067488 -403.920198) (xy 419.073267 -403.91304) (xy 419.079792 -403.895859) (xy 419.080188 -403.88667)
			(xy 419.080188 -403.728682) (xy 419.08055 -403.718503) (xy 419.088351 -403.699698) (xy 419.102756 -403.685313)
			(xy 419.12157 -403.677537) (xy 419.13175 -403.67712) (xy 419.84803 -403.67712) (xy 419.858187 -403.677608)
			(xy 419.876954 -403.685389) (xy 419.891317 -403.699756) (xy 419.899094 -403.718524) (xy 419.899592 -403.728682)
			(xy 419.899592 -403.88667) (xy 419.900018 -403.895855) (xy 419.906521 -403.91304) (xy 419.912292 -403.920198)
			(xy 419.9341 -403.945833) (xy 419.972047 -404.001422) (xy 420.003077 -404.061149) (xy 420.026747 -404.124155)
			(xy 420.042718 -404.189539) (xy 420.05076 -404.256363) (xy 420.050758 -404.32367) (xy 420.042712 -404.390493)
			(xy 420.026738 -404.455876) (xy 420.003064 -404.518882) (xy 419.97203 -404.578606) (xy 419.93408 -404.634193)
			(xy 419.912292 -404.659846) (xy 419.906492 -404.666989) (xy 419.89998 -404.684181) (xy 419.899592 -404.693374)
			(xy 419.899592 -405.186642) (xy 419.899984 -405.195831) (xy 419.90651 -405.213015) (xy 419.912292 -405.22017)
			(xy 419.934073 -405.245827) (xy 419.97202 -405.301414) (xy 420.003052 -405.361137) (xy 420.026723 -405.424141)
			(xy 420.042696 -405.489522) (xy 420.05074 -405.556343) (xy 420.050741 -405.623647) (xy 420.042698 -405.690469)
			(xy 420.026726 -405.755851) (xy 420.003055 -405.818855) (xy 419.972025 -405.878578) (xy 419.934078 -405.934165)
			(xy 419.912292 -405.959818) (xy 419.906504 -405.96697) (xy 419.899985 -405.984155) (xy 419.899592 -405.993346)
			(xy 419.899592 -406.151334) (xy 419.899095 -406.16149) (xy 419.891315 -406.180254) (xy 419.876951 -406.194617)
			(xy 419.858186 -406.202396) (xy 419.84803 -406.202896) (xy 419.13175 -406.202896) (xy 419.121586 -406.202396)
			(xy 419.102799 -406.194634) (xy 419.088413 -406.180272) (xy 419.08062 -406.161497) (xy 419.080188 -406.151334)
			(xy 419.080188 -405.993346) (xy 419.079759 -405.984161) (xy 419.073259 -405.966976) (xy 419.067488 -405.959818)
			(xy 419.045693 -405.934171) (xy 419.007741 -405.878585) (xy 418.976705 -405.818861) (xy 418.953031 -405.755856)
			(xy 418.937057 -405.690473) (xy 418.929012 -405.623649) (xy 414.525968 -405.623649) (xy 414.525968 -406.723789)
			(xy 421.128626 -406.723789) (xy 421.128629 -406.656363) (xy 421.136708 -406.589421) (xy 421.152748 -406.52393)
			(xy 421.176518 -406.460832) (xy 421.207674 -406.401035) (xy 421.245769 -406.345401) (xy 421.267636 -406.319736)
			(xy 421.273447 -406.312601) (xy 421.279952 -406.295403) (xy 421.280336 -406.286208) (xy 421.280336 -405.793956)
			(xy 421.279939 -405.784768) (xy 421.273415 -405.767584) (xy 421.267636 -405.760428) (xy 421.245767 -405.734767)
			(xy 421.207676 -405.679132) (xy 421.176523 -405.619336) (xy 421.152758 -405.556239) (xy 421.136722 -405.490749)
			(xy 421.128645 -405.423809) (xy 421.128646 -405.356385) (xy 421.136723 -405.289445) (xy 421.15276 -405.223956)
			(xy 421.176526 -405.160859) (xy 421.207679 -405.101062) (xy 421.245771 -405.045429) (xy 421.267636 -405.019764)
			(xy 421.273435 -405.012621) (xy 421.279947 -404.995429) (xy 421.280336 -404.986236) (xy 421.280336 -404.828756)
			(xy 421.28075 -404.81864) (xy 421.288509 -404.799954) (xy 421.302828 -404.785659) (xy 421.321527 -404.777933)
			(xy 421.331644 -404.777448) (xy 422.047924 -404.777448) (xy 422.058028 -404.777964) (xy 422.076697 -404.7857)
			(xy 422.090989 -404.799986) (xy 422.098732 -404.818652) (xy 422.099232 -404.828756) (xy 422.099232 -404.986236)
			(xy 422.09964 -404.995423) (xy 422.106157 -405.012607) (xy 422.111932 -405.019764) (xy 422.133791 -405.045433)
			(xy 422.171878 -405.101068) (xy 422.203027 -405.160864) (xy 422.22679 -405.22396) (xy 422.242825 -405.289448)
			(xy 422.2509 -405.356386) (xy 422.250901 -405.423808) (xy 422.242826 -405.490746) (xy 422.226792 -405.556234)
			(xy 422.203029 -405.619331) (xy 422.20075 -405.623707) (xy 423.328805 -405.623707) (xy 423.328805 -405.556284)
			(xy 423.336882 -405.489345) (xy 423.352917 -405.423856) (xy 423.376681 -405.360759) (xy 423.407832 -405.300962)
			(xy 423.44592 -405.245328) (xy 423.467784 -405.219662) (xy 423.473577 -405.212514) (xy 423.480094 -405.195326)
			(xy 423.480484 -405.186134) (xy 423.480484 -404.693882) (xy 423.480086 -404.684693) (xy 423.473564 -404.667509)
			(xy 423.467784 -404.660354) (xy 423.445942 -404.634671) (xy 423.407854 -404.579038) (xy 423.376703 -404.519245)
			(xy 423.352938 -404.45615) (xy 423.336902 -404.390663) (xy 423.328825 -404.323727) (xy 423.328823 -404.256306)
			(xy 423.336896 -404.189369) (xy 423.352929 -404.123882) (xy 423.37669 -404.060786) (xy 423.407837 -404.00099)
			(xy 423.445922 -403.945355) (xy 423.467784 -403.91969) (xy 423.473565 -403.912534) (xy 423.48009 -403.895352)
			(xy 423.480484 -403.886162) (xy 423.480484 -403.728682) (xy 423.480913 -403.718549) (xy 423.488655 -403.699819)
			(xy 423.502959 -403.685461) (xy 423.521661 -403.677651) (xy 423.531792 -403.67712) (xy 424.248072 -403.67712)
			(xy 424.258227 -403.677545) (xy 424.276983 -403.685335) (xy 424.291308 -403.699731) (xy 424.299005 -403.718525)
			(xy 424.29938 -403.728682) (xy 424.29938 -403.886162) (xy 424.299813 -403.895347) (xy 424.306311 -403.912531)
			(xy 424.31208 -403.91969) (xy 424.333966 -403.945337) (xy 424.372056 -404.000974) (xy 424.403207 -404.060772)
			(xy 424.42697 -404.123872) (xy 424.443005 -404.189363) (xy 424.451079 -404.256304) (xy 424.451077 -404.323729)
			(xy 424.442999 -404.39067) (xy 424.426961 -404.45616) (xy 424.403193 -404.519258) (xy 424.372039 -404.579055)
			(xy 424.333946 -404.634689) (xy 424.31208 -404.660354) (xy 424.306276 -404.667494) (xy 424.299766 -404.684688)
			(xy 424.29938 -404.693882) (xy 424.29938 -405.186134) (xy 424.299778 -405.195322) (xy 424.306301 -405.212506)
			(xy 424.31208 -405.219662) (xy 424.333939 -405.245332) (xy 424.372029 -405.300965) (xy 424.403181 -405.360761)
			(xy 424.426946 -405.423857) (xy 424.442983 -405.489346) (xy 424.45106 -405.556284) (xy 424.45106 -405.623707)
			(xy 424.442985 -405.690646) (xy 424.426949 -405.756134) (xy 424.403185 -405.819231) (xy 424.372034 -405.879027)
			(xy 424.333944 -405.934661) (xy 424.31208 -405.960326) (xy 424.306288 -405.967474) (xy 424.299771 -405.984662)
			(xy 424.29938 -405.993854) (xy 424.29938 -406.151334) (xy 424.298902 -406.16146) (xy 424.291167 -406.180179)
			(xy 424.276878 -406.194533) (xy 424.258196 -406.202355) (xy 424.248072 -406.202896) (xy 423.531792 -406.202896)
			(xy 423.521637 -406.202485) (xy 423.502884 -406.194686) (xy 423.48856 -406.180286) (xy 423.480862 -406.161491)
			(xy 423.480484 -406.151334) (xy 423.480484 -405.993854) (xy 423.480051 -405.984669) (xy 423.473553 -405.967484)
			(xy 423.467784 -405.960326) (xy 423.445915 -405.934665) (xy 423.407827 -405.87903) (xy 423.376678 -405.819233)
			(xy 423.352915 -405.756135) (xy 423.33688 -405.690646) (xy 423.328805 -405.623707) (xy 422.20075 -405.623707)
			(xy 422.171881 -405.679127) (xy 422.133795 -405.734762) (xy 422.111932 -405.760428) (xy 422.106133 -405.767571)
			(xy 422.099622 -405.784763) (xy 422.099232 -405.793956) (xy 422.099232 -406.286208) (xy 422.099654 -406.295394)
			(xy 422.106161 -406.312577) (xy 422.111932 -406.319736) (xy 422.133763 -406.345428) (xy 422.171851 -406.401059)
			(xy 422.203001 -406.460852) (xy 422.226766 -406.523945) (xy 422.242803 -406.589431) (xy 422.250881 -406.656366)
			(xy 422.250883 -406.72373) (xy 425.528945 -406.72373) (xy 425.528948 -406.656422) (xy 425.536995 -406.589598)
			(xy 425.552971 -406.524214) (xy 425.576647 -406.461208) (xy 425.607683 -406.401484) (xy 425.645635 -406.345896)
			(xy 425.667424 -406.320244) (xy 425.67323 -406.313105) (xy 425.679738 -406.29591) (xy 425.680124 -406.286716)
			(xy 425.680124 -405.793448) (xy 425.679685 -405.784264) (xy 425.673191 -405.76708) (xy 425.667424 -405.75992)
			(xy 425.645633 -405.734271) (xy 425.607685 -405.678684) (xy 425.576653 -405.61896) (xy 425.552981 -405.555955)
			(xy 425.537009 -405.490572) (xy 425.528965 -405.42375) (xy 425.528965 -405.356444) (xy 425.53701 -405.289622)
			(xy 425.552983 -405.22424) (xy 425.576655 -405.161235) (xy 425.607688 -405.101511) (xy 425.645636 -405.045924)
			(xy 425.667424 -405.020272) (xy 425.673218 -405.013125) (xy 425.679733 -404.995936) (xy 425.680124 -404.986744)
			(xy 425.680124 -404.828756) (xy 425.680486 -404.818596) (xy 425.688301 -404.799838) (xy 425.702716 -404.785515)
			(xy 425.721523 -404.777822) (xy 425.731686 -404.777448) (xy 426.447966 -404.777448) (xy 426.458091 -404.777955)
			(xy 426.476813 -404.785673) (xy 426.491171 -404.799953) (xy 426.49899 -404.818633) (xy 426.499528 -404.828756)
			(xy 426.499528 -404.986744) (xy 426.499911 -404.995934) (xy 426.506443 -405.013119) (xy 426.512228 -405.020272)
			(xy 426.534013 -405.045927) (xy 426.571964 -405.101512) (xy 426.602999 -405.161235) (xy 426.626674 -405.224239)
			(xy 426.642648 -405.289622) (xy 426.650693 -405.356444) (xy 426.650693 -405.42375) (xy 426.642649 -405.490573)
			(xy 426.626675 -405.555955) (xy 426.603002 -405.618959) (xy 426.600565 -405.623649) (xy 427.7291 -405.623649)
			(xy 427.729101 -405.556342) (xy 427.737146 -405.489519) (xy 427.753121 -405.424136) (xy 427.776796 -405.361131)
			(xy 427.807831 -405.301408) (xy 427.845783 -405.245822) (xy 427.867572 -405.22017) (xy 427.873373 -405.213028)
			(xy 427.879883 -405.195835) (xy 427.880272 -405.186642) (xy 427.880272 -404.693374) (xy 427.879881 -404.684185)
			(xy 427.873355 -404.667) (xy 427.867572 -404.659846) (xy 427.845805 -404.634176) (xy 427.807853 -404.578593)
			(xy 427.776817 -404.518872) (xy 427.753142 -404.45587) (xy 427.737166 -404.39049) (xy 427.72912 -404.323668)
			(xy 427.729118 -404.256365) (xy 427.73716 -404.189543) (xy 427.753132 -404.124162) (xy 427.776804 -404.061158)
			(xy 427.807836 -404.001435) (xy 427.845785 -403.94585) (xy 427.867572 -403.920198) (xy 427.873361 -403.913048)
			(xy 427.879878 -403.895861) (xy 427.880272 -403.88667) (xy 427.880272 -403.728682) (xy 427.88065 -403.718505)
			(xy 427.888447 -403.699703) (xy 427.902847 -403.685318) (xy 427.921657 -403.67754) (xy 427.931834 -403.67712)
			(xy 428.648114 -403.67712) (xy 428.65827 -403.677622) (xy 428.677036 -403.685397) (xy 428.6914 -403.69976)
			(xy 428.699178 -403.718526) (xy 428.699676 -403.728682) (xy 428.699676 -403.88667) (xy 428.700106 -403.895855)
			(xy 428.706607 -403.913039) (xy 428.712376 -403.920198) (xy 428.734185 -403.945833) (xy 428.772132 -404.001422)
			(xy 428.803164 -404.061148) (xy 428.826835 -404.124155) (xy 428.842806 -404.189539) (xy 428.850848 -404.256363)
			(xy 428.850846 -404.32367) (xy 428.8428 -404.390494) (xy 428.826825 -404.455877) (xy 428.80315 -404.518882)
			(xy 428.772115 -404.578607) (xy 428.734165 -404.634194) (xy 428.712376 -404.659846) (xy 428.706575 -404.666988)
			(xy 428.700064 -404.684181) (xy 428.699676 -404.693374) (xy 428.699676 -405.186642) (xy 428.700071 -405.195831)
			(xy 428.706596 -405.213015) (xy 428.712376 -405.22017) (xy 428.734157 -405.245827) (xy 428.772106 -405.301413)
			(xy 428.803138 -405.361136) (xy 428.826811 -405.42414) (xy 428.842784 -405.489522) (xy 428.850828 -405.556343)
			(xy 428.850829 -405.623648) (xy 428.842785 -405.69047) (xy 428.826813 -405.755851) (xy 428.803142 -405.818856)
			(xy 428.77211 -405.878579) (xy 428.734163 -405.934166) (xy 428.712376 -405.959818) (xy 428.706587 -405.966968)
			(xy 428.700068 -405.984155) (xy 428.699676 -405.993346) (xy 428.699676 -406.151334) (xy 428.699195 -406.161492)
			(xy 428.691412 -406.180259) (xy 428.677043 -406.194623) (xy 428.658272 -406.202399) (xy 428.648114 -406.202896)
			(xy 427.931834 -406.202896) (xy 427.921683 -406.202339) (xy 427.902921 -406.194583) (xy 427.888556 -406.180236)
			(xy 427.880774 -406.161485) (xy 427.880272 -406.151334) (xy 427.880272 -405.993346) (xy 427.879846 -405.98416)
			(xy 427.873344 -405.966976) (xy 427.867572 -405.959818) (xy 427.845777 -405.934171) (xy 427.807827 -405.878585)
			(xy 427.776792 -405.818861) (xy 427.753118 -405.755855) (xy 427.737144 -405.690472) (xy 427.7291 -405.623649)
			(xy 426.600565 -405.623649) (xy 426.571967 -405.678683) (xy 426.534016 -405.734268) (xy 426.512228 -405.75992)
			(xy 426.506432 -405.767065) (xy 426.499919 -405.784256) (xy 426.499528 -405.793448) (xy 426.499528 -406.286716)
			(xy 426.499924 -406.295905) (xy 426.506447 -406.313089) (xy 426.512228 -406.320244) (xy 426.533985 -406.345922)
			(xy 426.571937 -406.401504) (xy 426.602974 -406.461223) (xy 426.62665 -406.524225) (xy 426.642626 -406.589604)
			(xy 426.650673 -406.656424) (xy 426.650676 -406.723728) (xy 426.650669 -406.723789) (xy 429.928714 -406.723789)
			(xy 429.928717 -406.656363) (xy 429.936796 -406.589422) (xy 429.952835 -406.523931) (xy 429.976604 -406.460832)
			(xy 430.00776 -406.401036) (xy 430.045853 -406.345401) (xy 430.06772 -406.319736) (xy 430.073529 -406.312599)
			(xy 430.080035 -406.295402) (xy 430.08042 -406.286208) (xy 430.08042 -405.793956) (xy 430.080027 -405.784767)
			(xy 430.073501 -405.767583) (xy 430.06772 -405.760428) (xy 430.045851 -405.734766) (xy 430.007761 -405.679132)
			(xy 429.97661 -405.619335) (xy 429.952845 -405.556238) (xy 429.936809 -405.490748) (xy 429.928733 -405.423809)
			(xy 429.928734 -405.356385) (xy 429.93681 -405.289446) (xy 429.952847 -405.223956) (xy 429.976612 -405.160859)
			(xy 430.007765 -405.101063) (xy 430.045855 -405.045429) (xy 430.06772 -405.019764) (xy 430.073517 -405.012619)
			(xy 430.080031 -404.995428) (xy 430.08042 -404.986236) (xy 430.08042 -404.828756) (xy 430.08085 -404.818642)
			(xy 430.088605 -404.799959) (xy 430.102919 -404.785665) (xy 430.121613 -404.777935) (xy 430.131728 -404.777448)
			(xy 430.848008 -404.777448) (xy 430.858111 -404.777977) (xy 430.876779 -404.785708) (xy 430.891072 -404.799991)
			(xy 430.898815 -404.818654) (xy 430.899316 -404.828756) (xy 430.899316 -404.986236) (xy 430.899705 -404.995425)
			(xy 430.906233 -405.01261) (xy 430.912016 -405.019764) (xy 430.933875 -405.045433) (xy 430.971963 -405.101067)
			(xy 431.003113 -405.160863) (xy 431.026877 -405.223959) (xy 431.042912 -405.289448) (xy 431.050988 -405.356385)
			(xy 431.050989 -405.423809) (xy 431.042913 -405.490746) (xy 431.026879 -405.556235) (xy 431.003116 -405.619331)
			(xy 431.000867 -405.623648) (xy 432.128891 -405.623648) (xy 432.128892 -405.556343) (xy 432.136937 -405.489519)
			(xy 432.152911 -405.424136) (xy 432.176585 -405.361132) (xy 432.207621 -405.301408) (xy 432.245571 -405.245822)
			(xy 432.26736 -405.22017) (xy 432.273159 -405.213027) (xy 432.279671 -405.195835) (xy 432.28006 -405.186642)
			(xy 432.28006 -404.693374) (xy 432.279649 -404.684187) (xy 432.273134 -404.667004) (xy 432.26736 -404.659846)
			(xy 432.245593 -404.634176) (xy 432.207643 -404.578593) (xy 432.176607 -404.518872) (xy 432.152932 -404.45587)
			(xy 432.136957 -404.390489) (xy 432.128911 -404.323668) (xy 432.128909 -404.256365) (xy 432.136951 -404.189543)
			(xy 432.152922 -404.124162) (xy 432.176594 -404.061158) (xy 432.207626 -404.001436) (xy 432.245573 -403.94585)
			(xy 432.26736 -403.920198) (xy 432.273147 -403.913047) (xy 432.279666 -403.895861) (xy 432.28006 -403.88667)
			(xy 432.28006 -403.728682) (xy 432.28045 -403.718507) (xy 432.288245 -403.699707) (xy 432.302641 -403.685322)
			(xy 432.321446 -403.677542) (xy 432.331622 -403.67712) (xy 433.047902 -403.67712) (xy 433.058058 -403.677631)
			(xy 433.076823 -403.685403) (xy 433.091188 -403.699763) (xy 433.098965 -403.718526) (xy 433.099464 -403.728682)
			(xy 433.099464 -403.88667) (xy 433.099897 -403.895855) (xy 433.106396 -403.913039) (xy 433.112164 -403.920198)
			(xy 433.133973 -403.945832) (xy 433.171921 -404.001421) (xy 433.202954 -404.061147) (xy 433.226625 -404.124154)
			(xy 433.242596 -404.189539) (xy 433.250639 -404.256363) (xy 433.250637 -404.32367) (xy 433.24259 -404.390494)
			(xy 433.226615 -404.455877) (xy 433.20294 -404.518883) (xy 433.171904 -404.578607) (xy 433.133953 -404.634194)
			(xy 433.112164 -404.659846) (xy 433.106361 -404.666986) (xy 433.099851 -404.684181) (xy 433.099464 -404.693374)
			(xy 433.099464 -405.186642) (xy 433.099862 -405.19583) (xy 433.106385 -405.213014) (xy 433.112164 -405.22017)
			(xy 433.133946 -405.245827) (xy 433.171895 -405.301413) (xy 433.202928 -405.361136) (xy 433.226601 -405.42414)
			(xy 433.242574 -405.489521) (xy 433.250619 -405.556343) (xy 433.250619 -405.623648) (xy 433.242576 -405.69047)
			(xy 433.226604 -405.755852) (xy 433.202932 -405.818856) (xy 433.171899 -405.878579) (xy 433.133951 -405.934166)
			(xy 433.112164 -405.959818) (xy 433.106373 -405.966967) (xy 433.099856 -405.984155) (xy 433.099464 -405.993346)
			(xy 433.099464 -406.151334) (xy 433.098995 -406.161494) (xy 433.091209 -406.180263) (xy 433.076836 -406.194627)
			(xy 433.058062 -406.202401) (xy 433.047902 -406.202896) (xy 432.331622 -406.202896) (xy 432.32147 -406.20235)
			(xy 432.302708 -406.194589) (xy 432.288343 -406.180239) (xy 432.280561 -406.161486) (xy 432.28006 -406.151334)
			(xy 432.28006 -405.993346) (xy 432.279614 -405.984163) (xy 432.273124 -405.966979) (xy 432.26736 -405.959818)
			(xy 432.245566 -405.934171) (xy 432.207616 -405.878584) (xy 432.176582 -405.81886) (xy 432.152908 -405.755855)
			(xy 432.136935 -405.690472) (xy 432.128891 -405.623648) (xy 431.000867 -405.623648) (xy 430.971966 -405.679128)
			(xy 430.933879 -405.734762) (xy 430.912016 -405.760428) (xy 430.906227 -405.767579) (xy 430.899707 -405.784765)
			(xy 430.899316 -405.793956) (xy 430.899316 -406.286208) (xy 430.899719 -406.295396) (xy 430.906237 -406.31258)
			(xy 430.912016 -406.319736) (xy 430.933848 -406.345427) (xy 430.971937 -406.401059) (xy 431.003088 -406.460851)
			(xy 431.026853 -406.523945) (xy 431.04289 -406.58943) (xy 431.050968 -406.656366) (xy 431.050971 -406.723729)
			(xy 434.329033 -406.723729) (xy 434.329036 -406.656422) (xy 434.337083 -406.589598) (xy 434.353058 -406.524215)
			(xy 434.376733 -406.461209) (xy 434.407769 -406.401484) (xy 434.445719 -406.345897) (xy 434.467508 -406.320244)
			(xy 434.473312 -406.313104) (xy 434.479822 -406.295909) (xy 434.480208 -406.286716) (xy 434.480208 -405.793448)
			(xy 434.479773 -405.784263) (xy 434.473276 -405.767079) (xy 434.467508 -405.75992) (xy 434.445717 -405.734271)
			(xy 434.407771 -405.678683) (xy 434.376739 -405.618959) (xy 434.353068 -405.555954) (xy 434.337096 -405.490572)
			(xy 434.329053 -405.423749) (xy 434.329053 -405.356445) (xy 434.337097 -405.289622) (xy 434.35307 -405.22424)
			(xy 434.376742 -405.161236) (xy 434.407774 -405.101512) (xy 434.445721 -405.045925) (xy 434.467508 -405.020272)
			(xy 434.4733 -405.013124) (xy 434.479817 -404.995935) (xy 434.480208 -404.986744) (xy 434.480208 -404.828756)
			(xy 434.480586 -404.818598) (xy 434.488397 -404.799843) (xy 434.502807 -404.785521) (xy 434.52161 -404.777824)
			(xy 434.53177 -404.777448) (xy 435.24805 -404.777448) (xy 435.258175 -404.777968) (xy 435.276896 -404.785681)
			(xy 435.291254 -404.799957) (xy 435.299074 -404.818634) (xy 435.299612 -404.828756) (xy 435.299612 -404.986744)
			(xy 435.299998 -404.995934) (xy 435.306528 -405.013118) (xy 435.312312 -405.020272) (xy 435.334097 -405.045927)
			(xy 435.372049 -405.101512) (xy 435.403086 -405.161234) (xy 435.426761 -405.224239) (xy 435.442735 -405.289621)
			(xy 435.450781 -405.356444) (xy 435.450781 -405.42375) (xy 435.442736 -405.490573) (xy 435.426762 -405.555956)
			(xy 435.403088 -405.61896) (xy 435.372052 -405.678683) (xy 435.334101 -405.734269) (xy 435.312312 -405.75992)
			(xy 435.306526 -405.767073) (xy 435.300005 -405.784257) (xy 435.299612 -405.793448) (xy 435.299612 -406.286716)
			(xy 435.300012 -406.295904) (xy 435.306532 -406.313089) (xy 435.312312 -406.320244) (xy 435.33407 -406.345921)
			(xy 435.372023 -406.401503) (xy 435.40306 -406.461223) (xy 435.426737 -406.524224) (xy 435.442713 -406.589604)
			(xy 435.450761 -406.656424) (xy 435.450764 -406.723728) (xy 435.442722 -406.790549) (xy 435.426751 -406.85593)
			(xy 435.40308 -406.918933) (xy 435.372048 -406.978656) (xy 435.334099 -407.034241) (xy 435.312312 -407.059892)
			(xy 435.306538 -407.067053) (xy 435.300009 -407.084231) (xy 435.299612 -407.09342) (xy 435.299612 -407.251408)
			(xy 435.299185 -407.261561) (xy 435.291389 -407.280311) (xy 435.276994 -407.294634) (xy 435.258205 -407.302335)
			(xy 435.24805 -407.302716) (xy 434.53177 -407.302716) (xy 434.521636 -407.302297) (xy 434.502906 -407.294551)
			(xy 434.488549 -407.280244) (xy 434.480739 -407.26154) (xy 434.480208 -407.251408) (xy 434.480208 -407.09342)
			(xy 434.479786 -407.084234) (xy 434.47328 -407.06705) (xy 434.467508 -407.059892) (xy 434.44569 -407.034265)
			(xy 434.407744 -406.978674) (xy 434.376714 -406.918947) (xy 434.353044 -406.855939) (xy 434.337074 -406.790554)
			(xy 434.329033 -406.723729) (xy 431.050971 -406.723729) (xy 431.050971 -406.723786) (xy 431.042899 -406.790722)
			(xy 431.026867 -406.856209) (xy 431.003107 -406.919305) (xy 430.971961 -406.9791) (xy 430.933877 -407.034735)
			(xy 430.912016 -407.0604) (xy 430.906239 -407.067559) (xy 430.899712 -407.084739) (xy 430.899316 -407.093928)
			(xy 430.899316 -407.251408) (xy 430.898822 -407.261515) (xy 430.891084 -407.28019) (xy 430.87679 -407.294484)
			(xy 430.858115 -407.302222) (xy 430.848008 -407.302716) (xy 430.131728 -407.302716) (xy 430.121609 -407.302262)
			(xy 430.102909 -407.294526) (xy 430.088595 -407.280221) (xy 430.080845 -407.261526) (xy 430.08042 -407.251408)
			(xy 430.08042 -407.093928) (xy 430.079992 -407.084743) (xy 430.07349 -407.067559) (xy 430.06772 -407.0604)
			(xy 430.045824 -407.034761) (xy 430.007735 -406.979123) (xy 429.976584 -406.919324) (xy 429.952821 -406.856223)
			(xy 429.936787 -406.790731) (xy 429.928714 -406.723789) (xy 426.650669 -406.723789) (xy 426.642634 -406.790548)
			(xy 426.626664 -406.855929) (xy 426.602993 -406.918933) (xy 426.571962 -406.978655) (xy 426.534015 -407.03424)
			(xy 426.512228 -407.059892) (xy 426.506444 -407.067045) (xy 426.499924 -407.08423) (xy 426.499528 -407.09342)
			(xy 426.499528 -407.251408) (xy 426.499085 -407.261559) (xy 426.491292 -407.280306) (xy 426.476903 -407.294628)
			(xy 426.458119 -407.302333) (xy 426.447966 -407.302716) (xy 425.731686 -407.302716) (xy 425.721553 -407.302283)
			(xy 425.702823 -407.294543) (xy 425.688466 -407.28024) (xy 425.680655 -407.261539) (xy 425.680124 -407.251408)
			(xy 425.680124 -407.09342) (xy 425.679699 -407.084235) (xy 425.673195 -407.06705) (xy 425.667424 -407.059892)
			(xy 425.645605 -407.034266) (xy 425.607658 -406.978675) (xy 425.576627 -406.918948) (xy 425.552957 -406.85594)
			(xy 425.536987 -406.790555) (xy 425.528945 -406.72373) (xy 422.250883 -406.72373) (xy 422.250883 -406.723786)
			(xy 422.242811 -406.790722) (xy 422.22678 -406.856209) (xy 422.203021 -406.919304) (xy 422.171876 -406.9791)
			(xy 422.133793 -407.034734) (xy 422.111932 -407.0604) (xy 422.106145 -407.067551) (xy 422.099626 -407.084737)
			(xy 422.099232 -407.093928) (xy 422.099232 -407.251408) (xy 422.098722 -407.261513) (xy 422.090988 -407.280185)
			(xy 422.076699 -407.294479) (xy 422.058029 -407.302219) (xy 422.047924 -407.302716) (xy 421.331644 -407.302716)
			(xy 421.321526 -407.302248) (xy 421.302827 -407.294518) (xy 421.288512 -407.280217) (xy 421.280762 -407.261525)
			(xy 421.280336 -407.251408) (xy 421.280336 -407.093928) (xy 421.279904 -407.084743) (xy 421.273405 -407.067559)
			(xy 421.267636 -407.0604) (xy 421.245739 -407.034761) (xy 421.207649 -406.979124) (xy 421.176498 -406.919324)
			(xy 421.152734 -406.856224) (xy 421.1367 -406.790731) (xy 421.128626 -406.723789) (xy 414.525968 -406.723789)
			(xy 414.525968 -409.523827) (xy 418.928991 -409.523827) (xy 418.928995 -409.456519) (xy 418.937043 -409.389693)
			(xy 418.953021 -409.324308) (xy 418.9767 -409.261302) (xy 419.00774 -409.201577) (xy 419.045697 -409.145992)
			(xy 419.067488 -409.12034) (xy 419.073291 -409.113199) (xy 419.079802 -409.096005) (xy 419.080188 -409.086812)
			(xy 419.080188 -408.593544) (xy 419.079759 -408.584359) (xy 419.073259 -408.567174) (xy 419.067488 -408.560016)
			(xy 419.045691 -408.534371) (xy 419.007739 -408.478785) (xy 418.976704 -408.419061) (xy 418.953029 -408.356055)
			(xy 418.937055 -408.290671) (xy 418.929011 -408.223847) (xy 418.929012 -408.156541) (xy 418.937057 -408.089717)
			(xy 418.953033 -408.024333) (xy 418.976708 -407.961328) (xy 419.007745 -407.901605) (xy 419.045698 -407.84602)
			(xy 419.067488 -407.820368) (xy 419.073279 -407.813219) (xy 419.079797 -407.796031) (xy 419.080188 -407.78684)
			(xy 419.080188 -407.628852) (xy 419.080582 -407.618696) (xy 419.088391 -407.599945) (xy 419.102796 -407.585624)
			(xy 419.121592 -407.577924) (xy 419.13175 -407.577544) (xy 419.84803 -407.577544) (xy 419.858159 -407.578002)
			(xy 419.876882 -407.58574) (xy 419.891237 -407.600035) (xy 419.899055 -407.618725) (xy 419.899592 -407.628852)
			(xy 419.899592 -407.78684) (xy 419.899985 -407.796029) (xy 419.906511 -407.813213) (xy 419.912292 -407.820368)
			(xy 419.934071 -407.846027) (xy 419.972018 -407.901613) (xy 420.00305 -407.961336) (xy 420.026722 -408.02434)
			(xy 420.042694 -408.089721) (xy 420.050739 -408.156542) (xy 420.050739 -408.223846) (xy 420.042697 -408.290667)
			(xy 420.026725 -408.356049) (xy 420.003055 -408.419053) (xy 419.972024 -408.478776) (xy 419.934078 -408.534363)
			(xy 419.912292 -408.560016) (xy 419.906505 -408.567168) (xy 419.899985 -408.584353) (xy 419.899592 -408.593544)
			(xy 419.899592 -409.086812) (xy 419.899998 -409.096) (xy 419.906515 -409.113184) (xy 419.912292 -409.12034)
			(xy 419.934043 -409.146022) (xy 419.971991 -409.201605) (xy 420.003024 -409.261324) (xy 420.026698 -409.324325)
			(xy 420.042672 -409.389703) (xy 420.050719 -409.456522) (xy 420.050722 -409.523824) (xy 420.042682 -409.590643)
			(xy 420.026714 -409.656023) (xy 420.003047 -409.719026) (xy 419.972019 -409.778749) (xy 419.934077 -409.834336)
			(xy 419.912292 -409.859988) (xy 419.906475 -409.867118) (xy 419.899973 -409.88432) (xy 419.899592 -409.893516)
			(xy 419.899592 -410.051504) (xy 419.899181 -410.061659) (xy 419.891383 -410.080413) (xy 419.876983 -410.094737)
			(xy 419.858187 -410.102435) (xy 419.84803 -410.102812) (xy 419.13175 -410.102812) (xy 419.121633 -410.102234)
			(xy 419.102923 -410.094532) (xy 419.088567 -410.080274) (xy 419.080736 -410.061618) (xy 419.080188 -410.051504)
			(xy 419.080188 -409.893516) (xy 419.079773 -409.884329) (xy 419.073263 -409.867145) (xy 419.067488 -409.859988)
			(xy 419.045663 -409.834366) (xy 419.007713 -409.778776) (xy 418.976678 -409.719049) (xy 418.953005 -409.65604)
			(xy 418.937033 -409.590654) (xy 418.928991 -409.523827) (xy 414.525968 -409.523827) (xy 414.525968 -410.623701)
			(xy 421.128637 -410.623701) (xy 421.128638 -410.556275) (xy 421.136716 -410.489335) (xy 421.152755 -410.423845)
			(xy 421.176522 -410.360747) (xy 421.207677 -410.300951) (xy 421.24577 -410.245317) (xy 421.267636 -410.219652)
			(xy 421.27344 -410.212512) (xy 421.279949 -410.195317) (xy 421.280336 -410.186124) (xy 421.280336 -409.693872)
			(xy 421.279931 -409.684684) (xy 421.273413 -409.667501) (xy 421.267636 -409.660344) (xy 421.245783 -409.63467)
			(xy 421.207691 -409.579037) (xy 421.176538 -409.519243) (xy 421.152771 -409.456147) (xy 421.136734 -409.390659)
			(xy 421.128657 -409.323721) (xy 421.128656 -409.256297) (xy 421.136731 -409.189359) (xy 421.152766 -409.12387)
			(xy 421.176531 -409.060774) (xy 421.207682 -409.000978) (xy 421.245771 -408.945345) (xy 421.267636 -408.91968)
			(xy 421.273428 -408.912532) (xy 421.279945 -408.895343) (xy 421.280336 -408.886152) (xy 421.280336 -408.728672)
			(xy 421.280694 -408.718543) (xy 421.288458 -408.699832) (xy 421.302793 -408.685517) (xy 421.321515 -408.67778)
			(xy 421.331644 -408.677364) (xy 422.047924 -408.677364) (xy 422.05803 -408.677864) (xy 422.076702 -408.685603)
			(xy 422.090994 -408.699895) (xy 422.098735 -408.718566) (xy 422.099232 -408.728672) (xy 422.099232 -408.886152)
			(xy 422.09968 -408.895335) (xy 422.106169 -408.912519) (xy 422.111932 -408.91968) (xy 422.133807 -408.945336)
			(xy 422.171893 -409.000973) (xy 422.203041 -409.06077) (xy 422.226803 -409.123868) (xy 422.242837 -409.189358)
			(xy 422.250911 -409.256297) (xy 422.25091 -409.323721) (xy 422.242834 -409.39066) (xy 422.226798 -409.456149)
			(xy 422.203034 -409.519246) (xy 422.200617 -409.523886) (xy 423.328784 -409.523886) (xy 423.328787 -409.45646)
			(xy 423.336866 -409.389519) (xy 423.352905 -409.324029) (xy 423.376672 -409.26093) (xy 423.407826 -409.201133)
			(xy 423.445918 -409.145498) (xy 423.467784 -409.119832) (xy 423.47359 -409.112693) (xy 423.4801 -409.095498)
			(xy 423.480484 -409.086304) (xy 423.480484 -408.594052) (xy 423.480052 -408.584867) (xy 423.473554 -408.567682)
			(xy 423.467784 -408.560524) (xy 423.445913 -408.534865) (xy 423.407825 -408.479229) (xy 423.376676 -408.419432)
			(xy 423.352913 -408.356334) (xy 423.336878 -408.290845) (xy 423.328803 -408.223906) (xy 423.328804 -408.156482)
			(xy 423.336881 -408.089543) (xy 423.352916 -408.024054) (xy 423.376681 -407.960957) (xy 423.407832 -407.901161)
			(xy 423.44592 -407.845526) (xy 423.467784 -407.81986) (xy 423.473578 -407.812713) (xy 423.480095 -407.795524)
			(xy 423.480484 -407.786332) (xy 423.480484 -407.628852) (xy 423.480946 -407.618742) (xy 423.488696 -407.600066)
			(xy 423.503 -407.585774) (xy 423.521682 -407.578038) (xy 423.531792 -407.577544) (xy 424.248072 -407.577544)
			(xy 424.258172 -407.578106) (xy 424.276839 -407.585825) (xy 424.291133 -407.600097) (xy 424.298879 -407.618753)
			(xy 424.29938 -407.628852) (xy 424.29938 -407.786332) (xy 424.299779 -407.79552) (xy 424.306301 -407.812704)
			(xy 424.31208 -407.81986) (xy 424.333937 -407.845531) (xy 424.372027 -407.901165) (xy 424.403179 -407.96096)
			(xy 424.426945 -408.024056) (xy 424.442981 -408.089544) (xy 424.451058 -408.156482) (xy 424.451059 -408.223906)
			(xy 424.442984 -408.290844) (xy 424.426948 -408.356333) (xy 424.403184 -408.419429) (xy 424.372033 -408.479225)
			(xy 424.333944 -408.534859) (xy 424.31208 -408.560524) (xy 424.306288 -408.567673) (xy 424.299771 -408.584861)
			(xy 424.29938 -408.594052) (xy 424.29938 -409.086304) (xy 424.299792 -409.095491) (xy 424.306305 -409.112675)
			(xy 424.31208 -409.119832) (xy 424.333909 -409.145526) (xy 424.372 -409.201156) (xy 424.403154 -409.260948)
			(xy 424.426921 -409.324041) (xy 424.442959 -409.389527) (xy 424.451039 -409.456462) (xy 424.451042 -409.523884)
			(xy 424.442969 -409.59082) (xy 424.426937 -409.656307) (xy 424.403176 -409.719403) (xy 424.372028 -409.779198)
			(xy 424.333943 -409.834831) (xy 424.31208 -409.860496) (xy 424.3063 -409.867653) (xy 424.299776 -409.884835)
			(xy 424.29938 -409.894024) (xy 424.29938 -410.051504) (xy 424.298987 -410.061629) (xy 424.291234 -410.080337)
			(xy 424.27691 -410.094651) (xy 424.258197 -410.102393) (xy 424.248072 -410.102812) (xy 423.531792 -410.102812)
			(xy 423.521684 -410.102322) (xy 423.503008 -410.094584) (xy 423.488714 -410.080288) (xy 423.480978 -410.061612)
			(xy 423.480484 -410.051504) (xy 423.480484 -409.894024) (xy 423.480066 -409.884838) (xy 423.473558 -409.867653)
			(xy 423.467784 -409.860496) (xy 423.445885 -409.83486) (xy 423.407799 -409.779221) (xy 423.37665 -409.71942)
			(xy 423.352889 -409.65632) (xy 423.336856 -409.590827) (xy 423.328784 -409.523886) (xy 422.200617 -409.523886)
			(xy 422.171884 -409.579043) (xy 422.133796 -409.634678) (xy 422.111932 -409.660344) (xy 422.106126 -409.667482)
			(xy 422.099619 -409.684678) (xy 422.099232 -409.693872) (xy 422.099232 -410.186124) (xy 422.099646 -410.19531)
			(xy 422.106159 -410.212494) (xy 422.111932 -410.219652) (xy 422.133779 -410.245331) (xy 422.171866 -410.300964)
			(xy 422.203016 -410.360759) (xy 422.22678 -410.423854) (xy 422.242815 -410.489341) (xy 422.250892 -410.556277)
			(xy 422.250893 -410.623641) (xy 425.528957 -410.623641) (xy 425.528958 -410.556335) (xy 425.537003 -410.489512)
			(xy 425.552978 -410.424129) (xy 425.576652 -410.361123) (xy 425.607686 -410.301399) (xy 425.645636 -410.245812)
			(xy 425.667424 -410.22016) (xy 425.673223 -410.213017) (xy 425.679735 -410.195825) (xy 425.680124 -410.186632)
			(xy 425.680124 -409.693364) (xy 425.679726 -409.684176) (xy 425.673203 -409.666992) (xy 425.667424 -409.659836)
			(xy 425.645648 -409.634174) (xy 425.6077 -409.578589) (xy 425.576667 -409.518866) (xy 425.552994 -409.455863)
			(xy 425.537021 -409.390482) (xy 425.528976 -409.323661) (xy 425.528975 -409.256357) (xy 425.537018 -409.189536)
			(xy 425.552989 -409.124154) (xy 425.57666 -409.06115) (xy 425.607691 -409.001427) (xy 425.645637 -408.94584)
			(xy 425.667424 -408.920188) (xy 425.673211 -408.913036) (xy 425.679731 -408.895851) (xy 425.680124 -408.88666)
			(xy 425.680124 -408.728672) (xy 425.680499 -408.718513) (xy 425.688308 -408.699755) (xy 425.70272 -408.685432)
			(xy 425.721525 -408.677738) (xy 425.731686 -408.677364) (xy 426.447966 -408.677364) (xy 426.458093 -408.677855)
			(xy 426.476818 -408.685576) (xy 426.491177 -408.699862) (xy 426.498993 -408.718547) (xy 426.499528 -408.728672)
			(xy 426.499528 -408.88666) (xy 426.499951 -408.895846) (xy 426.506455 -408.913031) (xy 426.512228 -408.920188)
			(xy 426.534028 -408.94583) (xy 426.571979 -409.001417) (xy 426.603014 -409.061142) (xy 426.626687 -409.124148)
			(xy 426.64266 -409.189532) (xy 426.650704 -409.256356) (xy 426.650703 -409.323662) (xy 426.642657 -409.390486)
			(xy 426.626682 -409.45587) (xy 426.603006 -409.518875) (xy 426.600433 -409.523827) (xy 427.729079 -409.523827)
			(xy 427.729082 -409.456519) (xy 427.73713 -409.389693) (xy 427.753108 -409.324308) (xy 427.776786 -409.261302)
			(xy 427.807826 -409.201578) (xy 427.845781 -409.145992) (xy 427.867572 -409.12034) (xy 427.873385 -409.113207)
			(xy 427.879888 -409.096007) (xy 427.880272 -409.086812) (xy 427.880272 -408.593544) (xy 427.879847 -408.584358)
			(xy 427.873344 -408.567174) (xy 427.867572 -408.560016) (xy 427.845776 -408.534371) (xy 427.807825 -408.478784)
			(xy 427.77679 -408.41906) (xy 427.753116 -408.356054) (xy 427.737143 -408.290671) (xy 427.729099 -408.223847)
			(xy 427.7291 -408.156541) (xy 427.737145 -408.089717) (xy 427.75312 -408.024334) (xy 427.776795 -407.961329)
			(xy 427.807831 -407.901606) (xy 427.845783 -407.84602) (xy 427.867572 -407.820368) (xy 427.873373 -407.813227)
			(xy 427.879883 -407.796033) (xy 427.880272 -407.78684) (xy 427.880272 -407.628852) (xy 427.880682 -407.618698)
			(xy 427.888488 -407.59995) (xy 427.902887 -407.58563) (xy 427.921678 -407.577927) (xy 427.931834 -407.577544)
			(xy 428.648114 -407.577544) (xy 428.658242 -407.578015) (xy 428.676964 -407.585749) (xy 428.69132 -407.600039)
			(xy 428.699138 -407.618726) (xy 428.699676 -407.628852) (xy 428.699676 -407.78684) (xy 428.700072 -407.796029)
			(xy 428.706596 -407.813212) (xy 428.712376 -407.820368) (xy 428.734155 -407.846027) (xy 428.772104 -407.901613)
			(xy 428.803136 -407.961335) (xy 428.826809 -408.024339) (xy 428.842782 -408.08972) (xy 428.850827 -408.156542)
			(xy 428.850827 -408.223846) (xy 428.842784 -408.290668) (xy 428.826813 -408.356049) (xy 428.803141 -408.419054)
			(xy 428.77211 -408.478777) (xy 428.734163 -408.534364) (xy 428.712376 -408.560016) (xy 428.706587 -408.567167)
			(xy 428.700069 -408.584353) (xy 428.699676 -408.593544) (xy 428.699676 -409.086812) (xy 428.700086 -409.095999)
			(xy 428.7066 -409.113183) (xy 428.712376 -409.12034) (xy 428.734128 -409.146022) (xy 428.772077 -409.201604)
			(xy 428.803111 -409.261324) (xy 428.826785 -409.324324) (xy 428.84276 -409.389703) (xy 428.850806 -409.456522)
			(xy 428.85081 -409.523824) (xy 428.842769 -409.590644) (xy 428.826801 -409.656024) (xy 428.803133 -409.719027)
			(xy 428.772104 -409.778749) (xy 428.734161 -409.834335) (xy 428.712376 -409.859988) (xy 428.706557 -409.867117)
			(xy 428.700056 -409.88432) (xy 428.699676 -409.893516) (xy 428.699676 -410.051504) (xy 428.699281 -410.061661)
			(xy 428.69148 -410.080418) (xy 428.677074 -410.094742) (xy 428.658274 -410.102438) (xy 428.648114 -410.102812)
			(xy 427.931834 -410.102812) (xy 427.921716 -410.102247) (xy 427.903005 -410.09454) (xy 427.88865 -410.080278)
			(xy 427.88082 -410.061619) (xy 427.880272 -410.051504) (xy 427.880272 -409.893516) (xy 427.879861 -409.884329)
			(xy 427.873349 -409.867144) (xy 427.867572 -409.859988) (xy 427.845748 -409.834366) (xy 427.807798 -409.778776)
			(xy 427.776764 -409.719048) (xy 427.753092 -409.65604) (xy 427.73712 -409.590654) (xy 427.729079 -409.523827)
			(xy 426.600433 -409.523827) (xy 426.57197 -409.578598) (xy 426.534017 -409.634184) (xy 426.512228 -409.659836)
			(xy 426.506425 -409.666976) (xy 426.499916 -409.684171) (xy 426.499528 -409.693364) (xy 426.499528 -410.186632)
			(xy 426.499917 -410.195822) (xy 426.506445 -410.213006) (xy 426.512228 -410.22016) (xy 426.534001 -410.245825)
			(xy 426.571952 -410.301409) (xy 426.602988 -410.36113) (xy 426.626663 -410.424133) (xy 426.642638 -410.489514)
			(xy 426.650684 -410.556336) (xy 426.650686 -410.62364) (xy 426.650679 -410.623701) (xy 429.928725 -410.623701)
			(xy 429.928726 -410.556275) (xy 429.936804 -410.489336) (xy 429.952842 -410.423845) (xy 429.976609 -410.360748)
			(xy 430.007762 -410.300951) (xy 430.045854 -410.245317) (xy 430.06772 -410.219652) (xy 430.073522 -410.212511)
			(xy 430.080033 -410.195317) (xy 430.08042 -410.186124) (xy 430.08042 -409.693872) (xy 430.080019 -409.684684)
			(xy 430.073498 -409.6675) (xy 430.06772 -409.660344) (xy 430.045867 -409.634669) (xy 430.007777 -409.579037)
			(xy 429.976624 -409.519242) (xy 429.952859 -409.456146) (xy 429.936822 -409.390658) (xy 429.928745 -409.323721)
			(xy 429.928744 -409.256297) (xy 429.936819 -409.18936) (xy 429.952853 -409.123871) (xy 429.976617 -409.060775)
			(xy 430.007767 -409.000979) (xy 430.045856 -408.945345) (xy 430.06772 -408.91968) (xy 430.07351 -408.91253)
			(xy 430.080028 -408.895343) (xy 430.08042 -408.886152) (xy 430.08042 -408.728672) (xy 430.080863 -408.718559)
			(xy 430.088613 -408.699876) (xy 430.102923 -408.685582) (xy 430.121614 -408.677852) (xy 430.131728 -408.677364)
			(xy 430.848008 -408.677364) (xy 430.858113 -408.677878) (xy 430.876784 -408.685611) (xy 430.891077 -408.699899)
			(xy 430.898818 -408.718567) (xy 430.899316 -408.728672) (xy 430.899316 -408.886152) (xy 430.899745 -408.895337)
			(xy 430.906245 -408.912522) (xy 430.912016 -408.91968) (xy 430.933891 -408.945336) (xy 430.971979 -409.000972)
			(xy 431.003128 -409.06077) (xy 431.026891 -409.123868) (xy 431.042925 -409.189358) (xy 431.050999 -409.256297)
			(xy 431.050998 -409.323721) (xy 431.042922 -409.39066) (xy 431.026885 -409.456149) (xy 431.00312 -409.519247)
			(xy 431.000734 -409.523827) (xy 432.12887 -409.523827) (xy 432.128873 -409.456519) (xy 432.136921 -409.389693)
			(xy 432.152898 -409.324309) (xy 432.176576 -409.261303) (xy 432.207615 -409.201578) (xy 432.245569 -409.145992)
			(xy 432.26736 -409.12034) (xy 432.273172 -409.113206) (xy 432.279676 -409.096007) (xy 432.28006 -409.086812)
			(xy 432.28006 -408.593544) (xy 432.279615 -408.584361) (xy 432.273124 -408.567177) (xy 432.26736 -408.560016)
			(xy 432.245564 -408.53437) (xy 432.207614 -408.478784) (xy 432.17658 -408.419059) (xy 432.152907 -408.356054)
			(xy 432.136934 -408.290671) (xy 432.12889 -408.223847) (xy 432.128891 -408.156541) (xy 432.136936 -408.089717)
			(xy 432.15291 -408.024335) (xy 432.176585 -407.96133) (xy 432.20762 -407.901606) (xy 432.245571 -407.84602)
			(xy 432.26736 -407.820368) (xy 432.27316 -407.813226) (xy 432.279671 -407.796033) (xy 432.28006 -407.78684)
			(xy 432.28006 -407.628852) (xy 432.280482 -407.6187) (xy 432.288286 -407.599954) (xy 432.302681 -407.585634)
			(xy 432.321468 -407.577929) (xy 432.331622 -407.577544) (xy 433.047902 -407.577544) (xy 433.058029 -407.578025)
			(xy 433.076751 -407.585754) (xy 433.091108 -407.600042) (xy 433.098926 -407.618727) (xy 433.099464 -407.628852)
			(xy 433.099464 -407.78684) (xy 433.099863 -407.796028) (xy 433.106385 -407.813212) (xy 433.112164 -407.820368)
			(xy 433.133944 -407.846027) (xy 433.171893 -407.901612) (xy 433.202926 -407.961335) (xy 433.226599 -408.024339)
			(xy 433.242573 -408.08972) (xy 433.250618 -408.156542) (xy 433.250618 -408.223846) (xy 433.242575 -408.290668)
			(xy 433.226603 -408.35605) (xy 433.202931 -408.419054) (xy 433.171899 -408.478778) (xy 433.133951 -408.534364)
			(xy 433.112164 -408.560016) (xy 433.106374 -408.567165) (xy 433.099856 -408.584353) (xy 433.099464 -408.593544)
			(xy 433.099464 -409.086812) (xy 433.099876 -409.095999) (xy 433.106389 -409.113183) (xy 433.112164 -409.12034)
			(xy 433.133916 -409.146021) (xy 433.171866 -409.201604) (xy 433.2029 -409.261323) (xy 433.226575 -409.324324)
			(xy 433.24255 -409.389703) (xy 433.250597 -409.456522) (xy 433.250601 -409.523824) (xy 433.24256 -409.590644)
			(xy 433.226591 -409.656024) (xy 433.202922 -409.719027) (xy 433.171894 -409.77875) (xy 433.133949 -409.834336)
			(xy 433.112164 -409.859988) (xy 433.106343 -409.867116) (xy 433.099844 -409.88432) (xy 433.099464 -409.893516)
			(xy 433.099464 -410.051504) (xy 433.099081 -410.061663) (xy 433.091277 -410.080422) (xy 433.076868 -410.094747)
			(xy 433.058063 -410.10244) (xy 433.047902 -410.102812) (xy 432.331622 -410.102812) (xy 432.321503 -410.102257)
			(xy 432.302792 -410.094546) (xy 432.288437 -410.080281) (xy 432.280608 -410.06162) (xy 432.28006 -410.051504)
			(xy 432.28006 -409.893516) (xy 432.279629 -409.884331) (xy 432.273128 -409.867147) (xy 432.26736 -409.859988)
			(xy 432.245536 -409.834365) (xy 432.207587 -409.778775) (xy 432.176554 -409.719048) (xy 432.152882 -409.656039)
			(xy 432.136911 -409.590653) (xy 432.12887 -409.523827) (xy 431.000734 -409.523827) (xy 430.971969 -409.579043)
			(xy 430.93388 -409.634678) (xy 430.912016 -409.660344) (xy 430.90622 -409.66749) (xy 430.899705 -409.68468)
			(xy 430.899316 -409.693872) (xy 430.899316 -410.186124) (xy 430.899711 -410.195313) (xy 430.906235 -410.212497)
			(xy 430.912016 -410.219652) (xy 430.933864 -410.24533) (xy 430.971952 -410.300963) (xy 431.003102 -410.360758)
			(xy 431.026867 -410.423853) (xy 431.042903 -410.48934) (xy 431.05098 -410.556277) (xy 431.050981 -410.623641)
			(xy 434.329044 -410.623641) (xy 434.329046 -410.556335) (xy 434.337091 -410.489512) (xy 434.353065 -410.424129)
			(xy 434.376738 -410.361124) (xy 434.407772 -410.3014) (xy 434.44572 -410.245813) (xy 434.467508 -410.22016)
			(xy 434.473305 -410.213015) (xy 434.479819 -410.195824) (xy 434.480208 -410.186632) (xy 434.480208 -409.693364)
			(xy 434.479814 -409.684175) (xy 434.473289 -409.666991) (xy 434.467508 -409.659836) (xy 434.445733 -409.634174)
			(xy 434.407786 -409.578588) (xy 434.376754 -409.518866) (xy 434.353082 -409.455862) (xy 434.337109 -409.390482)
			(xy 434.329064 -409.323661) (xy 434.329063 -409.256357) (xy 434.337106 -409.189536) (xy 434.353076 -409.124155)
			(xy 434.376746 -409.061151) (xy 434.407777 -409.001427) (xy 434.445722 -408.945841) (xy 434.467508 -408.920188)
			(xy 434.473293 -408.913035) (xy 434.479814 -408.89585) (xy 434.480208 -408.88666) (xy 434.480208 -408.728672)
			(xy 434.480599 -408.718515) (xy 434.488405 -408.69976) (xy 434.502811 -408.685438) (xy 434.521611 -408.67774)
			(xy 434.53177 -408.677364) (xy 435.24805 -408.677364) (xy 435.258176 -408.677868) (xy 435.276901 -408.685584)
			(xy 435.29126 -408.699866) (xy 435.299077 -408.718548) (xy 435.299612 -408.728672) (xy 435.299612 -408.88666)
			(xy 435.300039 -408.895846) (xy 435.30654 -408.91303) (xy 435.312312 -408.920188) (xy 435.334113 -408.94583)
			(xy 435.372065 -409.001417) (xy 435.4031 -409.061141) (xy 435.426774 -409.124147) (xy 435.442748 -409.189531)
			(xy 435.450792 -409.256356) (xy 435.450791 -409.323662) (xy 435.442745 -409.390487) (xy 435.426769 -409.45587)
			(xy 435.403093 -409.518875) (xy 435.372055 -409.578599) (xy 435.334102 -409.634184) (xy 435.312312 -409.659836)
			(xy 435.306519 -409.666984) (xy 435.300002 -409.684172) (xy 435.299612 -409.693364) (xy 435.299612 -410.186632)
			(xy 435.300004 -410.195821) (xy 435.30653 -410.213006) (xy 435.312312 -410.22016) (xy 435.334085 -410.245824)
			(xy 435.372038 -410.301408) (xy 435.403075 -410.361129) (xy 435.42675 -410.424132) (xy 435.442726 -410.489514)
			(xy 435.450772 -410.556336) (xy 435.450774 -410.62364) (xy 435.44273 -410.690463) (xy 435.426758 -410.755845)
			(xy 435.403084 -410.818849) (xy 435.37205 -410.878571) (xy 435.3341 -410.934157) (xy 435.312312 -410.959808)
			(xy 435.306531 -410.966964) (xy 435.300007 -410.984146) (xy 435.299612 -410.993336) (xy 435.299612 -411.151324)
			(xy 435.299198 -411.161478) (xy 435.291397 -411.180229) (xy 435.276998 -411.194551) (xy 435.258206 -411.202252)
			(xy 435.24805 -411.202632) (xy 434.53177 -411.202632) (xy 434.521638 -411.202197) (xy 434.502911 -411.194454)
			(xy 434.488554 -411.180152) (xy 434.480741 -411.161454) (xy 434.480208 -411.151324) (xy 434.480208 -410.993336)
			(xy 434.479779 -410.984151) (xy 434.473278 -410.966966) (xy 434.467508 -410.959808) (xy 434.445706 -410.934168)
			(xy 434.407759 -410.878579) (xy 434.376728 -410.818854) (xy 434.353058 -410.755848) (xy 434.337087 -410.690464)
			(xy 434.329044 -410.623641) (xy 431.050981 -410.623641) (xy 431.050981 -410.623699) (xy 431.042907 -410.690636)
			(xy 431.026874 -410.756124) (xy 431.003112 -410.81922) (xy 430.971964 -410.879016) (xy 430.933878 -410.934651)
			(xy 430.912016 -410.960316) (xy 430.906232 -410.96747) (xy 430.899709 -410.984654) (xy 430.899316 -410.993844)
			(xy 430.899316 -411.151324) (xy 430.898835 -411.161432) (xy 430.891092 -411.180108) (xy 430.876795 -411.194401)
			(xy 430.858116 -411.202138) (xy 430.848008 -411.202632) (xy 430.131728 -411.202632) (xy 430.121611 -411.202162)
			(xy 430.102914 -411.194429) (xy 430.0886 -411.180129) (xy 430.080848 -411.16144) (xy 430.08042 -411.151324)
			(xy 430.08042 -410.993844) (xy 430.079984 -410.98466) (xy 430.073488 -410.967475) (xy 430.06772 -410.960316)
			(xy 430.04584 -410.934664) (xy 430.00775 -410.879028) (xy 429.976599 -410.81923) (xy 429.952835 -410.756132)
			(xy 429.9368 -410.690641) (xy 429.928725 -410.623701) (xy 426.650679 -410.623701) (xy 426.642643 -410.690462)
			(xy 426.62667 -410.755844) (xy 426.602998 -410.818848) (xy 426.571965 -410.878571) (xy 426.534016 -410.934156)
			(xy 426.512228 -410.959808) (xy 426.506437 -410.966957) (xy 426.499921 -410.984145) (xy 426.499528 -410.993336)
			(xy 426.499528 -411.151324) (xy 426.499099 -411.161476) (xy 426.4913 -411.180224) (xy 426.476907 -411.194545)
			(xy 426.45812 -411.202249) (xy 426.447966 -411.202632) (xy 425.731686 -411.202632) (xy 425.721555 -411.202184)
			(xy 425.702828 -411.194446) (xy 425.688472 -411.180148) (xy 425.680658 -411.161453) (xy 425.680124 -411.151324)
			(xy 425.680124 -410.993336) (xy 425.679691 -410.984151) (xy 425.673193 -410.966967) (xy 425.667424 -410.959808)
			(xy 425.645621 -410.934169) (xy 425.607674 -410.87858) (xy 425.576642 -410.818855) (xy 425.552971 -410.755848)
			(xy 425.536999 -410.690465) (xy 425.528957 -410.623641) (xy 422.250893 -410.623641) (xy 422.250893 -410.623699)
			(xy 422.242819 -410.690635) (xy 422.226787 -410.756123) (xy 422.203026 -410.819219) (xy 422.171879 -410.879015)
			(xy 422.133794 -410.93465) (xy 422.111932 -410.960316) (xy 422.106138 -410.967463) (xy 422.099624 -410.984652)
			(xy 422.099232 -410.993844) (xy 422.099232 -411.151324) (xy 422.098735 -411.16143) (xy 422.090996 -411.180103)
			(xy 422.076703 -411.194396) (xy 422.05803 -411.202135) (xy 422.047924 -411.202632) (xy 421.331644 -411.202632)
			(xy 421.321528 -411.202149) (xy 421.302832 -411.194421) (xy 421.288517 -411.180125) (xy 421.280765 -411.161439)
			(xy 421.280336 -411.151324) (xy 421.280336 -410.993844) (xy 421.279896 -410.98466) (xy 421.273402 -410.967476)
			(xy 421.267636 -410.960316) (xy 421.245755 -410.934664) (xy 421.207664 -410.879029) (xy 421.176512 -410.819231)
			(xy 421.152748 -410.756132) (xy 421.136712 -410.690641) (xy 421.128637 -410.623701) (xy 414.525968 -410.623701)
			(xy 414.525968 -417.366196) (xy 414.52546 -417.366196) (xy 414.52546 -417.533836) (xy 414.525117 -417.545925)
			(xy 414.517634 -417.568917) (xy 414.503411 -417.588471) (xy 414.483842 -417.602672) (xy 414.460842 -417.61013)
			(xy 414.448752 -417.610544) (xy 401.15109 -417.610544) (xy 401.138998 -417.610101) (xy 401.115995 -417.602639)
			(xy 401.096414 -417.588447) (xy 401.082164 -417.568908) (xy 401.074635 -417.545926) (xy 401.074128 -417.533836)
			(xy 326.525636 -417.533836) (xy 326.525172 -417.545885) (xy 326.517733 -417.568805) (xy 326.503592 -417.588317)
			(xy 326.484126 -417.602521) (xy 326.461229 -417.610032) (xy 326.449182 -417.610544) (xy 313.151012 -417.610544)
			(xy 313.138942 -417.610026) (xy 313.115981 -417.602571) (xy 313.096447 -417.588387) (xy 313.082251 -417.568862)
			(xy 313.074781 -417.545906) (xy 313.074304 -417.533836) (xy 313.074304 -417.379404) (xy 313.073796 -417.379404)
			(xy 273.434939 -417.379404) (xy 273.506495 -417.442585) (xy 273.605798 -417.540617) (xy 273.652996 -417.592002)
			(xy 273.691387 -417.633573) (xy 273.773525 -417.71142) (xy 273.861325 -417.782821) (xy 273.954282 -417.847364)
			(xy 274.051862 -417.90468) (xy 274.153504 -417.954438) (xy 274.258623 -417.996352) (xy 274.366616 -418.030181)
			(xy 274.476862 -418.055732) (xy 274.588726 -418.072856) (xy 274.701566 -418.081457) (xy 274.75815 -418.081968)
			(xy 465.600034 -418.081968) (xy 465.65584 -418.081445) (xy 465.767139 -418.073102) (xy 465.877504 -418.056464)
			(xy 465.986317 -418.031626) (xy 466.092969 -417.998726) (xy 466.196865 -417.957947) (xy 466.297422 -417.909518)
			(xy 466.39408 -417.85371) (xy 466.486296 -417.790835) (xy 466.573556 -417.721245) (xy 466.655372 -417.645328)
			(xy 466.731285 -417.563509) (xy 466.800872 -417.476246) (xy 466.863743 -417.384027) (xy 466.919547 -417.287367)
			(xy 466.967972 -417.186808) (xy 467.008746 -417.082911) (xy 467.041642 -416.976257) (xy 467.066476 -416.867443)
			(xy 467.083109 -416.757078) (xy 467.091447 -416.645778) (xy 467.09203 -416.589972) (xy 467.09203 -246.48795)
			(xy 467.091546 -246.4347) (xy 467.083933 -246.328473) (xy 467.068764 -246.223059) (xy 467.046116 -246.118995)
			(xy 467.016104 -246.016811) (xy 466.978881 -245.917028) (xy 466.934637 -245.820154) (xy 466.883597 -245.726681)
			(xy 466.82602 -245.637087) (xy 466.762201 -245.551827) (xy 466.692464 -245.471335) (xy 466.65515 -245.433342)
			(xy 464.026504 -242.80495) (xy 463.9771 -242.754859) (xy 463.883341 -242.649941) (xy 463.795613 -242.53993)
			(xy 463.714192 -242.425173) (xy 463.639333 -242.306031) (xy 463.571273 -242.182879) (xy 463.510225 -242.056105)
			(xy 463.456381 -241.926107) (xy 463.409911 -241.793295) (xy 463.370962 -241.658086) (xy 463.339655 -241.520905)
			(xy 463.31609 -241.382185) (xy 463.300339 -241.242362) (xy 463.292454 -241.101876) (xy 463.291936 -241.031522)
			(xy 463.291936 -87.588344) (xy 463.292417 -87.517998) (xy 463.3003 -87.377526) (xy 463.316048 -87.237717)
			(xy 463.339614 -87.099011) (xy 463.370921 -86.961846) (xy 463.409872 -86.826652) (xy 463.456344 -86.693856)
			(xy 463.510191 -86.563875) (xy 463.571243 -86.437119) (xy 463.639308 -86.313987) (xy 463.714172 -86.194865)
			(xy 463.7956 -86.08013) (xy 463.883333 -85.970143) (xy 463.977098 -85.865249) (xy 464.026504 -85.81517)
			(xy 466.65515 -83.186524) (xy 466.692477 -83.148543) (xy 466.762224 -83.068056) (xy 466.826051 -82.982799)
			(xy 466.883632 -82.893206) (xy 466.934676 -82.799733) (xy 466.978921 -82.702856) (xy 467.016141 -82.60307)
			(xy 467.046149 -82.500883) (xy 467.068789 -82.396815) (xy 467.083947 -82.291397) (xy 467.091547 -82.185167)
			(xy 467.09203 -82.131916) (xy 467.09203 -1.999996) (xy 467.091508 -1.944189) (xy 467.083167 -1.832886)
			(xy 467.066532 -1.722518) (xy 467.041695 -1.613701) (xy 467.008796 -1.507045) (xy 466.968019 -1.403146)
			(xy 466.919592 -1.302584) (xy 466.863785 -1.205923) (xy 466.800911 -1.113702) (xy 466.731321 -1.026437)
			(xy 466.655404 -0.944617) (xy 466.573586 -0.868699) (xy 466.486322 -0.799107) (xy 466.394103 -0.736231)
			(xy 466.297442 -0.680422) (xy 466.196882 -0.631993) (xy 466.092983 -0.591214) (xy 465.986328 -0.558313)
			(xy 465.877512 -0.533474) (xy 465.767144 -0.516836) (xy 465.655841 -0.508493) (xy 465.600034 -0.508)
			(xy 446.265046 -0.508) (xy 446.209237 -0.508508) (xy 446.097932 -0.516845) (xy 445.987561 -0.533478)
			(xy 445.878741 -0.558312) (xy 445.772082 -0.591209) (xy 445.668179 -0.631985) (xy 445.567615 -0.680412)
			(xy 445.47095 -0.736218) (xy 445.378726 -0.799093) (xy 445.291459 -0.868683) (xy 445.209636 -0.944601)
			(xy 445.133716 -1.026421) (xy 445.064123 -1.113686) (xy 445.001245 -1.205908) (xy 444.945435 -1.30257)
			(xy 444.897005 -1.403134) (xy 444.856226 -1.507035) (xy 444.823325 -1.613693) (xy 444.798487 -1.722512)
			(xy 444.781851 -1.832882) (xy 444.773509 -1.944187) (xy 444.77305 -1.999996) (xy 444.77305 -11.850116)
			(xy 444.77258 -11.903957) (xy 444.764897 -12.011363) (xy 444.749571 -12.117948) (xy 444.726681 -12.223168)
			(xy 444.696342 -12.326487) (xy 444.65871 -12.427378) (xy 444.613976 -12.525327) (xy 444.562368 -12.619836)
			(xy 444.504149 -12.710422) (xy 444.439617 -12.796624) (xy 444.369099 -12.878002) (xy 444.292955 -12.954143)
			(xy 444.211574 -13.024657) (xy 444.125369 -13.089186) (xy 444.034781 -13.147401) (xy 443.94027 -13.199004)
			(xy 443.842319 -13.243734) (xy 443.741426 -13.281362) (xy 443.638106 -13.311696) (xy 443.532885 -13.334583)
			(xy 443.4263 -13.349904) (xy 443.318893 -13.357583) (xy 443.265052 -13.358114) (xy 435.265068 -13.358114)
			(xy 435.211227 -13.357632) (xy 435.103821 -13.349948) (xy 434.997236 -13.334622) (xy 434.892016 -13.311731)
			(xy 434.788697 -13.281392) (xy 434.687806 -13.24376) (xy 434.589856 -13.199026) (xy 434.495347 -13.147419)
			(xy 434.40476 -13.089201) (xy 434.318558 -13.024669) (xy 434.237178 -12.954153) (xy 434.161036 -12.87801)
			(xy 434.090521 -12.79663) (xy 434.02599 -12.710426) (xy 433.967773 -12.619839) (xy 433.916167 -12.52533)
			(xy 433.871434 -12.42738) (xy 433.833803 -12.326488) (xy 433.803465 -12.223169) (xy 433.780576 -12.117948)
			(xy 433.76525 -12.011363) (xy 433.757567 -11.903957) (xy 433.75707 -11.850116) (xy 433.75707 -1.999996)
			(xy 433.756561 -1.944189) (xy 433.748219 -1.832887) (xy 433.731584 -1.72252) (xy 433.706747 -1.613704)
			(xy 433.673847 -1.507049) (xy 433.633069 -1.40315) (xy 433.584641 -1.30259) (xy 433.528833 -1.20593)
			(xy 433.465958 -1.11371) (xy 433.396367 -1.026448) (xy 433.320449 -0.944629) (xy 433.23863 -0.868713)
			(xy 433.151366 -0.799124) (xy 433.059145 -0.736251) (xy 432.962484 -0.680445) (xy 432.861922 -0.632019)
			(xy 432.758023 -0.591243) (xy 432.651367 -0.558346) (xy 432.542551 -0.533511) (xy 432.432183 -0.516877)
			(xy 432.320881 -0.508538) (xy 432.265074 -0.508) (xy 420.265098 -0.508) (xy 420.209291 -0.508522)
			(xy 420.097989 -0.516863) (xy 419.987622 -0.533498) (xy 419.878806 -0.558335) (xy 419.772151 -0.591234)
			(xy 419.668252 -0.632011) (xy 419.567691 -0.680438) (xy 419.471031 -0.736245) (xy 419.378811 -0.79912)
			(xy 419.291547 -0.86871) (xy 419.209728 -0.944627) (xy 419.133811 -1.026446) (xy 419.064221 -1.113709)
			(xy 419.001346 -1.205929) (xy 418.945539 -1.302589) (xy 418.897112 -1.40315) (xy 418.856334 -1.507049)
			(xy 418.823435 -1.613704) (xy 418.798599 -1.72252) (xy 418.781963 -1.832887) (xy 418.773622 -1.944189)
			(xy 418.773102 -1.999996) (xy 418.773102 -11.850116) (xy 418.772621 -11.903957) (xy 418.764938 -12.011364)
			(xy 418.749612 -12.117949) (xy 418.726722 -12.22317) (xy 418.696384 -12.326489) (xy 418.658752 -12.427381)
			(xy 418.614019 -12.525332) (xy 418.562412 -12.619841) (xy 418.504194 -12.710429) (xy 418.439663 -12.796632)
			(xy 418.369146 -12.878012) (xy 418.293003 -12.954154) (xy 418.211622 -13.02467) (xy 418.125419 -13.089201)
			(xy 418.034831 -13.147418) (xy 417.940321 -13.199024) (xy 417.84237 -13.243756) (xy 417.741478 -13.281387)
			(xy 417.638158 -13.311725) (xy 417.532938 -13.334614) (xy 417.426352 -13.349939) (xy 417.318945 -13.357621)
			(xy 417.265104 -13.358114) (xy 409.26512 -13.358114) (xy 409.211278 -13.357646) (xy 409.103868 -13.349965)
			(xy 408.997279 -13.334641) (xy 408.892055 -13.311753) (xy 408.788733 -13.281416) (xy 408.687837 -13.243785)
			(xy 408.589884 -13.199053) (xy 408.495371 -13.147446) (xy 408.40478 -13.089229) (xy 408.318573 -13.024697)
			(xy 408.23719 -12.95418) (xy 408.161045 -12.878036) (xy 408.090526 -12.796655) (xy 408.025992 -12.71045)
			(xy 407.967772 -12.61986) (xy 407.916164 -12.525349) (xy 407.871429 -12.427396) (xy 407.833796 -12.326502)
			(xy 407.803456 -12.223179) (xy 407.780565 -12.117956) (xy 407.765239 -12.011368) (xy 407.757556 -11.903958)
			(xy 407.757122 -11.850116) (xy 407.757122 -1.999996) (xy 407.7566 -1.944189) (xy 407.748259 -1.832886)
			(xy 407.731624 -1.722518) (xy 407.706787 -1.613702) (xy 407.673888 -1.507046) (xy 407.633111 -1.403147)
			(xy 407.584684 -1.302586) (xy 407.528877 -1.205924) (xy 407.466002 -1.113704) (xy 407.396412 -1.02644)
			(xy 407.320496 -0.94462) (xy 407.238677 -0.868702) (xy 407.151414 -0.799111) (xy 407.059194 -0.736235)
			(xy 406.962534 -0.680427) (xy 406.861973 -0.631998) (xy 406.758075 -0.591219) (xy 406.651419 -0.558319)
			(xy 406.542603 -0.53348) (xy 406.432236 -0.516843) (xy 406.320933 -0.508501) (xy 406.265126 -0.508)
			(xy 394.264896 -0.508) (xy 394.209089 -0.508522) (xy 394.097787 -0.516863) (xy 393.98742 -0.533498)
			(xy 393.878604 -0.558335) (xy 393.771949 -0.591234) (xy 393.668051 -0.632011) (xy 393.56749 -0.680439)
			(xy 393.470829 -0.736246) (xy 393.37861 -0.799121) (xy 393.291346 -0.868711) (xy 393.209528 -0.944628)
			(xy 393.133611 -1.026446) (xy 393.064021 -1.11371) (xy 393.001146 -1.205929) (xy 392.945339 -1.30259)
			(xy 392.896911 -1.403151) (xy 392.856134 -1.507049) (xy 392.823235 -1.613704) (xy 392.798398 -1.72252)
			(xy 392.781763 -1.832887) (xy 392.773422 -1.944189) (xy 392.7729 -1.999996) (xy 392.7729 -11.850116)
			(xy 392.772419 -11.903957) (xy 392.764736 -12.011364) (xy 392.74941 -12.117949) (xy 392.72652 -12.22317)
			(xy 392.696182 -12.326489) (xy 392.65855 -12.427381) (xy 392.613817 -12.525331) (xy 392.56221 -12.619841)
			(xy 392.503992 -12.710428) (xy 392.43946 -12.796631) (xy 392.368944 -12.878011) (xy 392.292801 -12.954153)
			(xy 392.21142 -13.024669) (xy 392.125217 -13.0892) (xy 392.034629 -13.147417) (xy 391.940119 -13.199023)
			(xy 391.842168 -13.243755) (xy 391.741276 -13.281386) (xy 391.637956 -13.311723) (xy 391.532735 -13.334613)
			(xy 391.42615 -13.349937) (xy 391.318743 -13.357619) (xy 391.264902 -13.358114) (xy 383.264918 -13.358114)
			(xy 383.211076 -13.357645) (xy 383.103666 -13.349965) (xy 382.997077 -13.334641) (xy 382.891854 -13.311752)
			(xy 382.788531 -13.281415) (xy 382.687636 -13.243785) (xy 382.589682 -13.199052) (xy 382.495169 -13.147445)
			(xy 382.404579 -13.089228) (xy 382.318373 -13.024696) (xy 382.236989 -12.954179) (xy 382.160844 -12.878035)
			(xy 382.090325 -12.796654) (xy 382.025791 -12.710449) (xy 381.967572 -12.61986) (xy 381.915963 -12.525348)
			(xy 381.871228 -12.427396) (xy 381.833596 -12.326501) (xy 381.803256 -12.223179) (xy 381.780365 -12.117956)
			(xy 381.765039 -12.011368) (xy 381.757356 -11.903958) (xy 381.75692 -11.850116) (xy 381.75692 -1.999996)
			(xy 381.756398 -1.944189) (xy 381.748057 -1.832886) (xy 381.731422 -1.722518) (xy 381.706585 -1.613702)
			(xy 381.673686 -1.507047) (xy 381.632909 -1.403147) (xy 381.584482 -1.302586) (xy 381.528675 -1.205925)
			(xy 381.4658 -1.113704) (xy 381.39621 -1.02644) (xy 381.320294 -0.944621) (xy 381.238475 -0.868703)
			(xy 381.151212 -0.799112) (xy 381.058992 -0.736236) (xy 380.962332 -0.680428) (xy 380.861771 -0.631999)
			(xy 380.757872 -0.59122) (xy 380.651217 -0.55832) (xy 380.542401 -0.533482) (xy 380.432034 -0.516845)
			(xy 380.320731 -0.508503) (xy 380.264924 -0.508) (xy 368.264948 -0.508) (xy 368.209139 -0.508507)
			(xy 368.097834 -0.516845) (xy 367.987463 -0.533478) (xy 367.878643 -0.558312) (xy 367.771984 -0.591209)
			(xy 367.668081 -0.631985) (xy 367.567516 -0.680411) (xy 367.470851 -0.736218) (xy 367.378627 -0.799092)
			(xy 367.29136 -0.868683) (xy 367.209537 -0.9446) (xy 367.133617 -1.02642) (xy 367.064023 -1.113685)
			(xy 367.001145 -1.205907) (xy 366.945336 -1.30257) (xy 366.896905 -1.403133) (xy 366.856126 -1.507034)
			(xy 366.823225 -1.613693) (xy 366.798387 -1.722511) (xy 366.781751 -1.832882) (xy 366.773409 -1.944187)
			(xy 366.772952 -1.999996) (xy 366.772952 -11.850116) (xy 366.772482 -11.903957) (xy 366.764799 -12.011363)
			(xy 366.749473 -12.117948) (xy 366.726583 -12.223168) (xy 366.696244 -12.326487) (xy 366.658612 -12.427378)
			(xy 366.613878 -12.525328) (xy 366.56227 -12.619836) (xy 366.504051 -12.710422) (xy 366.439519 -12.796624)
			(xy 366.369001 -12.878003) (xy 366.292858 -12.954143) (xy 366.211476 -13.024658) (xy 366.125271 -13.089187)
			(xy 366.034683 -13.147402) (xy 365.940172 -13.199005) (xy 365.842221 -13.243735) (xy 365.741328 -13.281363)
			(xy 365.638008 -13.311698) (xy 365.532787 -13.334584) (xy 365.426202 -13.349906) (xy 365.318795 -13.357584)
			(xy 365.264954 -13.358114) (xy 357.26497 -13.358114) (xy 357.211129 -13.357632) (xy 357.103723 -13.349948)
			(xy 356.997138 -13.334622) (xy 356.891918 -13.311731) (xy 356.788599 -13.281392) (xy 356.687707 -13.24376)
			(xy 356.589757 -13.199027) (xy 356.495248 -13.147419) (xy 356.404661 -13.089202) (xy 356.318459 -13.02467)
			(xy 356.237079 -12.954153) (xy 356.160937 -12.878011) (xy 356.090421 -12.796631) (xy 356.02589 -12.710427)
			(xy 355.967673 -12.61984) (xy 355.916067 -12.52533) (xy 355.871335 -12.42738) (xy 355.833703 -12.326488)
			(xy 355.803366 -12.223169) (xy 355.780476 -12.117949) (xy 355.76515 -12.011363) (xy 355.757467 -11.903957)
			(xy 355.756972 -11.850116) (xy 355.756972 -1.999996) (xy 355.756463 -1.944189) (xy 355.748121 -1.832887)
			(xy 355.731486 -1.722519) (xy 355.706649 -1.613704) (xy 355.673749 -1.507049) (xy 355.632971 -1.40315)
			(xy 355.584543 -1.30259) (xy 355.528735 -1.205929) (xy 355.46586 -1.11371) (xy 355.396269 -1.026447)
			(xy 355.320352 -0.944629) (xy 355.238532 -0.868713) (xy 355.151268 -0.799123) (xy 355.059047 -0.73625)
			(xy 354.962386 -0.680444) (xy 354.861824 -0.632017) (xy 354.757925 -0.591241) (xy 354.651269 -0.558344)
			(xy 354.542453 -0.533509) (xy 354.432085 -0.516876) (xy 354.320783 -0.508536) (xy 354.264976 -0.508)
			(xy 330.164948 -0.508) (xy 330.109139 -0.508507) (xy 329.997834 -0.516845) (xy 329.887463 -0.533478)
			(xy 329.778643 -0.558312) (xy 329.671984 -0.591209) (xy 329.568081 -0.631985) (xy 329.467516 -0.680411)
			(xy 329.370851 -0.736218) (xy 329.278627 -0.799092) (xy 329.19136 -0.868683) (xy 329.109537 -0.9446)
			(xy 329.033617 -1.02642) (xy 328.964023 -1.113685) (xy 328.901145 -1.205907) (xy 328.845336 -1.30257)
			(xy 328.796905 -1.403133) (xy 328.756126 -1.507034) (xy 328.723225 -1.613693) (xy 328.698387 -1.722511)
			(xy 328.681751 -1.832882) (xy 328.673409 -1.944187) (xy 328.672952 -1.999996) (xy 328.672952 -11.850116)
			(xy 328.672482 -11.903957) (xy 328.664799 -12.011363) (xy 328.649473 -12.117948) (xy 328.626583 -12.223168)
			(xy 328.596244 -12.326487) (xy 328.558612 -12.427378) (xy 328.513878 -12.525328) (xy 328.46227 -12.619836)
			(xy 328.404051 -12.710422) (xy 328.339519 -12.796624) (xy 328.269001 -12.878003) (xy 328.192858 -12.954143)
			(xy 328.111476 -13.024658) (xy 328.025271 -13.089187) (xy 327.934683 -13.147402) (xy 327.840172 -13.199005)
			(xy 327.742221 -13.243735) (xy 327.641328 -13.281363) (xy 327.538008 -13.311698) (xy 327.432787 -13.334584)
			(xy 327.326202 -13.349906) (xy 327.218795 -13.357584) (xy 327.164954 -13.358114) (xy 319.16497 -13.358114)
			(xy 319.111129 -13.357632) (xy 319.003723 -13.349948) (xy 318.897138 -13.334622) (xy 318.791918 -13.311731)
			(xy 318.688599 -13.281392) (xy 318.587707 -13.24376) (xy 318.489757 -13.199027) (xy 318.395248 -13.147419)
			(xy 318.304661 -13.089202) (xy 318.218459 -13.02467) (xy 318.137079 -12.954153) (xy 318.060937 -12.878011)
			(xy 317.990421 -12.796631) (xy 317.92589 -12.710427) (xy 317.867673 -12.61984) (xy 317.816067 -12.52533)
			(xy 317.771335 -12.42738) (xy 317.733703 -12.326488) (xy 317.703366 -12.223169) (xy 317.680476 -12.117949)
			(xy 317.66515 -12.011363) (xy 317.657467 -11.903957) (xy 317.656972 -11.850116) (xy 317.656972 -1.999996)
			(xy 317.656463 -1.944189) (xy 317.648121 -1.832887) (xy 317.631486 -1.722519) (xy 317.606649 -1.613704)
			(xy 317.573749 -1.507049) (xy 317.532971 -1.40315) (xy 317.484543 -1.30259) (xy 317.428735 -1.205929)
			(xy 317.36586 -1.11371) (xy 317.296269 -1.026447) (xy 317.220352 -0.944629) (xy 317.138532 -0.868713)
			(xy 317.051268 -0.799123) (xy 316.959047 -0.73625) (xy 316.862386 -0.680444) (xy 316.761824 -0.632017)
			(xy 316.657925 -0.591241) (xy 316.551269 -0.558344) (xy 316.442453 -0.533509) (xy 316.332085 -0.516876)
			(xy 316.220783 -0.508536) (xy 316.164976 -0.508) (xy 304.165 -0.508) (xy 304.109193 -0.508522) (xy 303.997891 -0.516863)
			(xy 303.887523 -0.533498) (xy 303.778708 -0.558334) (xy 303.672052 -0.591233) (xy 303.568153 -0.63201)
			(xy 303.467592 -0.680438) (xy 303.370932 -0.736245) (xy 303.278712 -0.799119) (xy 303.191448 -0.868709)
			(xy 303.109629 -0.944626) (xy 303.033712 -1.026445) (xy 302.964122 -1.113708) (xy 302.901247 -1.205928)
			(xy 302.84544 -1.302589) (xy 302.797012 -1.40315) (xy 302.756234 -1.507048) (xy 302.723335 -1.613704)
			(xy 302.698499 -1.722519) (xy 302.681863 -1.832887) (xy 302.673522 -1.944189) (xy 302.673004 -1.999996)
			(xy 302.673004 -11.850116) (xy 302.672523 -11.903957) (xy 302.66484 -12.011364) (xy 302.649514 -12.11795)
			(xy 302.626624 -12.22317) (xy 302.596286 -12.32649) (xy 302.558654 -12.427382) (xy 302.513921 -12.525332)
			(xy 302.462314 -12.619842) (xy 302.404096 -12.710429) (xy 302.339565 -12.796632) (xy 302.269048 -12.878012)
			(xy 302.192905 -12.954155) (xy 302.111525 -13.024671) (xy 302.025321 -13.089202) (xy 301.934733 -13.147419)
			(xy 301.840223 -13.199025) (xy 301.742272 -13.243758) (xy 301.64138 -13.281389) (xy 301.53806 -13.311726)
			(xy 301.43284 -13.334616) (xy 301.326254 -13.349941) (xy 301.218847 -13.357623) (xy 301.165006 -13.358114)
			(xy 293.165022 -13.358114) (xy 293.11118 -13.357646) (xy 293.00377 -13.349965) (xy 292.897181 -13.334641)
			(xy 292.791957 -13.311753) (xy 292.688634 -13.281416) (xy 292.587739 -13.243786) (xy 292.489785 -13.199053)
			(xy 292.395272 -13.147447) (xy 292.304681 -13.089229) (xy 292.218474 -13.024698) (xy 292.137091 -12.95418)
			(xy 292.060946 -12.878037) (xy 291.990426 -12.796655) (xy 291.925892 -12.71045) (xy 291.867673 -12.619861)
			(xy 291.816064 -12.525349) (xy 291.771329 -12.427396) (xy 291.733696 -12.326502) (xy 291.703356 -12.22318)
			(xy 291.680465 -12.117956) (xy 291.665139 -12.011368) (xy 291.657456 -11.903958) (xy 291.657024 -11.850116)
			(xy 291.657024 -1.999996) (xy 291.656502 -1.944189) (xy 291.648161 -1.832886) (xy 291.631526 -1.722518)
			(xy 291.606689 -1.613702) (xy 291.57379 -1.507046) (xy 291.533013 -1.403147) (xy 291.484586 -1.302585)
			(xy 291.428779 -1.205924) (xy 291.365905 -1.113703) (xy 291.296314 -1.026439) (xy 291.220398 -0.944619)
			(xy 291.138579 -0.868701) (xy 291.051316 -0.79911) (xy 290.959096 -0.736234) (xy 290.862436 -0.680426)
			(xy 290.761875 -0.631997) (xy 290.657977 -0.591218) (xy 290.551321 -0.558317) (xy 290.442505 -0.533479)
			(xy 290.332138 -0.516842) (xy 290.220835 -0.508499) (xy 290.165028 -0.508) (xy 278.165052 -0.508)
			(xy 278.109246 -0.508523) (xy 277.997947 -0.516868) (xy 277.887582 -0.533506) (xy 277.778769 -0.558345)
			(xy 277.672116 -0.591246) (xy 277.568221 -0.632024) (xy 277.467663 -0.680453) (xy 277.371005 -0.736261)
			(xy 277.278789 -0.799136) (xy 277.191528 -0.868726) (xy 277.109712 -0.944643) (xy 277.033798 -1.026461)
			(xy 276.96421 -1.113724) (xy 276.901338 -1.205943) (xy 276.845533 -1.302602) (xy 276.797107 -1.403161)
			(xy 276.756331 -1.507058) (xy 276.723433 -1.613711) (xy 276.698598 -1.722525) (xy 276.681963 -1.83289)
			(xy 276.673622 -1.94419) (xy 276.673056 -1.999996) (xy 276.673056 -11.850116) (xy 276.672586 -11.903957)
			(xy 276.664903 -12.011363) (xy 276.649577 -12.117948) (xy 276.626687 -12.223169) (xy 276.596348 -12.326487)
			(xy 276.558716 -12.427379) (xy 276.513982 -12.525328) (xy 276.462374 -12.619837) (xy 276.404156 -12.710423)
			(xy 276.339623 -12.796626) (xy 276.269105 -12.878004) (xy 276.192962 -12.954145) (xy 276.11158 -13.02466)
			(xy 276.025376 -13.089189) (xy 275.934787 -13.147404) (xy 275.840277 -13.199008) (xy 275.742325 -13.243738)
			(xy 275.641432 -13.281366) (xy 275.538112 -13.311701) (xy 275.432891 -13.334588) (xy 275.326306 -13.349909)
			(xy 275.218899 -13.357588) (xy 275.165058 -13.358114) (xy 267.165074 -13.358114) (xy 267.111233 -13.357632)
			(xy 267.003826 -13.349949) (xy 266.897241 -13.334623) (xy 266.792021 -13.311732) (xy 266.688702 -13.281393)
			(xy 266.58781 -13.243761) (xy 266.48986 -13.199028) (xy 266.39535 -13.147421) (xy 266.304763 -13.089203)
			(xy 266.21856 -13.024672) (xy 266.13718 -12.954155) (xy 266.061038 -12.878012) (xy 265.990522 -12.796632)
			(xy 265.925991 -12.710428) (xy 265.867774 -12.619841) (xy 265.816168 -12.525331) (xy 265.771435 -12.427381)
			(xy 265.733804 -12.326489) (xy 265.703466 -12.22317) (xy 265.680576 -12.117949) (xy 265.66525 -12.011364)
			(xy 265.657567 -11.903957) (xy 265.657076 -11.850116) (xy 265.657076 -1.999996) (xy 265.656567 -1.944189)
			(xy 265.648225 -1.832887) (xy 265.63159 -1.722519) (xy 265.606753 -1.613703) (xy 265.573853 -1.507048)
			(xy 265.533076 -1.403149) (xy 265.484647 -1.302589) (xy 265.42884 -1.205928) (xy 265.365964 -1.113709)
			(xy 265.296373 -1.026446) (xy 265.220456 -0.944627) (xy 265.138636 -0.868711) (xy 265.051372 -0.799121)
			(xy 264.959151 -0.736248) (xy 264.86249 -0.680441) (xy 264.761929 -0.632015) (xy 264.658029 -0.591239)
			(xy 264.551373 -0.558341) (xy 264.442557 -0.533506) (xy 264.332189 -0.516872) (xy 264.220887 -0.508532)
			(xy 264.16508 -0.508) (xy 252.165104 -0.508) (xy 252.109297 -0.508522) (xy 251.997995 -0.516862)
			(xy 251.887627 -0.533497) (xy 251.778811 -0.558333) (xy 251.672155 -0.591232) (xy 251.568256 -0.632009)
			(xy 251.467695 -0.680436) (xy 251.371034 -0.736243) (xy 251.278814 -0.799118) (xy 251.19155 -0.868708)
			(xy 251.10973 -0.944625) (xy 251.033813 -1.026444) (xy 250.964222 -1.113707) (xy 250.901348 -1.205927)
			(xy 250.84554 -1.302588) (xy 250.797112 -1.403149) (xy 250.756335 -1.507047) (xy 250.723435 -1.613703)
			(xy 250.698599 -1.722519) (xy 250.681963 -1.832887) (xy 250.673622 -1.944189) (xy 250.673108 -1.999996)
			(xy 250.673108 -11.850116) (xy 250.672627 -11.903957) (xy 250.664944 -12.011364) (xy 250.649618 -12.11795)
			(xy 250.626728 -12.223171) (xy 250.59639 -12.32649) (xy 250.558758 -12.427382) (xy 250.514025 -12.525333)
			(xy 250.462418 -12.619843) (xy 250.4042 -12.71043) (xy 250.339669 -12.796633) (xy 250.269152 -12.878014)
			(xy 250.193009 -12.954156) (xy 250.111629 -13.024673) (xy 250.025425 -13.089204) (xy 249.934837 -13.147421)
			(xy 249.840327 -13.199027) (xy 249.742377 -13.24376) (xy 249.641484 -13.281392) (xy 249.538165 -13.311729)
			(xy 249.432944 -13.334619) (xy 249.326358 -13.349944) (xy 249.218951 -13.357627) (xy 249.16511 -13.358114)
			(xy 241.164872 -13.358114) (xy 241.111035 -13.357619) (xy 241.003638 -13.34991) (xy 240.897064 -13.334562)
			(xy 240.791856 -13.311652) (xy 240.688549 -13.281298) (xy 240.58767 -13.243654) (xy 240.489733 -13.198912)
			(xy 240.395235 -13.1473) (xy 240.304659 -13.08908) (xy 240.218466 -13.024548) (xy 240.137093 -12.954035)
			(xy 240.060957 -12.877898) (xy 239.990444 -12.796525) (xy 239.925914 -12.710331) (xy 239.867694 -12.619754)
			(xy 239.816083 -12.525256) (xy 239.771341 -12.427319) (xy 239.733698 -12.326439) (xy 239.703345 -12.223133)
			(xy 239.680436 -12.117924) (xy 239.665089 -12.01135) (xy 239.657381 -11.903953) (xy 239.656874 -11.850116)
			(xy 239.656874 -1.999996) (xy 239.656365 -1.944189) (xy 239.648023 -1.832887) (xy 239.631388 -1.722519)
			(xy 239.606551 -1.613704) (xy 239.573651 -1.507048) (xy 239.532873 -1.40315) (xy 239.484445 -1.302589)
			(xy 239.428638 -1.205929) (xy 239.365762 -1.113709) (xy 239.296171 -1.026446) (xy 239.220254 -0.944628)
			(xy 239.138434 -0.868712) (xy 239.05117 -0.799122) (xy 238.958949 -0.736249) (xy 238.862288 -0.680443)
			(xy 238.761726 -0.632016) (xy 238.657827 -0.59124) (xy 238.551171 -0.558343) (xy 238.442355 -0.533507)
			(xy 238.331987 -0.516874) (xy 238.220685 -0.508534) (xy 238.164878 -0.508) (xy 214.065104 -0.508)
			(xy 214.009297 -0.508522) (xy 213.897995 -0.516862) (xy 213.787627 -0.533497) (xy 213.678811 -0.558333)
			(xy 213.572155 -0.591232) (xy 213.468256 -0.632009) (xy 213.367695 -0.680436) (xy 213.271034 -0.736243)
			(xy 213.178814 -0.799118) (xy 213.09155 -0.868708) (xy 213.00973 -0.944625) (xy 212.933813 -1.026444)
			(xy 212.864222 -1.113707) (xy 212.801348 -1.205927) (xy 212.74554 -1.302588) (xy 212.697112 -1.403149)
			(xy 212.656335 -1.507047) (xy 212.623435 -1.613703) (xy 212.598599 -1.722519) (xy 212.581963 -1.832887)
			(xy 212.573622 -1.944189) (xy 212.573108 -1.999996) (xy 212.573108 -11.850116) (xy 212.572627 -11.903957)
			(xy 212.564944 -12.011364) (xy 212.549618 -12.11795) (xy 212.526728 -12.223171) (xy 212.49639 -12.32649)
			(xy 212.458758 -12.427382) (xy 212.414025 -12.525333) (xy 212.362418 -12.619843) (xy 212.3042 -12.71043)
			(xy 212.239669 -12.796633) (xy 212.169152 -12.878014) (xy 212.093009 -12.954156) (xy 212.011629 -13.024673)
			(xy 211.925425 -13.089204) (xy 211.834837 -13.147421) (xy 211.740327 -13.199027) (xy 211.642377 -13.24376)
			(xy 211.541484 -13.281392) (xy 211.438165 -13.311729) (xy 211.332944 -13.334619) (xy 211.226358 -13.349944)
			(xy 211.118951 -13.357627) (xy 211.06511 -13.358114) (xy 203.064872 -13.358114) (xy 203.011035 -13.357619)
			(xy 202.903638 -13.34991) (xy 202.797064 -13.334562) (xy 202.691856 -13.311652) (xy 202.588549 -13.281298)
			(xy 202.48767 -13.243654) (xy 202.389733 -13.198912) (xy 202.295235 -13.1473) (xy 202.204659 -13.08908)
			(xy 202.118466 -13.024548) (xy 202.037093 -12.954035) (xy 201.960957 -12.877898) (xy 201.890444 -12.796525)
			(xy 201.825914 -12.710331) (xy 201.767694 -12.619754) (xy 201.716083 -12.525256) (xy 201.671341 -12.427319)
			(xy 201.633698 -12.326439) (xy 201.603345 -12.223133) (xy 201.580436 -12.117924) (xy 201.565089 -12.01135)
			(xy 201.557381 -11.903953) (xy 201.556874 -11.850116) (xy 201.556874 -1.999996) (xy 201.556365 -1.944189)
			(xy 201.548023 -1.832887) (xy 201.531388 -1.722519) (xy 201.506551 -1.613704) (xy 201.473651 -1.507048)
			(xy 201.432873 -1.40315) (xy 201.384445 -1.302589) (xy 201.328638 -1.205929) (xy 201.265762 -1.113709)
			(xy 201.196171 -1.026446) (xy 201.120254 -0.944628) (xy 201.038434 -0.868712) (xy 200.95117 -0.799122)
			(xy 200.858949 -0.736249) (xy 200.762288 -0.680443) (xy 200.661726 -0.632016) (xy 200.557827 -0.59124)
			(xy 200.451171 -0.558343) (xy 200.342355 -0.533507) (xy 200.231987 -0.516874) (xy 200.120685 -0.508534)
			(xy 200.064878 -0.508) (xy 188.064902 -0.508) (xy 188.009095 -0.508522) (xy 187.897793 -0.516862)
			(xy 187.787425 -0.533498) (xy 187.678609 -0.558334) (xy 187.571954 -0.591233) (xy 187.468055 -0.63201)
			(xy 187.367494 -0.680437) (xy 187.270833 -0.736244) (xy 187.178613 -0.799118) (xy 187.091349 -0.868709)
			(xy 187.00953 -0.944625) (xy 186.933613 -1.026444) (xy 186.864022 -1.113708) (xy 186.801147 -1.205928)
			(xy 186.74534 -1.302588) (xy 186.696912 -1.403149) (xy 186.656135 -1.507048) (xy 186.623235 -1.613703)
			(xy 186.598399 -1.722519) (xy 186.581763 -1.832887) (xy 186.573422 -1.944189) (xy 186.572906 -1.999996)
			(xy 186.572906 -11.850116) (xy 186.572425 -11.903957) (xy 186.564742 -12.011364) (xy 186.549416 -12.11795)
			(xy 186.526526 -12.22317) (xy 186.496188 -12.32649) (xy 186.458556 -12.427382) (xy 186.413823 -12.525332)
			(xy 186.362216 -12.619842) (xy 186.303998 -12.71043) (xy 186.239467 -12.796633) (xy 186.16895 -12.878013)
			(xy 186.092807 -12.954155) (xy 186.011427 -13.024672) (xy 185.925223 -13.089203) (xy 185.834635 -13.14742)
			(xy 185.740125 -13.199026) (xy 185.642175 -13.243759) (xy 185.541282 -13.28139) (xy 185.437963 -13.311728)
			(xy 185.332742 -13.334618) (xy 185.226156 -13.349943) (xy 185.118749 -13.357625) (xy 185.064908 -13.358114)
			(xy 177.064924 -13.358114) (xy 177.011082 -13.357646) (xy 176.903671 -13.349965) (xy 176.797083 -13.334642)
			(xy 176.691859 -13.311753) (xy 176.588536 -13.281417) (xy 176.48764 -13.243786) (xy 176.389686 -13.199054)
			(xy 176.295173 -13.147447) (xy 176.204582 -13.08923) (xy 176.118375 -13.024698) (xy 176.036992 -12.954181)
			(xy 175.960846 -12.878038) (xy 175.890327 -12.796656) (xy 175.825793 -12.710451) (xy 175.767573 -12.619862)
			(xy 175.715964 -12.52535) (xy 175.671229 -12.427397) (xy 175.633596 -12.326502) (xy 175.603257 -12.22318)
			(xy 175.580365 -12.117957) (xy 175.565039 -12.011368) (xy 175.557356 -11.903958) (xy 175.556926 -11.850116)
			(xy 175.556926 -1.999996) (xy 175.556404 -1.944189) (xy 175.548063 -1.832886) (xy 175.531428 -1.722518)
			(xy 175.506591 -1.613702) (xy 175.473692 -1.507046) (xy 175.432915 -1.403146) (xy 175.384488 -1.302585)
			(xy 175.328681 -1.205923) (xy 175.265807 -1.113703) (xy 175.196217 -1.026438) (xy 175.1203 -0.944618)
			(xy 175.038481 -0.8687) (xy 174.951218 -0.799109) (xy 174.858999 -0.736233) (xy 174.762338 -0.680424)
			(xy 174.661777 -0.631995) (xy 174.557879 -0.591216) (xy 174.451223 -0.558316) (xy 174.342408 -0.533477)
			(xy 174.23204 -0.51684) (xy 174.120737 -0.508497) (xy 174.06493 -0.508) (xy 162.064954 -0.508) (xy 162.009148 -0.508523)
			(xy 161.897848 -0.516867) (xy 161.787483 -0.533505) (xy 161.67867 -0.558344) (xy 161.572018 -0.591245)
			(xy 161.468122 -0.632024) (xy 161.367564 -0.680453) (xy 161.270907 -0.73626) (xy 161.17869 -0.799135)
			(xy 161.091429 -0.868726) (xy 161.009613 -0.944642) (xy 160.933698 -1.026461) (xy 160.86411 -1.113723)
			(xy 160.801238 -1.205942) (xy 160.745433 -1.302601) (xy 160.697007 -1.403161) (xy 160.656231 -1.507058)
			(xy 160.623333 -1.613711) (xy 160.598498 -1.722525) (xy 160.581863 -1.83289) (xy 160.573522 -1.94419)
			(xy 160.572958 -1.999996) (xy 160.572958 -11.850116) (xy 160.572488 -11.903957) (xy 160.564805 -12.011363)
			(xy 160.549479 -12.117949) (xy 160.526589 -12.223169) (xy 160.49625 -12.326488) (xy 160.458618 -12.427379)
			(xy 160.413884 -12.525329) (xy 160.362276 -12.619838) (xy 160.304058 -12.710424) (xy 160.239525 -12.796626)
			(xy 160.169008 -12.878005) (xy 160.092864 -12.954146) (xy 160.011483 -13.02466) (xy 159.925278 -13.08919)
			(xy 159.834689 -13.147405) (xy 159.740179 -13.199009) (xy 159.642227 -13.243739) (xy 159.541335 -13.281368)
			(xy 159.438014 -13.311702) (xy 159.332793 -13.334589) (xy 159.226208 -13.349911) (xy 159.118801 -13.35759)
			(xy 159.06496 -13.358114) (xy 151.064976 -13.358114) (xy 151.011135 -13.357633) (xy 150.903728 -13.349949)
			(xy 150.797143 -13.334623) (xy 150.691922 -13.311732) (xy 150.588603 -13.281394) (xy 150.487711 -13.243762)
			(xy 150.389761 -13.199028) (xy 150.295252 -13.147421) (xy 150.204664 -13.089204) (xy 150.118461 -13.024672)
			(xy 150.037081 -12.954156) (xy 149.960939 -12.878013) (xy 149.890423 -12.796633) (xy 149.825892 -12.710429)
			(xy 149.767674 -12.619842) (xy 149.716068 -12.525332) (xy 149.671335 -12.427381) (xy 149.633704 -12.326489)
			(xy 149.603366 -12.22317) (xy 149.580476 -12.117949) (xy 149.56515 -12.011364) (xy 149.557467 -11.903957)
			(xy 149.556978 -11.850116) (xy 149.556978 -1.999996) (xy 149.556469 -1.944189) (xy 149.548127 -1.832887)
			(xy 149.531492 -1.722519) (xy 149.506655 -1.613703) (xy 149.473755 -1.507048) (xy 149.432978 -1.403149)
			(xy 149.384549 -1.302588) (xy 149.328742 -1.205928) (xy 149.265867 -1.113708) (xy 149.196276 -1.026445)
			(xy 149.120358 -0.944627) (xy 149.038538 -0.86871) (xy 148.951274 -0.79912) (xy 148.859054 -0.736247)
			(xy 148.762392 -0.68044) (xy 148.661831 -0.632014) (xy 148.557931 -0.591237) (xy 148.451276 -0.55834)
			(xy 148.342459 -0.533504) (xy 148.232091 -0.51687) (xy 148.120789 -0.508531) (xy 148.064982 -0.508)
			(xy 136.065006 -0.508) (xy 136.009198 -0.508509) (xy 135.897895 -0.51685) (xy 135.787526 -0.533485)
			(xy 135.678709 -0.558321) (xy 135.572052 -0.59122) (xy 135.468152 -0.631997) (xy 135.36759 -0.680425)
			(xy 135.270928 -0.736232) (xy 135.178707 -0.799107) (xy 135.091442 -0.868698) (xy 135.009622 -0.944615)
			(xy 134.933704 -1.026435) (xy 134.864113 -1.113699) (xy 134.801237 -1.20592) (xy 134.745429 -1.302581)
			(xy 134.697001 -1.403143) (xy 134.656223 -1.507043) (xy 134.623324 -1.613699) (xy 134.598486 -1.722516)
			(xy 134.581851 -1.832885) (xy 134.573509 -1.944188) (xy 134.57301 -1.999996) (xy 134.57301 -11.850116)
			(xy 134.572529 -11.903957) (xy 134.564846 -12.011364) (xy 134.54952 -12.11795) (xy 134.52663 -12.223171)
			(xy 134.496292 -12.32649) (xy 134.45866 -12.427383) (xy 134.413927 -12.525333) (xy 134.36232 -12.619843)
			(xy 134.304102 -12.710431) (xy 134.239571 -12.796634) (xy 134.169054 -12.878014) (xy 134.092911 -12.954157)
			(xy 134.011531 -13.024673) (xy 133.925327 -13.089205) (xy 133.83474 -13.147422) (xy 133.74023 -13.199029)
			(xy 133.642279 -13.243762) (xy 133.541387 -13.281393) (xy 133.438067 -13.311731) (xy 133.332846 -13.334621)
			(xy 133.22626 -13.349946) (xy 133.118853 -13.357629) (xy 133.065012 -13.358114) (xy 125.065028 -13.358114)
			(xy 125.011186 -13.357646) (xy 124.903775 -13.349966) (xy 124.797186 -13.334642) (xy 124.691962 -13.311754)
			(xy 124.588639 -13.281418) (xy 124.487743 -13.243787) (xy 124.389789 -13.199055) (xy 124.295275 -13.147449)
			(xy 124.204684 -13.089231) (xy 124.118477 -13.0247) (xy 124.037093 -12.954182) (xy 123.960948 -12.878039)
			(xy 123.890428 -12.796657) (xy 123.825894 -12.710452) (xy 123.767674 -12.619863) (xy 123.716065 -12.525351)
			(xy 123.671329 -12.427398) (xy 123.633696 -12.326503) (xy 123.603357 -12.223181) (xy 123.580465 -12.117957)
			(xy 123.565139 -12.011369) (xy 123.557456 -11.903958) (xy 123.55703 -11.850116) (xy 123.55703 -1.999996)
			(xy 123.556508 -1.944189) (xy 123.548167 -1.832886) (xy 123.531532 -1.722518) (xy 123.506695 -1.613701)
			(xy 123.473796 -1.507045) (xy 123.433019 -1.403146) (xy 123.384592 -1.302584) (xy 123.328785 -1.205923)
			(xy 123.265911 -1.113702) (xy 123.196321 -1.026437) (xy 123.120404 -0.944617) (xy 123.038586 -0.868699)
			(xy 122.951322 -0.799107) (xy 122.859103 -0.736231) (xy 122.762442 -0.680422) (xy 122.661882 -0.631993)
			(xy 122.557983 -0.591214) (xy 122.451328 -0.558313) (xy 122.342512 -0.533474) (xy 122.232144 -0.516836)
			(xy 122.120841 -0.508493) (xy 122.065034 -0.508) (xy 97.965006 -0.508) (xy 97.909198 -0.508509) (xy 97.797895 -0.51685)
			(xy 97.687526 -0.533485) (xy 97.578709 -0.558321) (xy 97.472052 -0.59122) (xy 97.368152 -0.631997)
			(xy 97.26759 -0.680425) (xy 97.170928 -0.736232) (xy 97.078707 -0.799107) (xy 96.991442 -0.868698)
			(xy 96.909622 -0.944615) (xy 96.833704 -1.026435) (xy 96.764113 -1.113699) (xy 96.701237 -1.20592)
			(xy 96.645429 -1.302581) (xy 96.597001 -1.403143) (xy 96.556223 -1.507043) (xy 96.523324 -1.613699)
			(xy 96.498486 -1.722516) (xy 96.481851 -1.832885) (xy 96.473509 -1.944188) (xy 96.47301 -1.999996)
			(xy 96.47301 -11.850116) (xy 96.472529 -11.903957) (xy 96.464846 -12.011364) (xy 96.44952 -12.11795)
			(xy 96.42663 -12.223171) (xy 96.396292 -12.32649) (xy 96.35866 -12.427383) (xy 96.313927 -12.525333)
			(xy 96.26232 -12.619843) (xy 96.204102 -12.710431) (xy 96.139571 -12.796634) (xy 96.069054 -12.878014)
			(xy 95.992911 -12.954157) (xy 95.911531 -13.024673) (xy 95.825327 -13.089205) (xy 95.73474 -13.147422)
			(xy 95.64023 -13.199029) (xy 95.542279 -13.243762) (xy 95.441387 -13.281393) (xy 95.338067 -13.311731)
			(xy 95.232846 -13.334621) (xy 95.12626 -13.349946) (xy 95.018853 -13.357629) (xy 94.965012 -13.358114)
			(xy 86.965028 -13.358114) (xy 86.911186 -13.357646) (xy 86.803775 -13.349966) (xy 86.697186 -13.334642)
			(xy 86.591962 -13.311754) (xy 86.488639 -13.281418) (xy 86.387743 -13.243787) (xy 86.289789 -13.199055)
			(xy 86.195275 -13.147449) (xy 86.104684 -13.089231) (xy 86.018477 -13.0247) (xy 85.937093 -12.954182)
			(xy 85.860948 -12.878039) (xy 85.790428 -12.796657) (xy 85.725894 -12.710452) (xy 85.667674 -12.619863)
			(xy 85.616065 -12.525351) (xy 85.571329 -12.427398) (xy 85.533696 -12.326503) (xy 85.503357 -12.223181)
			(xy 85.480465 -12.117957) (xy 85.465139 -12.011369) (xy 85.457456 -11.903958) (xy 85.45703 -11.850116)
			(xy 85.45703 -1.999996) (xy 85.456508 -1.944189) (xy 85.448167 -1.832886) (xy 85.431532 -1.722518)
			(xy 85.406695 -1.613701) (xy 85.373796 -1.507045) (xy 85.333019 -1.403146) (xy 85.284592 -1.302584)
			(xy 85.228785 -1.205923) (xy 85.165911 -1.113702) (xy 85.096321 -1.026437) (xy 85.020404 -0.944617)
			(xy 84.938586 -0.868699) (xy 84.851322 -0.799107) (xy 84.759103 -0.736231) (xy 84.662442 -0.680422)
			(xy 84.561882 -0.631993) (xy 84.457983 -0.591214) (xy 84.351328 -0.558313) (xy 84.242512 -0.533474)
			(xy 84.132144 -0.516836) (xy 84.020841 -0.508493) (xy 83.965034 -0.508) (xy 71.965058 -0.508) (xy 71.909252 -0.508523)
			(xy 71.797952 -0.516867) (xy 71.687587 -0.533505) (xy 71.578774 -0.558343) (xy 71.472121 -0.591244)
			(xy 71.368225 -0.632023) (xy 71.267667 -0.680451) (xy 71.171009 -0.736259) (xy 71.078791 -0.799134)
			(xy 70.991531 -0.868724) (xy 70.909714 -0.944641) (xy 70.8338 -1.026459) (xy 70.764211 -1.113722)
			(xy 70.701339 -1.205941) (xy 70.645534 -1.3026) (xy 70.597107 -1.40316) (xy 70.556331 -1.507057)
			(xy 70.523434 -1.61371) (xy 70.498598 -1.722524) (xy 70.481963 -1.83289) (xy 70.473622 -1.94419)
			(xy 70.473062 -1.999996) (xy 70.473062 -11.850116) (xy 70.472592 -11.903957) (xy 70.464909 -12.011364)
			(xy 70.449583 -12.117949) (xy 70.426693 -12.223169) (xy 70.396354 -12.326488) (xy 70.358722 -12.42738)
			(xy 70.313988 -12.52533) (xy 70.26238 -12.619839) (xy 70.204162 -12.710425) (xy 70.139629 -12.796627)
			(xy 70.069112 -12.878006) (xy 69.992968 -12.954147) (xy 69.911587 -13.024662) (xy 69.825382 -13.089192)
			(xy 69.734794 -13.147407) (xy 69.640283 -13.199011) (xy 69.542332 -13.243742) (xy 69.441439 -13.28137)
			(xy 69.338119 -13.311705) (xy 69.232898 -13.334592) (xy 69.126312 -13.349915) (xy 69.018905 -13.357594)
			(xy 68.965064 -13.358114) (xy 60.96508 -13.358114) (xy 60.911239 -13.357633) (xy 60.803832 -13.349949)
			(xy 60.697246 -13.334624) (xy 60.592026 -13.311733) (xy 60.488706 -13.281395) (xy 60.387814 -13.243763)
			(xy 60.289864 -13.19903) (xy 60.195354 -13.147423) (xy 60.104766 -13.089205) (xy 60.018563 -13.024674)
			(xy 59.937183 -12.954157) (xy 59.86104 -12.878014) (xy 59.790524 -12.796634) (xy 59.725992 -12.71043)
			(xy 59.667775 -12.619843) (xy 59.616169 -12.525333) (xy 59.571435 -12.427382) (xy 59.533804 -12.32649)
			(xy 59.503466 -12.22317) (xy 59.480576 -12.11795) (xy 59.46525 -12.011364) (xy 59.457567 -11.903957)
			(xy 59.457082 -11.850116) (xy 59.457082 -1.999996) (xy 59.456573 -1.944189) (xy 59.448231 -1.832886)
			(xy 59.431596 -1.722519) (xy 59.406759 -1.613703) (xy 59.373859 -1.507047) (xy 59.333082 -1.403148)
			(xy 59.284653 -1.302588) (xy 59.228846 -1.205927) (xy 59.165971 -1.113707) (xy 59.09638 -1.026444)
			(xy 59.020462 -0.944625) (xy 58.938643 -0.868709) (xy 58.851378 -0.799119) (xy 58.759158 -0.736245)
			(xy 58.662496 -0.680438) (xy 58.561935 -0.632011) (xy 58.458036 -0.591235) (xy 58.35138 -0.558337)
			(xy 58.242564 -0.533501) (xy 58.132196 -0.516867) (xy 58.020893 -0.508527) (xy 57.965086 -0.508)
			(xy 45.96511 -0.508) (xy 45.909302 -0.508509) (xy 45.797999 -0.516849) (xy 45.68763 -0.533484) (xy 45.578812 -0.55832)
			(xy 45.472155 -0.591219) (xy 45.368255 -0.631996) (xy 45.267693 -0.680423) (xy 45.17103 -0.736231)
			(xy 45.078809 -0.799106) (xy 44.991544 -0.868696) (xy 44.909724 -0.944614) (xy 44.833805 -1.026433)
			(xy 44.764214 -1.113698) (xy 44.701338 -1.205919) (xy 44.64553 -1.30258) (xy 44.597101 -1.403142)
			(xy 44.556323 -1.507042) (xy 44.523424 -1.613699) (xy 44.498587 -1.722516) (xy 44.481951 -1.832885)
			(xy 44.473609 -1.944188) (xy 44.473114 -1.999996) (xy 44.473114 -11.850116) (xy 44.472633 -11.903957)
			(xy 44.46495 -12.011364) (xy 44.449624 -12.11795) (xy 44.426734 -12.223171) (xy 44.396396 -12.326491)
			(xy 44.358764 -12.427383) (xy 44.314031 -12.525334) (xy 44.262424 -12.619844) (xy 44.204207 -12.710432)
			(xy 44.139675 -12.796635) (xy 44.069158 -12.878016) (xy 43.993016 -12.954158) (xy 43.911635 -13.024675)
			(xy 43.825432 -13.089207) (xy 43.734844 -13.147424) (xy 43.640334 -13.199031) (xy 43.542383 -13.243764)
			(xy 43.441491 -13.281396) (xy 43.338171 -13.311734) (xy 43.23295 -13.334624) (xy 43.126364 -13.34995)
			(xy 43.018957 -13.357633) (xy 42.965116 -13.358114) (xy 34.964878 -13.358114) (xy 34.911037 -13.357633)
			(xy 34.80363 -13.349949) (xy 34.697045 -13.334623) (xy 34.591824 -13.311733) (xy 34.488505 -13.281394)
			(xy 34.387613 -13.243762) (xy 34.289662 -13.199029) (xy 34.195153 -13.147422) (xy 34.104565 -13.089205)
			(xy 34.018362 -13.024673) (xy 33.936982 -12.954156) (xy 33.86084 -12.878014) (xy 33.790323 -12.796633)
			(xy 33.725792 -12.71043) (xy 33.667575 -12.619842) (xy 33.615968 -12.525332) (xy 33.571235 -12.427382)
			(xy 33.533604 -12.32649) (xy 33.503266 -12.22317) (xy 33.480376 -12.11795) (xy 33.46505 -12.011364)
			(xy 33.457367 -11.903957) (xy 33.45688 -11.850116) (xy 33.45688 -1.999996) (xy 33.456371 -1.944189)
			(xy 33.448029 -1.832887) (xy 33.431394 -1.722519) (xy 33.406557 -1.613703) (xy 33.373657 -1.507048)
			(xy 33.33288 -1.403149) (xy 33.284451 -1.302588) (xy 33.228644 -1.205927) (xy 33.165769 -1.113708)
			(xy 33.096178 -1.026444) (xy 33.02026 -0.944626) (xy 32.93844 -0.868709) (xy 32.851176 -0.79912)
			(xy 32.758956 -0.736246) (xy 32.662294 -0.680439) (xy 32.561733 -0.632012) (xy 32.457834 -0.591236)
			(xy 32.351178 -0.558338) (xy 32.242361 -0.533503) (xy 32.131994 -0.516868) (xy 32.020691 -0.508529)
			(xy 31.964884 -0.508) (xy 19.964908 -0.508) (xy 19.9091 -0.508509) (xy 19.797797 -0.516849) (xy 19.687428 -0.533484)
			(xy 19.578611 -0.55832) (xy 19.471954 -0.591219) (xy 19.368054 -0.631996) (xy 19.267491 -0.680424)
			(xy 19.170829 -0.736231) (xy 19.078608 -0.799106) (xy 18.991343 -0.868697) (xy 18.909523 -0.944614)
			(xy 18.833605 -1.026434) (xy 18.764013 -1.113698) (xy 18.701138 -1.205919) (xy 18.64533 -1.302581)
			(xy 18.596901 -1.403143) (xy 18.556123 -1.507043) (xy 18.523224 -1.613699) (xy 18.498386 -1.722516)
			(xy 18.481751 -1.832885) (xy 18.473409 -1.944188) (xy 18.472912 -1.999996) (xy 18.472912 -11.850116)
			(xy 18.472443 -11.903958) (xy 18.464761 -12.011366) (xy 18.449437 -12.117953) (xy 18.426547 -12.223176)
			(xy 18.396209 -12.326497) (xy 18.358578 -12.42739) (xy 18.313845 -12.525342) (xy 18.262238 -12.619854)
			(xy 18.20402 -12.710442) (xy 18.139488 -12.796647) (xy 18.068971 -12.878029) (xy 17.992827 -12.954172)
			(xy 17.911446 -13.024689) (xy 17.825241 -13.089221) (xy 17.734652 -13.147439) (xy 17.640141 -13.199046)
			(xy 17.542189 -13.243779) (xy 17.441295 -13.28141) (xy 17.337974 -13.311748) (xy 17.232751 -13.334637)
			(xy 17.126164 -13.349961) (xy 17.018756 -13.357643) (xy 16.964914 -13.358114) (xy 8.96493 -13.358114)
			(xy 8.911089 -13.357645) (xy 8.80368 -13.349963) (xy 8.697093 -13.334638) (xy 8.591871 -13.311748)
			(xy 8.48855 -13.28141) (xy 8.387656 -13.243779) (xy 8.289705 -13.199046) (xy 8.195194 -13.147439)
			(xy 8.104605 -13.089221) (xy 8.0184 -13.024689) (xy 7.937019 -12.954171) (xy 7.860876 -12.878028)
			(xy 7.790359 -12.796646) (xy 7.725827 -12.710442) (xy 7.667609 -12.619853) (xy 7.616002 -12.525342)
			(xy 7.57127 -12.42739) (xy 7.533638 -12.326496) (xy 7.503301 -12.223175) (xy 7.480411 -12.117953)
			(xy 7.465087 -12.011366) (xy 7.457405 -11.903957) (xy 7.456932 -11.850116) (xy 7.456932 -1.999996)
			(xy 7.45641 -1.944189) (xy 7.448069 -1.832887) (xy 7.431434 -1.72252) (xy 7.406597 -1.613704) (xy 7.373698 -1.507049)
			(xy 7.332921 -1.40315) (xy 7.284493 -1.30259) (xy 7.228686 -1.205929) (xy 7.165812 -1.113709) (xy 7.096221 -1.026446)
			(xy 7.020305 -0.944627) (xy 6.938486 -0.86871) (xy 6.851222 -0.79912) (xy 6.759003 -0.736245) (xy 6.662342 -0.680438)
			(xy 6.561782 -0.63201) (xy 6.457883 -0.591233) (xy 6.351228 -0.558334) (xy 6.242412 -0.533497) (xy 6.132045 -0.516861)
			(xy 6.020743 -0.50852) (xy 5.964936 -0.508) (xy 1.999996 -0.508) (xy 1.944189 -0.508522) (xy 1.832887 -0.516863)
			(xy 1.72252 -0.533498) (xy 1.613704 -0.558335) (xy 1.507049 -0.591234) (xy 1.403151 -0.632011) (xy 1.30259 -0.680439)
			(xy 1.205929 -0.736246) (xy 1.11371 -0.799121) (xy 1.026446 -0.868711) (xy 0.944628 -0.944628) (xy 0.868711 -1.026446)
			(xy 0.799121 -1.11371) (xy 0.736246 -1.205929) (xy 0.680439 -1.30259) (xy 0.632011 -1.403151) (xy 0.591234 -1.507049)
			(xy 0.558335 -1.613704) (xy 0.533498 -1.72252) (xy 0.516863 -1.832887) (xy 0.508522 -1.944189) (xy 0.508 -1.999996)
			(xy 0.508 -15.200122) (xy 459.541372 -15.200122) (xy 459.541372 -13.599922) (xy 459.54188 -13.535242)
			(xy 459.550003 -13.406136) (xy 459.566216 -13.277796) (xy 459.590456 -13.150726) (xy 459.622626 -13.02543)
			(xy 459.662601 -12.9024) (xy 459.710222 -12.782124) (xy 459.765301 -12.665075) (xy 459.827621 -12.551715)
			(xy 459.896936 -12.442492) (xy 459.972972 -12.337837) (xy 460.05543 -12.238163) (xy 460.143983 -12.143863)
			(xy 460.238283 -12.05531) (xy 460.337957 -11.972852) (xy 460.442612 -11.896816) (xy 460.551835 -11.827501)
			(xy 460.665195 -11.765181) (xy 460.782244 -11.710102) (xy 460.90252 -11.662481) (xy 461.02555 -11.622506)
			(xy 461.150846 -11.590336) (xy 461.277916 -11.566096) (xy 461.406256 -11.549883) (xy 461.535362 -11.54176)
			(xy 461.664722 -11.54176) (xy 461.793828 -11.549883) (xy 461.922168 -11.566096) (xy 462.049238 -11.590336)
			(xy 462.174534 -11.622506) (xy 462.297564 -11.662481) (xy 462.41784 -11.710102) (xy 462.534889 -11.765181)
			(xy 462.648249 -11.827501) (xy 462.757472 -11.896816) (xy 462.862127 -11.972852) (xy 462.961801 -12.05531)
			(xy 463.056101 -12.143863) (xy 463.144654 -12.238163) (xy 463.227112 -12.337837) (xy 463.303148 -12.442492)
			(xy 463.372463 -12.551715) (xy 463.434783 -12.665075) (xy 463.489862 -12.782124) (xy 463.537483 -12.9024)
			(xy 463.577458 -13.02543) (xy 463.609628 -13.150726) (xy 463.633868 -13.277796) (xy 463.650081 -13.406136)
			(xy 463.658204 -13.535242) (xy 463.658712 -13.599922) (xy 463.658712 -15.200122) (xy 463.658204 -15.264802)
			(xy 463.650081 -15.393908) (xy 463.633868 -15.522248) (xy 463.609628 -15.649318) (xy 463.577458 -15.774614)
			(xy 463.537483 -15.897644) (xy 463.489862 -16.01792) (xy 463.434783 -16.134969) (xy 463.372463 -16.248329)
			(xy 463.303148 -16.357552) (xy 463.227112 -16.462207) (xy 463.144654 -16.561881) (xy 463.056101 -16.656181)
			(xy 462.961801 -16.744734) (xy 462.862127 -16.827192) (xy 462.757472 -16.903228) (xy 462.648249 -16.972543)
			(xy 462.534889 -17.034863) (xy 462.41784 -17.089942) (xy 462.297564 -17.137563) (xy 462.174534 -17.177538)
			(xy 462.049238 -17.209708) (xy 461.922168 -17.233948) (xy 461.793828 -17.250161) (xy 461.664722 -17.258284)
			(xy 461.535362 -17.258284) (xy 461.406256 -17.250161) (xy 461.277916 -17.233948) (xy 461.150846 -17.209708)
			(xy 461.02555 -17.177538) (xy 460.90252 -17.137563) (xy 460.782244 -17.089942) (xy 460.665195 -17.034863)
			(xy 460.551835 -16.972543) (xy 460.442612 -16.903228) (xy 460.337957 -16.827192) (xy 460.238283 -16.744734)
			(xy 460.143983 -16.656181) (xy 460.05543 -16.561881) (xy 459.972972 -16.462207) (xy 459.896936 -16.357552)
			(xy 459.827621 -16.248329) (xy 459.765301 -16.134969) (xy 459.710222 -16.01792) (xy 459.662601 -15.897644)
			(xy 459.622626 -15.774614) (xy 459.590456 -15.649318) (xy 459.566216 -15.522248) (xy 459.550003 -15.393908)
			(xy 459.54188 -15.264802) (xy 459.541372 -15.200122) (xy 0.508 -15.200122) (xy 0.508 -16.969994)
			(xy 13.748265 -16.969994) (xy 13.75227 -16.882086) (xy 13.764253 -16.794906) (xy 13.784113 -16.709177)
			(xy 13.811688 -16.625609) (xy 13.846747 -16.544895) (xy 13.889 -16.467703) (xy 13.938098 -16.394674)
			(xy 13.993634 -16.326412) (xy 14.055146 -16.263482) (xy 14.122127 -16.206408) (xy 14.19402 -16.15566)
			(xy 14.270229 -16.11166) (xy 14.350124 -16.074773) (xy 14.433043 -16.045304) (xy 14.518298 -16.023497)
			(xy 14.605182 -16.009533) (xy 14.692976 -16.003527) (xy 14.780953 -16.005531) (xy 14.868383 -16.015526)
			(xy 14.954542 -16.03343) (xy 15.038716 -16.059094) (xy 15.120207 -16.092307) (xy 15.198341 -16.132793)
			(xy 15.272469 -16.180215) (xy 15.341977 -16.234182) (xy 15.406291 -16.294247) (xy 15.464875 -16.359911)
			(xy 15.517246 -16.43063) (xy 15.562969 -16.505818) (xy 15.601666 -16.584853) (xy 15.633015 -16.667079)
			(xy 15.656757 -16.751815) (xy 15.672695 -16.838359) (xy 15.680697 -16.925994) (xy 15.681198 -16.969994)
			(xy 39.748213 -16.969994) (xy 39.752218 -16.882086) (xy 39.764201 -16.794906) (xy 39.784061 -16.709177)
			(xy 39.811636 -16.625609) (xy 39.846695 -16.544895) (xy 39.888948 -16.467703) (xy 39.938046 -16.394674)
			(xy 39.993582 -16.326412) (xy 40.055094 -16.263482) (xy 40.122075 -16.206408) (xy 40.193968 -16.15566)
			(xy 40.270177 -16.11166) (xy 40.350072 -16.074773) (xy 40.432991 -16.045304) (xy 40.518246 -16.023497)
			(xy 40.60513 -16.009533) (xy 40.692924 -16.003527) (xy 40.780901 -16.005531) (xy 40.868331 -16.015526)
			(xy 40.95449 -16.03343) (xy 41.038664 -16.059094) (xy 41.120155 -16.092307) (xy 41.198289 -16.132793)
			(xy 41.272417 -16.180215) (xy 41.341925 -16.234182) (xy 41.406239 -16.294247) (xy 41.464823 -16.359911)
			(xy 41.517194 -16.43063) (xy 41.562917 -16.505818) (xy 41.601614 -16.584853) (xy 41.632963 -16.667079)
			(xy 41.656705 -16.751815) (xy 41.672643 -16.838359) (xy 41.680645 -16.925994) (xy 41.681146 -16.969994)
			(xy 65.748161 -16.969994) (xy 65.752166 -16.882086) (xy 65.764149 -16.794906) (xy 65.784009 -16.709177)
			(xy 65.811584 -16.625609) (xy 65.846643 -16.544895) (xy 65.888896 -16.467703) (xy 65.937994 -16.394674)
			(xy 65.99353 -16.326412) (xy 66.055042 -16.263482) (xy 66.122023 -16.206408) (xy 66.193916 -16.15566)
			(xy 66.270125 -16.11166) (xy 66.35002 -16.074773) (xy 66.432939 -16.045304) (xy 66.518194 -16.023497)
			(xy 66.605078 -16.009533) (xy 66.692872 -16.003527) (xy 66.780849 -16.005531) (xy 66.868279 -16.015526)
			(xy 66.954438 -16.03343) (xy 67.038612 -16.059094) (xy 67.120103 -16.092307) (xy 67.198237 -16.132793)
			(xy 67.272365 -16.180215) (xy 67.341873 -16.234182) (xy 67.406187 -16.294247) (xy 67.464771 -16.359911)
			(xy 67.517142 -16.43063) (xy 67.562865 -16.505818) (xy 67.601562 -16.584853) (xy 67.632911 -16.667079)
			(xy 67.656653 -16.751815) (xy 67.672591 -16.838359) (xy 67.680593 -16.925994) (xy 67.681094 -16.969994)
			(xy 91.748109 -16.969994) (xy 91.752114 -16.882086) (xy 91.764097 -16.794906) (xy 91.783957 -16.709177)
			(xy 91.811532 -16.625609) (xy 91.846591 -16.544895) (xy 91.888844 -16.467703) (xy 91.937942 -16.394674)
			(xy 91.993478 -16.326412) (xy 92.05499 -16.263482) (xy 92.121971 -16.206408) (xy 92.193864 -16.15566)
			(xy 92.270073 -16.11166) (xy 92.349968 -16.074773) (xy 92.432887 -16.045304) (xy 92.518142 -16.023497)
			(xy 92.605026 -16.009533) (xy 92.69282 -16.003527) (xy 92.780797 -16.005531) (xy 92.868227 -16.015526)
			(xy 92.954386 -16.03343) (xy 93.03856 -16.059094) (xy 93.120051 -16.092307) (xy 93.198185 -16.132793)
			(xy 93.272313 -16.180215) (xy 93.341821 -16.234182) (xy 93.406135 -16.294247) (xy 93.464719 -16.359911)
			(xy 93.51709 -16.43063) (xy 93.562813 -16.505818) (xy 93.60151 -16.584853) (xy 93.632859 -16.667079)
			(xy 93.656601 -16.751815) (xy 93.672539 -16.838359) (xy 93.680541 -16.925994) (xy 93.681042 -16.969994)
			(xy 129.848363 -16.969994) (xy 129.852368 -16.882086) (xy 129.864351 -16.794906) (xy 129.884211 -16.709177)
			(xy 129.911786 -16.625609) (xy 129.946845 -16.544895) (xy 129.989098 -16.467703) (xy 130.038196 -16.394674)
			(xy 130.093732 -16.326412) (xy 130.155244 -16.263482) (xy 130.222225 -16.206408) (xy 130.294118 -16.15566)
			(xy 130.370327 -16.11166) (xy 130.450222 -16.074773) (xy 130.533141 -16.045304) (xy 130.618396 -16.023497)
			(xy 130.70528 -16.009533) (xy 130.793074 -16.003527) (xy 130.881051 -16.005531) (xy 130.968481 -16.015526)
			(xy 131.05464 -16.03343) (xy 131.138814 -16.059094) (xy 131.220305 -16.092307) (xy 131.298439 -16.132793)
			(xy 131.372567 -16.180215) (xy 131.442075 -16.234182) (xy 131.506389 -16.294247) (xy 131.564973 -16.359911)
			(xy 131.617344 -16.43063) (xy 131.663067 -16.505818) (xy 131.701764 -16.584853) (xy 131.733113 -16.667079)
			(xy 131.756855 -16.751815) (xy 131.772793 -16.838359) (xy 131.780795 -16.925994) (xy 131.781296 -16.969994)
			(xy 155.848311 -16.969994) (xy 155.852316 -16.882086) (xy 155.864299 -16.794906) (xy 155.884159 -16.709177)
			(xy 155.911734 -16.625609) (xy 155.946793 -16.544895) (xy 155.989046 -16.467703) (xy 156.038144 -16.394674)
			(xy 156.09368 -16.326412) (xy 156.155192 -16.263482) (xy 156.222173 -16.206408) (xy 156.294066 -16.15566)
			(xy 156.370275 -16.11166) (xy 156.45017 -16.074773) (xy 156.533089 -16.045304) (xy 156.618344 -16.023497)
			(xy 156.705228 -16.009533) (xy 156.793022 -16.003527) (xy 156.880999 -16.005531) (xy 156.968429 -16.015526)
			(xy 157.054588 -16.03343) (xy 157.138762 -16.059094) (xy 157.220253 -16.092307) (xy 157.298387 -16.132793)
			(xy 157.372515 -16.180215) (xy 157.442023 -16.234182) (xy 157.506337 -16.294247) (xy 157.564921 -16.359911)
			(xy 157.617292 -16.43063) (xy 157.663015 -16.505818) (xy 157.701712 -16.584853) (xy 157.733061 -16.667079)
			(xy 157.756803 -16.751815) (xy 157.772741 -16.838359) (xy 157.780743 -16.925994) (xy 157.781244 -16.969994)
			(xy 181.848259 -16.969994) (xy 181.852264 -16.882086) (xy 181.864247 -16.794906) (xy 181.884107 -16.709177)
			(xy 181.911682 -16.625609) (xy 181.946741 -16.544895) (xy 181.988994 -16.467703) (xy 182.038092 -16.394674)
			(xy 182.093628 -16.326412) (xy 182.15514 -16.263482) (xy 182.222121 -16.206408) (xy 182.294014 -16.15566)
			(xy 182.370223 -16.11166) (xy 182.450118 -16.074773) (xy 182.533037 -16.045304) (xy 182.618292 -16.023497)
			(xy 182.705176 -16.009533) (xy 182.79297 -16.003527) (xy 182.880947 -16.005531) (xy 182.968377 -16.015526)
			(xy 183.054536 -16.03343) (xy 183.13871 -16.059094) (xy 183.220201 -16.092307) (xy 183.298335 -16.132793)
			(xy 183.372463 -16.180215) (xy 183.441971 -16.234182) (xy 183.506285 -16.294247) (xy 183.564869 -16.359911)
			(xy 183.61724 -16.43063) (xy 183.662963 -16.505818) (xy 183.70166 -16.584853) (xy 183.733009 -16.667079)
			(xy 183.756751 -16.751815) (xy 183.772689 -16.838359) (xy 183.780691 -16.925994) (xy 183.781192 -16.969994)
			(xy 207.848207 -16.969994) (xy 207.852212 -16.882086) (xy 207.864195 -16.794906) (xy 207.884055 -16.709177)
			(xy 207.91163 -16.625609) (xy 207.946689 -16.544895) (xy 207.988942 -16.467703) (xy 208.03804 -16.394674)
			(xy 208.093576 -16.326412) (xy 208.155088 -16.263482) (xy 208.222069 -16.206408) (xy 208.293962 -16.15566)
			(xy 208.370171 -16.11166) (xy 208.450066 -16.074773) (xy 208.532985 -16.045304) (xy 208.61824 -16.023497)
			(xy 208.705124 -16.009533) (xy 208.792918 -16.003527) (xy 208.880895 -16.005531) (xy 208.968325 -16.015526)
			(xy 209.054484 -16.03343) (xy 209.138658 -16.059094) (xy 209.220149 -16.092307) (xy 209.298283 -16.132793)
			(xy 209.372411 -16.180215) (xy 209.441919 -16.234182) (xy 209.506233 -16.294247) (xy 209.564817 -16.359911)
			(xy 209.617188 -16.43063) (xy 209.662911 -16.505818) (xy 209.701608 -16.584853) (xy 209.732957 -16.667079)
			(xy 209.756699 -16.751815) (xy 209.772637 -16.838359) (xy 209.780639 -16.925994) (xy 209.78114 -16.969994)
			(xy 245.948207 -16.969994) (xy 245.952212 -16.882086) (xy 245.964195 -16.794906) (xy 245.984055 -16.709177)
			(xy 246.01163 -16.625609) (xy 246.046689 -16.544895) (xy 246.088942 -16.467703) (xy 246.13804 -16.394674)
			(xy 246.193576 -16.326412) (xy 246.255088 -16.263482) (xy 246.322069 -16.206408) (xy 246.393962 -16.15566)
			(xy 246.470171 -16.11166) (xy 246.550066 -16.074773) (xy 246.632985 -16.045304) (xy 246.71824 -16.023497)
			(xy 246.805124 -16.009533) (xy 246.892918 -16.003527) (xy 246.980895 -16.005531) (xy 247.068325 -16.015526)
			(xy 247.154484 -16.03343) (xy 247.238658 -16.059094) (xy 247.320149 -16.092307) (xy 247.398283 -16.132793)
			(xy 247.472411 -16.180215) (xy 247.541919 -16.234182) (xy 247.606233 -16.294247) (xy 247.664817 -16.359911)
			(xy 247.717188 -16.43063) (xy 247.762911 -16.505818) (xy 247.801608 -16.584853) (xy 247.832957 -16.667079)
			(xy 247.856699 -16.751815) (xy 247.872637 -16.838359) (xy 247.880639 -16.925994) (xy 247.88114 -16.969994)
			(xy 271.948155 -16.969994) (xy 271.95216 -16.882086) (xy 271.964143 -16.794906) (xy 271.984003 -16.709177)
			(xy 272.011578 -16.625609) (xy 272.046637 -16.544895) (xy 272.08889 -16.467703) (xy 272.137988 -16.394674)
			(xy 272.193524 -16.326412) (xy 272.255036 -16.263482) (xy 272.322017 -16.206408) (xy 272.39391 -16.15566)
			(xy 272.470119 -16.11166) (xy 272.550014 -16.074773) (xy 272.632933 -16.045304) (xy 272.718188 -16.023497)
			(xy 272.805072 -16.009533) (xy 272.892866 -16.003527) (xy 272.980843 -16.005531) (xy 273.068273 -16.015526)
			(xy 273.154432 -16.03343) (xy 273.238606 -16.059094) (xy 273.320097 -16.092307) (xy 273.398231 -16.132793)
			(xy 273.472359 -16.180215) (xy 273.541867 -16.234182) (xy 273.606181 -16.294247) (xy 273.664765 -16.359911)
			(xy 273.717136 -16.43063) (xy 273.762859 -16.505818) (xy 273.801556 -16.584853) (xy 273.832905 -16.667079)
			(xy 273.856647 -16.751815) (xy 273.872585 -16.838359) (xy 273.880587 -16.925994) (xy 273.881088 -16.969994)
			(xy 297.948103 -16.969994) (xy 297.952108 -16.882086) (xy 297.964091 -16.794906) (xy 297.983951 -16.709177)
			(xy 298.011526 -16.625609) (xy 298.046585 -16.544895) (xy 298.088838 -16.467703) (xy 298.137936 -16.394674)
			(xy 298.193472 -16.326412) (xy 298.254984 -16.263482) (xy 298.321965 -16.206408) (xy 298.393858 -16.15566)
			(xy 298.470067 -16.11166) (xy 298.549962 -16.074773) (xy 298.632881 -16.045304) (xy 298.718136 -16.023497)
			(xy 298.80502 -16.009533) (xy 298.892814 -16.003527) (xy 298.980791 -16.005531) (xy 299.068221 -16.015526)
			(xy 299.15438 -16.03343) (xy 299.238554 -16.059094) (xy 299.320045 -16.092307) (xy 299.398179 -16.132793)
			(xy 299.472307 -16.180215) (xy 299.541815 -16.234182) (xy 299.606129 -16.294247) (xy 299.664713 -16.359911)
			(xy 299.717084 -16.43063) (xy 299.762807 -16.505818) (xy 299.801504 -16.584853) (xy 299.832853 -16.667079)
			(xy 299.856595 -16.751815) (xy 299.872533 -16.838359) (xy 299.880535 -16.925994) (xy 299.881036 -16.969994)
			(xy 323.948051 -16.969994) (xy 323.952056 -16.882086) (xy 323.964039 -16.794906) (xy 323.983899 -16.709177)
			(xy 324.011474 -16.625609) (xy 324.046533 -16.544895) (xy 324.088786 -16.467703) (xy 324.137884 -16.394674)
			(xy 324.19342 -16.326412) (xy 324.254932 -16.263482) (xy 324.321913 -16.206408) (xy 324.393806 -16.15566)
			(xy 324.470015 -16.11166) (xy 324.54991 -16.074773) (xy 324.632829 -16.045304) (xy 324.718084 -16.023497)
			(xy 324.804968 -16.009533) (xy 324.892762 -16.003527) (xy 324.980739 -16.005531) (xy 325.068169 -16.015526)
			(xy 325.154328 -16.03343) (xy 325.238502 -16.059094) (xy 325.319993 -16.092307) (xy 325.398127 -16.132793)
			(xy 325.472255 -16.180215) (xy 325.541763 -16.234182) (xy 325.606077 -16.294247) (xy 325.664661 -16.359911)
			(xy 325.717032 -16.43063) (xy 325.762755 -16.505818) (xy 325.801452 -16.584853) (xy 325.832801 -16.667079)
			(xy 325.856543 -16.751815) (xy 325.872481 -16.838359) (xy 325.880483 -16.925994) (xy 325.880984 -16.969994)
			(xy 362.048305 -16.969994) (xy 362.05231 -16.882086) (xy 362.064293 -16.794906) (xy 362.084153 -16.709177)
			(xy 362.111728 -16.625609) (xy 362.146787 -16.544895) (xy 362.18904 -16.467703) (xy 362.238138 -16.394674)
			(xy 362.293674 -16.326412) (xy 362.355186 -16.263482) (xy 362.422167 -16.206408) (xy 362.49406 -16.15566)
			(xy 362.570269 -16.11166) (xy 362.650164 -16.074773) (xy 362.733083 -16.045304) (xy 362.818338 -16.023497)
			(xy 362.905222 -16.009533) (xy 362.993016 -16.003527) (xy 363.080993 -16.005531) (xy 363.168423 -16.015526)
			(xy 363.254582 -16.03343) (xy 363.338756 -16.059094) (xy 363.420247 -16.092307) (xy 363.498381 -16.132793)
			(xy 363.572509 -16.180215) (xy 363.642017 -16.234182) (xy 363.706331 -16.294247) (xy 363.764915 -16.359911)
			(xy 363.817286 -16.43063) (xy 363.863009 -16.505818) (xy 363.901706 -16.584853) (xy 363.933055 -16.667079)
			(xy 363.956797 -16.751815) (xy 363.972735 -16.838359) (xy 363.980737 -16.925994) (xy 363.981238 -16.969994)
			(xy 388.048253 -16.969994) (xy 388.052258 -16.882086) (xy 388.064241 -16.794906) (xy 388.084101 -16.709177)
			(xy 388.111676 -16.625609) (xy 388.146735 -16.544895) (xy 388.188988 -16.467703) (xy 388.238086 -16.394674)
			(xy 388.293622 -16.326412) (xy 388.355134 -16.263482) (xy 388.422115 -16.206408) (xy 388.494008 -16.15566)
			(xy 388.570217 -16.11166) (xy 388.650112 -16.074773) (xy 388.733031 -16.045304) (xy 388.818286 -16.023497)
			(xy 388.90517 -16.009533) (xy 388.992964 -16.003527) (xy 389.080941 -16.005531) (xy 389.168371 -16.015526)
			(xy 389.25453 -16.03343) (xy 389.338704 -16.059094) (xy 389.420195 -16.092307) (xy 389.498329 -16.132793)
			(xy 389.572457 -16.180215) (xy 389.641965 -16.234182) (xy 389.706279 -16.294247) (xy 389.764863 -16.359911)
			(xy 389.817234 -16.43063) (xy 389.862957 -16.505818) (xy 389.901654 -16.584853) (xy 389.933003 -16.667079)
			(xy 389.956745 -16.751815) (xy 389.972683 -16.838359) (xy 389.980685 -16.925994) (xy 389.981186 -16.969994)
			(xy 414.048201 -16.969994) (xy 414.052206 -16.882086) (xy 414.064189 -16.794906) (xy 414.084049 -16.709177)
			(xy 414.111624 -16.625609) (xy 414.146683 -16.544895) (xy 414.188936 -16.467703) (xy 414.238034 -16.394674)
			(xy 414.29357 -16.326412) (xy 414.355082 -16.263482) (xy 414.422063 -16.206408) (xy 414.493956 -16.15566)
			(xy 414.570165 -16.11166) (xy 414.65006 -16.074773) (xy 414.732979 -16.045304) (xy 414.818234 -16.023497)
			(xy 414.905118 -16.009533) (xy 414.992912 -16.003527) (xy 415.080889 -16.005531) (xy 415.168319 -16.015526)
			(xy 415.254478 -16.03343) (xy 415.338652 -16.059094) (xy 415.420143 -16.092307) (xy 415.498277 -16.132793)
			(xy 415.572405 -16.180215) (xy 415.641913 -16.234182) (xy 415.706227 -16.294247) (xy 415.764811 -16.359911)
			(xy 415.817182 -16.43063) (xy 415.862905 -16.505818) (xy 415.901602 -16.584853) (xy 415.932951 -16.667079)
			(xy 415.956693 -16.751815) (xy 415.972631 -16.838359) (xy 415.980633 -16.925994) (xy 415.981134 -16.969994)
			(xy 440.048149 -16.969994) (xy 440.052154 -16.882086) (xy 440.064137 -16.794906) (xy 440.083997 -16.709177)
			(xy 440.111572 -16.625609) (xy 440.146631 -16.544895) (xy 440.188884 -16.467703) (xy 440.237982 -16.394674)
			(xy 440.293518 -16.326412) (xy 440.35503 -16.263482) (xy 440.422011 -16.206408) (xy 440.493904 -16.15566)
			(xy 440.570113 -16.11166) (xy 440.650008 -16.074773) (xy 440.732927 -16.045304) (xy 440.818182 -16.023497)
			(xy 440.905066 -16.009533) (xy 440.99286 -16.003527) (xy 441.080837 -16.005531) (xy 441.168267 -16.015526)
			(xy 441.254426 -16.03343) (xy 441.3386 -16.059094) (xy 441.420091 -16.092307) (xy 441.498225 -16.132793)
			(xy 441.572353 -16.180215) (xy 441.641861 -16.234182) (xy 441.706175 -16.294247) (xy 441.764759 -16.359911)
			(xy 441.81713 -16.43063) (xy 441.862853 -16.505818) (xy 441.90155 -16.584853) (xy 441.932899 -16.667079)
			(xy 441.956641 -16.751815) (xy 441.972579 -16.838359) (xy 441.980581 -16.925994) (xy 441.981082 -16.969994)
			(xy 441.980581 -17.013994) (xy 441.972579 -17.101629) (xy 441.956641 -17.188173) (xy 441.932899 -17.272909)
			(xy 441.90155 -17.355135) (xy 441.862853 -17.43417) (xy 441.81713 -17.509358) (xy 441.764759 -17.580077)
			(xy 441.706175 -17.645741) (xy 441.641861 -17.705806) (xy 441.572353 -17.759773) (xy 441.498225 -17.807195)
			(xy 441.420091 -17.847681) (xy 441.3386 -17.880894) (xy 441.254426 -17.906558) (xy 441.168267 -17.924462)
			(xy 441.080837 -17.934457) (xy 440.99286 -17.936461) (xy 440.905066 -17.930455) (xy 440.818182 -17.916491)
			(xy 440.732927 -17.894684) (xy 440.650008 -17.865215) (xy 440.570113 -17.828328) (xy 440.493904 -17.784328)
			(xy 440.422011 -17.73358) (xy 440.35503 -17.676506) (xy 440.293518 -17.613576) (xy 440.237982 -17.545314)
			(xy 440.188884 -17.472285) (xy 440.146631 -17.395093) (xy 440.111572 -17.314379) (xy 440.083997 -17.230811)
			(xy 440.064137 -17.145082) (xy 440.052154 -17.057902) (xy 440.048149 -16.969994) (xy 415.981134 -16.969994)
			(xy 415.980633 -17.013994) (xy 415.972631 -17.101629) (xy 415.956693 -17.188173) (xy 415.932951 -17.272909)
			(xy 415.901602 -17.355135) (xy 415.862905 -17.43417) (xy 415.817182 -17.509358) (xy 415.764811 -17.580077)
			(xy 415.706227 -17.645741) (xy 415.641913 -17.705806) (xy 415.572405 -17.759773) (xy 415.498277 -17.807195)
			(xy 415.420143 -17.847681) (xy 415.338652 -17.880894) (xy 415.254478 -17.906558) (xy 415.168319 -17.924462)
			(xy 415.080889 -17.934457) (xy 414.992912 -17.936461) (xy 414.905118 -17.930455) (xy 414.818234 -17.916491)
			(xy 414.732979 -17.894684) (xy 414.65006 -17.865215) (xy 414.570165 -17.828328) (xy 414.493956 -17.784328)
			(xy 414.422063 -17.73358) (xy 414.355082 -17.676506) (xy 414.29357 -17.613576) (xy 414.238034 -17.545314)
			(xy 414.188936 -17.472285) (xy 414.146683 -17.395093) (xy 414.111624 -17.314379) (xy 414.084049 -17.230811)
			(xy 414.064189 -17.145082) (xy 414.052206 -17.057902) (xy 414.048201 -16.969994) (xy 389.981186 -16.969994)
			(xy 389.980685 -17.013994) (xy 389.972683 -17.101629) (xy 389.956745 -17.188173) (xy 389.933003 -17.272909)
			(xy 389.901654 -17.355135) (xy 389.862957 -17.43417) (xy 389.817234 -17.509358) (xy 389.764863 -17.580077)
			(xy 389.706279 -17.645741) (xy 389.641965 -17.705806) (xy 389.572457 -17.759773) (xy 389.498329 -17.807195)
			(xy 389.420195 -17.847681) (xy 389.338704 -17.880894) (xy 389.25453 -17.906558) (xy 389.168371 -17.924462)
			(xy 389.080941 -17.934457) (xy 388.992964 -17.936461) (xy 388.90517 -17.930455) (xy 388.818286 -17.916491)
			(xy 388.733031 -17.894684) (xy 388.650112 -17.865215) (xy 388.570217 -17.828328) (xy 388.494008 -17.784328)
			(xy 388.422115 -17.73358) (xy 388.355134 -17.676506) (xy 388.293622 -17.613576) (xy 388.238086 -17.545314)
			(xy 388.188988 -17.472285) (xy 388.146735 -17.395093) (xy 388.111676 -17.314379) (xy 388.084101 -17.230811)
			(xy 388.064241 -17.145082) (xy 388.052258 -17.057902) (xy 388.048253 -16.969994) (xy 363.981238 -16.969994)
			(xy 363.980737 -17.013994) (xy 363.972735 -17.101629) (xy 363.956797 -17.188173) (xy 363.933055 -17.272909)
			(xy 363.901706 -17.355135) (xy 363.863009 -17.43417) (xy 363.817286 -17.509358) (xy 363.764915 -17.580077)
			(xy 363.706331 -17.645741) (xy 363.642017 -17.705806) (xy 363.572509 -17.759773) (xy 363.498381 -17.807195)
			(xy 363.420247 -17.847681) (xy 363.338756 -17.880894) (xy 363.254582 -17.906558) (xy 363.168423 -17.924462)
			(xy 363.080993 -17.934457) (xy 362.993016 -17.936461) (xy 362.905222 -17.930455) (xy 362.818338 -17.916491)
			(xy 362.733083 -17.894684) (xy 362.650164 -17.865215) (xy 362.570269 -17.828328) (xy 362.49406 -17.784328)
			(xy 362.422167 -17.73358) (xy 362.355186 -17.676506) (xy 362.293674 -17.613576) (xy 362.238138 -17.545314)
			(xy 362.18904 -17.472285) (xy 362.146787 -17.395093) (xy 362.111728 -17.314379) (xy 362.084153 -17.230811)
			(xy 362.064293 -17.145082) (xy 362.05231 -17.057902) (xy 362.048305 -16.969994) (xy 325.880984 -16.969994)
			(xy 325.880483 -17.013994) (xy 325.872481 -17.101629) (xy 325.856543 -17.188173) (xy 325.832801 -17.272909)
			(xy 325.801452 -17.355135) (xy 325.762755 -17.43417) (xy 325.717032 -17.509358) (xy 325.664661 -17.580077)
			(xy 325.606077 -17.645741) (xy 325.541763 -17.705806) (xy 325.472255 -17.759773) (xy 325.398127 -17.807195)
			(xy 325.319993 -17.847681) (xy 325.238502 -17.880894) (xy 325.154328 -17.906558) (xy 325.068169 -17.924462)
			(xy 324.980739 -17.934457) (xy 324.892762 -17.936461) (xy 324.804968 -17.930455) (xy 324.718084 -17.916491)
			(xy 324.632829 -17.894684) (xy 324.54991 -17.865215) (xy 324.470015 -17.828328) (xy 324.393806 -17.784328)
			(xy 324.321913 -17.73358) (xy 324.254932 -17.676506) (xy 324.19342 -17.613576) (xy 324.137884 -17.545314)
			(xy 324.088786 -17.472285) (xy 324.046533 -17.395093) (xy 324.011474 -17.314379) (xy 323.983899 -17.230811)
			(xy 323.964039 -17.145082) (xy 323.952056 -17.057902) (xy 323.948051 -16.969994) (xy 299.881036 -16.969994)
			(xy 299.880535 -17.013994) (xy 299.872533 -17.101629) (xy 299.856595 -17.188173) (xy 299.832853 -17.272909)
			(xy 299.801504 -17.355135) (xy 299.762807 -17.43417) (xy 299.717084 -17.509358) (xy 299.664713 -17.580077)
			(xy 299.606129 -17.645741) (xy 299.541815 -17.705806) (xy 299.472307 -17.759773) (xy 299.398179 -17.807195)
			(xy 299.320045 -17.847681) (xy 299.238554 -17.880894) (xy 299.15438 -17.906558) (xy 299.068221 -17.924462)
			(xy 298.980791 -17.934457) (xy 298.892814 -17.936461) (xy 298.80502 -17.930455) (xy 298.718136 -17.916491)
			(xy 298.632881 -17.894684) (xy 298.549962 -17.865215) (xy 298.470067 -17.828328) (xy 298.393858 -17.784328)
			(xy 298.321965 -17.73358) (xy 298.254984 -17.676506) (xy 298.193472 -17.613576) (xy 298.137936 -17.545314)
			(xy 298.088838 -17.472285) (xy 298.046585 -17.395093) (xy 298.011526 -17.314379) (xy 297.983951 -17.230811)
			(xy 297.964091 -17.145082) (xy 297.952108 -17.057902) (xy 297.948103 -16.969994) (xy 273.881088 -16.969994)
			(xy 273.880587 -17.013994) (xy 273.872585 -17.101629) (xy 273.856647 -17.188173) (xy 273.832905 -17.272909)
			(xy 273.801556 -17.355135) (xy 273.762859 -17.43417) (xy 273.717136 -17.509358) (xy 273.664765 -17.580077)
			(xy 273.606181 -17.645741) (xy 273.541867 -17.705806) (xy 273.472359 -17.759773) (xy 273.398231 -17.807195)
			(xy 273.320097 -17.847681) (xy 273.238606 -17.880894) (xy 273.154432 -17.906558) (xy 273.068273 -17.924462)
			(xy 272.980843 -17.934457) (xy 272.892866 -17.936461) (xy 272.805072 -17.930455) (xy 272.718188 -17.916491)
			(xy 272.632933 -17.894684) (xy 272.550014 -17.865215) (xy 272.470119 -17.828328) (xy 272.39391 -17.784328)
			(xy 272.322017 -17.73358) (xy 272.255036 -17.676506) (xy 272.193524 -17.613576) (xy 272.137988 -17.545314)
			(xy 272.08889 -17.472285) (xy 272.046637 -17.395093) (xy 272.011578 -17.314379) (xy 271.984003 -17.230811)
			(xy 271.964143 -17.145082) (xy 271.95216 -17.057902) (xy 271.948155 -16.969994) (xy 247.88114 -16.969994)
			(xy 247.880639 -17.013994) (xy 247.872637 -17.101629) (xy 247.856699 -17.188173) (xy 247.832957 -17.272909)
			(xy 247.801608 -17.355135) (xy 247.762911 -17.43417) (xy 247.717188 -17.509358) (xy 247.664817 -17.580077)
			(xy 247.606233 -17.645741) (xy 247.541919 -17.705806) (xy 247.472411 -17.759773) (xy 247.398283 -17.807195)
			(xy 247.320149 -17.847681) (xy 247.238658 -17.880894) (xy 247.154484 -17.906558) (xy 247.068325 -17.924462)
			(xy 246.980895 -17.934457) (xy 246.892918 -17.936461) (xy 246.805124 -17.930455) (xy 246.71824 -17.916491)
			(xy 246.632985 -17.894684) (xy 246.550066 -17.865215) (xy 246.470171 -17.828328) (xy 246.393962 -17.784328)
			(xy 246.322069 -17.73358) (xy 246.255088 -17.676506) (xy 246.193576 -17.613576) (xy 246.13804 -17.545314)
			(xy 246.088942 -17.472285) (xy 246.046689 -17.395093) (xy 246.01163 -17.314379) (xy 245.984055 -17.230811)
			(xy 245.964195 -17.145082) (xy 245.952212 -17.057902) (xy 245.948207 -16.969994) (xy 209.78114 -16.969994)
			(xy 209.780639 -17.013994) (xy 209.772637 -17.101629) (xy 209.756699 -17.188173) (xy 209.732957 -17.272909)
			(xy 209.701608 -17.355135) (xy 209.662911 -17.43417) (xy 209.617188 -17.509358) (xy 209.564817 -17.580077)
			(xy 209.506233 -17.645741) (xy 209.441919 -17.705806) (xy 209.372411 -17.759773) (xy 209.298283 -17.807195)
			(xy 209.220149 -17.847681) (xy 209.138658 -17.880894) (xy 209.054484 -17.906558) (xy 208.968325 -17.924462)
			(xy 208.880895 -17.934457) (xy 208.792918 -17.936461) (xy 208.705124 -17.930455) (xy 208.61824 -17.916491)
			(xy 208.532985 -17.894684) (xy 208.450066 -17.865215) (xy 208.370171 -17.828328) (xy 208.293962 -17.784328)
			(xy 208.222069 -17.73358) (xy 208.155088 -17.676506) (xy 208.093576 -17.613576) (xy 208.03804 -17.545314)
			(xy 207.988942 -17.472285) (xy 207.946689 -17.395093) (xy 207.91163 -17.314379) (xy 207.884055 -17.230811)
			(xy 207.864195 -17.145082) (xy 207.852212 -17.057902) (xy 207.848207 -16.969994) (xy 183.781192 -16.969994)
			(xy 183.780691 -17.013994) (xy 183.772689 -17.101629) (xy 183.756751 -17.188173) (xy 183.733009 -17.272909)
			(xy 183.70166 -17.355135) (xy 183.662963 -17.43417) (xy 183.61724 -17.509358) (xy 183.564869 -17.580077)
			(xy 183.506285 -17.645741) (xy 183.441971 -17.705806) (xy 183.372463 -17.759773) (xy 183.298335 -17.807195)
			(xy 183.220201 -17.847681) (xy 183.13871 -17.880894) (xy 183.054536 -17.906558) (xy 182.968377 -17.924462)
			(xy 182.880947 -17.934457) (xy 182.79297 -17.936461) (xy 182.705176 -17.930455) (xy 182.618292 -17.916491)
			(xy 182.533037 -17.894684) (xy 182.450118 -17.865215) (xy 182.370223 -17.828328) (xy 182.294014 -17.784328)
			(xy 182.222121 -17.73358) (xy 182.15514 -17.676506) (xy 182.093628 -17.613576) (xy 182.038092 -17.545314)
			(xy 181.988994 -17.472285) (xy 181.946741 -17.395093) (xy 181.911682 -17.314379) (xy 181.884107 -17.230811)
			(xy 181.864247 -17.145082) (xy 181.852264 -17.057902) (xy 181.848259 -16.969994) (xy 157.781244 -16.969994)
			(xy 157.780743 -17.013994) (xy 157.772741 -17.101629) (xy 157.756803 -17.188173) (xy 157.733061 -17.272909)
			(xy 157.701712 -17.355135) (xy 157.663015 -17.43417) (xy 157.617292 -17.509358) (xy 157.564921 -17.580077)
			(xy 157.506337 -17.645741) (xy 157.442023 -17.705806) (xy 157.372515 -17.759773) (xy 157.298387 -17.807195)
			(xy 157.220253 -17.847681) (xy 157.138762 -17.880894) (xy 157.054588 -17.906558) (xy 156.968429 -17.924462)
			(xy 156.880999 -17.934457) (xy 156.793022 -17.936461) (xy 156.705228 -17.930455) (xy 156.618344 -17.916491)
			(xy 156.533089 -17.894684) (xy 156.45017 -17.865215) (xy 156.370275 -17.828328) (xy 156.294066 -17.784328)
			(xy 156.222173 -17.73358) (xy 156.155192 -17.676506) (xy 156.09368 -17.613576) (xy 156.038144 -17.545314)
			(xy 155.989046 -17.472285) (xy 155.946793 -17.395093) (xy 155.911734 -17.314379) (xy 155.884159 -17.230811)
			(xy 155.864299 -17.145082) (xy 155.852316 -17.057902) (xy 155.848311 -16.969994) (xy 131.781296 -16.969994)
			(xy 131.780795 -17.013994) (xy 131.772793 -17.101629) (xy 131.756855 -17.188173) (xy 131.733113 -17.272909)
			(xy 131.701764 -17.355135) (xy 131.663067 -17.43417) (xy 131.617344 -17.509358) (xy 131.564973 -17.580077)
			(xy 131.506389 -17.645741) (xy 131.442075 -17.705806) (xy 131.372567 -17.759773) (xy 131.298439 -17.807195)
			(xy 131.220305 -17.847681) (xy 131.138814 -17.880894) (xy 131.05464 -17.906558) (xy 130.968481 -17.924462)
			(xy 130.881051 -17.934457) (xy 130.793074 -17.936461) (xy 130.70528 -17.930455) (xy 130.618396 -17.916491)
			(xy 130.533141 -17.894684) (xy 130.450222 -17.865215) (xy 130.370327 -17.828328) (xy 130.294118 -17.784328)
			(xy 130.222225 -17.73358) (xy 130.155244 -17.676506) (xy 130.093732 -17.613576) (xy 130.038196 -17.545314)
			(xy 129.989098 -17.472285) (xy 129.946845 -17.395093) (xy 129.911786 -17.314379) (xy 129.884211 -17.230811)
			(xy 129.864351 -17.145082) (xy 129.852368 -17.057902) (xy 129.848363 -16.969994) (xy 93.681042 -16.969994)
			(xy 93.680541 -17.013994) (xy 93.672539 -17.101629) (xy 93.656601 -17.188173) (xy 93.632859 -17.272909)
			(xy 93.60151 -17.355135) (xy 93.562813 -17.43417) (xy 93.51709 -17.509358) (xy 93.464719 -17.580077)
			(xy 93.406135 -17.645741) (xy 93.341821 -17.705806) (xy 93.272313 -17.759773) (xy 93.198185 -17.807195)
			(xy 93.120051 -17.847681) (xy 93.03856 -17.880894) (xy 92.954386 -17.906558) (xy 92.868227 -17.924462)
			(xy 92.780797 -17.934457) (xy 92.69282 -17.936461) (xy 92.605026 -17.930455) (xy 92.518142 -17.916491)
			(xy 92.432887 -17.894684) (xy 92.349968 -17.865215) (xy 92.270073 -17.828328) (xy 92.193864 -17.784328)
			(xy 92.121971 -17.73358) (xy 92.05499 -17.676506) (xy 91.993478 -17.613576) (xy 91.937942 -17.545314)
			(xy 91.888844 -17.472285) (xy 91.846591 -17.395093) (xy 91.811532 -17.314379) (xy 91.783957 -17.230811)
			(xy 91.764097 -17.145082) (xy 91.752114 -17.057902) (xy 91.748109 -16.969994) (xy 67.681094 -16.969994)
			(xy 67.680593 -17.013994) (xy 67.672591 -17.101629) (xy 67.656653 -17.188173) (xy 67.632911 -17.272909)
			(xy 67.601562 -17.355135) (xy 67.562865 -17.43417) (xy 67.517142 -17.509358) (xy 67.464771 -17.580077)
			(xy 67.406187 -17.645741) (xy 67.341873 -17.705806) (xy 67.272365 -17.759773) (xy 67.198237 -17.807195)
			(xy 67.120103 -17.847681) (xy 67.038612 -17.880894) (xy 66.954438 -17.906558) (xy 66.868279 -17.924462)
			(xy 66.780849 -17.934457) (xy 66.692872 -17.936461) (xy 66.605078 -17.930455) (xy 66.518194 -17.916491)
			(xy 66.432939 -17.894684) (xy 66.35002 -17.865215) (xy 66.270125 -17.828328) (xy 66.193916 -17.784328)
			(xy 66.122023 -17.73358) (xy 66.055042 -17.676506) (xy 65.99353 -17.613576) (xy 65.937994 -17.545314)
			(xy 65.888896 -17.472285) (xy 65.846643 -17.395093) (xy 65.811584 -17.314379) (xy 65.784009 -17.230811)
			(xy 65.764149 -17.145082) (xy 65.752166 -17.057902) (xy 65.748161 -16.969994) (xy 41.681146 -16.969994)
			(xy 41.680645 -17.013994) (xy 41.672643 -17.101629) (xy 41.656705 -17.188173) (xy 41.632963 -17.272909)
			(xy 41.601614 -17.355135) (xy 41.562917 -17.43417) (xy 41.517194 -17.509358) (xy 41.464823 -17.580077)
			(xy 41.406239 -17.645741) (xy 41.341925 -17.705806) (xy 41.272417 -17.759773) (xy 41.198289 -17.807195)
			(xy 41.120155 -17.847681) (xy 41.038664 -17.880894) (xy 40.95449 -17.906558) (xy 40.868331 -17.924462)
			(xy 40.780901 -17.934457) (xy 40.692924 -17.936461) (xy 40.60513 -17.930455) (xy 40.518246 -17.916491)
			(xy 40.432991 -17.894684) (xy 40.350072 -17.865215) (xy 40.270177 -17.828328) (xy 40.193968 -17.784328)
			(xy 40.122075 -17.73358) (xy 40.055094 -17.676506) (xy 39.993582 -17.613576) (xy 39.938046 -17.545314)
			(xy 39.888948 -17.472285) (xy 39.846695 -17.395093) (xy 39.811636 -17.314379) (xy 39.784061 -17.230811)
			(xy 39.764201 -17.145082) (xy 39.752218 -17.057902) (xy 39.748213 -16.969994) (xy 15.681198 -16.969994)
			(xy 15.680697 -17.013994) (xy 15.672695 -17.101629) (xy 15.656757 -17.188173) (xy 15.633015 -17.272909)
			(xy 15.601666 -17.355135) (xy 15.562969 -17.43417) (xy 15.517246 -17.509358) (xy 15.464875 -17.580077)
			(xy 15.406291 -17.645741) (xy 15.341977 -17.705806) (xy 15.272469 -17.759773) (xy 15.198341 -17.807195)
			(xy 15.120207 -17.847681) (xy 15.038716 -17.880894) (xy 14.954542 -17.906558) (xy 14.868383 -17.924462)
			(xy 14.780953 -17.934457) (xy 14.692976 -17.936461) (xy 14.605182 -17.930455) (xy 14.518298 -17.916491)
			(xy 14.433043 -17.894684) (xy 14.350124 -17.865215) (xy 14.270229 -17.828328) (xy 14.19402 -17.784328)
			(xy 14.122127 -17.73358) (xy 14.055146 -17.676506) (xy 13.993634 -17.613576) (xy 13.938098 -17.545314)
			(xy 13.889 -17.472285) (xy 13.846747 -17.395093) (xy 13.811688 -17.314379) (xy 13.784113 -17.230811)
			(xy 13.764253 -17.145082) (xy 13.75227 -17.057902) (xy 13.748265 -16.969994) (xy 0.508 -16.969994)
			(xy 0.508 -27.342846) (xy 16.523716 -27.342846) (xy 16.523716 -26.479246) (xy 16.524206 -26.449278)
			(xy 16.532029 -26.389856) (xy 16.547542 -26.331963) (xy 16.570478 -26.27659) (xy 16.600445 -26.224684)
			(xy 16.636932 -26.177134) (xy 16.679312 -26.134754) (xy 16.726862 -26.098267) (xy 16.778768 -26.0683)
			(xy 16.834141 -26.045364) (xy 16.892034 -26.029851) (xy 16.951456 -26.022028) (xy 17.011392 -26.022028)
			(xy 17.070814 -26.029851) (xy 17.128707 -26.045364) (xy 17.18408 -26.0683) (xy 17.235986 -26.098267)
			(xy 17.283536 -26.134754) (xy 17.325916 -26.177134) (xy 17.362403 -26.224684) (xy 17.39237 -26.27659)
			(xy 17.415306 -26.331963) (xy 17.430819 -26.389856) (xy 17.438642 -26.449278) (xy 17.439132 -26.479246)
			(xy 17.439132 -27.342846) (xy 42.523664 -27.342846) (xy 42.523664 -26.479246) (xy 42.524154 -26.449278)
			(xy 42.531977 -26.389856) (xy 42.54749 -26.331963) (xy 42.570426 -26.27659) (xy 42.600393 -26.224684)
			(xy 42.63688 -26.177134) (xy 42.67926 -26.134754) (xy 42.72681 -26.098267) (xy 42.778716 -26.0683)
			(xy 42.834089 -26.045364) (xy 42.891982 -26.029851) (xy 42.951404 -26.022028) (xy 43.01134 -26.022028)
			(xy 43.070762 -26.029851) (xy 43.128655 -26.045364) (xy 43.184028 -26.0683) (xy 43.235934 -26.098267)
			(xy 43.283484 -26.134754) (xy 43.325864 -26.177134) (xy 43.362351 -26.224684) (xy 43.392318 -26.27659)
			(xy 43.415254 -26.331963) (xy 43.430767 -26.389856) (xy 43.43859 -26.449278) (xy 43.43908 -26.479246)
			(xy 43.43908 -27.342846) (xy 68.523612 -27.342846) (xy 68.523612 -26.479246) (xy 68.524102 -26.449278)
			(xy 68.531925 -26.389856) (xy 68.547438 -26.331963) (xy 68.570374 -26.27659) (xy 68.600341 -26.224684)
			(xy 68.636828 -26.177134) (xy 68.679208 -26.134754) (xy 68.726758 -26.098267) (xy 68.778664 -26.0683)
			(xy 68.834037 -26.045364) (xy 68.89193 -26.029851) (xy 68.951352 -26.022028) (xy 69.011288 -26.022028)
			(xy 69.07071 -26.029851) (xy 69.128603 -26.045364) (xy 69.183976 -26.0683) (xy 69.235882 -26.098267)
			(xy 69.283432 -26.134754) (xy 69.325812 -26.177134) (xy 69.362299 -26.224684) (xy 69.392266 -26.27659)
			(xy 69.415202 -26.331963) (xy 69.430715 -26.389856) (xy 69.438538 -26.449278) (xy 69.439028 -26.479246)
			(xy 69.439028 -27.342846) (xy 94.52356 -27.342846) (xy 94.52356 -26.479246) (xy 94.52405 -26.449278)
			(xy 94.531873 -26.389856) (xy 94.547386 -26.331963) (xy 94.570322 -26.27659) (xy 94.600289 -26.224684)
			(xy 94.636776 -26.177134) (xy 94.679156 -26.134754) (xy 94.726706 -26.098267) (xy 94.778612 -26.0683)
			(xy 94.833985 -26.045364) (xy 94.891878 -26.029851) (xy 94.9513 -26.022028) (xy 95.011236 -26.022028)
			(xy 95.070658 -26.029851) (xy 95.128551 -26.045364) (xy 95.183924 -26.0683) (xy 95.23583 -26.098267)
			(xy 95.28338 -26.134754) (xy 95.32576 -26.177134) (xy 95.362247 -26.224684) (xy 95.392214 -26.27659)
			(xy 95.41515 -26.331963) (xy 95.430663 -26.389856) (xy 95.438486 -26.449278) (xy 95.438976 -26.479246)
			(xy 95.438976 -27.342846) (xy 132.62356 -27.342846) (xy 132.62356 -26.479246) (xy 132.62405 -26.449262)
			(xy 132.631878 -26.389806) (xy 132.647399 -26.331881) (xy 132.670348 -26.276477) (xy 132.700332 -26.224543)
			(xy 132.736838 -26.176967) (xy 132.779243 -26.134562) (xy 132.826819 -26.098056) (xy 132.878753 -26.068072)
			(xy 132.934157 -26.045123) (xy 132.992082 -26.029602) (xy 133.051538 -26.021774) (xy 133.111506 -26.021774)
			(xy 133.170962 -26.029602) (xy 133.228887 -26.045123) (xy 133.284291 -26.068072) (xy 133.336225 -26.098056)
			(xy 133.383801 -26.134562) (xy 133.426206 -26.176967) (xy 133.462712 -26.224543) (xy 133.492696 -26.276477)
			(xy 133.515645 -26.331881) (xy 133.531166 -26.389806) (xy 133.538994 -26.449262) (xy 133.539484 -26.479246)
			(xy 133.539484 -27.342846) (xy 158.623508 -27.342846) (xy 158.623508 -26.479246) (xy 158.623998 -26.449262)
			(xy 158.631826 -26.389806) (xy 158.647347 -26.331881) (xy 158.670296 -26.276477) (xy 158.70028 -26.224543)
			(xy 158.736786 -26.176967) (xy 158.779191 -26.134562) (xy 158.826767 -26.098056) (xy 158.878701 -26.068072)
			(xy 158.934105 -26.045123) (xy 158.99203 -26.029602) (xy 159.051486 -26.021774) (xy 159.111454 -26.021774)
			(xy 159.17091 -26.029602) (xy 159.228835 -26.045123) (xy 159.284239 -26.068072) (xy 159.336173 -26.098056)
			(xy 159.383749 -26.134562) (xy 159.426154 -26.176967) (xy 159.46266 -26.224543) (xy 159.492644 -26.276477)
			(xy 159.515593 -26.331881) (xy 159.531114 -26.389806) (xy 159.538942 -26.449262) (xy 159.539432 -26.479246)
			(xy 159.539432 -27.342846) (xy 184.623456 -27.342846) (xy 184.623456 -26.479246) (xy 184.623946 -26.449262)
			(xy 184.631774 -26.389806) (xy 184.647295 -26.331881) (xy 184.670244 -26.276477) (xy 184.700228 -26.224543)
			(xy 184.736734 -26.176967) (xy 184.779139 -26.134562) (xy 184.826715 -26.098056) (xy 184.878649 -26.068072)
			(xy 184.934053 -26.045123) (xy 184.991978 -26.029602) (xy 185.051434 -26.021774) (xy 185.111402 -26.021774)
			(xy 185.170858 -26.029602) (xy 185.228783 -26.045123) (xy 185.284187 -26.068072) (xy 185.336121 -26.098056)
			(xy 185.383697 -26.134562) (xy 185.426102 -26.176967) (xy 185.462608 -26.224543) (xy 185.492592 -26.276477)
			(xy 185.515541 -26.331881) (xy 185.531062 -26.389806) (xy 185.53889 -26.449262) (xy 185.53938 -26.479246)
			(xy 185.53938 -27.342846) (xy 210.623404 -27.342846) (xy 210.623404 -26.479246) (xy 210.623894 -26.449262)
			(xy 210.631722 -26.389806) (xy 210.647243 -26.331881) (xy 210.670192 -26.276477) (xy 210.700176 -26.224543)
			(xy 210.736682 -26.176967) (xy 210.779087 -26.134562) (xy 210.826663 -26.098056) (xy 210.878597 -26.068072)
			(xy 210.934001 -26.045123) (xy 210.991926 -26.029602) (xy 211.051382 -26.021774) (xy 211.11135 -26.021774)
			(xy 211.170806 -26.029602) (xy 211.228731 -26.045123) (xy 211.284135 -26.068072) (xy 211.336069 -26.098056)
			(xy 211.383645 -26.134562) (xy 211.42605 -26.176967) (xy 211.462556 -26.224543) (xy 211.49254 -26.276477)
			(xy 211.515489 -26.331881) (xy 211.53101 -26.389806) (xy 211.538838 -26.449262) (xy 211.539328 -26.479246)
			(xy 211.539328 -27.342846) (xy 248.723404 -27.342846) (xy 248.723404 -26.479246) (xy 248.723894 -26.449262)
			(xy 248.731722 -26.389806) (xy 248.747243 -26.331881) (xy 248.770192 -26.276477) (xy 248.800176 -26.224543)
			(xy 248.836682 -26.176967) (xy 248.879087 -26.134562) (xy 248.926663 -26.098056) (xy 248.978597 -26.068072)
			(xy 249.034001 -26.045123) (xy 249.091926 -26.029602) (xy 249.151382 -26.021774) (xy 249.21135 -26.021774)
			(xy 249.270806 -26.029602) (xy 249.328731 -26.045123) (xy 249.384135 -26.068072) (xy 249.436069 -26.098056)
			(xy 249.483645 -26.134562) (xy 249.52605 -26.176967) (xy 249.562556 -26.224543) (xy 249.59254 -26.276477)
			(xy 249.615489 -26.331881) (xy 249.63101 -26.389806) (xy 249.638838 -26.449262) (xy 249.639328 -26.479246)
			(xy 249.639328 -27.342846) (xy 274.723352 -27.342846) (xy 274.723352 -26.479246) (xy 274.723842 -26.449262)
			(xy 274.73167 -26.389806) (xy 274.747191 -26.331881) (xy 274.77014 -26.276477) (xy 274.800124 -26.224543)
			(xy 274.83663 -26.176967) (xy 274.879035 -26.134562) (xy 274.926611 -26.098056) (xy 274.978545 -26.068072)
			(xy 275.033949 -26.045123) (xy 275.091874 -26.029602) (xy 275.15133 -26.021774) (xy 275.211298 -26.021774)
			(xy 275.270754 -26.029602) (xy 275.328679 -26.045123) (xy 275.384083 -26.068072) (xy 275.436017 -26.098056)
			(xy 275.483593 -26.134562) (xy 275.525998 -26.176967) (xy 275.562504 -26.224543) (xy 275.592488 -26.276477)
			(xy 275.615437 -26.331881) (xy 275.630958 -26.389806) (xy 275.638786 -26.449262) (xy 275.639276 -26.479246)
			(xy 275.639276 -27.342846) (xy 300.7233 -27.342846) (xy 300.7233 -26.479246) (xy 300.72379 -26.449262)
			(xy 300.731618 -26.389806) (xy 300.747139 -26.331881) (xy 300.770088 -26.276477) (xy 300.800072 -26.224543)
			(xy 300.836578 -26.176967) (xy 300.878983 -26.134562) (xy 300.926559 -26.098056) (xy 300.978493 -26.068072)
			(xy 301.033897 -26.045123) (xy 301.091822 -26.029602) (xy 301.151278 -26.021774) (xy 301.211246 -26.021774)
			(xy 301.270702 -26.029602) (xy 301.328627 -26.045123) (xy 301.384031 -26.068072) (xy 301.435965 -26.098056)
			(xy 301.483541 -26.134562) (xy 301.525946 -26.176967) (xy 301.562452 -26.224543) (xy 301.592436 -26.276477)
			(xy 301.615385 -26.331881) (xy 301.630906 -26.389806) (xy 301.638734 -26.449262) (xy 301.639224 -26.479246)
			(xy 301.639224 -27.342846) (xy 326.723248 -27.342846) (xy 326.723248 -26.479246) (xy 326.723738 -26.449262)
			(xy 326.731566 -26.389806) (xy 326.747087 -26.331881) (xy 326.770036 -26.276477) (xy 326.80002 -26.224543)
			(xy 326.836526 -26.176967) (xy 326.878931 -26.134562) (xy 326.926507 -26.098056) (xy 326.978441 -26.068072)
			(xy 327.033845 -26.045123) (xy 327.09177 -26.029602) (xy 327.151226 -26.021774) (xy 327.211194 -26.021774)
			(xy 327.27065 -26.029602) (xy 327.328575 -26.045123) (xy 327.383979 -26.068072) (xy 327.435913 -26.098056)
			(xy 327.483489 -26.134562) (xy 327.525894 -26.176967) (xy 327.5624 -26.224543) (xy 327.592384 -26.276477)
			(xy 327.615333 -26.331881) (xy 327.630854 -26.389806) (xy 327.638682 -26.449262) (xy 327.639172 -26.479246)
			(xy 327.639172 -27.342846) (xy 364.823756 -27.342846) (xy 364.823756 -26.479246) (xy 364.824246 -26.449278)
			(xy 364.832069 -26.389856) (xy 364.847582 -26.331963) (xy 364.870518 -26.27659) (xy 364.900485 -26.224684)
			(xy 364.936972 -26.177134) (xy 364.979352 -26.134754) (xy 365.026902 -26.098267) (xy 365.078808 -26.0683)
			(xy 365.134181 -26.045364) (xy 365.192074 -26.029851) (xy 365.251496 -26.022028) (xy 365.311432 -26.022028)
			(xy 365.370854 -26.029851) (xy 365.428747 -26.045364) (xy 365.48412 -26.0683) (xy 365.536026 -26.098267)
			(xy 365.583576 -26.134754) (xy 365.625956 -26.177134) (xy 365.662443 -26.224684) (xy 365.69241 -26.27659)
			(xy 365.715346 -26.331963) (xy 365.730859 -26.389856) (xy 365.738682 -26.449278) (xy 365.739172 -26.479246)
			(xy 365.739172 -27.342846) (xy 390.823704 -27.342846) (xy 390.823704 -26.479246) (xy 390.824194 -26.449278)
			(xy 390.832017 -26.389856) (xy 390.84753 -26.331963) (xy 390.870466 -26.27659) (xy 390.900433 -26.224684)
			(xy 390.93692 -26.177134) (xy 390.9793 -26.134754) (xy 391.02685 -26.098267) (xy 391.078756 -26.0683)
			(xy 391.134129 -26.045364) (xy 391.192022 -26.029851) (xy 391.251444 -26.022028) (xy 391.31138 -26.022028)
			(xy 391.370802 -26.029851) (xy 391.428695 -26.045364) (xy 391.484068 -26.0683) (xy 391.535974 -26.098267)
			(xy 391.583524 -26.134754) (xy 391.625904 -26.177134) (xy 391.662391 -26.224684) (xy 391.692358 -26.27659)
			(xy 391.715294 -26.331963) (xy 391.730807 -26.389856) (xy 391.73863 -26.449278) (xy 391.73912 -26.479246)
			(xy 391.73912 -27.342846) (xy 416.823652 -27.342846) (xy 416.823652 -26.479246) (xy 416.824142 -26.449278)
			(xy 416.831965 -26.389856) (xy 416.847478 -26.331963) (xy 416.870414 -26.27659) (xy 416.900381 -26.224684)
			(xy 416.936868 -26.177134) (xy 416.979248 -26.134754) (xy 417.026798 -26.098267) (xy 417.078704 -26.0683)
			(xy 417.134077 -26.045364) (xy 417.19197 -26.029851) (xy 417.251392 -26.022028) (xy 417.311328 -26.022028)
			(xy 417.37075 -26.029851) (xy 417.428643 -26.045364) (xy 417.484016 -26.0683) (xy 417.535922 -26.098267)
			(xy 417.583472 -26.134754) (xy 417.625852 -26.177134) (xy 417.662339 -26.224684) (xy 417.692306 -26.27659)
			(xy 417.715242 -26.331963) (xy 417.730755 -26.389856) (xy 417.738578 -26.449278) (xy 417.739068 -26.479246)
			(xy 417.739068 -27.342846) (xy 442.8236 -27.342846) (xy 442.8236 -26.479246) (xy 442.82409 -26.449278)
			(xy 442.831913 -26.389856) (xy 442.847426 -26.331963) (xy 442.870362 -26.27659) (xy 442.900329 -26.224684)
			(xy 442.936816 -26.177134) (xy 442.979196 -26.134754) (xy 443.026746 -26.098267) (xy 443.078652 -26.0683)
			(xy 443.134025 -26.045364) (xy 443.191918 -26.029851) (xy 443.25134 -26.022028) (xy 443.311276 -26.022028)
			(xy 443.370698 -26.029851) (xy 443.428591 -26.045364) (xy 443.483964 -26.0683) (xy 443.53587 -26.098267)
			(xy 443.58342 -26.134754) (xy 443.6258 -26.177134) (xy 443.662287 -26.224684) (xy 443.692254 -26.27659)
			(xy 443.71519 -26.331963) (xy 443.730703 -26.389856) (xy 443.738526 -26.449278) (xy 443.739016 -26.479246)
			(xy 443.739016 -27.342846) (xy 443.738526 -27.372814) (xy 443.730703 -27.432236) (xy 443.71519 -27.490129)
			(xy 443.692254 -27.545502) (xy 443.662287 -27.597408) (xy 443.6258 -27.644958) (xy 443.58342 -27.687338)
			(xy 443.53587 -27.723825) (xy 443.483964 -27.753792) (xy 443.428591 -27.776728) (xy 443.370698 -27.792241)
			(xy 443.311276 -27.800064) (xy 443.25134 -27.800064) (xy 443.191918 -27.792241) (xy 443.134025 -27.776728)
			(xy 443.078652 -27.753792) (xy 443.026746 -27.723825) (xy 442.979196 -27.687338) (xy 442.936816 -27.644958)
			(xy 442.900329 -27.597408) (xy 442.870362 -27.545502) (xy 442.847426 -27.490129) (xy 442.831913 -27.432236)
			(xy 442.82409 -27.372814) (xy 442.8236 -27.342846) (xy 417.739068 -27.342846) (xy 417.738578 -27.372814)
			(xy 417.730755 -27.432236) (xy 417.715242 -27.490129) (xy 417.692306 -27.545502) (xy 417.662339 -27.597408)
			(xy 417.625852 -27.644958) (xy 417.583472 -27.687338) (xy 417.535922 -27.723825) (xy 417.484016 -27.753792)
			(xy 417.428643 -27.776728) (xy 417.37075 -27.792241) (xy 417.311328 -27.800064) (xy 417.251392 -27.800064)
			(xy 417.19197 -27.792241) (xy 417.134077 -27.776728) (xy 417.078704 -27.753792) (xy 417.026798 -27.723825)
			(xy 416.979248 -27.687338) (xy 416.936868 -27.644958) (xy 416.900381 -27.597408) (xy 416.870414 -27.545502)
			(xy 416.847478 -27.490129) (xy 416.831965 -27.432236) (xy 416.824142 -27.372814) (xy 416.823652 -27.342846)
			(xy 391.73912 -27.342846) (xy 391.73863 -27.372814) (xy 391.730807 -27.432236) (xy 391.715294 -27.490129)
			(xy 391.692358 -27.545502) (xy 391.662391 -27.597408) (xy 391.625904 -27.644958) (xy 391.583524 -27.687338)
			(xy 391.535974 -27.723825) (xy 391.484068 -27.753792) (xy 391.428695 -27.776728) (xy 391.370802 -27.792241)
			(xy 391.31138 -27.800064) (xy 391.251444 -27.800064) (xy 391.192022 -27.792241) (xy 391.134129 -27.776728)
			(xy 391.078756 -27.753792) (xy 391.02685 -27.723825) (xy 390.9793 -27.687338) (xy 390.93692 -27.644958)
			(xy 390.900433 -27.597408) (xy 390.870466 -27.545502) (xy 390.84753 -27.490129) (xy 390.832017 -27.432236)
			(xy 390.824194 -27.372814) (xy 390.823704 -27.342846) (xy 365.739172 -27.342846) (xy 365.738682 -27.372814)
			(xy 365.730859 -27.432236) (xy 365.715346 -27.490129) (xy 365.69241 -27.545502) (xy 365.662443 -27.597408)
			(xy 365.625956 -27.644958) (xy 365.583576 -27.687338) (xy 365.536026 -27.723825) (xy 365.48412 -27.753792)
			(xy 365.428747 -27.776728) (xy 365.370854 -27.792241) (xy 365.311432 -27.800064) (xy 365.251496 -27.800064)
			(xy 365.192074 -27.792241) (xy 365.134181 -27.776728) (xy 365.078808 -27.753792) (xy 365.026902 -27.723825)
			(xy 364.979352 -27.687338) (xy 364.936972 -27.644958) (xy 364.900485 -27.597408) (xy 364.870518 -27.545502)
			(xy 364.847582 -27.490129) (xy 364.832069 -27.432236) (xy 364.824246 -27.372814) (xy 364.823756 -27.342846)
			(xy 327.639172 -27.342846) (xy 327.638682 -27.37283) (xy 327.630854 -27.432286) (xy 327.615333 -27.490211)
			(xy 327.592384 -27.545615) (xy 327.5624 -27.597549) (xy 327.525894 -27.645125) (xy 327.483489 -27.68753)
			(xy 327.435913 -27.724036) (xy 327.383979 -27.75402) (xy 327.328575 -27.776969) (xy 327.27065 -27.79249)
			(xy 327.211194 -27.800318) (xy 327.151226 -27.800318) (xy 327.09177 -27.79249) (xy 327.033845 -27.776969)
			(xy 326.978441 -27.75402) (xy 326.926507 -27.724036) (xy 326.878931 -27.68753) (xy 326.836526 -27.645125)
			(xy 326.80002 -27.597549) (xy 326.770036 -27.545615) (xy 326.747087 -27.490211) (xy 326.731566 -27.432286)
			(xy 326.723738 -27.37283) (xy 326.723248 -27.342846) (xy 301.639224 -27.342846) (xy 301.638734 -27.37283)
			(xy 301.630906 -27.432286) (xy 301.615385 -27.490211) (xy 301.592436 -27.545615) (xy 301.562452 -27.597549)
			(xy 301.525946 -27.645125) (xy 301.483541 -27.68753) (xy 301.435965 -27.724036) (xy 301.384031 -27.75402)
			(xy 301.328627 -27.776969) (xy 301.270702 -27.79249) (xy 301.211246 -27.800318) (xy 301.151278 -27.800318)
			(xy 301.091822 -27.79249) (xy 301.033897 -27.776969) (xy 300.978493 -27.75402) (xy 300.926559 -27.724036)
			(xy 300.878983 -27.68753) (xy 300.836578 -27.645125) (xy 300.800072 -27.597549) (xy 300.770088 -27.545615)
			(xy 300.747139 -27.490211) (xy 300.731618 -27.432286) (xy 300.72379 -27.37283) (xy 300.7233 -27.342846)
			(xy 275.639276 -27.342846) (xy 275.638786 -27.37283) (xy 275.630958 -27.432286) (xy 275.615437 -27.490211)
			(xy 275.592488 -27.545615) (xy 275.562504 -27.597549) (xy 275.525998 -27.645125) (xy 275.483593 -27.68753)
			(xy 275.436017 -27.724036) (xy 275.384083 -27.75402) (xy 275.328679 -27.776969) (xy 275.270754 -27.79249)
			(xy 275.211298 -27.800318) (xy 275.15133 -27.800318) (xy 275.091874 -27.79249) (xy 275.033949 -27.776969)
			(xy 274.978545 -27.75402) (xy 274.926611 -27.724036) (xy 274.879035 -27.68753) (xy 274.83663 -27.645125)
			(xy 274.800124 -27.597549) (xy 274.77014 -27.545615) (xy 274.747191 -27.490211) (xy 274.73167 -27.432286)
			(xy 274.723842 -27.37283) (xy 274.723352 -27.342846) (xy 249.639328 -27.342846) (xy 249.638838 -27.37283)
			(xy 249.63101 -27.432286) (xy 249.615489 -27.490211) (xy 249.59254 -27.545615) (xy 249.562556 -27.597549)
			(xy 249.52605 -27.645125) (xy 249.483645 -27.68753) (xy 249.436069 -27.724036) (xy 249.384135 -27.75402)
			(xy 249.328731 -27.776969) (xy 249.270806 -27.79249) (xy 249.21135 -27.800318) (xy 249.151382 -27.800318)
			(xy 249.091926 -27.79249) (xy 249.034001 -27.776969) (xy 248.978597 -27.75402) (xy 248.926663 -27.724036)
			(xy 248.879087 -27.68753) (xy 248.836682 -27.645125) (xy 248.800176 -27.597549) (xy 248.770192 -27.545615)
			(xy 248.747243 -27.490211) (xy 248.731722 -27.432286) (xy 248.723894 -27.37283) (xy 248.723404 -27.342846)
			(xy 211.539328 -27.342846) (xy 211.538838 -27.37283) (xy 211.53101 -27.432286) (xy 211.515489 -27.490211)
			(xy 211.49254 -27.545615) (xy 211.462556 -27.597549) (xy 211.42605 -27.645125) (xy 211.383645 -27.68753)
			(xy 211.336069 -27.724036) (xy 211.284135 -27.75402) (xy 211.228731 -27.776969) (xy 211.170806 -27.79249)
			(xy 211.11135 -27.800318) (xy 211.051382 -27.800318) (xy 210.991926 -27.79249) (xy 210.934001 -27.776969)
			(xy 210.878597 -27.75402) (xy 210.826663 -27.724036) (xy 210.779087 -27.68753) (xy 210.736682 -27.645125)
			(xy 210.700176 -27.597549) (xy 210.670192 -27.545615) (xy 210.647243 -27.490211) (xy 210.631722 -27.432286)
			(xy 210.623894 -27.37283) (xy 210.623404 -27.342846) (xy 185.53938 -27.342846) (xy 185.53889 -27.37283)
			(xy 185.531062 -27.432286) (xy 185.515541 -27.490211) (xy 185.492592 -27.545615) (xy 185.462608 -27.597549)
			(xy 185.426102 -27.645125) (xy 185.383697 -27.68753) (xy 185.336121 -27.724036) (xy 185.284187 -27.75402)
			(xy 185.228783 -27.776969) (xy 185.170858 -27.79249) (xy 185.111402 -27.800318) (xy 185.051434 -27.800318)
			(xy 184.991978 -27.79249) (xy 184.934053 -27.776969) (xy 184.878649 -27.75402) (xy 184.826715 -27.724036)
			(xy 184.779139 -27.68753) (xy 184.736734 -27.645125) (xy 184.700228 -27.597549) (xy 184.670244 -27.545615)
			(xy 184.647295 -27.490211) (xy 184.631774 -27.432286) (xy 184.623946 -27.37283) (xy 184.623456 -27.342846)
			(xy 159.539432 -27.342846) (xy 159.538942 -27.37283) (xy 159.531114 -27.432286) (xy 159.515593 -27.490211)
			(xy 159.492644 -27.545615) (xy 159.46266 -27.597549) (xy 159.426154 -27.645125) (xy 159.383749 -27.68753)
			(xy 159.336173 -27.724036) (xy 159.284239 -27.75402) (xy 159.228835 -27.776969) (xy 159.17091 -27.79249)
			(xy 159.111454 -27.800318) (xy 159.051486 -27.800318) (xy 158.99203 -27.79249) (xy 158.934105 -27.776969)
			(xy 158.878701 -27.75402) (xy 158.826767 -27.724036) (xy 158.779191 -27.68753) (xy 158.736786 -27.645125)
			(xy 158.70028 -27.597549) (xy 158.670296 -27.545615) (xy 158.647347 -27.490211) (xy 158.631826 -27.432286)
			(xy 158.623998 -27.37283) (xy 158.623508 -27.342846) (xy 133.539484 -27.342846) (xy 133.538994 -27.37283)
			(xy 133.531166 -27.432286) (xy 133.515645 -27.490211) (xy 133.492696 -27.545615) (xy 133.462712 -27.597549)
			(xy 133.426206 -27.645125) (xy 133.383801 -27.68753) (xy 133.336225 -27.724036) (xy 133.284291 -27.75402)
			(xy 133.228887 -27.776969) (xy 133.170962 -27.79249) (xy 133.111506 -27.800318) (xy 133.051538 -27.800318)
			(xy 132.992082 -27.79249) (xy 132.934157 -27.776969) (xy 132.878753 -27.75402) (xy 132.826819 -27.724036)
			(xy 132.779243 -27.68753) (xy 132.736838 -27.645125) (xy 132.700332 -27.597549) (xy 132.670348 -27.545615)
			(xy 132.647399 -27.490211) (xy 132.631878 -27.432286) (xy 132.62405 -27.37283) (xy 132.62356 -27.342846)
			(xy 95.438976 -27.342846) (xy 95.438486 -27.372814) (xy 95.430663 -27.432236) (xy 95.41515 -27.490129)
			(xy 95.392214 -27.545502) (xy 95.362247 -27.597408) (xy 95.32576 -27.644958) (xy 95.28338 -27.687338)
			(xy 95.23583 -27.723825) (xy 95.183924 -27.753792) (xy 95.128551 -27.776728) (xy 95.070658 -27.792241)
			(xy 95.011236 -27.800064) (xy 94.9513 -27.800064) (xy 94.891878 -27.792241) (xy 94.833985 -27.776728)
			(xy 94.778612 -27.753792) (xy 94.726706 -27.723825) (xy 94.679156 -27.687338) (xy 94.636776 -27.644958)
			(xy 94.600289 -27.597408) (xy 94.570322 -27.545502) (xy 94.547386 -27.490129) (xy 94.531873 -27.432236)
			(xy 94.52405 -27.372814) (xy 94.52356 -27.342846) (xy 69.439028 -27.342846) (xy 69.438538 -27.372814)
			(xy 69.430715 -27.432236) (xy 69.415202 -27.490129) (xy 69.392266 -27.545502) (xy 69.362299 -27.597408)
			(xy 69.325812 -27.644958) (xy 69.283432 -27.687338) (xy 69.235882 -27.723825) (xy 69.183976 -27.753792)
			(xy 69.128603 -27.776728) (xy 69.07071 -27.792241) (xy 69.011288 -27.800064) (xy 68.951352 -27.800064)
			(xy 68.89193 -27.792241) (xy 68.834037 -27.776728) (xy 68.778664 -27.753792) (xy 68.726758 -27.723825)
			(xy 68.679208 -27.687338) (xy 68.636828 -27.644958) (xy 68.600341 -27.597408) (xy 68.570374 -27.545502)
			(xy 68.547438 -27.490129) (xy 68.531925 -27.432236) (xy 68.524102 -27.372814) (xy 68.523612 -27.342846)
			(xy 43.43908 -27.342846) (xy 43.43859 -27.372814) (xy 43.430767 -27.432236) (xy 43.415254 -27.490129)
			(xy 43.392318 -27.545502) (xy 43.362351 -27.597408) (xy 43.325864 -27.644958) (xy 43.283484 -27.687338)
			(xy 43.235934 -27.723825) (xy 43.184028 -27.753792) (xy 43.128655 -27.776728) (xy 43.070762 -27.792241)
			(xy 43.01134 -27.800064) (xy 42.951404 -27.800064) (xy 42.891982 -27.792241) (xy 42.834089 -27.776728)
			(xy 42.778716 -27.753792) (xy 42.72681 -27.723825) (xy 42.67926 -27.687338) (xy 42.63688 -27.644958)
			(xy 42.600393 -27.597408) (xy 42.570426 -27.545502) (xy 42.54749 -27.490129) (xy 42.531977 -27.432236)
			(xy 42.524154 -27.372814) (xy 42.523664 -27.342846) (xy 17.439132 -27.342846) (xy 17.438642 -27.372814)
			(xy 17.430819 -27.432236) (xy 17.415306 -27.490129) (xy 17.39237 -27.545502) (xy 17.362403 -27.597408)
			(xy 17.325916 -27.644958) (xy 17.283536 -27.687338) (xy 17.235986 -27.723825) (xy 17.18408 -27.753792)
			(xy 17.128707 -27.776728) (xy 17.070814 -27.792241) (xy 17.011392 -27.800064) (xy 16.951456 -27.800064)
			(xy 16.892034 -27.792241) (xy 16.834141 -27.776728) (xy 16.778768 -27.753792) (xy 16.726862 -27.723825)
			(xy 16.679312 -27.687338) (xy 16.636932 -27.644958) (xy 16.600445 -27.597408) (xy 16.570478 -27.545502)
			(xy 16.547542 -27.490129) (xy 16.532029 -27.432236) (xy 16.524206 -27.372814) (xy 16.523716 -27.342846)
			(xy 0.508 -27.342846) (xy 0.508 -29.12237) (xy 8.607044 -29.12237) (xy 8.607044 -28.25877) (xy 8.607534 -28.228802)
			(xy 8.615357 -28.16938) (xy 8.63087 -28.111487) (xy 8.653806 -28.056114) (xy 8.683773 -28.004208)
			(xy 8.72026 -27.956658) (xy 8.76264 -27.914278) (xy 8.81019 -27.877791) (xy 8.862096 -27.847824)
			(xy 8.917469 -27.824888) (xy 8.975362 -27.809375) (xy 9.034784 -27.801552) (xy 9.09472 -27.801552)
			(xy 9.154142 -27.809375) (xy 9.212035 -27.824888) (xy 9.267408 -27.847824) (xy 9.319314 -27.877791)
			(xy 9.366864 -27.914278) (xy 9.409244 -27.956658) (xy 9.445731 -28.004208) (xy 9.475698 -28.056114)
			(xy 9.498634 -28.111487) (xy 9.514147 -28.16938) (xy 9.52197 -28.228802) (xy 9.52246 -28.25877) (xy 9.52246 -29.114242)
			(xy 18.847308 -29.114242) (xy 18.847308 -28.250642) (xy 18.847798 -28.220658) (xy 18.855626 -28.161202)
			(xy 18.871147 -28.103277) (xy 18.894096 -28.047873) (xy 18.92408 -27.995939) (xy 18.960586 -27.948363)
			(xy 19.002991 -27.905958) (xy 19.050567 -27.869452) (xy 19.102501 -27.839468) (xy 19.157905 -27.816519)
			(xy 19.21583 -27.800998) (xy 19.275286 -27.79317) (xy 19.335254 -27.79317) (xy 19.39471 -27.800998)
			(xy 19.452635 -27.816519) (xy 19.508039 -27.839468) (xy 19.559973 -27.869452) (xy 19.607549 -27.905958)
			(xy 19.649954 -27.948363) (xy 19.68646 -27.995939) (xy 19.716444 -28.047873) (xy 19.739393 -28.103277)
			(xy 19.754914 -28.161202) (xy 19.762742 -28.220658) (xy 19.763232 -28.250642) (xy 19.763232 -29.114242)
			(xy 19.763099 -29.12237) (xy 34.606992 -29.12237) (xy 34.606992 -28.25877) (xy 34.607482 -28.228802)
			(xy 34.615305 -28.16938) (xy 34.630818 -28.111487) (xy 34.653754 -28.056114) (xy 34.683721 -28.004208)
			(xy 34.720208 -27.956658) (xy 34.762588 -27.914278) (xy 34.810138 -27.877791) (xy 34.862044 -27.847824)
			(xy 34.917417 -27.824888) (xy 34.97531 -27.809375) (xy 35.034732 -27.801552) (xy 35.094668 -27.801552)
			(xy 35.15409 -27.809375) (xy 35.211983 -27.824888) (xy 35.267356 -27.847824) (xy 35.319262 -27.877791)
			(xy 35.366812 -27.914278) (xy 35.409192 -27.956658) (xy 35.445679 -28.004208) (xy 35.475646 -28.056114)
			(xy 35.498582 -28.111487) (xy 35.514095 -28.16938) (xy 35.521918 -28.228802) (xy 35.522408 -28.25877)
			(xy 35.522408 -29.114242) (xy 44.847256 -29.114242) (xy 44.847256 -28.250642) (xy 44.847746 -28.220658)
			(xy 44.855574 -28.161202) (xy 44.871095 -28.103277) (xy 44.894044 -28.047873) (xy 44.924028 -27.995939)
			(xy 44.960534 -27.948363) (xy 45.002939 -27.905958) (xy 45.050515 -27.869452) (xy 45.102449 -27.839468)
			(xy 45.157853 -27.816519) (xy 45.215778 -27.800998) (xy 45.275234 -27.79317) (xy 45.335202 -27.79317)
			(xy 45.394658 -27.800998) (xy 45.452583 -27.816519) (xy 45.507987 -27.839468) (xy 45.559921 -27.869452)
			(xy 45.607497 -27.905958) (xy 45.649902 -27.948363) (xy 45.686408 -27.995939) (xy 45.716392 -28.047873)
			(xy 45.739341 -28.103277) (xy 45.754862 -28.161202) (xy 45.76269 -28.220658) (xy 45.76318 -28.250642)
			(xy 45.76318 -29.114242) (xy 45.763047 -29.12237) (xy 60.60694 -29.12237) (xy 60.60694 -28.25877)
			(xy 60.60743 -28.228802) (xy 60.615253 -28.16938) (xy 60.630766 -28.111487) (xy 60.653702 -28.056114)
			(xy 60.683669 -28.004208) (xy 60.720156 -27.956658) (xy 60.762536 -27.914278) (xy 60.810086 -27.877791)
			(xy 60.861992 -27.847824) (xy 60.917365 -27.824888) (xy 60.975258 -27.809375) (xy 61.03468 -27.801552)
			(xy 61.094616 -27.801552) (xy 61.154038 -27.809375) (xy 61.211931 -27.824888) (xy 61.267304 -27.847824)
			(xy 61.31921 -27.877791) (xy 61.36676 -27.914278) (xy 61.40914 -27.956658) (xy 61.445627 -28.004208)
			(xy 61.475594 -28.056114) (xy 61.49853 -28.111487) (xy 61.514043 -28.16938) (xy 61.521866 -28.228802)
			(xy 61.522356 -28.25877) (xy 61.522356 -29.114242) (xy 70.847204 -29.114242) (xy 70.847204 -28.250642)
			(xy 70.847694 -28.220658) (xy 70.855522 -28.161202) (xy 70.871043 -28.103277) (xy 70.893992 -28.047873)
			(xy 70.923976 -27.995939) (xy 70.960482 -27.948363) (xy 71.002887 -27.905958) (xy 71.050463 -27.869452)
			(xy 71.102397 -27.839468) (xy 71.157801 -27.816519) (xy 71.215726 -27.800998) (xy 71.275182 -27.79317)
			(xy 71.33515 -27.79317) (xy 71.394606 -27.800998) (xy 71.452531 -27.816519) (xy 71.507935 -27.839468)
			(xy 71.559869 -27.869452) (xy 71.607445 -27.905958) (xy 71.64985 -27.948363) (xy 71.686356 -27.995939)
			(xy 71.71634 -28.047873) (xy 71.739289 -28.103277) (xy 71.75481 -28.161202) (xy 71.762638 -28.220658)
			(xy 71.763128 -28.250642) (xy 71.763128 -29.114242) (xy 71.762995 -29.12237) (xy 86.606888 -29.12237)
			(xy 86.606888 -28.25877) (xy 86.607378 -28.228802) (xy 86.615201 -28.16938) (xy 86.630714 -28.111487)
			(xy 86.65365 -28.056114) (xy 86.683617 -28.004208) (xy 86.720104 -27.956658) (xy 86.762484 -27.914278)
			(xy 86.810034 -27.877791) (xy 86.86194 -27.847824) (xy 86.917313 -27.824888) (xy 86.975206 -27.809375)
			(xy 87.034628 -27.801552) (xy 87.094564 -27.801552) (xy 87.153986 -27.809375) (xy 87.211879 -27.824888)
			(xy 87.267252 -27.847824) (xy 87.319158 -27.877791) (xy 87.366708 -27.914278) (xy 87.409088 -27.956658)
			(xy 87.445575 -28.004208) (xy 87.475542 -28.056114) (xy 87.498478 -28.111487) (xy 87.513991 -28.16938)
			(xy 87.521814 -28.228802) (xy 87.522304 -28.25877) (xy 87.522304 -29.114242) (xy 96.847152 -29.114242)
			(xy 96.847152 -28.250642) (xy 96.847642 -28.220658) (xy 96.85547 -28.161202) (xy 96.870991 -28.103277)
			(xy 96.89394 -28.047873) (xy 96.923924 -27.995939) (xy 96.96043 -27.948363) (xy 97.002835 -27.905958)
			(xy 97.050411 -27.869452) (xy 97.102345 -27.839468) (xy 97.157749 -27.816519) (xy 97.215674 -27.800998)
			(xy 97.27513 -27.79317) (xy 97.335098 -27.79317) (xy 97.394554 -27.800998) (xy 97.452479 -27.816519)
			(xy 97.507883 -27.839468) (xy 97.559817 -27.869452) (xy 97.607393 -27.905958) (xy 97.649798 -27.948363)
			(xy 97.686304 -27.995939) (xy 97.716288 -28.047873) (xy 97.739237 -28.103277) (xy 97.754758 -28.161202)
			(xy 97.762586 -28.220658) (xy 97.763076 -28.250642) (xy 97.763076 -29.114242) (xy 97.762943 -29.12237)
			(xy 124.706888 -29.12237) (xy 124.706888 -28.25877) (xy 124.707378 -28.228786) (xy 124.715206 -28.16933)
			(xy 124.730727 -28.111405) (xy 124.753676 -28.056001) (xy 124.78366 -28.004067) (xy 124.820166 -27.956491)
			(xy 124.862571 -27.914086) (xy 124.910147 -27.87758) (xy 124.962081 -27.847596) (xy 125.017485 -27.824647)
			(xy 125.07541 -27.809126) (xy 125.134866 -27.801298) (xy 125.194834 -27.801298) (xy 125.25429 -27.809126)
			(xy 125.312215 -27.824647) (xy 125.367619 -27.847596) (xy 125.419553 -27.87758) (xy 125.467129 -27.914086)
			(xy 125.509534 -27.956491) (xy 125.54604 -28.004067) (xy 125.576024 -28.056001) (xy 125.598973 -28.111405)
			(xy 125.614494 -28.16933) (xy 125.622322 -28.228786) (xy 125.622812 -28.25877) (xy 125.622812 -29.114242)
			(xy 134.94766 -29.114242) (xy 134.94766 -28.250642) (xy 134.94815 -28.220674) (xy 134.955973 -28.161252)
			(xy 134.971486 -28.103359) (xy 134.994422 -28.047986) (xy 135.024389 -27.99608) (xy 135.060876 -27.94853)
			(xy 135.103256 -27.90615) (xy 135.150806 -27.869663) (xy 135.202712 -27.839696) (xy 135.258085 -27.81676)
			(xy 135.315978 -27.801247) (xy 135.3754 -27.793424) (xy 135.435336 -27.793424) (xy 135.494758 -27.801247)
			(xy 135.552651 -27.81676) (xy 135.608024 -27.839696) (xy 135.65993 -27.869663) (xy 135.70748 -27.90615)
			(xy 135.74986 -27.94853) (xy 135.786347 -27.99608) (xy 135.816314 -28.047986) (xy 135.83925 -28.103359)
			(xy 135.854763 -28.161252) (xy 135.862586 -28.220674) (xy 135.863076 -28.250642) (xy 135.863076 -29.114242)
			(xy 135.862943 -29.12237) (xy 150.706836 -29.12237) (xy 150.706836 -28.25877) (xy 150.707326 -28.228786)
			(xy 150.715154 -28.16933) (xy 150.730675 -28.111405) (xy 150.753624 -28.056001) (xy 150.783608 -28.004067)
			(xy 150.820114 -27.956491) (xy 150.862519 -27.914086) (xy 150.910095 -27.87758) (xy 150.962029 -27.847596)
			(xy 151.017433 -27.824647) (xy 151.075358 -27.809126) (xy 151.134814 -27.801298) (xy 151.194782 -27.801298)
			(xy 151.254238 -27.809126) (xy 151.312163 -27.824647) (xy 151.367567 -27.847596) (xy 151.419501 -27.87758)
			(xy 151.467077 -27.914086) (xy 151.509482 -27.956491) (xy 151.545988 -28.004067) (xy 151.575972 -28.056001)
			(xy 151.598921 -28.111405) (xy 151.614442 -28.16933) (xy 151.62227 -28.228786) (xy 151.62276 -28.25877)
			(xy 151.62276 -29.114242) (xy 160.947608 -29.114242) (xy 160.947608 -28.250642) (xy 160.948098 -28.220674)
			(xy 160.955921 -28.161252) (xy 160.971434 -28.103359) (xy 160.99437 -28.047986) (xy 161.024337 -27.99608)
			(xy 161.060824 -27.94853) (xy 161.103204 -27.90615) (xy 161.150754 -27.869663) (xy 161.20266 -27.839696)
			(xy 161.258033 -27.81676) (xy 161.315926 -27.801247) (xy 161.375348 -27.793424) (xy 161.435284 -27.793424)
			(xy 161.494706 -27.801247) (xy 161.552599 -27.81676) (xy 161.607972 -27.839696) (xy 161.659878 -27.869663)
			(xy 161.707428 -27.90615) (xy 161.749808 -27.94853) (xy 161.786295 -27.99608) (xy 161.816262 -28.047986)
			(xy 161.839198 -28.103359) (xy 161.854711 -28.161252) (xy 161.862534 -28.220674) (xy 161.863024 -28.250642)
			(xy 161.863024 -29.114242) (xy 161.862891 -29.12237) (xy 176.706784 -29.12237) (xy 176.706784 -28.25877)
			(xy 176.707274 -28.228786) (xy 176.715102 -28.16933) (xy 176.730623 -28.111405) (xy 176.753572 -28.056001)
			(xy 176.783556 -28.004067) (xy 176.820062 -27.956491) (xy 176.862467 -27.914086) (xy 176.910043 -27.87758)
			(xy 176.961977 -27.847596) (xy 177.017381 -27.824647) (xy 177.075306 -27.809126) (xy 177.134762 -27.801298)
			(xy 177.19473 -27.801298) (xy 177.254186 -27.809126) (xy 177.312111 -27.824647) (xy 177.367515 -27.847596)
			(xy 177.419449 -27.87758) (xy 177.467025 -27.914086) (xy 177.50943 -27.956491) (xy 177.545936 -28.004067)
			(xy 177.57592 -28.056001) (xy 177.598869 -28.111405) (xy 177.61439 -28.16933) (xy 177.622218 -28.228786)
			(xy 177.622708 -28.25877) (xy 177.622708 -29.114242) (xy 186.947556 -29.114242) (xy 186.947556 -28.250642)
			(xy 186.948046 -28.220674) (xy 186.955869 -28.161252) (xy 186.971382 -28.103359) (xy 186.994318 -28.047986)
			(xy 187.024285 -27.99608) (xy 187.060772 -27.94853) (xy 187.103152 -27.90615) (xy 187.150702 -27.869663)
			(xy 187.202608 -27.839696) (xy 187.257981 -27.81676) (xy 187.315874 -27.801247) (xy 187.375296 -27.793424)
			(xy 187.435232 -27.793424) (xy 187.494654 -27.801247) (xy 187.552547 -27.81676) (xy 187.60792 -27.839696)
			(xy 187.659826 -27.869663) (xy 187.707376 -27.90615) (xy 187.749756 -27.94853) (xy 187.786243 -27.99608)
			(xy 187.81621 -28.047986) (xy 187.839146 -28.103359) (xy 187.854659 -28.161252) (xy 187.862482 -28.220674)
			(xy 187.862972 -28.250642) (xy 187.862972 -29.114242) (xy 187.862839 -29.12237) (xy 202.706732 -29.12237)
			(xy 202.706732 -28.25877) (xy 202.707222 -28.228786) (xy 202.71505 -28.16933) (xy 202.730571 -28.111405)
			(xy 202.75352 -28.056001) (xy 202.783504 -28.004067) (xy 202.82001 -27.956491) (xy 202.862415 -27.914086)
			(xy 202.909991 -27.87758) (xy 202.961925 -27.847596) (xy 203.017329 -27.824647) (xy 203.075254 -27.809126)
			(xy 203.13471 -27.801298) (xy 203.194678 -27.801298) (xy 203.254134 -27.809126) (xy 203.312059 -27.824647)
			(xy 203.367463 -27.847596) (xy 203.419397 -27.87758) (xy 203.466973 -27.914086) (xy 203.509378 -27.956491)
			(xy 203.545884 -28.004067) (xy 203.575868 -28.056001) (xy 203.598817 -28.111405) (xy 203.614338 -28.16933)
			(xy 203.622166 -28.228786) (xy 203.622656 -28.25877) (xy 203.622656 -29.114242) (xy 212.947504 -29.114242)
			(xy 212.947504 -28.250642) (xy 212.947994 -28.220674) (xy 212.955817 -28.161252) (xy 212.97133 -28.103359)
			(xy 212.994266 -28.047986) (xy 213.024233 -27.99608) (xy 213.06072 -27.94853) (xy 213.1031 -27.90615)
			(xy 213.15065 -27.869663) (xy 213.202556 -27.839696) (xy 213.257929 -27.81676) (xy 213.315822 -27.801247)
			(xy 213.375244 -27.793424) (xy 213.43518 -27.793424) (xy 213.494602 -27.801247) (xy 213.552495 -27.81676)
			(xy 213.607868 -27.839696) (xy 213.659774 -27.869663) (xy 213.707324 -27.90615) (xy 213.749704 -27.94853)
			(xy 213.786191 -27.99608) (xy 213.816158 -28.047986) (xy 213.839094 -28.103359) (xy 213.854607 -28.161252)
			(xy 213.86243 -28.220674) (xy 213.86292 -28.250642) (xy 213.86292 -29.114242) (xy 213.862787 -29.12237)
			(xy 240.806732 -29.12237) (xy 240.806732 -28.25877) (xy 240.807222 -28.228786) (xy 240.81505 -28.16933)
			(xy 240.830571 -28.111405) (xy 240.85352 -28.056001) (xy 240.883504 -28.004067) (xy 240.92001 -27.956491)
			(xy 240.962415 -27.914086) (xy 241.009991 -27.87758) (xy 241.061925 -27.847596) (xy 241.117329 -27.824647)
			(xy 241.175254 -27.809126) (xy 241.23471 -27.801298) (xy 241.294678 -27.801298) (xy 241.354134 -27.809126)
			(xy 241.412059 -27.824647) (xy 241.467463 -27.847596) (xy 241.519397 -27.87758) (xy 241.566973 -27.914086)
			(xy 241.609378 -27.956491) (xy 241.645884 -28.004067) (xy 241.675868 -28.056001) (xy 241.698817 -28.111405)
			(xy 241.714338 -28.16933) (xy 241.722166 -28.228786) (xy 241.722656 -28.25877) (xy 241.722656 -29.114242)
			(xy 251.047504 -29.114242) (xy 251.047504 -28.250642) (xy 251.047994 -28.220674) (xy 251.055817 -28.161252)
			(xy 251.07133 -28.103359) (xy 251.094266 -28.047986) (xy 251.124233 -27.99608) (xy 251.16072 -27.94853)
			(xy 251.2031 -27.90615) (xy 251.25065 -27.869663) (xy 251.302556 -27.839696) (xy 251.357929 -27.81676)
			(xy 251.415822 -27.801247) (xy 251.475244 -27.793424) (xy 251.53518 -27.793424) (xy 251.594602 -27.801247)
			(xy 251.652495 -27.81676) (xy 251.707868 -27.839696) (xy 251.759774 -27.869663) (xy 251.807324 -27.90615)
			(xy 251.849704 -27.94853) (xy 251.886191 -27.99608) (xy 251.916158 -28.047986) (xy 251.939094 -28.103359)
			(xy 251.954607 -28.161252) (xy 251.96243 -28.220674) (xy 251.96292 -28.250642) (xy 251.96292 -29.114242)
			(xy 251.962787 -29.12237) (xy 266.80668 -29.12237) (xy 266.80668 -28.25877) (xy 266.80717 -28.228786)
			(xy 266.814998 -28.16933) (xy 266.830519 -28.111405) (xy 266.853468 -28.056001) (xy 266.883452 -28.004067)
			(xy 266.919958 -27.956491) (xy 266.962363 -27.914086) (xy 267.009939 -27.87758) (xy 267.061873 -27.847596)
			(xy 267.117277 -27.824647) (xy 267.175202 -27.809126) (xy 267.234658 -27.801298) (xy 267.294626 -27.801298)
			(xy 267.354082 -27.809126) (xy 267.412007 -27.824647) (xy 267.467411 -27.847596) (xy 267.519345 -27.87758)
			(xy 267.566921 -27.914086) (xy 267.609326 -27.956491) (xy 267.645832 -28.004067) (xy 267.675816 -28.056001)
			(xy 267.698765 -28.111405) (xy 267.714286 -28.16933) (xy 267.722114 -28.228786) (xy 267.722604 -28.25877)
			(xy 267.722604 -29.114242) (xy 277.047452 -29.114242) (xy 277.047452 -28.250642) (xy 277.047942 -28.220674)
			(xy 277.055765 -28.161252) (xy 277.071278 -28.103359) (xy 277.094214 -28.047986) (xy 277.124181 -27.99608)
			(xy 277.160668 -27.94853) (xy 277.203048 -27.90615) (xy 277.250598 -27.869663) (xy 277.302504 -27.839696)
			(xy 277.357877 -27.81676) (xy 277.41577 -27.801247) (xy 277.475192 -27.793424) (xy 277.535128 -27.793424)
			(xy 277.59455 -27.801247) (xy 277.652443 -27.81676) (xy 277.707816 -27.839696) (xy 277.759722 -27.869663)
			(xy 277.807272 -27.90615) (xy 277.849652 -27.94853) (xy 277.886139 -27.99608) (xy 277.916106 -28.047986)
			(xy 277.939042 -28.103359) (xy 277.954555 -28.161252) (xy 277.962378 -28.220674) (xy 277.962868 -28.250642)
			(xy 277.962868 -29.114242) (xy 277.962735 -29.12237) (xy 292.806628 -29.12237) (xy 292.806628 -28.25877)
			(xy 292.807118 -28.228786) (xy 292.814946 -28.16933) (xy 292.830467 -28.111405) (xy 292.853416 -28.056001)
			(xy 292.8834 -28.004067) (xy 292.919906 -27.956491) (xy 292.962311 -27.914086) (xy 293.009887 -27.87758)
			(xy 293.061821 -27.847596) (xy 293.117225 -27.824647) (xy 293.17515 -27.809126) (xy 293.234606 -27.801298)
			(xy 293.294574 -27.801298) (xy 293.35403 -27.809126) (xy 293.411955 -27.824647) (xy 293.467359 -27.847596)
			(xy 293.519293 -27.87758) (xy 293.566869 -27.914086) (xy 293.609274 -27.956491) (xy 293.64578 -28.004067)
			(xy 293.675764 -28.056001) (xy 293.698713 -28.111405) (xy 293.714234 -28.16933) (xy 293.722062 -28.228786)
			(xy 293.722552 -28.25877) (xy 293.722552 -29.114242) (xy 303.0474 -29.114242) (xy 303.0474 -28.250642)
			(xy 303.04789 -28.220674) (xy 303.055713 -28.161252) (xy 303.071226 -28.103359) (xy 303.094162 -28.047986)
			(xy 303.124129 -27.99608) (xy 303.160616 -27.94853) (xy 303.202996 -27.90615) (xy 303.250546 -27.869663)
			(xy 303.302452 -27.839696) (xy 303.357825 -27.81676) (xy 303.415718 -27.801247) (xy 303.47514 -27.793424)
			(xy 303.535076 -27.793424) (xy 303.594498 -27.801247) (xy 303.652391 -27.81676) (xy 303.707764 -27.839696)
			(xy 303.75967 -27.869663) (xy 303.80722 -27.90615) (xy 303.8496 -27.94853) (xy 303.886087 -27.99608)
			(xy 303.916054 -28.047986) (xy 303.93899 -28.103359) (xy 303.954503 -28.161252) (xy 303.962326 -28.220674)
			(xy 303.962816 -28.250642) (xy 303.962816 -29.114242) (xy 303.962683 -29.12237) (xy 318.806576 -29.12237)
			(xy 318.806576 -28.25877) (xy 318.807066 -28.228786) (xy 318.814894 -28.16933) (xy 318.830415 -28.111405)
			(xy 318.853364 -28.056001) (xy 318.883348 -28.004067) (xy 318.919854 -27.956491) (xy 318.962259 -27.914086)
			(xy 319.009835 -27.87758) (xy 319.061769 -27.847596) (xy 319.117173 -27.824647) (xy 319.175098 -27.809126)
			(xy 319.234554 -27.801298) (xy 319.294522 -27.801298) (xy 319.353978 -27.809126) (xy 319.411903 -27.824647)
			(xy 319.467307 -27.847596) (xy 319.519241 -27.87758) (xy 319.566817 -27.914086) (xy 319.609222 -27.956491)
			(xy 319.645728 -28.004067) (xy 319.675712 -28.056001) (xy 319.698661 -28.111405) (xy 319.714182 -28.16933)
			(xy 319.72201 -28.228786) (xy 319.7225 -28.25877) (xy 319.7225 -29.114242) (xy 329.047348 -29.114242)
			(xy 329.047348 -28.250642) (xy 329.047838 -28.220674) (xy 329.055661 -28.161252) (xy 329.071174 -28.103359)
			(xy 329.09411 -28.047986) (xy 329.124077 -27.99608) (xy 329.160564 -27.94853) (xy 329.202944 -27.90615)
			(xy 329.250494 -27.869663) (xy 329.3024 -27.839696) (xy 329.357773 -27.81676) (xy 329.415666 -27.801247)
			(xy 329.475088 -27.793424) (xy 329.535024 -27.793424) (xy 329.594446 -27.801247) (xy 329.652339 -27.81676)
			(xy 329.707712 -27.839696) (xy 329.759618 -27.869663) (xy 329.807168 -27.90615) (xy 329.849548 -27.94853)
			(xy 329.886035 -27.99608) (xy 329.916002 -28.047986) (xy 329.938938 -28.103359) (xy 329.954451 -28.161252)
			(xy 329.962274 -28.220674) (xy 329.962764 -28.250642) (xy 329.962764 -29.114242) (xy 329.962631 -29.12237)
			(xy 356.907084 -29.12237) (xy 356.907084 -28.25877) (xy 356.907574 -28.228802) (xy 356.915397 -28.16938)
			(xy 356.93091 -28.111487) (xy 356.953846 -28.056114) (xy 356.983813 -28.004208) (xy 357.0203 -27.956658)
			(xy 357.06268 -27.914278) (xy 357.11023 -27.877791) (xy 357.162136 -27.847824) (xy 357.217509 -27.824888)
			(xy 357.275402 -27.809375) (xy 357.334824 -27.801552) (xy 357.39476 -27.801552) (xy 357.454182 -27.809375)
			(xy 357.512075 -27.824888) (xy 357.567448 -27.847824) (xy 357.619354 -27.877791) (xy 357.666904 -27.914278)
			(xy 357.709284 -27.956658) (xy 357.745771 -28.004208) (xy 357.775738 -28.056114) (xy 357.798674 -28.111487)
			(xy 357.814187 -28.16938) (xy 357.82201 -28.228802) (xy 357.8225 -28.25877) (xy 357.8225 -29.114242)
			(xy 367.147348 -29.114242) (xy 367.147348 -28.250642) (xy 367.147838 -28.220658) (xy 367.155666 -28.161202)
			(xy 367.171187 -28.103277) (xy 367.194136 -28.047873) (xy 367.22412 -27.995939) (xy 367.260626 -27.948363)
			(xy 367.303031 -27.905958) (xy 367.350607 -27.869452) (xy 367.402541 -27.839468) (xy 367.457945 -27.816519)
			(xy 367.51587 -27.800998) (xy 367.575326 -27.79317) (xy 367.635294 -27.79317) (xy 367.69475 -27.800998)
			(xy 367.752675 -27.816519) (xy 367.808079 -27.839468) (xy 367.860013 -27.869452) (xy 367.907589 -27.905958)
			(xy 367.949994 -27.948363) (xy 367.9865 -27.995939) (xy 368.016484 -28.047873) (xy 368.039433 -28.103277)
			(xy 368.054954 -28.161202) (xy 368.062782 -28.220658) (xy 368.063272 -28.250642) (xy 368.063272 -29.114242)
			(xy 368.063139 -29.12237) (xy 382.907032 -29.12237) (xy 382.907032 -28.25877) (xy 382.907522 -28.228802)
			(xy 382.915345 -28.16938) (xy 382.930858 -28.111487) (xy 382.953794 -28.056114) (xy 382.983761 -28.004208)
			(xy 383.020248 -27.956658) (xy 383.062628 -27.914278) (xy 383.110178 -27.877791) (xy 383.162084 -27.847824)
			(xy 383.217457 -27.824888) (xy 383.27535 -27.809375) (xy 383.334772 -27.801552) (xy 383.394708 -27.801552)
			(xy 383.45413 -27.809375) (xy 383.512023 -27.824888) (xy 383.567396 -27.847824) (xy 383.619302 -27.877791)
			(xy 383.666852 -27.914278) (xy 383.709232 -27.956658) (xy 383.745719 -28.004208) (xy 383.775686 -28.056114)
			(xy 383.798622 -28.111487) (xy 383.814135 -28.16938) (xy 383.821958 -28.228802) (xy 383.822448 -28.25877)
			(xy 383.822448 -29.114242) (xy 393.147296 -29.114242) (xy 393.147296 -28.250642) (xy 393.147786 -28.220658)
			(xy 393.155614 -28.161202) (xy 393.171135 -28.103277) (xy 393.194084 -28.047873) (xy 393.224068 -27.995939)
			(xy 393.260574 -27.948363) (xy 393.302979 -27.905958) (xy 393.350555 -27.869452) (xy 393.402489 -27.839468)
			(xy 393.457893 -27.816519) (xy 393.515818 -27.800998) (xy 393.575274 -27.79317) (xy 393.635242 -27.79317)
			(xy 393.694698 -27.800998) (xy 393.752623 -27.816519) (xy 393.808027 -27.839468) (xy 393.859961 -27.869452)
			(xy 393.907537 -27.905958) (xy 393.949942 -27.948363) (xy 393.986448 -27.995939) (xy 394.016432 -28.047873)
			(xy 394.039381 -28.103277) (xy 394.054902 -28.161202) (xy 394.06273 -28.220658) (xy 394.06322 -28.250642)
			(xy 394.06322 -29.114242) (xy 394.063087 -29.12237) (xy 408.90698 -29.12237) (xy 408.90698 -28.25877)
			(xy 408.90747 -28.228802) (xy 408.915293 -28.16938) (xy 408.930806 -28.111487) (xy 408.953742 -28.056114)
			(xy 408.983709 -28.004208) (xy 409.020196 -27.956658) (xy 409.062576 -27.914278) (xy 409.110126 -27.877791)
			(xy 409.162032 -27.847824) (xy 409.217405 -27.824888) (xy 409.275298 -27.809375) (xy 409.33472 -27.801552)
			(xy 409.394656 -27.801552) (xy 409.454078 -27.809375) (xy 409.511971 -27.824888) (xy 409.567344 -27.847824)
			(xy 409.61925 -27.877791) (xy 409.6668 -27.914278) (xy 409.70918 -27.956658) (xy 409.745667 -28.004208)
			(xy 409.775634 -28.056114) (xy 409.79857 -28.111487) (xy 409.814083 -28.16938) (xy 409.821906 -28.228802)
			(xy 409.822396 -28.25877) (xy 409.822396 -29.114242) (xy 419.147244 -29.114242) (xy 419.147244 -28.250642)
			(xy 419.147734 -28.220658) (xy 419.155562 -28.161202) (xy 419.171083 -28.103277) (xy 419.194032 -28.047873)
			(xy 419.224016 -27.995939) (xy 419.260522 -27.948363) (xy 419.302927 -27.905958) (xy 419.350503 -27.869452)
			(xy 419.402437 -27.839468) (xy 419.457841 -27.816519) (xy 419.515766 -27.800998) (xy 419.575222 -27.79317)
			(xy 419.63519 -27.79317) (xy 419.694646 -27.800998) (xy 419.752571 -27.816519) (xy 419.807975 -27.839468)
			(xy 419.859909 -27.869452) (xy 419.907485 -27.905958) (xy 419.94989 -27.948363) (xy 419.986396 -27.995939)
			(xy 420.01638 -28.047873) (xy 420.039329 -28.103277) (xy 420.05485 -28.161202) (xy 420.062678 -28.220658)
			(xy 420.063168 -28.250642) (xy 420.063168 -29.114242) (xy 420.063035 -29.12237) (xy 434.906928 -29.12237)
			(xy 434.906928 -28.25877) (xy 434.907418 -28.228802) (xy 434.915241 -28.16938) (xy 434.930754 -28.111487)
			(xy 434.95369 -28.056114) (xy 434.983657 -28.004208) (xy 435.020144 -27.956658) (xy 435.062524 -27.914278)
			(xy 435.110074 -27.877791) (xy 435.16198 -27.847824) (xy 435.217353 -27.824888) (xy 435.275246 -27.809375)
			(xy 435.334668 -27.801552) (xy 435.394604 -27.801552) (xy 435.454026 -27.809375) (xy 435.511919 -27.824888)
			(xy 435.567292 -27.847824) (xy 435.619198 -27.877791) (xy 435.666748 -27.914278) (xy 435.709128 -27.956658)
			(xy 435.745615 -28.004208) (xy 435.775582 -28.056114) (xy 435.798518 -28.111487) (xy 435.814031 -28.16938)
			(xy 435.821854 -28.228802) (xy 435.822344 -28.25877) (xy 435.822344 -29.114242) (xy 445.147192 -29.114242)
			(xy 445.147192 -28.250642) (xy 445.147682 -28.220658) (xy 445.15551 -28.161202) (xy 445.171031 -28.103277)
			(xy 445.19398 -28.047873) (xy 445.223964 -27.995939) (xy 445.26047 -27.948363) (xy 445.302875 -27.905958)
			(xy 445.350451 -27.869452) (xy 445.402385 -27.839468) (xy 445.457789 -27.816519) (xy 445.515714 -27.800998)
			(xy 445.57517 -27.79317) (xy 445.635138 -27.79317) (xy 445.694594 -27.800998) (xy 445.752519 -27.816519)
			(xy 445.807923 -27.839468) (xy 445.859857 -27.869452) (xy 445.907433 -27.905958) (xy 445.949838 -27.948363)
			(xy 445.986344 -27.995939) (xy 446.016328 -28.047873) (xy 446.039277 -28.103277) (xy 446.054798 -28.161202)
			(xy 446.062626 -28.220658) (xy 446.063116 -28.250642) (xy 446.063116 -29.114242) (xy 446.062626 -29.144226)
			(xy 446.054798 -29.203682) (xy 446.039277 -29.261607) (xy 446.016328 -29.317011) (xy 445.986344 -29.368945)
			(xy 445.949838 -29.416521) (xy 445.907433 -29.458926) (xy 445.859857 -29.495432) (xy 445.807923 -29.525416)
			(xy 445.752519 -29.548365) (xy 445.694594 -29.563886) (xy 445.635138 -29.571714) (xy 445.57517 -29.571714)
			(xy 445.515714 -29.563886) (xy 445.457789 -29.548365) (xy 445.402385 -29.525416) (xy 445.350451 -29.495432)
			(xy 445.302875 -29.458926) (xy 445.26047 -29.416521) (xy 445.223964 -29.368945) (xy 445.19398 -29.317011)
			(xy 445.171031 -29.261607) (xy 445.15551 -29.203682) (xy 445.147682 -29.144226) (xy 445.147192 -29.114242)
			(xy 435.822344 -29.114242) (xy 435.822344 -29.12237) (xy 435.821854 -29.152338) (xy 435.814031 -29.21176)
			(xy 435.798518 -29.269653) (xy 435.775582 -29.325026) (xy 435.745615 -29.376932) (xy 435.709128 -29.424482)
			(xy 435.666748 -29.466862) (xy 435.619198 -29.503349) (xy 435.567292 -29.533316) (xy 435.511919 -29.556252)
			(xy 435.454026 -29.571765) (xy 435.394604 -29.579588) (xy 435.334668 -29.579588) (xy 435.275246 -29.571765)
			(xy 435.217353 -29.556252) (xy 435.16198 -29.533316) (xy 435.110074 -29.503349) (xy 435.062524 -29.466862)
			(xy 435.020144 -29.424482) (xy 434.983657 -29.376932) (xy 434.95369 -29.325026) (xy 434.930754 -29.269653)
			(xy 434.915241 -29.21176) (xy 434.907418 -29.152338) (xy 434.906928 -29.12237) (xy 420.063035 -29.12237)
			(xy 420.062678 -29.144226) (xy 420.05485 -29.203682) (xy 420.039329 -29.261607) (xy 420.01638 -29.317011)
			(xy 419.986396 -29.368945) (xy 419.94989 -29.416521) (xy 419.907485 -29.458926) (xy 419.859909 -29.495432)
			(xy 419.807975 -29.525416) (xy 419.752571 -29.548365) (xy 419.694646 -29.563886) (xy 419.63519 -29.571714)
			(xy 419.575222 -29.571714) (xy 419.515766 -29.563886) (xy 419.457841 -29.548365) (xy 419.402437 -29.525416)
			(xy 419.350503 -29.495432) (xy 419.302927 -29.458926) (xy 419.260522 -29.416521) (xy 419.224016 -29.368945)
			(xy 419.194032 -29.317011) (xy 419.171083 -29.261607) (xy 419.155562 -29.203682) (xy 419.147734 -29.144226)
			(xy 419.147244 -29.114242) (xy 409.822396 -29.114242) (xy 409.822396 -29.12237) (xy 409.821906 -29.152338)
			(xy 409.814083 -29.21176) (xy 409.79857 -29.269653) (xy 409.775634 -29.325026) (xy 409.745667 -29.376932)
			(xy 409.70918 -29.424482) (xy 409.6668 -29.466862) (xy 409.61925 -29.503349) (xy 409.567344 -29.533316)
			(xy 409.511971 -29.556252) (xy 409.454078 -29.571765) (xy 409.394656 -29.579588) (xy 409.33472 -29.579588)
			(xy 409.275298 -29.571765) (xy 409.217405 -29.556252) (xy 409.162032 -29.533316) (xy 409.110126 -29.503349)
			(xy 409.062576 -29.466862) (xy 409.020196 -29.424482) (xy 408.983709 -29.376932) (xy 408.953742 -29.325026)
			(xy 408.930806 -29.269653) (xy 408.915293 -29.21176) (xy 408.90747 -29.152338) (xy 408.90698 -29.12237)
			(xy 394.063087 -29.12237) (xy 394.06273 -29.144226) (xy 394.054902 -29.203682) (xy 394.039381 -29.261607)
			(xy 394.016432 -29.317011) (xy 393.986448 -29.368945) (xy 393.949942 -29.416521) (xy 393.907537 -29.458926)
			(xy 393.859961 -29.495432) (xy 393.808027 -29.525416) (xy 393.752623 -29.548365) (xy 393.694698 -29.563886)
			(xy 393.635242 -29.571714) (xy 393.575274 -29.571714) (xy 393.515818 -29.563886) (xy 393.457893 -29.548365)
			(xy 393.402489 -29.525416) (xy 393.350555 -29.495432) (xy 393.302979 -29.458926) (xy 393.260574 -29.416521)
			(xy 393.224068 -29.368945) (xy 393.194084 -29.317011) (xy 393.171135 -29.261607) (xy 393.155614 -29.203682)
			(xy 393.147786 -29.144226) (xy 393.147296 -29.114242) (xy 383.822448 -29.114242) (xy 383.822448 -29.12237)
			(xy 383.821958 -29.152338) (xy 383.814135 -29.21176) (xy 383.798622 -29.269653) (xy 383.775686 -29.325026)
			(xy 383.745719 -29.376932) (xy 383.709232 -29.424482) (xy 383.666852 -29.466862) (xy 383.619302 -29.503349)
			(xy 383.567396 -29.533316) (xy 383.512023 -29.556252) (xy 383.45413 -29.571765) (xy 383.394708 -29.579588)
			(xy 383.334772 -29.579588) (xy 383.27535 -29.571765) (xy 383.217457 -29.556252) (xy 383.162084 -29.533316)
			(xy 383.110178 -29.503349) (xy 383.062628 -29.466862) (xy 383.020248 -29.424482) (xy 382.983761 -29.376932)
			(xy 382.953794 -29.325026) (xy 382.930858 -29.269653) (xy 382.915345 -29.21176) (xy 382.907522 -29.152338)
			(xy 382.907032 -29.12237) (xy 368.063139 -29.12237) (xy 368.062782 -29.144226) (xy 368.054954 -29.203682)
			(xy 368.039433 -29.261607) (xy 368.016484 -29.317011) (xy 367.9865 -29.368945) (xy 367.949994 -29.416521)
			(xy 367.907589 -29.458926) (xy 367.860013 -29.495432) (xy 367.808079 -29.525416) (xy 367.752675 -29.548365)
			(xy 367.69475 -29.563886) (xy 367.635294 -29.571714) (xy 367.575326 -29.571714) (xy 367.51587 -29.563886)
			(xy 367.457945 -29.548365) (xy 367.402541 -29.525416) (xy 367.350607 -29.495432) (xy 367.303031 -29.458926)
			(xy 367.260626 -29.416521) (xy 367.22412 -29.368945) (xy 367.194136 -29.317011) (xy 367.171187 -29.261607)
			(xy 367.155666 -29.203682) (xy 367.147838 -29.144226) (xy 367.147348 -29.114242) (xy 357.8225 -29.114242)
			(xy 357.8225 -29.12237) (xy 357.82201 -29.152338) (xy 357.814187 -29.21176) (xy 357.798674 -29.269653)
			(xy 357.775738 -29.325026) (xy 357.745771 -29.376932) (xy 357.709284 -29.424482) (xy 357.666904 -29.466862)
			(xy 357.619354 -29.503349) (xy 357.567448 -29.533316) (xy 357.512075 -29.556252) (xy 357.454182 -29.571765)
			(xy 357.39476 -29.579588) (xy 357.334824 -29.579588) (xy 357.275402 -29.571765) (xy 357.217509 -29.556252)
			(xy 357.162136 -29.533316) (xy 357.11023 -29.503349) (xy 357.06268 -29.466862) (xy 357.0203 -29.424482)
			(xy 356.983813 -29.376932) (xy 356.953846 -29.325026) (xy 356.93091 -29.269653) (xy 356.915397 -29.21176)
			(xy 356.907574 -29.152338) (xy 356.907084 -29.12237) (xy 329.962631 -29.12237) (xy 329.962274 -29.14421)
			(xy 329.954451 -29.203632) (xy 329.938938 -29.261525) (xy 329.916002 -29.316898) (xy 329.886035 -29.368804)
			(xy 329.849548 -29.416354) (xy 329.807168 -29.458734) (xy 329.759618 -29.495221) (xy 329.707712 -29.525188)
			(xy 329.652339 -29.548124) (xy 329.594446 -29.563637) (xy 329.535024 -29.57146) (xy 329.475088 -29.57146)
			(xy 329.415666 -29.563637) (xy 329.357773 -29.548124) (xy 329.3024 -29.525188) (xy 329.250494 -29.495221)
			(xy 329.202944 -29.458734) (xy 329.160564 -29.416354) (xy 329.124077 -29.368804) (xy 329.09411 -29.316898)
			(xy 329.071174 -29.261525) (xy 329.055661 -29.203632) (xy 329.047838 -29.14421) (xy 329.047348 -29.114242)
			(xy 319.7225 -29.114242) (xy 319.7225 -29.12237) (xy 319.72201 -29.152354) (xy 319.714182 -29.21181)
			(xy 319.698661 -29.269735) (xy 319.675712 -29.325139) (xy 319.645728 -29.377073) (xy 319.609222 -29.424649)
			(xy 319.566817 -29.467054) (xy 319.519241 -29.50356) (xy 319.467307 -29.533544) (xy 319.411903 -29.556493)
			(xy 319.353978 -29.572014) (xy 319.294522 -29.579842) (xy 319.234554 -29.579842) (xy 319.175098 -29.572014)
			(xy 319.117173 -29.556493) (xy 319.061769 -29.533544) (xy 319.009835 -29.50356) (xy 318.962259 -29.467054)
			(xy 318.919854 -29.424649) (xy 318.883348 -29.377073) (xy 318.853364 -29.325139) (xy 318.830415 -29.269735)
			(xy 318.814894 -29.21181) (xy 318.807066 -29.152354) (xy 318.806576 -29.12237) (xy 303.962683 -29.12237)
			(xy 303.962326 -29.14421) (xy 303.954503 -29.203632) (xy 303.93899 -29.261525) (xy 303.916054 -29.316898)
			(xy 303.886087 -29.368804) (xy 303.8496 -29.416354) (xy 303.80722 -29.458734) (xy 303.75967 -29.495221)
			(xy 303.707764 -29.525188) (xy 303.652391 -29.548124) (xy 303.594498 -29.563637) (xy 303.535076 -29.57146)
			(xy 303.47514 -29.57146) (xy 303.415718 -29.563637) (xy 303.357825 -29.548124) (xy 303.302452 -29.525188)
			(xy 303.250546 -29.495221) (xy 303.202996 -29.458734) (xy 303.160616 -29.416354) (xy 303.124129 -29.368804)
			(xy 303.094162 -29.316898) (xy 303.071226 -29.261525) (xy 303.055713 -29.203632) (xy 303.04789 -29.14421)
			(xy 303.0474 -29.114242) (xy 293.722552 -29.114242) (xy 293.722552 -29.12237) (xy 293.722062 -29.152354)
			(xy 293.714234 -29.21181) (xy 293.698713 -29.269735) (xy 293.675764 -29.325139) (xy 293.64578 -29.377073)
			(xy 293.609274 -29.424649) (xy 293.566869 -29.467054) (xy 293.519293 -29.50356) (xy 293.467359 -29.533544)
			(xy 293.411955 -29.556493) (xy 293.35403 -29.572014) (xy 293.294574 -29.579842) (xy 293.234606 -29.579842)
			(xy 293.17515 -29.572014) (xy 293.117225 -29.556493) (xy 293.061821 -29.533544) (xy 293.009887 -29.50356)
			(xy 292.962311 -29.467054) (xy 292.919906 -29.424649) (xy 292.8834 -29.377073) (xy 292.853416 -29.325139)
			(xy 292.830467 -29.269735) (xy 292.814946 -29.21181) (xy 292.807118 -29.152354) (xy 292.806628 -29.12237)
			(xy 277.962735 -29.12237) (xy 277.962378 -29.14421) (xy 277.954555 -29.203632) (xy 277.939042 -29.261525)
			(xy 277.916106 -29.316898) (xy 277.886139 -29.368804) (xy 277.849652 -29.416354) (xy 277.807272 -29.458734)
			(xy 277.759722 -29.495221) (xy 277.707816 -29.525188) (xy 277.652443 -29.548124) (xy 277.59455 -29.563637)
			(xy 277.535128 -29.57146) (xy 277.475192 -29.57146) (xy 277.41577 -29.563637) (xy 277.357877 -29.548124)
			(xy 277.302504 -29.525188) (xy 277.250598 -29.495221) (xy 277.203048 -29.458734) (xy 277.160668 -29.416354)
			(xy 277.124181 -29.368804) (xy 277.094214 -29.316898) (xy 277.071278 -29.261525) (xy 277.055765 -29.203632)
			(xy 277.047942 -29.14421) (xy 277.047452 -29.114242) (xy 267.722604 -29.114242) (xy 267.722604 -29.12237)
			(xy 267.722114 -29.152354) (xy 267.714286 -29.21181) (xy 267.698765 -29.269735) (xy 267.675816 -29.325139)
			(xy 267.645832 -29.377073) (xy 267.609326 -29.424649) (xy 267.566921 -29.467054) (xy 267.519345 -29.50356)
			(xy 267.467411 -29.533544) (xy 267.412007 -29.556493) (xy 267.354082 -29.572014) (xy 267.294626 -29.579842)
			(xy 267.234658 -29.579842) (xy 267.175202 -29.572014) (xy 267.117277 -29.556493) (xy 267.061873 -29.533544)
			(xy 267.009939 -29.50356) (xy 266.962363 -29.467054) (xy 266.919958 -29.424649) (xy 266.883452 -29.377073)
			(xy 266.853468 -29.325139) (xy 266.830519 -29.269735) (xy 266.814998 -29.21181) (xy 266.80717 -29.152354)
			(xy 266.80668 -29.12237) (xy 251.962787 -29.12237) (xy 251.96243 -29.14421) (xy 251.954607 -29.203632)
			(xy 251.939094 -29.261525) (xy 251.916158 -29.316898) (xy 251.886191 -29.368804) (xy 251.849704 -29.416354)
			(xy 251.807324 -29.458734) (xy 251.759774 -29.495221) (xy 251.707868 -29.525188) (xy 251.652495 -29.548124)
			(xy 251.594602 -29.563637) (xy 251.53518 -29.57146) (xy 251.475244 -29.57146) (xy 251.415822 -29.563637)
			(xy 251.357929 -29.548124) (xy 251.302556 -29.525188) (xy 251.25065 -29.495221) (xy 251.2031 -29.458734)
			(xy 251.16072 -29.416354) (xy 251.124233 -29.368804) (xy 251.094266 -29.316898) (xy 251.07133 -29.261525)
			(xy 251.055817 -29.203632) (xy 251.047994 -29.14421) (xy 251.047504 -29.114242) (xy 241.722656 -29.114242)
			(xy 241.722656 -29.12237) (xy 241.722166 -29.152354) (xy 241.714338 -29.21181) (xy 241.698817 -29.269735)
			(xy 241.675868 -29.325139) (xy 241.645884 -29.377073) (xy 241.609378 -29.424649) (xy 241.566973 -29.467054)
			(xy 241.519397 -29.50356) (xy 241.467463 -29.533544) (xy 241.412059 -29.556493) (xy 241.354134 -29.572014)
			(xy 241.294678 -29.579842) (xy 241.23471 -29.579842) (xy 241.175254 -29.572014) (xy 241.117329 -29.556493)
			(xy 241.061925 -29.533544) (xy 241.009991 -29.50356) (xy 240.962415 -29.467054) (xy 240.92001 -29.424649)
			(xy 240.883504 -29.377073) (xy 240.85352 -29.325139) (xy 240.830571 -29.269735) (xy 240.81505 -29.21181)
			(xy 240.807222 -29.152354) (xy 240.806732 -29.12237) (xy 213.862787 -29.12237) (xy 213.86243 -29.14421)
			(xy 213.854607 -29.203632) (xy 213.839094 -29.261525) (xy 213.816158 -29.316898) (xy 213.786191 -29.368804)
			(xy 213.749704 -29.416354) (xy 213.707324 -29.458734) (xy 213.659774 -29.495221) (xy 213.607868 -29.525188)
			(xy 213.552495 -29.548124) (xy 213.494602 -29.563637) (xy 213.43518 -29.57146) (xy 213.375244 -29.57146)
			(xy 213.315822 -29.563637) (xy 213.257929 -29.548124) (xy 213.202556 -29.525188) (xy 213.15065 -29.495221)
			(xy 213.1031 -29.458734) (xy 213.06072 -29.416354) (xy 213.024233 -29.368804) (xy 212.994266 -29.316898)
			(xy 212.97133 -29.261525) (xy 212.955817 -29.203632) (xy 212.947994 -29.14421) (xy 212.947504 -29.114242)
			(xy 203.622656 -29.114242) (xy 203.622656 -29.12237) (xy 203.622166 -29.152354) (xy 203.614338 -29.21181)
			(xy 203.598817 -29.269735) (xy 203.575868 -29.325139) (xy 203.545884 -29.377073) (xy 203.509378 -29.424649)
			(xy 203.466973 -29.467054) (xy 203.419397 -29.50356) (xy 203.367463 -29.533544) (xy 203.312059 -29.556493)
			(xy 203.254134 -29.572014) (xy 203.194678 -29.579842) (xy 203.13471 -29.579842) (xy 203.075254 -29.572014)
			(xy 203.017329 -29.556493) (xy 202.961925 -29.533544) (xy 202.909991 -29.50356) (xy 202.862415 -29.467054)
			(xy 202.82001 -29.424649) (xy 202.783504 -29.377073) (xy 202.75352 -29.325139) (xy 202.730571 -29.269735)
			(xy 202.71505 -29.21181) (xy 202.707222 -29.152354) (xy 202.706732 -29.12237) (xy 187.862839 -29.12237)
			(xy 187.862482 -29.14421) (xy 187.854659 -29.203632) (xy 187.839146 -29.261525) (xy 187.81621 -29.316898)
			(xy 187.786243 -29.368804) (xy 187.749756 -29.416354) (xy 187.707376 -29.458734) (xy 187.659826 -29.495221)
			(xy 187.60792 -29.525188) (xy 187.552547 -29.548124) (xy 187.494654 -29.563637) (xy 187.435232 -29.57146)
			(xy 187.375296 -29.57146) (xy 187.315874 -29.563637) (xy 187.257981 -29.548124) (xy 187.202608 -29.525188)
			(xy 187.150702 -29.495221) (xy 187.103152 -29.458734) (xy 187.060772 -29.416354) (xy 187.024285 -29.368804)
			(xy 186.994318 -29.316898) (xy 186.971382 -29.261525) (xy 186.955869 -29.203632) (xy 186.948046 -29.14421)
			(xy 186.947556 -29.114242) (xy 177.622708 -29.114242) (xy 177.622708 -29.12237) (xy 177.622218 -29.152354)
			(xy 177.61439 -29.21181) (xy 177.598869 -29.269735) (xy 177.57592 -29.325139) (xy 177.545936 -29.377073)
			(xy 177.50943 -29.424649) (xy 177.467025 -29.467054) (xy 177.419449 -29.50356) (xy 177.367515 -29.533544)
			(xy 177.312111 -29.556493) (xy 177.254186 -29.572014) (xy 177.19473 -29.579842) (xy 177.134762 -29.579842)
			(xy 177.075306 -29.572014) (xy 177.017381 -29.556493) (xy 176.961977 -29.533544) (xy 176.910043 -29.50356)
			(xy 176.862467 -29.467054) (xy 176.820062 -29.424649) (xy 176.783556 -29.377073) (xy 176.753572 -29.325139)
			(xy 176.730623 -29.269735) (xy 176.715102 -29.21181) (xy 176.707274 -29.152354) (xy 176.706784 -29.12237)
			(xy 161.862891 -29.12237) (xy 161.862534 -29.14421) (xy 161.854711 -29.203632) (xy 161.839198 -29.261525)
			(xy 161.816262 -29.316898) (xy 161.786295 -29.368804) (xy 161.749808 -29.416354) (xy 161.707428 -29.458734)
			(xy 161.659878 -29.495221) (xy 161.607972 -29.525188) (xy 161.552599 -29.548124) (xy 161.494706 -29.563637)
			(xy 161.435284 -29.57146) (xy 161.375348 -29.57146) (xy 161.315926 -29.563637) (xy 161.258033 -29.548124)
			(xy 161.20266 -29.525188) (xy 161.150754 -29.495221) (xy 161.103204 -29.458734) (xy 161.060824 -29.416354)
			(xy 161.024337 -29.368804) (xy 160.99437 -29.316898) (xy 160.971434 -29.261525) (xy 160.955921 -29.203632)
			(xy 160.948098 -29.14421) (xy 160.947608 -29.114242) (xy 151.62276 -29.114242) (xy 151.62276 -29.12237)
			(xy 151.62227 -29.152354) (xy 151.614442 -29.21181) (xy 151.598921 -29.269735) (xy 151.575972 -29.325139)
			(xy 151.545988 -29.377073) (xy 151.509482 -29.424649) (xy 151.467077 -29.467054) (xy 151.419501 -29.50356)
			(xy 151.367567 -29.533544) (xy 151.312163 -29.556493) (xy 151.254238 -29.572014) (xy 151.194782 -29.579842)
			(xy 151.134814 -29.579842) (xy 151.075358 -29.572014) (xy 151.017433 -29.556493) (xy 150.962029 -29.533544)
			(xy 150.910095 -29.50356) (xy 150.862519 -29.467054) (xy 150.820114 -29.424649) (xy 150.783608 -29.377073)
			(xy 150.753624 -29.325139) (xy 150.730675 -29.269735) (xy 150.715154 -29.21181) (xy 150.707326 -29.152354)
			(xy 150.706836 -29.12237) (xy 135.862943 -29.12237) (xy 135.862586 -29.14421) (xy 135.854763 -29.203632)
			(xy 135.83925 -29.261525) (xy 135.816314 -29.316898) (xy 135.786347 -29.368804) (xy 135.74986 -29.416354)
			(xy 135.70748 -29.458734) (xy 135.65993 -29.495221) (xy 135.608024 -29.525188) (xy 135.552651 -29.548124)
			(xy 135.494758 -29.563637) (xy 135.435336 -29.57146) (xy 135.3754 -29.57146) (xy 135.315978 -29.563637)
			(xy 135.258085 -29.548124) (xy 135.202712 -29.525188) (xy 135.150806 -29.495221) (xy 135.103256 -29.458734)
			(xy 135.060876 -29.416354) (xy 135.024389 -29.368804) (xy 134.994422 -29.316898) (xy 134.971486 -29.261525)
			(xy 134.955973 -29.203632) (xy 134.94815 -29.14421) (xy 134.94766 -29.114242) (xy 125.622812 -29.114242)
			(xy 125.622812 -29.12237) (xy 125.622322 -29.152354) (xy 125.614494 -29.21181) (xy 125.598973 -29.269735)
			(xy 125.576024 -29.325139) (xy 125.54604 -29.377073) (xy 125.509534 -29.424649) (xy 125.467129 -29.467054)
			(xy 125.419553 -29.50356) (xy 125.367619 -29.533544) (xy 125.312215 -29.556493) (xy 125.25429 -29.572014)
			(xy 125.194834 -29.579842) (xy 125.134866 -29.579842) (xy 125.07541 -29.572014) (xy 125.017485 -29.556493)
			(xy 124.962081 -29.533544) (xy 124.910147 -29.50356) (xy 124.862571 -29.467054) (xy 124.820166 -29.424649)
			(xy 124.78366 -29.377073) (xy 124.753676 -29.325139) (xy 124.730727 -29.269735) (xy 124.715206 -29.21181)
			(xy 124.707378 -29.152354) (xy 124.706888 -29.12237) (xy 97.762943 -29.12237) (xy 97.762586 -29.144226)
			(xy 97.754758 -29.203682) (xy 97.739237 -29.261607) (xy 97.716288 -29.317011) (xy 97.686304 -29.368945)
			(xy 97.649798 -29.416521) (xy 97.607393 -29.458926) (xy 97.559817 -29.495432) (xy 97.507883 -29.525416)
			(xy 97.452479 -29.548365) (xy 97.394554 -29.563886) (xy 97.335098 -29.571714) (xy 97.27513 -29.571714)
			(xy 97.215674 -29.563886) (xy 97.157749 -29.548365) (xy 97.102345 -29.525416) (xy 97.050411 -29.495432)
			(xy 97.002835 -29.458926) (xy 96.96043 -29.416521) (xy 96.923924 -29.368945) (xy 96.89394 -29.317011)
			(xy 96.870991 -29.261607) (xy 96.85547 -29.203682) (xy 96.847642 -29.144226) (xy 96.847152 -29.114242)
			(xy 87.522304 -29.114242) (xy 87.522304 -29.12237) (xy 87.521814 -29.152338) (xy 87.513991 -29.21176)
			(xy 87.498478 -29.269653) (xy 87.475542 -29.325026) (xy 87.445575 -29.376932) (xy 87.409088 -29.424482)
			(xy 87.366708 -29.466862) (xy 87.319158 -29.503349) (xy 87.267252 -29.533316) (xy 87.211879 -29.556252)
			(xy 87.153986 -29.571765) (xy 87.094564 -29.579588) (xy 87.034628 -29.579588) (xy 86.975206 -29.571765)
			(xy 86.917313 -29.556252) (xy 86.86194 -29.533316) (xy 86.810034 -29.503349) (xy 86.762484 -29.466862)
			(xy 86.720104 -29.424482) (xy 86.683617 -29.376932) (xy 86.65365 -29.325026) (xy 86.630714 -29.269653)
			(xy 86.615201 -29.21176) (xy 86.607378 -29.152338) (xy 86.606888 -29.12237) (xy 71.762995 -29.12237)
			(xy 71.762638 -29.144226) (xy 71.75481 -29.203682) (xy 71.739289 -29.261607) (xy 71.71634 -29.317011)
			(xy 71.686356 -29.368945) (xy 71.64985 -29.416521) (xy 71.607445 -29.458926) (xy 71.559869 -29.495432)
			(xy 71.507935 -29.525416) (xy 71.452531 -29.548365) (xy 71.394606 -29.563886) (xy 71.33515 -29.571714)
			(xy 71.275182 -29.571714) (xy 71.215726 -29.563886) (xy 71.157801 -29.548365) (xy 71.102397 -29.525416)
			(xy 71.050463 -29.495432) (xy 71.002887 -29.458926) (xy 70.960482 -29.416521) (xy 70.923976 -29.368945)
			(xy 70.893992 -29.317011) (xy 70.871043 -29.261607) (xy 70.855522 -29.203682) (xy 70.847694 -29.144226)
			(xy 70.847204 -29.114242) (xy 61.522356 -29.114242) (xy 61.522356 -29.12237) (xy 61.521866 -29.152338)
			(xy 61.514043 -29.21176) (xy 61.49853 -29.269653) (xy 61.475594 -29.325026) (xy 61.445627 -29.376932)
			(xy 61.40914 -29.424482) (xy 61.36676 -29.466862) (xy 61.31921 -29.503349) (xy 61.267304 -29.533316)
			(xy 61.211931 -29.556252) (xy 61.154038 -29.571765) (xy 61.094616 -29.579588) (xy 61.03468 -29.579588)
			(xy 60.975258 -29.571765) (xy 60.917365 -29.556252) (xy 60.861992 -29.533316) (xy 60.810086 -29.503349)
			(xy 60.762536 -29.466862) (xy 60.720156 -29.424482) (xy 60.683669 -29.376932) (xy 60.653702 -29.325026)
			(xy 60.630766 -29.269653) (xy 60.615253 -29.21176) (xy 60.60743 -29.152338) (xy 60.60694 -29.12237)
			(xy 45.763047 -29.12237) (xy 45.76269 -29.144226) (xy 45.754862 -29.203682) (xy 45.739341 -29.261607)
			(xy 45.716392 -29.317011) (xy 45.686408 -29.368945) (xy 45.649902 -29.416521) (xy 45.607497 -29.458926)
			(xy 45.559921 -29.495432) (xy 45.507987 -29.525416) (xy 45.452583 -29.548365) (xy 45.394658 -29.563886)
			(xy 45.335202 -29.571714) (xy 45.275234 -29.571714) (xy 45.215778 -29.563886) (xy 45.157853 -29.548365)
			(xy 45.102449 -29.525416) (xy 45.050515 -29.495432) (xy 45.002939 -29.458926) (xy 44.960534 -29.416521)
			(xy 44.924028 -29.368945) (xy 44.894044 -29.317011) (xy 44.871095 -29.261607) (xy 44.855574 -29.203682)
			(xy 44.847746 -29.144226) (xy 44.847256 -29.114242) (xy 35.522408 -29.114242) (xy 35.522408 -29.12237)
			(xy 35.521918 -29.152338) (xy 35.514095 -29.21176) (xy 35.498582 -29.269653) (xy 35.475646 -29.325026)
			(xy 35.445679 -29.376932) (xy 35.409192 -29.424482) (xy 35.366812 -29.466862) (xy 35.319262 -29.503349)
			(xy 35.267356 -29.533316) (xy 35.211983 -29.556252) (xy 35.15409 -29.571765) (xy 35.094668 -29.579588)
			(xy 35.034732 -29.579588) (xy 34.97531 -29.571765) (xy 34.917417 -29.556252) (xy 34.862044 -29.533316)
			(xy 34.810138 -29.503349) (xy 34.762588 -29.466862) (xy 34.720208 -29.424482) (xy 34.683721 -29.376932)
			(xy 34.653754 -29.325026) (xy 34.630818 -29.269653) (xy 34.615305 -29.21176) (xy 34.607482 -29.152338)
			(xy 34.606992 -29.12237) (xy 19.763099 -29.12237) (xy 19.762742 -29.144226) (xy 19.754914 -29.203682)
			(xy 19.739393 -29.261607) (xy 19.716444 -29.317011) (xy 19.68646 -29.368945) (xy 19.649954 -29.416521)
			(xy 19.607549 -29.458926) (xy 19.559973 -29.495432) (xy 19.508039 -29.525416) (xy 19.452635 -29.548365)
			(xy 19.39471 -29.563886) (xy 19.335254 -29.571714) (xy 19.275286 -29.571714) (xy 19.21583 -29.563886)
			(xy 19.157905 -29.548365) (xy 19.102501 -29.525416) (xy 19.050567 -29.495432) (xy 19.002991 -29.458926)
			(xy 18.960586 -29.416521) (xy 18.92408 -29.368945) (xy 18.894096 -29.317011) (xy 18.871147 -29.261607)
			(xy 18.855626 -29.203682) (xy 18.847798 -29.144226) (xy 18.847308 -29.114242) (xy 9.52246 -29.114242)
			(xy 9.52246 -29.12237) (xy 9.52197 -29.152338) (xy 9.514147 -29.21176) (xy 9.498634 -29.269653) (xy 9.475698 -29.325026)
			(xy 9.445731 -29.376932) (xy 9.409244 -29.424482) (xy 9.366864 -29.466862) (xy 9.319314 -29.503349)
			(xy 9.267408 -29.533316) (xy 9.212035 -29.556252) (xy 9.154142 -29.571765) (xy 9.09472 -29.579588)
			(xy 9.034784 -29.579588) (xy 8.975362 -29.571765) (xy 8.917469 -29.556252) (xy 8.862096 -29.533316)
			(xy 8.81019 -29.503349) (xy 8.76264 -29.466862) (xy 8.72026 -29.424482) (xy 8.683773 -29.376932)
			(xy 8.653806 -29.325026) (xy 8.63087 -29.269653) (xy 8.615357 -29.21176) (xy 8.607534 -29.152338)
			(xy 8.607044 -29.12237) (xy 0.508 -29.12237) (xy 0.508 -30.922468) (xy 6.752844 -30.922468) (xy 6.752844 -30.058868)
			(xy 6.753334 -30.0289) (xy 6.761157 -29.969478) (xy 6.77667 -29.911585) (xy 6.799606 -29.856212)
			(xy 6.829573 -29.804306) (xy 6.86606 -29.756756) (xy 6.90844 -29.714376) (xy 6.95599 -29.677889)
			(xy 7.007896 -29.647922) (xy 7.063269 -29.624986) (xy 7.121162 -29.609473) (xy 7.180584 -29.60165)
			(xy 7.24052 -29.60165) (xy 7.299942 -29.609473) (xy 7.357835 -29.624986) (xy 7.413208 -29.647922)
			(xy 7.465114 -29.677889) (xy 7.512664 -29.714376) (xy 7.555044 -29.756756) (xy 7.591531 -29.804306)
			(xy 7.621498 -29.856212) (xy 7.644434 -29.911585) (xy 7.659947 -29.969478) (xy 7.66777 -30.0289)
			(xy 7.66826 -30.058868) (xy 7.66826 -30.92069) (xy 21.489416 -30.92069) (xy 21.489416 -30.05709)
			(xy 21.489906 -30.027106) (xy 21.497734 -29.96765) (xy 21.513255 -29.909725) (xy 21.536204 -29.854321)
			(xy 21.566188 -29.802387) (xy 21.602694 -29.754811) (xy 21.645099 -29.712406) (xy 21.692675 -29.6759)
			(xy 21.744609 -29.645916) (xy 21.800013 -29.622967) (xy 21.857938 -29.607446) (xy 21.917394 -29.599618)
			(xy 21.977362 -29.599618) (xy 22.036818 -29.607446) (xy 22.094743 -29.622967) (xy 22.150147 -29.645916)
			(xy 22.202081 -29.6759) (xy 22.249657 -29.712406) (xy 22.292062 -29.754811) (xy 22.328568 -29.802387)
			(xy 22.358552 -29.854321) (xy 22.381501 -29.909725) (xy 22.397022 -29.96765) (xy 22.40485 -30.027106)
			(xy 22.40534 -30.05709) (xy 22.40534 -30.92069) (xy 22.405311 -30.922468) (xy 32.752792 -30.922468)
			(xy 32.752792 -30.058868) (xy 32.753282 -30.0289) (xy 32.761105 -29.969478) (xy 32.776618 -29.911585)
			(xy 32.799554 -29.856212) (xy 32.829521 -29.804306) (xy 32.866008 -29.756756) (xy 32.908388 -29.714376)
			(xy 32.955938 -29.677889) (xy 33.007844 -29.647922) (xy 33.063217 -29.624986) (xy 33.12111 -29.609473)
			(xy 33.180532 -29.60165) (xy 33.240468 -29.60165) (xy 33.29989 -29.609473) (xy 33.357783 -29.624986)
			(xy 33.413156 -29.647922) (xy 33.465062 -29.677889) (xy 33.512612 -29.714376) (xy 33.554992 -29.756756)
			(xy 33.591479 -29.804306) (xy 33.621446 -29.856212) (xy 33.644382 -29.911585) (xy 33.659895 -29.969478)
			(xy 33.667718 -30.0289) (xy 33.668208 -30.058868) (xy 33.668208 -30.92069) (xy 47.489364 -30.92069)
			(xy 47.489364 -30.05709) (xy 47.489854 -30.027106) (xy 47.497682 -29.96765) (xy 47.513203 -29.909725)
			(xy 47.536152 -29.854321) (xy 47.566136 -29.802387) (xy 47.602642 -29.754811) (xy 47.645047 -29.712406)
			(xy 47.692623 -29.6759) (xy 47.744557 -29.645916) (xy 47.799961 -29.622967) (xy 47.857886 -29.607446)
			(xy 47.917342 -29.599618) (xy 47.97731 -29.599618) (xy 48.036766 -29.607446) (xy 48.094691 -29.622967)
			(xy 48.150095 -29.645916) (xy 48.202029 -29.6759) (xy 48.249605 -29.712406) (xy 48.29201 -29.754811)
			(xy 48.328516 -29.802387) (xy 48.3585 -29.854321) (xy 48.381449 -29.909725) (xy 48.39697 -29.96765)
			(xy 48.404798 -30.027106) (xy 48.405288 -30.05709) (xy 48.405288 -30.92069) (xy 48.405259 -30.922468)
			(xy 58.75274 -30.922468) (xy 58.75274 -30.058868) (xy 58.75323 -30.0289) (xy 58.761053 -29.969478)
			(xy 58.776566 -29.911585) (xy 58.799502 -29.856212) (xy 58.829469 -29.804306) (xy 58.865956 -29.756756)
			(xy 58.908336 -29.714376) (xy 58.955886 -29.677889) (xy 59.007792 -29.647922) (xy 59.063165 -29.624986)
			(xy 59.121058 -29.609473) (xy 59.18048 -29.60165) (xy 59.240416 -29.60165) (xy 59.299838 -29.609473)
			(xy 59.357731 -29.624986) (xy 59.413104 -29.647922) (xy 59.46501 -29.677889) (xy 59.51256 -29.714376)
			(xy 59.55494 -29.756756) (xy 59.591427 -29.804306) (xy 59.621394 -29.856212) (xy 59.64433 -29.911585)
			(xy 59.659843 -29.969478) (xy 59.667666 -30.0289) (xy 59.668156 -30.058868) (xy 59.668156 -30.92069)
			(xy 73.489312 -30.92069) (xy 73.489312 -30.05709) (xy 73.489802 -30.027106) (xy 73.49763 -29.96765)
			(xy 73.513151 -29.909725) (xy 73.5361 -29.854321) (xy 73.566084 -29.802387) (xy 73.60259 -29.754811)
			(xy 73.644995 -29.712406) (xy 73.692571 -29.6759) (xy 73.744505 -29.645916) (xy 73.799909 -29.622967)
			(xy 73.857834 -29.607446) (xy 73.91729 -29.599618) (xy 73.977258 -29.599618) (xy 74.036714 -29.607446)
			(xy 74.094639 -29.622967) (xy 74.150043 -29.645916) (xy 74.201977 -29.6759) (xy 74.249553 -29.712406)
			(xy 74.291958 -29.754811) (xy 74.328464 -29.802387) (xy 74.358448 -29.854321) (xy 74.381397 -29.909725)
			(xy 74.396918 -29.96765) (xy 74.404746 -30.027106) (xy 74.405236 -30.05709) (xy 74.405236 -30.92069)
			(xy 74.405207 -30.922468) (xy 84.752688 -30.922468) (xy 84.752688 -30.058868) (xy 84.753178 -30.0289)
			(xy 84.761001 -29.969478) (xy 84.776514 -29.911585) (xy 84.79945 -29.856212) (xy 84.829417 -29.804306)
			(xy 84.865904 -29.756756) (xy 84.908284 -29.714376) (xy 84.955834 -29.677889) (xy 85.00774 -29.647922)
			(xy 85.063113 -29.624986) (xy 85.121006 -29.609473) (xy 85.180428 -29.60165) (xy 85.240364 -29.60165)
			(xy 85.299786 -29.609473) (xy 85.357679 -29.624986) (xy 85.413052 -29.647922) (xy 85.464958 -29.677889)
			(xy 85.512508 -29.714376) (xy 85.554888 -29.756756) (xy 85.591375 -29.804306) (xy 85.621342 -29.856212)
			(xy 85.644278 -29.911585) (xy 85.659791 -29.969478) (xy 85.667614 -30.0289) (xy 85.668104 -30.058868)
			(xy 85.668104 -30.92069) (xy 99.48926 -30.92069) (xy 99.48926 -30.05709) (xy 99.48975 -30.027106)
			(xy 99.497578 -29.96765) (xy 99.513099 -29.909725) (xy 99.536048 -29.854321) (xy 99.566032 -29.802387)
			(xy 99.602538 -29.754811) (xy 99.644943 -29.712406) (xy 99.692519 -29.6759) (xy 99.744453 -29.645916)
			(xy 99.799857 -29.622967) (xy 99.857782 -29.607446) (xy 99.917238 -29.599618) (xy 99.977206 -29.599618)
			(xy 100.036662 -29.607446) (xy 100.094587 -29.622967) (xy 100.149991 -29.645916) (xy 100.201925 -29.6759)
			(xy 100.249501 -29.712406) (xy 100.291906 -29.754811) (xy 100.328412 -29.802387) (xy 100.358396 -29.854321)
			(xy 100.381345 -29.909725) (xy 100.396866 -29.96765) (xy 100.404694 -30.027106) (xy 100.405184 -30.05709)
			(xy 100.405184 -30.92069) (xy 100.405155 -30.922468) (xy 122.852688 -30.922468) (xy 122.852688 -30.058868)
			(xy 122.853178 -30.028884) (xy 122.861006 -29.969428) (xy 122.876527 -29.911503) (xy 122.899476 -29.856099)
			(xy 122.92946 -29.804165) (xy 122.965966 -29.756589) (xy 123.008371 -29.714184) (xy 123.055947 -29.677678)
			(xy 123.107881 -29.647694) (xy 123.163285 -29.624745) (xy 123.22121 -29.609224) (xy 123.280666 -29.601396)
			(xy 123.340634 -29.601396) (xy 123.40009 -29.609224) (xy 123.458015 -29.624745) (xy 123.513419 -29.647694)
			(xy 123.565353 -29.677678) (xy 123.612929 -29.714184) (xy 123.655334 -29.756589) (xy 123.69184 -29.804165)
			(xy 123.721824 -29.856099) (xy 123.744773 -29.911503) (xy 123.760294 -29.969428) (xy 123.768122 -30.028884)
			(xy 123.768612 -30.058868) (xy 123.768612 -30.92069) (xy 137.589768 -30.92069) (xy 137.589768 -30.05709)
			(xy 137.590258 -30.027122) (xy 137.598081 -29.9677) (xy 137.613594 -29.909807) (xy 137.63653 -29.854434)
			(xy 137.666497 -29.802528) (xy 137.702984 -29.754978) (xy 137.745364 -29.712598) (xy 137.792914 -29.676111)
			(xy 137.84482 -29.646144) (xy 137.900193 -29.623208) (xy 137.958086 -29.607695) (xy 138.017508 -29.599872)
			(xy 138.077444 -29.599872) (xy 138.136866 -29.607695) (xy 138.194759 -29.623208) (xy 138.250132 -29.646144)
			(xy 138.302038 -29.676111) (xy 138.349588 -29.712598) (xy 138.391968 -29.754978) (xy 138.428455 -29.802528)
			(xy 138.458422 -29.854434) (xy 138.481358 -29.909807) (xy 138.496871 -29.9677) (xy 138.504694 -30.027122)
			(xy 138.505184 -30.05709) (xy 138.505184 -30.92069) (xy 138.505155 -30.922468) (xy 148.852636 -30.922468)
			(xy 148.852636 -30.058868) (xy 148.853126 -30.028884) (xy 148.860954 -29.969428) (xy 148.876475 -29.911503)
			(xy 148.899424 -29.856099) (xy 148.929408 -29.804165) (xy 148.965914 -29.756589) (xy 149.008319 -29.714184)
			(xy 149.055895 -29.677678) (xy 149.107829 -29.647694) (xy 149.163233 -29.624745) (xy 149.221158 -29.609224)
			(xy 149.280614 -29.601396) (xy 149.340582 -29.601396) (xy 149.400038 -29.609224) (xy 149.457963 -29.624745)
			(xy 149.513367 -29.647694) (xy 149.565301 -29.677678) (xy 149.612877 -29.714184) (xy 149.655282 -29.756589)
			(xy 149.691788 -29.804165) (xy 149.721772 -29.856099) (xy 149.744721 -29.911503) (xy 149.760242 -29.969428)
			(xy 149.76807 -30.028884) (xy 149.76856 -30.058868) (xy 149.76856 -30.92069) (xy 163.589716 -30.92069)
			(xy 163.589716 -30.05709) (xy 163.590206 -30.027122) (xy 163.598029 -29.9677) (xy 163.613542 -29.909807)
			(xy 163.636478 -29.854434) (xy 163.666445 -29.802528) (xy 163.702932 -29.754978) (xy 163.745312 -29.712598)
			(xy 163.792862 -29.676111) (xy 163.844768 -29.646144) (xy 163.900141 -29.623208) (xy 163.958034 -29.607695)
			(xy 164.017456 -29.599872) (xy 164.077392 -29.599872) (xy 164.136814 -29.607695) (xy 164.194707 -29.623208)
			(xy 164.25008 -29.646144) (xy 164.301986 -29.676111) (xy 164.349536 -29.712598) (xy 164.391916 -29.754978)
			(xy 164.428403 -29.802528) (xy 164.45837 -29.854434) (xy 164.481306 -29.909807) (xy 164.496819 -29.9677)
			(xy 164.504642 -30.027122) (xy 164.505132 -30.05709) (xy 164.505132 -30.92069) (xy 164.505103 -30.922468)
			(xy 174.852584 -30.922468) (xy 174.852584 -30.058868) (xy 174.853074 -30.028884) (xy 174.860902 -29.969428)
			(xy 174.876423 -29.911503) (xy 174.899372 -29.856099) (xy 174.929356 -29.804165) (xy 174.965862 -29.756589)
			(xy 175.008267 -29.714184) (xy 175.055843 -29.677678) (xy 175.107777 -29.647694) (xy 175.163181 -29.624745)
			(xy 175.221106 -29.609224) (xy 175.280562 -29.601396) (xy 175.34053 -29.601396) (xy 175.399986 -29.609224)
			(xy 175.457911 -29.624745) (xy 175.513315 -29.647694) (xy 175.565249 -29.677678) (xy 175.612825 -29.714184)
			(xy 175.65523 -29.756589) (xy 175.691736 -29.804165) (xy 175.72172 -29.856099) (xy 175.744669 -29.911503)
			(xy 175.76019 -29.969428) (xy 175.768018 -30.028884) (xy 175.768508 -30.058868) (xy 175.768508 -30.92069)
			(xy 189.589664 -30.92069) (xy 189.589664 -30.05709) (xy 189.590154 -30.027122) (xy 189.597977 -29.9677)
			(xy 189.61349 -29.909807) (xy 189.636426 -29.854434) (xy 189.666393 -29.802528) (xy 189.70288 -29.754978)
			(xy 189.74526 -29.712598) (xy 189.79281 -29.676111) (xy 189.844716 -29.646144) (xy 189.900089 -29.623208)
			(xy 189.957982 -29.607695) (xy 190.017404 -29.599872) (xy 190.07734 -29.599872) (xy 190.136762 -29.607695)
			(xy 190.194655 -29.623208) (xy 190.250028 -29.646144) (xy 190.301934 -29.676111) (xy 190.349484 -29.712598)
			(xy 190.391864 -29.754978) (xy 190.428351 -29.802528) (xy 190.458318 -29.854434) (xy 190.481254 -29.909807)
			(xy 190.496767 -29.9677) (xy 190.50459 -30.027122) (xy 190.50508 -30.05709) (xy 190.50508 -30.92069)
			(xy 190.505051 -30.922468) (xy 200.852532 -30.922468) (xy 200.852532 -30.058868) (xy 200.853022 -30.028884)
			(xy 200.86085 -29.969428) (xy 200.876371 -29.911503) (xy 200.89932 -29.856099) (xy 200.929304 -29.804165)
			(xy 200.96581 -29.756589) (xy 201.008215 -29.714184) (xy 201.055791 -29.677678) (xy 201.107725 -29.647694)
			(xy 201.163129 -29.624745) (xy 201.221054 -29.609224) (xy 201.28051 -29.601396) (xy 201.340478 -29.601396)
			(xy 201.399934 -29.609224) (xy 201.457859 -29.624745) (xy 201.513263 -29.647694) (xy 201.565197 -29.677678)
			(xy 201.612773 -29.714184) (xy 201.655178 -29.756589) (xy 201.691684 -29.804165) (xy 201.721668 -29.856099)
			(xy 201.744617 -29.911503) (xy 201.760138 -29.969428) (xy 201.767966 -30.028884) (xy 201.768456 -30.058868)
			(xy 201.768456 -30.92069) (xy 215.589612 -30.92069) (xy 215.589612 -30.05709) (xy 215.590102 -30.027122)
			(xy 215.597925 -29.9677) (xy 215.613438 -29.909807) (xy 215.636374 -29.854434) (xy 215.666341 -29.802528)
			(xy 215.702828 -29.754978) (xy 215.745208 -29.712598) (xy 215.792758 -29.676111) (xy 215.844664 -29.646144)
			(xy 215.900037 -29.623208) (xy 215.95793 -29.607695) (xy 216.017352 -29.599872) (xy 216.077288 -29.599872)
			(xy 216.13671 -29.607695) (xy 216.194603 -29.623208) (xy 216.249976 -29.646144) (xy 216.301882 -29.676111)
			(xy 216.349432 -29.712598) (xy 216.391812 -29.754978) (xy 216.428299 -29.802528) (xy 216.458266 -29.854434)
			(xy 216.481202 -29.909807) (xy 216.496715 -29.9677) (xy 216.504538 -30.027122) (xy 216.505028 -30.05709)
			(xy 216.505028 -30.92069) (xy 216.504999 -30.922468) (xy 238.952532 -30.922468) (xy 238.952532 -30.058868)
			(xy 238.953022 -30.028884) (xy 238.96085 -29.969428) (xy 238.976371 -29.911503) (xy 238.99932 -29.856099)
			(xy 239.029304 -29.804165) (xy 239.06581 -29.756589) (xy 239.108215 -29.714184) (xy 239.155791 -29.677678)
			(xy 239.207725 -29.647694) (xy 239.263129 -29.624745) (xy 239.321054 -29.609224) (xy 239.38051 -29.601396)
			(xy 239.440478 -29.601396) (xy 239.499934 -29.609224) (xy 239.557859 -29.624745) (xy 239.613263 -29.647694)
			(xy 239.665197 -29.677678) (xy 239.712773 -29.714184) (xy 239.755178 -29.756589) (xy 239.791684 -29.804165)
			(xy 239.821668 -29.856099) (xy 239.844617 -29.911503) (xy 239.860138 -29.969428) (xy 239.867966 -30.028884)
			(xy 239.868456 -30.058868) (xy 239.868456 -30.92069) (xy 253.689612 -30.92069) (xy 253.689612 -30.05709)
			(xy 253.690102 -30.027122) (xy 253.697925 -29.9677) (xy 253.713438 -29.909807) (xy 253.736374 -29.854434)
			(xy 253.766341 -29.802528) (xy 253.802828 -29.754978) (xy 253.845208 -29.712598) (xy 253.892758 -29.676111)
			(xy 253.944664 -29.646144) (xy 254.000037 -29.623208) (xy 254.05793 -29.607695) (xy 254.117352 -29.599872)
			(xy 254.177288 -29.599872) (xy 254.23671 -29.607695) (xy 254.294603 -29.623208) (xy 254.349976 -29.646144)
			(xy 254.401882 -29.676111) (xy 254.449432 -29.712598) (xy 254.491812 -29.754978) (xy 254.528299 -29.802528)
			(xy 254.558266 -29.854434) (xy 254.581202 -29.909807) (xy 254.596715 -29.9677) (xy 254.604538 -30.027122)
			(xy 254.605028 -30.05709) (xy 254.605028 -30.92069) (xy 254.604999 -30.922468) (xy 264.95248 -30.922468)
			(xy 264.95248 -30.058868) (xy 264.95297 -30.028884) (xy 264.960798 -29.969428) (xy 264.976319 -29.911503)
			(xy 264.999268 -29.856099) (xy 265.029252 -29.804165) (xy 265.065758 -29.756589) (xy 265.108163 -29.714184)
			(xy 265.155739 -29.677678) (xy 265.207673 -29.647694) (xy 265.263077 -29.624745) (xy 265.321002 -29.609224)
			(xy 265.380458 -29.601396) (xy 265.440426 -29.601396) (xy 265.499882 -29.609224) (xy 265.557807 -29.624745)
			(xy 265.613211 -29.647694) (xy 265.665145 -29.677678) (xy 265.712721 -29.714184) (xy 265.755126 -29.756589)
			(xy 265.791632 -29.804165) (xy 265.821616 -29.856099) (xy 265.844565 -29.911503) (xy 265.860086 -29.969428)
			(xy 265.867914 -30.028884) (xy 265.868404 -30.058868) (xy 265.868404 -30.92069) (xy 279.68956 -30.92069)
			(xy 279.68956 -30.05709) (xy 279.69005 -30.027122) (xy 279.697873 -29.9677) (xy 279.713386 -29.909807)
			(xy 279.736322 -29.854434) (xy 279.766289 -29.802528) (xy 279.802776 -29.754978) (xy 279.845156 -29.712598)
			(xy 279.892706 -29.676111) (xy 279.944612 -29.646144) (xy 279.999985 -29.623208) (xy 280.057878 -29.607695)
			(xy 280.1173 -29.599872) (xy 280.177236 -29.599872) (xy 280.236658 -29.607695) (xy 280.294551 -29.623208)
			(xy 280.349924 -29.646144) (xy 280.40183 -29.676111) (xy 280.44938 -29.712598) (xy 280.49176 -29.754978)
			(xy 280.528247 -29.802528) (xy 280.558214 -29.854434) (xy 280.58115 -29.909807) (xy 280.596663 -29.9677)
			(xy 280.604486 -30.027122) (xy 280.604976 -30.05709) (xy 280.604976 -30.92069) (xy 280.604947 -30.922468)
			(xy 290.952428 -30.922468) (xy 290.952428 -30.058868) (xy 290.952918 -30.028884) (xy 290.960746 -29.969428)
			(xy 290.976267 -29.911503) (xy 290.999216 -29.856099) (xy 291.0292 -29.804165) (xy 291.065706 -29.756589)
			(xy 291.108111 -29.714184) (xy 291.155687 -29.677678) (xy 291.207621 -29.647694) (xy 291.263025 -29.624745)
			(xy 291.32095 -29.609224) (xy 291.380406 -29.601396) (xy 291.440374 -29.601396) (xy 291.49983 -29.609224)
			(xy 291.557755 -29.624745) (xy 291.613159 -29.647694) (xy 291.665093 -29.677678) (xy 291.712669 -29.714184)
			(xy 291.755074 -29.756589) (xy 291.79158 -29.804165) (xy 291.821564 -29.856099) (xy 291.844513 -29.911503)
			(xy 291.860034 -29.969428) (xy 291.867862 -30.028884) (xy 291.868352 -30.058868) (xy 291.868352 -30.92069)
			(xy 305.689508 -30.92069) (xy 305.689508 -30.05709) (xy 305.689998 -30.027122) (xy 305.697821 -29.9677)
			(xy 305.713334 -29.909807) (xy 305.73627 -29.854434) (xy 305.766237 -29.802528) (xy 305.802724 -29.754978)
			(xy 305.845104 -29.712598) (xy 305.892654 -29.676111) (xy 305.94456 -29.646144) (xy 305.999933 -29.623208)
			(xy 306.057826 -29.607695) (xy 306.117248 -29.599872) (xy 306.177184 -29.599872) (xy 306.236606 -29.607695)
			(xy 306.294499 -29.623208) (xy 306.349872 -29.646144) (xy 306.401778 -29.676111) (xy 306.449328 -29.712598)
			(xy 306.491708 -29.754978) (xy 306.528195 -29.802528) (xy 306.558162 -29.854434) (xy 306.581098 -29.909807)
			(xy 306.596611 -29.9677) (xy 306.604434 -30.027122) (xy 306.604924 -30.05709) (xy 306.604924 -30.92069)
			(xy 306.604895 -30.922468) (xy 316.952376 -30.922468) (xy 316.952376 -30.058868) (xy 316.952866 -30.028884)
			(xy 316.960694 -29.969428) (xy 316.976215 -29.911503) (xy 316.999164 -29.856099) (xy 317.029148 -29.804165)
			(xy 317.065654 -29.756589) (xy 317.108059 -29.714184) (xy 317.155635 -29.677678) (xy 317.207569 -29.647694)
			(xy 317.262973 -29.624745) (xy 317.320898 -29.609224) (xy 317.380354 -29.601396) (xy 317.440322 -29.601396)
			(xy 317.499778 -29.609224) (xy 317.557703 -29.624745) (xy 317.613107 -29.647694) (xy 317.665041 -29.677678)
			(xy 317.712617 -29.714184) (xy 317.755022 -29.756589) (xy 317.791528 -29.804165) (xy 317.821512 -29.856099)
			(xy 317.844461 -29.911503) (xy 317.859982 -29.969428) (xy 317.86781 -30.028884) (xy 317.8683 -30.058868)
			(xy 317.8683 -30.92069) (xy 331.689456 -30.92069) (xy 331.689456 -30.05709) (xy 331.689946 -30.027122)
			(xy 331.697769 -29.9677) (xy 331.713282 -29.909807) (xy 331.736218 -29.854434) (xy 331.766185 -29.802528)
			(xy 331.802672 -29.754978) (xy 331.845052 -29.712598) (xy 331.892602 -29.676111) (xy 331.944508 -29.646144)
			(xy 331.999881 -29.623208) (xy 332.057774 -29.607695) (xy 332.117196 -29.599872) (xy 332.177132 -29.599872)
			(xy 332.236554 -29.607695) (xy 332.294447 -29.623208) (xy 332.34982 -29.646144) (xy 332.401726 -29.676111)
			(xy 332.449276 -29.712598) (xy 332.491656 -29.754978) (xy 332.528143 -29.802528) (xy 332.55811 -29.854434)
			(xy 332.581046 -29.909807) (xy 332.596559 -29.9677) (xy 332.604382 -30.027122) (xy 332.604872 -30.05709)
			(xy 332.604872 -30.92069) (xy 332.604843 -30.922468) (xy 355.052884 -30.922468) (xy 355.052884 -30.058868)
			(xy 355.053374 -30.0289) (xy 355.061197 -29.969478) (xy 355.07671 -29.911585) (xy 355.099646 -29.856212)
			(xy 355.129613 -29.804306) (xy 355.1661 -29.756756) (xy 355.20848 -29.714376) (xy 355.25603 -29.677889)
			(xy 355.307936 -29.647922) (xy 355.363309 -29.624986) (xy 355.421202 -29.609473) (xy 355.480624 -29.60165)
			(xy 355.54056 -29.60165) (xy 355.599982 -29.609473) (xy 355.657875 -29.624986) (xy 355.713248 -29.647922)
			(xy 355.765154 -29.677889) (xy 355.812704 -29.714376) (xy 355.855084 -29.756756) (xy 355.891571 -29.804306)
			(xy 355.921538 -29.856212) (xy 355.944474 -29.911585) (xy 355.959987 -29.969478) (xy 355.96781 -30.0289)
			(xy 355.9683 -30.058868) (xy 355.9683 -30.92069) (xy 369.789456 -30.92069) (xy 369.789456 -30.05709)
			(xy 369.789946 -30.027106) (xy 369.797774 -29.96765) (xy 369.813295 -29.909725) (xy 369.836244 -29.854321)
			(xy 369.866228 -29.802387) (xy 369.902734 -29.754811) (xy 369.945139 -29.712406) (xy 369.992715 -29.6759)
			(xy 370.044649 -29.645916) (xy 370.100053 -29.622967) (xy 370.157978 -29.607446) (xy 370.217434 -29.599618)
			(xy 370.277402 -29.599618) (xy 370.336858 -29.607446) (xy 370.394783 -29.622967) (xy 370.450187 -29.645916)
			(xy 370.502121 -29.6759) (xy 370.549697 -29.712406) (xy 370.592102 -29.754811) (xy 370.628608 -29.802387)
			(xy 370.658592 -29.854321) (xy 370.681541 -29.909725) (xy 370.697062 -29.96765) (xy 370.70489 -30.027106)
			(xy 370.70538 -30.05709) (xy 370.70538 -30.92069) (xy 370.705351 -30.922468) (xy 381.052832 -30.922468)
			(xy 381.052832 -30.058868) (xy 381.053322 -30.0289) (xy 381.061145 -29.969478) (xy 381.076658 -29.911585)
			(xy 381.099594 -29.856212) (xy 381.129561 -29.804306) (xy 381.166048 -29.756756) (xy 381.208428 -29.714376)
			(xy 381.255978 -29.677889) (xy 381.307884 -29.647922) (xy 381.363257 -29.624986) (xy 381.42115 -29.609473)
			(xy 381.480572 -29.60165) (xy 381.540508 -29.60165) (xy 381.59993 -29.609473) (xy 381.657823 -29.624986)
			(xy 381.713196 -29.647922) (xy 381.765102 -29.677889) (xy 381.812652 -29.714376) (xy 381.855032 -29.756756)
			(xy 381.891519 -29.804306) (xy 381.921486 -29.856212) (xy 381.944422 -29.911585) (xy 381.959935 -29.969478)
			(xy 381.967758 -30.0289) (xy 381.968248 -30.058868) (xy 381.968248 -30.92069) (xy 395.789404 -30.92069)
			(xy 395.789404 -30.05709) (xy 395.789894 -30.027106) (xy 395.797722 -29.96765) (xy 395.813243 -29.909725)
			(xy 395.836192 -29.854321) (xy 395.866176 -29.802387) (xy 395.902682 -29.754811) (xy 395.945087 -29.712406)
			(xy 395.992663 -29.6759) (xy 396.044597 -29.645916) (xy 396.100001 -29.622967) (xy 396.157926 -29.607446)
			(xy 396.217382 -29.599618) (xy 396.27735 -29.599618) (xy 396.336806 -29.607446) (xy 396.394731 -29.622967)
			(xy 396.450135 -29.645916) (xy 396.502069 -29.6759) (xy 396.549645 -29.712406) (xy 396.59205 -29.754811)
			(xy 396.628556 -29.802387) (xy 396.65854 -29.854321) (xy 396.681489 -29.909725) (xy 396.69701 -29.96765)
			(xy 396.704838 -30.027106) (xy 396.705328 -30.05709) (xy 396.705328 -30.92069) (xy 396.705299 -30.922468)
			(xy 407.05278 -30.922468) (xy 407.05278 -30.058868) (xy 407.05327 -30.0289) (xy 407.061093 -29.969478)
			(xy 407.076606 -29.911585) (xy 407.099542 -29.856212) (xy 407.129509 -29.804306) (xy 407.165996 -29.756756)
			(xy 407.208376 -29.714376) (xy 407.255926 -29.677889) (xy 407.307832 -29.647922) (xy 407.363205 -29.624986)
			(xy 407.421098 -29.609473) (xy 407.48052 -29.60165) (xy 407.540456 -29.60165) (xy 407.599878 -29.609473)
			(xy 407.657771 -29.624986) (xy 407.713144 -29.647922) (xy 407.76505 -29.677889) (xy 407.8126 -29.714376)
			(xy 407.85498 -29.756756) (xy 407.891467 -29.804306) (xy 407.921434 -29.856212) (xy 407.94437 -29.911585)
			(xy 407.959883 -29.969478) (xy 407.967706 -30.0289) (xy 407.968196 -30.058868) (xy 407.968196 -30.92069)
			(xy 421.789352 -30.92069) (xy 421.789352 -30.05709) (xy 421.789842 -30.027106) (xy 421.79767 -29.96765)
			(xy 421.813191 -29.909725) (xy 421.83614 -29.854321) (xy 421.866124 -29.802387) (xy 421.90263 -29.754811)
			(xy 421.945035 -29.712406) (xy 421.992611 -29.6759) (xy 422.044545 -29.645916) (xy 422.099949 -29.622967)
			(xy 422.157874 -29.607446) (xy 422.21733 -29.599618) (xy 422.277298 -29.599618) (xy 422.336754 -29.607446)
			(xy 422.394679 -29.622967) (xy 422.450083 -29.645916) (xy 422.502017 -29.6759) (xy 422.549593 -29.712406)
			(xy 422.591998 -29.754811) (xy 422.628504 -29.802387) (xy 422.658488 -29.854321) (xy 422.681437 -29.909725)
			(xy 422.696958 -29.96765) (xy 422.704786 -30.027106) (xy 422.705276 -30.05709) (xy 422.705276 -30.92069)
			(xy 422.705247 -30.922468) (xy 433.052728 -30.922468) (xy 433.052728 -30.058868) (xy 433.053218 -30.0289)
			(xy 433.061041 -29.969478) (xy 433.076554 -29.911585) (xy 433.09949 -29.856212) (xy 433.129457 -29.804306)
			(xy 433.165944 -29.756756) (xy 433.208324 -29.714376) (xy 433.255874 -29.677889) (xy 433.30778 -29.647922)
			(xy 433.363153 -29.624986) (xy 433.421046 -29.609473) (xy 433.480468 -29.60165) (xy 433.540404 -29.60165)
			(xy 433.599826 -29.609473) (xy 433.657719 -29.624986) (xy 433.713092 -29.647922) (xy 433.764998 -29.677889)
			(xy 433.812548 -29.714376) (xy 433.854928 -29.756756) (xy 433.891415 -29.804306) (xy 433.921382 -29.856212)
			(xy 433.944318 -29.911585) (xy 433.959831 -29.969478) (xy 433.967654 -30.0289) (xy 433.968144 -30.058868)
			(xy 433.968144 -30.92069) (xy 447.7893 -30.92069) (xy 447.7893 -30.05709) (xy 447.78979 -30.027106)
			(xy 447.797618 -29.96765) (xy 447.813139 -29.909725) (xy 447.836088 -29.854321) (xy 447.866072 -29.802387)
			(xy 447.902578 -29.754811) (xy 447.944983 -29.712406) (xy 447.992559 -29.6759) (xy 448.044493 -29.645916)
			(xy 448.099897 -29.622967) (xy 448.157822 -29.607446) (xy 448.217278 -29.599618) (xy 448.277246 -29.599618)
			(xy 448.336702 -29.607446) (xy 448.394627 -29.622967) (xy 448.450031 -29.645916) (xy 448.501965 -29.6759)
			(xy 448.549541 -29.712406) (xy 448.591946 -29.754811) (xy 448.628452 -29.802387) (xy 448.658436 -29.854321)
			(xy 448.681385 -29.909725) (xy 448.696906 -29.96765) (xy 448.704734 -30.027106) (xy 448.705224 -30.05709)
			(xy 448.705224 -30.745738) (xy 457.614517 -30.745738) (xy 457.614517 -30.616598) (xy 457.622467 -30.487703)
			(xy 457.638337 -30.359543) (xy 457.662066 -30.232602) (xy 457.693565 -30.107363) (xy 457.732714 -29.9843)
			(xy 457.779365 -29.863881) (xy 457.83334 -29.746562) (xy 457.894435 -29.632788) (xy 457.962418 -29.522991)
			(xy 458.037032 -29.417588) (xy 458.117993 -29.316978) (xy 458.204993 -29.221543) (xy 458.297704 -29.131644)
			(xy 458.395774 -29.047623) (xy 458.498829 -28.969799) (xy 458.60648 -28.898467) (xy 458.718319 -28.833897)
			(xy 458.83392 -28.776335) (xy 458.952845 -28.725998) (xy 459.074644 -28.683078) (xy 459.198854 -28.647737)
			(xy 459.325003 -28.62011) (xy 459.452615 -28.600301) (xy 459.581204 -28.588385) (xy 459.710282 -28.584409)
			(xy 459.83936 -28.588385) (xy 459.967949 -28.600301) (xy 460.095561 -28.62011) (xy 460.22171 -28.647737)
			(xy 460.34592 -28.683078) (xy 460.467719 -28.725998) (xy 460.586644 -28.776335) (xy 460.702245 -28.833897)
			(xy 460.814084 -28.898467) (xy 460.921735 -28.969799) (xy 461.02479 -29.047623) (xy 461.12286 -29.131644)
			(xy 461.215571 -29.221543) (xy 461.302571 -29.316978) (xy 461.383532 -29.417588) (xy 461.458146 -29.522991)
			(xy 461.526129 -29.632788) (xy 461.587224 -29.746562) (xy 461.641199 -29.863881) (xy 461.68785 -29.9843)
			(xy 461.726999 -30.107363) (xy 461.758498 -30.232602) (xy 461.782227 -30.359543) (xy 461.798097 -30.487703)
			(xy 461.806047 -30.616598) (xy 461.806544 -30.681168) (xy 461.806047 -30.745738) (xy 461.798097 -30.874633)
			(xy 461.782227 -31.002793) (xy 461.758498 -31.129734) (xy 461.726999 -31.254973) (xy 461.68785 -31.378036)
			(xy 461.641199 -31.498455) (xy 461.587224 -31.615774) (xy 461.526129 -31.729548) (xy 461.458146 -31.839345)
			(xy 461.383532 -31.944748) (xy 461.302571 -32.045358) (xy 461.215571 -32.140793) (xy 461.12286 -32.230692)
			(xy 461.02479 -32.314713) (xy 460.921735 -32.392537) (xy 460.814084 -32.463869) (xy 460.702245 -32.528439)
			(xy 460.586644 -32.586001) (xy 460.467719 -32.636338) (xy 460.34592 -32.679258) (xy 460.22171 -32.714599)
			(xy 460.095561 -32.742226) (xy 459.967949 -32.762035) (xy 459.83936 -32.773951) (xy 459.710282 -32.777928)
			(xy 459.581204 -32.773951) (xy 459.452615 -32.762035) (xy 459.325003 -32.742226) (xy 459.198854 -32.714599)
			(xy 459.074644 -32.679258) (xy 458.952845 -32.636338) (xy 458.83392 -32.586001) (xy 458.718319 -32.528439)
			(xy 458.60648 -32.463869) (xy 458.498829 -32.392537) (xy 458.395774 -32.314713) (xy 458.297704 -32.230692)
			(xy 458.204993 -32.140793) (xy 458.117993 -32.045358) (xy 458.037032 -31.944748) (xy 457.962418 -31.839345)
			(xy 457.894435 -31.729548) (xy 457.83334 -31.615774) (xy 457.779365 -31.498455) (xy 457.732714 -31.378036)
			(xy 457.693565 -31.254973) (xy 457.662066 -31.129734) (xy 457.638337 -31.002793) (xy 457.622467 -30.874633)
			(xy 457.614517 -30.745738) (xy 448.705224 -30.745738) (xy 448.705224 -30.92069) (xy 448.704734 -30.950674)
			(xy 448.696906 -31.01013) (xy 448.681385 -31.068055) (xy 448.658436 -31.123459) (xy 448.628452 -31.175393)
			(xy 448.591946 -31.222969) (xy 448.549541 -31.265374) (xy 448.501965 -31.30188) (xy 448.450031 -31.331864)
			(xy 448.394627 -31.354813) (xy 448.336702 -31.370334) (xy 448.277246 -31.378162) (xy 448.217278 -31.378162)
			(xy 448.157822 -31.370334) (xy 448.099897 -31.354813) (xy 448.044493 -31.331864) (xy 447.992559 -31.30188)
			(xy 447.944983 -31.265374) (xy 447.902578 -31.222969) (xy 447.866072 -31.175393) (xy 447.836088 -31.123459)
			(xy 447.813139 -31.068055) (xy 447.797618 -31.01013) (xy 447.78979 -30.950674) (xy 447.7893 -30.92069)
			(xy 433.968144 -30.92069) (xy 433.968144 -30.922468) (xy 433.967654 -30.952436) (xy 433.959831 -31.011858)
			(xy 433.944318 -31.069751) (xy 433.921382 -31.125124) (xy 433.891415 -31.17703) (xy 433.854928 -31.22458)
			(xy 433.812548 -31.26696) (xy 433.764998 -31.303447) (xy 433.713092 -31.333414) (xy 433.657719 -31.35635)
			(xy 433.599826 -31.371863) (xy 433.540404 -31.379686) (xy 433.480468 -31.379686) (xy 433.421046 -31.371863)
			(xy 433.363153 -31.35635) (xy 433.30778 -31.333414) (xy 433.255874 -31.303447) (xy 433.208324 -31.26696)
			(xy 433.165944 -31.22458) (xy 433.129457 -31.17703) (xy 433.09949 -31.125124) (xy 433.076554 -31.069751)
			(xy 433.061041 -31.011858) (xy 433.053218 -30.952436) (xy 433.052728 -30.922468) (xy 422.705247 -30.922468)
			(xy 422.704786 -30.950674) (xy 422.696958 -31.01013) (xy 422.681437 -31.068055) (xy 422.658488 -31.123459)
			(xy 422.628504 -31.175393) (xy 422.591998 -31.222969) (xy 422.549593 -31.265374) (xy 422.502017 -31.30188)
			(xy 422.450083 -31.331864) (xy 422.394679 -31.354813) (xy 422.336754 -31.370334) (xy 422.277298 -31.378162)
			(xy 422.21733 -31.378162) (xy 422.157874 -31.370334) (xy 422.099949 -31.354813) (xy 422.044545 -31.331864)
			(xy 421.992611 -31.30188) (xy 421.945035 -31.265374) (xy 421.90263 -31.222969) (xy 421.866124 -31.175393)
			(xy 421.83614 -31.123459) (xy 421.813191 -31.068055) (xy 421.79767 -31.01013) (xy 421.789842 -30.950674)
			(xy 421.789352 -30.92069) (xy 407.968196 -30.92069) (xy 407.968196 -30.922468) (xy 407.967706 -30.952436)
			(xy 407.959883 -31.011858) (xy 407.94437 -31.069751) (xy 407.921434 -31.125124) (xy 407.891467 -31.17703)
			(xy 407.85498 -31.22458) (xy 407.8126 -31.26696) (xy 407.76505 -31.303447) (xy 407.713144 -31.333414)
			(xy 407.657771 -31.35635) (xy 407.599878 -31.371863) (xy 407.540456 -31.379686) (xy 407.48052 -31.379686)
			(xy 407.421098 -31.371863) (xy 407.363205 -31.35635) (xy 407.307832 -31.333414) (xy 407.255926 -31.303447)
			(xy 407.208376 -31.26696) (xy 407.165996 -31.22458) (xy 407.129509 -31.17703) (xy 407.099542 -31.125124)
			(xy 407.076606 -31.069751) (xy 407.061093 -31.011858) (xy 407.05327 -30.952436) (xy 407.05278 -30.922468)
			(xy 396.705299 -30.922468) (xy 396.704838 -30.950674) (xy 396.69701 -31.01013) (xy 396.681489 -31.068055)
			(xy 396.65854 -31.123459) (xy 396.628556 -31.175393) (xy 396.59205 -31.222969) (xy 396.549645 -31.265374)
			(xy 396.502069 -31.30188) (xy 396.450135 -31.331864) (xy 396.394731 -31.354813) (xy 396.336806 -31.370334)
			(xy 396.27735 -31.378162) (xy 396.217382 -31.378162) (xy 396.157926 -31.370334) (xy 396.100001 -31.354813)
			(xy 396.044597 -31.331864) (xy 395.992663 -31.30188) (xy 395.945087 -31.265374) (xy 395.902682 -31.222969)
			(xy 395.866176 -31.175393) (xy 395.836192 -31.123459) (xy 395.813243 -31.068055) (xy 395.797722 -31.01013)
			(xy 395.789894 -30.950674) (xy 395.789404 -30.92069) (xy 381.968248 -30.92069) (xy 381.968248 -30.922468)
			(xy 381.967758 -30.952436) (xy 381.959935 -31.011858) (xy 381.944422 -31.069751) (xy 381.921486 -31.125124)
			(xy 381.891519 -31.17703) (xy 381.855032 -31.22458) (xy 381.812652 -31.26696) (xy 381.765102 -31.303447)
			(xy 381.713196 -31.333414) (xy 381.657823 -31.35635) (xy 381.59993 -31.371863) (xy 381.540508 -31.379686)
			(xy 381.480572 -31.379686) (xy 381.42115 -31.371863) (xy 381.363257 -31.35635) (xy 381.307884 -31.333414)
			(xy 381.255978 -31.303447) (xy 381.208428 -31.26696) (xy 381.166048 -31.22458) (xy 381.129561 -31.17703)
			(xy 381.099594 -31.125124) (xy 381.076658 -31.069751) (xy 381.061145 -31.011858) (xy 381.053322 -30.952436)
			(xy 381.052832 -30.922468) (xy 370.705351 -30.922468) (xy 370.70489 -30.950674) (xy 370.697062 -31.01013)
			(xy 370.681541 -31.068055) (xy 370.658592 -31.123459) (xy 370.628608 -31.175393) (xy 370.592102 -31.222969)
			(xy 370.549697 -31.265374) (xy 370.502121 -31.30188) (xy 370.450187 -31.331864) (xy 370.394783 -31.354813)
			(xy 370.336858 -31.370334) (xy 370.277402 -31.378162) (xy 370.217434 -31.378162) (xy 370.157978 -31.370334)
			(xy 370.100053 -31.354813) (xy 370.044649 -31.331864) (xy 369.992715 -31.30188) (xy 369.945139 -31.265374)
			(xy 369.902734 -31.222969) (xy 369.866228 -31.175393) (xy 369.836244 -31.123459) (xy 369.813295 -31.068055)
			(xy 369.797774 -31.01013) (xy 369.789946 -30.950674) (xy 369.789456 -30.92069) (xy 355.9683 -30.92069)
			(xy 355.9683 -30.922468) (xy 355.96781 -30.952436) (xy 355.959987 -31.011858) (xy 355.944474 -31.069751)
			(xy 355.921538 -31.125124) (xy 355.891571 -31.17703) (xy 355.855084 -31.22458) (xy 355.812704 -31.26696)
			(xy 355.765154 -31.303447) (xy 355.713248 -31.333414) (xy 355.657875 -31.35635) (xy 355.599982 -31.371863)
			(xy 355.54056 -31.379686) (xy 355.480624 -31.379686) (xy 355.421202 -31.371863) (xy 355.363309 -31.35635)
			(xy 355.307936 -31.333414) (xy 355.25603 -31.303447) (xy 355.20848 -31.26696) (xy 355.1661 -31.22458)
			(xy 355.129613 -31.17703) (xy 355.099646 -31.125124) (xy 355.07671 -31.069751) (xy 355.061197 -31.011858)
			(xy 355.053374 -30.952436) (xy 355.052884 -30.922468) (xy 332.604843 -30.922468) (xy 332.604382 -30.950658)
			(xy 332.596559 -31.01008) (xy 332.581046 -31.067973) (xy 332.55811 -31.123346) (xy 332.528143 -31.175252)
			(xy 332.491656 -31.222802) (xy 332.449276 -31.265182) (xy 332.401726 -31.301669) (xy 332.34982 -31.331636)
			(xy 332.294447 -31.354572) (xy 332.236554 -31.370085) (xy 332.177132 -31.377908) (xy 332.117196 -31.377908)
			(xy 332.057774 -31.370085) (xy 331.999881 -31.354572) (xy 331.944508 -31.331636) (xy 331.892602 -31.301669)
			(xy 331.845052 -31.265182) (xy 331.802672 -31.222802) (xy 331.766185 -31.175252) (xy 331.736218 -31.123346)
			(xy 331.713282 -31.067973) (xy 331.697769 -31.01008) (xy 331.689946 -30.950658) (xy 331.689456 -30.92069)
			(xy 317.8683 -30.92069) (xy 317.8683 -30.922468) (xy 317.86781 -30.952452) (xy 317.859982 -31.011908)
			(xy 317.844461 -31.069833) (xy 317.821512 -31.125237) (xy 317.791528 -31.177171) (xy 317.755022 -31.224747)
			(xy 317.712617 -31.267152) (xy 317.665041 -31.303658) (xy 317.613107 -31.333642) (xy 317.557703 -31.356591)
			(xy 317.499778 -31.372112) (xy 317.440322 -31.37994) (xy 317.380354 -31.37994) (xy 317.320898 -31.372112)
			(xy 317.262973 -31.356591) (xy 317.207569 -31.333642) (xy 317.155635 -31.303658) (xy 317.108059 -31.267152)
			(xy 317.065654 -31.224747) (xy 317.029148 -31.177171) (xy 316.999164 -31.125237) (xy 316.976215 -31.069833)
			(xy 316.960694 -31.011908) (xy 316.952866 -30.952452) (xy 316.952376 -30.922468) (xy 306.604895 -30.922468)
			(xy 306.604434 -30.950658) (xy 306.596611 -31.01008) (xy 306.581098 -31.067973) (xy 306.558162 -31.123346)
			(xy 306.528195 -31.175252) (xy 306.491708 -31.222802) (xy 306.449328 -31.265182) (xy 306.401778 -31.301669)
			(xy 306.349872 -31.331636) (xy 306.294499 -31.354572) (xy 306.236606 -31.370085) (xy 306.177184 -31.377908)
			(xy 306.117248 -31.377908) (xy 306.057826 -31.370085) (xy 305.999933 -31.354572) (xy 305.94456 -31.331636)
			(xy 305.892654 -31.301669) (xy 305.845104 -31.265182) (xy 305.802724 -31.222802) (xy 305.766237 -31.175252)
			(xy 305.73627 -31.123346) (xy 305.713334 -31.067973) (xy 305.697821 -31.01008) (xy 305.689998 -30.950658)
			(xy 305.689508 -30.92069) (xy 291.868352 -30.92069) (xy 291.868352 -30.922468) (xy 291.867862 -30.952452)
			(xy 291.860034 -31.011908) (xy 291.844513 -31.069833) (xy 291.821564 -31.125237) (xy 291.79158 -31.177171)
			(xy 291.755074 -31.224747) (xy 291.712669 -31.267152) (xy 291.665093 -31.303658) (xy 291.613159 -31.333642)
			(xy 291.557755 -31.356591) (xy 291.49983 -31.372112) (xy 291.440374 -31.37994) (xy 291.380406 -31.37994)
			(xy 291.32095 -31.372112) (xy 291.263025 -31.356591) (xy 291.207621 -31.333642) (xy 291.155687 -31.303658)
			(xy 291.108111 -31.267152) (xy 291.065706 -31.224747) (xy 291.0292 -31.177171) (xy 290.999216 -31.125237)
			(xy 290.976267 -31.069833) (xy 290.960746 -31.011908) (xy 290.952918 -30.952452) (xy 290.952428 -30.922468)
			(xy 280.604947 -30.922468) (xy 280.604486 -30.950658) (xy 280.596663 -31.01008) (xy 280.58115 -31.067973)
			(xy 280.558214 -31.123346) (xy 280.528247 -31.175252) (xy 280.49176 -31.222802) (xy 280.44938 -31.265182)
			(xy 280.40183 -31.301669) (xy 280.349924 -31.331636) (xy 280.294551 -31.354572) (xy 280.236658 -31.370085)
			(xy 280.177236 -31.377908) (xy 280.1173 -31.377908) (xy 280.057878 -31.370085) (xy 279.999985 -31.354572)
			(xy 279.944612 -31.331636) (xy 279.892706 -31.301669) (xy 279.845156 -31.265182) (xy 279.802776 -31.222802)
			(xy 279.766289 -31.175252) (xy 279.736322 -31.123346) (xy 279.713386 -31.067973) (xy 279.697873 -31.01008)
			(xy 279.69005 -30.950658) (xy 279.68956 -30.92069) (xy 265.868404 -30.92069) (xy 265.868404 -30.922468)
			(xy 265.867914 -30.952452) (xy 265.860086 -31.011908) (xy 265.844565 -31.069833) (xy 265.821616 -31.125237)
			(xy 265.791632 -31.177171) (xy 265.755126 -31.224747) (xy 265.712721 -31.267152) (xy 265.665145 -31.303658)
			(xy 265.613211 -31.333642) (xy 265.557807 -31.356591) (xy 265.499882 -31.372112) (xy 265.440426 -31.37994)
			(xy 265.380458 -31.37994) (xy 265.321002 -31.372112) (xy 265.263077 -31.356591) (xy 265.207673 -31.333642)
			(xy 265.155739 -31.303658) (xy 265.108163 -31.267152) (xy 265.065758 -31.224747) (xy 265.029252 -31.177171)
			(xy 264.999268 -31.125237) (xy 264.976319 -31.069833) (xy 264.960798 -31.011908) (xy 264.95297 -30.952452)
			(xy 264.95248 -30.922468) (xy 254.604999 -30.922468) (xy 254.604538 -30.950658) (xy 254.596715 -31.01008)
			(xy 254.581202 -31.067973) (xy 254.558266 -31.123346) (xy 254.528299 -31.175252) (xy 254.491812 -31.222802)
			(xy 254.449432 -31.265182) (xy 254.401882 -31.301669) (xy 254.349976 -31.331636) (xy 254.294603 -31.354572)
			(xy 254.23671 -31.370085) (xy 254.177288 -31.377908) (xy 254.117352 -31.377908) (xy 254.05793 -31.370085)
			(xy 254.000037 -31.354572) (xy 253.944664 -31.331636) (xy 253.892758 -31.301669) (xy 253.845208 -31.265182)
			(xy 253.802828 -31.222802) (xy 253.766341 -31.175252) (xy 253.736374 -31.123346) (xy 253.713438 -31.067973)
			(xy 253.697925 -31.01008) (xy 253.690102 -30.950658) (xy 253.689612 -30.92069) (xy 239.868456 -30.92069)
			(xy 239.868456 -30.922468) (xy 239.867966 -30.952452) (xy 239.860138 -31.011908) (xy 239.844617 -31.069833)
			(xy 239.821668 -31.125237) (xy 239.791684 -31.177171) (xy 239.755178 -31.224747) (xy 239.712773 -31.267152)
			(xy 239.665197 -31.303658) (xy 239.613263 -31.333642) (xy 239.557859 -31.356591) (xy 239.499934 -31.372112)
			(xy 239.440478 -31.37994) (xy 239.38051 -31.37994) (xy 239.321054 -31.372112) (xy 239.263129 -31.356591)
			(xy 239.207725 -31.333642) (xy 239.155791 -31.303658) (xy 239.108215 -31.267152) (xy 239.06581 -31.224747)
			(xy 239.029304 -31.177171) (xy 238.99932 -31.125237) (xy 238.976371 -31.069833) (xy 238.96085 -31.011908)
			(xy 238.953022 -30.952452) (xy 238.952532 -30.922468) (xy 216.504999 -30.922468) (xy 216.504538 -30.950658)
			(xy 216.496715 -31.01008) (xy 216.481202 -31.067973) (xy 216.458266 -31.123346) (xy 216.428299 -31.175252)
			(xy 216.391812 -31.222802) (xy 216.349432 -31.265182) (xy 216.301882 -31.301669) (xy 216.249976 -31.331636)
			(xy 216.194603 -31.354572) (xy 216.13671 -31.370085) (xy 216.077288 -31.377908) (xy 216.017352 -31.377908)
			(xy 215.95793 -31.370085) (xy 215.900037 -31.354572) (xy 215.844664 -31.331636) (xy 215.792758 -31.301669)
			(xy 215.745208 -31.265182) (xy 215.702828 -31.222802) (xy 215.666341 -31.175252) (xy 215.636374 -31.123346)
			(xy 215.613438 -31.067973) (xy 215.597925 -31.01008) (xy 215.590102 -30.950658) (xy 215.589612 -30.92069)
			(xy 201.768456 -30.92069) (xy 201.768456 -30.922468) (xy 201.767966 -30.952452) (xy 201.760138 -31.011908)
			(xy 201.744617 -31.069833) (xy 201.721668 -31.125237) (xy 201.691684 -31.177171) (xy 201.655178 -31.224747)
			(xy 201.612773 -31.267152) (xy 201.565197 -31.303658) (xy 201.513263 -31.333642) (xy 201.457859 -31.356591)
			(xy 201.399934 -31.372112) (xy 201.340478 -31.37994) (xy 201.28051 -31.37994) (xy 201.221054 -31.372112)
			(xy 201.163129 -31.356591) (xy 201.107725 -31.333642) (xy 201.055791 -31.303658) (xy 201.008215 -31.267152)
			(xy 200.96581 -31.224747) (xy 200.929304 -31.177171) (xy 200.89932 -31.125237) (xy 200.876371 -31.069833)
			(xy 200.86085 -31.011908) (xy 200.853022 -30.952452) (xy 200.852532 -30.922468) (xy 190.505051 -30.922468)
			(xy 190.50459 -30.950658) (xy 190.496767 -31.01008) (xy 190.481254 -31.067973) (xy 190.458318 -31.123346)
			(xy 190.428351 -31.175252) (xy 190.391864 -31.222802) (xy 190.349484 -31.265182) (xy 190.301934 -31.301669)
			(xy 190.250028 -31.331636) (xy 190.194655 -31.354572) (xy 190.136762 -31.370085) (xy 190.07734 -31.377908)
			(xy 190.017404 -31.377908) (xy 189.957982 -31.370085) (xy 189.900089 -31.354572) (xy 189.844716 -31.331636)
			(xy 189.79281 -31.301669) (xy 189.74526 -31.265182) (xy 189.70288 -31.222802) (xy 189.666393 -31.175252)
			(xy 189.636426 -31.123346) (xy 189.61349 -31.067973) (xy 189.597977 -31.01008) (xy 189.590154 -30.950658)
			(xy 189.589664 -30.92069) (xy 175.768508 -30.92069) (xy 175.768508 -30.922468) (xy 175.768018 -30.952452)
			(xy 175.76019 -31.011908) (xy 175.744669 -31.069833) (xy 175.72172 -31.125237) (xy 175.691736 -31.177171)
			(xy 175.65523 -31.224747) (xy 175.612825 -31.267152) (xy 175.565249 -31.303658) (xy 175.513315 -31.333642)
			(xy 175.457911 -31.356591) (xy 175.399986 -31.372112) (xy 175.34053 -31.37994) (xy 175.280562 -31.37994)
			(xy 175.221106 -31.372112) (xy 175.163181 -31.356591) (xy 175.107777 -31.333642) (xy 175.055843 -31.303658)
			(xy 175.008267 -31.267152) (xy 174.965862 -31.224747) (xy 174.929356 -31.177171) (xy 174.899372 -31.125237)
			(xy 174.876423 -31.069833) (xy 174.860902 -31.011908) (xy 174.853074 -30.952452) (xy 174.852584 -30.922468)
			(xy 164.505103 -30.922468) (xy 164.504642 -30.950658) (xy 164.496819 -31.01008) (xy 164.481306 -31.067973)
			(xy 164.45837 -31.123346) (xy 164.428403 -31.175252) (xy 164.391916 -31.222802) (xy 164.349536 -31.265182)
			(xy 164.301986 -31.301669) (xy 164.25008 -31.331636) (xy 164.194707 -31.354572) (xy 164.136814 -31.370085)
			(xy 164.077392 -31.377908) (xy 164.017456 -31.377908) (xy 163.958034 -31.370085) (xy 163.900141 -31.354572)
			(xy 163.844768 -31.331636) (xy 163.792862 -31.301669) (xy 163.745312 -31.265182) (xy 163.702932 -31.222802)
			(xy 163.666445 -31.175252) (xy 163.636478 -31.123346) (xy 163.613542 -31.067973) (xy 163.598029 -31.01008)
			(xy 163.590206 -30.950658) (xy 163.589716 -30.92069) (xy 149.76856 -30.92069) (xy 149.76856 -30.922468)
			(xy 149.76807 -30.952452) (xy 149.760242 -31.011908) (xy 149.744721 -31.069833) (xy 149.721772 -31.125237)
			(xy 149.691788 -31.177171) (xy 149.655282 -31.224747) (xy 149.612877 -31.267152) (xy 149.565301 -31.303658)
			(xy 149.513367 -31.333642) (xy 149.457963 -31.356591) (xy 149.400038 -31.372112) (xy 149.340582 -31.37994)
			(xy 149.280614 -31.37994) (xy 149.221158 -31.372112) (xy 149.163233 -31.356591) (xy 149.107829 -31.333642)
			(xy 149.055895 -31.303658) (xy 149.008319 -31.267152) (xy 148.965914 -31.224747) (xy 148.929408 -31.177171)
			(xy 148.899424 -31.125237) (xy 148.876475 -31.069833) (xy 148.860954 -31.011908) (xy 148.853126 -30.952452)
			(xy 148.852636 -30.922468) (xy 138.505155 -30.922468) (xy 138.504694 -30.950658) (xy 138.496871 -31.01008)
			(xy 138.481358 -31.067973) (xy 138.458422 -31.123346) (xy 138.428455 -31.175252) (xy 138.391968 -31.222802)
			(xy 138.349588 -31.265182) (xy 138.302038 -31.301669) (xy 138.250132 -31.331636) (xy 138.194759 -31.354572)
			(xy 138.136866 -31.370085) (xy 138.077444 -31.377908) (xy 138.017508 -31.377908) (xy 137.958086 -31.370085)
			(xy 137.900193 -31.354572) (xy 137.84482 -31.331636) (xy 137.792914 -31.301669) (xy 137.745364 -31.265182)
			(xy 137.702984 -31.222802) (xy 137.666497 -31.175252) (xy 137.63653 -31.123346) (xy 137.613594 -31.067973)
			(xy 137.598081 -31.01008) (xy 137.590258 -30.950658) (xy 137.589768 -30.92069) (xy 123.768612 -30.92069)
			(xy 123.768612 -30.922468) (xy 123.768122 -30.952452) (xy 123.760294 -31.011908) (xy 123.744773 -31.069833)
			(xy 123.721824 -31.125237) (xy 123.69184 -31.177171) (xy 123.655334 -31.224747) (xy 123.612929 -31.267152)
			(xy 123.565353 -31.303658) (xy 123.513419 -31.333642) (xy 123.458015 -31.356591) (xy 123.40009 -31.372112)
			(xy 123.340634 -31.37994) (xy 123.280666 -31.37994) (xy 123.22121 -31.372112) (xy 123.163285 -31.356591)
			(xy 123.107881 -31.333642) (xy 123.055947 -31.303658) (xy 123.008371 -31.267152) (xy 122.965966 -31.224747)
			(xy 122.92946 -31.177171) (xy 122.899476 -31.125237) (xy 122.876527 -31.069833) (xy 122.861006 -31.011908)
			(xy 122.853178 -30.952452) (xy 122.852688 -30.922468) (xy 100.405155 -30.922468) (xy 100.404694 -30.950674)
			(xy 100.396866 -31.01013) (xy 100.381345 -31.068055) (xy 100.358396 -31.123459) (xy 100.328412 -31.175393)
			(xy 100.291906 -31.222969) (xy 100.249501 -31.265374) (xy 100.201925 -31.30188) (xy 100.149991 -31.331864)
			(xy 100.094587 -31.354813) (xy 100.036662 -31.370334) (xy 99.977206 -31.378162) (xy 99.917238 -31.378162)
			(xy 99.857782 -31.370334) (xy 99.799857 -31.354813) (xy 99.744453 -31.331864) (xy 99.692519 -31.30188)
			(xy 99.644943 -31.265374) (xy 99.602538 -31.222969) (xy 99.566032 -31.175393) (xy 99.536048 -31.123459)
			(xy 99.513099 -31.068055) (xy 99.497578 -31.01013) (xy 99.48975 -30.950674) (xy 99.48926 -30.92069)
			(xy 85.668104 -30.92069) (xy 85.668104 -30.922468) (xy 85.667614 -30.952436) (xy 85.659791 -31.011858)
			(xy 85.644278 -31.069751) (xy 85.621342 -31.125124) (xy 85.591375 -31.17703) (xy 85.554888 -31.22458)
			(xy 85.512508 -31.26696) (xy 85.464958 -31.303447) (xy 85.413052 -31.333414) (xy 85.357679 -31.35635)
			(xy 85.299786 -31.371863) (xy 85.240364 -31.379686) (xy 85.180428 -31.379686) (xy 85.121006 -31.371863)
			(xy 85.063113 -31.35635) (xy 85.00774 -31.333414) (xy 84.955834 -31.303447) (xy 84.908284 -31.26696)
			(xy 84.865904 -31.22458) (xy 84.829417 -31.17703) (xy 84.79945 -31.125124) (xy 84.776514 -31.069751)
			(xy 84.761001 -31.011858) (xy 84.753178 -30.952436) (xy 84.752688 -30.922468) (xy 74.405207 -30.922468)
			(xy 74.404746 -30.950674) (xy 74.396918 -31.01013) (xy 74.381397 -31.068055) (xy 74.358448 -31.123459)
			(xy 74.328464 -31.175393) (xy 74.291958 -31.222969) (xy 74.249553 -31.265374) (xy 74.201977 -31.30188)
			(xy 74.150043 -31.331864) (xy 74.094639 -31.354813) (xy 74.036714 -31.370334) (xy 73.977258 -31.378162)
			(xy 73.91729 -31.378162) (xy 73.857834 -31.370334) (xy 73.799909 -31.354813) (xy 73.744505 -31.331864)
			(xy 73.692571 -31.30188) (xy 73.644995 -31.265374) (xy 73.60259 -31.222969) (xy 73.566084 -31.175393)
			(xy 73.5361 -31.123459) (xy 73.513151 -31.068055) (xy 73.49763 -31.01013) (xy 73.489802 -30.950674)
			(xy 73.489312 -30.92069) (xy 59.668156 -30.92069) (xy 59.668156 -30.922468) (xy 59.667666 -30.952436)
			(xy 59.659843 -31.011858) (xy 59.64433 -31.069751) (xy 59.621394 -31.125124) (xy 59.591427 -31.17703)
			(xy 59.55494 -31.22458) (xy 59.51256 -31.26696) (xy 59.46501 -31.303447) (xy 59.413104 -31.333414)
			(xy 59.357731 -31.35635) (xy 59.299838 -31.371863) (xy 59.240416 -31.379686) (xy 59.18048 -31.379686)
			(xy 59.121058 -31.371863) (xy 59.063165 -31.35635) (xy 59.007792 -31.333414) (xy 58.955886 -31.303447)
			(xy 58.908336 -31.26696) (xy 58.865956 -31.22458) (xy 58.829469 -31.17703) (xy 58.799502 -31.125124)
			(xy 58.776566 -31.069751) (xy 58.761053 -31.011858) (xy 58.75323 -30.952436) (xy 58.75274 -30.922468)
			(xy 48.405259 -30.922468) (xy 48.404798 -30.950674) (xy 48.39697 -31.01013) (xy 48.381449 -31.068055)
			(xy 48.3585 -31.123459) (xy 48.328516 -31.175393) (xy 48.29201 -31.222969) (xy 48.249605 -31.265374)
			(xy 48.202029 -31.30188) (xy 48.150095 -31.331864) (xy 48.094691 -31.354813) (xy 48.036766 -31.370334)
			(xy 47.97731 -31.378162) (xy 47.917342 -31.378162) (xy 47.857886 -31.370334) (xy 47.799961 -31.354813)
			(xy 47.744557 -31.331864) (xy 47.692623 -31.30188) (xy 47.645047 -31.265374) (xy 47.602642 -31.222969)
			(xy 47.566136 -31.175393) (xy 47.536152 -31.123459) (xy 47.513203 -31.068055) (xy 47.497682 -31.01013)
			(xy 47.489854 -30.950674) (xy 47.489364 -30.92069) (xy 33.668208 -30.92069) (xy 33.668208 -30.922468)
			(xy 33.667718 -30.952436) (xy 33.659895 -31.011858) (xy 33.644382 -31.069751) (xy 33.621446 -31.125124)
			(xy 33.591479 -31.17703) (xy 33.554992 -31.22458) (xy 33.512612 -31.26696) (xy 33.465062 -31.303447)
			(xy 33.413156 -31.333414) (xy 33.357783 -31.35635) (xy 33.29989 -31.371863) (xy 33.240468 -31.379686)
			(xy 33.180532 -31.379686) (xy 33.12111 -31.371863) (xy 33.063217 -31.35635) (xy 33.007844 -31.333414)
			(xy 32.955938 -31.303447) (xy 32.908388 -31.26696) (xy 32.866008 -31.22458) (xy 32.829521 -31.17703)
			(xy 32.799554 -31.125124) (xy 32.776618 -31.069751) (xy 32.761105 -31.011858) (xy 32.753282 -30.952436)
			(xy 32.752792 -30.922468) (xy 22.405311 -30.922468) (xy 22.40485 -30.950674) (xy 22.397022 -31.01013)
			(xy 22.381501 -31.068055) (xy 22.358552 -31.123459) (xy 22.328568 -31.175393) (xy 22.292062 -31.222969)
			(xy 22.249657 -31.265374) (xy 22.202081 -31.30188) (xy 22.150147 -31.331864) (xy 22.094743 -31.354813)
			(xy 22.036818 -31.370334) (xy 21.977362 -31.378162) (xy 21.917394 -31.378162) (xy 21.857938 -31.370334)
			(xy 21.800013 -31.354813) (xy 21.744609 -31.331864) (xy 21.692675 -31.30188) (xy 21.645099 -31.265374)
			(xy 21.602694 -31.222969) (xy 21.566188 -31.175393) (xy 21.536204 -31.123459) (xy 21.513255 -31.068055)
			(xy 21.497734 -31.01013) (xy 21.489906 -30.950674) (xy 21.489416 -30.92069) (xy 7.66826 -30.92069)
			(xy 7.66826 -30.922468) (xy 7.66777 -30.952436) (xy 7.659947 -31.011858) (xy 7.644434 -31.069751)
			(xy 7.621498 -31.125124) (xy 7.591531 -31.17703) (xy 7.555044 -31.22458) (xy 7.512664 -31.26696)
			(xy 7.465114 -31.303447) (xy 7.413208 -31.333414) (xy 7.357835 -31.35635) (xy 7.299942 -31.371863)
			(xy 7.24052 -31.379686) (xy 7.180584 -31.379686) (xy 7.121162 -31.371863) (xy 7.063269 -31.35635)
			(xy 7.007896 -31.333414) (xy 6.95599 -31.303447) (xy 6.90844 -31.26696) (xy 6.86606 -31.22458) (xy 6.829573 -31.17703)
			(xy 6.799606 -31.125124) (xy 6.77667 -31.069751) (xy 6.761157 -31.011858) (xy 6.753334 -30.952436)
			(xy 6.752844 -30.922468) (xy 0.508 -30.922468) (xy 0.508 -32.722312) (xy 8.607044 -32.722312) (xy 8.607044 -31.858712)
			(xy 8.607534 -31.828744) (xy 8.615357 -31.769322) (xy 8.63087 -31.711429) (xy 8.653806 -31.656056)
			(xy 8.683773 -31.60415) (xy 8.72026 -31.5566) (xy 8.76264 -31.51422) (xy 8.81019 -31.477733) (xy 8.862096 -31.447766)
			(xy 8.917469 -31.42483) (xy 8.975362 -31.409317) (xy 9.034784 -31.401494) (xy 9.09472 -31.401494)
			(xy 9.154142 -31.409317) (xy 9.212035 -31.42483) (xy 9.267408 -31.447766) (xy 9.319314 -31.477733)
			(xy 9.366864 -31.51422) (xy 9.409244 -31.5566) (xy 9.445731 -31.60415) (xy 9.475698 -31.656056) (xy 9.498634 -31.711429)
			(xy 9.514147 -31.769322) (xy 9.52197 -31.828744) (xy 9.52246 -31.858712) (xy 9.52246 -32.714184)
			(xy 18.847308 -32.714184) (xy 18.847308 -31.850584) (xy 18.847798 -31.8206) (xy 18.855626 -31.761144)
			(xy 18.871147 -31.703219) (xy 18.894096 -31.647815) (xy 18.92408 -31.595881) (xy 18.960586 -31.548305)
			(xy 19.002991 -31.5059) (xy 19.050567 -31.469394) (xy 19.102501 -31.43941) (xy 19.157905 -31.416461)
			(xy 19.21583 -31.40094) (xy 19.275286 -31.393112) (xy 19.335254 -31.393112) (xy 19.39471 -31.40094)
			(xy 19.452635 -31.416461) (xy 19.508039 -31.43941) (xy 19.559973 -31.469394) (xy 19.607549 -31.5059)
			(xy 19.649954 -31.548305) (xy 19.68646 -31.595881) (xy 19.716444 -31.647815) (xy 19.739393 -31.703219)
			(xy 19.754914 -31.761144) (xy 19.762742 -31.8206) (xy 19.763232 -31.850584) (xy 19.763232 -32.714184)
			(xy 19.763099 -32.722312) (xy 34.606992 -32.722312) (xy 34.606992 -31.858712) (xy 34.607482 -31.828744)
			(xy 34.615305 -31.769322) (xy 34.630818 -31.711429) (xy 34.653754 -31.656056) (xy 34.683721 -31.60415)
			(xy 34.720208 -31.5566) (xy 34.762588 -31.51422) (xy 34.810138 -31.477733) (xy 34.862044 -31.447766)
			(xy 34.917417 -31.42483) (xy 34.97531 -31.409317) (xy 35.034732 -31.401494) (xy 35.094668 -31.401494)
			(xy 35.15409 -31.409317) (xy 35.211983 -31.42483) (xy 35.267356 -31.447766) (xy 35.319262 -31.477733)
			(xy 35.366812 -31.51422) (xy 35.409192 -31.5566) (xy 35.445679 -31.60415) (xy 35.475646 -31.656056)
			(xy 35.498582 -31.711429) (xy 35.514095 -31.769322) (xy 35.521918 -31.828744) (xy 35.522408 -31.858712)
			(xy 35.522408 -32.714184) (xy 44.847256 -32.714184) (xy 44.847256 -31.850584) (xy 44.847746 -31.8206)
			(xy 44.855574 -31.761144) (xy 44.871095 -31.703219) (xy 44.894044 -31.647815) (xy 44.924028 -31.595881)
			(xy 44.960534 -31.548305) (xy 45.002939 -31.5059) (xy 45.050515 -31.469394) (xy 45.102449 -31.43941)
			(xy 45.157853 -31.416461) (xy 45.215778 -31.40094) (xy 45.275234 -31.393112) (xy 45.335202 -31.393112)
			(xy 45.394658 -31.40094) (xy 45.452583 -31.416461) (xy 45.507987 -31.43941) (xy 45.559921 -31.469394)
			(xy 45.607497 -31.5059) (xy 45.649902 -31.548305) (xy 45.686408 -31.595881) (xy 45.716392 -31.647815)
			(xy 45.739341 -31.703219) (xy 45.754862 -31.761144) (xy 45.76269 -31.8206) (xy 45.76318 -31.850584)
			(xy 45.76318 -32.714184) (xy 45.763047 -32.722312) (xy 60.60694 -32.722312) (xy 60.60694 -31.858712)
			(xy 60.60743 -31.828744) (xy 60.615253 -31.769322) (xy 60.630766 -31.711429) (xy 60.653702 -31.656056)
			(xy 60.683669 -31.60415) (xy 60.720156 -31.5566) (xy 60.762536 -31.51422) (xy 60.810086 -31.477733)
			(xy 60.861992 -31.447766) (xy 60.917365 -31.42483) (xy 60.975258 -31.409317) (xy 61.03468 -31.401494)
			(xy 61.094616 -31.401494) (xy 61.154038 -31.409317) (xy 61.211931 -31.42483) (xy 61.267304 -31.447766)
			(xy 61.31921 -31.477733) (xy 61.36676 -31.51422) (xy 61.40914 -31.5566) (xy 61.445627 -31.60415)
			(xy 61.475594 -31.656056) (xy 61.49853 -31.711429) (xy 61.514043 -31.769322) (xy 61.521866 -31.828744)
			(xy 61.522356 -31.858712) (xy 61.522356 -32.714184) (xy 70.847204 -32.714184) (xy 70.847204 -31.850584)
			(xy 70.847694 -31.8206) (xy 70.855522 -31.761144) (xy 70.871043 -31.703219) (xy 70.893992 -31.647815)
			(xy 70.923976 -31.595881) (xy 70.960482 -31.548305) (xy 71.002887 -31.5059) (xy 71.050463 -31.469394)
			(xy 71.102397 -31.43941) (xy 71.157801 -31.416461) (xy 71.215726 -31.40094) (xy 71.275182 -31.393112)
			(xy 71.33515 -31.393112) (xy 71.394606 -31.40094) (xy 71.452531 -31.416461) (xy 71.507935 -31.43941)
			(xy 71.559869 -31.469394) (xy 71.607445 -31.5059) (xy 71.64985 -31.548305) (xy 71.686356 -31.595881)
			(xy 71.71634 -31.647815) (xy 71.739289 -31.703219) (xy 71.75481 -31.761144) (xy 71.762638 -31.8206)
			(xy 71.763128 -31.850584) (xy 71.763128 -32.714184) (xy 71.762995 -32.722312) (xy 86.606888 -32.722312)
			(xy 86.606888 -31.858712) (xy 86.607378 -31.828744) (xy 86.615201 -31.769322) (xy 86.630714 -31.711429)
			(xy 86.65365 -31.656056) (xy 86.683617 -31.60415) (xy 86.720104 -31.5566) (xy 86.762484 -31.51422)
			(xy 86.810034 -31.477733) (xy 86.86194 -31.447766) (xy 86.917313 -31.42483) (xy 86.975206 -31.409317)
			(xy 87.034628 -31.401494) (xy 87.094564 -31.401494) (xy 87.153986 -31.409317) (xy 87.211879 -31.42483)
			(xy 87.267252 -31.447766) (xy 87.319158 -31.477733) (xy 87.366708 -31.51422) (xy 87.409088 -31.5566)
			(xy 87.445575 -31.60415) (xy 87.475542 -31.656056) (xy 87.498478 -31.711429) (xy 87.513991 -31.769322)
			(xy 87.521814 -31.828744) (xy 87.522304 -31.858712) (xy 87.522304 -32.714184) (xy 96.847152 -32.714184)
			(xy 96.847152 -31.850584) (xy 96.847642 -31.8206) (xy 96.85547 -31.761144) (xy 96.870991 -31.703219)
			(xy 96.89394 -31.647815) (xy 96.923924 -31.595881) (xy 96.96043 -31.548305) (xy 97.002835 -31.5059)
			(xy 97.050411 -31.469394) (xy 97.102345 -31.43941) (xy 97.157749 -31.416461) (xy 97.215674 -31.40094)
			(xy 97.27513 -31.393112) (xy 97.335098 -31.393112) (xy 97.394554 -31.40094) (xy 97.452479 -31.416461)
			(xy 97.507883 -31.43941) (xy 97.559817 -31.469394) (xy 97.607393 -31.5059) (xy 97.649798 -31.548305)
			(xy 97.686304 -31.595881) (xy 97.716288 -31.647815) (xy 97.739237 -31.703219) (xy 97.754758 -31.761144)
			(xy 97.762586 -31.8206) (xy 97.763076 -31.850584) (xy 97.763076 -32.714184) (xy 97.762943 -32.722312)
			(xy 124.706888 -32.722312) (xy 124.706888 -31.858712) (xy 124.707378 -31.828728) (xy 124.715206 -31.769272)
			(xy 124.730727 -31.711347) (xy 124.753676 -31.655943) (xy 124.78366 -31.604009) (xy 124.820166 -31.556433)
			(xy 124.862571 -31.514028) (xy 124.910147 -31.477522) (xy 124.962081 -31.447538) (xy 125.017485 -31.424589)
			(xy 125.07541 -31.409068) (xy 125.134866 -31.40124) (xy 125.194834 -31.40124) (xy 125.25429 -31.409068)
			(xy 125.312215 -31.424589) (xy 125.367619 -31.447538) (xy 125.419553 -31.477522) (xy 125.467129 -31.514028)
			(xy 125.509534 -31.556433) (xy 125.54604 -31.604009) (xy 125.576024 -31.655943) (xy 125.598973 -31.711347)
			(xy 125.614494 -31.769272) (xy 125.622322 -31.828728) (xy 125.622812 -31.858712) (xy 125.622812 -32.714184)
			(xy 134.94766 -32.714184) (xy 134.94766 -31.850584) (xy 134.94815 -31.820616) (xy 134.955973 -31.761194)
			(xy 134.971486 -31.703301) (xy 134.994422 -31.647928) (xy 135.024389 -31.596022) (xy 135.060876 -31.548472)
			(xy 135.103256 -31.506092) (xy 135.150806 -31.469605) (xy 135.202712 -31.439638) (xy 135.258085 -31.416702)
			(xy 135.315978 -31.401189) (xy 135.3754 -31.393366) (xy 135.435336 -31.393366) (xy 135.494758 -31.401189)
			(xy 135.552651 -31.416702) (xy 135.608024 -31.439638) (xy 135.65993 -31.469605) (xy 135.70748 -31.506092)
			(xy 135.74986 -31.548472) (xy 135.786347 -31.596022) (xy 135.816314 -31.647928) (xy 135.83925 -31.703301)
			(xy 135.854763 -31.761194) (xy 135.862586 -31.820616) (xy 135.863076 -31.850584) (xy 135.863076 -32.714184)
			(xy 135.862943 -32.722312) (xy 150.706836 -32.722312) (xy 150.706836 -31.858712) (xy 150.707326 -31.828728)
			(xy 150.715154 -31.769272) (xy 150.730675 -31.711347) (xy 150.753624 -31.655943) (xy 150.783608 -31.604009)
			(xy 150.820114 -31.556433) (xy 150.862519 -31.514028) (xy 150.910095 -31.477522) (xy 150.962029 -31.447538)
			(xy 151.017433 -31.424589) (xy 151.075358 -31.409068) (xy 151.134814 -31.40124) (xy 151.194782 -31.40124)
			(xy 151.254238 -31.409068) (xy 151.312163 -31.424589) (xy 151.367567 -31.447538) (xy 151.419501 -31.477522)
			(xy 151.467077 -31.514028) (xy 151.509482 -31.556433) (xy 151.545988 -31.604009) (xy 151.575972 -31.655943)
			(xy 151.598921 -31.711347) (xy 151.614442 -31.769272) (xy 151.62227 -31.828728) (xy 151.62276 -31.858712)
			(xy 151.62276 -32.714184) (xy 160.947608 -32.714184) (xy 160.947608 -31.850584) (xy 160.948098 -31.820616)
			(xy 160.955921 -31.761194) (xy 160.971434 -31.703301) (xy 160.99437 -31.647928) (xy 161.024337 -31.596022)
			(xy 161.060824 -31.548472) (xy 161.103204 -31.506092) (xy 161.150754 -31.469605) (xy 161.20266 -31.439638)
			(xy 161.258033 -31.416702) (xy 161.315926 -31.401189) (xy 161.375348 -31.393366) (xy 161.435284 -31.393366)
			(xy 161.494706 -31.401189) (xy 161.552599 -31.416702) (xy 161.607972 -31.439638) (xy 161.659878 -31.469605)
			(xy 161.707428 -31.506092) (xy 161.749808 -31.548472) (xy 161.786295 -31.596022) (xy 161.816262 -31.647928)
			(xy 161.839198 -31.703301) (xy 161.854711 -31.761194) (xy 161.862534 -31.820616) (xy 161.863024 -31.850584)
			(xy 161.863024 -32.714184) (xy 161.862891 -32.722312) (xy 176.706784 -32.722312) (xy 176.706784 -31.858712)
			(xy 176.707274 -31.828728) (xy 176.715102 -31.769272) (xy 176.730623 -31.711347) (xy 176.753572 -31.655943)
			(xy 176.783556 -31.604009) (xy 176.820062 -31.556433) (xy 176.862467 -31.514028) (xy 176.910043 -31.477522)
			(xy 176.961977 -31.447538) (xy 177.017381 -31.424589) (xy 177.075306 -31.409068) (xy 177.134762 -31.40124)
			(xy 177.19473 -31.40124) (xy 177.254186 -31.409068) (xy 177.312111 -31.424589) (xy 177.367515 -31.447538)
			(xy 177.419449 -31.477522) (xy 177.467025 -31.514028) (xy 177.50943 -31.556433) (xy 177.545936 -31.604009)
			(xy 177.57592 -31.655943) (xy 177.598869 -31.711347) (xy 177.61439 -31.769272) (xy 177.622218 -31.828728)
			(xy 177.622708 -31.858712) (xy 177.622708 -32.714184) (xy 186.947556 -32.714184) (xy 186.947556 -31.850584)
			(xy 186.948046 -31.820616) (xy 186.955869 -31.761194) (xy 186.971382 -31.703301) (xy 186.994318 -31.647928)
			(xy 187.024285 -31.596022) (xy 187.060772 -31.548472) (xy 187.103152 -31.506092) (xy 187.150702 -31.469605)
			(xy 187.202608 -31.439638) (xy 187.257981 -31.416702) (xy 187.315874 -31.401189) (xy 187.375296 -31.393366)
			(xy 187.435232 -31.393366) (xy 187.494654 -31.401189) (xy 187.552547 -31.416702) (xy 187.60792 -31.439638)
			(xy 187.659826 -31.469605) (xy 187.707376 -31.506092) (xy 187.749756 -31.548472) (xy 187.786243 -31.596022)
			(xy 187.81621 -31.647928) (xy 187.839146 -31.703301) (xy 187.854659 -31.761194) (xy 187.862482 -31.820616)
			(xy 187.862972 -31.850584) (xy 187.862972 -32.714184) (xy 187.862839 -32.722312) (xy 202.706732 -32.722312)
			(xy 202.706732 -31.858712) (xy 202.707222 -31.828728) (xy 202.71505 -31.769272) (xy 202.730571 -31.711347)
			(xy 202.75352 -31.655943) (xy 202.783504 -31.604009) (xy 202.82001 -31.556433) (xy 202.862415 -31.514028)
			(xy 202.909991 -31.477522) (xy 202.961925 -31.447538) (xy 203.017329 -31.424589) (xy 203.075254 -31.409068)
			(xy 203.13471 -31.40124) (xy 203.194678 -31.40124) (xy 203.254134 -31.409068) (xy 203.312059 -31.424589)
			(xy 203.367463 -31.447538) (xy 203.419397 -31.477522) (xy 203.466973 -31.514028) (xy 203.509378 -31.556433)
			(xy 203.545884 -31.604009) (xy 203.575868 -31.655943) (xy 203.598817 -31.711347) (xy 203.614338 -31.769272)
			(xy 203.622166 -31.828728) (xy 203.622656 -31.858712) (xy 203.622656 -32.714184) (xy 212.947504 -32.714184)
			(xy 212.947504 -31.850584) (xy 212.947994 -31.820616) (xy 212.955817 -31.761194) (xy 212.97133 -31.703301)
			(xy 212.994266 -31.647928) (xy 213.024233 -31.596022) (xy 213.06072 -31.548472) (xy 213.1031 -31.506092)
			(xy 213.15065 -31.469605) (xy 213.202556 -31.439638) (xy 213.257929 -31.416702) (xy 213.315822 -31.401189)
			(xy 213.375244 -31.393366) (xy 213.43518 -31.393366) (xy 213.494602 -31.401189) (xy 213.552495 -31.416702)
			(xy 213.607868 -31.439638) (xy 213.659774 -31.469605) (xy 213.707324 -31.506092) (xy 213.749704 -31.548472)
			(xy 213.786191 -31.596022) (xy 213.816158 -31.647928) (xy 213.839094 -31.703301) (xy 213.854607 -31.761194)
			(xy 213.86243 -31.820616) (xy 213.86292 -31.850584) (xy 213.86292 -32.714184) (xy 213.862787 -32.722312)
			(xy 240.806732 -32.722312) (xy 240.806732 -31.858712) (xy 240.807222 -31.828728) (xy 240.81505 -31.769272)
			(xy 240.830571 -31.711347) (xy 240.85352 -31.655943) (xy 240.883504 -31.604009) (xy 240.92001 -31.556433)
			(xy 240.962415 -31.514028) (xy 241.009991 -31.477522) (xy 241.061925 -31.447538) (xy 241.117329 -31.424589)
			(xy 241.175254 -31.409068) (xy 241.23471 -31.40124) (xy 241.294678 -31.40124) (xy 241.354134 -31.409068)
			(xy 241.412059 -31.424589) (xy 241.467463 -31.447538) (xy 241.519397 -31.477522) (xy 241.566973 -31.514028)
			(xy 241.609378 -31.556433) (xy 241.645884 -31.604009) (xy 241.675868 -31.655943) (xy 241.698817 -31.711347)
			(xy 241.714338 -31.769272) (xy 241.722166 -31.828728) (xy 241.722656 -31.858712) (xy 241.722656 -32.714184)
			(xy 251.047504 -32.714184) (xy 251.047504 -31.850584) (xy 251.047994 -31.820616) (xy 251.055817 -31.761194)
			(xy 251.07133 -31.703301) (xy 251.094266 -31.647928) (xy 251.124233 -31.596022) (xy 251.16072 -31.548472)
			(xy 251.2031 -31.506092) (xy 251.25065 -31.469605) (xy 251.302556 -31.439638) (xy 251.357929 -31.416702)
			(xy 251.415822 -31.401189) (xy 251.475244 -31.393366) (xy 251.53518 -31.393366) (xy 251.594602 -31.401189)
			(xy 251.652495 -31.416702) (xy 251.707868 -31.439638) (xy 251.759774 -31.469605) (xy 251.807324 -31.506092)
			(xy 251.849704 -31.548472) (xy 251.886191 -31.596022) (xy 251.916158 -31.647928) (xy 251.939094 -31.703301)
			(xy 251.954607 -31.761194) (xy 251.96243 -31.820616) (xy 251.96292 -31.850584) (xy 251.96292 -32.714184)
			(xy 251.962787 -32.722312) (xy 266.80668 -32.722312) (xy 266.80668 -31.858712) (xy 266.80717 -31.828728)
			(xy 266.814998 -31.769272) (xy 266.830519 -31.711347) (xy 266.853468 -31.655943) (xy 266.883452 -31.604009)
			(xy 266.919958 -31.556433) (xy 266.962363 -31.514028) (xy 267.009939 -31.477522) (xy 267.061873 -31.447538)
			(xy 267.117277 -31.424589) (xy 267.175202 -31.409068) (xy 267.234658 -31.40124) (xy 267.294626 -31.40124)
			(xy 267.354082 -31.409068) (xy 267.412007 -31.424589) (xy 267.467411 -31.447538) (xy 267.519345 -31.477522)
			(xy 267.566921 -31.514028) (xy 267.609326 -31.556433) (xy 267.645832 -31.604009) (xy 267.675816 -31.655943)
			(xy 267.698765 -31.711347) (xy 267.714286 -31.769272) (xy 267.722114 -31.828728) (xy 267.722604 -31.858712)
			(xy 267.722604 -32.714184) (xy 277.047452 -32.714184) (xy 277.047452 -31.850584) (xy 277.047942 -31.820616)
			(xy 277.055765 -31.761194) (xy 277.071278 -31.703301) (xy 277.094214 -31.647928) (xy 277.124181 -31.596022)
			(xy 277.160668 -31.548472) (xy 277.203048 -31.506092) (xy 277.250598 -31.469605) (xy 277.302504 -31.439638)
			(xy 277.357877 -31.416702) (xy 277.41577 -31.401189) (xy 277.475192 -31.393366) (xy 277.535128 -31.393366)
			(xy 277.59455 -31.401189) (xy 277.652443 -31.416702) (xy 277.707816 -31.439638) (xy 277.759722 -31.469605)
			(xy 277.807272 -31.506092) (xy 277.849652 -31.548472) (xy 277.886139 -31.596022) (xy 277.916106 -31.647928)
			(xy 277.939042 -31.703301) (xy 277.954555 -31.761194) (xy 277.962378 -31.820616) (xy 277.962868 -31.850584)
			(xy 277.962868 -32.714184) (xy 277.962735 -32.722312) (xy 292.806628 -32.722312) (xy 292.806628 -31.858712)
			(xy 292.807118 -31.828728) (xy 292.814946 -31.769272) (xy 292.830467 -31.711347) (xy 292.853416 -31.655943)
			(xy 292.8834 -31.604009) (xy 292.919906 -31.556433) (xy 292.962311 -31.514028) (xy 293.009887 -31.477522)
			(xy 293.061821 -31.447538) (xy 293.117225 -31.424589) (xy 293.17515 -31.409068) (xy 293.234606 -31.40124)
			(xy 293.294574 -31.40124) (xy 293.35403 -31.409068) (xy 293.411955 -31.424589) (xy 293.467359 -31.447538)
			(xy 293.519293 -31.477522) (xy 293.566869 -31.514028) (xy 293.609274 -31.556433) (xy 293.64578 -31.604009)
			(xy 293.675764 -31.655943) (xy 293.698713 -31.711347) (xy 293.714234 -31.769272) (xy 293.722062 -31.828728)
			(xy 293.722552 -31.858712) (xy 293.722552 -32.714184) (xy 303.0474 -32.714184) (xy 303.0474 -31.850584)
			(xy 303.04789 -31.820616) (xy 303.055713 -31.761194) (xy 303.071226 -31.703301) (xy 303.094162 -31.647928)
			(xy 303.124129 -31.596022) (xy 303.160616 -31.548472) (xy 303.202996 -31.506092) (xy 303.250546 -31.469605)
			(xy 303.302452 -31.439638) (xy 303.357825 -31.416702) (xy 303.415718 -31.401189) (xy 303.47514 -31.393366)
			(xy 303.535076 -31.393366) (xy 303.594498 -31.401189) (xy 303.652391 -31.416702) (xy 303.707764 -31.439638)
			(xy 303.75967 -31.469605) (xy 303.80722 -31.506092) (xy 303.8496 -31.548472) (xy 303.886087 -31.596022)
			(xy 303.916054 -31.647928) (xy 303.93899 -31.703301) (xy 303.954503 -31.761194) (xy 303.962326 -31.820616)
			(xy 303.962816 -31.850584) (xy 303.962816 -32.714184) (xy 303.962683 -32.722312) (xy 318.806576 -32.722312)
			(xy 318.806576 -31.858712) (xy 318.807066 -31.828728) (xy 318.814894 -31.769272) (xy 318.830415 -31.711347)
			(xy 318.853364 -31.655943) (xy 318.883348 -31.604009) (xy 318.919854 -31.556433) (xy 318.962259 -31.514028)
			(xy 319.009835 -31.477522) (xy 319.061769 -31.447538) (xy 319.117173 -31.424589) (xy 319.175098 -31.409068)
			(xy 319.234554 -31.40124) (xy 319.294522 -31.40124) (xy 319.353978 -31.409068) (xy 319.411903 -31.424589)
			(xy 319.467307 -31.447538) (xy 319.519241 -31.477522) (xy 319.566817 -31.514028) (xy 319.609222 -31.556433)
			(xy 319.645728 -31.604009) (xy 319.675712 -31.655943) (xy 319.698661 -31.711347) (xy 319.714182 -31.769272)
			(xy 319.72201 -31.828728) (xy 319.7225 -31.858712) (xy 319.7225 -32.714184) (xy 329.047348 -32.714184)
			(xy 329.047348 -31.850584) (xy 329.047838 -31.820616) (xy 329.055661 -31.761194) (xy 329.071174 -31.703301)
			(xy 329.09411 -31.647928) (xy 329.124077 -31.596022) (xy 329.160564 -31.548472) (xy 329.202944 -31.506092)
			(xy 329.250494 -31.469605) (xy 329.3024 -31.439638) (xy 329.357773 -31.416702) (xy 329.415666 -31.401189)
			(xy 329.475088 -31.393366) (xy 329.535024 -31.393366) (xy 329.594446 -31.401189) (xy 329.652339 -31.416702)
			(xy 329.707712 -31.439638) (xy 329.759618 -31.469605) (xy 329.807168 -31.506092) (xy 329.849548 -31.548472)
			(xy 329.886035 -31.596022) (xy 329.916002 -31.647928) (xy 329.938938 -31.703301) (xy 329.954451 -31.761194)
			(xy 329.962274 -31.820616) (xy 329.962764 -31.850584) (xy 329.962764 -32.714184) (xy 329.962631 -32.722312)
			(xy 356.907084 -32.722312) (xy 356.907084 -31.858712) (xy 356.907574 -31.828744) (xy 356.915397 -31.769322)
			(xy 356.93091 -31.711429) (xy 356.953846 -31.656056) (xy 356.983813 -31.60415) (xy 357.0203 -31.5566)
			(xy 357.06268 -31.51422) (xy 357.11023 -31.477733) (xy 357.162136 -31.447766) (xy 357.217509 -31.42483)
			(xy 357.275402 -31.409317) (xy 357.334824 -31.401494) (xy 357.39476 -31.401494) (xy 357.454182 -31.409317)
			(xy 357.512075 -31.42483) (xy 357.567448 -31.447766) (xy 357.619354 -31.477733) (xy 357.666904 -31.51422)
			(xy 357.709284 -31.5566) (xy 357.745771 -31.60415) (xy 357.775738 -31.656056) (xy 357.798674 -31.711429)
			(xy 357.814187 -31.769322) (xy 357.82201 -31.828744) (xy 357.8225 -31.858712) (xy 357.8225 -32.714184)
			(xy 367.147348 -32.714184) (xy 367.147348 -31.850584) (xy 367.147838 -31.8206) (xy 367.155666 -31.761144)
			(xy 367.171187 -31.703219) (xy 367.194136 -31.647815) (xy 367.22412 -31.595881) (xy 367.260626 -31.548305)
			(xy 367.303031 -31.5059) (xy 367.350607 -31.469394) (xy 367.402541 -31.43941) (xy 367.457945 -31.416461)
			(xy 367.51587 -31.40094) (xy 367.575326 -31.393112) (xy 367.635294 -31.393112) (xy 367.69475 -31.40094)
			(xy 367.752675 -31.416461) (xy 367.808079 -31.43941) (xy 367.860013 -31.469394) (xy 367.907589 -31.5059)
			(xy 367.949994 -31.548305) (xy 367.9865 -31.595881) (xy 368.016484 -31.647815) (xy 368.039433 -31.703219)
			(xy 368.054954 -31.761144) (xy 368.062782 -31.8206) (xy 368.063272 -31.850584) (xy 368.063272 -32.714184)
			(xy 368.063139 -32.722312) (xy 382.907032 -32.722312) (xy 382.907032 -31.858712) (xy 382.907522 -31.828744)
			(xy 382.915345 -31.769322) (xy 382.930858 -31.711429) (xy 382.953794 -31.656056) (xy 382.983761 -31.60415)
			(xy 383.020248 -31.5566) (xy 383.062628 -31.51422) (xy 383.110178 -31.477733) (xy 383.162084 -31.447766)
			(xy 383.217457 -31.42483) (xy 383.27535 -31.409317) (xy 383.334772 -31.401494) (xy 383.394708 -31.401494)
			(xy 383.45413 -31.409317) (xy 383.512023 -31.42483) (xy 383.567396 -31.447766) (xy 383.619302 -31.477733)
			(xy 383.666852 -31.51422) (xy 383.709232 -31.5566) (xy 383.745719 -31.60415) (xy 383.775686 -31.656056)
			(xy 383.798622 -31.711429) (xy 383.814135 -31.769322) (xy 383.821958 -31.828744) (xy 383.822448 -31.858712)
			(xy 383.822448 -32.714184) (xy 393.147296 -32.714184) (xy 393.147296 -31.850584) (xy 393.147786 -31.8206)
			(xy 393.155614 -31.761144) (xy 393.171135 -31.703219) (xy 393.194084 -31.647815) (xy 393.224068 -31.595881)
			(xy 393.260574 -31.548305) (xy 393.302979 -31.5059) (xy 393.350555 -31.469394) (xy 393.402489 -31.43941)
			(xy 393.457893 -31.416461) (xy 393.515818 -31.40094) (xy 393.575274 -31.393112) (xy 393.635242 -31.393112)
			(xy 393.694698 -31.40094) (xy 393.752623 -31.416461) (xy 393.808027 -31.43941) (xy 393.859961 -31.469394)
			(xy 393.907537 -31.5059) (xy 393.949942 -31.548305) (xy 393.986448 -31.595881) (xy 394.016432 -31.647815)
			(xy 394.039381 -31.703219) (xy 394.054902 -31.761144) (xy 394.06273 -31.8206) (xy 394.06322 -31.850584)
			(xy 394.06322 -32.714184) (xy 394.063087 -32.722312) (xy 408.90698 -32.722312) (xy 408.90698 -31.858712)
			(xy 408.90747 -31.828744) (xy 408.915293 -31.769322) (xy 408.930806 -31.711429) (xy 408.953742 -31.656056)
			(xy 408.983709 -31.60415) (xy 409.020196 -31.5566) (xy 409.062576 -31.51422) (xy 409.110126 -31.477733)
			(xy 409.162032 -31.447766) (xy 409.217405 -31.42483) (xy 409.275298 -31.409317) (xy 409.33472 -31.401494)
			(xy 409.394656 -31.401494) (xy 409.454078 -31.409317) (xy 409.511971 -31.42483) (xy 409.567344 -31.447766)
			(xy 409.61925 -31.477733) (xy 409.6668 -31.51422) (xy 409.70918 -31.5566) (xy 409.745667 -31.60415)
			(xy 409.775634 -31.656056) (xy 409.79857 -31.711429) (xy 409.814083 -31.769322) (xy 409.821906 -31.828744)
			(xy 409.822396 -31.858712) (xy 409.822396 -32.714184) (xy 419.147244 -32.714184) (xy 419.147244 -31.850584)
			(xy 419.147734 -31.8206) (xy 419.155562 -31.761144) (xy 419.171083 -31.703219) (xy 419.194032 -31.647815)
			(xy 419.224016 -31.595881) (xy 419.260522 -31.548305) (xy 419.302927 -31.5059) (xy 419.350503 -31.469394)
			(xy 419.402437 -31.43941) (xy 419.457841 -31.416461) (xy 419.515766 -31.40094) (xy 419.575222 -31.393112)
			(xy 419.63519 -31.393112) (xy 419.694646 -31.40094) (xy 419.752571 -31.416461) (xy 419.807975 -31.43941)
			(xy 419.859909 -31.469394) (xy 419.907485 -31.5059) (xy 419.94989 -31.548305) (xy 419.986396 -31.595881)
			(xy 420.01638 -31.647815) (xy 420.039329 -31.703219) (xy 420.05485 -31.761144) (xy 420.062678 -31.8206)
			(xy 420.063168 -31.850584) (xy 420.063168 -32.714184) (xy 420.063035 -32.722312) (xy 434.906928 -32.722312)
			(xy 434.906928 -31.858712) (xy 434.907418 -31.828744) (xy 434.915241 -31.769322) (xy 434.930754 -31.711429)
			(xy 434.95369 -31.656056) (xy 434.983657 -31.60415) (xy 435.020144 -31.5566) (xy 435.062524 -31.51422)
			(xy 435.110074 -31.477733) (xy 435.16198 -31.447766) (xy 435.217353 -31.42483) (xy 435.275246 -31.409317)
			(xy 435.334668 -31.401494) (xy 435.394604 -31.401494) (xy 435.454026 -31.409317) (xy 435.511919 -31.42483)
			(xy 435.567292 -31.447766) (xy 435.619198 -31.477733) (xy 435.666748 -31.51422) (xy 435.709128 -31.5566)
			(xy 435.745615 -31.60415) (xy 435.775582 -31.656056) (xy 435.798518 -31.711429) (xy 435.814031 -31.769322)
			(xy 435.821854 -31.828744) (xy 435.822344 -31.858712) (xy 435.822344 -32.714184) (xy 445.147192 -32.714184)
			(xy 445.147192 -31.850584) (xy 445.147682 -31.8206) (xy 445.15551 -31.761144) (xy 445.171031 -31.703219)
			(xy 445.19398 -31.647815) (xy 445.223964 -31.595881) (xy 445.26047 -31.548305) (xy 445.302875 -31.5059)
			(xy 445.350451 -31.469394) (xy 445.402385 -31.43941) (xy 445.457789 -31.416461) (xy 445.515714 -31.40094)
			(xy 445.57517 -31.393112) (xy 445.635138 -31.393112) (xy 445.694594 -31.40094) (xy 445.752519 -31.416461)
			(xy 445.807923 -31.43941) (xy 445.859857 -31.469394) (xy 445.907433 -31.5059) (xy 445.949838 -31.548305)
			(xy 445.986344 -31.595881) (xy 446.016328 -31.647815) (xy 446.039277 -31.703219) (xy 446.054798 -31.761144)
			(xy 446.062626 -31.8206) (xy 446.063116 -31.850584) (xy 446.063116 -32.714184) (xy 446.062626 -32.744168)
			(xy 446.054798 -32.803624) (xy 446.039277 -32.861549) (xy 446.016328 -32.916953) (xy 445.986344 -32.968887)
			(xy 445.949838 -33.016463) (xy 445.907433 -33.058868) (xy 445.859857 -33.095374) (xy 445.807923 -33.125358)
			(xy 445.752519 -33.148307) (xy 445.694594 -33.163828) (xy 445.635138 -33.171656) (xy 445.57517 -33.171656)
			(xy 445.515714 -33.163828) (xy 445.457789 -33.148307) (xy 445.402385 -33.125358) (xy 445.350451 -33.095374)
			(xy 445.302875 -33.058868) (xy 445.26047 -33.016463) (xy 445.223964 -32.968887) (xy 445.19398 -32.916953)
			(xy 445.171031 -32.861549) (xy 445.15551 -32.803624) (xy 445.147682 -32.744168) (xy 445.147192 -32.714184)
			(xy 435.822344 -32.714184) (xy 435.822344 -32.722312) (xy 435.821854 -32.75228) (xy 435.814031 -32.811702)
			(xy 435.798518 -32.869595) (xy 435.775582 -32.924968) (xy 435.745615 -32.976874) (xy 435.709128 -33.024424)
			(xy 435.666748 -33.066804) (xy 435.619198 -33.103291) (xy 435.567292 -33.133258) (xy 435.511919 -33.156194)
			(xy 435.454026 -33.171707) (xy 435.394604 -33.17953) (xy 435.334668 -33.17953) (xy 435.275246 -33.171707)
			(xy 435.217353 -33.156194) (xy 435.16198 -33.133258) (xy 435.110074 -33.103291) (xy 435.062524 -33.066804)
			(xy 435.020144 -33.024424) (xy 434.983657 -32.976874) (xy 434.95369 -32.924968) (xy 434.930754 -32.869595)
			(xy 434.915241 -32.811702) (xy 434.907418 -32.75228) (xy 434.906928 -32.722312) (xy 420.063035 -32.722312)
			(xy 420.062678 -32.744168) (xy 420.05485 -32.803624) (xy 420.039329 -32.861549) (xy 420.01638 -32.916953)
			(xy 419.986396 -32.968887) (xy 419.94989 -33.016463) (xy 419.907485 -33.058868) (xy 419.859909 -33.095374)
			(xy 419.807975 -33.125358) (xy 419.752571 -33.148307) (xy 419.694646 -33.163828) (xy 419.63519 -33.171656)
			(xy 419.575222 -33.171656) (xy 419.515766 -33.163828) (xy 419.457841 -33.148307) (xy 419.402437 -33.125358)
			(xy 419.350503 -33.095374) (xy 419.302927 -33.058868) (xy 419.260522 -33.016463) (xy 419.224016 -32.968887)
			(xy 419.194032 -32.916953) (xy 419.171083 -32.861549) (xy 419.155562 -32.803624) (xy 419.147734 -32.744168)
			(xy 419.147244 -32.714184) (xy 409.822396 -32.714184) (xy 409.822396 -32.722312) (xy 409.821906 -32.75228)
			(xy 409.814083 -32.811702) (xy 409.79857 -32.869595) (xy 409.775634 -32.924968) (xy 409.745667 -32.976874)
			(xy 409.70918 -33.024424) (xy 409.6668 -33.066804) (xy 409.61925 -33.103291) (xy 409.567344 -33.133258)
			(xy 409.511971 -33.156194) (xy 409.454078 -33.171707) (xy 409.394656 -33.17953) (xy 409.33472 -33.17953)
			(xy 409.275298 -33.171707) (xy 409.217405 -33.156194) (xy 409.162032 -33.133258) (xy 409.110126 -33.103291)
			(xy 409.062576 -33.066804) (xy 409.020196 -33.024424) (xy 408.983709 -32.976874) (xy 408.953742 -32.924968)
			(xy 408.930806 -32.869595) (xy 408.915293 -32.811702) (xy 408.90747 -32.75228) (xy 408.90698 -32.722312)
			(xy 394.063087 -32.722312) (xy 394.06273 -32.744168) (xy 394.054902 -32.803624) (xy 394.039381 -32.861549)
			(xy 394.016432 -32.916953) (xy 393.986448 -32.968887) (xy 393.949942 -33.016463) (xy 393.907537 -33.058868)
			(xy 393.859961 -33.095374) (xy 393.808027 -33.125358) (xy 393.752623 -33.148307) (xy 393.694698 -33.163828)
			(xy 393.635242 -33.171656) (xy 393.575274 -33.171656) (xy 393.515818 -33.163828) (xy 393.457893 -33.148307)
			(xy 393.402489 -33.125358) (xy 393.350555 -33.095374) (xy 393.302979 -33.058868) (xy 393.260574 -33.016463)
			(xy 393.224068 -32.968887) (xy 393.194084 -32.916953) (xy 393.171135 -32.861549) (xy 393.155614 -32.803624)
			(xy 393.147786 -32.744168) (xy 393.147296 -32.714184) (xy 383.822448 -32.714184) (xy 383.822448 -32.722312)
			(xy 383.821958 -32.75228) (xy 383.814135 -32.811702) (xy 383.798622 -32.869595) (xy 383.775686 -32.924968)
			(xy 383.745719 -32.976874) (xy 383.709232 -33.024424) (xy 383.666852 -33.066804) (xy 383.619302 -33.103291)
			(xy 383.567396 -33.133258) (xy 383.512023 -33.156194) (xy 383.45413 -33.171707) (xy 383.394708 -33.17953)
			(xy 383.334772 -33.17953) (xy 383.27535 -33.171707) (xy 383.217457 -33.156194) (xy 383.162084 -33.133258)
			(xy 383.110178 -33.103291) (xy 383.062628 -33.066804) (xy 383.020248 -33.024424) (xy 382.983761 -32.976874)
			(xy 382.953794 -32.924968) (xy 382.930858 -32.869595) (xy 382.915345 -32.811702) (xy 382.907522 -32.75228)
			(xy 382.907032 -32.722312) (xy 368.063139 -32.722312) (xy 368.062782 -32.744168) (xy 368.054954 -32.803624)
			(xy 368.039433 -32.861549) (xy 368.016484 -32.916953) (xy 367.9865 -32.968887) (xy 367.949994 -33.016463)
			(xy 367.907589 -33.058868) (xy 367.860013 -33.095374) (xy 367.808079 -33.125358) (xy 367.752675 -33.148307)
			(xy 367.69475 -33.163828) (xy 367.635294 -33.171656) (xy 367.575326 -33.171656) (xy 367.51587 -33.163828)
			(xy 367.457945 -33.148307) (xy 367.402541 -33.125358) (xy 367.350607 -33.095374) (xy 367.303031 -33.058868)
			(xy 367.260626 -33.016463) (xy 367.22412 -32.968887) (xy 367.194136 -32.916953) (xy 367.171187 -32.861549)
			(xy 367.155666 -32.803624) (xy 367.147838 -32.744168) (xy 367.147348 -32.714184) (xy 357.8225 -32.714184)
			(xy 357.8225 -32.722312) (xy 357.82201 -32.75228) (xy 357.814187 -32.811702) (xy 357.798674 -32.869595)
			(xy 357.775738 -32.924968) (xy 357.745771 -32.976874) (xy 357.709284 -33.024424) (xy 357.666904 -33.066804)
			(xy 357.619354 -33.103291) (xy 357.567448 -33.133258) (xy 357.512075 -33.156194) (xy 357.454182 -33.171707)
			(xy 357.39476 -33.17953) (xy 357.334824 -33.17953) (xy 357.275402 -33.171707) (xy 357.217509 -33.156194)
			(xy 357.162136 -33.133258) (xy 357.11023 -33.103291) (xy 357.06268 -33.066804) (xy 357.0203 -33.024424)
			(xy 356.983813 -32.976874) (xy 356.953846 -32.924968) (xy 356.93091 -32.869595) (xy 356.915397 -32.811702)
			(xy 356.907574 -32.75228) (xy 356.907084 -32.722312) (xy 329.962631 -32.722312) (xy 329.962274 -32.744152)
			(xy 329.954451 -32.803574) (xy 329.938938 -32.861467) (xy 329.916002 -32.91684) (xy 329.886035 -32.968746)
			(xy 329.849548 -33.016296) (xy 329.807168 -33.058676) (xy 329.759618 -33.095163) (xy 329.707712 -33.12513)
			(xy 329.652339 -33.148066) (xy 329.594446 -33.163579) (xy 329.535024 -33.171402) (xy 329.475088 -33.171402)
			(xy 329.415666 -33.163579) (xy 329.357773 -33.148066) (xy 329.3024 -33.12513) (xy 329.250494 -33.095163)
			(xy 329.202944 -33.058676) (xy 329.160564 -33.016296) (xy 329.124077 -32.968746) (xy 329.09411 -32.91684)
			(xy 329.071174 -32.861467) (xy 329.055661 -32.803574) (xy 329.047838 -32.744152) (xy 329.047348 -32.714184)
			(xy 319.7225 -32.714184) (xy 319.7225 -32.722312) (xy 319.72201 -32.752296) (xy 319.714182 -32.811752)
			(xy 319.698661 -32.869677) (xy 319.675712 -32.925081) (xy 319.645728 -32.977015) (xy 319.609222 -33.024591)
			(xy 319.566817 -33.066996) (xy 319.519241 -33.103502) (xy 319.467307 -33.133486) (xy 319.411903 -33.156435)
			(xy 319.353978 -33.171956) (xy 319.294522 -33.179784) (xy 319.234554 -33.179784) (xy 319.175098 -33.171956)
			(xy 319.117173 -33.156435) (xy 319.061769 -33.133486) (xy 319.009835 -33.103502) (xy 318.962259 -33.066996)
			(xy 318.919854 -33.024591) (xy 318.883348 -32.977015) (xy 318.853364 -32.925081) (xy 318.830415 -32.869677)
			(xy 318.814894 -32.811752) (xy 318.807066 -32.752296) (xy 318.806576 -32.722312) (xy 303.962683 -32.722312)
			(xy 303.962326 -32.744152) (xy 303.954503 -32.803574) (xy 303.93899 -32.861467) (xy 303.916054 -32.91684)
			(xy 303.886087 -32.968746) (xy 303.8496 -33.016296) (xy 303.80722 -33.058676) (xy 303.75967 -33.095163)
			(xy 303.707764 -33.12513) (xy 303.652391 -33.148066) (xy 303.594498 -33.163579) (xy 303.535076 -33.171402)
			(xy 303.47514 -33.171402) (xy 303.415718 -33.163579) (xy 303.357825 -33.148066) (xy 303.302452 -33.12513)
			(xy 303.250546 -33.095163) (xy 303.202996 -33.058676) (xy 303.160616 -33.016296) (xy 303.124129 -32.968746)
			(xy 303.094162 -32.91684) (xy 303.071226 -32.861467) (xy 303.055713 -32.803574) (xy 303.04789 -32.744152)
			(xy 303.0474 -32.714184) (xy 293.722552 -32.714184) (xy 293.722552 -32.722312) (xy 293.722062 -32.752296)
			(xy 293.714234 -32.811752) (xy 293.698713 -32.869677) (xy 293.675764 -32.925081) (xy 293.64578 -32.977015)
			(xy 293.609274 -33.024591) (xy 293.566869 -33.066996) (xy 293.519293 -33.103502) (xy 293.467359 -33.133486)
			(xy 293.411955 -33.156435) (xy 293.35403 -33.171956) (xy 293.294574 -33.179784) (xy 293.234606 -33.179784)
			(xy 293.17515 -33.171956) (xy 293.117225 -33.156435) (xy 293.061821 -33.133486) (xy 293.009887 -33.103502)
			(xy 292.962311 -33.066996) (xy 292.919906 -33.024591) (xy 292.8834 -32.977015) (xy 292.853416 -32.925081)
			(xy 292.830467 -32.869677) (xy 292.814946 -32.811752) (xy 292.807118 -32.752296) (xy 292.806628 -32.722312)
			(xy 277.962735 -32.722312) (xy 277.962378 -32.744152) (xy 277.954555 -32.803574) (xy 277.939042 -32.861467)
			(xy 277.916106 -32.91684) (xy 277.886139 -32.968746) (xy 277.849652 -33.016296) (xy 277.807272 -33.058676)
			(xy 277.759722 -33.095163) (xy 277.707816 -33.12513) (xy 277.652443 -33.148066) (xy 277.59455 -33.163579)
			(xy 277.535128 -33.171402) (xy 277.475192 -33.171402) (xy 277.41577 -33.163579) (xy 277.357877 -33.148066)
			(xy 277.302504 -33.12513) (xy 277.250598 -33.095163) (xy 277.203048 -33.058676) (xy 277.160668 -33.016296)
			(xy 277.124181 -32.968746) (xy 277.094214 -32.91684) (xy 277.071278 -32.861467) (xy 277.055765 -32.803574)
			(xy 277.047942 -32.744152) (xy 277.047452 -32.714184) (xy 267.722604 -32.714184) (xy 267.722604 -32.722312)
			(xy 267.722114 -32.752296) (xy 267.714286 -32.811752) (xy 267.698765 -32.869677) (xy 267.675816 -32.925081)
			(xy 267.645832 -32.977015) (xy 267.609326 -33.024591) (xy 267.566921 -33.066996) (xy 267.519345 -33.103502)
			(xy 267.467411 -33.133486) (xy 267.412007 -33.156435) (xy 267.354082 -33.171956) (xy 267.294626 -33.179784)
			(xy 267.234658 -33.179784) (xy 267.175202 -33.171956) (xy 267.117277 -33.156435) (xy 267.061873 -33.133486)
			(xy 267.009939 -33.103502) (xy 266.962363 -33.066996) (xy 266.919958 -33.024591) (xy 266.883452 -32.977015)
			(xy 266.853468 -32.925081) (xy 266.830519 -32.869677) (xy 266.814998 -32.811752) (xy 266.80717 -32.752296)
			(xy 266.80668 -32.722312) (xy 251.962787 -32.722312) (xy 251.96243 -32.744152) (xy 251.954607 -32.803574)
			(xy 251.939094 -32.861467) (xy 251.916158 -32.91684) (xy 251.886191 -32.968746) (xy 251.849704 -33.016296)
			(xy 251.807324 -33.058676) (xy 251.759774 -33.095163) (xy 251.707868 -33.12513) (xy 251.652495 -33.148066)
			(xy 251.594602 -33.163579) (xy 251.53518 -33.171402) (xy 251.475244 -33.171402) (xy 251.415822 -33.163579)
			(xy 251.357929 -33.148066) (xy 251.302556 -33.12513) (xy 251.25065 -33.095163) (xy 251.2031 -33.058676)
			(xy 251.16072 -33.016296) (xy 251.124233 -32.968746) (xy 251.094266 -32.91684) (xy 251.07133 -32.861467)
			(xy 251.055817 -32.803574) (xy 251.047994 -32.744152) (xy 251.047504 -32.714184) (xy 241.722656 -32.714184)
			(xy 241.722656 -32.722312) (xy 241.722166 -32.752296) (xy 241.714338 -32.811752) (xy 241.698817 -32.869677)
			(xy 241.675868 -32.925081) (xy 241.645884 -32.977015) (xy 241.609378 -33.024591) (xy 241.566973 -33.066996)
			(xy 241.519397 -33.103502) (xy 241.467463 -33.133486) (xy 241.412059 -33.156435) (xy 241.354134 -33.171956)
			(xy 241.294678 -33.179784) (xy 241.23471 -33.179784) (xy 241.175254 -33.171956) (xy 241.117329 -33.156435)
			(xy 241.061925 -33.133486) (xy 241.009991 -33.103502) (xy 240.962415 -33.066996) (xy 240.92001 -33.024591)
			(xy 240.883504 -32.977015) (xy 240.85352 -32.925081) (xy 240.830571 -32.869677) (xy 240.81505 -32.811752)
			(xy 240.807222 -32.752296) (xy 240.806732 -32.722312) (xy 213.862787 -32.722312) (xy 213.86243 -32.744152)
			(xy 213.854607 -32.803574) (xy 213.839094 -32.861467) (xy 213.816158 -32.91684) (xy 213.786191 -32.968746)
			(xy 213.749704 -33.016296) (xy 213.707324 -33.058676) (xy 213.659774 -33.095163) (xy 213.607868 -33.12513)
			(xy 213.552495 -33.148066) (xy 213.494602 -33.163579) (xy 213.43518 -33.171402) (xy 213.375244 -33.171402)
			(xy 213.315822 -33.163579) (xy 213.257929 -33.148066) (xy 213.202556 -33.12513) (xy 213.15065 -33.095163)
			(xy 213.1031 -33.058676) (xy 213.06072 -33.016296) (xy 213.024233 -32.968746) (xy 212.994266 -32.91684)
			(xy 212.97133 -32.861467) (xy 212.955817 -32.803574) (xy 212.947994 -32.744152) (xy 212.947504 -32.714184)
			(xy 203.622656 -32.714184) (xy 203.622656 -32.722312) (xy 203.622166 -32.752296) (xy 203.614338 -32.811752)
			(xy 203.598817 -32.869677) (xy 203.575868 -32.925081) (xy 203.545884 -32.977015) (xy 203.509378 -33.024591)
			(xy 203.466973 -33.066996) (xy 203.419397 -33.103502) (xy 203.367463 -33.133486) (xy 203.312059 -33.156435)
			(xy 203.254134 -33.171956) (xy 203.194678 -33.179784) (xy 203.13471 -33.179784) (xy 203.075254 -33.171956)
			(xy 203.017329 -33.156435) (xy 202.961925 -33.133486) (xy 202.909991 -33.103502) (xy 202.862415 -33.066996)
			(xy 202.82001 -33.024591) (xy 202.783504 -32.977015) (xy 202.75352 -32.925081) (xy 202.730571 -32.869677)
			(xy 202.71505 -32.811752) (xy 202.707222 -32.752296) (xy 202.706732 -32.722312) (xy 187.862839 -32.722312)
			(xy 187.862482 -32.744152) (xy 187.854659 -32.803574) (xy 187.839146 -32.861467) (xy 187.81621 -32.91684)
			(xy 187.786243 -32.968746) (xy 187.749756 -33.016296) (xy 187.707376 -33.058676) (xy 187.659826 -33.095163)
			(xy 187.60792 -33.12513) (xy 187.552547 -33.148066) (xy 187.494654 -33.163579) (xy 187.435232 -33.171402)
			(xy 187.375296 -33.171402) (xy 187.315874 -33.163579) (xy 187.257981 -33.148066) (xy 187.202608 -33.12513)
			(xy 187.150702 -33.095163) (xy 187.103152 -33.058676) (xy 187.060772 -33.016296) (xy 187.024285 -32.968746)
			(xy 186.994318 -32.91684) (xy 186.971382 -32.861467) (xy 186.955869 -32.803574) (xy 186.948046 -32.744152)
			(xy 186.947556 -32.714184) (xy 177.622708 -32.714184) (xy 177.622708 -32.722312) (xy 177.622218 -32.752296)
			(xy 177.61439 -32.811752) (xy 177.598869 -32.869677) (xy 177.57592 -32.925081) (xy 177.545936 -32.977015)
			(xy 177.50943 -33.024591) (xy 177.467025 -33.066996) (xy 177.419449 -33.103502) (xy 177.367515 -33.133486)
			(xy 177.312111 -33.156435) (xy 177.254186 -33.171956) (xy 177.19473 -33.179784) (xy 177.134762 -33.179784)
			(xy 177.075306 -33.171956) (xy 177.017381 -33.156435) (xy 176.961977 -33.133486) (xy 176.910043 -33.103502)
			(xy 176.862467 -33.066996) (xy 176.820062 -33.024591) (xy 176.783556 -32.977015) (xy 176.753572 -32.925081)
			(xy 176.730623 -32.869677) (xy 176.715102 -32.811752) (xy 176.707274 -32.752296) (xy 176.706784 -32.722312)
			(xy 161.862891 -32.722312) (xy 161.862534 -32.744152) (xy 161.854711 -32.803574) (xy 161.839198 -32.861467)
			(xy 161.816262 -32.91684) (xy 161.786295 -32.968746) (xy 161.749808 -33.016296) (xy 161.707428 -33.058676)
			(xy 161.659878 -33.095163) (xy 161.607972 -33.12513) (xy 161.552599 -33.148066) (xy 161.494706 -33.163579)
			(xy 161.435284 -33.171402) (xy 161.375348 -33.171402) (xy 161.315926 -33.163579) (xy 161.258033 -33.148066)
			(xy 161.20266 -33.12513) (xy 161.150754 -33.095163) (xy 161.103204 -33.058676) (xy 161.060824 -33.016296)
			(xy 161.024337 -32.968746) (xy 160.99437 -32.91684) (xy 160.971434 -32.861467) (xy 160.955921 -32.803574)
			(xy 160.948098 -32.744152) (xy 160.947608 -32.714184) (xy 151.62276 -32.714184) (xy 151.62276 -32.722312)
			(xy 151.62227 -32.752296) (xy 151.614442 -32.811752) (xy 151.598921 -32.869677) (xy 151.575972 -32.925081)
			(xy 151.545988 -32.977015) (xy 151.509482 -33.024591) (xy 151.467077 -33.066996) (xy 151.419501 -33.103502)
			(xy 151.367567 -33.133486) (xy 151.312163 -33.156435) (xy 151.254238 -33.171956) (xy 151.194782 -33.179784)
			(xy 151.134814 -33.179784) (xy 151.075358 -33.171956) (xy 151.017433 -33.156435) (xy 150.962029 -33.133486)
			(xy 150.910095 -33.103502) (xy 150.862519 -33.066996) (xy 150.820114 -33.024591) (xy 150.783608 -32.977015)
			(xy 150.753624 -32.925081) (xy 150.730675 -32.869677) (xy 150.715154 -32.811752) (xy 150.707326 -32.752296)
			(xy 150.706836 -32.722312) (xy 135.862943 -32.722312) (xy 135.862586 -32.744152) (xy 135.854763 -32.803574)
			(xy 135.83925 -32.861467) (xy 135.816314 -32.91684) (xy 135.786347 -32.968746) (xy 135.74986 -33.016296)
			(xy 135.70748 -33.058676) (xy 135.65993 -33.095163) (xy 135.608024 -33.12513) (xy 135.552651 -33.148066)
			(xy 135.494758 -33.163579) (xy 135.435336 -33.171402) (xy 135.3754 -33.171402) (xy 135.315978 -33.163579)
			(xy 135.258085 -33.148066) (xy 135.202712 -33.12513) (xy 135.150806 -33.095163) (xy 135.103256 -33.058676)
			(xy 135.060876 -33.016296) (xy 135.024389 -32.968746) (xy 134.994422 -32.91684) (xy 134.971486 -32.861467)
			(xy 134.955973 -32.803574) (xy 134.94815 -32.744152) (xy 134.94766 -32.714184) (xy 125.622812 -32.714184)
			(xy 125.622812 -32.722312) (xy 125.622322 -32.752296) (xy 125.614494 -32.811752) (xy 125.598973 -32.869677)
			(xy 125.576024 -32.925081) (xy 125.54604 -32.977015) (xy 125.509534 -33.024591) (xy 125.467129 -33.066996)
			(xy 125.419553 -33.103502) (xy 125.367619 -33.133486) (xy 125.312215 -33.156435) (xy 125.25429 -33.171956)
			(xy 125.194834 -33.179784) (xy 125.134866 -33.179784) (xy 125.07541 -33.171956) (xy 125.017485 -33.156435)
			(xy 124.962081 -33.133486) (xy 124.910147 -33.103502) (xy 124.862571 -33.066996) (xy 124.820166 -33.024591)
			(xy 124.78366 -32.977015) (xy 124.753676 -32.925081) (xy 124.730727 -32.869677) (xy 124.715206 -32.811752)
			(xy 124.707378 -32.752296) (xy 124.706888 -32.722312) (xy 97.762943 -32.722312) (xy 97.762586 -32.744168)
			(xy 97.754758 -32.803624) (xy 97.739237 -32.861549) (xy 97.716288 -32.916953) (xy 97.686304 -32.968887)
			(xy 97.649798 -33.016463) (xy 97.607393 -33.058868) (xy 97.559817 -33.095374) (xy 97.507883 -33.125358)
			(xy 97.452479 -33.148307) (xy 97.394554 -33.163828) (xy 97.335098 -33.171656) (xy 97.27513 -33.171656)
			(xy 97.215674 -33.163828) (xy 97.157749 -33.148307) (xy 97.102345 -33.125358) (xy 97.050411 -33.095374)
			(xy 97.002835 -33.058868) (xy 96.96043 -33.016463) (xy 96.923924 -32.968887) (xy 96.89394 -32.916953)
			(xy 96.870991 -32.861549) (xy 96.85547 -32.803624) (xy 96.847642 -32.744168) (xy 96.847152 -32.714184)
			(xy 87.522304 -32.714184) (xy 87.522304 -32.722312) (xy 87.521814 -32.75228) (xy 87.513991 -32.811702)
			(xy 87.498478 -32.869595) (xy 87.475542 -32.924968) (xy 87.445575 -32.976874) (xy 87.409088 -33.024424)
			(xy 87.366708 -33.066804) (xy 87.319158 -33.103291) (xy 87.267252 -33.133258) (xy 87.211879 -33.156194)
			(xy 87.153986 -33.171707) (xy 87.094564 -33.17953) (xy 87.034628 -33.17953) (xy 86.975206 -33.171707)
			(xy 86.917313 -33.156194) (xy 86.86194 -33.133258) (xy 86.810034 -33.103291) (xy 86.762484 -33.066804)
			(xy 86.720104 -33.024424) (xy 86.683617 -32.976874) (xy 86.65365 -32.924968) (xy 86.630714 -32.869595)
			(xy 86.615201 -32.811702) (xy 86.607378 -32.75228) (xy 86.606888 -32.722312) (xy 71.762995 -32.722312)
			(xy 71.762638 -32.744168) (xy 71.75481 -32.803624) (xy 71.739289 -32.861549) (xy 71.71634 -32.916953)
			(xy 71.686356 -32.968887) (xy 71.64985 -33.016463) (xy 71.607445 -33.058868) (xy 71.559869 -33.095374)
			(xy 71.507935 -33.125358) (xy 71.452531 -33.148307) (xy 71.394606 -33.163828) (xy 71.33515 -33.171656)
			(xy 71.275182 -33.171656) (xy 71.215726 -33.163828) (xy 71.157801 -33.148307) (xy 71.102397 -33.125358)
			(xy 71.050463 -33.095374) (xy 71.002887 -33.058868) (xy 70.960482 -33.016463) (xy 70.923976 -32.968887)
			(xy 70.893992 -32.916953) (xy 70.871043 -32.861549) (xy 70.855522 -32.803624) (xy 70.847694 -32.744168)
			(xy 70.847204 -32.714184) (xy 61.522356 -32.714184) (xy 61.522356 -32.722312) (xy 61.521866 -32.75228)
			(xy 61.514043 -32.811702) (xy 61.49853 -32.869595) (xy 61.475594 -32.924968) (xy 61.445627 -32.976874)
			(xy 61.40914 -33.024424) (xy 61.36676 -33.066804) (xy 61.31921 -33.103291) (xy 61.267304 -33.133258)
			(xy 61.211931 -33.156194) (xy 61.154038 -33.171707) (xy 61.094616 -33.17953) (xy 61.03468 -33.17953)
			(xy 60.975258 -33.171707) (xy 60.917365 -33.156194) (xy 60.861992 -33.133258) (xy 60.810086 -33.103291)
			(xy 60.762536 -33.066804) (xy 60.720156 -33.024424) (xy 60.683669 -32.976874) (xy 60.653702 -32.924968)
			(xy 60.630766 -32.869595) (xy 60.615253 -32.811702) (xy 60.60743 -32.75228) (xy 60.60694 -32.722312)
			(xy 45.763047 -32.722312) (xy 45.76269 -32.744168) (xy 45.754862 -32.803624) (xy 45.739341 -32.861549)
			(xy 45.716392 -32.916953) (xy 45.686408 -32.968887) (xy 45.649902 -33.016463) (xy 45.607497 -33.058868)
			(xy 45.559921 -33.095374) (xy 45.507987 -33.125358) (xy 45.452583 -33.148307) (xy 45.394658 -33.163828)
			(xy 45.335202 -33.171656) (xy 45.275234 -33.171656) (xy 45.215778 -33.163828) (xy 45.157853 -33.148307)
			(xy 45.102449 -33.125358) (xy 45.050515 -33.095374) (xy 45.002939 -33.058868) (xy 44.960534 -33.016463)
			(xy 44.924028 -32.968887) (xy 44.894044 -32.916953) (xy 44.871095 -32.861549) (xy 44.855574 -32.803624)
			(xy 44.847746 -32.744168) (xy 44.847256 -32.714184) (xy 35.522408 -32.714184) (xy 35.522408 -32.722312)
			(xy 35.521918 -32.75228) (xy 35.514095 -32.811702) (xy 35.498582 -32.869595) (xy 35.475646 -32.924968)
			(xy 35.445679 -32.976874) (xy 35.409192 -33.024424) (xy 35.366812 -33.066804) (xy 35.319262 -33.103291)
			(xy 35.267356 -33.133258) (xy 35.211983 -33.156194) (xy 35.15409 -33.171707) (xy 35.094668 -33.17953)
			(xy 35.034732 -33.17953) (xy 34.97531 -33.171707) (xy 34.917417 -33.156194) (xy 34.862044 -33.133258)
			(xy 34.810138 -33.103291) (xy 34.762588 -33.066804) (xy 34.720208 -33.024424) (xy 34.683721 -32.976874)
			(xy 34.653754 -32.924968) (xy 34.630818 -32.869595) (xy 34.615305 -32.811702) (xy 34.607482 -32.75228)
			(xy 34.606992 -32.722312) (xy 19.763099 -32.722312) (xy 19.762742 -32.744168) (xy 19.754914 -32.803624)
			(xy 19.739393 -32.861549) (xy 19.716444 -32.916953) (xy 19.68646 -32.968887) (xy 19.649954 -33.016463)
			(xy 19.607549 -33.058868) (xy 19.559973 -33.095374) (xy 19.508039 -33.125358) (xy 19.452635 -33.148307)
			(xy 19.39471 -33.163828) (xy 19.335254 -33.171656) (xy 19.275286 -33.171656) (xy 19.21583 -33.163828)
			(xy 19.157905 -33.148307) (xy 19.102501 -33.125358) (xy 19.050567 -33.095374) (xy 19.002991 -33.058868)
			(xy 18.960586 -33.016463) (xy 18.92408 -32.968887) (xy 18.894096 -32.916953) (xy 18.871147 -32.861549)
			(xy 18.855626 -32.803624) (xy 18.847798 -32.744168) (xy 18.847308 -32.714184) (xy 9.52246 -32.714184)
			(xy 9.52246 -32.722312) (xy 9.52197 -32.75228) (xy 9.514147 -32.811702) (xy 9.498634 -32.869595)
			(xy 9.475698 -32.924968) (xy 9.445731 -32.976874) (xy 9.409244 -33.024424) (xy 9.366864 -33.066804)
			(xy 9.319314 -33.103291) (xy 9.267408 -33.133258) (xy 9.212035 -33.156194) (xy 9.154142 -33.171707)
			(xy 9.09472 -33.17953) (xy 9.034784 -33.17953) (xy 8.975362 -33.171707) (xy 8.917469 -33.156194)
			(xy 8.862096 -33.133258) (xy 8.81019 -33.103291) (xy 8.76264 -33.066804) (xy 8.72026 -33.024424)
			(xy 8.683773 -32.976874) (xy 8.653806 -32.924968) (xy 8.63087 -32.869595) (xy 8.615357 -32.811702)
			(xy 8.607534 -32.75228) (xy 8.607044 -32.722312) (xy 0.508 -32.722312) (xy 0.508 -34.52241) (xy 6.752844 -34.52241)
			(xy 6.752844 -33.65881) (xy 6.753334 -33.628842) (xy 6.761157 -33.56942) (xy 6.77667 -33.511527)
			(xy 6.799606 -33.456154) (xy 6.829573 -33.404248) (xy 6.86606 -33.356698) (xy 6.90844 -33.314318)
			(xy 6.95599 -33.277831) (xy 7.007896 -33.247864) (xy 7.063269 -33.224928) (xy 7.121162 -33.209415)
			(xy 7.180584 -33.201592) (xy 7.24052 -33.201592) (xy 7.299942 -33.209415) (xy 7.357835 -33.224928)
			(xy 7.413208 -33.247864) (xy 7.465114 -33.277831) (xy 7.512664 -33.314318) (xy 7.555044 -33.356698)
			(xy 7.591531 -33.404248) (xy 7.621498 -33.456154) (xy 7.644434 -33.511527) (xy 7.659947 -33.56942)
			(xy 7.66777 -33.628842) (xy 7.66826 -33.65881) (xy 7.66826 -34.520886) (xy 21.489416 -34.520886)
			(xy 21.489416 -33.657286) (xy 21.489906 -33.627302) (xy 21.497734 -33.567846) (xy 21.513255 -33.509921)
			(xy 21.536204 -33.454517) (xy 21.566188 -33.402583) (xy 21.602694 -33.355007) (xy 21.645099 -33.312602)
			(xy 21.692675 -33.276096) (xy 21.744609 -33.246112) (xy 21.800013 -33.223163) (xy 21.857938 -33.207642)
			(xy 21.917394 -33.199814) (xy 21.977362 -33.199814) (xy 22.036818 -33.207642) (xy 22.094743 -33.223163)
			(xy 22.150147 -33.246112) (xy 22.202081 -33.276096) (xy 22.249657 -33.312602) (xy 22.292062 -33.355007)
			(xy 22.328568 -33.402583) (xy 22.358552 -33.454517) (xy 22.381501 -33.509921) (xy 22.397022 -33.567846)
			(xy 22.40485 -33.627302) (xy 22.40534 -33.657286) (xy 22.40534 -34.520886) (xy 22.405315 -34.52241)
			(xy 32.752792 -34.52241) (xy 32.752792 -33.65881) (xy 32.753282 -33.628842) (xy 32.761105 -33.56942)
			(xy 32.776618 -33.511527) (xy 32.799554 -33.456154) (xy 32.829521 -33.404248) (xy 32.866008 -33.356698)
			(xy 32.908388 -33.314318) (xy 32.955938 -33.277831) (xy 33.007844 -33.247864) (xy 33.063217 -33.224928)
			(xy 33.12111 -33.209415) (xy 33.180532 -33.201592) (xy 33.240468 -33.201592) (xy 33.29989 -33.209415)
			(xy 33.357783 -33.224928) (xy 33.413156 -33.247864) (xy 33.465062 -33.277831) (xy 33.512612 -33.314318)
			(xy 33.554992 -33.356698) (xy 33.591479 -33.404248) (xy 33.621446 -33.456154) (xy 33.644382 -33.511527)
			(xy 33.659895 -33.56942) (xy 33.667718 -33.628842) (xy 33.668208 -33.65881) (xy 33.668208 -34.520886)
			(xy 47.489364 -34.520886) (xy 47.489364 -33.657286) (xy 47.489854 -33.627302) (xy 47.497682 -33.567846)
			(xy 47.513203 -33.509921) (xy 47.536152 -33.454517) (xy 47.566136 -33.402583) (xy 47.602642 -33.355007)
			(xy 47.645047 -33.312602) (xy 47.692623 -33.276096) (xy 47.744557 -33.246112) (xy 47.799961 -33.223163)
			(xy 47.857886 -33.207642) (xy 47.917342 -33.199814) (xy 47.97731 -33.199814) (xy 48.036766 -33.207642)
			(xy 48.094691 -33.223163) (xy 48.150095 -33.246112) (xy 48.202029 -33.276096) (xy 48.249605 -33.312602)
			(xy 48.29201 -33.355007) (xy 48.328516 -33.402583) (xy 48.3585 -33.454517) (xy 48.381449 -33.509921)
			(xy 48.39697 -33.567846) (xy 48.404798 -33.627302) (xy 48.405288 -33.657286) (xy 48.405288 -34.520886)
			(xy 48.405263 -34.52241) (xy 58.75274 -34.52241) (xy 58.75274 -33.65881) (xy 58.75323 -33.628842)
			(xy 58.761053 -33.56942) (xy 58.776566 -33.511527) (xy 58.799502 -33.456154) (xy 58.829469 -33.404248)
			(xy 58.865956 -33.356698) (xy 58.908336 -33.314318) (xy 58.955886 -33.277831) (xy 59.007792 -33.247864)
			(xy 59.063165 -33.224928) (xy 59.121058 -33.209415) (xy 59.18048 -33.201592) (xy 59.240416 -33.201592)
			(xy 59.299838 -33.209415) (xy 59.357731 -33.224928) (xy 59.413104 -33.247864) (xy 59.46501 -33.277831)
			(xy 59.51256 -33.314318) (xy 59.55494 -33.356698) (xy 59.591427 -33.404248) (xy 59.621394 -33.456154)
			(xy 59.64433 -33.511527) (xy 59.659843 -33.56942) (xy 59.667666 -33.628842) (xy 59.668156 -33.65881)
			(xy 59.668156 -34.520886) (xy 73.489312 -34.520886) (xy 73.489312 -33.657286) (xy 73.489802 -33.627302)
			(xy 73.49763 -33.567846) (xy 73.513151 -33.509921) (xy 73.5361 -33.454517) (xy 73.566084 -33.402583)
			(xy 73.60259 -33.355007) (xy 73.644995 -33.312602) (xy 73.692571 -33.276096) (xy 73.744505 -33.246112)
			(xy 73.799909 -33.223163) (xy 73.857834 -33.207642) (xy 73.91729 -33.199814) (xy 73.977258 -33.199814)
			(xy 74.036714 -33.207642) (xy 74.094639 -33.223163) (xy 74.150043 -33.246112) (xy 74.201977 -33.276096)
			(xy 74.249553 -33.312602) (xy 74.291958 -33.355007) (xy 74.328464 -33.402583) (xy 74.358448 -33.454517)
			(xy 74.381397 -33.509921) (xy 74.396918 -33.567846) (xy 74.404746 -33.627302) (xy 74.405236 -33.657286)
			(xy 74.405236 -34.520886) (xy 74.405211 -34.52241) (xy 84.752688 -34.52241) (xy 84.752688 -33.65881)
			(xy 84.753178 -33.628842) (xy 84.761001 -33.56942) (xy 84.776514 -33.511527) (xy 84.79945 -33.456154)
			(xy 84.829417 -33.404248) (xy 84.865904 -33.356698) (xy 84.908284 -33.314318) (xy 84.955834 -33.277831)
			(xy 85.00774 -33.247864) (xy 85.063113 -33.224928) (xy 85.121006 -33.209415) (xy 85.180428 -33.201592)
			(xy 85.240364 -33.201592) (xy 85.299786 -33.209415) (xy 85.357679 -33.224928) (xy 85.413052 -33.247864)
			(xy 85.464958 -33.277831) (xy 85.512508 -33.314318) (xy 85.554888 -33.356698) (xy 85.591375 -33.404248)
			(xy 85.621342 -33.456154) (xy 85.644278 -33.511527) (xy 85.659791 -33.56942) (xy 85.667614 -33.628842)
			(xy 85.668104 -33.65881) (xy 85.668104 -34.520886) (xy 99.48926 -34.520886) (xy 99.48926 -33.657286)
			(xy 99.48975 -33.627302) (xy 99.497578 -33.567846) (xy 99.513099 -33.509921) (xy 99.536048 -33.454517)
			(xy 99.566032 -33.402583) (xy 99.602538 -33.355007) (xy 99.644943 -33.312602) (xy 99.692519 -33.276096)
			(xy 99.744453 -33.246112) (xy 99.799857 -33.223163) (xy 99.857782 -33.207642) (xy 99.917238 -33.199814)
			(xy 99.977206 -33.199814) (xy 100.036662 -33.207642) (xy 100.094587 -33.223163) (xy 100.149991 -33.246112)
			(xy 100.201925 -33.276096) (xy 100.249501 -33.312602) (xy 100.291906 -33.355007) (xy 100.328412 -33.402583)
			(xy 100.358396 -33.454517) (xy 100.381345 -33.509921) (xy 100.396866 -33.567846) (xy 100.404694 -33.627302)
			(xy 100.405184 -33.657286) (xy 100.405184 -34.520886) (xy 100.405159 -34.52241) (xy 122.852688 -34.52241)
			(xy 122.852688 -33.65881) (xy 122.853178 -33.628826) (xy 122.861006 -33.56937) (xy 122.876527 -33.511445)
			(xy 122.899476 -33.456041) (xy 122.92946 -33.404107) (xy 122.965966 -33.356531) (xy 123.008371 -33.314126)
			(xy 123.055947 -33.27762) (xy 123.107881 -33.247636) (xy 123.163285 -33.224687) (xy 123.22121 -33.209166)
			(xy 123.280666 -33.201338) (xy 123.340634 -33.201338) (xy 123.40009 -33.209166) (xy 123.458015 -33.224687)
			(xy 123.513419 -33.247636) (xy 123.565353 -33.27762) (xy 123.612929 -33.314126) (xy 123.655334 -33.356531)
			(xy 123.69184 -33.404107) (xy 123.721824 -33.456041) (xy 123.744773 -33.511445) (xy 123.760294 -33.56937)
			(xy 123.768122 -33.628826) (xy 123.768612 -33.65881) (xy 123.768612 -34.520886) (xy 137.589768 -34.520886)
			(xy 137.589768 -33.657286) (xy 137.590258 -33.627318) (xy 137.598081 -33.567896) (xy 137.613594 -33.510003)
			(xy 137.63653 -33.45463) (xy 137.666497 -33.402724) (xy 137.702984 -33.355174) (xy 137.745364 -33.312794)
			(xy 137.792914 -33.276307) (xy 137.84482 -33.24634) (xy 137.900193 -33.223404) (xy 137.958086 -33.207891)
			(xy 138.017508 -33.200068) (xy 138.077444 -33.200068) (xy 138.136866 -33.207891) (xy 138.194759 -33.223404)
			(xy 138.250132 -33.24634) (xy 138.302038 -33.276307) (xy 138.349588 -33.312794) (xy 138.391968 -33.355174)
			(xy 138.428455 -33.402724) (xy 138.458422 -33.45463) (xy 138.481358 -33.510003) (xy 138.496871 -33.567896)
			(xy 138.504694 -33.627318) (xy 138.505184 -33.657286) (xy 138.505184 -34.520886) (xy 138.505159 -34.52241)
			(xy 148.852636 -34.52241) (xy 148.852636 -33.65881) (xy 148.853126 -33.628826) (xy 148.860954 -33.56937)
			(xy 148.876475 -33.511445) (xy 148.899424 -33.456041) (xy 148.929408 -33.404107) (xy 148.965914 -33.356531)
			(xy 149.008319 -33.314126) (xy 149.055895 -33.27762) (xy 149.107829 -33.247636) (xy 149.163233 -33.224687)
			(xy 149.221158 -33.209166) (xy 149.280614 -33.201338) (xy 149.340582 -33.201338) (xy 149.400038 -33.209166)
			(xy 149.457963 -33.224687) (xy 149.513367 -33.247636) (xy 149.565301 -33.27762) (xy 149.612877 -33.314126)
			(xy 149.655282 -33.356531) (xy 149.691788 -33.404107) (xy 149.721772 -33.456041) (xy 149.744721 -33.511445)
			(xy 149.760242 -33.56937) (xy 149.76807 -33.628826) (xy 149.76856 -33.65881) (xy 149.76856 -34.520886)
			(xy 163.589716 -34.520886) (xy 163.589716 -33.657286) (xy 163.590206 -33.627318) (xy 163.598029 -33.567896)
			(xy 163.613542 -33.510003) (xy 163.636478 -33.45463) (xy 163.666445 -33.402724) (xy 163.702932 -33.355174)
			(xy 163.745312 -33.312794) (xy 163.792862 -33.276307) (xy 163.844768 -33.24634) (xy 163.900141 -33.223404)
			(xy 163.958034 -33.207891) (xy 164.017456 -33.200068) (xy 164.077392 -33.200068) (xy 164.136814 -33.207891)
			(xy 164.194707 -33.223404) (xy 164.25008 -33.24634) (xy 164.301986 -33.276307) (xy 164.349536 -33.312794)
			(xy 164.391916 -33.355174) (xy 164.428403 -33.402724) (xy 164.45837 -33.45463) (xy 164.481306 -33.510003)
			(xy 164.496819 -33.567896) (xy 164.504642 -33.627318) (xy 164.505132 -33.657286) (xy 164.505132 -34.520886)
			(xy 164.505107 -34.52241) (xy 174.852584 -34.52241) (xy 174.852584 -33.65881) (xy 174.853074 -33.628826)
			(xy 174.860902 -33.56937) (xy 174.876423 -33.511445) (xy 174.899372 -33.456041) (xy 174.929356 -33.404107)
			(xy 174.965862 -33.356531) (xy 175.008267 -33.314126) (xy 175.055843 -33.27762) (xy 175.107777 -33.247636)
			(xy 175.163181 -33.224687) (xy 175.221106 -33.209166) (xy 175.280562 -33.201338) (xy 175.34053 -33.201338)
			(xy 175.399986 -33.209166) (xy 175.457911 -33.224687) (xy 175.513315 -33.247636) (xy 175.565249 -33.27762)
			(xy 175.612825 -33.314126) (xy 175.65523 -33.356531) (xy 175.691736 -33.404107) (xy 175.72172 -33.456041)
			(xy 175.744669 -33.511445) (xy 175.76019 -33.56937) (xy 175.768018 -33.628826) (xy 175.768508 -33.65881)
			(xy 175.768508 -34.520886) (xy 189.589664 -34.520886) (xy 189.589664 -33.657286) (xy 189.590154 -33.627318)
			(xy 189.597977 -33.567896) (xy 189.61349 -33.510003) (xy 189.636426 -33.45463) (xy 189.666393 -33.402724)
			(xy 189.70288 -33.355174) (xy 189.74526 -33.312794) (xy 189.79281 -33.276307) (xy 189.844716 -33.24634)
			(xy 189.900089 -33.223404) (xy 189.957982 -33.207891) (xy 190.017404 -33.200068) (xy 190.07734 -33.200068)
			(xy 190.136762 -33.207891) (xy 190.194655 -33.223404) (xy 190.250028 -33.24634) (xy 190.301934 -33.276307)
			(xy 190.349484 -33.312794) (xy 190.391864 -33.355174) (xy 190.428351 -33.402724) (xy 190.458318 -33.45463)
			(xy 190.481254 -33.510003) (xy 190.496767 -33.567896) (xy 190.50459 -33.627318) (xy 190.50508 -33.657286)
			(xy 190.50508 -34.520886) (xy 190.505055 -34.52241) (xy 200.852532 -34.52241) (xy 200.852532 -33.65881)
			(xy 200.853022 -33.628826) (xy 200.86085 -33.56937) (xy 200.876371 -33.511445) (xy 200.89932 -33.456041)
			(xy 200.929304 -33.404107) (xy 200.96581 -33.356531) (xy 201.008215 -33.314126) (xy 201.055791 -33.27762)
			(xy 201.107725 -33.247636) (xy 201.163129 -33.224687) (xy 201.221054 -33.209166) (xy 201.28051 -33.201338)
			(xy 201.340478 -33.201338) (xy 201.399934 -33.209166) (xy 201.457859 -33.224687) (xy 201.513263 -33.247636)
			(xy 201.565197 -33.27762) (xy 201.612773 -33.314126) (xy 201.655178 -33.356531) (xy 201.691684 -33.404107)
			(xy 201.721668 -33.456041) (xy 201.744617 -33.511445) (xy 201.760138 -33.56937) (xy 201.767966 -33.628826)
			(xy 201.768456 -33.65881) (xy 201.768456 -34.520886) (xy 215.589612 -34.520886) (xy 215.589612 -33.657286)
			(xy 215.590102 -33.627318) (xy 215.597925 -33.567896) (xy 215.613438 -33.510003) (xy 215.636374 -33.45463)
			(xy 215.666341 -33.402724) (xy 215.702828 -33.355174) (xy 215.745208 -33.312794) (xy 215.792758 -33.276307)
			(xy 215.844664 -33.24634) (xy 215.900037 -33.223404) (xy 215.95793 -33.207891) (xy 216.017352 -33.200068)
			(xy 216.077288 -33.200068) (xy 216.13671 -33.207891) (xy 216.194603 -33.223404) (xy 216.249976 -33.24634)
			(xy 216.301882 -33.276307) (xy 216.349432 -33.312794) (xy 216.391812 -33.355174) (xy 216.428299 -33.402724)
			(xy 216.458266 -33.45463) (xy 216.481202 -33.510003) (xy 216.496715 -33.567896) (xy 216.504538 -33.627318)
			(xy 216.505028 -33.657286) (xy 216.505028 -34.520886) (xy 216.505003 -34.52241) (xy 238.952532 -34.52241)
			(xy 238.952532 -33.65881) (xy 238.953022 -33.628826) (xy 238.96085 -33.56937) (xy 238.976371 -33.511445)
			(xy 238.99932 -33.456041) (xy 239.029304 -33.404107) (xy 239.06581 -33.356531) (xy 239.108215 -33.314126)
			(xy 239.155791 -33.27762) (xy 239.207725 -33.247636) (xy 239.263129 -33.224687) (xy 239.321054 -33.209166)
			(xy 239.38051 -33.201338) (xy 239.440478 -33.201338) (xy 239.499934 -33.209166) (xy 239.557859 -33.224687)
			(xy 239.613263 -33.247636) (xy 239.665197 -33.27762) (xy 239.712773 -33.314126) (xy 239.755178 -33.356531)
			(xy 239.791684 -33.404107) (xy 239.821668 -33.456041) (xy 239.844617 -33.511445) (xy 239.860138 -33.56937)
			(xy 239.867966 -33.628826) (xy 239.868456 -33.65881) (xy 239.868456 -34.520886) (xy 253.689612 -34.520886)
			(xy 253.689612 -33.657286) (xy 253.690102 -33.627318) (xy 253.697925 -33.567896) (xy 253.713438 -33.510003)
			(xy 253.736374 -33.45463) (xy 253.766341 -33.402724) (xy 253.802828 -33.355174) (xy 253.845208 -33.312794)
			(xy 253.892758 -33.276307) (xy 253.944664 -33.24634) (xy 254.000037 -33.223404) (xy 254.05793 -33.207891)
			(xy 254.117352 -33.200068) (xy 254.177288 -33.200068) (xy 254.23671 -33.207891) (xy 254.294603 -33.223404)
			(xy 254.349976 -33.24634) (xy 254.401882 -33.276307) (xy 254.449432 -33.312794) (xy 254.491812 -33.355174)
			(xy 254.528299 -33.402724) (xy 254.558266 -33.45463) (xy 254.581202 -33.510003) (xy 254.596715 -33.567896)
			(xy 254.604538 -33.627318) (xy 254.605028 -33.657286) (xy 254.605028 -34.520886) (xy 254.605003 -34.52241)
			(xy 264.95248 -34.52241) (xy 264.95248 -33.65881) (xy 264.95297 -33.628826) (xy 264.960798 -33.56937)
			(xy 264.976319 -33.511445) (xy 264.999268 -33.456041) (xy 265.029252 -33.404107) (xy 265.065758 -33.356531)
			(xy 265.108163 -33.314126) (xy 265.155739 -33.27762) (xy 265.207673 -33.247636) (xy 265.263077 -33.224687)
			(xy 265.321002 -33.209166) (xy 265.380458 -33.201338) (xy 265.440426 -33.201338) (xy 265.499882 -33.209166)
			(xy 265.557807 -33.224687) (xy 265.613211 -33.247636) (xy 265.665145 -33.27762) (xy 265.712721 -33.314126)
			(xy 265.755126 -33.356531) (xy 265.791632 -33.404107) (xy 265.821616 -33.456041) (xy 265.844565 -33.511445)
			(xy 265.860086 -33.56937) (xy 265.867914 -33.628826) (xy 265.868404 -33.65881) (xy 265.868404 -34.520886)
			(xy 279.68956 -34.520886) (xy 279.68956 -33.657286) (xy 279.69005 -33.627318) (xy 279.697873 -33.567896)
			(xy 279.713386 -33.510003) (xy 279.736322 -33.45463) (xy 279.766289 -33.402724) (xy 279.802776 -33.355174)
			(xy 279.845156 -33.312794) (xy 279.892706 -33.276307) (xy 279.944612 -33.24634) (xy 279.999985 -33.223404)
			(xy 280.057878 -33.207891) (xy 280.1173 -33.200068) (xy 280.177236 -33.200068) (xy 280.236658 -33.207891)
			(xy 280.294551 -33.223404) (xy 280.349924 -33.24634) (xy 280.40183 -33.276307) (xy 280.44938 -33.312794)
			(xy 280.49176 -33.355174) (xy 280.528247 -33.402724) (xy 280.558214 -33.45463) (xy 280.58115 -33.510003)
			(xy 280.596663 -33.567896) (xy 280.604486 -33.627318) (xy 280.604976 -33.657286) (xy 280.604976 -34.520886)
			(xy 280.604951 -34.52241) (xy 290.952428 -34.52241) (xy 290.952428 -33.65881) (xy 290.952918 -33.628826)
			(xy 290.960746 -33.56937) (xy 290.976267 -33.511445) (xy 290.999216 -33.456041) (xy 291.0292 -33.404107)
			(xy 291.065706 -33.356531) (xy 291.108111 -33.314126) (xy 291.155687 -33.27762) (xy 291.207621 -33.247636)
			(xy 291.263025 -33.224687) (xy 291.32095 -33.209166) (xy 291.380406 -33.201338) (xy 291.440374 -33.201338)
			(xy 291.49983 -33.209166) (xy 291.557755 -33.224687) (xy 291.613159 -33.247636) (xy 291.665093 -33.27762)
			(xy 291.712669 -33.314126) (xy 291.755074 -33.356531) (xy 291.79158 -33.404107) (xy 291.821564 -33.456041)
			(xy 291.844513 -33.511445) (xy 291.860034 -33.56937) (xy 291.867862 -33.628826) (xy 291.868352 -33.65881)
			(xy 291.868352 -34.520886) (xy 305.689508 -34.520886) (xy 305.689508 -33.657286) (xy 305.689998 -33.627318)
			(xy 305.697821 -33.567896) (xy 305.713334 -33.510003) (xy 305.73627 -33.45463) (xy 305.766237 -33.402724)
			(xy 305.802724 -33.355174) (xy 305.845104 -33.312794) (xy 305.892654 -33.276307) (xy 305.94456 -33.24634)
			(xy 305.999933 -33.223404) (xy 306.057826 -33.207891) (xy 306.117248 -33.200068) (xy 306.177184 -33.200068)
			(xy 306.236606 -33.207891) (xy 306.294499 -33.223404) (xy 306.349872 -33.24634) (xy 306.401778 -33.276307)
			(xy 306.449328 -33.312794) (xy 306.491708 -33.355174) (xy 306.528195 -33.402724) (xy 306.558162 -33.45463)
			(xy 306.581098 -33.510003) (xy 306.596611 -33.567896) (xy 306.604434 -33.627318) (xy 306.604924 -33.657286)
			(xy 306.604924 -34.520886) (xy 306.604899 -34.52241) (xy 316.952376 -34.52241) (xy 316.952376 -33.65881)
			(xy 316.952866 -33.628826) (xy 316.960694 -33.56937) (xy 316.976215 -33.511445) (xy 316.999164 -33.456041)
			(xy 317.029148 -33.404107) (xy 317.065654 -33.356531) (xy 317.108059 -33.314126) (xy 317.155635 -33.27762)
			(xy 317.207569 -33.247636) (xy 317.262973 -33.224687) (xy 317.320898 -33.209166) (xy 317.380354 -33.201338)
			(xy 317.440322 -33.201338) (xy 317.499778 -33.209166) (xy 317.557703 -33.224687) (xy 317.613107 -33.247636)
			(xy 317.665041 -33.27762) (xy 317.712617 -33.314126) (xy 317.755022 -33.356531) (xy 317.791528 -33.404107)
			(xy 317.821512 -33.456041) (xy 317.844461 -33.511445) (xy 317.859982 -33.56937) (xy 317.86781 -33.628826)
			(xy 317.8683 -33.65881) (xy 317.8683 -34.520886) (xy 331.689456 -34.520886) (xy 331.689456 -33.657286)
			(xy 331.689946 -33.627318) (xy 331.697769 -33.567896) (xy 331.713282 -33.510003) (xy 331.736218 -33.45463)
			(xy 331.766185 -33.402724) (xy 331.802672 -33.355174) (xy 331.845052 -33.312794) (xy 331.892602 -33.276307)
			(xy 331.944508 -33.24634) (xy 331.999881 -33.223404) (xy 332.057774 -33.207891) (xy 332.117196 -33.200068)
			(xy 332.177132 -33.200068) (xy 332.236554 -33.207891) (xy 332.294447 -33.223404) (xy 332.34982 -33.24634)
			(xy 332.401726 -33.276307) (xy 332.449276 -33.312794) (xy 332.491656 -33.355174) (xy 332.528143 -33.402724)
			(xy 332.55811 -33.45463) (xy 332.581046 -33.510003) (xy 332.596559 -33.567896) (xy 332.604382 -33.627318)
			(xy 332.604872 -33.657286) (xy 332.604872 -34.520886) (xy 332.604847 -34.52241) (xy 355.052884 -34.52241)
			(xy 355.052884 -33.65881) (xy 355.053374 -33.628842) (xy 355.061197 -33.56942) (xy 355.07671 -33.511527)
			(xy 355.099646 -33.456154) (xy 355.129613 -33.404248) (xy 355.1661 -33.356698) (xy 355.20848 -33.314318)
			(xy 355.25603 -33.277831) (xy 355.307936 -33.247864) (xy 355.363309 -33.224928) (xy 355.421202 -33.209415)
			(xy 355.480624 -33.201592) (xy 355.54056 -33.201592) (xy 355.599982 -33.209415) (xy 355.657875 -33.224928)
			(xy 355.713248 -33.247864) (xy 355.765154 -33.277831) (xy 355.812704 -33.314318) (xy 355.855084 -33.356698)
			(xy 355.891571 -33.404248) (xy 355.921538 -33.456154) (xy 355.944474 -33.511527) (xy 355.959987 -33.56942)
			(xy 355.96781 -33.628842) (xy 355.9683 -33.65881) (xy 355.9683 -34.520886) (xy 369.789456 -34.520886)
			(xy 369.789456 -33.657286) (xy 369.789946 -33.627302) (xy 369.797774 -33.567846) (xy 369.813295 -33.509921)
			(xy 369.836244 -33.454517) (xy 369.866228 -33.402583) (xy 369.902734 -33.355007) (xy 369.945139 -33.312602)
			(xy 369.992715 -33.276096) (xy 370.044649 -33.246112) (xy 370.100053 -33.223163) (xy 370.157978 -33.207642)
			(xy 370.217434 -33.199814) (xy 370.277402 -33.199814) (xy 370.336858 -33.207642) (xy 370.394783 -33.223163)
			(xy 370.450187 -33.246112) (xy 370.502121 -33.276096) (xy 370.549697 -33.312602) (xy 370.592102 -33.355007)
			(xy 370.628608 -33.402583) (xy 370.658592 -33.454517) (xy 370.681541 -33.509921) (xy 370.697062 -33.567846)
			(xy 370.70489 -33.627302) (xy 370.70538 -33.657286) (xy 370.70538 -34.520886) (xy 370.705355 -34.52241)
			(xy 381.052832 -34.52241) (xy 381.052832 -33.65881) (xy 381.053322 -33.628842) (xy 381.061145 -33.56942)
			(xy 381.076658 -33.511527) (xy 381.099594 -33.456154) (xy 381.129561 -33.404248) (xy 381.166048 -33.356698)
			(xy 381.208428 -33.314318) (xy 381.255978 -33.277831) (xy 381.307884 -33.247864) (xy 381.363257 -33.224928)
			(xy 381.42115 -33.209415) (xy 381.480572 -33.201592) (xy 381.540508 -33.201592) (xy 381.59993 -33.209415)
			(xy 381.657823 -33.224928) (xy 381.713196 -33.247864) (xy 381.765102 -33.277831) (xy 381.812652 -33.314318)
			(xy 381.855032 -33.356698) (xy 381.891519 -33.404248) (xy 381.921486 -33.456154) (xy 381.944422 -33.511527)
			(xy 381.959935 -33.56942) (xy 381.967758 -33.628842) (xy 381.968248 -33.65881) (xy 381.968248 -34.520886)
			(xy 395.789404 -34.520886) (xy 395.789404 -33.657286) (xy 395.789894 -33.627302) (xy 395.797722 -33.567846)
			(xy 395.813243 -33.509921) (xy 395.836192 -33.454517) (xy 395.866176 -33.402583) (xy 395.902682 -33.355007)
			(xy 395.945087 -33.312602) (xy 395.992663 -33.276096) (xy 396.044597 -33.246112) (xy 396.100001 -33.223163)
			(xy 396.157926 -33.207642) (xy 396.217382 -33.199814) (xy 396.27735 -33.199814) (xy 396.336806 -33.207642)
			(xy 396.394731 -33.223163) (xy 396.450135 -33.246112) (xy 396.502069 -33.276096) (xy 396.549645 -33.312602)
			(xy 396.59205 -33.355007) (xy 396.628556 -33.402583) (xy 396.65854 -33.454517) (xy 396.681489 -33.509921)
			(xy 396.69701 -33.567846) (xy 396.704838 -33.627302) (xy 396.705328 -33.657286) (xy 396.705328 -34.520886)
			(xy 396.705303 -34.52241) (xy 407.05278 -34.52241) (xy 407.05278 -33.65881) (xy 407.05327 -33.628842)
			(xy 407.061093 -33.56942) (xy 407.076606 -33.511527) (xy 407.099542 -33.456154) (xy 407.129509 -33.404248)
			(xy 407.165996 -33.356698) (xy 407.208376 -33.314318) (xy 407.255926 -33.277831) (xy 407.307832 -33.247864)
			(xy 407.363205 -33.224928) (xy 407.421098 -33.209415) (xy 407.48052 -33.201592) (xy 407.540456 -33.201592)
			(xy 407.599878 -33.209415) (xy 407.657771 -33.224928) (xy 407.713144 -33.247864) (xy 407.76505 -33.277831)
			(xy 407.8126 -33.314318) (xy 407.85498 -33.356698) (xy 407.891467 -33.404248) (xy 407.921434 -33.456154)
			(xy 407.94437 -33.511527) (xy 407.959883 -33.56942) (xy 407.967706 -33.628842) (xy 407.968196 -33.65881)
			(xy 407.968196 -34.520886) (xy 421.789352 -34.520886) (xy 421.789352 -33.657286) (xy 421.789842 -33.627302)
			(xy 421.79767 -33.567846) (xy 421.813191 -33.509921) (xy 421.83614 -33.454517) (xy 421.866124 -33.402583)
			(xy 421.90263 -33.355007) (xy 421.945035 -33.312602) (xy 421.992611 -33.276096) (xy 422.044545 -33.246112)
			(xy 422.099949 -33.223163) (xy 422.157874 -33.207642) (xy 422.21733 -33.199814) (xy 422.277298 -33.199814)
			(xy 422.336754 -33.207642) (xy 422.394679 -33.223163) (xy 422.450083 -33.246112) (xy 422.502017 -33.276096)
			(xy 422.549593 -33.312602) (xy 422.591998 -33.355007) (xy 422.628504 -33.402583) (xy 422.658488 -33.454517)
			(xy 422.681437 -33.509921) (xy 422.696958 -33.567846) (xy 422.704786 -33.627302) (xy 422.705276 -33.657286)
			(xy 422.705276 -34.520886) (xy 422.705251 -34.52241) (xy 433.052728 -34.52241) (xy 433.052728 -33.65881)
			(xy 433.053218 -33.628842) (xy 433.061041 -33.56942) (xy 433.076554 -33.511527) (xy 433.09949 -33.456154)
			(xy 433.129457 -33.404248) (xy 433.165944 -33.356698) (xy 433.208324 -33.314318) (xy 433.255874 -33.277831)
			(xy 433.30778 -33.247864) (xy 433.363153 -33.224928) (xy 433.421046 -33.209415) (xy 433.480468 -33.201592)
			(xy 433.540404 -33.201592) (xy 433.599826 -33.209415) (xy 433.657719 -33.224928) (xy 433.713092 -33.247864)
			(xy 433.764998 -33.277831) (xy 433.812548 -33.314318) (xy 433.854928 -33.356698) (xy 433.891415 -33.404248)
			(xy 433.921382 -33.456154) (xy 433.944318 -33.511527) (xy 433.959831 -33.56942) (xy 433.967654 -33.628842)
			(xy 433.968144 -33.65881) (xy 433.968144 -34.520886) (xy 447.7893 -34.520886) (xy 447.7893 -33.657286)
			(xy 447.78979 -33.627302) (xy 447.797618 -33.567846) (xy 447.813139 -33.509921) (xy 447.836088 -33.454517)
			(xy 447.866072 -33.402583) (xy 447.902578 -33.355007) (xy 447.944983 -33.312602) (xy 447.992559 -33.276096)
			(xy 448.044493 -33.246112) (xy 448.099897 -33.223163) (xy 448.157822 -33.207642) (xy 448.217278 -33.199814)
			(xy 448.277246 -33.199814) (xy 448.336702 -33.207642) (xy 448.394627 -33.223163) (xy 448.450031 -33.246112)
			(xy 448.501965 -33.276096) (xy 448.549541 -33.312602) (xy 448.591946 -33.355007) (xy 448.628452 -33.402583)
			(xy 448.658436 -33.454517) (xy 448.681385 -33.509921) (xy 448.696906 -33.567846) (xy 448.704734 -33.627302)
			(xy 448.705224 -33.657286) (xy 448.705224 -34.520886) (xy 448.704734 -34.55087) (xy 448.696906 -34.610326)
			(xy 448.681385 -34.668251) (xy 448.658436 -34.723655) (xy 448.628452 -34.775589) (xy 448.591946 -34.823165)
			(xy 448.549541 -34.86557) (xy 448.501965 -34.902076) (xy 448.450031 -34.93206) (xy 448.394627 -34.955009)
			(xy 448.336702 -34.97053) (xy 448.277246 -34.978358) (xy 448.217278 -34.978358) (xy 448.157822 -34.97053)
			(xy 448.099897 -34.955009) (xy 448.044493 -34.93206) (xy 447.992559 -34.902076) (xy 447.944983 -34.86557)
			(xy 447.902578 -34.823165) (xy 447.866072 -34.775589) (xy 447.836088 -34.723655) (xy 447.813139 -34.668251)
			(xy 447.797618 -34.610326) (xy 447.78979 -34.55087) (xy 447.7893 -34.520886) (xy 433.968144 -34.520886)
			(xy 433.968144 -34.52241) (xy 433.967654 -34.552378) (xy 433.959831 -34.6118) (xy 433.944318 -34.669693)
			(xy 433.921382 -34.725066) (xy 433.891415 -34.776972) (xy 433.854928 -34.824522) (xy 433.812548 -34.866902)
			(xy 433.764998 -34.903389) (xy 433.713092 -34.933356) (xy 433.657719 -34.956292) (xy 433.599826 -34.971805)
			(xy 433.540404 -34.979628) (xy 433.480468 -34.979628) (xy 433.421046 -34.971805) (xy 433.363153 -34.956292)
			(xy 433.30778 -34.933356) (xy 433.255874 -34.903389) (xy 433.208324 -34.866902) (xy 433.165944 -34.824522)
			(xy 433.129457 -34.776972) (xy 433.09949 -34.725066) (xy 433.076554 -34.669693) (xy 433.061041 -34.6118)
			(xy 433.053218 -34.552378) (xy 433.052728 -34.52241) (xy 422.705251 -34.52241) (xy 422.704786 -34.55087)
			(xy 422.696958 -34.610326) (xy 422.681437 -34.668251) (xy 422.658488 -34.723655) (xy 422.628504 -34.775589)
			(xy 422.591998 -34.823165) (xy 422.549593 -34.86557) (xy 422.502017 -34.902076) (xy 422.450083 -34.93206)
			(xy 422.394679 -34.955009) (xy 422.336754 -34.97053) (xy 422.277298 -34.978358) (xy 422.21733 -34.978358)
			(xy 422.157874 -34.97053) (xy 422.099949 -34.955009) (xy 422.044545 -34.93206) (xy 421.992611 -34.902076)
			(xy 421.945035 -34.86557) (xy 421.90263 -34.823165) (xy 421.866124 -34.775589) (xy 421.83614 -34.723655)
			(xy 421.813191 -34.668251) (xy 421.79767 -34.610326) (xy 421.789842 -34.55087) (xy 421.789352 -34.520886)
			(xy 407.968196 -34.520886) (xy 407.968196 -34.52241) (xy 407.967706 -34.552378) (xy 407.959883 -34.6118)
			(xy 407.94437 -34.669693) (xy 407.921434 -34.725066) (xy 407.891467 -34.776972) (xy 407.85498 -34.824522)
			(xy 407.8126 -34.866902) (xy 407.76505 -34.903389) (xy 407.713144 -34.933356) (xy 407.657771 -34.956292)
			(xy 407.599878 -34.971805) (xy 407.540456 -34.979628) (xy 407.48052 -34.979628) (xy 407.421098 -34.971805)
			(xy 407.363205 -34.956292) (xy 407.307832 -34.933356) (xy 407.255926 -34.903389) (xy 407.208376 -34.866902)
			(xy 407.165996 -34.824522) (xy 407.129509 -34.776972) (xy 407.099542 -34.725066) (xy 407.076606 -34.669693)
			(xy 407.061093 -34.6118) (xy 407.05327 -34.552378) (xy 407.05278 -34.52241) (xy 396.705303 -34.52241)
			(xy 396.704838 -34.55087) (xy 396.69701 -34.610326) (xy 396.681489 -34.668251) (xy 396.65854 -34.723655)
			(xy 396.628556 -34.775589) (xy 396.59205 -34.823165) (xy 396.549645 -34.86557) (xy 396.502069 -34.902076)
			(xy 396.450135 -34.93206) (xy 396.394731 -34.955009) (xy 396.336806 -34.97053) (xy 396.27735 -34.978358)
			(xy 396.217382 -34.978358) (xy 396.157926 -34.97053) (xy 396.100001 -34.955009) (xy 396.044597 -34.93206)
			(xy 395.992663 -34.902076) (xy 395.945087 -34.86557) (xy 395.902682 -34.823165) (xy 395.866176 -34.775589)
			(xy 395.836192 -34.723655) (xy 395.813243 -34.668251) (xy 395.797722 -34.610326) (xy 395.789894 -34.55087)
			(xy 395.789404 -34.520886) (xy 381.968248 -34.520886) (xy 381.968248 -34.52241) (xy 381.967758 -34.552378)
			(xy 381.959935 -34.6118) (xy 381.944422 -34.669693) (xy 381.921486 -34.725066) (xy 381.891519 -34.776972)
			(xy 381.855032 -34.824522) (xy 381.812652 -34.866902) (xy 381.765102 -34.903389) (xy 381.713196 -34.933356)
			(xy 381.657823 -34.956292) (xy 381.59993 -34.971805) (xy 381.540508 -34.979628) (xy 381.480572 -34.979628)
			(xy 381.42115 -34.971805) (xy 381.363257 -34.956292) (xy 381.307884 -34.933356) (xy 381.255978 -34.903389)
			(xy 381.208428 -34.866902) (xy 381.166048 -34.824522) (xy 381.129561 -34.776972) (xy 381.099594 -34.725066)
			(xy 381.076658 -34.669693) (xy 381.061145 -34.6118) (xy 381.053322 -34.552378) (xy 381.052832 -34.52241)
			(xy 370.705355 -34.52241) (xy 370.70489 -34.55087) (xy 370.697062 -34.610326) (xy 370.681541 -34.668251)
			(xy 370.658592 -34.723655) (xy 370.628608 -34.775589) (xy 370.592102 -34.823165) (xy 370.549697 -34.86557)
			(xy 370.502121 -34.902076) (xy 370.450187 -34.93206) (xy 370.394783 -34.955009) (xy 370.336858 -34.97053)
			(xy 370.277402 -34.978358) (xy 370.217434 -34.978358) (xy 370.157978 -34.97053) (xy 370.100053 -34.955009)
			(xy 370.044649 -34.93206) (xy 369.992715 -34.902076) (xy 369.945139 -34.86557) (xy 369.902734 -34.823165)
			(xy 369.866228 -34.775589) (xy 369.836244 -34.723655) (xy 369.813295 -34.668251) (xy 369.797774 -34.610326)
			(xy 369.789946 -34.55087) (xy 369.789456 -34.520886) (xy 355.9683 -34.520886) (xy 355.9683 -34.52241)
			(xy 355.96781 -34.552378) (xy 355.959987 -34.6118) (xy 355.944474 -34.669693) (xy 355.921538 -34.725066)
			(xy 355.891571 -34.776972) (xy 355.855084 -34.824522) (xy 355.812704 -34.866902) (xy 355.765154 -34.903389)
			(xy 355.713248 -34.933356) (xy 355.657875 -34.956292) (xy 355.599982 -34.971805) (xy 355.54056 -34.979628)
			(xy 355.480624 -34.979628) (xy 355.421202 -34.971805) (xy 355.363309 -34.956292) (xy 355.307936 -34.933356)
			(xy 355.25603 -34.903389) (xy 355.20848 -34.866902) (xy 355.1661 -34.824522) (xy 355.129613 -34.776972)
			(xy 355.099646 -34.725066) (xy 355.07671 -34.669693) (xy 355.061197 -34.6118) (xy 355.053374 -34.552378)
			(xy 355.052884 -34.52241) (xy 332.604847 -34.52241) (xy 332.604382 -34.550854) (xy 332.596559 -34.610276)
			(xy 332.581046 -34.668169) (xy 332.55811 -34.723542) (xy 332.528143 -34.775448) (xy 332.491656 -34.822998)
			(xy 332.449276 -34.865378) (xy 332.401726 -34.901865) (xy 332.34982 -34.931832) (xy 332.294447 -34.954768)
			(xy 332.236554 -34.970281) (xy 332.177132 -34.978104) (xy 332.117196 -34.978104) (xy 332.057774 -34.970281)
			(xy 331.999881 -34.954768) (xy 331.944508 -34.931832) (xy 331.892602 -34.901865) (xy 331.845052 -34.865378)
			(xy 331.802672 -34.822998) (xy 331.766185 -34.775448) (xy 331.736218 -34.723542) (xy 331.713282 -34.668169)
			(xy 331.697769 -34.610276) (xy 331.689946 -34.550854) (xy 331.689456 -34.520886) (xy 317.8683 -34.520886)
			(xy 317.8683 -34.52241) (xy 317.86781 -34.552394) (xy 317.859982 -34.61185) (xy 317.844461 -34.669775)
			(xy 317.821512 -34.725179) (xy 317.791528 -34.777113) (xy 317.755022 -34.824689) (xy 317.712617 -34.867094)
			(xy 317.665041 -34.9036) (xy 317.613107 -34.933584) (xy 317.557703 -34.956533) (xy 317.499778 -34.972054)
			(xy 317.440322 -34.979882) (xy 317.380354 -34.979882) (xy 317.320898 -34.972054) (xy 317.262973 -34.956533)
			(xy 317.207569 -34.933584) (xy 317.155635 -34.9036) (xy 317.108059 -34.867094) (xy 317.065654 -34.824689)
			(xy 317.029148 -34.777113) (xy 316.999164 -34.725179) (xy 316.976215 -34.669775) (xy 316.960694 -34.61185)
			(xy 316.952866 -34.552394) (xy 316.952376 -34.52241) (xy 306.604899 -34.52241) (xy 306.604434 -34.550854)
			(xy 306.596611 -34.610276) (xy 306.581098 -34.668169) (xy 306.558162 -34.723542) (xy 306.528195 -34.775448)
			(xy 306.491708 -34.822998) (xy 306.449328 -34.865378) (xy 306.401778 -34.901865) (xy 306.349872 -34.931832)
			(xy 306.294499 -34.954768) (xy 306.236606 -34.970281) (xy 306.177184 -34.978104) (xy 306.117248 -34.978104)
			(xy 306.057826 -34.970281) (xy 305.999933 -34.954768) (xy 305.94456 -34.931832) (xy 305.892654 -34.901865)
			(xy 305.845104 -34.865378) (xy 305.802724 -34.822998) (xy 305.766237 -34.775448) (xy 305.73627 -34.723542)
			(xy 305.713334 -34.668169) (xy 305.697821 -34.610276) (xy 305.689998 -34.550854) (xy 305.689508 -34.520886)
			(xy 291.868352 -34.520886) (xy 291.868352 -34.52241) (xy 291.867862 -34.552394) (xy 291.860034 -34.61185)
			(xy 291.844513 -34.669775) (xy 291.821564 -34.725179) (xy 291.79158 -34.777113) (xy 291.755074 -34.824689)
			(xy 291.712669 -34.867094) (xy 291.665093 -34.9036) (xy 291.613159 -34.933584) (xy 291.557755 -34.956533)
			(xy 291.49983 -34.972054) (xy 291.440374 -34.979882) (xy 291.380406 -34.979882) (xy 291.32095 -34.972054)
			(xy 291.263025 -34.956533) (xy 291.207621 -34.933584) (xy 291.155687 -34.9036) (xy 291.108111 -34.867094)
			(xy 291.065706 -34.824689) (xy 291.0292 -34.777113) (xy 290.999216 -34.725179) (xy 290.976267 -34.669775)
			(xy 290.960746 -34.61185) (xy 290.952918 -34.552394) (xy 290.952428 -34.52241) (xy 280.604951 -34.52241)
			(xy 280.604486 -34.550854) (xy 280.596663 -34.610276) (xy 280.58115 -34.668169) (xy 280.558214 -34.723542)
			(xy 280.528247 -34.775448) (xy 280.49176 -34.822998) (xy 280.44938 -34.865378) (xy 280.40183 -34.901865)
			(xy 280.349924 -34.931832) (xy 280.294551 -34.954768) (xy 280.236658 -34.970281) (xy 280.177236 -34.978104)
			(xy 280.1173 -34.978104) (xy 280.057878 -34.970281) (xy 279.999985 -34.954768) (xy 279.944612 -34.931832)
			(xy 279.892706 -34.901865) (xy 279.845156 -34.865378) (xy 279.802776 -34.822998) (xy 279.766289 -34.775448)
			(xy 279.736322 -34.723542) (xy 279.713386 -34.668169) (xy 279.697873 -34.610276) (xy 279.69005 -34.550854)
			(xy 279.68956 -34.520886) (xy 265.868404 -34.520886) (xy 265.868404 -34.52241) (xy 265.867914 -34.552394)
			(xy 265.860086 -34.61185) (xy 265.844565 -34.669775) (xy 265.821616 -34.725179) (xy 265.791632 -34.777113)
			(xy 265.755126 -34.824689) (xy 265.712721 -34.867094) (xy 265.665145 -34.9036) (xy 265.613211 -34.933584)
			(xy 265.557807 -34.956533) (xy 265.499882 -34.972054) (xy 265.440426 -34.979882) (xy 265.380458 -34.979882)
			(xy 265.321002 -34.972054) (xy 265.263077 -34.956533) (xy 265.207673 -34.933584) (xy 265.155739 -34.9036)
			(xy 265.108163 -34.867094) (xy 265.065758 -34.824689) (xy 265.029252 -34.777113) (xy 264.999268 -34.725179)
			(xy 264.976319 -34.669775) (xy 264.960798 -34.61185) (xy 264.95297 -34.552394) (xy 264.95248 -34.52241)
			(xy 254.605003 -34.52241) (xy 254.604538 -34.550854) (xy 254.596715 -34.610276) (xy 254.581202 -34.668169)
			(xy 254.558266 -34.723542) (xy 254.528299 -34.775448) (xy 254.491812 -34.822998) (xy 254.449432 -34.865378)
			(xy 254.401882 -34.901865) (xy 254.349976 -34.931832) (xy 254.294603 -34.954768) (xy 254.23671 -34.970281)
			(xy 254.177288 -34.978104) (xy 254.117352 -34.978104) (xy 254.05793 -34.970281) (xy 254.000037 -34.954768)
			(xy 253.944664 -34.931832) (xy 253.892758 -34.901865) (xy 253.845208 -34.865378) (xy 253.802828 -34.822998)
			(xy 253.766341 -34.775448) (xy 253.736374 -34.723542) (xy 253.713438 -34.668169) (xy 253.697925 -34.610276)
			(xy 253.690102 -34.550854) (xy 253.689612 -34.520886) (xy 239.868456 -34.520886) (xy 239.868456 -34.52241)
			(xy 239.867966 -34.552394) (xy 239.860138 -34.61185) (xy 239.844617 -34.669775) (xy 239.821668 -34.725179)
			(xy 239.791684 -34.777113) (xy 239.755178 -34.824689) (xy 239.712773 -34.867094) (xy 239.665197 -34.9036)
			(xy 239.613263 -34.933584) (xy 239.557859 -34.956533) (xy 239.499934 -34.972054) (xy 239.440478 -34.979882)
			(xy 239.38051 -34.979882) (xy 239.321054 -34.972054) (xy 239.263129 -34.956533) (xy 239.207725 -34.933584)
			(xy 239.155791 -34.9036) (xy 239.108215 -34.867094) (xy 239.06581 -34.824689) (xy 239.029304 -34.777113)
			(xy 238.99932 -34.725179) (xy 238.976371 -34.669775) (xy 238.96085 -34.61185) (xy 238.953022 -34.552394)
			(xy 238.952532 -34.52241) (xy 216.505003 -34.52241) (xy 216.504538 -34.550854) (xy 216.496715 -34.610276)
			(xy 216.481202 -34.668169) (xy 216.458266 -34.723542) (xy 216.428299 -34.775448) (xy 216.391812 -34.822998)
			(xy 216.349432 -34.865378) (xy 216.301882 -34.901865) (xy 216.249976 -34.931832) (xy 216.194603 -34.954768)
			(xy 216.13671 -34.970281) (xy 216.077288 -34.978104) (xy 216.017352 -34.978104) (xy 215.95793 -34.970281)
			(xy 215.900037 -34.954768) (xy 215.844664 -34.931832) (xy 215.792758 -34.901865) (xy 215.745208 -34.865378)
			(xy 215.702828 -34.822998) (xy 215.666341 -34.775448) (xy 215.636374 -34.723542) (xy 215.613438 -34.668169)
			(xy 215.597925 -34.610276) (xy 215.590102 -34.550854) (xy 215.589612 -34.520886) (xy 201.768456 -34.520886)
			(xy 201.768456 -34.52241) (xy 201.767966 -34.552394) (xy 201.760138 -34.61185) (xy 201.744617 -34.669775)
			(xy 201.721668 -34.725179) (xy 201.691684 -34.777113) (xy 201.655178 -34.824689) (xy 201.612773 -34.867094)
			(xy 201.565197 -34.9036) (xy 201.513263 -34.933584) (xy 201.457859 -34.956533) (xy 201.399934 -34.972054)
			(xy 201.340478 -34.979882) (xy 201.28051 -34.979882) (xy 201.221054 -34.972054) (xy 201.163129 -34.956533)
			(xy 201.107725 -34.933584) (xy 201.055791 -34.9036) (xy 201.008215 -34.867094) (xy 200.96581 -34.824689)
			(xy 200.929304 -34.777113) (xy 200.89932 -34.725179) (xy 200.876371 -34.669775) (xy 200.86085 -34.61185)
			(xy 200.853022 -34.552394) (xy 200.852532 -34.52241) (xy 190.505055 -34.52241) (xy 190.50459 -34.550854)
			(xy 190.496767 -34.610276) (xy 190.481254 -34.668169) (xy 190.458318 -34.723542) (xy 190.428351 -34.775448)
			(xy 190.391864 -34.822998) (xy 190.349484 -34.865378) (xy 190.301934 -34.901865) (xy 190.250028 -34.931832)
			(xy 190.194655 -34.954768) (xy 190.136762 -34.970281) (xy 190.07734 -34.978104) (xy 190.017404 -34.978104)
			(xy 189.957982 -34.970281) (xy 189.900089 -34.954768) (xy 189.844716 -34.931832) (xy 189.79281 -34.901865)
			(xy 189.74526 -34.865378) (xy 189.70288 -34.822998) (xy 189.666393 -34.775448) (xy 189.636426 -34.723542)
			(xy 189.61349 -34.668169) (xy 189.597977 -34.610276) (xy 189.590154 -34.550854) (xy 189.589664 -34.520886)
			(xy 175.768508 -34.520886) (xy 175.768508 -34.52241) (xy 175.768018 -34.552394) (xy 175.76019 -34.61185)
			(xy 175.744669 -34.669775) (xy 175.72172 -34.725179) (xy 175.691736 -34.777113) (xy 175.65523 -34.824689)
			(xy 175.612825 -34.867094) (xy 175.565249 -34.9036) (xy 175.513315 -34.933584) (xy 175.457911 -34.956533)
			(xy 175.399986 -34.972054) (xy 175.34053 -34.979882) (xy 175.280562 -34.979882) (xy 175.221106 -34.972054)
			(xy 175.163181 -34.956533) (xy 175.107777 -34.933584) (xy 175.055843 -34.9036) (xy 175.008267 -34.867094)
			(xy 174.965862 -34.824689) (xy 174.929356 -34.777113) (xy 174.899372 -34.725179) (xy 174.876423 -34.669775)
			(xy 174.860902 -34.61185) (xy 174.853074 -34.552394) (xy 174.852584 -34.52241) (xy 164.505107 -34.52241)
			(xy 164.504642 -34.550854) (xy 164.496819 -34.610276) (xy 164.481306 -34.668169) (xy 164.45837 -34.723542)
			(xy 164.428403 -34.775448) (xy 164.391916 -34.822998) (xy 164.349536 -34.865378) (xy 164.301986 -34.901865)
			(xy 164.25008 -34.931832) (xy 164.194707 -34.954768) (xy 164.136814 -34.970281) (xy 164.077392 -34.978104)
			(xy 164.017456 -34.978104) (xy 163.958034 -34.970281) (xy 163.900141 -34.954768) (xy 163.844768 -34.931832)
			(xy 163.792862 -34.901865) (xy 163.745312 -34.865378) (xy 163.702932 -34.822998) (xy 163.666445 -34.775448)
			(xy 163.636478 -34.723542) (xy 163.613542 -34.668169) (xy 163.598029 -34.610276) (xy 163.590206 -34.550854)
			(xy 163.589716 -34.520886) (xy 149.76856 -34.520886) (xy 149.76856 -34.52241) (xy 149.76807 -34.552394)
			(xy 149.760242 -34.61185) (xy 149.744721 -34.669775) (xy 149.721772 -34.725179) (xy 149.691788 -34.777113)
			(xy 149.655282 -34.824689) (xy 149.612877 -34.867094) (xy 149.565301 -34.9036) (xy 149.513367 -34.933584)
			(xy 149.457963 -34.956533) (xy 149.400038 -34.972054) (xy 149.340582 -34.979882) (xy 149.280614 -34.979882)
			(xy 149.221158 -34.972054) (xy 149.163233 -34.956533) (xy 149.107829 -34.933584) (xy 149.055895 -34.9036)
			(xy 149.008319 -34.867094) (xy 148.965914 -34.824689) (xy 148.929408 -34.777113) (xy 148.899424 -34.725179)
			(xy 148.876475 -34.669775) (xy 148.860954 -34.61185) (xy 148.853126 -34.552394) (xy 148.852636 -34.52241)
			(xy 138.505159 -34.52241) (xy 138.504694 -34.550854) (xy 138.496871 -34.610276) (xy 138.481358 -34.668169)
			(xy 138.458422 -34.723542) (xy 138.428455 -34.775448) (xy 138.391968 -34.822998) (xy 138.349588 -34.865378)
			(xy 138.302038 -34.901865) (xy 138.250132 -34.931832) (xy 138.194759 -34.954768) (xy 138.136866 -34.970281)
			(xy 138.077444 -34.978104) (xy 138.017508 -34.978104) (xy 137.958086 -34.970281) (xy 137.900193 -34.954768)
			(xy 137.84482 -34.931832) (xy 137.792914 -34.901865) (xy 137.745364 -34.865378) (xy 137.702984 -34.822998)
			(xy 137.666497 -34.775448) (xy 137.63653 -34.723542) (xy 137.613594 -34.668169) (xy 137.598081 -34.610276)
			(xy 137.590258 -34.550854) (xy 137.589768 -34.520886) (xy 123.768612 -34.520886) (xy 123.768612 -34.52241)
			(xy 123.768122 -34.552394) (xy 123.760294 -34.61185) (xy 123.744773 -34.669775) (xy 123.721824 -34.725179)
			(xy 123.69184 -34.777113) (xy 123.655334 -34.824689) (xy 123.612929 -34.867094) (xy 123.565353 -34.9036)
			(xy 123.513419 -34.933584) (xy 123.458015 -34.956533) (xy 123.40009 -34.972054) (xy 123.340634 -34.979882)
			(xy 123.280666 -34.979882) (xy 123.22121 -34.972054) (xy 123.163285 -34.956533) (xy 123.107881 -34.933584)
			(xy 123.055947 -34.9036) (xy 123.008371 -34.867094) (xy 122.965966 -34.824689) (xy 122.92946 -34.777113)
			(xy 122.899476 -34.725179) (xy 122.876527 -34.669775) (xy 122.861006 -34.61185) (xy 122.853178 -34.552394)
			(xy 122.852688 -34.52241) (xy 100.405159 -34.52241) (xy 100.404694 -34.55087) (xy 100.396866 -34.610326)
			(xy 100.381345 -34.668251) (xy 100.358396 -34.723655) (xy 100.328412 -34.775589) (xy 100.291906 -34.823165)
			(xy 100.249501 -34.86557) (xy 100.201925 -34.902076) (xy 100.149991 -34.93206) (xy 100.094587 -34.955009)
			(xy 100.036662 -34.97053) (xy 99.977206 -34.978358) (xy 99.917238 -34.978358) (xy 99.857782 -34.97053)
			(xy 99.799857 -34.955009) (xy 99.744453 -34.93206) (xy 99.692519 -34.902076) (xy 99.644943 -34.86557)
			(xy 99.602538 -34.823165) (xy 99.566032 -34.775589) (xy 99.536048 -34.723655) (xy 99.513099 -34.668251)
			(xy 99.497578 -34.610326) (xy 99.48975 -34.55087) (xy 99.48926 -34.520886) (xy 85.668104 -34.520886)
			(xy 85.668104 -34.52241) (xy 85.667614 -34.552378) (xy 85.659791 -34.6118) (xy 85.644278 -34.669693)
			(xy 85.621342 -34.725066) (xy 85.591375 -34.776972) (xy 85.554888 -34.824522) (xy 85.512508 -34.866902)
			(xy 85.464958 -34.903389) (xy 85.413052 -34.933356) (xy 85.357679 -34.956292) (xy 85.299786 -34.971805)
			(xy 85.240364 -34.979628) (xy 85.180428 -34.979628) (xy 85.121006 -34.971805) (xy 85.063113 -34.956292)
			(xy 85.00774 -34.933356) (xy 84.955834 -34.903389) (xy 84.908284 -34.866902) (xy 84.865904 -34.824522)
			(xy 84.829417 -34.776972) (xy 84.79945 -34.725066) (xy 84.776514 -34.669693) (xy 84.761001 -34.6118)
			(xy 84.753178 -34.552378) (xy 84.752688 -34.52241) (xy 74.405211 -34.52241) (xy 74.404746 -34.55087)
			(xy 74.396918 -34.610326) (xy 74.381397 -34.668251) (xy 74.358448 -34.723655) (xy 74.328464 -34.775589)
			(xy 74.291958 -34.823165) (xy 74.249553 -34.86557) (xy 74.201977 -34.902076) (xy 74.150043 -34.93206)
			(xy 74.094639 -34.955009) (xy 74.036714 -34.97053) (xy 73.977258 -34.978358) (xy 73.91729 -34.978358)
			(xy 73.857834 -34.97053) (xy 73.799909 -34.955009) (xy 73.744505 -34.93206) (xy 73.692571 -34.902076)
			(xy 73.644995 -34.86557) (xy 73.60259 -34.823165) (xy 73.566084 -34.775589) (xy 73.5361 -34.723655)
			(xy 73.513151 -34.668251) (xy 73.49763 -34.610326) (xy 73.489802 -34.55087) (xy 73.489312 -34.520886)
			(xy 59.668156 -34.520886) (xy 59.668156 -34.52241) (xy 59.667666 -34.552378) (xy 59.659843 -34.6118)
			(xy 59.64433 -34.669693) (xy 59.621394 -34.725066) (xy 59.591427 -34.776972) (xy 59.55494 -34.824522)
			(xy 59.51256 -34.866902) (xy 59.46501 -34.903389) (xy 59.413104 -34.933356) (xy 59.357731 -34.956292)
			(xy 59.299838 -34.971805) (xy 59.240416 -34.979628) (xy 59.18048 -34.979628) (xy 59.121058 -34.971805)
			(xy 59.063165 -34.956292) (xy 59.007792 -34.933356) (xy 58.955886 -34.903389) (xy 58.908336 -34.866902)
			(xy 58.865956 -34.824522) (xy 58.829469 -34.776972) (xy 58.799502 -34.725066) (xy 58.776566 -34.669693)
			(xy 58.761053 -34.6118) (xy 58.75323 -34.552378) (xy 58.75274 -34.52241) (xy 48.405263 -34.52241)
			(xy 48.404798 -34.55087) (xy 48.39697 -34.610326) (xy 48.381449 -34.668251) (xy 48.3585 -34.723655)
			(xy 48.328516 -34.775589) (xy 48.29201 -34.823165) (xy 48.249605 -34.86557) (xy 48.202029 -34.902076)
			(xy 48.150095 -34.93206) (xy 48.094691 -34.955009) (xy 48.036766 -34.97053) (xy 47.97731 -34.978358)
			(xy 47.917342 -34.978358) (xy 47.857886 -34.97053) (xy 47.799961 -34.955009) (xy 47.744557 -34.93206)
			(xy 47.692623 -34.902076) (xy 47.645047 -34.86557) (xy 47.602642 -34.823165) (xy 47.566136 -34.775589)
			(xy 47.536152 -34.723655) (xy 47.513203 -34.668251) (xy 47.497682 -34.610326) (xy 47.489854 -34.55087)
			(xy 47.489364 -34.520886) (xy 33.668208 -34.520886) (xy 33.668208 -34.52241) (xy 33.667718 -34.552378)
			(xy 33.659895 -34.6118) (xy 33.644382 -34.669693) (xy 33.621446 -34.725066) (xy 33.591479 -34.776972)
			(xy 33.554992 -34.824522) (xy 33.512612 -34.866902) (xy 33.465062 -34.903389) (xy 33.413156 -34.933356)
			(xy 33.357783 -34.956292) (xy 33.29989 -34.971805) (xy 33.240468 -34.979628) (xy 33.180532 -34.979628)
			(xy 33.12111 -34.971805) (xy 33.063217 -34.956292) (xy 33.007844 -34.933356) (xy 32.955938 -34.903389)
			(xy 32.908388 -34.866902) (xy 32.866008 -34.824522) (xy 32.829521 -34.776972) (xy 32.799554 -34.725066)
			(xy 32.776618 -34.669693) (xy 32.761105 -34.6118) (xy 32.753282 -34.552378) (xy 32.752792 -34.52241)
			(xy 22.405315 -34.52241) (xy 22.40485 -34.55087) (xy 22.397022 -34.610326) (xy 22.381501 -34.668251)
			(xy 22.358552 -34.723655) (xy 22.328568 -34.775589) (xy 22.292062 -34.823165) (xy 22.249657 -34.86557)
			(xy 22.202081 -34.902076) (xy 22.150147 -34.93206) (xy 22.094743 -34.955009) (xy 22.036818 -34.97053)
			(xy 21.977362 -34.978358) (xy 21.917394 -34.978358) (xy 21.857938 -34.97053) (xy 21.800013 -34.955009)
			(xy 21.744609 -34.93206) (xy 21.692675 -34.902076) (xy 21.645099 -34.86557) (xy 21.602694 -34.823165)
			(xy 21.566188 -34.775589) (xy 21.536204 -34.723655) (xy 21.513255 -34.668251) (xy 21.497734 -34.610326)
			(xy 21.489906 -34.55087) (xy 21.489416 -34.520886) (xy 7.66826 -34.520886) (xy 7.66826 -34.52241)
			(xy 7.66777 -34.552378) (xy 7.659947 -34.6118) (xy 7.644434 -34.669693) (xy 7.621498 -34.725066)
			(xy 7.591531 -34.776972) (xy 7.555044 -34.824522) (xy 7.512664 -34.866902) (xy 7.465114 -34.903389)
			(xy 7.413208 -34.933356) (xy 7.357835 -34.956292) (xy 7.299942 -34.971805) (xy 7.24052 -34.979628)
			(xy 7.180584 -34.979628) (xy 7.121162 -34.971805) (xy 7.063269 -34.956292) (xy 7.007896 -34.933356)
			(xy 6.95599 -34.903389) (xy 6.90844 -34.866902) (xy 6.86606 -34.824522) (xy 6.829573 -34.776972)
			(xy 6.799606 -34.725066) (xy 6.77667 -34.669693) (xy 6.761157 -34.6118) (xy 6.753334 -34.552378)
			(xy 6.752844 -34.52241) (xy 0.508 -34.52241) (xy 0.508 -36.60013) (xy 11.998205 -36.60013) (xy 12.00221 -36.512222)
			(xy 12.014193 -36.425042) (xy 12.034053 -36.339313) (xy 12.061628 -36.255745) (xy 12.096687 -36.175031)
			(xy 12.13894 -36.097839) (xy 12.188038 -36.02481) (xy 12.243574 -35.956548) (xy 12.305086 -35.893618)
			(xy 12.372067 -35.836544) (xy 12.44396 -35.785796) (xy 12.520169 -35.741796) (xy 12.600064 -35.704909)
			(xy 12.682983 -35.67544) (xy 12.768238 -35.653633) (xy 12.855122 -35.639669) (xy 12.942916 -35.633663)
			(xy 13.030893 -35.635667) (xy 13.118323 -35.645662) (xy 13.204482 -35.663566) (xy 13.288656 -35.68923)
			(xy 13.370147 -35.722443) (xy 13.448281 -35.762929) (xy 13.522409 -35.810351) (xy 13.591917 -35.864318)
			(xy 13.656231 -35.924383) (xy 13.714815 -35.990047) (xy 13.767186 -36.060766) (xy 13.812909 -36.135954)
			(xy 13.851606 -36.214989) (xy 13.882955 -36.297215) (xy 13.906697 -36.381951) (xy 13.922635 -36.468495)
			(xy 13.930637 -36.55613) (xy 13.931138 -36.60013) (xy 37.998153 -36.60013) (xy 38.002158 -36.512222)
			(xy 38.014141 -36.425042) (xy 38.034001 -36.339313) (xy 38.061576 -36.255745) (xy 38.096635 -36.175031)
			(xy 38.138888 -36.097839) (xy 38.187986 -36.02481) (xy 38.243522 -35.956548) (xy 38.305034 -35.893618)
			(xy 38.372015 -35.836544) (xy 38.443908 -35.785796) (xy 38.520117 -35.741796) (xy 38.600012 -35.704909)
			(xy 38.682931 -35.67544) (xy 38.768186 -35.653633) (xy 38.85507 -35.639669) (xy 38.942864 -35.633663)
			(xy 39.030841 -35.635667) (xy 39.118271 -35.645662) (xy 39.20443 -35.663566) (xy 39.288604 -35.68923)
			(xy 39.370095 -35.722443) (xy 39.448229 -35.762929) (xy 39.522357 -35.810351) (xy 39.591865 -35.864318)
			(xy 39.656179 -35.924383) (xy 39.714763 -35.990047) (xy 39.767134 -36.060766) (xy 39.812857 -36.135954)
			(xy 39.851554 -36.214989) (xy 39.882903 -36.297215) (xy 39.906645 -36.381951) (xy 39.922583 -36.468495)
			(xy 39.930585 -36.55613) (xy 39.931086 -36.60013) (xy 63.998101 -36.60013) (xy 64.002106 -36.512222)
			(xy 64.014089 -36.425042) (xy 64.033949 -36.339313) (xy 64.061524 -36.255745) (xy 64.096583 -36.175031)
			(xy 64.138836 -36.097839) (xy 64.187934 -36.02481) (xy 64.24347 -35.956548) (xy 64.304982 -35.893618)
			(xy 64.371963 -35.836544) (xy 64.443856 -35.785796) (xy 64.520065 -35.741796) (xy 64.59996 -35.704909)
			(xy 64.682879 -35.67544) (xy 64.768134 -35.653633) (xy 64.855018 -35.639669) (xy 64.942812 -35.633663)
			(xy 65.030789 -35.635667) (xy 65.118219 -35.645662) (xy 65.204378 -35.663566) (xy 65.288552 -35.68923)
			(xy 65.370043 -35.722443) (xy 65.448177 -35.762929) (xy 65.522305 -35.810351) (xy 65.591813 -35.864318)
			(xy 65.656127 -35.924383) (xy 65.714711 -35.990047) (xy 65.767082 -36.060766) (xy 65.812805 -36.135954)
			(xy 65.851502 -36.214989) (xy 65.882851 -36.297215) (xy 65.906593 -36.381951) (xy 65.922531 -36.468495)
			(xy 65.930533 -36.55613) (xy 65.931034 -36.60013) (xy 89.998049 -36.60013) (xy 90.002054 -36.512222)
			(xy 90.014037 -36.425042) (xy 90.033897 -36.339313) (xy 90.061472 -36.255745) (xy 90.096531 -36.175031)
			(xy 90.138784 -36.097839) (xy 90.187882 -36.02481) (xy 90.243418 -35.956548) (xy 90.30493 -35.893618)
			(xy 90.371911 -35.836544) (xy 90.443804 -35.785796) (xy 90.520013 -35.741796) (xy 90.599908 -35.704909)
			(xy 90.682827 -35.67544) (xy 90.768082 -35.653633) (xy 90.854966 -35.639669) (xy 90.94276 -35.633663)
			(xy 91.030737 -35.635667) (xy 91.118167 -35.645662) (xy 91.204326 -35.663566) (xy 91.2885 -35.68923)
			(xy 91.369991 -35.722443) (xy 91.448125 -35.762929) (xy 91.522253 -35.810351) (xy 91.591761 -35.864318)
			(xy 91.656075 -35.924383) (xy 91.714659 -35.990047) (xy 91.76703 -36.060766) (xy 91.812753 -36.135954)
			(xy 91.85145 -36.214989) (xy 91.882799 -36.297215) (xy 91.906541 -36.381951) (xy 91.922479 -36.468495)
			(xy 91.930481 -36.55613) (xy 91.930982 -36.60013) (xy 128.098303 -36.60013) (xy 128.102308 -36.512222)
			(xy 128.114291 -36.425042) (xy 128.134151 -36.339313) (xy 128.161726 -36.255745) (xy 128.196785 -36.175031)
			(xy 128.239038 -36.097839) (xy 128.288136 -36.02481) (xy 128.343672 -35.956548) (xy 128.405184 -35.893618)
			(xy 128.472165 -35.836544) (xy 128.544058 -35.785796) (xy 128.620267 -35.741796) (xy 128.700162 -35.704909)
			(xy 128.783081 -35.67544) (xy 128.868336 -35.653633) (xy 128.95522 -35.639669) (xy 129.043014 -35.633663)
			(xy 129.130991 -35.635667) (xy 129.218421 -35.645662) (xy 129.30458 -35.663566) (xy 129.388754 -35.68923)
			(xy 129.470245 -35.722443) (xy 129.548379 -35.762929) (xy 129.622507 -35.810351) (xy 129.692015 -35.864318)
			(xy 129.756329 -35.924383) (xy 129.814913 -35.990047) (xy 129.867284 -36.060766) (xy 129.913007 -36.135954)
			(xy 129.951704 -36.214989) (xy 129.983053 -36.297215) (xy 130.006795 -36.381951) (xy 130.022733 -36.468495)
			(xy 130.030735 -36.55613) (xy 130.031236 -36.60013) (xy 154.098251 -36.60013) (xy 154.102256 -36.512222)
			(xy 154.114239 -36.425042) (xy 154.134099 -36.339313) (xy 154.161674 -36.255745) (xy 154.196733 -36.175031)
			(xy 154.238986 -36.097839) (xy 154.288084 -36.02481) (xy 154.34362 -35.956548) (xy 154.405132 -35.893618)
			(xy 154.472113 -35.836544) (xy 154.544006 -35.785796) (xy 154.620215 -35.741796) (xy 154.70011 -35.704909)
			(xy 154.783029 -35.67544) (xy 154.868284 -35.653633) (xy 154.955168 -35.639669) (xy 155.042962 -35.633663)
			(xy 155.130939 -35.635667) (xy 155.218369 -35.645662) (xy 155.304528 -35.663566) (xy 155.388702 -35.68923)
			(xy 155.470193 -35.722443) (xy 155.548327 -35.762929) (xy 155.622455 -35.810351) (xy 155.691963 -35.864318)
			(xy 155.756277 -35.924383) (xy 155.814861 -35.990047) (xy 155.867232 -36.060766) (xy 155.912955 -36.135954)
			(xy 155.951652 -36.214989) (xy 155.983001 -36.297215) (xy 156.006743 -36.381951) (xy 156.022681 -36.468495)
			(xy 156.030683 -36.55613) (xy 156.031184 -36.60013) (xy 180.098199 -36.60013) (xy 180.102204 -36.512222)
			(xy 180.114187 -36.425042) (xy 180.134047 -36.339313) (xy 180.161622 -36.255745) (xy 180.196681 -36.175031)
			(xy 180.238934 -36.097839) (xy 180.288032 -36.02481) (xy 180.343568 -35.956548) (xy 180.40508 -35.893618)
			(xy 180.472061 -35.836544) (xy 180.543954 -35.785796) (xy 180.620163 -35.741796) (xy 180.700058 -35.704909)
			(xy 180.782977 -35.67544) (xy 180.868232 -35.653633) (xy 180.955116 -35.639669) (xy 181.04291 -35.633663)
			(xy 181.130887 -35.635667) (xy 181.218317 -35.645662) (xy 181.304476 -35.663566) (xy 181.38865 -35.68923)
			(xy 181.470141 -35.722443) (xy 181.548275 -35.762929) (xy 181.622403 -35.810351) (xy 181.691911 -35.864318)
			(xy 181.756225 -35.924383) (xy 181.814809 -35.990047) (xy 181.86718 -36.060766) (xy 181.912903 -36.135954)
			(xy 181.9516 -36.214989) (xy 181.982949 -36.297215) (xy 182.006691 -36.381951) (xy 182.022629 -36.468495)
			(xy 182.030631 -36.55613) (xy 182.031132 -36.60013) (xy 206.098655 -36.60013) (xy 206.102659 -36.512245)
			(xy 206.114639 -36.425088) (xy 206.134494 -36.339381) (xy 206.162061 -36.255836) (xy 206.197111 -36.175143)
			(xy 206.239353 -36.097971) (xy 206.288438 -36.024961) (xy 206.343959 -35.956717) (xy 206.405456 -35.893804)
			(xy 206.472418 -35.836744) (xy 206.544292 -35.78601) (xy 206.620482 -35.742022) (xy 206.700356 -35.705144)
			(xy 206.783253 -35.675683) (xy 206.868485 -35.653881) (xy 206.955347 -35.639921) (xy 207.043118 -35.633917)
			(xy 207.131072 -35.63592) (xy 207.218479 -35.645912) (xy 207.304615 -35.663812) (xy 207.388767 -35.68947)
			(xy 207.470237 -35.722674) (xy 207.54835 -35.763148) (xy 207.622458 -35.810559) (xy 207.691949 -35.864512)
			(xy 207.756245 -35.92456) (xy 207.814814 -35.990207) (xy 207.867171 -36.060907) (xy 207.912883 -36.136076)
			(xy 207.951569 -36.21509) (xy 207.98291 -36.297295) (xy 208.006645 -36.382009) (xy 208.022579 -36.46853)
			(xy 208.030579 -36.556142) (xy 208.03108 -36.60013) (xy 244.198655 -36.60013) (xy 244.202659 -36.512245)
			(xy 244.214639 -36.425088) (xy 244.234494 -36.339381) (xy 244.262061 -36.255836) (xy 244.297111 -36.175143)
			(xy 244.339353 -36.097971) (xy 244.388438 -36.024961) (xy 244.443959 -35.956717) (xy 244.505456 -35.893804)
			(xy 244.572418 -35.836744) (xy 244.644292 -35.78601) (xy 244.720482 -35.742022) (xy 244.800356 -35.705144)
			(xy 244.883253 -35.675683) (xy 244.968485 -35.653881) (xy 245.055347 -35.639921) (xy 245.143118 -35.633917)
			(xy 245.231072 -35.63592) (xy 245.318479 -35.645912) (xy 245.404615 -35.663812) (xy 245.488767 -35.68947)
			(xy 245.570237 -35.722674) (xy 245.64835 -35.763148) (xy 245.722458 -35.810559) (xy 245.791949 -35.864512)
			(xy 245.856245 -35.92456) (xy 245.914814 -35.990207) (xy 245.967171 -36.060907) (xy 246.012883 -36.136076)
			(xy 246.051569 -36.21509) (xy 246.08291 -36.297295) (xy 246.106645 -36.382009) (xy 246.122579 -36.46853)
			(xy 246.130579 -36.556142) (xy 246.13108 -36.60013) (xy 270.198603 -36.60013) (xy 270.202607 -36.512245)
			(xy 270.214587 -36.425088) (xy 270.234442 -36.339381) (xy 270.262009 -36.255836) (xy 270.297059 -36.175143)
			(xy 270.339301 -36.097971) (xy 270.388386 -36.024961) (xy 270.443907 -35.956717) (xy 270.505404 -35.893804)
			(xy 270.572366 -35.836744) (xy 270.64424 -35.78601) (xy 270.72043 -35.742022) (xy 270.800304 -35.705144)
			(xy 270.883201 -35.675683) (xy 270.968433 -35.653881) (xy 271.055295 -35.639921) (xy 271.143066 -35.633917)
			(xy 271.23102 -35.63592) (xy 271.318427 -35.645912) (xy 271.404563 -35.663812) (xy 271.488715 -35.68947)
			(xy 271.570185 -35.722674) (xy 271.648298 -35.763148) (xy 271.722406 -35.810559) (xy 271.791897 -35.864512)
			(xy 271.856193 -35.92456) (xy 271.914762 -35.990207) (xy 271.967119 -36.060907) (xy 272.012831 -36.136076)
			(xy 272.051517 -36.21509) (xy 272.082858 -36.297295) (xy 272.106593 -36.382009) (xy 272.122527 -36.46853)
			(xy 272.130527 -36.556142) (xy 272.131028 -36.60013) (xy 296.198551 -36.60013) (xy 296.202555 -36.512245)
			(xy 296.214535 -36.425088) (xy 296.23439 -36.339381) (xy 296.261957 -36.255836) (xy 296.297007 -36.175143)
			(xy 296.339249 -36.097971) (xy 296.388334 -36.024961) (xy 296.443855 -35.956717) (xy 296.505352 -35.893804)
			(xy 296.572314 -35.836744) (xy 296.644188 -35.78601) (xy 296.720378 -35.742022) (xy 296.800252 -35.705144)
			(xy 296.883149 -35.675683) (xy 296.968381 -35.653881) (xy 297.055243 -35.639921) (xy 297.143014 -35.633917)
			(xy 297.230968 -35.63592) (xy 297.318375 -35.645912) (xy 297.404511 -35.663812) (xy 297.488663 -35.68947)
			(xy 297.570133 -35.722674) (xy 297.648246 -35.763148) (xy 297.722354 -35.810559) (xy 297.791845 -35.864512)
			(xy 297.856141 -35.92456) (xy 297.91471 -35.990207) (xy 297.967067 -36.060907) (xy 298.012779 -36.136076)
			(xy 298.051465 -36.21509) (xy 298.082806 -36.297295) (xy 298.106541 -36.382009) (xy 298.122475 -36.46853)
			(xy 298.130475 -36.556142) (xy 298.130976 -36.60013) (xy 322.197991 -36.60013) (xy 322.201996 -36.512222)
			(xy 322.213979 -36.425042) (xy 322.233839 -36.339313) (xy 322.261414 -36.255745) (xy 322.296473 -36.175031)
			(xy 322.338726 -36.097839) (xy 322.387824 -36.02481) (xy 322.44336 -35.956548) (xy 322.504872 -35.893618)
			(xy 322.571853 -35.836544) (xy 322.643746 -35.785796) (xy 322.719955 -35.741796) (xy 322.79985 -35.704909)
			(xy 322.882769 -35.67544) (xy 322.968024 -35.653633) (xy 323.054908 -35.639669) (xy 323.142702 -35.633663)
			(xy 323.230679 -35.635667) (xy 323.318109 -35.645662) (xy 323.404268 -35.663566) (xy 323.488442 -35.68923)
			(xy 323.569933 -35.722443) (xy 323.648067 -35.762929) (xy 323.722195 -35.810351) (xy 323.791703 -35.864318)
			(xy 323.856017 -35.924383) (xy 323.914601 -35.990047) (xy 323.966972 -36.060766) (xy 324.012695 -36.135954)
			(xy 324.051392 -36.214989) (xy 324.082741 -36.297215) (xy 324.106483 -36.381951) (xy 324.122421 -36.468495)
			(xy 324.130423 -36.55613) (xy 324.130924 -36.60013) (xy 360.298245 -36.60013) (xy 360.30225 -36.512222)
			(xy 360.314233 -36.425042) (xy 360.334093 -36.339313) (xy 360.361668 -36.255745) (xy 360.396727 -36.175031)
			(xy 360.43898 -36.097839) (xy 360.488078 -36.02481) (xy 360.543614 -35.956548) (xy 360.605126 -35.893618)
			(xy 360.672107 -35.836544) (xy 360.744 -35.785796) (xy 360.820209 -35.741796) (xy 360.900104 -35.704909)
			(xy 360.983023 -35.67544) (xy 361.068278 -35.653633) (xy 361.155162 -35.639669) (xy 361.242956 -35.633663)
			(xy 361.330933 -35.635667) (xy 361.418363 -35.645662) (xy 361.504522 -35.663566) (xy 361.588696 -35.68923)
			(xy 361.670187 -35.722443) (xy 361.748321 -35.762929) (xy 361.822449 -35.810351) (xy 361.891957 -35.864318)
			(xy 361.956271 -35.924383) (xy 362.014855 -35.990047) (xy 362.067226 -36.060766) (xy 362.112949 -36.135954)
			(xy 362.151646 -36.214989) (xy 362.182995 -36.297215) (xy 362.206737 -36.381951) (xy 362.222675 -36.468495)
			(xy 362.230677 -36.55613) (xy 362.231178 -36.60013) (xy 386.298193 -36.60013) (xy 386.302198 -36.512222)
			(xy 386.314181 -36.425042) (xy 386.334041 -36.339313) (xy 386.361616 -36.255745) (xy 386.396675 -36.175031)
			(xy 386.438928 -36.097839) (xy 386.488026 -36.02481) (xy 386.543562 -35.956548) (xy 386.605074 -35.893618)
			(xy 386.672055 -35.836544) (xy 386.743948 -35.785796) (xy 386.820157 -35.741796) (xy 386.900052 -35.704909)
			(xy 386.982971 -35.67544) (xy 387.068226 -35.653633) (xy 387.15511 -35.639669) (xy 387.242904 -35.633663)
			(xy 387.330881 -35.635667) (xy 387.418311 -35.645662) (xy 387.50447 -35.663566) (xy 387.588644 -35.68923)
			(xy 387.670135 -35.722443) (xy 387.748269 -35.762929) (xy 387.822397 -35.810351) (xy 387.891905 -35.864318)
			(xy 387.956219 -35.924383) (xy 388.014803 -35.990047) (xy 388.067174 -36.060766) (xy 388.112897 -36.135954)
			(xy 388.151594 -36.214989) (xy 388.182943 -36.297215) (xy 388.206685 -36.381951) (xy 388.222623 -36.468495)
			(xy 388.230625 -36.55613) (xy 388.231126 -36.60013) (xy 412.298649 -36.60013) (xy 412.302653 -36.512245)
			(xy 412.314633 -36.425088) (xy 412.334488 -36.339381) (xy 412.362055 -36.255836) (xy 412.397105 -36.175143)
			(xy 412.439347 -36.097971) (xy 412.488432 -36.024961) (xy 412.543953 -35.956717) (xy 412.60545 -35.893804)
			(xy 412.672412 -35.836744) (xy 412.744286 -35.78601) (xy 412.820476 -35.742022) (xy 412.90035 -35.705144)
			(xy 412.983247 -35.675683) (xy 413.068479 -35.653881) (xy 413.155341 -35.639921) (xy 413.243112 -35.633917)
			(xy 413.331066 -35.63592) (xy 413.418473 -35.645912) (xy 413.504609 -35.663812) (xy 413.588761 -35.68947)
			(xy 413.670231 -35.722674) (xy 413.748344 -35.763148) (xy 413.822452 -35.810559) (xy 413.891943 -35.864512)
			(xy 413.956239 -35.92456) (xy 414.014808 -35.990207) (xy 414.067165 -36.060907) (xy 414.112877 -36.136076)
			(xy 414.151563 -36.21509) (xy 414.182904 -36.297295) (xy 414.206639 -36.382009) (xy 414.222573 -36.46853)
			(xy 414.230573 -36.556142) (xy 414.231074 -36.60013) (xy 438.298597 -36.60013) (xy 438.302601 -36.512245)
			(xy 438.314581 -36.425088) (xy 438.334436 -36.339381) (xy 438.362003 -36.255836) (xy 438.397053 -36.175143)
			(xy 438.439295 -36.097971) (xy 438.48838 -36.024961) (xy 438.543901 -35.956717) (xy 438.605398 -35.893804)
			(xy 438.67236 -35.836744) (xy 438.744234 -35.78601) (xy 438.820424 -35.742022) (xy 438.900298 -35.705144)
			(xy 438.983195 -35.675683) (xy 439.068427 -35.653881) (xy 439.155289 -35.639921) (xy 439.24306 -35.633917)
			(xy 439.331014 -35.63592) (xy 439.418421 -35.645912) (xy 439.504557 -35.663812) (xy 439.588709 -35.68947)
			(xy 439.670179 -35.722674) (xy 439.748292 -35.763148) (xy 439.8224 -35.810559) (xy 439.891891 -35.864512)
			(xy 439.956187 -35.92456) (xy 440.014756 -35.990207) (xy 440.067113 -36.060907) (xy 440.112825 -36.136076)
			(xy 440.151511 -36.21509) (xy 440.182852 -36.297295) (xy 440.206587 -36.382009) (xy 440.222521 -36.46853)
			(xy 440.230521 -36.556142) (xy 440.231022 -36.60013) (xy 440.230521 -36.644118) (xy 440.222521 -36.73173)
			(xy 440.206587 -36.818251) (xy 440.182852 -36.902965) (xy 440.151511 -36.98517) (xy 440.112825 -37.064184)
			(xy 440.067113 -37.139353) (xy 440.014756 -37.210053) (xy 439.956187 -37.2757) (xy 439.891891 -37.335748)
			(xy 439.8224 -37.389701) (xy 439.748292 -37.437112) (xy 439.670179 -37.477586) (xy 439.588709 -37.51079)
			(xy 439.504557 -37.536448) (xy 439.418421 -37.554348) (xy 439.331014 -37.56434) (xy 439.24306 -37.566343)
			(xy 439.155289 -37.560339) (xy 439.068427 -37.546379) (xy 438.983195 -37.524577) (xy 438.900298 -37.495116)
			(xy 438.820424 -37.458238) (xy 438.744234 -37.41425) (xy 438.67236 -37.363516) (xy 438.605398 -37.306456)
			(xy 438.543901 -37.243543) (xy 438.48838 -37.175299) (xy 438.439295 -37.102289) (xy 438.397053 -37.025117)
			(xy 438.362003 -36.944424) (xy 438.334436 -36.860879) (xy 438.314581 -36.775172) (xy 438.302601 -36.688015)
			(xy 438.298597 -36.60013) (xy 414.231074 -36.60013) (xy 414.230573 -36.644118) (xy 414.222573 -36.73173)
			(xy 414.206639 -36.818251) (xy 414.182904 -36.902965) (xy 414.151563 -36.98517) (xy 414.112877 -37.064184)
			(xy 414.067165 -37.139353) (xy 414.014808 -37.210053) (xy 413.956239 -37.2757) (xy 413.891943 -37.335748)
			(xy 413.822452 -37.389701) (xy 413.748344 -37.437112) (xy 413.670231 -37.477586) (xy 413.588761 -37.51079)
			(xy 413.504609 -37.536448) (xy 413.418473 -37.554348) (xy 413.331066 -37.56434) (xy 413.243112 -37.566343)
			(xy 413.155341 -37.560339) (xy 413.068479 -37.546379) (xy 412.983247 -37.524577) (xy 412.90035 -37.495116)
			(xy 412.820476 -37.458238) (xy 412.744286 -37.41425) (xy 412.672412 -37.363516) (xy 412.60545 -37.306456)
			(xy 412.543953 -37.243543) (xy 412.488432 -37.175299) (xy 412.439347 -37.102289) (xy 412.397105 -37.025117)
			(xy 412.362055 -36.944424) (xy 412.334488 -36.860879) (xy 412.314633 -36.775172) (xy 412.302653 -36.688015)
			(xy 412.298649 -36.60013) (xy 388.231126 -36.60013) (xy 388.230625 -36.64413) (xy 388.222623 -36.731765)
			(xy 388.206685 -36.818309) (xy 388.182943 -36.903045) (xy 388.151594 -36.985271) (xy 388.112897 -37.064306)
			(xy 388.067174 -37.139494) (xy 388.014803 -37.210213) (xy 387.956219 -37.275877) (xy 387.891905 -37.335942)
			(xy 387.822397 -37.389909) (xy 387.748269 -37.437331) (xy 387.670135 -37.477817) (xy 387.588644 -37.51103)
			(xy 387.50447 -37.536694) (xy 387.418311 -37.554598) (xy 387.330881 -37.564593) (xy 387.242904 -37.566597)
			(xy 387.15511 -37.560591) (xy 387.068226 -37.546627) (xy 386.982971 -37.52482) (xy 386.900052 -37.495351)
			(xy 386.820157 -37.458464) (xy 386.743948 -37.414464) (xy 386.672055 -37.363716) (xy 386.605074 -37.306642)
			(xy 386.543562 -37.243712) (xy 386.488026 -37.17545) (xy 386.438928 -37.102421) (xy 386.396675 -37.025229)
			(xy 386.361616 -36.944515) (xy 386.334041 -36.860947) (xy 386.314181 -36.775218) (xy 386.302198 -36.688038)
			(xy 386.298193 -36.60013) (xy 362.231178 -36.60013) (xy 362.230677 -36.64413) (xy 362.222675 -36.731765)
			(xy 362.206737 -36.818309) (xy 362.182995 -36.903045) (xy 362.151646 -36.985271) (xy 362.112949 -37.064306)
			(xy 362.067226 -37.139494) (xy 362.014855 -37.210213) (xy 361.956271 -37.275877) (xy 361.891957 -37.335942)
			(xy 361.822449 -37.389909) (xy 361.748321 -37.437331) (xy 361.670187 -37.477817) (xy 361.588696 -37.51103)
			(xy 361.504522 -37.536694) (xy 361.418363 -37.554598) (xy 361.330933 -37.564593) (xy 361.242956 -37.566597)
			(xy 361.155162 -37.560591) (xy 361.068278 -37.546627) (xy 360.983023 -37.52482) (xy 360.900104 -37.495351)
			(xy 360.820209 -37.458464) (xy 360.744 -37.414464) (xy 360.672107 -37.363716) (xy 360.605126 -37.306642)
			(xy 360.543614 -37.243712) (xy 360.488078 -37.17545) (xy 360.43898 -37.102421) (xy 360.396727 -37.025229)
			(xy 360.361668 -36.944515) (xy 360.334093 -36.860947) (xy 360.314233 -36.775218) (xy 360.30225 -36.688038)
			(xy 360.298245 -36.60013) (xy 324.130924 -36.60013) (xy 324.130423 -36.64413) (xy 324.122421 -36.731765)
			(xy 324.106483 -36.818309) (xy 324.082741 -36.903045) (xy 324.051392 -36.985271) (xy 324.012695 -37.064306)
			(xy 323.966972 -37.139494) (xy 323.914601 -37.210213) (xy 323.856017 -37.275877) (xy 323.791703 -37.335942)
			(xy 323.722195 -37.389909) (xy 323.648067 -37.437331) (xy 323.569933 -37.477817) (xy 323.488442 -37.51103)
			(xy 323.404268 -37.536694) (xy 323.318109 -37.554598) (xy 323.230679 -37.564593) (xy 323.142702 -37.566597)
			(xy 323.054908 -37.560591) (xy 322.968024 -37.546627) (xy 322.882769 -37.52482) (xy 322.79985 -37.495351)
			(xy 322.719955 -37.458464) (xy 322.643746 -37.414464) (xy 322.571853 -37.363716) (xy 322.504872 -37.306642)
			(xy 322.44336 -37.243712) (xy 322.387824 -37.17545) (xy 322.338726 -37.102421) (xy 322.296473 -37.025229)
			(xy 322.261414 -36.944515) (xy 322.233839 -36.860947) (xy 322.213979 -36.775218) (xy 322.201996 -36.688038)
			(xy 322.197991 -36.60013) (xy 298.130976 -36.60013) (xy 298.130475 -36.644118) (xy 298.122475 -36.73173)
			(xy 298.106541 -36.818251) (xy 298.082806 -36.902965) (xy 298.051465 -36.98517) (xy 298.012779 -37.064184)
			(xy 297.967067 -37.139353) (xy 297.91471 -37.210053) (xy 297.856141 -37.2757) (xy 297.791845 -37.335748)
			(xy 297.722354 -37.389701) (xy 297.648246 -37.437112) (xy 297.570133 -37.477586) (xy 297.488663 -37.51079)
			(xy 297.404511 -37.536448) (xy 297.318375 -37.554348) (xy 297.230968 -37.56434) (xy 297.143014 -37.566343)
			(xy 297.055243 -37.560339) (xy 296.968381 -37.546379) (xy 296.883149 -37.524577) (xy 296.800252 -37.495116)
			(xy 296.720378 -37.458238) (xy 296.644188 -37.41425) (xy 296.572314 -37.363516) (xy 296.505352 -37.306456)
			(xy 296.443855 -37.243543) (xy 296.388334 -37.175299) (xy 296.339249 -37.102289) (xy 296.297007 -37.025117)
			(xy 296.261957 -36.944424) (xy 296.23439 -36.860879) (xy 296.214535 -36.775172) (xy 296.202555 -36.688015)
			(xy 296.198551 -36.60013) (xy 272.131028 -36.60013) (xy 272.130527 -36.644118) (xy 272.122527 -36.73173)
			(xy 272.106593 -36.818251) (xy 272.082858 -36.902965) (xy 272.051517 -36.98517) (xy 272.012831 -37.064184)
			(xy 271.967119 -37.139353) (xy 271.914762 -37.210053) (xy 271.856193 -37.2757) (xy 271.791897 -37.335748)
			(xy 271.722406 -37.389701) (xy 271.648298 -37.437112) (xy 271.570185 -37.477586) (xy 271.488715 -37.51079)
			(xy 271.404563 -37.536448) (xy 271.318427 -37.554348) (xy 271.23102 -37.56434) (xy 271.143066 -37.566343)
			(xy 271.055295 -37.560339) (xy 270.968433 -37.546379) (xy 270.883201 -37.524577) (xy 270.800304 -37.495116)
			(xy 270.72043 -37.458238) (xy 270.64424 -37.41425) (xy 270.572366 -37.363516) (xy 270.505404 -37.306456)
			(xy 270.443907 -37.243543) (xy 270.388386 -37.175299) (xy 270.339301 -37.102289) (xy 270.297059 -37.025117)
			(xy 270.262009 -36.944424) (xy 270.234442 -36.860879) (xy 270.214587 -36.775172) (xy 270.202607 -36.688015)
			(xy 270.198603 -36.60013) (xy 246.13108 -36.60013) (xy 246.130579 -36.644118) (xy 246.122579 -36.73173)
			(xy 246.106645 -36.818251) (xy 246.08291 -36.902965) (xy 246.051569 -36.98517) (xy 246.012883 -37.064184)
			(xy 245.967171 -37.139353) (xy 245.914814 -37.210053) (xy 245.856245 -37.2757) (xy 245.791949 -37.335748)
			(xy 245.722458 -37.389701) (xy 245.64835 -37.437112) (xy 245.570237 -37.477586) (xy 245.488767 -37.51079)
			(xy 245.404615 -37.536448) (xy 245.318479 -37.554348) (xy 245.231072 -37.56434) (xy 245.143118 -37.566343)
			(xy 245.055347 -37.560339) (xy 244.968485 -37.546379) (xy 244.883253 -37.524577) (xy 244.800356 -37.495116)
			(xy 244.720482 -37.458238) (xy 244.644292 -37.41425) (xy 244.572418 -37.363516) (xy 244.505456 -37.306456)
			(xy 244.443959 -37.243543) (xy 244.388438 -37.175299) (xy 244.339353 -37.102289) (xy 244.297111 -37.025117)
			(xy 244.262061 -36.944424) (xy 244.234494 -36.860879) (xy 244.214639 -36.775172) (xy 244.202659 -36.688015)
			(xy 244.198655 -36.60013) (xy 208.03108 -36.60013) (xy 208.030579 -36.644118) (xy 208.022579 -36.73173)
			(xy 208.006645 -36.818251) (xy 207.98291 -36.902965) (xy 207.951569 -36.98517) (xy 207.912883 -37.064184)
			(xy 207.867171 -37.139353) (xy 207.814814 -37.210053) (xy 207.756245 -37.2757) (xy 207.691949 -37.335748)
			(xy 207.622458 -37.389701) (xy 207.54835 -37.437112) (xy 207.470237 -37.477586) (xy 207.388767 -37.51079)
			(xy 207.304615 -37.536448) (xy 207.218479 -37.554348) (xy 207.131072 -37.56434) (xy 207.043118 -37.566343)
			(xy 206.955347 -37.560339) (xy 206.868485 -37.546379) (xy 206.783253 -37.524577) (xy 206.700356 -37.495116)
			(xy 206.620482 -37.458238) (xy 206.544292 -37.41425) (xy 206.472418 -37.363516) (xy 206.405456 -37.306456)
			(xy 206.343959 -37.243543) (xy 206.288438 -37.175299) (xy 206.239353 -37.102289) (xy 206.197111 -37.025117)
			(xy 206.162061 -36.944424) (xy 206.134494 -36.860879) (xy 206.114639 -36.775172) (xy 206.102659 -36.688015)
			(xy 206.098655 -36.60013) (xy 182.031132 -36.60013) (xy 182.030631 -36.64413) (xy 182.022629 -36.731765)
			(xy 182.006691 -36.818309) (xy 181.982949 -36.903045) (xy 181.9516 -36.985271) (xy 181.912903 -37.064306)
			(xy 181.86718 -37.139494) (xy 181.814809 -37.210213) (xy 181.756225 -37.275877) (xy 181.691911 -37.335942)
			(xy 181.622403 -37.389909) (xy 181.548275 -37.437331) (xy 181.470141 -37.477817) (xy 181.38865 -37.51103)
			(xy 181.304476 -37.536694) (xy 181.218317 -37.554598) (xy 181.130887 -37.564593) (xy 181.04291 -37.566597)
			(xy 180.955116 -37.560591) (xy 180.868232 -37.546627) (xy 180.782977 -37.52482) (xy 180.700058 -37.495351)
			(xy 180.620163 -37.458464) (xy 180.543954 -37.414464) (xy 180.472061 -37.363716) (xy 180.40508 -37.306642)
			(xy 180.343568 -37.243712) (xy 180.288032 -37.17545) (xy 180.238934 -37.102421) (xy 180.196681 -37.025229)
			(xy 180.161622 -36.944515) (xy 180.134047 -36.860947) (xy 180.114187 -36.775218) (xy 180.102204 -36.688038)
			(xy 180.098199 -36.60013) (xy 156.031184 -36.60013) (xy 156.030683 -36.64413) (xy 156.022681 -36.731765)
			(xy 156.006743 -36.818309) (xy 155.983001 -36.903045) (xy 155.951652 -36.985271) (xy 155.912955 -37.064306)
			(xy 155.867232 -37.139494) (xy 155.814861 -37.210213) (xy 155.756277 -37.275877) (xy 155.691963 -37.335942)
			(xy 155.622455 -37.389909) (xy 155.548327 -37.437331) (xy 155.470193 -37.477817) (xy 155.388702 -37.51103)
			(xy 155.304528 -37.536694) (xy 155.218369 -37.554598) (xy 155.130939 -37.564593) (xy 155.042962 -37.566597)
			(xy 154.955168 -37.560591) (xy 154.868284 -37.546627) (xy 154.783029 -37.52482) (xy 154.70011 -37.495351)
			(xy 154.620215 -37.458464) (xy 154.544006 -37.414464) (xy 154.472113 -37.363716) (xy 154.405132 -37.306642)
			(xy 154.34362 -37.243712) (xy 154.288084 -37.17545) (xy 154.238986 -37.102421) (xy 154.196733 -37.025229)
			(xy 154.161674 -36.944515) (xy 154.134099 -36.860947) (xy 154.114239 -36.775218) (xy 154.102256 -36.688038)
			(xy 154.098251 -36.60013) (xy 130.031236 -36.60013) (xy 130.030735 -36.64413) (xy 130.022733 -36.731765)
			(xy 130.006795 -36.818309) (xy 129.983053 -36.903045) (xy 129.951704 -36.985271) (xy 129.913007 -37.064306)
			(xy 129.867284 -37.139494) (xy 129.814913 -37.210213) (xy 129.756329 -37.275877) (xy 129.692015 -37.335942)
			(xy 129.622507 -37.389909) (xy 129.548379 -37.437331) (xy 129.470245 -37.477817) (xy 129.388754 -37.51103)
			(xy 129.30458 -37.536694) (xy 129.218421 -37.554598) (xy 129.130991 -37.564593) (xy 129.043014 -37.566597)
			(xy 128.95522 -37.560591) (xy 128.868336 -37.546627) (xy 128.783081 -37.52482) (xy 128.700162 -37.495351)
			(xy 128.620267 -37.458464) (xy 128.544058 -37.414464) (xy 128.472165 -37.363716) (xy 128.405184 -37.306642)
			(xy 128.343672 -37.243712) (xy 128.288136 -37.17545) (xy 128.239038 -37.102421) (xy 128.196785 -37.025229)
			(xy 128.161726 -36.944515) (xy 128.134151 -36.860947) (xy 128.114291 -36.775218) (xy 128.102308 -36.688038)
			(xy 128.098303 -36.60013) (xy 91.930982 -36.60013) (xy 91.930481 -36.64413) (xy 91.922479 -36.731765)
			(xy 91.906541 -36.818309) (xy 91.882799 -36.903045) (xy 91.85145 -36.985271) (xy 91.812753 -37.064306)
			(xy 91.76703 -37.139494) (xy 91.714659 -37.210213) (xy 91.656075 -37.275877) (xy 91.591761 -37.335942)
			(xy 91.522253 -37.389909) (xy 91.448125 -37.437331) (xy 91.369991 -37.477817) (xy 91.2885 -37.51103)
			(xy 91.204326 -37.536694) (xy 91.118167 -37.554598) (xy 91.030737 -37.564593) (xy 90.94276 -37.566597)
			(xy 90.854966 -37.560591) (xy 90.768082 -37.546627) (xy 90.682827 -37.52482) (xy 90.599908 -37.495351)
			(xy 90.520013 -37.458464) (xy 90.443804 -37.414464) (xy 90.371911 -37.363716) (xy 90.30493 -37.306642)
			(xy 90.243418 -37.243712) (xy 90.187882 -37.17545) (xy 90.138784 -37.102421) (xy 90.096531 -37.025229)
			(xy 90.061472 -36.944515) (xy 90.033897 -36.860947) (xy 90.014037 -36.775218) (xy 90.002054 -36.688038)
			(xy 89.998049 -36.60013) (xy 65.931034 -36.60013) (xy 65.930533 -36.64413) (xy 65.922531 -36.731765)
			(xy 65.906593 -36.818309) (xy 65.882851 -36.903045) (xy 65.851502 -36.985271) (xy 65.812805 -37.064306)
			(xy 65.767082 -37.139494) (xy 65.714711 -37.210213) (xy 65.656127 -37.275877) (xy 65.591813 -37.335942)
			(xy 65.522305 -37.389909) (xy 65.448177 -37.437331) (xy 65.370043 -37.477817) (xy 65.288552 -37.51103)
			(xy 65.204378 -37.536694) (xy 65.118219 -37.554598) (xy 65.030789 -37.564593) (xy 64.942812 -37.566597)
			(xy 64.855018 -37.560591) (xy 64.768134 -37.546627) (xy 64.682879 -37.52482) (xy 64.59996 -37.495351)
			(xy 64.520065 -37.458464) (xy 64.443856 -37.414464) (xy 64.371963 -37.363716) (xy 64.304982 -37.306642)
			(xy 64.24347 -37.243712) (xy 64.187934 -37.17545) (xy 64.138836 -37.102421) (xy 64.096583 -37.025229)
			(xy 64.061524 -36.944515) (xy 64.033949 -36.860947) (xy 64.014089 -36.775218) (xy 64.002106 -36.688038)
			(xy 63.998101 -36.60013) (xy 39.931086 -36.60013) (xy 39.930585 -36.64413) (xy 39.922583 -36.731765)
			(xy 39.906645 -36.818309) (xy 39.882903 -36.903045) (xy 39.851554 -36.985271) (xy 39.812857 -37.064306)
			(xy 39.767134 -37.139494) (xy 39.714763 -37.210213) (xy 39.656179 -37.275877) (xy 39.591865 -37.335942)
			(xy 39.522357 -37.389909) (xy 39.448229 -37.437331) (xy 39.370095 -37.477817) (xy 39.288604 -37.51103)
			(xy 39.20443 -37.536694) (xy 39.118271 -37.554598) (xy 39.030841 -37.564593) (xy 38.942864 -37.566597)
			(xy 38.85507 -37.560591) (xy 38.768186 -37.546627) (xy 38.682931 -37.52482) (xy 38.600012 -37.495351)
			(xy 38.520117 -37.458464) (xy 38.443908 -37.414464) (xy 38.372015 -37.363716) (xy 38.305034 -37.306642)
			(xy 38.243522 -37.243712) (xy 38.187986 -37.17545) (xy 38.138888 -37.102421) (xy 38.096635 -37.025229)
			(xy 38.061576 -36.944515) (xy 38.034001 -36.860947) (xy 38.014141 -36.775218) (xy 38.002158 -36.688038)
			(xy 37.998153 -36.60013) (xy 13.931138 -36.60013) (xy 13.930637 -36.64413) (xy 13.922635 -36.731765)
			(xy 13.906697 -36.818309) (xy 13.882955 -36.903045) (xy 13.851606 -36.985271) (xy 13.812909 -37.064306)
			(xy 13.767186 -37.139494) (xy 13.714815 -37.210213) (xy 13.656231 -37.275877) (xy 13.591917 -37.335942)
			(xy 13.522409 -37.389909) (xy 13.448281 -37.437331) (xy 13.370147 -37.477817) (xy 13.288656 -37.51103)
			(xy 13.204482 -37.536694) (xy 13.118323 -37.554598) (xy 13.030893 -37.564593) (xy 12.942916 -37.566597)
			(xy 12.855122 -37.560591) (xy 12.768238 -37.546627) (xy 12.682983 -37.52482) (xy 12.600064 -37.495351)
			(xy 12.520169 -37.458464) (xy 12.44396 -37.414464) (xy 12.372067 -37.363716) (xy 12.305086 -37.306642)
			(xy 12.243574 -37.243712) (xy 12.188038 -37.17545) (xy 12.13894 -37.102421) (xy 12.096687 -37.025229)
			(xy 12.061628 -36.944515) (xy 12.034053 -36.860947) (xy 12.014193 -36.775218) (xy 12.00221 -36.688038)
			(xy 11.998205 -36.60013) (xy 0.508 -36.60013) (xy 0.508 -58.698471) (xy 229.808523 -58.698471) (xy 229.808523 -58.601777)
			(xy 229.816508 -58.505414) (xy 229.832424 -58.410039) (xy 229.85616 -58.316305) (xy 229.887557 -58.22485)
			(xy 229.926398 -58.136301) (xy 229.972419 -58.051261) (xy 230.025305 -57.970313) (xy 230.084696 -57.894008)
			(xy 230.150184 -57.822868) (xy 230.221324 -57.75738) (xy 230.297629 -57.697989) (xy 230.378577 -57.645103)
			(xy 230.463617 -57.599082) (xy 230.552166 -57.560241) (xy 230.643621 -57.528844) (xy 230.737355 -57.505108)
			(xy 230.83273 -57.489192) (xy 230.929093 -57.481207) (xy 231.025787 -57.481207) (xy 231.12215 -57.489192)
			(xy 231.217525 -57.505108) (xy 231.311259 -57.528844) (xy 231.402714 -57.560241) (xy 231.491263 -57.599082)
			(xy 231.576303 -57.645103) (xy 231.657251 -57.697989) (xy 231.733556 -57.75738) (xy 231.804696 -57.822868)
			(xy 231.870184 -57.894008) (xy 231.929575 -57.970313) (xy 231.982461 -58.051261) (xy 232.028482 -58.136301)
			(xy 232.067323 -58.22485) (xy 232.09872 -58.316305) (xy 232.122456 -58.410039) (xy 232.138372 -58.505414)
			(xy 232.146357 -58.601777) (xy 232.146856 -58.650124) (xy 232.146357 -58.698471) (xy 232.138372 -58.794834)
			(xy 232.122456 -58.890209) (xy 232.09872 -58.983943) (xy 232.067323 -59.075398) (xy 232.028482 -59.163947)
			(xy 231.982461 -59.248987) (xy 231.929575 -59.329935) (xy 231.870184 -59.40624) (xy 231.804696 -59.47738)
			(xy 231.733556 -59.542868) (xy 231.657251 -59.602259) (xy 231.576303 -59.655145) (xy 231.491263 -59.701166)
			(xy 231.402714 -59.740007) (xy 231.311259 -59.771404) (xy 231.217525 -59.79514) (xy 231.12215 -59.811056)
			(xy 231.025787 -59.819041) (xy 230.929093 -59.819041) (xy 230.83273 -59.811056) (xy 230.737355 -59.79514)
			(xy 230.643621 -59.771404) (xy 230.552166 -59.740007) (xy 230.463617 -59.701166) (xy 230.378577 -59.655145)
			(xy 230.297629 -59.602259) (xy 230.221324 -59.542868) (xy 230.150184 -59.47738) (xy 230.084696 -59.40624)
			(xy 230.025305 -59.329935) (xy 229.972419 -59.248987) (xy 229.926398 -59.163947) (xy 229.887557 -59.075398)
			(xy 229.85616 -58.983943) (xy 229.832424 -58.890209) (xy 229.816508 -58.794834) (xy 229.808523 -58.698471)
			(xy 0.508 -58.698471) (xy 0.508 -60.13196) (xy 226.436428 -60.13196) (xy 226.436428 -59.26836) (xy 226.436918 -59.238392)
			(xy 226.444741 -59.17897) (xy 226.460254 -59.121077) (xy 226.48319 -59.065704) (xy 226.513157 -59.013798)
			(xy 226.549644 -58.966248) (xy 226.592024 -58.923868) (xy 226.639574 -58.887381) (xy 226.69148 -58.857414)
			(xy 226.746853 -58.834478) (xy 226.804746 -58.818965) (xy 226.864168 -58.811142) (xy 226.924104 -58.811142)
			(xy 226.983526 -58.818965) (xy 227.041419 -58.834478) (xy 227.096792 -58.857414) (xy 227.148698 -58.887381)
			(xy 227.196248 -58.923868) (xy 227.238628 -58.966248) (xy 227.275115 -59.013798) (xy 227.305082 -59.065704)
			(xy 227.328018 -59.121077) (xy 227.343531 -59.17897) (xy 227.351354 -59.238392) (xy 227.351844 -59.26836)
			(xy 227.351844 -60.13196) (xy 227.351354 -60.161928) (xy 227.343531 -60.22135) (xy 227.328018 -60.279243)
			(xy 227.305082 -60.334616) (xy 227.275115 -60.386522) (xy 227.238628 -60.434072) (xy 227.196248 -60.476452)
			(xy 227.148698 -60.512939) (xy 227.096792 -60.542906) (xy 227.041419 -60.565842) (xy 226.983526 -60.581355)
			(xy 226.924104 -60.589178) (xy 226.864168 -60.589178) (xy 226.804746 -60.581355) (xy 226.746853 -60.565842)
			(xy 226.69148 -60.542906) (xy 226.639574 -60.512939) (xy 226.592024 -60.476452) (xy 226.549644 -60.434072)
			(xy 226.513157 -60.386522) (xy 226.48319 -60.334616) (xy 226.460254 -60.279243) (xy 226.444741 -60.22135)
			(xy 226.436918 -60.161928) (xy 226.436428 -60.13196) (xy 0.508 -60.13196) (xy 0.508 -69.798271) (xy 229.808523 -69.798271)
			(xy 229.808523 -69.701577) (xy 229.816508 -69.605214) (xy 229.832424 -69.509839) (xy 229.85616 -69.416105)
			(xy 229.887557 -69.32465) (xy 229.926398 -69.236101) (xy 229.972419 -69.151061) (xy 230.025305 -69.070113)
			(xy 230.084696 -68.993808) (xy 230.150184 -68.922668) (xy 230.221324 -68.85718) (xy 230.297629 -68.797789)
			(xy 230.378577 -68.744903) (xy 230.463617 -68.698882) (xy 230.552166 -68.660041) (xy 230.643621 -68.628644)
			(xy 230.737355 -68.604908) (xy 230.83273 -68.588992) (xy 230.929093 -68.581007) (xy 231.025787 -68.581007)
			(xy 231.12215 -68.588992) (xy 231.217525 -68.604908) (xy 231.311259 -68.628644) (xy 231.402714 -68.660041)
			(xy 231.491263 -68.698882) (xy 231.576303 -68.744903) (xy 231.657251 -68.797789) (xy 231.733556 -68.85718)
			(xy 231.804696 -68.922668) (xy 231.870184 -68.993808) (xy 231.929575 -69.070113) (xy 231.982461 -69.151061)
			(xy 232.028482 -69.236101) (xy 232.067323 -69.32465) (xy 232.09872 -69.416105) (xy 232.122456 -69.509839)
			(xy 232.138372 -69.605214) (xy 232.146357 -69.701577) (xy 232.146856 -69.749924) (xy 232.146357 -69.798271)
			(xy 232.138372 -69.894634) (xy 232.122456 -69.990009) (xy 232.09872 -70.083743) (xy 232.067323 -70.175198)
			(xy 232.028482 -70.263747) (xy 231.982461 -70.348787) (xy 231.929575 -70.429735) (xy 231.870184 -70.50604)
			(xy 231.804696 -70.57718) (xy 231.733556 -70.642668) (xy 231.657251 -70.702059) (xy 231.576303 -70.754945)
			(xy 231.491263 -70.800966) (xy 231.402714 -70.839807) (xy 231.311259 -70.871204) (xy 231.217525 -70.89494)
			(xy 231.12215 -70.910856) (xy 231.025787 -70.918841) (xy 230.929093 -70.918841) (xy 230.83273 -70.910856)
			(xy 230.737355 -70.89494) (xy 230.643621 -70.871204) (xy 230.552166 -70.839807) (xy 230.463617 -70.800966)
			(xy 230.378577 -70.754945) (xy 230.297629 -70.702059) (xy 230.221324 -70.642668) (xy 230.150184 -70.57718)
			(xy 230.084696 -70.50604) (xy 230.025305 -70.429735) (xy 229.972419 -70.348787) (xy 229.926398 -70.263747)
			(xy 229.887557 -70.175198) (xy 229.85616 -70.083743) (xy 229.832424 -69.990009) (xy 229.816508 -69.894634)
			(xy 229.808523 -69.798271) (xy 0.508 -69.798271) (xy 0.508 -75.288385) (xy 262.150829 -75.288385)
			(xy 262.150829 -75.228415) (xy 262.158657 -75.168959) (xy 262.174178 -75.111033) (xy 262.197128 -75.055628)
			(xy 262.227114 -75.003693) (xy 262.263621 -74.956116) (xy 262.306027 -74.913712) (xy 262.353605 -74.877206)
			(xy 262.405541 -74.847222) (xy 262.460946 -74.824274) (xy 262.518872 -74.808754) (xy 262.578329 -74.800928)
			(xy 262.608314 -74.80046) (xy 263.471914 -74.80046) (xy 263.501899 -74.800907) (xy 263.561356 -74.808736)
			(xy 263.619283 -74.824259) (xy 263.674687 -74.84721) (xy 263.726623 -74.877196) (xy 263.7742 -74.913705)
			(xy 263.816604 -74.956111) (xy 263.853111 -75.003689) (xy 263.883096 -75.055625) (xy 263.906045 -75.111031)
			(xy 263.921566 -75.168958) (xy 263.929394 -75.228415) (xy 263.929394 -75.288385) (xy 263.921566 -75.347842)
			(xy 263.906045 -75.405769) (xy 263.883096 -75.461175) (xy 263.853111 -75.513111) (xy 263.816604 -75.560689)
			(xy 263.7742 -75.603095) (xy 263.726623 -75.639604) (xy 263.674687 -75.66959) (xy 263.619283 -75.692541)
			(xy 263.561356 -75.708064) (xy 263.501899 -75.715893) (xy 263.471914 -75.716384) (xy 262.608314 -75.716384)
			(xy 262.578329 -75.715872) (xy 262.518872 -75.708046) (xy 262.460946 -75.692526) (xy 262.405541 -75.669578)
			(xy 262.353605 -75.639594) (xy 262.306027 -75.603088) (xy 262.263621 -75.560684) (xy 262.227114 -75.513107)
			(xy 262.197128 -75.461172) (xy 262.174178 -75.405767) (xy 262.158657 -75.347841) (xy 262.150829 -75.288385)
			(xy 0.508 -75.288385) (xy 0.508 -76.826085) (xy 229.640845 -76.826085) (xy 229.640845 -76.766115)
			(xy 229.648673 -76.706658) (xy 229.664196 -76.648731) (xy 229.687147 -76.593327) (xy 229.717134 -76.541392)
			(xy 229.753643 -76.493816) (xy 229.796051 -76.451413) (xy 229.84363 -76.414908) (xy 229.895568 -76.384926)
			(xy 229.950975 -76.361981) (xy 230.008903 -76.346464) (xy 230.068361 -76.338642) (xy 230.098346 -76.338176)
			(xy 230.961946 -76.338176) (xy 230.991931 -76.338593) (xy 231.051387 -76.346426) (xy 231.109312 -76.361952)
			(xy 231.164715 -76.384906) (xy 231.216648 -76.414894) (xy 231.264223 -76.451404) (xy 231.306626 -76.493811)
			(xy 231.343131 -76.54139) (xy 231.373114 -76.593326) (xy 231.396063 -76.648732) (xy 231.411583 -76.706658)
			(xy 231.41941 -76.766115) (xy 231.41941 -76.826085) (xy 231.411583 -76.885542) (xy 231.396063 -76.943468)
			(xy 231.373114 -76.998874) (xy 231.343131 -77.05081) (xy 231.306626 -77.098389) (xy 231.264223 -77.140796)
			(xy 231.216648 -77.177306) (xy 231.164715 -77.207294) (xy 231.109312 -77.230248) (xy 231.051387 -77.245774)
			(xy 230.991931 -77.253607) (xy 230.961946 -77.2541) (xy 230.098346 -77.2541) (xy 230.068361 -77.253558)
			(xy 230.008903 -77.245736) (xy 229.950975 -77.230219) (xy 229.895568 -77.207274) (xy 229.84363 -77.177292)
			(xy 229.796051 -77.140787) (xy 229.753643 -77.098384) (xy 229.717134 -77.050808) (xy 229.687147 -76.998873)
			(xy 229.664196 -76.943469) (xy 229.648673 -76.885542) (xy 229.640845 -76.826085) (xy 0.508 -76.826085)
			(xy 0.508 -77.365367) (xy 105.150162 -77.365367) (xy 105.150162 -77.305433) (xy 105.157985 -77.246011)
			(xy 105.173496 -77.188119) (xy 105.19643 -77.132746) (xy 105.226396 -77.08084) (xy 105.26288 -77.03329)
			(xy 105.305258 -76.990908) (xy 105.352805 -76.954419) (xy 105.404708 -76.924449) (xy 105.460079 -76.901509)
			(xy 105.51797 -76.885993) (xy 105.577391 -76.878165) (xy 105.607358 -76.877672) (xy 106.470958 -76.877672)
			(xy 106.500928 -76.878178) (xy 106.560354 -76.885997) (xy 106.618252 -76.901506) (xy 106.67363 -76.92444)
			(xy 106.72554 -76.954406) (xy 106.773095 -76.990892) (xy 106.81548 -77.033273) (xy 106.851971 -77.080825)
			(xy 106.881942 -77.132732) (xy 106.904881 -77.188108) (xy 106.920395 -77.246004) (xy 106.928219 -77.305431)
			(xy 106.928219 -77.365367) (xy 109.150162 -77.365367) (xy 109.150162 -77.305433) (xy 109.157984 -77.246012)
			(xy 109.173495 -77.18812) (xy 109.196429 -77.132748) (xy 109.226394 -77.080843) (xy 109.262878 -77.033292)
			(xy 109.305255 -76.990911) (xy 109.352801 -76.954422) (xy 109.404703 -76.924452) (xy 109.460073 -76.901511)
			(xy 109.517963 -76.885994) (xy 109.577383 -76.878165) (xy 109.60735 -76.877672) (xy 110.47095 -76.877672)
			(xy 110.50092 -76.878178) (xy 110.560347 -76.885996) (xy 110.618246 -76.901504) (xy 110.673625 -76.924437)
			(xy 110.725536 -76.954403) (xy 110.773092 -76.990889) (xy 110.815478 -77.03327) (xy 110.851969 -77.080822)
			(xy 110.881941 -77.13273) (xy 110.90488 -77.188107) (xy 110.920395 -77.246003) (xy 110.928219 -77.30543)
			(xy 110.928219 -77.36537) (xy 110.920395 -77.424797) (xy 110.90488 -77.482693) (xy 110.881941 -77.53807)
			(xy 110.851969 -77.589978) (xy 110.815478 -77.63753) (xy 110.773092 -77.679911) (xy 110.725536 -77.716397)
			(xy 110.673625 -77.746363) (xy 110.618246 -77.769296) (xy 110.560347 -77.784804) (xy 110.50092 -77.792622)
			(xy 110.47095 -77.793088) (xy 109.60735 -77.793088) (xy 109.577383 -77.792635) (xy 109.517963 -77.784806)
			(xy 109.460073 -77.769289) (xy 109.404703 -77.746348) (xy 109.352801 -77.716378) (xy 109.305255 -77.679889)
			(xy 109.262878 -77.637508) (xy 109.226394 -77.589957) (xy 109.196429 -77.538052) (xy 109.173495 -77.48268)
			(xy 109.157984 -77.424788) (xy 109.150162 -77.365367) (xy 106.928219 -77.365367) (xy 106.928219 -77.365369)
			(xy 106.920395 -77.424796) (xy 106.904881 -77.482692) (xy 106.881942 -77.538068) (xy 106.851971 -77.589975)
			(xy 106.81548 -77.637527) (xy 106.773095 -77.679908) (xy 106.72554 -77.716394) (xy 106.67363 -77.74636)
			(xy 106.618252 -77.769294) (xy 106.560354 -77.784803) (xy 106.500928 -77.792622) (xy 106.470958 -77.793088)
			(xy 105.607358 -77.793088) (xy 105.577391 -77.792635) (xy 105.51797 -77.784807) (xy 105.460079 -77.769291)
			(xy 105.404708 -77.746351) (xy 105.352805 -77.716381) (xy 105.305258 -77.679892) (xy 105.26288 -77.63751)
			(xy 105.226396 -77.58996) (xy 105.19643 -77.538054) (xy 105.173496 -77.482681) (xy 105.157985 -77.424789)
			(xy 105.150162 -77.365367) (xy 0.508 -77.365367) (xy 0.508 -78.127367) (xy 107.150162 -78.127367)
			(xy 107.150162 -78.067433) (xy 107.157984 -78.008012) (xy 107.173496 -77.950119) (xy 107.19643 -77.894747)
			(xy 107.226395 -77.842842) (xy 107.262879 -77.795291) (xy 107.305256 -77.752909) (xy 107.352803 -77.716421)
			(xy 107.404706 -77.68645) (xy 107.460076 -77.66351) (xy 107.517966 -77.647993) (xy 107.577387 -77.640165)
			(xy 107.607354 -77.639672) (xy 108.470954 -77.639672) (xy 108.500924 -77.640178) (xy 108.560351 -77.647996)
			(xy 108.618249 -77.663505) (xy 108.673627 -77.686438) (xy 108.725538 -77.716405) (xy 108.773094 -77.752891)
			(xy 108.815479 -77.795272) (xy 108.85197 -77.842823) (xy 108.881941 -77.894731) (xy 108.90488 -77.950107)
			(xy 108.920395 -78.008004) (xy 108.928219 -78.06743) (xy 108.928219 -78.12737) (xy 108.920395 -78.186796)
			(xy 108.90488 -78.244693) (xy 108.881941 -78.300069) (xy 108.85197 -78.351977) (xy 108.815479 -78.399528)
			(xy 108.773093 -78.441909) (xy 108.725538 -78.478395) (xy 108.673627 -78.508362) (xy 108.618249 -78.531295)
			(xy 108.560351 -78.546804) (xy 108.500924 -78.554622) (xy 108.470954 -78.555088) (xy 107.607354 -78.555088)
			(xy 107.577387 -78.554635) (xy 107.517966 -78.546807) (xy 107.460076 -78.53129) (xy 107.404706 -78.50835)
			(xy 107.352803 -78.478379) (xy 107.305256 -78.441891) (xy 107.262879 -78.399509) (xy 107.226395 -78.351958)
			(xy 107.19643 -78.300053) (xy 107.173496 -78.244681) (xy 107.157984 -78.186788) (xy 107.150162 -78.127367)
			(xy 0.508 -78.127367) (xy 0.508 -79.238094) (xy 227.9777 -79.238094) (xy 227.9777 -78.374494) (xy 227.97819 -78.344526)
			(xy 227.986013 -78.285104) (xy 228.001526 -78.227211) (xy 228.024462 -78.171838) (xy 228.054429 -78.119932)
			(xy 228.090916 -78.072382) (xy 228.133296 -78.030002) (xy 228.180846 -77.993515) (xy 228.232752 -77.963548)
			(xy 228.288125 -77.940612) (xy 228.346018 -77.925099) (xy 228.40544 -77.917276) (xy 228.465376 -77.917276)
			(xy 228.524798 -77.925099) (xy 228.582691 -77.940612) (xy 228.638064 -77.963548) (xy 228.68997 -77.993515)
			(xy 228.73752 -78.030002) (xy 228.7799 -78.072382) (xy 228.816387 -78.119932) (xy 228.83413 -78.150664)
			(xy 336.40703 -78.150664) (xy 336.40703 -78.090736) (xy 336.414852 -78.031319) (xy 336.430363 -77.973433)
			(xy 336.453297 -77.918066) (xy 336.483261 -77.866166) (xy 336.519743 -77.818621) (xy 336.562119 -77.776245)
			(xy 336.609664 -77.739762) (xy 336.661564 -77.709797) (xy 336.716931 -77.686864) (xy 336.774817 -77.671353)
			(xy 336.834234 -77.66353) (xy 336.864198 -77.66304) (xy 337.727798 -77.66304) (xy 337.75777 -77.663413)
			(xy 337.817202 -77.671237) (xy 337.875104 -77.686751) (xy 337.930486 -77.709691) (xy 337.982399 -77.739663)
			(xy 338.029957 -77.776155) (xy 338.072344 -77.818542) (xy 338.108836 -77.866099) (xy 338.138808 -77.918013)
			(xy 338.161748 -77.973394) (xy 338.177263 -78.031296) (xy 338.185087 -78.090728) (xy 338.185087 -78.150672)
			(xy 338.177263 -78.210104) (xy 338.161748 -78.268006) (xy 338.138808 -78.323387) (xy 338.108836 -78.375301)
			(xy 338.072344 -78.422858) (xy 338.029957 -78.465245) (xy 337.982399 -78.501737) (xy 337.930486 -78.531709)
			(xy 337.875104 -78.554649) (xy 337.817202 -78.570163) (xy 337.75777 -78.577987) (xy 337.727798 -78.578456)
			(xy 336.864198 -78.578456) (xy 336.834234 -78.57787) (xy 336.774817 -78.570047) (xy 336.716931 -78.554536)
			(xy 336.661564 -78.531603) (xy 336.609664 -78.501638) (xy 336.562119 -78.465155) (xy 336.519743 -78.422779)
			(xy 336.483261 -78.375234) (xy 336.453297 -78.323334) (xy 336.430363 -78.267967) (xy 336.414852 -78.210081)
			(xy 336.40703 -78.150664) (xy 228.83413 -78.150664) (xy 228.846354 -78.171838) (xy 228.86929 -78.227211)
			(xy 228.884803 -78.285104) (xy 228.892626 -78.344526) (xy 228.893116 -78.374494) (xy 228.893116 -79.238094)
			(xy 228.892626 -79.268062) (xy 228.884803 -79.327484) (xy 228.86929 -79.385377) (xy 228.846354 -79.44075)
			(xy 228.816387 -79.492656) (xy 228.7799 -79.540206) (xy 228.73752 -79.582586) (xy 228.68997 -79.619073)
			(xy 228.638064 -79.64904) (xy 228.582691 -79.671976) (xy 228.524798 -79.687489) (xy 228.465376 -79.695312)
			(xy 228.40544 -79.695312) (xy 228.346018 -79.687489) (xy 228.288125 -79.671976) (xy 228.232752 -79.64904)
			(xy 228.180846 -79.619073) (xy 228.133296 -79.582586) (xy 228.090916 -79.540206) (xy 228.054429 -79.492656)
			(xy 228.024462 -79.44075) (xy 228.001526 -79.385377) (xy 227.986013 -79.327484) (xy 227.97819 -79.268062)
			(xy 227.9777 -79.238094) (xy 0.508 -79.238094) (xy 0.508 -80.183482) (xy 237.540292 -80.183482) (xy 237.540292 -79.319882)
			(xy 237.540782 -79.289914) (xy 237.548605 -79.230492) (xy 237.564118 -79.172599) (xy 237.587054 -79.117226)
			(xy 237.617021 -79.06532) (xy 237.653508 -79.01777) (xy 237.695888 -78.97539) (xy 237.743438 -78.938903)
			(xy 237.795344 -78.908936) (xy 237.850717 -78.886) (xy 237.90861 -78.870487) (xy 237.968032 -78.862664)
			(xy 238.027968 -78.862664) (xy 238.08739 -78.870487) (xy 238.145283 -78.886) (xy 238.200656 -78.908936)
			(xy 238.207117 -78.912666) (xy 334.407009 -78.912666) (xy 334.407009 -78.852734) (xy 334.414832 -78.793315)
			(xy 334.430343 -78.735425) (xy 334.453278 -78.680055) (xy 334.483244 -78.628153) (xy 334.519729 -78.580606)
			(xy 334.562107 -78.538227) (xy 334.609654 -78.501743) (xy 334.661557 -78.471777) (xy 334.716927 -78.448843)
			(xy 334.774817 -78.433331) (xy 334.834236 -78.425509) (xy 334.864202 -78.42504) (xy 335.727802 -78.42504)
			(xy 335.757773 -78.425434) (xy 335.817201 -78.433258) (xy 335.8751 -78.448773) (xy 335.930479 -78.471711)
			(xy 335.982389 -78.501682) (xy 336.029944 -78.538172) (xy 336.072329 -78.580557) (xy 336.108819 -78.628112)
			(xy 336.13879 -78.680023) (xy 336.161728 -78.735402) (xy 336.177242 -78.793301) (xy 336.185066 -78.852729)
			(xy 336.185066 -78.912664) (xy 338.40703 -78.912664) (xy 338.40703 -78.852736) (xy 338.414852 -78.79332)
			(xy 338.430363 -78.735433) (xy 338.453296 -78.680067) (xy 338.48326 -78.628167) (xy 338.519742 -78.580622)
			(xy 338.562118 -78.538246) (xy 338.609662 -78.501763) (xy 338.661561 -78.471799) (xy 338.716928 -78.448865)
			(xy 338.774814 -78.433353) (xy 338.83423 -78.42553) (xy 338.864194 -78.42504) (xy 339.727794 -78.42504)
			(xy 339.757766 -78.425412) (xy 339.817199 -78.433236) (xy 339.875101 -78.44875) (xy 339.930483 -78.47169)
			(xy 339.982397 -78.501662) (xy 340.029955 -78.538153) (xy 340.072343 -78.580541) (xy 340.108835 -78.628098)
			(xy 340.138808 -78.680011) (xy 340.161748 -78.735393) (xy 340.177263 -78.793296) (xy 340.185087 -78.852728)
			(xy 340.185087 -78.912672) (xy 340.177263 -78.972104) (xy 340.161748 -79.030007) (xy 340.138808 -79.085389)
			(xy 340.108835 -79.137302) (xy 340.072343 -79.184859) (xy 340.029955 -79.227247) (xy 339.982397 -79.263738)
			(xy 339.930483 -79.29371) (xy 339.875101 -79.31665) (xy 339.817199 -79.332164) (xy 339.757766 -79.339988)
			(xy 339.727794 -79.340456) (xy 338.864194 -79.340456) (xy 338.83423 -79.33987) (xy 338.774814 -79.332047)
			(xy 338.716928 -79.316535) (xy 338.661561 -79.293601) (xy 338.609662 -79.263637) (xy 338.562118 -79.227154)
			(xy 338.519742 -79.184778) (xy 338.48326 -79.137233) (xy 338.453296 -79.085333) (xy 338.430363 -79.029967)
			(xy 338.414852 -78.97208) (xy 338.40703 -78.912664) (xy 336.185066 -78.912664) (xy 336.185066 -78.912671)
			(xy 336.177242 -78.972099) (xy 336.161728 -79.029998) (xy 336.13879 -79.085377) (xy 336.108819 -79.137288)
			(xy 336.072329 -79.184843) (xy 336.029944 -79.227228) (xy 335.982389 -79.263718) (xy 335.930479 -79.293689)
			(xy 335.8751 -79.316627) (xy 335.817201 -79.332142) (xy 335.757773 -79.339966) (xy 335.727802 -79.340456)
			(xy 334.864202 -79.340456) (xy 334.834236 -79.339891) (xy 334.774817 -79.332069) (xy 334.716927 -79.316557)
			(xy 334.661557 -79.293623) (xy 334.609654 -79.263657) (xy 334.562107 -79.227173) (xy 334.519729 -79.184794)
			(xy 334.483244 -79.137247) (xy 334.453278 -79.085345) (xy 334.430343 -79.029975) (xy 334.414832 -78.972085)
			(xy 334.407009 -78.912666) (xy 238.207117 -78.912666) (xy 238.252562 -78.938903) (xy 238.300112 -78.97539)
			(xy 238.342492 -79.01777) (xy 238.378979 -79.06532) (xy 238.408946 -79.117226) (xy 238.431882 -79.172599)
			(xy 238.447395 -79.230492) (xy 238.455218 -79.289914) (xy 238.455708 -79.319882) (xy 238.455708 -80.183482)
			(xy 238.455218 -80.21345) (xy 238.447395 -80.272872) (xy 238.431882 -80.330765) (xy 238.408946 -80.386138)
			(xy 238.378979 -80.438044) (xy 238.342492 -80.485594) (xy 238.300112 -80.527974) (xy 238.252562 -80.564461)
			(xy 238.200656 -80.594428) (xy 238.145283 -80.617364) (xy 238.08739 -80.632877) (xy 238.027968 -80.6407)
			(xy 237.968032 -80.6407) (xy 237.90861 -80.632877) (xy 237.850717 -80.617364) (xy 237.795344 -80.594428)
			(xy 237.743438 -80.564461) (xy 237.695888 -80.527974) (xy 237.653508 -80.485594) (xy 237.617021 -80.438044)
			(xy 237.587054 -80.386138) (xy 237.564118 -80.330765) (xy 237.548605 -80.272872) (xy 237.540782 -80.21345)
			(xy 237.540292 -80.183482) (xy 0.508 -80.183482) (xy 0.508 -82.131916) (xy 0.508487 -82.185165) (xy 0.516104 -82.291392)
			(xy 0.531277 -82.396804) (xy 0.553928 -82.500867) (xy 0.583941 -82.603049) (xy 0.621164 -82.702831)
			(xy 0.665407 -82.799705) (xy 0.716446 -82.893178) (xy 0.774019 -82.982773) (xy 0.837835 -83.068035)
			(xy 0.907568 -83.14853) (xy 0.94488 -83.186524) (xy 2.783716 -85.025538) (xy 44.856389 -85.025538)
			(xy 44.856389 -84.896398) (xy 44.864339 -84.767503) (xy 44.880209 -84.639343) (xy 44.903938 -84.512402)
			(xy 44.935437 -84.387163) (xy 44.974586 -84.2641) (xy 45.021237 -84.143681) (xy 45.075212 -84.026362)
			(xy 45.136307 -83.912588) (xy 45.20429 -83.802791) (xy 45.278904 -83.697388) (xy 45.359865 -83.596778)
			(xy 45.446865 -83.501343) (xy 45.539576 -83.411444) (xy 45.637646 -83.327423) (xy 45.740701 -83.249599)
			(xy 45.848352 -83.178267) (xy 45.960191 -83.113697) (xy 46.075792 -83.056135) (xy 46.194717 -83.005798)
			(xy 46.316516 -82.962878) (xy 46.440726 -82.927537) (xy 46.566875 -82.89991) (xy 46.694487 -82.880101)
			(xy 46.823076 -82.868185) (xy 46.952154 -82.864209) (xy 47.081232 -82.868185) (xy 47.209821 -82.880101)
			(xy 47.337433 -82.89991) (xy 47.463582 -82.927537) (xy 47.587792 -82.962878) (xy 47.709591 -83.005798)
			(xy 47.828516 -83.056135) (xy 47.944117 -83.113697) (xy 48.055956 -83.178267) (xy 48.163607 -83.249599)
			(xy 48.266662 -83.327423) (xy 48.303507 -83.35899) (xy 116.623592 -83.35899) (xy 116.623592 -82.49539)
			(xy 116.624082 -82.465422) (xy 116.631905 -82.406) (xy 116.647418 -82.348107) (xy 116.670354 -82.292734)
			(xy 116.700321 -82.240828) (xy 116.736808 -82.193278) (xy 116.779188 -82.150898) (xy 116.826738 -82.114411)
			(xy 116.878644 -82.084444) (xy 116.934017 -82.061508) (xy 116.99191 -82.045995) (xy 117.051332 -82.038172)
			(xy 117.111268 -82.038172) (xy 117.17069 -82.045995) (xy 117.228583 -82.061508) (xy 117.283956 -82.084444)
			(xy 117.335862 -82.114411) (xy 117.383412 -82.150898) (xy 117.425792 -82.193278) (xy 117.462279 -82.240828)
			(xy 117.492246 -82.292734) (xy 117.515182 -82.348107) (xy 117.530695 -82.406) (xy 117.538518 -82.465422)
			(xy 117.539008 -82.49539) (xy 117.539008 -83.35899) (xy 117.538875 -83.367118) (xy 232.68432 -83.367118)
			(xy 232.68432 -82.503518) (xy 232.68481 -82.47355) (xy 232.692633 -82.414128) (xy 232.708146 -82.356235)
			(xy 232.731082 -82.300862) (xy 232.761049 -82.248956) (xy 232.797536 -82.201406) (xy 232.839916 -82.159026)
			(xy 232.887466 -82.122539) (xy 232.939372 -82.092572) (xy 232.994745 -82.069636) (xy 233.052638 -82.054123)
			(xy 233.11206 -82.0463) (xy 233.171996 -82.0463) (xy 233.231418 -82.054123) (xy 233.289311 -82.069636)
			(xy 233.344684 -82.092572) (xy 233.39659 -82.122539) (xy 233.44414 -82.159026) (xy 233.48652 -82.201406)
			(xy 233.523007 -82.248956) (xy 233.552974 -82.300862) (xy 233.568014 -82.337171) (xy 238.132537 -82.337171)
			(xy 238.132537 -82.277229) (xy 238.140362 -82.217799) (xy 238.155876 -82.159898) (xy 238.178816 -82.104519)
			(xy 238.208788 -82.052607) (xy 238.24528 -82.005052) (xy 238.287667 -81.962667) (xy 238.335224 -81.926177)
			(xy 238.387137 -81.896207) (xy 238.442517 -81.87327) (xy 238.500418 -81.857758) (xy 238.559849 -81.849936)
			(xy 238.58982 -81.849468) (xy 239.45342 -81.849468) (xy 239.483385 -81.850007) (xy 239.542803 -81.857832)
			(xy 239.600691 -81.873345) (xy 239.656058 -81.896282) (xy 239.707959 -81.926248) (xy 239.755504 -81.962733)
			(xy 239.769238 -81.976468) (xy 273.798284 -81.976468) (xy 273.798284 -81.112868) (xy 273.798774 -81.0829)
			(xy 273.806597 -81.023478) (xy 273.82211 -80.965585) (xy 273.845046 -80.910212) (xy 273.875013 -80.858306)
			(xy 273.9115 -80.810756) (xy 273.95388 -80.768376) (xy 274.00143 -80.731889) (xy 274.053336 -80.701922)
			(xy 274.108709 -80.678986) (xy 274.166602 -80.663473) (xy 274.226024 -80.65565) (xy 274.28596 -80.65565)
			(xy 274.345382 -80.663473) (xy 274.403275 -80.678986) (xy 274.458648 -80.701922) (xy 274.510554 -80.731889)
			(xy 274.558104 -80.768376) (xy 274.600484 -80.810756) (xy 274.636971 -80.858306) (xy 274.666938 -80.910212)
			(xy 274.689874 -80.965585) (xy 274.705387 -81.023478) (xy 274.71321 -81.0829) (xy 274.7137 -81.112868)
			(xy 274.7137 -81.976468) (xy 274.71321 -82.006436) (xy 274.705387 -82.065858) (xy 274.689874 -82.123751)
			(xy 274.666938 -82.179124) (xy 274.636971 -82.23103) (xy 274.600484 -82.27858) (xy 274.558104 -82.32096)
			(xy 274.510554 -82.357447) (xy 274.458648 -82.387414) (xy 274.403275 -82.41035) (xy 274.345382 -82.425863)
			(xy 274.28596 -82.433686) (xy 274.226024 -82.433686) (xy 274.166602 -82.425863) (xy 274.108709 -82.41035)
			(xy 274.053336 -82.387414) (xy 274.00143 -82.357447) (xy 273.95388 -82.32096) (xy 273.9115 -82.27858)
			(xy 273.875013 -82.23103) (xy 273.845046 -82.179124) (xy 273.82211 -82.123751) (xy 273.806597 -82.065858)
			(xy 273.798774 -82.006436) (xy 273.798284 -81.976468) (xy 239.769238 -81.976468) (xy 239.79788 -82.005111)
			(xy 239.834363 -82.052658) (xy 239.864327 -82.10456) (xy 239.887261 -82.159928) (xy 239.902772 -82.217817)
			(xy 239.910594 -82.277235) (xy 239.910594 -82.337165) (xy 239.902772 -82.396583) (xy 239.887261 -82.454472)
			(xy 239.864327 -82.50984) (xy 239.834363 -82.561742) (xy 239.79788 -82.609289) (xy 239.755504 -82.651667)
			(xy 239.707959 -82.688152) (xy 239.656058 -82.718118) (xy 239.600691 -82.741055) (xy 239.542803 -82.756568)
			(xy 239.483385 -82.764393) (xy 239.45342 -82.764884) (xy 238.58982 -82.764884) (xy 238.559849 -82.764464)
			(xy 238.500418 -82.756642) (xy 238.442517 -82.74113) (xy 238.387137 -82.718193) (xy 238.335224 -82.688223)
			(xy 238.287667 -82.651733) (xy 238.24528 -82.609348) (xy 238.208788 -82.561793) (xy 238.178816 -82.509881)
			(xy 238.155876 -82.454502) (xy 238.140362 -82.396601) (xy 238.132537 -82.337171) (xy 233.568014 -82.337171)
			(xy 233.57591 -82.356235) (xy 233.591423 -82.414128) (xy 233.599246 -82.47355) (xy 233.599736 -82.503518)
			(xy 233.599736 -83.367118) (xy 233.599246 -83.397086) (xy 233.591423 -83.456508) (xy 233.57591 -83.514401)
			(xy 233.552974 -83.569774) (xy 233.523007 -83.62168) (xy 233.48652 -83.66923) (xy 233.44414 -83.71161)
			(xy 233.39659 -83.748097) (xy 233.344684 -83.778064) (xy 233.289311 -83.801) (xy 233.231418 -83.816513)
			(xy 233.171996 -83.824336) (xy 233.11206 -83.824336) (xy 233.052638 -83.816513) (xy 232.994745 -83.801)
			(xy 232.939372 -83.778064) (xy 232.887466 -83.748097) (xy 232.839916 -83.71161) (xy 232.797536 -83.66923)
			(xy 232.761049 -83.62168) (xy 232.731082 -83.569774) (xy 232.708146 -83.514401) (xy 232.692633 -83.456508)
			(xy 232.68481 -83.397086) (xy 232.68432 -83.367118) (xy 117.538875 -83.367118) (xy 117.538518 -83.388958)
			(xy 117.530695 -83.44838) (xy 117.515182 -83.506273) (xy 117.492246 -83.561646) (xy 117.462279 -83.613552)
			(xy 117.425792 -83.661102) (xy 117.383412 -83.703482) (xy 117.335862 -83.739969) (xy 117.283956 -83.769936)
			(xy 117.228583 -83.792872) (xy 117.17069 -83.808385) (xy 117.111268 -83.816208) (xy 117.051332 -83.816208)
			(xy 116.99191 -83.808385) (xy 116.934017 -83.792872) (xy 116.878644 -83.769936) (xy 116.826738 -83.739969)
			(xy 116.779188 -83.703482) (xy 116.736808 -83.661102) (xy 116.700321 -83.613552) (xy 116.670354 -83.561646)
			(xy 116.647418 -83.506273) (xy 116.631905 -83.44838) (xy 116.624082 -83.388958) (xy 116.623592 -83.35899)
			(xy 48.303507 -83.35899) (xy 48.364732 -83.411444) (xy 48.457443 -83.501343) (xy 48.544443 -83.596778)
			(xy 48.625404 -83.697388) (xy 48.700018 -83.802791) (xy 48.768001 -83.912588) (xy 48.829096 -84.026362)
			(xy 48.883071 -84.143681) (xy 48.929722 -84.2641) (xy 48.968871 -84.387163) (xy 49.00037 -84.512402)
			(xy 49.024099 -84.639343) (xy 49.039969 -84.767503) (xy 49.047919 -84.896398) (xy 49.048416 -84.960968)
			(xy 49.047919 -85.025538) (xy 49.039969 -85.154433) (xy 49.024099 -85.282593) (xy 49.009819 -85.358986)
			(xy 117.385592 -85.358986) (xy 117.385592 -84.495386) (xy 117.386082 -84.465418) (xy 117.393905 -84.405996)
			(xy 117.409418 -84.348103) (xy 117.432354 -84.29273) (xy 117.462321 -84.240824) (xy 117.498808 -84.193274)
			(xy 117.541188 -84.150894) (xy 117.588738 -84.114407) (xy 117.640644 -84.08444) (xy 117.696017 -84.061504)
			(xy 117.75391 -84.045991) (xy 117.813332 -84.038168) (xy 117.873268 -84.038168) (xy 117.93269 -84.045991)
			(xy 117.990583 -84.061504) (xy 118.045956 -84.08444) (xy 118.097862 -84.114407) (xy 118.145412 -84.150894)
			(xy 118.187792 -84.193274) (xy 118.224279 -84.240824) (xy 118.254246 -84.29273) (xy 118.277182 -84.348103)
			(xy 118.292695 -84.405996) (xy 118.300518 -84.465418) (xy 118.301008 -84.495386) (xy 118.301008 -85.358986)
			(xy 118.300518 -85.388954) (xy 118.292695 -85.448376) (xy 118.289959 -85.458587) (xy 232.264389 -85.458587)
			(xy 232.264389 -85.398613) (xy 232.272218 -85.339151) (xy 232.28774 -85.28122) (xy 232.310692 -85.225811)
			(xy 232.34068 -85.173871) (xy 232.377191 -85.126291) (xy 232.4196 -85.083883) (xy 232.467181 -85.047373)
			(xy 232.519122 -85.017387) (xy 232.574531 -84.994437) (xy 232.632463 -84.978915) (xy 232.691925 -84.971088)
			(xy 232.721912 -84.97062) (xy 233.585512 -84.97062) (xy 233.615495 -84.971147) (xy 233.674947 -84.978975)
			(xy 233.732868 -84.994497) (xy 233.788268 -85.017445) (xy 233.840199 -85.047429) (xy 233.887772 -85.083934)
			(xy 233.930174 -85.126337) (xy 233.963295 -85.169502) (xy 238.555276 -85.169502) (xy 238.555276 -84.305902)
			(xy 238.555766 -84.275918) (xy 238.563594 -84.216462) (xy 238.579115 -84.158537) (xy 238.602064 -84.103133)
			(xy 238.632048 -84.051199) (xy 238.668554 -84.003623) (xy 238.710959 -83.961218) (xy 238.758535 -83.924712)
			(xy 238.810469 -83.894728) (xy 238.865873 -83.871779) (xy 238.923798 -83.856258) (xy 238.983254 -83.84843)
			(xy 239.043222 -83.84843) (xy 239.102678 -83.856258) (xy 239.160603 -83.871779) (xy 239.216007 -83.894728)
			(xy 239.267941 -83.924712) (xy 239.315517 -83.961218) (xy 239.357922 -84.003623) (xy 239.394428 -84.051199)
			(xy 239.424412 -84.103133) (xy 239.447361 -84.158537) (xy 239.462882 -84.216462) (xy 239.46603 -84.24037)
			(xy 273.951192 -84.24037) (xy 273.951192 -83.37677) (xy 273.951682 -83.346786) (xy 273.95951 -83.28733)
			(xy 273.975031 -83.229405) (xy 273.99798 -83.174001) (xy 274.027964 -83.122067) (xy 274.06447 -83.074491)
			(xy 274.106875 -83.032086) (xy 274.154451 -82.99558) (xy 274.206385 -82.965596) (xy 274.261789 -82.942647)
			(xy 274.319714 -82.927126) (xy 274.37917 -82.919298) (xy 274.439138 -82.919298) (xy 274.498594 -82.927126)
			(xy 274.556519 -82.942647) (xy 274.611923 -82.965596) (xy 274.663857 -82.99558) (xy 274.711433 -83.032086)
			(xy 274.753838 -83.074491) (xy 274.790344 -83.122067) (xy 274.820328 -83.174001) (xy 274.843277 -83.229405)
			(xy 274.858798 -83.28733) (xy 274.866626 -83.346786) (xy 274.867116 -83.37677) (xy 274.867116 -84.144612)
			(xy 345.879928 -84.144612) (xy 345.879928 -83.281012) (xy 345.880418 -83.251028) (xy 345.888246 -83.191572)
			(xy 345.903767 -83.133647) (xy 345.926716 -83.078243) (xy 345.9567 -83.026309) (xy 345.993206 -82.978733)
			(xy 346.035611 -82.936328) (xy 346.083187 -82.899822) (xy 346.135121 -82.869838) (xy 346.190525 -82.846889)
			(xy 346.24845 -82.831368) (xy 346.307906 -82.82354) (xy 346.367874 -82.82354) (xy 346.42733 -82.831368)
			(xy 346.485255 -82.846889) (xy 346.540659 -82.869838) (xy 346.592593 -82.899822) (xy 346.640169 -82.936328)
			(xy 346.682574 -82.978733) (xy 346.71908 -83.026309) (xy 346.749064 -83.078243) (xy 346.772013 -83.133647)
			(xy 346.787534 -83.191572) (xy 346.795362 -83.251028) (xy 346.795852 -83.281012) (xy 346.795852 -84.144612)
			(xy 346.795362 -84.174596) (xy 346.787534 -84.234052) (xy 346.772013 -84.291977) (xy 346.749064 -84.347381)
			(xy 346.71908 -84.399315) (xy 346.682574 -84.446891) (xy 346.640169 -84.489296) (xy 346.592593 -84.525802)
			(xy 346.540659 -84.555786) (xy 346.485255 -84.578735) (xy 346.42733 -84.594256) (xy 346.367874 -84.602084)
			(xy 346.307906 -84.602084) (xy 346.24845 -84.594256) (xy 346.190525 -84.578735) (xy 346.135121 -84.555786)
			(xy 346.083187 -84.525802) (xy 346.035611 -84.489296) (xy 345.993206 -84.446891) (xy 345.9567 -84.399315)
			(xy 345.926716 -84.347381) (xy 345.903767 -84.291977) (xy 345.888246 -84.234052) (xy 345.880418 -84.174596)
			(xy 345.879928 -84.144612) (xy 274.867116 -84.144612) (xy 274.867116 -84.24037) (xy 274.866626 -84.270354)
			(xy 274.858798 -84.32981) (xy 274.843277 -84.387735) (xy 274.820328 -84.443139) (xy 274.790344 -84.495073)
			(xy 274.753838 -84.542649) (xy 274.711433 -84.585054) (xy 274.663857 -84.62156) (xy 274.611923 -84.651544)
			(xy 274.556519 -84.674493) (xy 274.498594 -84.690014) (xy 274.439138 -84.697842) (xy 274.37917 -84.697842)
			(xy 274.319714 -84.690014) (xy 274.261789 -84.674493) (xy 274.206385 -84.651544) (xy 274.154451 -84.62156)
			(xy 274.106875 -84.585054) (xy 274.06447 -84.542649) (xy 274.027964 -84.495073) (xy 273.99798 -84.443139)
			(xy 273.975031 -84.387735) (xy 273.95951 -84.32981) (xy 273.951682 -84.270354) (xy 273.951192 -84.24037)
			(xy 239.46603 -84.24037) (xy 239.47071 -84.275918) (xy 239.4712 -84.305902) (xy 239.4712 -85.169502)
			(xy 239.47071 -85.199486) (xy 239.462882 -85.258942) (xy 239.447361 -85.316867) (xy 239.424412 -85.372271)
			(xy 239.394428 -85.424205) (xy 239.357922 -85.471781) (xy 239.315517 -85.514186) (xy 239.267941 -85.550692)
			(xy 239.216007 -85.580676) (xy 239.160603 -85.603625) (xy 239.102678 -85.619146) (xy 239.043222 -85.626974)
			(xy 238.983254 -85.626974) (xy 238.923798 -85.619146) (xy 238.865873 -85.603625) (xy 238.810469 -85.580676)
			(xy 238.758535 -85.550692) (xy 238.710959 -85.514186) (xy 238.668554 -85.471781) (xy 238.632048 -85.424205)
			(xy 238.602064 -85.372271) (xy 238.579115 -85.316867) (xy 238.563594 -85.258942) (xy 238.555766 -85.199486)
			(xy 238.555276 -85.169502) (xy 233.963295 -85.169502) (xy 233.966678 -85.173911) (xy 233.99666 -85.225842)
			(xy 234.019607 -85.281243) (xy 234.035127 -85.339165) (xy 234.042954 -85.398617) (xy 234.042954 -85.458583)
			(xy 234.035127 -85.518035) (xy 234.019607 -85.575957) (xy 233.99666 -85.631358) (xy 233.966678 -85.683289)
			(xy 233.930174 -85.730863) (xy 233.887772 -85.773266) (xy 233.840199 -85.809771) (xy 233.788268 -85.839755)
			(xy 233.732868 -85.862703) (xy 233.674947 -85.878225) (xy 233.615495 -85.886053) (xy 233.585512 -85.886544)
			(xy 232.721912 -85.886544) (xy 232.691925 -85.886112) (xy 232.632463 -85.878285) (xy 232.574531 -85.862763)
			(xy 232.519122 -85.839813) (xy 232.467181 -85.809827) (xy 232.4196 -85.773317) (xy 232.377191 -85.730909)
			(xy 232.34068 -85.683329) (xy 232.310692 -85.631389) (xy 232.28774 -85.57598) (xy 232.272218 -85.518049)
			(xy 232.264389 -85.458587) (xy 118.289959 -85.458587) (xy 118.277182 -85.506269) (xy 118.254246 -85.561642)
			(xy 118.224279 -85.613548) (xy 118.187792 -85.661098) (xy 118.145412 -85.703478) (xy 118.097862 -85.739965)
			(xy 118.045956 -85.769932) (xy 117.990583 -85.792868) (xy 117.93269 -85.808381) (xy 117.873268 -85.816204)
			(xy 117.813332 -85.816204) (xy 117.75391 -85.808381) (xy 117.696017 -85.792868) (xy 117.640644 -85.769932)
			(xy 117.588738 -85.739965) (xy 117.541188 -85.703478) (xy 117.498808 -85.661098) (xy 117.462321 -85.613548)
			(xy 117.432354 -85.561642) (xy 117.409418 -85.506269) (xy 117.393905 -85.448376) (xy 117.386082 -85.388954)
			(xy 117.385592 -85.358986) (xy 49.009819 -85.358986) (xy 49.00037 -85.409534) (xy 48.968871 -85.534773)
			(xy 48.929722 -85.657836) (xy 48.883071 -85.778255) (xy 48.829096 -85.895574) (xy 48.768001 -86.009348)
			(xy 48.700018 -86.119145) (xy 48.625404 -86.224548) (xy 48.544443 -86.325158) (xy 48.457443 -86.420593)
			(xy 48.364732 -86.510492) (xy 48.266662 -86.594513) (xy 48.163607 -86.672337) (xy 48.055956 -86.743669)
			(xy 47.944117 -86.808239) (xy 47.937853 -86.811358) (xy 99.84232 -86.811358) (xy 99.84232 -85.947758)
			(xy 99.84281 -85.917774) (xy 99.850638 -85.858318) (xy 99.866159 -85.800393) (xy 99.889108 -85.744989)
			(xy 99.919092 -85.693055) (xy 99.955598 -85.645479) (xy 99.998003 -85.603074) (xy 100.045579 -85.566568)
			(xy 100.097513 -85.536584) (xy 100.152917 -85.513635) (xy 100.210842 -85.498114) (xy 100.270298 -85.490286)
			(xy 100.330266 -85.490286) (xy 100.389722 -85.498114) (xy 100.447647 -85.513635) (xy 100.503051 -85.536584)
			(xy 100.554985 -85.566568) (xy 100.602561 -85.603074) (xy 100.644966 -85.645479) (xy 100.681472 -85.693055)
			(xy 100.711456 -85.744989) (xy 100.734405 -85.800393) (xy 100.749926 -85.858318) (xy 100.757754 -85.917774)
			(xy 100.758244 -85.947758) (xy 100.758244 -86.811358) (xy 100.757754 -86.841342) (xy 100.749926 -86.900798)
			(xy 100.734405 -86.958723) (xy 100.711456 -87.014127) (xy 100.681472 -87.066061) (xy 100.644966 -87.113637)
			(xy 100.602561 -87.156042) (xy 100.554985 -87.192548) (xy 100.503051 -87.222532) (xy 100.447647 -87.245481)
			(xy 100.389722 -87.261002) (xy 100.330266 -87.26883) (xy 100.270298 -87.26883) (xy 100.210842 -87.261002)
			(xy 100.152917 -87.245481) (xy 100.097513 -87.222532) (xy 100.045579 -87.192548) (xy 99.998003 -87.156042)
			(xy 99.955598 -87.113637) (xy 99.919092 -87.066061) (xy 99.889108 -87.014127) (xy 99.866159 -86.958723)
			(xy 99.850638 -86.900798) (xy 99.84281 -86.841342) (xy 99.84232 -86.811358) (xy 47.937853 -86.811358)
			(xy 47.828516 -86.865801) (xy 47.709591 -86.916138) (xy 47.587792 -86.959058) (xy 47.463582 -86.994399)
			(xy 47.337433 -87.022026) (xy 47.209821 -87.041835) (xy 47.081232 -87.053751) (xy 46.952154 -87.057728)
			(xy 46.823076 -87.053751) (xy 46.694487 -87.041835) (xy 46.566875 -87.022026) (xy 46.440726 -86.994399)
			(xy 46.316516 -86.959058) (xy 46.194717 -86.916138) (xy 46.075792 -86.865801) (xy 45.960191 -86.808239)
			(xy 45.848352 -86.743669) (xy 45.740701 -86.672337) (xy 45.637646 -86.594513) (xy 45.539576 -86.510492)
			(xy 45.446865 -86.420593) (xy 45.359865 -86.325158) (xy 45.278904 -86.224548) (xy 45.20429 -86.119145)
			(xy 45.136307 -86.009348) (xy 45.075212 -85.895574) (xy 45.021237 -85.778255) (xy 44.974586 -85.657836)
			(xy 44.935437 -85.534773) (xy 44.903938 -85.409534) (xy 44.880209 -85.282593) (xy 44.864339 -85.154433)
			(xy 44.856389 -85.025538) (xy 2.783716 -85.025538) (xy 3.573272 -85.81517) (xy 3.622687 -85.865245)
			(xy 3.716468 -85.970133) (xy 3.804219 -86.080117) (xy 3.885663 -86.194848) (xy 3.960544 -86.313966)
			(xy 4.028628 -86.437097) (xy 4.089698 -86.563852) (xy 4.143563 -86.693833) (xy 4.190054 -86.82663)
			(xy 4.229024 -86.961825) (xy 4.260351 -87.098994) (xy 4.283935 -87.237703) (xy 4.297613 -87.358982)
			(xy 116.623592 -87.358982) (xy 116.623592 -86.495382) (xy 116.624082 -86.465414) (xy 116.631905 -86.405992)
			(xy 116.647418 -86.348099) (xy 116.670354 -86.292726) (xy 116.700321 -86.24082) (xy 116.736808 -86.19327)
			(xy 116.779188 -86.15089) (xy 116.826738 -86.114403) (xy 116.878644 -86.084436) (xy 116.934017 -86.0615)
			(xy 116.99191 -86.045987) (xy 117.051332 -86.038164) (xy 117.111268 -86.038164) (xy 117.17069 -86.045987)
			(xy 117.228583 -86.0615) (xy 117.283956 -86.084436) (xy 117.335862 -86.114403) (xy 117.383412 -86.15089)
			(xy 117.425792 -86.19327) (xy 117.462279 -86.24082) (xy 117.492246 -86.292726) (xy 117.515182 -86.348099)
			(xy 117.530695 -86.405992) (xy 117.538518 -86.465414) (xy 117.539008 -86.495382) (xy 117.539008 -87.358982)
			(xy 117.538518 -87.38895) (xy 117.531262 -87.444066) (xy 232.194882 -87.444066) (xy 232.194882 -87.384134)
			(xy 232.202704 -87.324714) (xy 232.218215 -87.266824) (xy 232.241149 -87.211454) (xy 232.271114 -87.15955)
			(xy 232.307596 -87.112002) (xy 232.349973 -87.069621) (xy 232.397519 -87.033135) (xy 232.44942 -87.003166)
			(xy 232.504788 -86.980227) (xy 232.562677 -86.964712) (xy 232.622096 -86.956884) (xy 232.652062 -86.956392)
			(xy 233.515662 -86.956392) (xy 233.545633 -86.956859) (xy 233.605062 -86.964678) (xy 233.662961 -86.980188)
			(xy 233.718341 -87.003123) (xy 233.770254 -87.033091) (xy 233.81781 -87.069578) (xy 233.860197 -87.111961)
			(xy 233.896688 -87.159515) (xy 233.92666 -87.211425) (xy 233.9496 -87.266803) (xy 233.965115 -87.324701)
			(xy 233.972939 -87.384129) (xy 233.972939 -87.416385) (xy 234.381521 -87.416385) (xy 234.381521 -87.356415)
			(xy 234.389349 -87.296959) (xy 234.40487 -87.239032) (xy 234.42782 -87.183628) (xy 234.457804 -87.131692)
			(xy 234.494312 -87.084115) (xy 234.536717 -87.04171) (xy 234.584294 -87.005203) (xy 234.636229 -86.975219)
			(xy 234.691634 -86.952269) (xy 234.749561 -86.936748) (xy 234.809017 -86.928921) (xy 234.839002 -86.928452)
			(xy 235.702602 -86.928452) (xy 235.732587 -86.928914) (xy 235.792044 -86.936742) (xy 235.849971 -86.952264)
			(xy 235.905376 -86.975214) (xy 235.957312 -87.005199) (xy 236.004889 -87.041707) (xy 236.047295 -87.084112)
			(xy 236.083802 -87.13169) (xy 236.113787 -87.183626) (xy 236.136737 -87.239031) (xy 236.152258 -87.296958)
			(xy 236.155843 -87.324184) (xy 330.477876 -87.324184) (xy 330.477876 -86.460584) (xy 330.478366 -86.430616)
			(xy 330.486189 -86.371194) (xy 330.501702 -86.313301) (xy 330.524638 -86.257928) (xy 330.554605 -86.206022)
			(xy 330.591092 -86.158472) (xy 330.633472 -86.116092) (xy 330.681022 -86.079605) (xy 330.732928 -86.049638)
			(xy 330.788301 -86.026702) (xy 330.846194 -86.011189) (xy 330.905616 -86.003366) (xy 330.965552 -86.003366)
			(xy 331.024974 -86.011189) (xy 331.082867 -86.026702) (xy 331.13824 -86.049638) (xy 331.190146 -86.079605)
			(xy 331.237696 -86.116092) (xy 331.266212 -86.144608) (xy 346.641928 -86.144608) (xy 346.641928 -85.281008)
			(xy 346.642418 -85.251024) (xy 346.650246 -85.191568) (xy 346.665767 -85.133643) (xy 346.688716 -85.078239)
			(xy 346.7187 -85.026305) (xy 346.755206 -84.978729) (xy 346.797611 -84.936324) (xy 346.845187 -84.899818)
			(xy 346.897121 -84.869834) (xy 346.952525 -84.846885) (xy 347.01045 -84.831364) (xy 347.069906 -84.823536)
			(xy 347.129874 -84.823536) (xy 347.18933 -84.831364) (xy 347.247255 -84.846885) (xy 347.302659 -84.869834)
			(xy 347.354593 -84.899818) (xy 347.402169 -84.936324) (xy 347.444574 -84.978729) (xy 347.48108 -85.026305)
			(xy 347.511064 -85.078239) (xy 347.534013 -85.133643) (xy 347.549534 -85.191568) (xy 347.557362 -85.251024)
			(xy 347.557852 -85.281008) (xy 347.557852 -86.144608) (xy 347.557362 -86.174592) (xy 347.549534 -86.234048)
			(xy 347.534013 -86.291973) (xy 347.511064 -86.347377) (xy 347.48108 -86.399311) (xy 347.444574 -86.446887)
			(xy 347.402169 -86.489292) (xy 347.354593 -86.525798) (xy 347.302659 -86.555782) (xy 347.247255 -86.578731)
			(xy 347.18933 -86.594252) (xy 347.129874 -86.60208) (xy 347.069906 -86.60208) (xy 347.01045 -86.594252)
			(xy 346.952525 -86.578731) (xy 346.897121 -86.555782) (xy 346.845187 -86.525798) (xy 346.797611 -86.489292)
			(xy 346.755206 -86.446887) (xy 346.7187 -86.399311) (xy 346.688716 -86.347377) (xy 346.665767 -86.291973)
			(xy 346.650246 -86.234048) (xy 346.642418 -86.174592) (xy 346.641928 -86.144608) (xy 331.266212 -86.144608)
			(xy 331.280076 -86.158472) (xy 331.316563 -86.206022) (xy 331.34653 -86.257928) (xy 331.369466 -86.313301)
			(xy 331.384979 -86.371194) (xy 331.392802 -86.430616) (xy 331.393292 -86.460584) (xy 331.393292 -87.324184)
			(xy 331.392802 -87.354152) (xy 331.384979 -87.413574) (xy 331.369466 -87.471467) (xy 331.34653 -87.52684)
			(xy 331.316563 -87.578746) (xy 331.280076 -87.626296) (xy 331.237696 -87.668676) (xy 331.190146 -87.705163)
			(xy 331.13824 -87.73513) (xy 331.082867 -87.758066) (xy 331.024974 -87.773579) (xy 330.965552 -87.781402)
			(xy 330.905616 -87.781402) (xy 330.846194 -87.773579) (xy 330.788301 -87.758066) (xy 330.732928 -87.73513)
			(xy 330.681022 -87.705163) (xy 330.633472 -87.668676) (xy 330.591092 -87.626296) (xy 330.554605 -87.578746)
			(xy 330.524638 -87.52684) (xy 330.501702 -87.471467) (xy 330.486189 -87.413574) (xy 330.478366 -87.354152)
			(xy 330.477876 -87.324184) (xy 236.155843 -87.324184) (xy 236.160086 -87.356415) (xy 236.160086 -87.416385)
			(xy 236.152258 -87.475842) (xy 236.136737 -87.533769) (xy 236.113787 -87.589174) (xy 236.083802 -87.64111)
			(xy 236.047295 -87.688688) (xy 236.004889 -87.731093) (xy 235.957312 -87.767601) (xy 235.905376 -87.797586)
			(xy 235.849971 -87.820536) (xy 235.792044 -87.836058) (xy 235.732587 -87.843886) (xy 235.702602 -87.844376)
			(xy 234.839002 -87.844376) (xy 234.809017 -87.843879) (xy 234.749561 -87.836052) (xy 234.691634 -87.820531)
			(xy 234.636229 -87.797581) (xy 234.584294 -87.767597) (xy 234.536717 -87.73109) (xy 234.494312 -87.688685)
			(xy 234.457804 -87.641108) (xy 234.42782 -87.589172) (xy 234.40487 -87.533768) (xy 234.389349 -87.475841)
			(xy 234.381521 -87.416385) (xy 233.972939 -87.416385) (xy 233.972939 -87.444071) (xy 233.965115 -87.503499)
			(xy 233.9496 -87.561397) (xy 233.92666 -87.616775) (xy 233.896688 -87.668685) (xy 233.860197 -87.716239)
			(xy 233.81781 -87.758622) (xy 233.770254 -87.795109) (xy 233.718341 -87.825077) (xy 233.662961 -87.848012)
			(xy 233.605062 -87.863522) (xy 233.545633 -87.871341) (xy 233.515662 -87.871808) (xy 232.652062 -87.871808)
			(xy 232.622096 -87.871316) (xy 232.562677 -87.863488) (xy 232.504788 -87.847973) (xy 232.44942 -87.825034)
			(xy 232.397519 -87.795065) (xy 232.349973 -87.758579) (xy 232.307596 -87.716198) (xy 232.271114 -87.66865)
			(xy 232.241149 -87.616746) (xy 232.218215 -87.561376) (xy 232.202704 -87.503486) (xy 232.194882 -87.444066)
			(xy 117.531262 -87.444066) (xy 117.530695 -87.448372) (xy 117.515182 -87.506265) (xy 117.492246 -87.561638)
			(xy 117.462279 -87.613544) (xy 117.425792 -87.661094) (xy 117.383412 -87.703474) (xy 117.335862 -87.739961)
			(xy 117.283956 -87.769928) (xy 117.228583 -87.792864) (xy 117.17069 -87.808377) (xy 117.111268 -87.8162)
			(xy 117.051332 -87.8162) (xy 116.99191 -87.808377) (xy 116.934017 -87.792864) (xy 116.878644 -87.769928)
			(xy 116.826738 -87.739961) (xy 116.779188 -87.703474) (xy 116.736808 -87.661094) (xy 116.700321 -87.613544)
			(xy 116.670354 -87.561638) (xy 116.647418 -87.506265) (xy 116.631905 -87.448372) (xy 116.624082 -87.38895)
			(xy 116.623592 -87.358982) (xy 4.297613 -87.358982) (xy 4.299703 -87.377516) (xy 4.307605 -87.517994)
			(xy 4.308094 -87.588344) (xy 4.308094 -88.006187) (xy 238.124409 -88.006187) (xy 238.124409 -87.946213)
			(xy 238.132238 -87.886751) (xy 238.147762 -87.82882) (xy 238.170714 -87.773411) (xy 238.200704 -87.721472)
			(xy 238.237216 -87.673892) (xy 238.279627 -87.631486) (xy 238.32721 -87.594978) (xy 238.379152 -87.564994)
			(xy 238.434563 -87.542047) (xy 238.492496 -87.526529) (xy 238.551959 -87.518706) (xy 238.581946 -87.51824)
			(xy 239.445546 -87.51824) (xy 239.475528 -87.518729) (xy 239.53498 -87.526561) (xy 239.5929 -87.542086)
			(xy 239.648299 -87.565038) (xy 239.700228 -87.595024) (xy 239.747799 -87.631531) (xy 239.790199 -87.673935)
			(xy 239.826701 -87.72151) (xy 239.856682 -87.773442) (xy 239.879628 -87.828843) (xy 239.895148 -87.886765)
			(xy 239.902974 -87.946217) (xy 239.902974 -88.006183) (xy 239.895148 -88.065635) (xy 239.879628 -88.123557)
			(xy 239.870911 -88.144604) (xy 345.879928 -88.144604) (xy 345.879928 -87.281004) (xy 345.880418 -87.25102)
			(xy 345.888246 -87.191564) (xy 345.903767 -87.133639) (xy 345.926716 -87.078235) (xy 345.9567 -87.026301)
			(xy 345.993206 -86.978725) (xy 346.035611 -86.93632) (xy 346.083187 -86.899814) (xy 346.135121 -86.86983)
			(xy 346.190525 -86.846881) (xy 346.24845 -86.83136) (xy 346.307906 -86.823532) (xy 346.367874 -86.823532)
			(xy 346.42733 -86.83136) (xy 346.485255 -86.846881) (xy 346.540659 -86.86983) (xy 346.592593 -86.899814)
			(xy 346.640169 -86.93632) (xy 346.682574 -86.978725) (xy 346.71908 -87.026301) (xy 346.749064 -87.078235)
			(xy 346.772013 -87.133639) (xy 346.787534 -87.191564) (xy 346.795362 -87.25102) (xy 346.795852 -87.281004)
			(xy 346.795852 -88.144604) (xy 346.795362 -88.174588) (xy 346.787534 -88.234044) (xy 346.772013 -88.291969)
			(xy 346.749064 -88.347373) (xy 346.71908 -88.399307) (xy 346.682574 -88.446883) (xy 346.640169 -88.489288)
			(xy 346.592593 -88.525794) (xy 346.540659 -88.555778) (xy 346.485255 -88.578727) (xy 346.42733 -88.594248)
			(xy 346.367874 -88.602076) (xy 346.307906 -88.602076) (xy 346.24845 -88.594248) (xy 346.190525 -88.578727)
			(xy 346.135121 -88.555778) (xy 346.083187 -88.525794) (xy 346.035611 -88.489288) (xy 345.993206 -88.446883)
			(xy 345.9567 -88.399307) (xy 345.926716 -88.347373) (xy 345.903767 -88.291969) (xy 345.888246 -88.234044)
			(xy 345.880418 -88.174588) (xy 345.879928 -88.144604) (xy 239.870911 -88.144604) (xy 239.856682 -88.178958)
			(xy 239.826701 -88.23089) (xy 239.790199 -88.278465) (xy 239.747799 -88.320869) (xy 239.700228 -88.357376)
			(xy 239.648299 -88.387362) (xy 239.5929 -88.410314) (xy 239.53498 -88.425839) (xy 239.475528 -88.433671)
			(xy 239.445546 -88.434164) (xy 238.581946 -88.434164) (xy 238.551959 -88.433694) (xy 238.492496 -88.425871)
			(xy 238.434563 -88.410353) (xy 238.379152 -88.387406) (xy 238.32721 -88.357422) (xy 238.279627 -88.320914)
			(xy 238.237216 -88.278508) (xy 238.200704 -88.230928) (xy 238.170714 -88.178989) (xy 238.147762 -88.12358)
			(xy 238.132238 -88.065649) (xy 238.124409 -88.006187) (xy 4.308094 -88.006187) (xy 4.308094 -89.358978)
			(xy 117.385592 -89.358978) (xy 117.385592 -88.495378) (xy 117.386082 -88.46541) (xy 117.393905 -88.405988)
			(xy 117.409418 -88.348095) (xy 117.432354 -88.292722) (xy 117.462321 -88.240816) (xy 117.498808 -88.193266)
			(xy 117.541188 -88.150886) (xy 117.588738 -88.114399) (xy 117.640644 -88.084432) (xy 117.696017 -88.061496)
			(xy 117.75391 -88.045983) (xy 117.813332 -88.03816) (xy 117.873268 -88.03816) (xy 117.93269 -88.045983)
			(xy 117.990583 -88.061496) (xy 118.045956 -88.084432) (xy 118.097862 -88.114399) (xy 118.145412 -88.150886)
			(xy 118.187792 -88.193266) (xy 118.224279 -88.240816) (xy 118.254246 -88.292722) (xy 118.277182 -88.348095)
			(xy 118.292695 -88.405988) (xy 118.300518 -88.46541) (xy 118.301008 -88.495378) (xy 118.301008 -89.358978)
			(xy 118.300518 -89.388946) (xy 118.292695 -89.448368) (xy 118.277182 -89.506261) (xy 118.254246 -89.561634)
			(xy 118.224279 -89.61354) (xy 118.187792 -89.66109) (xy 118.145412 -89.70347) (xy 118.097862 -89.739957)
			(xy 118.045956 -89.769924) (xy 117.990583 -89.79286) (xy 117.93269 -89.808373) (xy 117.873268 -89.816196)
			(xy 117.813332 -89.816196) (xy 117.75391 -89.808373) (xy 117.696017 -89.79286) (xy 117.640644 -89.769924)
			(xy 117.588738 -89.739957) (xy 117.541188 -89.70347) (xy 117.498808 -89.66109) (xy 117.462321 -89.61354)
			(xy 117.432354 -89.561634) (xy 117.409418 -89.506261) (xy 117.393905 -89.448368) (xy 117.386082 -89.388946)
			(xy 117.385592 -89.358978) (xy 4.308094 -89.358978) (xy 4.308094 -90.1446) (xy 346.641928 -90.1446)
			(xy 346.641928 -89.281) (xy 346.642418 -89.251016) (xy 346.650246 -89.19156) (xy 346.665767 -89.133635)
			(xy 346.688716 -89.078231) (xy 346.7187 -89.026297) (xy 346.755206 -88.978721) (xy 346.797611 -88.936316)
			(xy 346.845187 -88.89981) (xy 346.897121 -88.869826) (xy 346.952525 -88.846877) (xy 347.01045 -88.831356)
			(xy 347.069906 -88.823528) (xy 347.129874 -88.823528) (xy 347.18933 -88.831356) (xy 347.247255 -88.846877)
			(xy 347.302659 -88.869826) (xy 347.354593 -88.89981) (xy 347.402169 -88.936316) (xy 347.444574 -88.978721)
			(xy 347.48108 -89.026297) (xy 347.511064 -89.078231) (xy 347.534013 -89.133635) (xy 347.549534 -89.19156)
			(xy 347.557362 -89.251016) (xy 347.557852 -89.281) (xy 347.557852 -90.1446) (xy 347.557362 -90.174584)
			(xy 347.549534 -90.23404) (xy 347.534013 -90.291965) (xy 347.511064 -90.347369) (xy 347.48108 -90.399303)
			(xy 347.444574 -90.446879) (xy 347.402169 -90.489284) (xy 347.354593 -90.52579) (xy 347.302659 -90.555774)
			(xy 347.247255 -90.578723) (xy 347.18933 -90.594244) (xy 347.129874 -90.602072) (xy 347.069906 -90.602072)
			(xy 347.01045 -90.594244) (xy 346.952525 -90.578723) (xy 346.897121 -90.555774) (xy 346.845187 -90.52579)
			(xy 346.797611 -90.489284) (xy 346.755206 -90.446879) (xy 346.7187 -90.399303) (xy 346.688716 -90.347369)
			(xy 346.665767 -90.291965) (xy 346.650246 -90.23404) (xy 346.642418 -90.174584) (xy 346.641928 -90.1446)
			(xy 4.308094 -90.1446) (xy 4.308094 -94.088485) (xy 109.149614 -94.088485) (xy 109.149614 -94.028515)
			(xy 109.157442 -93.969058) (xy 109.172963 -93.911131) (xy 109.195912 -93.855726) (xy 109.225897 -93.80379)
			(xy 109.262405 -93.756213) (xy 109.30481 -93.713807) (xy 109.352387 -93.6773) (xy 109.404322 -93.647314)
			(xy 109.459727 -93.624364) (xy 109.517654 -93.608843) (xy 109.577111 -93.601014) (xy 109.607096 -93.600524)
			(xy 110.470696 -93.600524) (xy 110.500681 -93.601021) (xy 110.560138 -93.608848) (xy 110.618064 -93.624369)
			(xy 110.673469 -93.647318) (xy 110.725405 -93.677303) (xy 110.772982 -93.71381) (xy 110.815388 -93.756215)
			(xy 110.851895 -93.803792) (xy 110.88188 -93.855727) (xy 110.90483 -93.911132) (xy 110.920351 -93.969058)
			(xy 110.928179 -94.028515) (xy 110.928179 -94.088485) (xy 110.920351 -94.147942) (xy 110.90483 -94.205868)
			(xy 110.88188 -94.261273) (xy 110.851895 -94.313208) (xy 110.815388 -94.360785) (xy 110.772982 -94.40319)
			(xy 110.725405 -94.439697) (xy 110.673469 -94.469682) (xy 110.618064 -94.492631) (xy 110.560138 -94.508152)
			(xy 110.500681 -94.515979) (xy 110.470696 -94.516448) (xy 109.607096 -94.516448) (xy 109.577111 -94.515986)
			(xy 109.517654 -94.508157) (xy 109.459727 -94.492636) (xy 109.404322 -94.469686) (xy 109.352387 -94.4397)
			(xy 109.30481 -94.403193) (xy 109.262405 -94.360787) (xy 109.225897 -94.31321) (xy 109.195912 -94.261274)
			(xy 109.172963 -94.205869) (xy 109.157442 -94.147942) (xy 109.149614 -94.088485) (xy 4.308094 -94.088485)
			(xy 4.308094 -95.214948) (xy 47.274239 -95.214948) (xy 47.278194 -95.123111) (xy 47.290029 -95.031954)
			(xy 47.309656 -94.942151) (xy 47.33693 -94.854369) (xy 47.37165 -94.769255) (xy 47.413558 -94.687442)
			(xy 47.462344 -94.609534) (xy 47.517647 -94.536109) (xy 47.579057 -94.467709) (xy 47.646119 -94.404842)
			(xy 47.718338 -94.347972) (xy 47.795178 -94.297521) (xy 47.876071 -94.253862) (xy 47.960417 -94.217319)
			(xy 48.047593 -94.188162) (xy 48.136952 -94.166608) (xy 48.227833 -94.152814) (xy 48.319564 -94.146884)
			(xy 48.411465 -94.148862) (xy 48.502856 -94.158733) (xy 48.59306 -94.176423) (xy 48.681409 -94.201803)
			(xy 48.767249 -94.234683) (xy 48.849945 -94.274821) (xy 48.928885 -94.32192) (xy 49.003483 -94.37563)
			(xy 49.073189 -94.435554) (xy 49.137484 -94.501248) (xy 49.195895 -94.572226) (xy 49.247987 -94.647963)
			(xy 49.293376 -94.727898) (xy 49.331726 -94.811438) (xy 49.362751 -94.897966) (xy 49.386224 -94.986841)
			(xy 49.40197 -95.077405) (xy 49.409872 -95.168987) (xy 49.410366 -95.214948) (xy 71.639189 -95.214948)
			(xy 71.643144 -95.123111) (xy 71.654979 -95.031954) (xy 71.674606 -94.942151) (xy 71.70188 -94.854369)
			(xy 71.7366 -94.769255) (xy 71.778508 -94.687442) (xy 71.827294 -94.609534) (xy 71.882597 -94.536109)
			(xy 71.944007 -94.467709) (xy 72.011069 -94.404842) (xy 72.083288 -94.347972) (xy 72.160128 -94.297521)
			(xy 72.241021 -94.253862) (xy 72.325367 -94.217319) (xy 72.412543 -94.188162) (xy 72.501902 -94.166608)
			(xy 72.592783 -94.152814) (xy 72.684514 -94.146884) (xy 72.776415 -94.148862) (xy 72.867806 -94.158733)
			(xy 72.95801 -94.176423) (xy 73.046359 -94.201803) (xy 73.132199 -94.234683) (xy 73.214895 -94.274821)
			(xy 73.293835 -94.32192) (xy 73.368433 -94.37563) (xy 73.438139 -94.435554) (xy 73.502434 -94.501248)
			(xy 73.560845 -94.572226) (xy 73.612937 -94.647963) (xy 73.658326 -94.727898) (xy 73.696676 -94.811438)
			(xy 73.727701 -94.897966) (xy 73.751174 -94.986841) (xy 73.76692 -95.077405) (xy 73.774822 -95.168987)
			(xy 73.775316 -95.214948) (xy 73.774822 -95.260909) (xy 73.774772 -95.261486) (xy 163.375394 -95.261486)
			(xy 163.375394 -95.168314) (xy 163.383515 -95.075496) (xy 163.399694 -94.983738) (xy 163.423808 -94.893741)
			(xy 163.455675 -94.806187) (xy 163.495052 -94.721744) (xy 163.541638 -94.641054) (xy 163.595079 -94.564731)
			(xy 163.654969 -94.493357) (xy 163.720852 -94.427473) (xy 163.792226 -94.367583) (xy 163.868549 -94.314141)
			(xy 163.949238 -94.267554) (xy 164.033681 -94.228178) (xy 164.121235 -94.19631) (xy 164.211233 -94.172195)
			(xy 164.30299 -94.156015) (xy 164.395808 -94.147894) (xy 164.442394 -94.147386) (xy 164.442648 -94.147386)
			(xy 164.489237 -94.1478) (xy 164.582061 -94.155925) (xy 164.673824 -94.172109) (xy 164.763826 -94.196229)
			(xy 164.851385 -94.228101) (xy 164.935832 -94.267483) (xy 165.016526 -94.314074) (xy 165.092852 -94.367522)
			(xy 165.164229 -94.427418) (xy 165.230115 -94.493306) (xy 165.290008 -94.564687) (xy 165.343451 -94.641015)
			(xy 165.390039 -94.721711) (xy 165.429417 -94.80616) (xy 165.461286 -94.893719) (xy 165.485401 -94.983723)
			(xy 165.501581 -95.075487) (xy 165.509702 -95.168311) (xy 165.509702 -95.214948) (xy 187.739796 -95.214948)
			(xy 187.743748 -95.123155) (xy 187.755578 -95.032041) (xy 187.775195 -94.942281) (xy 187.802457 -94.85454)
			(xy 187.83716 -94.769468) (xy 187.879048 -94.687693) (xy 187.927811 -94.609822) (xy 187.983087 -94.536432)
			(xy 188.044468 -94.468065) (xy 188.111499 -94.405227) (xy 188.183683 -94.348385) (xy 188.260487 -94.297958)
			(xy 188.341341 -94.25432) (xy 188.425647 -94.217794) (xy 188.512781 -94.188651) (xy 188.602098 -94.167106)
			(xy 188.692936 -94.15332) (xy 188.784623 -94.147393) (xy 188.87648 -94.14937) (xy 188.967828 -94.159236)
			(xy 189.057988 -94.176918) (xy 189.146296 -94.202285) (xy 189.232095 -94.23515) (xy 189.314752 -94.275269)
			(xy 189.393654 -94.322345) (xy 189.468217 -94.376029) (xy 189.537889 -94.435925) (xy 189.602154 -94.501588)
			(xy 189.660537 -94.572532) (xy 189.712604 -94.648233) (xy 189.757972 -94.72813) (xy 189.796303 -94.81163)
			(xy 189.827314 -94.898117) (xy 189.850775 -94.98695) (xy 189.866514 -95.07747) (xy 189.874412 -95.169009)
			(xy 189.874906 -95.214948) (xy 279.474181 -95.214948) (xy 279.478136 -95.123111) (xy 279.489971 -95.031954)
			(xy 279.509598 -94.942151) (xy 279.536872 -94.854369) (xy 279.571592 -94.769255) (xy 279.6135 -94.687442)
			(xy 279.662286 -94.609534) (xy 279.717589 -94.536109) (xy 279.778999 -94.467709) (xy 279.846061 -94.404842)
			(xy 279.91828 -94.347972) (xy 279.99512 -94.297521) (xy 280.076013 -94.253862) (xy 280.160359 -94.217319)
			(xy 280.247535 -94.188162) (xy 280.336894 -94.166608) (xy 280.427775 -94.152814) (xy 280.519506 -94.146884)
			(xy 280.611407 -94.148862) (xy 280.702798 -94.158733) (xy 280.793002 -94.176423) (xy 280.881351 -94.201803)
			(xy 280.967191 -94.234683) (xy 281.049887 -94.274821) (xy 281.128827 -94.32192) (xy 281.203425 -94.37563)
			(xy 281.273131 -94.435554) (xy 281.337426 -94.501248) (xy 281.395837 -94.572226) (xy 281.447929 -94.647963)
			(xy 281.493318 -94.727898) (xy 281.531668 -94.811438) (xy 281.562693 -94.897966) (xy 281.586166 -94.986841)
			(xy 281.601912 -95.077405) (xy 281.609814 -95.168987) (xy 281.610308 -95.214948) (xy 303.839131 -95.214948)
			(xy 303.843086 -95.123111) (xy 303.854921 -95.031954) (xy 303.874548 -94.942151) (xy 303.901822 -94.854369)
			(xy 303.936542 -94.769255) (xy 303.97845 -94.687442) (xy 304.027236 -94.609534) (xy 304.082539 -94.536109)
			(xy 304.143949 -94.467709) (xy 304.211011 -94.404842) (xy 304.28323 -94.347972) (xy 304.36007 -94.297521)
			(xy 304.440963 -94.253862) (xy 304.525309 -94.217319) (xy 304.612485 -94.188162) (xy 304.701844 -94.166608)
			(xy 304.792725 -94.152814) (xy 304.884456 -94.146884) (xy 304.976357 -94.148862) (xy 305.067748 -94.158733)
			(xy 305.157952 -94.176423) (xy 305.246301 -94.201803) (xy 305.332141 -94.234683) (xy 305.414837 -94.274821)
			(xy 305.493777 -94.32192) (xy 305.568375 -94.37563) (xy 305.638081 -94.435554) (xy 305.702376 -94.501248)
			(xy 305.760787 -94.572226) (xy 305.812879 -94.647963) (xy 305.858268 -94.727898) (xy 305.896618 -94.811438)
			(xy 305.91901 -94.87389) (xy 338.405861 -94.87389) (xy 338.405861 -94.81391) (xy 338.413691 -94.754443)
			(xy 338.429215 -94.696507) (xy 338.45217 -94.641093) (xy 338.482161 -94.58915) (xy 338.518676 -94.541565)
			(xy 338.561089 -94.499155) (xy 338.608676 -94.462643) (xy 338.660622 -94.432655) (xy 338.716037 -94.409705)
			(xy 338.773975 -94.394184) (xy 338.833442 -94.386359) (xy 338.863432 -94.385892) (xy 339.727032 -94.385892)
			(xy 339.757012 -94.386476) (xy 339.816458 -94.394306) (xy 339.874374 -94.409828) (xy 339.929769 -94.432777)
			(xy 339.981694 -94.462759) (xy 340.029262 -94.499262) (xy 340.071659 -94.541662) (xy 340.108159 -94.589232)
			(xy 340.138137 -94.64116) (xy 340.161082 -94.696556) (xy 340.1766 -94.754473) (xy 340.184426 -94.81392)
			(xy 340.184426 -94.87388) (xy 340.1766 -94.933327) (xy 340.161082 -94.991244) (xy 340.138137 -95.04664)
			(xy 340.108159 -95.098568) (xy 340.071659 -95.146138) (xy 340.029262 -95.188538) (xy 339.994846 -95.214948)
			(xy 395.574279 -95.214948) (xy 395.578234 -95.123111) (xy 395.590069 -95.031954) (xy 395.609696 -94.942151)
			(xy 395.63697 -94.854369) (xy 395.67169 -94.769255) (xy 395.713598 -94.687442) (xy 395.762384 -94.609534)
			(xy 395.817687 -94.536109) (xy 395.879097 -94.467709) (xy 395.946159 -94.404842) (xy 396.018378 -94.347972)
			(xy 396.095218 -94.297521) (xy 396.176111 -94.253862) (xy 396.260457 -94.217319) (xy 396.347633 -94.188162)
			(xy 396.436992 -94.166608) (xy 396.527873 -94.152814) (xy 396.619604 -94.146884) (xy 396.711505 -94.148862)
			(xy 396.802896 -94.158733) (xy 396.8931 -94.176423) (xy 396.981449 -94.201803) (xy 397.067289 -94.234683)
			(xy 397.149985 -94.274821) (xy 397.228925 -94.32192) (xy 397.303523 -94.37563) (xy 397.373229 -94.435554)
			(xy 397.437524 -94.501248) (xy 397.495935 -94.572226) (xy 397.548027 -94.647963) (xy 397.593416 -94.727898)
			(xy 397.631766 -94.811438) (xy 397.662791 -94.897966) (xy 397.686264 -94.986841) (xy 397.70201 -95.077405)
			(xy 397.709912 -95.168987) (xy 397.710406 -95.214948) (xy 419.939229 -95.214948) (xy 419.943184 -95.123111)
			(xy 419.955019 -95.031954) (xy 419.974646 -94.942151) (xy 420.00192 -94.854369) (xy 420.03664 -94.769255)
			(xy 420.078548 -94.687442) (xy 420.127334 -94.609534) (xy 420.182637 -94.536109) (xy 420.244047 -94.467709)
			(xy 420.311109 -94.404842) (xy 420.383328 -94.347972) (xy 420.460168 -94.297521) (xy 420.541061 -94.253862)
			(xy 420.625407 -94.217319) (xy 420.712583 -94.188162) (xy 420.801942 -94.166608) (xy 420.892823 -94.152814)
			(xy 420.984554 -94.146884) (xy 421.076455 -94.148862) (xy 421.167846 -94.158733) (xy 421.25805 -94.176423)
			(xy 421.346399 -94.201803) (xy 421.432239 -94.234683) (xy 421.514935 -94.274821) (xy 421.593875 -94.32192)
			(xy 421.668473 -94.37563) (xy 421.738179 -94.435554) (xy 421.802474 -94.501248) (xy 421.860885 -94.572226)
			(xy 421.912977 -94.647963) (xy 421.958366 -94.727898) (xy 421.996716 -94.811438) (xy 422.027741 -94.897966)
			(xy 422.051214 -94.986841) (xy 422.06696 -95.077405) (xy 422.074862 -95.168987) (xy 422.075356 -95.214948)
			(xy 422.074862 -95.260909) (xy 422.06696 -95.352491) (xy 422.051214 -95.443055) (xy 422.027741 -95.53193)
			(xy 421.996716 -95.618458) (xy 421.958366 -95.701998) (xy 421.912977 -95.781933) (xy 421.860885 -95.85767)
			(xy 421.802474 -95.928648) (xy 421.738179 -95.994342) (xy 421.668473 -96.054266) (xy 421.593875 -96.107976)
			(xy 421.514935 -96.155075) (xy 421.432239 -96.195213) (xy 421.346399 -96.228093) (xy 421.25805 -96.253473)
			(xy 421.167846 -96.271163) (xy 421.076455 -96.281034) (xy 420.984554 -96.283012) (xy 420.892823 -96.277082)
			(xy 420.801942 -96.263288) (xy 420.712583 -96.241734) (xy 420.625407 -96.212577) (xy 420.541061 -96.176034)
			(xy 420.460168 -96.132375) (xy 420.383328 -96.081924) (xy 420.311109 -96.025054) (xy 420.244047 -95.962187)
			(xy 420.182637 -95.893787) (xy 420.127334 -95.820362) (xy 420.078548 -95.742454) (xy 420.03664 -95.660641)
			(xy 420.00192 -95.575527) (xy 419.974646 -95.487745) (xy 419.955019 -95.397942) (xy 419.943184 -95.306785)
			(xy 419.939229 -95.214948) (xy 397.710406 -95.214948) (xy 397.709912 -95.260909) (xy 397.70201 -95.352491)
			(xy 397.686264 -95.443055) (xy 397.662791 -95.53193) (xy 397.631766 -95.618458) (xy 397.593416 -95.701998)
			(xy 397.548027 -95.781933) (xy 397.495935 -95.85767) (xy 397.437524 -95.928648) (xy 397.373229 -95.994342)
			(xy 397.303523 -96.054266) (xy 397.228925 -96.107976) (xy 397.149985 -96.155075) (xy 397.067289 -96.195213)
			(xy 396.981449 -96.228093) (xy 396.8931 -96.253473) (xy 396.802896 -96.271163) (xy 396.711505 -96.281034)
			(xy 396.619604 -96.283012) (xy 396.527873 -96.277082) (xy 396.436992 -96.263288) (xy 396.347633 -96.241734)
			(xy 396.260457 -96.212577) (xy 396.176111 -96.176034) (xy 396.095218 -96.132375) (xy 396.018378 -96.081924)
			(xy 395.946159 -96.025054) (xy 395.879097 -95.962187) (xy 395.817687 -95.893787) (xy 395.762384 -95.820362)
			(xy 395.713598 -95.742454) (xy 395.67169 -95.660641) (xy 395.63697 -95.575527) (xy 395.609696 -95.487745)
			(xy 395.590069 -95.397942) (xy 395.578234 -95.306785) (xy 395.574279 -95.214948) (xy 339.994846 -95.214948)
			(xy 339.981694 -95.225041) (xy 339.929769 -95.255023) (xy 339.874374 -95.277972) (xy 339.816458 -95.293494)
			(xy 339.757012 -95.301324) (xy 339.727032 -95.301816) (xy 338.863432 -95.301816) (xy 338.833442 -95.301441)
			(xy 338.773975 -95.293616) (xy 338.716037 -95.278095) (xy 338.660622 -95.255145) (xy 338.608676 -95.225157)
			(xy 338.561089 -95.188645) (xy 338.518676 -95.146235) (xy 338.482161 -95.09865) (xy 338.45217 -95.046707)
			(xy 338.429215 -94.991293) (xy 338.413691 -94.933357) (xy 338.405861 -94.87389) (xy 305.91901 -94.87389)
			(xy 305.927643 -94.897966) (xy 305.951116 -94.986841) (xy 305.966862 -95.077405) (xy 305.974764 -95.168987)
			(xy 305.975258 -95.214948) (xy 305.974764 -95.260909) (xy 305.966862 -95.352491) (xy 305.951116 -95.443055)
			(xy 305.927643 -95.53193) (xy 305.896618 -95.618458) (xy 305.858268 -95.701998) (xy 305.812879 -95.781933)
			(xy 305.760787 -95.85767) (xy 305.702376 -95.928648) (xy 305.638081 -95.994342) (xy 305.568375 -96.054266)
			(xy 305.493777 -96.107976) (xy 305.414837 -96.155075) (xy 305.332141 -96.195213) (xy 305.246301 -96.228093)
			(xy 305.157952 -96.253473) (xy 305.067748 -96.271163) (xy 304.976357 -96.281034) (xy 304.884456 -96.283012)
			(xy 304.792725 -96.277082) (xy 304.701844 -96.263288) (xy 304.612485 -96.241734) (xy 304.525309 -96.212577)
			(xy 304.440963 -96.176034) (xy 304.36007 -96.132375) (xy 304.28323 -96.081924) (xy 304.211011 -96.025054)
			(xy 304.143949 -95.962187) (xy 304.082539 -95.893787) (xy 304.027236 -95.820362) (xy 303.97845 -95.742454)
			(xy 303.936542 -95.660641) (xy 303.901822 -95.575527) (xy 303.874548 -95.487745) (xy 303.854921 -95.397942)
			(xy 303.843086 -95.306785) (xy 303.839131 -95.214948) (xy 281.610308 -95.214948) (xy 281.609814 -95.260909)
			(xy 281.601912 -95.352491) (xy 281.586166 -95.443055) (xy 281.562693 -95.53193) (xy 281.531668 -95.618458)
			(xy 281.493318 -95.701998) (xy 281.447929 -95.781933) (xy 281.395837 -95.85767) (xy 281.337426 -95.928648)
			(xy 281.273131 -95.994342) (xy 281.203425 -96.054266) (xy 281.128827 -96.107976) (xy 281.049887 -96.155075)
			(xy 280.967191 -96.195213) (xy 280.881351 -96.228093) (xy 280.793002 -96.253473) (xy 280.702798 -96.271163)
			(xy 280.611407 -96.281034) (xy 280.519506 -96.283012) (xy 280.427775 -96.277082) (xy 280.336894 -96.263288)
			(xy 280.247535 -96.241734) (xy 280.160359 -96.212577) (xy 280.076013 -96.176034) (xy 279.99512 -96.132375)
			(xy 279.91828 -96.081924) (xy 279.846061 -96.025054) (xy 279.778999 -95.962187) (xy 279.717589 -95.893787)
			(xy 279.662286 -95.820362) (xy 279.6135 -95.742454) (xy 279.571592 -95.660641) (xy 279.536872 -95.575527)
			(xy 279.509598 -95.487745) (xy 279.489971 -95.397942) (xy 279.478136 -95.306785) (xy 279.474181 -95.214948)
			(xy 189.874906 -95.214948) (xy 189.874412 -95.260887) (xy 189.866514 -95.352426) (xy 189.850775 -95.442946)
			(xy 189.827314 -95.531779) (xy 189.796303 -95.618266) (xy 189.757972 -95.701766) (xy 189.712604 -95.781663)
			(xy 189.660537 -95.857364) (xy 189.602154 -95.928308) (xy 189.537889 -95.993971) (xy 189.468217 -96.053867)
			(xy 189.393654 -96.107551) (xy 189.314752 -96.154627) (xy 189.232095 -96.194746) (xy 189.146296 -96.227611)
			(xy 189.057988 -96.252978) (xy 188.967828 -96.27066) (xy 188.87648 -96.280526) (xy 188.784623 -96.282503)
			(xy 188.692936 -96.276576) (xy 188.602098 -96.26279) (xy 188.512781 -96.241245) (xy 188.425647 -96.212102)
			(xy 188.341341 -96.175576) (xy 188.260487 -96.131938) (xy 188.183683 -96.081511) (xy 188.111499 -96.024669)
			(xy 188.044468 -95.961831) (xy 187.983087 -95.893464) (xy 187.927811 -95.820074) (xy 187.879048 -95.742203)
			(xy 187.83716 -95.660428) (xy 187.802457 -95.575356) (xy 187.775195 -95.487615) (xy 187.755578 -95.397855)
			(xy 187.743748 -95.306741) (xy 187.739796 -95.214948) (xy 165.509702 -95.214948) (xy 165.509702 -95.261489)
			(xy 165.501581 -95.354313) (xy 165.485401 -95.446077) (xy 165.461286 -95.536081) (xy 165.429417 -95.62364)
			(xy 165.390039 -95.708089) (xy 165.343451 -95.788785) (xy 165.290008 -95.865113) (xy 165.230115 -95.936494)
			(xy 165.164229 -96.002382) (xy 165.092852 -96.062278) (xy 165.016526 -96.115726) (xy 164.935832 -96.162317)
			(xy 164.851385 -96.201699) (xy 164.763826 -96.233571) (xy 164.673824 -96.257691) (xy 164.582061 -96.273875)
			(xy 164.489237 -96.282) (xy 164.442648 -96.28251) (xy 164.442394 -96.28251) (xy 164.395808 -96.281906)
			(xy 164.30299 -96.273785) (xy 164.211233 -96.257605) (xy 164.121235 -96.23349) (xy 164.033681 -96.201622)
			(xy 163.949238 -96.162246) (xy 163.868549 -96.115659) (xy 163.792226 -96.062217) (xy 163.720852 -96.002327)
			(xy 163.654969 -95.936443) (xy 163.595079 -95.865069) (xy 163.541638 -95.788746) (xy 163.495052 -95.708056)
			(xy 163.455675 -95.623613) (xy 163.423808 -95.536059) (xy 163.399694 -95.446062) (xy 163.383515 -95.354304)
			(xy 163.375394 -95.261486) (xy 73.774772 -95.261486) (xy 73.76692 -95.352491) (xy 73.751174 -95.443055)
			(xy 73.727701 -95.53193) (xy 73.696676 -95.618458) (xy 73.658326 -95.701998) (xy 73.612937 -95.781933)
			(xy 73.560845 -95.85767) (xy 73.502434 -95.928648) (xy 73.438139 -95.994342) (xy 73.368433 -96.054266)
			(xy 73.293835 -96.107976) (xy 73.214895 -96.155075) (xy 73.132199 -96.195213) (xy 73.046359 -96.228093)
			(xy 72.95801 -96.253473) (xy 72.867806 -96.271163) (xy 72.776415 -96.281034) (xy 72.684514 -96.283012)
			(xy 72.592783 -96.277082) (xy 72.501902 -96.263288) (xy 72.412543 -96.241734) (xy 72.325367 -96.212577)
			(xy 72.241021 -96.176034) (xy 72.160128 -96.132375) (xy 72.083288 -96.081924) (xy 72.011069 -96.025054)
			(xy 71.944007 -95.962187) (xy 71.882597 -95.893787) (xy 71.827294 -95.820362) (xy 71.778508 -95.742454)
			(xy 71.7366 -95.660641) (xy 71.70188 -95.575527) (xy 71.674606 -95.487745) (xy 71.654979 -95.397942)
			(xy 71.643144 -95.306785) (xy 71.639189 -95.214948) (xy 49.410366 -95.214948) (xy 49.409872 -95.260909)
			(xy 49.40197 -95.352491) (xy 49.386224 -95.443055) (xy 49.362751 -95.53193) (xy 49.331726 -95.618458)
			(xy 49.293376 -95.701998) (xy 49.247987 -95.781933) (xy 49.195895 -95.85767) (xy 49.137484 -95.928648)
			(xy 49.073189 -95.994342) (xy 49.003483 -96.054266) (xy 48.928885 -96.107976) (xy 48.849945 -96.155075)
			(xy 48.767249 -96.195213) (xy 48.681409 -96.228093) (xy 48.59306 -96.253473) (xy 48.502856 -96.271163)
			(xy 48.411465 -96.281034) (xy 48.319564 -96.283012) (xy 48.227833 -96.277082) (xy 48.136952 -96.263288)
			(xy 48.047593 -96.241734) (xy 47.960417 -96.212577) (xy 47.876071 -96.176034) (xy 47.795178 -96.132375)
			(xy 47.718338 -96.081924) (xy 47.646119 -96.025054) (xy 47.579057 -95.962187) (xy 47.517647 -95.893787)
			(xy 47.462344 -95.820362) (xy 47.413558 -95.742454) (xy 47.37165 -95.660641) (xy 47.33693 -95.575527)
			(xy 47.309656 -95.487745) (xy 47.290029 -95.397942) (xy 47.278194 -95.306785) (xy 47.274239 -95.214948)
			(xy 4.308094 -95.214948) (xy 4.308094 -98.766863) (xy 206.090008 -98.766863) (xy 206.090008 -98.633301)
			(xy 206.098072 -98.499983) (xy 206.114172 -98.367395) (xy 206.138247 -98.236021) (xy 206.17021 -98.10634)
			(xy 206.209945 -97.978826) (xy 206.257307 -97.853943) (xy 206.312122 -97.732148) (xy 206.374192 -97.613885)
			(xy 206.443288 -97.499586) (xy 206.51916 -97.389666) (xy 206.60153 -97.284529) (xy 206.690098 -97.184556)
			(xy 206.78454 -97.090114) (xy 206.884513 -97.001546) (xy 206.98965 -96.919176) (xy 207.09957 -96.843304)
			(xy 207.213869 -96.774208) (xy 207.332132 -96.712138) (xy 207.453927 -96.657323) (xy 207.57881 -96.609961)
			(xy 207.706324 -96.570226) (xy 207.836005 -96.538263) (xy 207.967379 -96.514188) (xy 208.099967 -96.498088)
			(xy 208.233285 -96.490024) (xy 208.366847 -96.490024) (xy 208.500165 -96.498088) (xy 208.632753 -96.514188)
			(xy 208.764127 -96.538263) (xy 208.893808 -96.570226) (xy 209.021322 -96.609961) (xy 209.146205 -96.657323)
			(xy 209.268 -96.712138) (xy 209.386263 -96.774208) (xy 209.500562 -96.843304) (xy 209.610482 -96.919176)
			(xy 209.715619 -97.001546) (xy 209.815592 -97.090114) (xy 209.910034 -97.184556) (xy 209.998602 -97.284529)
			(xy 210.080972 -97.389666) (xy 210.156844 -97.499586) (xy 210.22594 -97.613885) (xy 210.28801 -97.732148)
			(xy 210.342825 -97.853943) (xy 210.390187 -97.978826) (xy 210.429922 -98.10634) (xy 210.461885 -98.236021)
			(xy 210.48596 -98.367395) (xy 210.50206 -98.499983) (xy 210.510124 -98.633301) (xy 210.510628 -98.700082)
			(xy 210.510124 -98.766863) (xy 257.089906 -98.766863) (xy 257.089906 -98.633301) (xy 257.09797 -98.499983)
			(xy 257.11407 -98.367395) (xy 257.138145 -98.236021) (xy 257.170108 -98.10634) (xy 257.209843 -97.978826)
			(xy 257.257205 -97.853943) (xy 257.31202 -97.732148) (xy 257.37409 -97.613885) (xy 257.443186 -97.499586)
			(xy 257.519058 -97.389666) (xy 257.601428 -97.284529) (xy 257.689996 -97.184556) (xy 257.784438 -97.090114)
			(xy 257.884411 -97.001546) (xy 257.989548 -96.919176) (xy 258.099468 -96.843304) (xy 258.213767 -96.774208)
			(xy 258.33203 -96.712138) (xy 258.453825 -96.657323) (xy 258.578708 -96.609961) (xy 258.706222 -96.570226)
			(xy 258.835903 -96.538263) (xy 258.967277 -96.514188) (xy 259.099865 -96.498088) (xy 259.233183 -96.490024)
			(xy 259.366745 -96.490024) (xy 259.500063 -96.498088) (xy 259.632651 -96.514188) (xy 259.764025 -96.538263)
			(xy 259.893706 -96.570226) (xy 260.02122 -96.609961) (xy 260.146103 -96.657323) (xy 260.267898 -96.712138)
			(xy 260.386161 -96.774208) (xy 260.50046 -96.843304) (xy 260.61038 -96.919176) (xy 260.715517 -97.001546)
			(xy 260.81549 -97.090114) (xy 260.909932 -97.184556) (xy 260.9985 -97.284529) (xy 261.08087 -97.389666)
			(xy 261.156742 -97.499586) (xy 261.225838 -97.613885) (xy 261.287908 -97.732148) (xy 261.342723 -97.853943)
			(xy 261.390085 -97.978826) (xy 261.42982 -98.10634) (xy 261.461783 -98.236021) (xy 261.485858 -98.367395)
			(xy 261.501958 -98.499983) (xy 261.510022 -98.633301) (xy 261.510526 -98.700082) (xy 261.510022 -98.766863)
			(xy 261.501958 -98.900181) (xy 261.485858 -99.032769) (xy 261.461783 -99.164143) (xy 261.42982 -99.293824)
			(xy 261.390085 -99.421338) (xy 261.342723 -99.546221) (xy 261.287908 -99.668016) (xy 261.225838 -99.786279)
			(xy 261.156742 -99.900578) (xy 261.08087 -100.010498) (xy 260.9985 -100.115635) (xy 260.943379 -100.177854)
			(xy 269.509748 -100.177854) (xy 269.509748 -99.314254) (xy 269.510238 -99.28427) (xy 269.518066 -99.224814)
			(xy 269.533587 -99.166889) (xy 269.556536 -99.111485) (xy 269.58652 -99.059551) (xy 269.623026 -99.011975)
			(xy 269.665431 -98.96957) (xy 269.713007 -98.933064) (xy 269.764941 -98.90308) (xy 269.820345 -98.880131)
			(xy 269.87827 -98.86461) (xy 269.937726 -98.856782) (xy 269.997694 -98.856782) (xy 270.05715 -98.86461)
			(xy 270.115075 -98.880131) (xy 270.170479 -98.90308) (xy 270.222413 -98.933064) (xy 270.269989 -98.96957)
			(xy 270.312394 -99.011975) (xy 270.3489 -99.059551) (xy 270.378884 -99.111485) (xy 270.401833 -99.166889)
			(xy 270.417354 -99.224814) (xy 270.425182 -99.28427) (xy 270.425672 -99.314254) (xy 270.425672 -100.17633)
			(xy 285.8389 -100.17633) (xy 285.8389 -99.31273) (xy 285.83939 -99.282746) (xy 285.847218 -99.22329)
			(xy 285.862739 -99.165365) (xy 285.885688 -99.109961) (xy 285.915672 -99.058027) (xy 285.952178 -99.010451)
			(xy 285.994583 -98.968046) (xy 286.042159 -98.93154) (xy 286.094093 -98.901556) (xy 286.149497 -98.878607)
			(xy 286.207422 -98.863086) (xy 286.266878 -98.855258) (xy 286.326846 -98.855258) (xy 286.386302 -98.863086)
			(xy 286.444227 -98.878607) (xy 286.499631 -98.901556) (xy 286.551565 -98.93154) (xy 286.599141 -98.968046)
			(xy 286.641546 -99.010451) (xy 286.678052 -99.058027) (xy 286.708036 -99.109961) (xy 286.730985 -99.165365)
			(xy 286.746506 -99.22329) (xy 286.754334 -99.282746) (xy 286.754824 -99.31273) (xy 286.754824 -100.17633)
			(xy 286.754799 -100.177854) (xy 385.6101 -100.177854) (xy 385.6101 -99.314254) (xy 385.61059 -99.284286)
			(xy 385.618413 -99.224864) (xy 385.633926 -99.166971) (xy 385.656862 -99.111598) (xy 385.686829 -99.059692)
			(xy 385.723316 -99.012142) (xy 385.765696 -98.969762) (xy 385.813246 -98.933275) (xy 385.865152 -98.903308)
			(xy 385.920525 -98.880372) (xy 385.978418 -98.864859) (xy 386.03784 -98.857036) (xy 386.097776 -98.857036)
			(xy 386.157198 -98.864859) (xy 386.215091 -98.880372) (xy 386.270464 -98.903308) (xy 386.32237 -98.933275)
			(xy 386.36992 -98.969762) (xy 386.4123 -99.012142) (xy 386.448787 -99.059692) (xy 386.478754 -99.111598)
			(xy 386.50169 -99.166971) (xy 386.517203 -99.224864) (xy 386.525026 -99.284286) (xy 386.525516 -99.314254)
			(xy 386.525516 -100.17633) (xy 401.939252 -100.17633) (xy 401.939252 -99.31273) (xy 401.939742 -99.282762)
			(xy 401.947565 -99.22334) (xy 401.963078 -99.165447) (xy 401.986014 -99.110074) (xy 402.015981 -99.058168)
			(xy 402.052468 -99.010618) (xy 402.094848 -98.968238) (xy 402.142398 -98.931751) (xy 402.194304 -98.901784)
			(xy 402.249677 -98.878848) (xy 402.30757 -98.863335) (xy 402.366992 -98.855512) (xy 402.426928 -98.855512)
			(xy 402.48635 -98.863335) (xy 402.544243 -98.878848) (xy 402.599616 -98.901784) (xy 402.651522 -98.931751)
			(xy 402.699072 -98.968238) (xy 402.741452 -99.010618) (xy 402.777939 -99.058168) (xy 402.807906 -99.110074)
			(xy 402.830842 -99.165447) (xy 402.846355 -99.22334) (xy 402.854178 -99.282762) (xy 402.854668 -99.31273)
			(xy 402.854668 -100.17633) (xy 402.854178 -100.206298) (xy 402.846355 -100.26572) (xy 402.830842 -100.323613)
			(xy 402.807906 -100.378986) (xy 402.777939 -100.430892) (xy 402.741452 -100.478442) (xy 402.699072 -100.520822)
			(xy 402.651522 -100.557309) (xy 402.599616 -100.587276) (xy 402.544243 -100.610212) (xy 402.48635 -100.625725)
			(xy 402.426928 -100.633548) (xy 402.366992 -100.633548) (xy 402.30757 -100.625725) (xy 402.249677 -100.610212)
			(xy 402.194304 -100.587276) (xy 402.142398 -100.557309) (xy 402.094848 -100.520822) (xy 402.052468 -100.478442)
			(xy 402.015981 -100.430892) (xy 401.986014 -100.378986) (xy 401.963078 -100.323613) (xy 401.947565 -100.26572)
			(xy 401.939742 -100.206298) (xy 401.939252 -100.17633) (xy 386.525516 -100.17633) (xy 386.525516 -100.177854)
			(xy 386.525026 -100.207822) (xy 386.517203 -100.267244) (xy 386.50169 -100.325137) (xy 386.478754 -100.38051)
			(xy 386.448787 -100.432416) (xy 386.4123 -100.479966) (xy 386.36992 -100.522346) (xy 386.32237 -100.558833)
			(xy 386.270464 -100.5888) (xy 386.215091 -100.611736) (xy 386.157198 -100.627249) (xy 386.097776 -100.635072)
			(xy 386.03784 -100.635072) (xy 385.978418 -100.627249) (xy 385.920525 -100.611736) (xy 385.865152 -100.5888)
			(xy 385.813246 -100.558833) (xy 385.765696 -100.522346) (xy 385.723316 -100.479966) (xy 385.686829 -100.432416)
			(xy 385.656862 -100.38051) (xy 385.633926 -100.325137) (xy 385.618413 -100.267244) (xy 385.61059 -100.207822)
			(xy 385.6101 -100.177854) (xy 286.754799 -100.177854) (xy 286.754334 -100.206314) (xy 286.746506 -100.26577)
			(xy 286.730985 -100.323695) (xy 286.708036 -100.379099) (xy 286.678052 -100.431033) (xy 286.641546 -100.478609)
			(xy 286.599141 -100.521014) (xy 286.551565 -100.55752) (xy 286.499631 -100.587504) (xy 286.444227 -100.610453)
			(xy 286.386302 -100.625974) (xy 286.326846 -100.633802) (xy 286.266878 -100.633802) (xy 286.207422 -100.625974)
			(xy 286.149497 -100.610453) (xy 286.094093 -100.587504) (xy 286.042159 -100.55752) (xy 285.994583 -100.521014)
			(xy 285.952178 -100.478609) (xy 285.915672 -100.431033) (xy 285.885688 -100.379099) (xy 285.862739 -100.323695)
			(xy 285.847218 -100.26577) (xy 285.83939 -100.206314) (xy 285.8389 -100.17633) (xy 270.425672 -100.17633)
			(xy 270.425672 -100.177854) (xy 270.425182 -100.207838) (xy 270.417354 -100.267294) (xy 270.401833 -100.325219)
			(xy 270.378884 -100.380623) (xy 270.3489 -100.432557) (xy 270.312394 -100.480133) (xy 270.269989 -100.522538)
			(xy 270.222413 -100.559044) (xy 270.170479 -100.589028) (xy 270.115075 -100.611977) (xy 270.05715 -100.627498)
			(xy 269.997694 -100.635326) (xy 269.937726 -100.635326) (xy 269.87827 -100.627498) (xy 269.820345 -100.611977)
			(xy 269.764941 -100.589028) (xy 269.713007 -100.559044) (xy 269.665431 -100.522538) (xy 269.623026 -100.480133)
			(xy 269.58652 -100.432557) (xy 269.556536 -100.380623) (xy 269.533587 -100.325219) (xy 269.518066 -100.267294)
			(xy 269.510238 -100.207838) (xy 269.509748 -100.177854) (xy 260.943379 -100.177854) (xy 260.909932 -100.215608)
			(xy 260.81549 -100.31005) (xy 260.715517 -100.398618) (xy 260.61038 -100.480988) (xy 260.50046 -100.55686)
			(xy 260.386161 -100.625956) (xy 260.267898 -100.688026) (xy 260.146103 -100.742841) (xy 260.02122 -100.790203)
			(xy 259.893706 -100.829938) (xy 259.764025 -100.861901) (xy 259.632651 -100.885976) (xy 259.500063 -100.902076)
			(xy 259.366745 -100.91014) (xy 259.233183 -100.91014) (xy 259.099865 -100.902076) (xy 258.967277 -100.885976)
			(xy 258.835903 -100.861901) (xy 258.706222 -100.829938) (xy 258.578708 -100.790203) (xy 258.453825 -100.742841)
			(xy 258.33203 -100.688026) (xy 258.213767 -100.625956) (xy 258.099468 -100.55686) (xy 257.989548 -100.480988)
			(xy 257.884411 -100.398618) (xy 257.784438 -100.31005) (xy 257.689996 -100.215608) (xy 257.601428 -100.115635)
			(xy 257.519058 -100.010498) (xy 257.443186 -99.900578) (xy 257.37409 -99.786279) (xy 257.31202 -99.668016)
			(xy 257.257205 -99.546221) (xy 257.209843 -99.421338) (xy 257.170108 -99.293824) (xy 257.138145 -99.164143)
			(xy 257.11407 -99.032769) (xy 257.09797 -98.900181) (xy 257.089906 -98.766863) (xy 210.510124 -98.766863)
			(xy 210.50206 -98.900181) (xy 210.48596 -99.032769) (xy 210.461885 -99.164143) (xy 210.429922 -99.293824)
			(xy 210.390187 -99.421338) (xy 210.342825 -99.546221) (xy 210.28801 -99.668016) (xy 210.22594 -99.786279)
			(xy 210.156844 -99.900578) (xy 210.080972 -100.010498) (xy 209.998602 -100.115635) (xy 209.910034 -100.215608)
			(xy 209.815592 -100.31005) (xy 209.715619 -100.398618) (xy 209.610482 -100.480988) (xy 209.500562 -100.55686)
			(xy 209.386263 -100.625956) (xy 209.268 -100.688026) (xy 209.146205 -100.742841) (xy 209.021322 -100.790203)
			(xy 208.893808 -100.829938) (xy 208.764127 -100.861901) (xy 208.632753 -100.885976) (xy 208.500165 -100.902076)
			(xy 208.366847 -100.91014) (xy 208.233285 -100.91014) (xy 208.099967 -100.902076) (xy 207.967379 -100.885976)
			(xy 207.836005 -100.861901) (xy 207.706324 -100.829938) (xy 207.57881 -100.790203) (xy 207.453927 -100.742841)
			(xy 207.332132 -100.688026) (xy 207.213869 -100.625956) (xy 207.09957 -100.55686) (xy 206.98965 -100.480988)
			(xy 206.884513 -100.398618) (xy 206.78454 -100.31005) (xy 206.690098 -100.215608) (xy 206.60153 -100.115635)
			(xy 206.51916 -100.010498) (xy 206.443288 -99.900578) (xy 206.374192 -99.786279) (xy 206.312122 -99.668016)
			(xy 206.257307 -99.546221) (xy 206.209945 -99.421338) (xy 206.17021 -99.293824) (xy 206.138247 -99.164143)
			(xy 206.114172 -99.032769) (xy 206.098072 -98.900181) (xy 206.090008 -98.766863) (xy 4.308094 -98.766863)
			(xy 4.308094 -100.177854) (xy 37.31006 -100.177854) (xy 37.31006 -99.314254) (xy 37.31055 -99.284286)
			(xy 37.318373 -99.224864) (xy 37.333886 -99.166971) (xy 37.356822 -99.111598) (xy 37.386789 -99.059692)
			(xy 37.423276 -99.012142) (xy 37.465656 -98.969762) (xy 37.513206 -98.933275) (xy 37.565112 -98.903308)
			(xy 37.620485 -98.880372) (xy 37.678378 -98.864859) (xy 37.7378 -98.857036) (xy 37.797736 -98.857036)
			(xy 37.857158 -98.864859) (xy 37.915051 -98.880372) (xy 37.970424 -98.903308) (xy 38.02233 -98.933275)
			(xy 38.06988 -98.969762) (xy 38.11226 -99.012142) (xy 38.148747 -99.059692) (xy 38.178714 -99.111598)
			(xy 38.20165 -99.166971) (xy 38.217163 -99.224864) (xy 38.224986 -99.284286) (xy 38.225476 -99.314254)
			(xy 38.225476 -100.17633) (xy 53.639212 -100.17633) (xy 53.639212 -99.31273) (xy 53.639702 -99.282762)
			(xy 53.647525 -99.22334) (xy 53.663038 -99.165447) (xy 53.685974 -99.110074) (xy 53.715941 -99.058168)
			(xy 53.752428 -99.010618) (xy 53.794808 -98.968238) (xy 53.842358 -98.931751) (xy 53.894264 -98.901784)
			(xy 53.949637 -98.878848) (xy 54.00753 -98.863335) (xy 54.066952 -98.855512) (xy 54.126888 -98.855512)
			(xy 54.18631 -98.863335) (xy 54.244203 -98.878848) (xy 54.299576 -98.901784) (xy 54.351482 -98.931751)
			(xy 54.399032 -98.968238) (xy 54.441412 -99.010618) (xy 54.477899 -99.058168) (xy 54.507866 -99.110074)
			(xy 54.530802 -99.165447) (xy 54.546315 -99.22334) (xy 54.554138 -99.282762) (xy 54.554628 -99.31273)
			(xy 54.554628 -100.17633) (xy 54.554603 -100.177854) (xy 153.409904 -100.177854) (xy 153.409904 -99.314254)
			(xy 153.410394 -99.28427) (xy 153.418222 -99.224814) (xy 153.433743 -99.166889) (xy 153.456692 -99.111485)
			(xy 153.486676 -99.059551) (xy 153.523182 -99.011975) (xy 153.565587 -98.96957) (xy 153.613163 -98.933064)
			(xy 153.665097 -98.90308) (xy 153.720501 -98.880131) (xy 153.778426 -98.86461) (xy 153.837882 -98.856782)
			(xy 153.89785 -98.856782) (xy 153.957306 -98.86461) (xy 154.015231 -98.880131) (xy 154.070635 -98.90308)
			(xy 154.122569 -98.933064) (xy 154.170145 -98.96957) (xy 154.21255 -99.011975) (xy 154.249056 -99.059551)
			(xy 154.27904 -99.111485) (xy 154.301989 -99.166889) (xy 154.31751 -99.224814) (xy 154.325338 -99.28427)
			(xy 154.325828 -99.314254) (xy 154.325828 -100.17633) (xy 169.739056 -100.17633) (xy 169.739056 -99.31273)
			(xy 169.739546 -99.282746) (xy 169.747374 -99.22329) (xy 169.762895 -99.165365) (xy 169.785844 -99.109961)
			(xy 169.815828 -99.058027) (xy 169.852334 -99.010451) (xy 169.894739 -98.968046) (xy 169.942315 -98.93154)
			(xy 169.994249 -98.901556) (xy 170.049653 -98.878607) (xy 170.107578 -98.863086) (xy 170.167034 -98.855258)
			(xy 170.227002 -98.855258) (xy 170.286458 -98.863086) (xy 170.344383 -98.878607) (xy 170.399787 -98.901556)
			(xy 170.451721 -98.93154) (xy 170.499297 -98.968046) (xy 170.541702 -99.010451) (xy 170.578208 -99.058027)
			(xy 170.608192 -99.109961) (xy 170.631141 -99.165365) (xy 170.646662 -99.22329) (xy 170.65449 -99.282746)
			(xy 170.65498 -99.31273) (xy 170.65498 -100.17633) (xy 170.65449 -100.206314) (xy 170.646662 -100.26577)
			(xy 170.631141 -100.323695) (xy 170.608192 -100.379099) (xy 170.578208 -100.431033) (xy 170.541702 -100.478609)
			(xy 170.499297 -100.521014) (xy 170.451721 -100.55752) (xy 170.399787 -100.587504) (xy 170.344383 -100.610453)
			(xy 170.286458 -100.625974) (xy 170.227002 -100.633802) (xy 170.167034 -100.633802) (xy 170.107578 -100.625974)
			(xy 170.049653 -100.610453) (xy 169.994249 -100.587504) (xy 169.942315 -100.55752) (xy 169.894739 -100.521014)
			(xy 169.852334 -100.478609) (xy 169.815828 -100.431033) (xy 169.785844 -100.379099) (xy 169.762895 -100.323695)
			(xy 169.747374 -100.26577) (xy 169.739546 -100.206314) (xy 169.739056 -100.17633) (xy 154.325828 -100.17633)
			(xy 154.325828 -100.177854) (xy 154.325338 -100.207838) (xy 154.31751 -100.267294) (xy 154.301989 -100.325219)
			(xy 154.27904 -100.380623) (xy 154.249056 -100.432557) (xy 154.21255 -100.480133) (xy 154.170145 -100.522538)
			(xy 154.122569 -100.559044) (xy 154.070635 -100.589028) (xy 154.015231 -100.611977) (xy 153.957306 -100.627498)
			(xy 153.89785 -100.635326) (xy 153.837882 -100.635326) (xy 153.778426 -100.627498) (xy 153.720501 -100.611977)
			(xy 153.665097 -100.589028) (xy 153.613163 -100.559044) (xy 153.565587 -100.522538) (xy 153.523182 -100.480133)
			(xy 153.486676 -100.432557) (xy 153.456692 -100.380623) (xy 153.433743 -100.325219) (xy 153.418222 -100.267294)
			(xy 153.410394 -100.207838) (xy 153.409904 -100.177854) (xy 54.554603 -100.177854) (xy 54.554138 -100.206298)
			(xy 54.546315 -100.26572) (xy 54.530802 -100.323613) (xy 54.507866 -100.378986) (xy 54.477899 -100.430892)
			(xy 54.441412 -100.478442) (xy 54.399032 -100.520822) (xy 54.351482 -100.557309) (xy 54.299576 -100.587276)
			(xy 54.244203 -100.610212) (xy 54.18631 -100.625725) (xy 54.126888 -100.633548) (xy 54.066952 -100.633548)
			(xy 54.00753 -100.625725) (xy 53.949637 -100.610212) (xy 53.894264 -100.587276) (xy 53.842358 -100.557309)
			(xy 53.794808 -100.520822) (xy 53.752428 -100.478442) (xy 53.715941 -100.430892) (xy 53.685974 -100.378986)
			(xy 53.663038 -100.323613) (xy 53.647525 -100.26572) (xy 53.639702 -100.206298) (xy 53.639212 -100.17633)
			(xy 38.225476 -100.17633) (xy 38.225476 -100.177854) (xy 38.224986 -100.207822) (xy 38.217163 -100.267244)
			(xy 38.20165 -100.325137) (xy 38.178714 -100.38051) (xy 38.148747 -100.432416) (xy 38.11226 -100.479966)
			(xy 38.06988 -100.522346) (xy 38.02233 -100.558833) (xy 37.970424 -100.5888) (xy 37.915051 -100.611736)
			(xy 37.857158 -100.627249) (xy 37.797736 -100.635072) (xy 37.7378 -100.635072) (xy 37.678378 -100.627249)
			(xy 37.620485 -100.611736) (xy 37.565112 -100.5888) (xy 37.513206 -100.558833) (xy 37.465656 -100.522346)
			(xy 37.423276 -100.479966) (xy 37.386789 -100.432416) (xy 37.356822 -100.38051) (xy 37.333886 -100.325137)
			(xy 37.318373 -100.267244) (xy 37.31055 -100.207822) (xy 37.31006 -100.177854) (xy 4.308094 -100.177854)
			(xy 4.308094 -101.984302) (xy 35.277552 -101.984302) (xy 35.277552 -101.120702) (xy 35.278042 -101.090734)
			(xy 35.285865 -101.031312) (xy 35.301378 -100.973419) (xy 35.324314 -100.918046) (xy 35.354281 -100.86614)
			(xy 35.390768 -100.81859) (xy 35.433148 -100.77621) (xy 35.480698 -100.739723) (xy 35.532604 -100.709756)
			(xy 35.587977 -100.68682) (xy 35.64587 -100.671307) (xy 35.705292 -100.663484) (xy 35.765228 -100.663484)
			(xy 35.82465 -100.671307) (xy 35.882543 -100.68682) (xy 35.937916 -100.709756) (xy 35.989822 -100.739723)
			(xy 36.037372 -100.77621) (xy 36.079752 -100.81859) (xy 36.116239 -100.86614) (xy 36.146206 -100.918046)
			(xy 36.169142 -100.973419) (xy 36.184655 -101.031312) (xy 36.192478 -101.090734) (xy 36.192968 -101.120702)
			(xy 36.192968 -101.976428) (xy 51.785012 -101.976428) (xy 51.785012 -101.112828) (xy 51.785502 -101.08286)
			(xy 51.793325 -101.023438) (xy 51.808838 -100.965545) (xy 51.831774 -100.910172) (xy 51.861741 -100.858266)
			(xy 51.898228 -100.810716) (xy 51.940608 -100.768336) (xy 51.988158 -100.731849) (xy 52.040064 -100.701882)
			(xy 52.095437 -100.678946) (xy 52.15333 -100.663433) (xy 52.212752 -100.65561) (xy 52.272688 -100.65561)
			(xy 52.33211 -100.663433) (xy 52.390003 -100.678946) (xy 52.445376 -100.701882) (xy 52.497282 -100.731849)
			(xy 52.544832 -100.768336) (xy 52.587212 -100.810716) (xy 52.623699 -100.858266) (xy 52.653666 -100.910172)
			(xy 52.676602 -100.965545) (xy 52.692115 -101.023438) (xy 52.699938 -101.08286) (xy 52.700428 -101.112828)
			(xy 52.700428 -101.976428) (xy 52.700299 -101.984302) (xy 151.377396 -101.984302) (xy 151.377396 -101.120702)
			(xy 151.377886 -101.090718) (xy 151.385714 -101.031262) (xy 151.401235 -100.973337) (xy 151.424184 -100.917933)
			(xy 151.454168 -100.865999) (xy 151.490674 -100.818423) (xy 151.533079 -100.776018) (xy 151.580655 -100.739512)
			(xy 151.632589 -100.709528) (xy 151.687993 -100.686579) (xy 151.745918 -100.671058) (xy 151.805374 -100.66323)
			(xy 151.865342 -100.66323) (xy 151.924798 -100.671058) (xy 151.982723 -100.686579) (xy 152.038127 -100.709528)
			(xy 152.090061 -100.739512) (xy 152.137637 -100.776018) (xy 152.180042 -100.818423) (xy 152.216548 -100.865999)
			(xy 152.246532 -100.917933) (xy 152.269481 -100.973337) (xy 152.285002 -101.031262) (xy 152.29283 -101.090718)
			(xy 152.29332 -101.120702) (xy 152.29332 -101.976428) (xy 167.884856 -101.976428) (xy 167.884856 -101.112828)
			(xy 167.885346 -101.082844) (xy 167.893174 -101.023388) (xy 167.908695 -100.965463) (xy 167.931644 -100.910059)
			(xy 167.961628 -100.858125) (xy 167.998134 -100.810549) (xy 168.040539 -100.768144) (xy 168.088115 -100.731638)
			(xy 168.140049 -100.701654) (xy 168.195453 -100.678705) (xy 168.253378 -100.663184) (xy 168.312834 -100.655356)
			(xy 168.372802 -100.655356) (xy 168.432258 -100.663184) (xy 168.490183 -100.678705) (xy 168.545587 -100.701654)
			(xy 168.597521 -100.731638) (xy 168.645097 -100.768144) (xy 168.687502 -100.810549) (xy 168.724008 -100.858125)
			(xy 168.753992 -100.910059) (xy 168.776941 -100.965463) (xy 168.792462 -101.023388) (xy 168.80029 -101.082844)
			(xy 168.80078 -101.112828) (xy 168.80078 -101.976428) (xy 168.800651 -101.984302) (xy 267.47724 -101.984302)
			(xy 267.47724 -101.120702) (xy 267.47773 -101.090718) (xy 267.485558 -101.031262) (xy 267.501079 -100.973337)
			(xy 267.524028 -100.917933) (xy 267.554012 -100.865999) (xy 267.590518 -100.818423) (xy 267.632923 -100.776018)
			(xy 267.680499 -100.739512) (xy 267.732433 -100.709528) (xy 267.787837 -100.686579) (xy 267.845762 -100.671058)
			(xy 267.905218 -100.66323) (xy 267.965186 -100.66323) (xy 268.024642 -100.671058) (xy 268.082567 -100.686579)
			(xy 268.137971 -100.709528) (xy 268.189905 -100.739512) (xy 268.237481 -100.776018) (xy 268.279886 -100.818423)
			(xy 268.316392 -100.865999) (xy 268.346376 -100.917933) (xy 268.369325 -100.973337) (xy 268.384846 -101.031262)
			(xy 268.392674 -101.090718) (xy 268.393164 -101.120702) (xy 268.393164 -101.976428) (xy 283.9847 -101.976428)
			(xy 283.9847 -101.112828) (xy 283.98519 -101.082844) (xy 283.993018 -101.023388) (xy 284.008539 -100.965463)
			(xy 284.031488 -100.910059) (xy 284.061472 -100.858125) (xy 284.097978 -100.810549) (xy 284.140383 -100.768144)
			(xy 284.187959 -100.731638) (xy 284.239893 -100.701654) (xy 284.295297 -100.678705) (xy 284.353222 -100.663184)
			(xy 284.412678 -100.655356) (xy 284.472646 -100.655356) (xy 284.532102 -100.663184) (xy 284.590027 -100.678705)
			(xy 284.645431 -100.701654) (xy 284.697365 -100.731638) (xy 284.744941 -100.768144) (xy 284.787346 -100.810549)
			(xy 284.823852 -100.858125) (xy 284.853836 -100.910059) (xy 284.876785 -100.965463) (xy 284.892306 -101.023388)
			(xy 284.900134 -101.082844) (xy 284.900624 -101.112828) (xy 284.900624 -101.976428) (xy 284.900495 -101.984302)
			(xy 383.577592 -101.984302) (xy 383.577592 -101.120702) (xy 383.578082 -101.090734) (xy 383.585905 -101.031312)
			(xy 383.601418 -100.973419) (xy 383.624354 -100.918046) (xy 383.654321 -100.86614) (xy 383.690808 -100.81859)
			(xy 383.733188 -100.77621) (xy 383.780738 -100.739723) (xy 383.832644 -100.709756) (xy 383.888017 -100.68682)
			(xy 383.94591 -100.671307) (xy 384.005332 -100.663484) (xy 384.065268 -100.663484) (xy 384.12469 -100.671307)
			(xy 384.182583 -100.68682) (xy 384.237956 -100.709756) (xy 384.289862 -100.739723) (xy 384.337412 -100.77621)
			(xy 384.379792 -100.81859) (xy 384.416279 -100.86614) (xy 384.446246 -100.918046) (xy 384.469182 -100.973419)
			(xy 384.484695 -101.031312) (xy 384.492518 -101.090734) (xy 384.493008 -101.120702) (xy 384.493008 -101.976428)
			(xy 400.085052 -101.976428) (xy 400.085052 -101.112828) (xy 400.085542 -101.08286) (xy 400.093365 -101.023438)
			(xy 400.108878 -100.965545) (xy 400.131814 -100.910172) (xy 400.161781 -100.858266) (xy 400.198268 -100.810716)
			(xy 400.240648 -100.768336) (xy 400.288198 -100.731849) (xy 400.340104 -100.701882) (xy 400.395477 -100.678946)
			(xy 400.45337 -100.663433) (xy 400.512792 -100.65561) (xy 400.572728 -100.65561) (xy 400.63215 -100.663433)
			(xy 400.690043 -100.678946) (xy 400.745416 -100.701882) (xy 400.797322 -100.731849) (xy 400.844872 -100.768336)
			(xy 400.887252 -100.810716) (xy 400.923739 -100.858266) (xy 400.953706 -100.910172) (xy 400.976642 -100.965545)
			(xy 400.992155 -101.023438) (xy 400.999978 -101.08286) (xy 401.000468 -101.112828) (xy 401.000468 -101.976428)
			(xy 400.999978 -102.006396) (xy 400.992155 -102.065818) (xy 400.976642 -102.123711) (xy 400.953706 -102.179084)
			(xy 400.923739 -102.23099) (xy 400.887252 -102.27854) (xy 400.844872 -102.32092) (xy 400.797322 -102.357407)
			(xy 400.745416 -102.387374) (xy 400.690043 -102.41031) (xy 400.63215 -102.425823) (xy 400.572728 -102.433646)
			(xy 400.512792 -102.433646) (xy 400.45337 -102.425823) (xy 400.395477 -102.41031) (xy 400.340104 -102.387374)
			(xy 400.288198 -102.357407) (xy 400.240648 -102.32092) (xy 400.198268 -102.27854) (xy 400.161781 -102.23099)
			(xy 400.131814 -102.179084) (xy 400.108878 -102.123711) (xy 400.093365 -102.065818) (xy 400.085542 -102.006396)
			(xy 400.085052 -101.976428) (xy 384.493008 -101.976428) (xy 384.493008 -101.984302) (xy 384.492518 -102.01427)
			(xy 384.484695 -102.073692) (xy 384.469182 -102.131585) (xy 384.446246 -102.186958) (xy 384.416279 -102.238864)
			(xy 384.379792 -102.286414) (xy 384.337412 -102.328794) (xy 384.289862 -102.365281) (xy 384.237956 -102.395248)
			(xy 384.182583 -102.418184) (xy 384.12469 -102.433697) (xy 384.065268 -102.44152) (xy 384.005332 -102.44152)
			(xy 383.94591 -102.433697) (xy 383.888017 -102.418184) (xy 383.832644 -102.395248) (xy 383.780738 -102.365281)
			(xy 383.733188 -102.328794) (xy 383.690808 -102.286414) (xy 383.654321 -102.238864) (xy 383.624354 -102.186958)
			(xy 383.601418 -102.131585) (xy 383.585905 -102.073692) (xy 383.578082 -102.01427) (xy 383.577592 -101.984302)
			(xy 284.900495 -101.984302) (xy 284.900134 -102.006412) (xy 284.892306 -102.065868) (xy 284.876785 -102.123793)
			(xy 284.853836 -102.179197) (xy 284.823852 -102.231131) (xy 284.787346 -102.278707) (xy 284.744941 -102.321112)
			(xy 284.697365 -102.357618) (xy 284.645431 -102.387602) (xy 284.590027 -102.410551) (xy 284.532102 -102.426072)
			(xy 284.472646 -102.4339) (xy 284.412678 -102.4339) (xy 284.353222 -102.426072) (xy 284.295297 -102.410551)
			(xy 284.239893 -102.387602) (xy 284.187959 -102.357618) (xy 284.140383 -102.321112) (xy 284.097978 -102.278707)
			(xy 284.061472 -102.231131) (xy 284.031488 -102.179197) (xy 284.008539 -102.123793) (xy 283.993018 -102.065868)
			(xy 283.98519 -102.006412) (xy 283.9847 -101.976428) (xy 268.393164 -101.976428) (xy 268.393164 -101.984302)
			(xy 268.392674 -102.014286) (xy 268.384846 -102.073742) (xy 268.369325 -102.131667) (xy 268.346376 -102.187071)
			(xy 268.316392 -102.239005) (xy 268.279886 -102.286581) (xy 268.237481 -102.328986) (xy 268.189905 -102.365492)
			(xy 268.137971 -102.395476) (xy 268.082567 -102.418425) (xy 268.024642 -102.433946) (xy 267.965186 -102.441774)
			(xy 267.905218 -102.441774) (xy 267.845762 -102.433946) (xy 267.787837 -102.418425) (xy 267.732433 -102.395476)
			(xy 267.680499 -102.365492) (xy 267.632923 -102.328986) (xy 267.590518 -102.286581) (xy 267.554012 -102.239005)
			(xy 267.524028 -102.187071) (xy 267.501079 -102.131667) (xy 267.485558 -102.073742) (xy 267.47773 -102.014286)
			(xy 267.47724 -101.984302) (xy 168.800651 -101.984302) (xy 168.80029 -102.006412) (xy 168.792462 -102.065868)
			(xy 168.776941 -102.123793) (xy 168.753992 -102.179197) (xy 168.724008 -102.231131) (xy 168.687502 -102.278707)
			(xy 168.645097 -102.321112) (xy 168.597521 -102.357618) (xy 168.545587 -102.387602) (xy 168.490183 -102.410551)
			(xy 168.432258 -102.426072) (xy 168.372802 -102.4339) (xy 168.312834 -102.4339) (xy 168.253378 -102.426072)
			(xy 168.195453 -102.410551) (xy 168.140049 -102.387602) (xy 168.088115 -102.357618) (xy 168.040539 -102.321112)
			(xy 167.998134 -102.278707) (xy 167.961628 -102.231131) (xy 167.931644 -102.179197) (xy 167.908695 -102.123793)
			(xy 167.893174 -102.065868) (xy 167.885346 -102.006412) (xy 167.884856 -101.976428) (xy 152.29332 -101.976428)
			(xy 152.29332 -101.984302) (xy 152.29283 -102.014286) (xy 152.285002 -102.073742) (xy 152.269481 -102.131667)
			(xy 152.246532 -102.187071) (xy 152.216548 -102.239005) (xy 152.180042 -102.286581) (xy 152.137637 -102.328986)
			(xy 152.090061 -102.365492) (xy 152.038127 -102.395476) (xy 151.982723 -102.418425) (xy 151.924798 -102.433946)
			(xy 151.865342 -102.441774) (xy 151.805374 -102.441774) (xy 151.745918 -102.433946) (xy 151.687993 -102.418425)
			(xy 151.632589 -102.395476) (xy 151.580655 -102.365492) (xy 151.533079 -102.328986) (xy 151.490674 -102.286581)
			(xy 151.454168 -102.239005) (xy 151.424184 -102.187071) (xy 151.401235 -102.131667) (xy 151.385714 -102.073742)
			(xy 151.377886 -102.014286) (xy 151.377396 -101.984302) (xy 52.700299 -101.984302) (xy 52.699938 -102.006396)
			(xy 52.692115 -102.065818) (xy 52.676602 -102.123711) (xy 52.653666 -102.179084) (xy 52.623699 -102.23099)
			(xy 52.587212 -102.27854) (xy 52.544832 -102.32092) (xy 52.497282 -102.357407) (xy 52.445376 -102.387374)
			(xy 52.390003 -102.41031) (xy 52.33211 -102.425823) (xy 52.272688 -102.433646) (xy 52.212752 -102.433646)
			(xy 52.15333 -102.425823) (xy 52.095437 -102.41031) (xy 52.040064 -102.387374) (xy 51.988158 -102.357407)
			(xy 51.940608 -102.32092) (xy 51.898228 -102.27854) (xy 51.861741 -102.23099) (xy 51.831774 -102.179084)
			(xy 51.808838 -102.123711) (xy 51.793325 -102.065818) (xy 51.785502 -102.006396) (xy 51.785012 -101.976428)
			(xy 36.192968 -101.976428) (xy 36.192968 -101.984302) (xy 36.192478 -102.01427) (xy 36.184655 -102.073692)
			(xy 36.169142 -102.131585) (xy 36.146206 -102.186958) (xy 36.116239 -102.238864) (xy 36.079752 -102.286414)
			(xy 36.037372 -102.328794) (xy 35.989822 -102.365281) (xy 35.937916 -102.395248) (xy 35.882543 -102.418184)
			(xy 35.82465 -102.433697) (xy 35.765228 -102.44152) (xy 35.705292 -102.44152) (xy 35.64587 -102.433697)
			(xy 35.587977 -102.418184) (xy 35.532604 -102.395248) (xy 35.480698 -102.365281) (xy 35.433148 -102.328794)
			(xy 35.390768 -102.286414) (xy 35.354281 -102.238864) (xy 35.324314 -102.186958) (xy 35.301378 -102.131585)
			(xy 35.285865 -102.073692) (xy 35.278042 -102.01427) (xy 35.277552 -101.984302) (xy 4.308094 -101.984302)
			(xy 4.308094 -103.777796) (xy 37.31006 -103.777796) (xy 37.31006 -102.914196) (xy 37.31055 -102.884228)
			(xy 37.318373 -102.824806) (xy 37.333886 -102.766913) (xy 37.356822 -102.71154) (xy 37.386789 -102.659634)
			(xy 37.423276 -102.612084) (xy 37.465656 -102.569704) (xy 37.513206 -102.533217) (xy 37.565112 -102.50325)
			(xy 37.620485 -102.480314) (xy 37.678378 -102.464801) (xy 37.7378 -102.456978) (xy 37.797736 -102.456978)
			(xy 37.857158 -102.464801) (xy 37.915051 -102.480314) (xy 37.970424 -102.50325) (xy 38.02233 -102.533217)
			(xy 38.06988 -102.569704) (xy 38.11226 -102.612084) (xy 38.148747 -102.659634) (xy 38.178714 -102.71154)
			(xy 38.20165 -102.766913) (xy 38.217163 -102.824806) (xy 38.224986 -102.884228) (xy 38.225476 -102.914196)
			(xy 38.225476 -103.776272) (xy 53.639212 -103.776272) (xy 53.639212 -102.912672) (xy 53.639702 -102.882704)
			(xy 53.647525 -102.823282) (xy 53.663038 -102.765389) (xy 53.685974 -102.710016) (xy 53.715941 -102.65811)
			(xy 53.752428 -102.61056) (xy 53.794808 -102.56818) (xy 53.842358 -102.531693) (xy 53.894264 -102.501726)
			(xy 53.949637 -102.47879) (xy 54.00753 -102.463277) (xy 54.066952 -102.455454) (xy 54.126888 -102.455454)
			(xy 54.18631 -102.463277) (xy 54.244203 -102.47879) (xy 54.299576 -102.501726) (xy 54.351482 -102.531693)
			(xy 54.399032 -102.56818) (xy 54.441412 -102.61056) (xy 54.477899 -102.65811) (xy 54.507866 -102.710016)
			(xy 54.530802 -102.765389) (xy 54.546315 -102.823282) (xy 54.554138 -102.882704) (xy 54.554628 -102.912672)
			(xy 54.554628 -103.776272) (xy 54.554603 -103.777796) (xy 153.409904 -103.777796) (xy 153.409904 -102.914196)
			(xy 153.410394 -102.884212) (xy 153.418222 -102.824756) (xy 153.433743 -102.766831) (xy 153.456692 -102.711427)
			(xy 153.486676 -102.659493) (xy 153.523182 -102.611917) (xy 153.565587 -102.569512) (xy 153.613163 -102.533006)
			(xy 153.665097 -102.503022) (xy 153.720501 -102.480073) (xy 153.778426 -102.464552) (xy 153.837882 -102.456724)
			(xy 153.89785 -102.456724) (xy 153.957306 -102.464552) (xy 154.015231 -102.480073) (xy 154.070635 -102.503022)
			(xy 154.122569 -102.533006) (xy 154.170145 -102.569512) (xy 154.21255 -102.611917) (xy 154.249056 -102.659493)
			(xy 154.27904 -102.711427) (xy 154.301989 -102.766831) (xy 154.31751 -102.824756) (xy 154.325338 -102.884212)
			(xy 154.325828 -102.914196) (xy 154.325828 -103.776272) (xy 169.739056 -103.776272) (xy 169.739056 -102.912672)
			(xy 169.739546 -102.882688) (xy 169.747374 -102.823232) (xy 169.762895 -102.765307) (xy 169.785844 -102.709903)
			(xy 169.815828 -102.657969) (xy 169.852334 -102.610393) (xy 169.894739 -102.567988) (xy 169.942315 -102.531482)
			(xy 169.994249 -102.501498) (xy 170.049653 -102.478549) (xy 170.107578 -102.463028) (xy 170.167034 -102.4552)
			(xy 170.227002 -102.4552) (xy 170.286458 -102.463028) (xy 170.344383 -102.478549) (xy 170.399787 -102.501498)
			(xy 170.451721 -102.531482) (xy 170.499297 -102.567988) (xy 170.541702 -102.610393) (xy 170.578208 -102.657969)
			(xy 170.608192 -102.709903) (xy 170.631141 -102.765307) (xy 170.646662 -102.823232) (xy 170.65449 -102.882688)
			(xy 170.65498 -102.912672) (xy 170.65498 -103.776272) (xy 170.654955 -103.777796) (xy 269.509748 -103.777796)
			(xy 269.509748 -102.914196) (xy 269.510238 -102.884212) (xy 269.518066 -102.824756) (xy 269.533587 -102.766831)
			(xy 269.556536 -102.711427) (xy 269.58652 -102.659493) (xy 269.623026 -102.611917) (xy 269.665431 -102.569512)
			(xy 269.713007 -102.533006) (xy 269.764941 -102.503022) (xy 269.820345 -102.480073) (xy 269.87827 -102.464552)
			(xy 269.937726 -102.456724) (xy 269.997694 -102.456724) (xy 270.05715 -102.464552) (xy 270.115075 -102.480073)
			(xy 270.170479 -102.503022) (xy 270.222413 -102.533006) (xy 270.269989 -102.569512) (xy 270.312394 -102.611917)
			(xy 270.3489 -102.659493) (xy 270.378884 -102.711427) (xy 270.401833 -102.766831) (xy 270.417354 -102.824756)
			(xy 270.425182 -102.884212) (xy 270.425672 -102.914196) (xy 270.425672 -103.776272) (xy 285.8389 -103.776272)
			(xy 285.8389 -102.912672) (xy 285.83939 -102.882688) (xy 285.847218 -102.823232) (xy 285.862739 -102.765307)
			(xy 285.885688 -102.709903) (xy 285.915672 -102.657969) (xy 285.952178 -102.610393) (xy 285.994583 -102.567988)
			(xy 286.042159 -102.531482) (xy 286.094093 -102.501498) (xy 286.149497 -102.478549) (xy 286.207422 -102.463028)
			(xy 286.266878 -102.4552) (xy 286.326846 -102.4552) (xy 286.386302 -102.463028) (xy 286.444227 -102.478549)
			(xy 286.499631 -102.501498) (xy 286.551565 -102.531482) (xy 286.599141 -102.567988) (xy 286.641546 -102.610393)
			(xy 286.678052 -102.657969) (xy 286.708036 -102.709903) (xy 286.730985 -102.765307) (xy 286.746506 -102.823232)
			(xy 286.754334 -102.882688) (xy 286.754824 -102.912672) (xy 286.754824 -103.776272) (xy 286.754799 -103.777796)
			(xy 385.6101 -103.777796) (xy 385.6101 -102.914196) (xy 385.61059 -102.884228) (xy 385.618413 -102.824806)
			(xy 385.633926 -102.766913) (xy 385.656862 -102.71154) (xy 385.686829 -102.659634) (xy 385.723316 -102.612084)
			(xy 385.765696 -102.569704) (xy 385.813246 -102.533217) (xy 385.865152 -102.50325) (xy 385.920525 -102.480314)
			(xy 385.978418 -102.464801) (xy 386.03784 -102.456978) (xy 386.097776 -102.456978) (xy 386.157198 -102.464801)
			(xy 386.215091 -102.480314) (xy 386.270464 -102.50325) (xy 386.32237 -102.533217) (xy 386.36992 -102.569704)
			(xy 386.4123 -102.612084) (xy 386.448787 -102.659634) (xy 386.478754 -102.71154) (xy 386.50169 -102.766913)
			(xy 386.517203 -102.824806) (xy 386.525026 -102.884228) (xy 386.525516 -102.914196) (xy 386.525516 -103.776272)
			(xy 401.939252 -103.776272) (xy 401.939252 -102.912672) (xy 401.939742 -102.882704) (xy 401.947565 -102.823282)
			(xy 401.963078 -102.765389) (xy 401.986014 -102.710016) (xy 402.015981 -102.65811) (xy 402.052468 -102.61056)
			(xy 402.094848 -102.56818) (xy 402.142398 -102.531693) (xy 402.194304 -102.501726) (xy 402.249677 -102.47879)
			(xy 402.30757 -102.463277) (xy 402.366992 -102.455454) (xy 402.426928 -102.455454) (xy 402.48635 -102.463277)
			(xy 402.544243 -102.47879) (xy 402.599616 -102.501726) (xy 402.651522 -102.531693) (xy 402.699072 -102.56818)
			(xy 402.741452 -102.61056) (xy 402.777939 -102.65811) (xy 402.807906 -102.710016) (xy 402.830842 -102.765389)
			(xy 402.846355 -102.823282) (xy 402.854178 -102.882704) (xy 402.854668 -102.912672) (xy 402.854668 -103.776272)
			(xy 402.854178 -103.80624) (xy 402.846355 -103.865662) (xy 402.830842 -103.923555) (xy 402.807906 -103.978928)
			(xy 402.777939 -104.030834) (xy 402.741452 -104.078384) (xy 402.699072 -104.120764) (xy 402.651522 -104.157251)
			(xy 402.599616 -104.187218) (xy 402.544243 -104.210154) (xy 402.48635 -104.225667) (xy 402.426928 -104.23349)
			(xy 402.366992 -104.23349) (xy 402.30757 -104.225667) (xy 402.249677 -104.210154) (xy 402.194304 -104.187218)
			(xy 402.142398 -104.157251) (xy 402.094848 -104.120764) (xy 402.052468 -104.078384) (xy 402.015981 -104.030834)
			(xy 401.986014 -103.978928) (xy 401.963078 -103.923555) (xy 401.947565 -103.865662) (xy 401.939742 -103.80624)
			(xy 401.939252 -103.776272) (xy 386.525516 -103.776272) (xy 386.525516 -103.777796) (xy 386.525026 -103.807764)
			(xy 386.517203 -103.867186) (xy 386.50169 -103.925079) (xy 386.478754 -103.980452) (xy 386.448787 -104.032358)
			(xy 386.4123 -104.079908) (xy 386.36992 -104.122288) (xy 386.32237 -104.158775) (xy 386.270464 -104.188742)
			(xy 386.215091 -104.211678) (xy 386.157198 -104.227191) (xy 386.097776 -104.235014) (xy 386.03784 -104.235014)
			(xy 385.978418 -104.227191) (xy 385.920525 -104.211678) (xy 385.865152 -104.188742) (xy 385.813246 -104.158775)
			(xy 385.765696 -104.122288) (xy 385.723316 -104.079908) (xy 385.686829 -104.032358) (xy 385.656862 -103.980452)
			(xy 385.633926 -103.925079) (xy 385.618413 -103.867186) (xy 385.61059 -103.807764) (xy 385.6101 -103.777796)
			(xy 286.754799 -103.777796) (xy 286.754334 -103.806256) (xy 286.746506 -103.865712) (xy 286.730985 -103.923637)
			(xy 286.708036 -103.979041) (xy 286.678052 -104.030975) (xy 286.641546 -104.078551) (xy 286.599141 -104.120956)
			(xy 286.551565 -104.157462) (xy 286.499631 -104.187446) (xy 286.444227 -104.210395) (xy 286.386302 -104.225916)
			(xy 286.326846 -104.233744) (xy 286.266878 -104.233744) (xy 286.207422 -104.225916) (xy 286.149497 -104.210395)
			(xy 286.094093 -104.187446) (xy 286.042159 -104.157462) (xy 285.994583 -104.120956) (xy 285.952178 -104.078551)
			(xy 285.915672 -104.030975) (xy 285.885688 -103.979041) (xy 285.862739 -103.923637) (xy 285.847218 -103.865712)
			(xy 285.83939 -103.806256) (xy 285.8389 -103.776272) (xy 270.425672 -103.776272) (xy 270.425672 -103.777796)
			(xy 270.425182 -103.80778) (xy 270.417354 -103.867236) (xy 270.401833 -103.925161) (xy 270.378884 -103.980565)
			(xy 270.3489 -104.032499) (xy 270.312394 -104.080075) (xy 270.269989 -104.12248) (xy 270.222413 -104.158986)
			(xy 270.170479 -104.18897) (xy 270.115075 -104.211919) (xy 270.05715 -104.22744) (xy 269.997694 -104.235268)
			(xy 269.937726 -104.235268) (xy 269.87827 -104.22744) (xy 269.820345 -104.211919) (xy 269.764941 -104.18897)
			(xy 269.713007 -104.158986) (xy 269.665431 -104.12248) (xy 269.623026 -104.080075) (xy 269.58652 -104.032499)
			(xy 269.556536 -103.980565) (xy 269.533587 -103.925161) (xy 269.518066 -103.867236) (xy 269.510238 -103.80778)
			(xy 269.509748 -103.777796) (xy 170.654955 -103.777796) (xy 170.65449 -103.806256) (xy 170.646662 -103.865712)
			(xy 170.631141 -103.923637) (xy 170.608192 -103.979041) (xy 170.578208 -104.030975) (xy 170.541702 -104.078551)
			(xy 170.499297 -104.120956) (xy 170.451721 -104.157462) (xy 170.399787 -104.187446) (xy 170.344383 -104.210395)
			(xy 170.286458 -104.225916) (xy 170.227002 -104.233744) (xy 170.167034 -104.233744) (xy 170.107578 -104.225916)
			(xy 170.049653 -104.210395) (xy 169.994249 -104.187446) (xy 169.942315 -104.157462) (xy 169.894739 -104.120956)
			(xy 169.852334 -104.078551) (xy 169.815828 -104.030975) (xy 169.785844 -103.979041) (xy 169.762895 -103.923637)
			(xy 169.747374 -103.865712) (xy 169.739546 -103.806256) (xy 169.739056 -103.776272) (xy 154.325828 -103.776272)
			(xy 154.325828 -103.777796) (xy 154.325338 -103.80778) (xy 154.31751 -103.867236) (xy 154.301989 -103.925161)
			(xy 154.27904 -103.980565) (xy 154.249056 -104.032499) (xy 154.21255 -104.080075) (xy 154.170145 -104.12248)
			(xy 154.122569 -104.158986) (xy 154.070635 -104.18897) (xy 154.015231 -104.211919) (xy 153.957306 -104.22744)
			(xy 153.89785 -104.235268) (xy 153.837882 -104.235268) (xy 153.778426 -104.22744) (xy 153.720501 -104.211919)
			(xy 153.665097 -104.18897) (xy 153.613163 -104.158986) (xy 153.565587 -104.12248) (xy 153.523182 -104.080075)
			(xy 153.486676 -104.032499) (xy 153.456692 -103.980565) (xy 153.433743 -103.925161) (xy 153.418222 -103.867236)
			(xy 153.410394 -103.80778) (xy 153.409904 -103.777796) (xy 54.554603 -103.777796) (xy 54.554138 -103.80624)
			(xy 54.546315 -103.865662) (xy 54.530802 -103.923555) (xy 54.507866 -103.978928) (xy 54.477899 -104.030834)
			(xy 54.441412 -104.078384) (xy 54.399032 -104.120764) (xy 54.351482 -104.157251) (xy 54.299576 -104.187218)
			(xy 54.244203 -104.210154) (xy 54.18631 -104.225667) (xy 54.126888 -104.23349) (xy 54.066952 -104.23349)
			(xy 54.00753 -104.225667) (xy 53.949637 -104.210154) (xy 53.894264 -104.187218) (xy 53.842358 -104.157251)
			(xy 53.794808 -104.120764) (xy 53.752428 -104.078384) (xy 53.715941 -104.030834) (xy 53.685974 -103.978928)
			(xy 53.663038 -103.923555) (xy 53.647525 -103.865662) (xy 53.639702 -103.80624) (xy 53.639212 -103.776272)
			(xy 38.225476 -103.776272) (xy 38.225476 -103.777796) (xy 38.224986 -103.807764) (xy 38.217163 -103.867186)
			(xy 38.20165 -103.925079) (xy 38.178714 -103.980452) (xy 38.148747 -104.032358) (xy 38.11226 -104.079908)
			(xy 38.06988 -104.122288) (xy 38.02233 -104.158775) (xy 37.970424 -104.188742) (xy 37.915051 -104.211678)
			(xy 37.857158 -104.227191) (xy 37.797736 -104.235014) (xy 37.7378 -104.235014) (xy 37.678378 -104.227191)
			(xy 37.620485 -104.211678) (xy 37.565112 -104.188742) (xy 37.513206 -104.158775) (xy 37.465656 -104.122288)
			(xy 37.423276 -104.079908) (xy 37.386789 -104.032358) (xy 37.356822 -103.980452) (xy 37.333886 -103.925079)
			(xy 37.318373 -103.867186) (xy 37.31055 -103.807764) (xy 37.31006 -103.777796) (xy 4.308094 -103.777796)
			(xy 4.308094 -105.584498) (xy 34.667952 -105.584498) (xy 34.667952 -104.720898) (xy 34.668442 -104.69093)
			(xy 34.676265 -104.631508) (xy 34.691778 -104.573615) (xy 34.714714 -104.518242) (xy 34.744681 -104.466336)
			(xy 34.781168 -104.418786) (xy 34.823548 -104.376406) (xy 34.871098 -104.339919) (xy 34.923004 -104.309952)
			(xy 34.978377 -104.287016) (xy 35.03627 -104.271503) (xy 35.095692 -104.26368) (xy 35.155628 -104.26368)
			(xy 35.21505 -104.271503) (xy 35.272943 -104.287016) (xy 35.328316 -104.309952) (xy 35.380222 -104.339919)
			(xy 35.427772 -104.376406) (xy 35.470152 -104.418786) (xy 35.506639 -104.466336) (xy 35.536606 -104.518242)
			(xy 35.559542 -104.573615) (xy 35.575055 -104.631508) (xy 35.582878 -104.69093) (xy 35.583368 -104.720898)
			(xy 35.583368 -105.57637) (xy 51.785012 -105.57637) (xy 51.785012 -104.71277) (xy 51.785502 -104.682802)
			(xy 51.793325 -104.62338) (xy 51.808838 -104.565487) (xy 51.831774 -104.510114) (xy 51.861741 -104.458208)
			(xy 51.898228 -104.410658) (xy 51.940608 -104.368278) (xy 51.988158 -104.331791) (xy 52.040064 -104.301824)
			(xy 52.095437 -104.278888) (xy 52.15333 -104.263375) (xy 52.212752 -104.255552) (xy 52.272688 -104.255552)
			(xy 52.33211 -104.263375) (xy 52.390003 -104.278888) (xy 52.445376 -104.301824) (xy 52.497282 -104.331791)
			(xy 52.544832 -104.368278) (xy 52.587212 -104.410658) (xy 52.623699 -104.458208) (xy 52.653666 -104.510114)
			(xy 52.676602 -104.565487) (xy 52.692115 -104.62338) (xy 52.699938 -104.682802) (xy 52.700428 -104.71277)
			(xy 52.700428 -105.57637) (xy 52.700295 -105.584498) (xy 150.767796 -105.584498) (xy 150.767796 -104.720898)
			(xy 150.768286 -104.690914) (xy 150.776114 -104.631458) (xy 150.791635 -104.573533) (xy 150.814584 -104.518129)
			(xy 150.844568 -104.466195) (xy 150.881074 -104.418619) (xy 150.923479 -104.376214) (xy 150.971055 -104.339708)
			(xy 151.022989 -104.309724) (xy 151.078393 -104.286775) (xy 151.136318 -104.271254) (xy 151.195774 -104.263426)
			(xy 151.255742 -104.263426) (xy 151.315198 -104.271254) (xy 151.373123 -104.286775) (xy 151.428527 -104.309724)
			(xy 151.480461 -104.339708) (xy 151.528037 -104.376214) (xy 151.570442 -104.418619) (xy 151.606948 -104.466195)
			(xy 151.636932 -104.518129) (xy 151.659881 -104.573533) (xy 151.675402 -104.631458) (xy 151.68323 -104.690914)
			(xy 151.68372 -104.720898) (xy 151.68372 -105.57637) (xy 167.884856 -105.57637) (xy 167.884856 -104.71277)
			(xy 167.885346 -104.682786) (xy 167.893174 -104.62333) (xy 167.908695 -104.565405) (xy 167.931644 -104.510001)
			(xy 167.961628 -104.458067) (xy 167.998134 -104.410491) (xy 168.040539 -104.368086) (xy 168.088115 -104.33158)
			(xy 168.140049 -104.301596) (xy 168.195453 -104.278647) (xy 168.253378 -104.263126) (xy 168.312834 -104.255298)
			(xy 168.372802 -104.255298) (xy 168.432258 -104.263126) (xy 168.490183 -104.278647) (xy 168.545587 -104.301596)
			(xy 168.597521 -104.33158) (xy 168.645097 -104.368086) (xy 168.687502 -104.410491) (xy 168.724008 -104.458067)
			(xy 168.753992 -104.510001) (xy 168.776941 -104.565405) (xy 168.792462 -104.62333) (xy 168.80029 -104.682786)
			(xy 168.80078 -104.71277) (xy 168.80078 -105.57637) (xy 168.800647 -105.584498) (xy 266.86764 -105.584498)
			(xy 266.86764 -104.720898) (xy 266.86813 -104.690914) (xy 266.875958 -104.631458) (xy 266.891479 -104.573533)
			(xy 266.914428 -104.518129) (xy 266.944412 -104.466195) (xy 266.980918 -104.418619) (xy 267.023323 -104.376214)
			(xy 267.070899 -104.339708) (xy 267.122833 -104.309724) (xy 267.178237 -104.286775) (xy 267.236162 -104.271254)
			(xy 267.295618 -104.263426) (xy 267.355586 -104.263426) (xy 267.415042 -104.271254) (xy 267.472967 -104.286775)
			(xy 267.528371 -104.309724) (xy 267.580305 -104.339708) (xy 267.627881 -104.376214) (xy 267.670286 -104.418619)
			(xy 267.706792 -104.466195) (xy 267.736776 -104.518129) (xy 267.759725 -104.573533) (xy 267.775246 -104.631458)
			(xy 267.783074 -104.690914) (xy 267.783564 -104.720898) (xy 267.783564 -105.57637) (xy 283.9847 -105.57637)
			(xy 283.9847 -104.71277) (xy 283.98519 -104.682786) (xy 283.993018 -104.62333) (xy 284.008539 -104.565405)
			(xy 284.031488 -104.510001) (xy 284.061472 -104.458067) (xy 284.097978 -104.410491) (xy 284.140383 -104.368086)
			(xy 284.187959 -104.33158) (xy 284.239893 -104.301596) (xy 284.295297 -104.278647) (xy 284.353222 -104.263126)
			(xy 284.412678 -104.255298) (xy 284.472646 -104.255298) (xy 284.532102 -104.263126) (xy 284.590027 -104.278647)
			(xy 284.645431 -104.301596) (xy 284.697365 -104.33158) (xy 284.744941 -104.368086) (xy 284.787346 -104.410491)
			(xy 284.823852 -104.458067) (xy 284.853836 -104.510001) (xy 284.876785 -104.565405) (xy 284.892306 -104.62333)
			(xy 284.900134 -104.682786) (xy 284.900624 -104.71277) (xy 284.900624 -105.57637) (xy 284.900491 -105.584498)
			(xy 382.967992 -105.584498) (xy 382.967992 -104.720898) (xy 382.968482 -104.69093) (xy 382.976305 -104.631508)
			(xy 382.991818 -104.573615) (xy 383.014754 -104.518242) (xy 383.044721 -104.466336) (xy 383.081208 -104.418786)
			(xy 383.123588 -104.376406) (xy 383.171138 -104.339919) (xy 383.223044 -104.309952) (xy 383.278417 -104.287016)
			(xy 383.33631 -104.271503) (xy 383.395732 -104.26368) (xy 383.455668 -104.26368) (xy 383.51509 -104.271503)
			(xy 383.572983 -104.287016) (xy 383.628356 -104.309952) (xy 383.680262 -104.339919) (xy 383.727812 -104.376406)
			(xy 383.770192 -104.418786) (xy 383.806679 -104.466336) (xy 383.836646 -104.518242) (xy 383.859582 -104.573615)
			(xy 383.875095 -104.631508) (xy 383.882918 -104.69093) (xy 383.883408 -104.720898) (xy 383.883408 -105.57637)
			(xy 400.085052 -105.57637) (xy 400.085052 -104.71277) (xy 400.085542 -104.682802) (xy 400.093365 -104.62338)
			(xy 400.108878 -104.565487) (xy 400.131814 -104.510114) (xy 400.161781 -104.458208) (xy 400.198268 -104.410658)
			(xy 400.240648 -104.368278) (xy 400.288198 -104.331791) (xy 400.340104 -104.301824) (xy 400.395477 -104.278888)
			(xy 400.45337 -104.263375) (xy 400.512792 -104.255552) (xy 400.572728 -104.255552) (xy 400.63215 -104.263375)
			(xy 400.690043 -104.278888) (xy 400.745416 -104.301824) (xy 400.797322 -104.331791) (xy 400.844872 -104.368278)
			(xy 400.887252 -104.410658) (xy 400.923739 -104.458208) (xy 400.953706 -104.510114) (xy 400.976642 -104.565487)
			(xy 400.992155 -104.62338) (xy 400.999978 -104.682802) (xy 401.000468 -104.71277) (xy 401.000468 -105.57637)
			(xy 400.999978 -105.606338) (xy 400.992155 -105.66576) (xy 400.976642 -105.723653) (xy 400.953706 -105.779026)
			(xy 400.923739 -105.830932) (xy 400.887252 -105.878482) (xy 400.844872 -105.920862) (xy 400.797322 -105.957349)
			(xy 400.745416 -105.987316) (xy 400.690043 -106.010252) (xy 400.63215 -106.025765) (xy 400.572728 -106.033588)
			(xy 400.512792 -106.033588) (xy 400.45337 -106.025765) (xy 400.395477 -106.010252) (xy 400.340104 -105.987316)
			(xy 400.288198 -105.957349) (xy 400.240648 -105.920862) (xy 400.198268 -105.878482) (xy 400.161781 -105.830932)
			(xy 400.131814 -105.779026) (xy 400.108878 -105.723653) (xy 400.093365 -105.66576) (xy 400.085542 -105.606338)
			(xy 400.085052 -105.57637) (xy 383.883408 -105.57637) (xy 383.883408 -105.584498) (xy 383.882918 -105.614466)
			(xy 383.875095 -105.673888) (xy 383.859582 -105.731781) (xy 383.836646 -105.787154) (xy 383.806679 -105.83906)
			(xy 383.770192 -105.88661) (xy 383.727812 -105.92899) (xy 383.680262 -105.965477) (xy 383.628356 -105.995444)
			(xy 383.572983 -106.01838) (xy 383.51509 -106.033893) (xy 383.455668 -106.041716) (xy 383.395732 -106.041716)
			(xy 383.33631 -106.033893) (xy 383.278417 -106.01838) (xy 383.223044 -105.995444) (xy 383.171138 -105.965477)
			(xy 383.123588 -105.92899) (xy 383.081208 -105.88661) (xy 383.044721 -105.83906) (xy 383.014754 -105.787154)
			(xy 382.991818 -105.731781) (xy 382.976305 -105.673888) (xy 382.968482 -105.614466) (xy 382.967992 -105.584498)
			(xy 284.900491 -105.584498) (xy 284.900134 -105.606354) (xy 284.892306 -105.66581) (xy 284.876785 -105.723735)
			(xy 284.853836 -105.779139) (xy 284.823852 -105.831073) (xy 284.787346 -105.878649) (xy 284.744941 -105.921054)
			(xy 284.697365 -105.95756) (xy 284.645431 -105.987544) (xy 284.590027 -106.010493) (xy 284.532102 -106.026014)
			(xy 284.472646 -106.033842) (xy 284.412678 -106.033842) (xy 284.353222 -106.026014) (xy 284.295297 -106.010493)
			(xy 284.239893 -105.987544) (xy 284.187959 -105.95756) (xy 284.140383 -105.921054) (xy 284.097978 -105.878649)
			(xy 284.061472 -105.831073) (xy 284.031488 -105.779139) (xy 284.008539 -105.723735) (xy 283.993018 -105.66581)
			(xy 283.98519 -105.606354) (xy 283.9847 -105.57637) (xy 267.783564 -105.57637) (xy 267.783564 -105.584498)
			(xy 267.783074 -105.614482) (xy 267.775246 -105.673938) (xy 267.759725 -105.731863) (xy 267.736776 -105.787267)
			(xy 267.706792 -105.839201) (xy 267.670286 -105.886777) (xy 267.627881 -105.929182) (xy 267.580305 -105.965688)
			(xy 267.528371 -105.995672) (xy 267.472967 -106.018621) (xy 267.415042 -106.034142) (xy 267.355586 -106.04197)
			(xy 267.295618 -106.04197) (xy 267.236162 -106.034142) (xy 267.178237 -106.018621) (xy 267.122833 -105.995672)
			(xy 267.070899 -105.965688) (xy 267.023323 -105.929182) (xy 266.980918 -105.886777) (xy 266.944412 -105.839201)
			(xy 266.914428 -105.787267) (xy 266.891479 -105.731863) (xy 266.875958 -105.673938) (xy 266.86813 -105.614482)
			(xy 266.86764 -105.584498) (xy 168.800647 -105.584498) (xy 168.80029 -105.606354) (xy 168.792462 -105.66581)
			(xy 168.776941 -105.723735) (xy 168.753992 -105.779139) (xy 168.724008 -105.831073) (xy 168.687502 -105.878649)
			(xy 168.645097 -105.921054) (xy 168.597521 -105.95756) (xy 168.545587 -105.987544) (xy 168.490183 -106.010493)
			(xy 168.432258 -106.026014) (xy 168.372802 -106.033842) (xy 168.312834 -106.033842) (xy 168.253378 -106.026014)
			(xy 168.195453 -106.010493) (xy 168.140049 -105.987544) (xy 168.088115 -105.95756) (xy 168.040539 -105.921054)
			(xy 167.998134 -105.878649) (xy 167.961628 -105.831073) (xy 167.931644 -105.779139) (xy 167.908695 -105.723735)
			(xy 167.893174 -105.66581) (xy 167.885346 -105.606354) (xy 167.884856 -105.57637) (xy 151.68372 -105.57637)
			(xy 151.68372 -105.584498) (xy 151.68323 -105.614482) (xy 151.675402 -105.673938) (xy 151.659881 -105.731863)
			(xy 151.636932 -105.787267) (xy 151.606948 -105.839201) (xy 151.570442 -105.886777) (xy 151.528037 -105.929182)
			(xy 151.480461 -105.965688) (xy 151.428527 -105.995672) (xy 151.373123 -106.018621) (xy 151.315198 -106.034142)
			(xy 151.255742 -106.04197) (xy 151.195774 -106.04197) (xy 151.136318 -106.034142) (xy 151.078393 -106.018621)
			(xy 151.022989 -105.995672) (xy 150.971055 -105.965688) (xy 150.923479 -105.929182) (xy 150.881074 -105.886777)
			(xy 150.844568 -105.839201) (xy 150.814584 -105.787267) (xy 150.791635 -105.731863) (xy 150.776114 -105.673938)
			(xy 150.768286 -105.614482) (xy 150.767796 -105.584498) (xy 52.700295 -105.584498) (xy 52.699938 -105.606338)
			(xy 52.692115 -105.66576) (xy 52.676602 -105.723653) (xy 52.653666 -105.779026) (xy 52.623699 -105.830932)
			(xy 52.587212 -105.878482) (xy 52.544832 -105.920862) (xy 52.497282 -105.957349) (xy 52.445376 -105.987316)
			(xy 52.390003 -106.010252) (xy 52.33211 -106.025765) (xy 52.272688 -106.033588) (xy 52.212752 -106.033588)
			(xy 52.15333 -106.025765) (xy 52.095437 -106.010252) (xy 52.040064 -105.987316) (xy 51.988158 -105.957349)
			(xy 51.940608 -105.920862) (xy 51.898228 -105.878482) (xy 51.861741 -105.830932) (xy 51.831774 -105.779026)
			(xy 51.808838 -105.723653) (xy 51.793325 -105.66576) (xy 51.785502 -105.606338) (xy 51.785012 -105.57637)
			(xy 35.583368 -105.57637) (xy 35.583368 -105.584498) (xy 35.582878 -105.614466) (xy 35.575055 -105.673888)
			(xy 35.559542 -105.731781) (xy 35.536606 -105.787154) (xy 35.506639 -105.83906) (xy 35.470152 -105.88661)
			(xy 35.427772 -105.92899) (xy 35.380222 -105.965477) (xy 35.328316 -105.995444) (xy 35.272943 -106.01838)
			(xy 35.21505 -106.033893) (xy 35.155628 -106.041716) (xy 35.095692 -106.041716) (xy 35.03627 -106.033893)
			(xy 34.978377 -106.01838) (xy 34.923004 -105.995444) (xy 34.871098 -105.965477) (xy 34.823548 -105.92899)
			(xy 34.781168 -105.88661) (xy 34.744681 -105.83906) (xy 34.714714 -105.787154) (xy 34.691778 -105.731781)
			(xy 34.676265 -105.673888) (xy 34.668442 -105.614466) (xy 34.667952 -105.584498) (xy 4.308094 -105.584498)
			(xy 4.308094 -107.377738) (xy 37.31006 -107.377738) (xy 37.31006 -106.514138) (xy 37.31055 -106.48417)
			(xy 37.318373 -106.424748) (xy 37.333886 -106.366855) (xy 37.356822 -106.311482) (xy 37.386789 -106.259576)
			(xy 37.423276 -106.212026) (xy 37.465656 -106.169646) (xy 37.513206 -106.133159) (xy 37.565112 -106.103192)
			(xy 37.620485 -106.080256) (xy 37.678378 -106.064743) (xy 37.7378 -106.05692) (xy 37.797736 -106.05692)
			(xy 37.857158 -106.064743) (xy 37.915051 -106.080256) (xy 37.970424 -106.103192) (xy 38.02233 -106.133159)
			(xy 38.06988 -106.169646) (xy 38.11226 -106.212026) (xy 38.148747 -106.259576) (xy 38.178714 -106.311482)
			(xy 38.20165 -106.366855) (xy 38.217163 -106.424748) (xy 38.224986 -106.48417) (xy 38.225476 -106.514138)
			(xy 38.225476 -107.376214) (xy 53.639212 -107.376214) (xy 53.639212 -106.512614) (xy 53.639702 -106.482646)
			(xy 53.647525 -106.423224) (xy 53.663038 -106.365331) (xy 53.685974 -106.309958) (xy 53.715941 -106.258052)
			(xy 53.752428 -106.210502) (xy 53.794808 -106.168122) (xy 53.842358 -106.131635) (xy 53.894264 -106.101668)
			(xy 53.949637 -106.078732) (xy 54.00753 -106.063219) (xy 54.066952 -106.055396) (xy 54.126888 -106.055396)
			(xy 54.18631 -106.063219) (xy 54.244203 -106.078732) (xy 54.299576 -106.101668) (xy 54.351482 -106.131635)
			(xy 54.399032 -106.168122) (xy 54.441412 -106.210502) (xy 54.477899 -106.258052) (xy 54.507866 -106.309958)
			(xy 54.530802 -106.365331) (xy 54.546315 -106.423224) (xy 54.554138 -106.482646) (xy 54.554628 -106.512614)
			(xy 54.554628 -107.376214) (xy 54.554603 -107.377738) (xy 153.409904 -107.377738) (xy 153.409904 -106.514138)
			(xy 153.410394 -106.484154) (xy 153.418222 -106.424698) (xy 153.433743 -106.366773) (xy 153.456692 -106.311369)
			(xy 153.486676 -106.259435) (xy 153.523182 -106.211859) (xy 153.565587 -106.169454) (xy 153.613163 -106.132948)
			(xy 153.665097 -106.102964) (xy 153.720501 -106.080015) (xy 153.778426 -106.064494) (xy 153.837882 -106.056666)
			(xy 153.89785 -106.056666) (xy 153.957306 -106.064494) (xy 154.015231 -106.080015) (xy 154.070635 -106.102964)
			(xy 154.122569 -106.132948) (xy 154.170145 -106.169454) (xy 154.21255 -106.211859) (xy 154.249056 -106.259435)
			(xy 154.27904 -106.311369) (xy 154.301989 -106.366773) (xy 154.31751 -106.424698) (xy 154.325338 -106.484154)
			(xy 154.325828 -106.514138) (xy 154.325828 -107.376214) (xy 169.739056 -107.376214) (xy 169.739056 -106.512614)
			(xy 169.739546 -106.48263) (xy 169.747374 -106.423174) (xy 169.762895 -106.365249) (xy 169.785844 -106.309845)
			(xy 169.815828 -106.257911) (xy 169.852334 -106.210335) (xy 169.894739 -106.16793) (xy 169.942315 -106.131424)
			(xy 169.994249 -106.10144) (xy 170.049653 -106.078491) (xy 170.107578 -106.06297) (xy 170.167034 -106.055142)
			(xy 170.227002 -106.055142) (xy 170.286458 -106.06297) (xy 170.344383 -106.078491) (xy 170.399787 -106.10144)
			(xy 170.451721 -106.131424) (xy 170.499297 -106.16793) (xy 170.541702 -106.210335) (xy 170.578208 -106.257911)
			(xy 170.608192 -106.309845) (xy 170.631141 -106.365249) (xy 170.646662 -106.423174) (xy 170.65449 -106.48263)
			(xy 170.65498 -106.512614) (xy 170.65498 -107.376214) (xy 170.654955 -107.377738) (xy 269.509748 -107.377738)
			(xy 269.509748 -106.514138) (xy 269.510238 -106.484154) (xy 269.518066 -106.424698) (xy 269.533587 -106.366773)
			(xy 269.556536 -106.311369) (xy 269.58652 -106.259435) (xy 269.623026 -106.211859) (xy 269.665431 -106.169454)
			(xy 269.713007 -106.132948) (xy 269.764941 -106.102964) (xy 269.820345 -106.080015) (xy 269.87827 -106.064494)
			(xy 269.937726 -106.056666) (xy 269.997694 -106.056666) (xy 270.05715 -106.064494) (xy 270.115075 -106.080015)
			(xy 270.170479 -106.102964) (xy 270.222413 -106.132948) (xy 270.269989 -106.169454) (xy 270.312394 -106.211859)
			(xy 270.3489 -106.259435) (xy 270.378884 -106.311369) (xy 270.401833 -106.366773) (xy 270.417354 -106.424698)
			(xy 270.425182 -106.484154) (xy 270.425672 -106.514138) (xy 270.425672 -107.376214) (xy 285.8389 -107.376214)
			(xy 285.8389 -106.512614) (xy 285.83939 -106.48263) (xy 285.847218 -106.423174) (xy 285.862739 -106.365249)
			(xy 285.885688 -106.309845) (xy 285.915672 -106.257911) (xy 285.952178 -106.210335) (xy 285.994583 -106.16793)
			(xy 286.042159 -106.131424) (xy 286.094093 -106.10144) (xy 286.149497 -106.078491) (xy 286.207422 -106.06297)
			(xy 286.266878 -106.055142) (xy 286.326846 -106.055142) (xy 286.386302 -106.06297) (xy 286.444227 -106.078491)
			(xy 286.499631 -106.10144) (xy 286.551565 -106.131424) (xy 286.599141 -106.16793) (xy 286.641546 -106.210335)
			(xy 286.678052 -106.257911) (xy 286.708036 -106.309845) (xy 286.730985 -106.365249) (xy 286.746506 -106.423174)
			(xy 286.754334 -106.48263) (xy 286.754824 -106.512614) (xy 286.754824 -107.376214) (xy 286.754799 -107.377738)
			(xy 385.6101 -107.377738) (xy 385.6101 -106.514138) (xy 385.61059 -106.48417) (xy 385.618413 -106.424748)
			(xy 385.633926 -106.366855) (xy 385.656862 -106.311482) (xy 385.686829 -106.259576) (xy 385.723316 -106.212026)
			(xy 385.765696 -106.169646) (xy 385.813246 -106.133159) (xy 385.865152 -106.103192) (xy 385.920525 -106.080256)
			(xy 385.978418 -106.064743) (xy 386.03784 -106.05692) (xy 386.097776 -106.05692) (xy 386.157198 -106.064743)
			(xy 386.215091 -106.080256) (xy 386.270464 -106.103192) (xy 386.32237 -106.133159) (xy 386.36992 -106.169646)
			(xy 386.4123 -106.212026) (xy 386.448787 -106.259576) (xy 386.478754 -106.311482) (xy 386.50169 -106.366855)
			(xy 386.517203 -106.424748) (xy 386.525026 -106.48417) (xy 386.525516 -106.514138) (xy 386.525516 -107.376214)
			(xy 401.939252 -107.376214) (xy 401.939252 -106.512614) (xy 401.939742 -106.482646) (xy 401.947565 -106.423224)
			(xy 401.963078 -106.365331) (xy 401.986014 -106.309958) (xy 402.015981 -106.258052) (xy 402.052468 -106.210502)
			(xy 402.094848 -106.168122) (xy 402.142398 -106.131635) (xy 402.194304 -106.101668) (xy 402.249677 -106.078732)
			(xy 402.30757 -106.063219) (xy 402.366992 -106.055396) (xy 402.426928 -106.055396) (xy 402.48635 -106.063219)
			(xy 402.544243 -106.078732) (xy 402.599616 -106.101668) (xy 402.651522 -106.131635) (xy 402.699072 -106.168122)
			(xy 402.741452 -106.210502) (xy 402.777939 -106.258052) (xy 402.807906 -106.309958) (xy 402.830842 -106.365331)
			(xy 402.846355 -106.423224) (xy 402.854178 -106.482646) (xy 402.854668 -106.512614) (xy 402.854668 -107.376214)
			(xy 402.854178 -107.406182) (xy 402.846355 -107.465604) (xy 402.830842 -107.523497) (xy 402.807906 -107.57887)
			(xy 402.777939 -107.630776) (xy 402.741452 -107.678326) (xy 402.699072 -107.720706) (xy 402.651522 -107.757193)
			(xy 402.599616 -107.78716) (xy 402.544243 -107.810096) (xy 402.48635 -107.825609) (xy 402.426928 -107.833432)
			(xy 402.366992 -107.833432) (xy 402.30757 -107.825609) (xy 402.249677 -107.810096) (xy 402.194304 -107.78716)
			(xy 402.142398 -107.757193) (xy 402.094848 -107.720706) (xy 402.052468 -107.678326) (xy 402.015981 -107.630776)
			(xy 401.986014 -107.57887) (xy 401.963078 -107.523497) (xy 401.947565 -107.465604) (xy 401.939742 -107.406182)
			(xy 401.939252 -107.376214) (xy 386.525516 -107.376214) (xy 386.525516 -107.377738) (xy 386.525026 -107.407706)
			(xy 386.517203 -107.467128) (xy 386.50169 -107.525021) (xy 386.478754 -107.580394) (xy 386.448787 -107.6323)
			(xy 386.4123 -107.67985) (xy 386.36992 -107.72223) (xy 386.32237 -107.758717) (xy 386.270464 -107.788684)
			(xy 386.215091 -107.81162) (xy 386.157198 -107.827133) (xy 386.097776 -107.834956) (xy 386.03784 -107.834956)
			(xy 385.978418 -107.827133) (xy 385.920525 -107.81162) (xy 385.865152 -107.788684) (xy 385.813246 -107.758717)
			(xy 385.765696 -107.72223) (xy 385.723316 -107.67985) (xy 385.686829 -107.6323) (xy 385.656862 -107.580394)
			(xy 385.633926 -107.525021) (xy 385.618413 -107.467128) (xy 385.61059 -107.407706) (xy 385.6101 -107.377738)
			(xy 286.754799 -107.377738) (xy 286.754334 -107.406198) (xy 286.746506 -107.465654) (xy 286.730985 -107.523579)
			(xy 286.708036 -107.578983) (xy 286.678052 -107.630917) (xy 286.641546 -107.678493) (xy 286.599141 -107.720898)
			(xy 286.551565 -107.757404) (xy 286.499631 -107.787388) (xy 286.444227 -107.810337) (xy 286.386302 -107.825858)
			(xy 286.326846 -107.833686) (xy 286.266878 -107.833686) (xy 286.207422 -107.825858) (xy 286.149497 -107.810337)
			(xy 286.094093 -107.787388) (xy 286.042159 -107.757404) (xy 285.994583 -107.720898) (xy 285.952178 -107.678493)
			(xy 285.915672 -107.630917) (xy 285.885688 -107.578983) (xy 285.862739 -107.523579) (xy 285.847218 -107.465654)
			(xy 285.83939 -107.406198) (xy 285.8389 -107.376214) (xy 270.425672 -107.376214) (xy 270.425672 -107.377738)
			(xy 270.425182 -107.407722) (xy 270.417354 -107.467178) (xy 270.401833 -107.525103) (xy 270.378884 -107.580507)
			(xy 270.3489 -107.632441) (xy 270.312394 -107.680017) (xy 270.269989 -107.722422) (xy 270.222413 -107.758928)
			(xy 270.170479 -107.788912) (xy 270.115075 -107.811861) (xy 270.05715 -107.827382) (xy 269.997694 -107.83521)
			(xy 269.937726 -107.83521) (xy 269.87827 -107.827382) (xy 269.820345 -107.811861) (xy 269.764941 -107.788912)
			(xy 269.713007 -107.758928) (xy 269.665431 -107.722422) (xy 269.623026 -107.680017) (xy 269.58652 -107.632441)
			(xy 269.556536 -107.580507) (xy 269.533587 -107.525103) (xy 269.518066 -107.467178) (xy 269.510238 -107.407722)
			(xy 269.509748 -107.377738) (xy 170.654955 -107.377738) (xy 170.65449 -107.406198) (xy 170.646662 -107.465654)
			(xy 170.631141 -107.523579) (xy 170.608192 -107.578983) (xy 170.578208 -107.630917) (xy 170.541702 -107.678493)
			(xy 170.499297 -107.720898) (xy 170.451721 -107.757404) (xy 170.399787 -107.787388) (xy 170.344383 -107.810337)
			(xy 170.286458 -107.825858) (xy 170.227002 -107.833686) (xy 170.167034 -107.833686) (xy 170.107578 -107.825858)
			(xy 170.049653 -107.810337) (xy 169.994249 -107.787388) (xy 169.942315 -107.757404) (xy 169.894739 -107.720898)
			(xy 169.852334 -107.678493) (xy 169.815828 -107.630917) (xy 169.785844 -107.578983) (xy 169.762895 -107.523579)
			(xy 169.747374 -107.465654) (xy 169.739546 -107.406198) (xy 169.739056 -107.376214) (xy 154.325828 -107.376214)
			(xy 154.325828 -107.377738) (xy 154.325338 -107.407722) (xy 154.31751 -107.467178) (xy 154.301989 -107.525103)
			(xy 154.27904 -107.580507) (xy 154.249056 -107.632441) (xy 154.21255 -107.680017) (xy 154.170145 -107.722422)
			(xy 154.122569 -107.758928) (xy 154.070635 -107.788912) (xy 154.015231 -107.811861) (xy 153.957306 -107.827382)
			(xy 153.89785 -107.83521) (xy 153.837882 -107.83521) (xy 153.778426 -107.827382) (xy 153.720501 -107.811861)
			(xy 153.665097 -107.788912) (xy 153.613163 -107.758928) (xy 153.565587 -107.722422) (xy 153.523182 -107.680017)
			(xy 153.486676 -107.632441) (xy 153.456692 -107.580507) (xy 153.433743 -107.525103) (xy 153.418222 -107.467178)
			(xy 153.410394 -107.407722) (xy 153.409904 -107.377738) (xy 54.554603 -107.377738) (xy 54.554138 -107.406182)
			(xy 54.546315 -107.465604) (xy 54.530802 -107.523497) (xy 54.507866 -107.57887) (xy 54.477899 -107.630776)
			(xy 54.441412 -107.678326) (xy 54.399032 -107.720706) (xy 54.351482 -107.757193) (xy 54.299576 -107.78716)
			(xy 54.244203 -107.810096) (xy 54.18631 -107.825609) (xy 54.126888 -107.833432) (xy 54.066952 -107.833432)
			(xy 54.00753 -107.825609) (xy 53.949637 -107.810096) (xy 53.894264 -107.78716) (xy 53.842358 -107.757193)
			(xy 53.794808 -107.720706) (xy 53.752428 -107.678326) (xy 53.715941 -107.630776) (xy 53.685974 -107.57887)
			(xy 53.663038 -107.523497) (xy 53.647525 -107.465604) (xy 53.639702 -107.406182) (xy 53.639212 -107.376214)
			(xy 38.225476 -107.376214) (xy 38.225476 -107.377738) (xy 38.224986 -107.407706) (xy 38.217163 -107.467128)
			(xy 38.20165 -107.525021) (xy 38.178714 -107.580394) (xy 38.148747 -107.6323) (xy 38.11226 -107.67985)
			(xy 38.06988 -107.72223) (xy 38.02233 -107.758717) (xy 37.970424 -107.788684) (xy 37.915051 -107.81162)
			(xy 37.857158 -107.827133) (xy 37.797736 -107.834956) (xy 37.7378 -107.834956) (xy 37.678378 -107.827133)
			(xy 37.620485 -107.81162) (xy 37.565112 -107.788684) (xy 37.513206 -107.758717) (xy 37.465656 -107.72223)
			(xy 37.423276 -107.67985) (xy 37.386789 -107.6323) (xy 37.356822 -107.580394) (xy 37.333886 -107.525021)
			(xy 37.318373 -107.467128) (xy 37.31055 -107.407706) (xy 37.31006 -107.377738) (xy 4.308094 -107.377738)
			(xy 4.308094 -109.18444) (xy 34.667952 -109.18444) (xy 34.667952 -108.32084) (xy 34.668442 -108.290872)
			(xy 34.676265 -108.23145) (xy 34.691778 -108.173557) (xy 34.714714 -108.118184) (xy 34.744681 -108.066278)
			(xy 34.781168 -108.018728) (xy 34.823548 -107.976348) (xy 34.871098 -107.939861) (xy 34.923004 -107.909894)
			(xy 34.978377 -107.886958) (xy 35.03627 -107.871445) (xy 35.095692 -107.863622) (xy 35.155628 -107.863622)
			(xy 35.21505 -107.871445) (xy 35.272943 -107.886958) (xy 35.328316 -107.909894) (xy 35.380222 -107.939861)
			(xy 35.427772 -107.976348) (xy 35.470152 -108.018728) (xy 35.506639 -108.066278) (xy 35.536606 -108.118184)
			(xy 35.559542 -108.173557) (xy 35.575055 -108.23145) (xy 35.582878 -108.290872) (xy 35.583368 -108.32084)
			(xy 35.583368 -109.176312) (xy 51.785012 -109.176312) (xy 51.785012 -108.312712) (xy 51.785502 -108.282744)
			(xy 51.793325 -108.223322) (xy 51.808838 -108.165429) (xy 51.831774 -108.110056) (xy 51.861741 -108.05815)
			(xy 51.898228 -108.0106) (xy 51.940608 -107.96822) (xy 51.988158 -107.931733) (xy 52.040064 -107.901766)
			(xy 52.095437 -107.87883) (xy 52.15333 -107.863317) (xy 52.212752 -107.855494) (xy 52.272688 -107.855494)
			(xy 52.33211 -107.863317) (xy 52.390003 -107.87883) (xy 52.445376 -107.901766) (xy 52.497282 -107.931733)
			(xy 52.544832 -107.96822) (xy 52.587212 -108.0106) (xy 52.623699 -108.05815) (xy 52.653666 -108.110056)
			(xy 52.676602 -108.165429) (xy 52.692115 -108.223322) (xy 52.699938 -108.282744) (xy 52.700428 -108.312712)
			(xy 52.700428 -109.176312) (xy 52.700295 -109.18444) (xy 150.767796 -109.18444) (xy 150.767796 -108.32084)
			(xy 150.768286 -108.290856) (xy 150.776114 -108.2314) (xy 150.791635 -108.173475) (xy 150.814584 -108.118071)
			(xy 150.844568 -108.066137) (xy 150.881074 -108.018561) (xy 150.923479 -107.976156) (xy 150.971055 -107.93965)
			(xy 151.022989 -107.909666) (xy 151.078393 -107.886717) (xy 151.136318 -107.871196) (xy 151.195774 -107.863368)
			(xy 151.255742 -107.863368) (xy 151.315198 -107.871196) (xy 151.373123 -107.886717) (xy 151.428527 -107.909666)
			(xy 151.480461 -107.93965) (xy 151.528037 -107.976156) (xy 151.570442 -108.018561) (xy 151.606948 -108.066137)
			(xy 151.636932 -108.118071) (xy 151.659881 -108.173475) (xy 151.675402 -108.2314) (xy 151.68323 -108.290856)
			(xy 151.68372 -108.32084) (xy 151.68372 -109.176312) (xy 167.884856 -109.176312) (xy 167.884856 -108.312712)
			(xy 167.885346 -108.282728) (xy 167.893174 -108.223272) (xy 167.908695 -108.165347) (xy 167.931644 -108.109943)
			(xy 167.961628 -108.058009) (xy 167.998134 -108.010433) (xy 168.040539 -107.968028) (xy 168.088115 -107.931522)
			(xy 168.140049 -107.901538) (xy 168.195453 -107.878589) (xy 168.253378 -107.863068) (xy 168.312834 -107.85524)
			(xy 168.372802 -107.85524) (xy 168.432258 -107.863068) (xy 168.490183 -107.878589) (xy 168.545587 -107.901538)
			(xy 168.597521 -107.931522) (xy 168.645097 -107.968028) (xy 168.687502 -108.010433) (xy 168.724008 -108.058009)
			(xy 168.753992 -108.109943) (xy 168.776941 -108.165347) (xy 168.792462 -108.223272) (xy 168.80029 -108.282728)
			(xy 168.80078 -108.312712) (xy 168.80078 -109.176312) (xy 168.800647 -109.18444) (xy 266.86764 -109.18444)
			(xy 266.86764 -108.32084) (xy 266.86813 -108.290856) (xy 266.875958 -108.2314) (xy 266.891479 -108.173475)
			(xy 266.914428 -108.118071) (xy 266.944412 -108.066137) (xy 266.980918 -108.018561) (xy 267.023323 -107.976156)
			(xy 267.070899 -107.93965) (xy 267.122833 -107.909666) (xy 267.178237 -107.886717) (xy 267.236162 -107.871196)
			(xy 267.295618 -107.863368) (xy 267.355586 -107.863368) (xy 267.415042 -107.871196) (xy 267.472967 -107.886717)
			(xy 267.528371 -107.909666) (xy 267.580305 -107.93965) (xy 267.627881 -107.976156) (xy 267.670286 -108.018561)
			(xy 267.706792 -108.066137) (xy 267.736776 -108.118071) (xy 267.759725 -108.173475) (xy 267.775246 -108.2314)
			(xy 267.783074 -108.290856) (xy 267.783564 -108.32084) (xy 267.783564 -109.176312) (xy 283.9847 -109.176312)
			(xy 283.9847 -108.312712) (xy 283.98519 -108.282728) (xy 283.993018 -108.223272) (xy 284.008539 -108.165347)
			(xy 284.031488 -108.109943) (xy 284.061472 -108.058009) (xy 284.097978 -108.010433) (xy 284.140383 -107.968028)
			(xy 284.187959 -107.931522) (xy 284.239893 -107.901538) (xy 284.295297 -107.878589) (xy 284.353222 -107.863068)
			(xy 284.412678 -107.85524) (xy 284.472646 -107.85524) (xy 284.532102 -107.863068) (xy 284.590027 -107.878589)
			(xy 284.645431 -107.901538) (xy 284.697365 -107.931522) (xy 284.744941 -107.968028) (xy 284.787346 -108.010433)
			(xy 284.823852 -108.058009) (xy 284.853836 -108.109943) (xy 284.876785 -108.165347) (xy 284.892306 -108.223272)
			(xy 284.900134 -108.282728) (xy 284.900624 -108.312712) (xy 284.900624 -109.176312) (xy 284.900491 -109.18444)
			(xy 382.967992 -109.18444) (xy 382.967992 -108.32084) (xy 382.968482 -108.290872) (xy 382.976305 -108.23145)
			(xy 382.991818 -108.173557) (xy 383.014754 -108.118184) (xy 383.044721 -108.066278) (xy 383.081208 -108.018728)
			(xy 383.123588 -107.976348) (xy 383.171138 -107.939861) (xy 383.223044 -107.909894) (xy 383.278417 -107.886958)
			(xy 383.33631 -107.871445) (xy 383.395732 -107.863622) (xy 383.455668 -107.863622) (xy 383.51509 -107.871445)
			(xy 383.572983 -107.886958) (xy 383.628356 -107.909894) (xy 383.680262 -107.939861) (xy 383.727812 -107.976348)
			(xy 383.770192 -108.018728) (xy 383.806679 -108.066278) (xy 383.836646 -108.118184) (xy 383.859582 -108.173557)
			(xy 383.875095 -108.23145) (xy 383.882918 -108.290872) (xy 383.883408 -108.32084) (xy 383.883408 -109.176312)
			(xy 400.085052 -109.176312) (xy 400.085052 -108.312712) (xy 400.085542 -108.282744) (xy 400.093365 -108.223322)
			(xy 400.108878 -108.165429) (xy 400.131814 -108.110056) (xy 400.161781 -108.05815) (xy 400.198268 -108.0106)
			(xy 400.240648 -107.96822) (xy 400.288198 -107.931733) (xy 400.340104 -107.901766) (xy 400.395477 -107.87883)
			(xy 400.45337 -107.863317) (xy 400.512792 -107.855494) (xy 400.572728 -107.855494) (xy 400.63215 -107.863317)
			(xy 400.690043 -107.87883) (xy 400.745416 -107.901766) (xy 400.797322 -107.931733) (xy 400.844872 -107.96822)
			(xy 400.887252 -108.0106) (xy 400.923739 -108.05815) (xy 400.953706 -108.110056) (xy 400.976642 -108.165429)
			(xy 400.992155 -108.223322) (xy 400.999978 -108.282744) (xy 401.000468 -108.312712) (xy 401.000468 -109.176312)
			(xy 400.999978 -109.20628) (xy 400.992155 -109.265702) (xy 400.976642 -109.323595) (xy 400.953706 -109.378968)
			(xy 400.923739 -109.430874) (xy 400.887252 -109.478424) (xy 400.844872 -109.520804) (xy 400.797322 -109.557291)
			(xy 400.745416 -109.587258) (xy 400.690043 -109.610194) (xy 400.63215 -109.625707) (xy 400.572728 -109.63353)
			(xy 400.512792 -109.63353) (xy 400.45337 -109.625707) (xy 400.395477 -109.610194) (xy 400.340104 -109.587258)
			(xy 400.288198 -109.557291) (xy 400.240648 -109.520804) (xy 400.198268 -109.478424) (xy 400.161781 -109.430874)
			(xy 400.131814 -109.378968) (xy 400.108878 -109.323595) (xy 400.093365 -109.265702) (xy 400.085542 -109.20628)
			(xy 400.085052 -109.176312) (xy 383.883408 -109.176312) (xy 383.883408 -109.18444) (xy 383.882918 -109.214408)
			(xy 383.875095 -109.27383) (xy 383.859582 -109.331723) (xy 383.836646 -109.387096) (xy 383.806679 -109.439002)
			(xy 383.770192 -109.486552) (xy 383.727812 -109.528932) (xy 383.680262 -109.565419) (xy 383.628356 -109.595386)
			(xy 383.572983 -109.618322) (xy 383.51509 -109.633835) (xy 383.455668 -109.641658) (xy 383.395732 -109.641658)
			(xy 383.33631 -109.633835) (xy 383.278417 -109.618322) (xy 383.223044 -109.595386) (xy 383.171138 -109.565419)
			(xy 383.123588 -109.528932) (xy 383.081208 -109.486552) (xy 383.044721 -109.439002) (xy 383.014754 -109.387096)
			(xy 382.991818 -109.331723) (xy 382.976305 -109.27383) (xy 382.968482 -109.214408) (xy 382.967992 -109.18444)
			(xy 284.900491 -109.18444) (xy 284.900134 -109.206296) (xy 284.892306 -109.265752) (xy 284.876785 -109.323677)
			(xy 284.853836 -109.379081) (xy 284.823852 -109.431015) (xy 284.787346 -109.478591) (xy 284.744941 -109.520996)
			(xy 284.697365 -109.557502) (xy 284.645431 -109.587486) (xy 284.590027 -109.610435) (xy 284.532102 -109.625956)
			(xy 284.472646 -109.633784) (xy 284.412678 -109.633784) (xy 284.353222 -109.625956) (xy 284.295297 -109.610435)
			(xy 284.239893 -109.587486) (xy 284.187959 -109.557502) (xy 284.140383 -109.520996) (xy 284.097978 -109.478591)
			(xy 284.061472 -109.431015) (xy 284.031488 -109.379081) (xy 284.008539 -109.323677) (xy 283.993018 -109.265752)
			(xy 283.98519 -109.206296) (xy 283.9847 -109.176312) (xy 267.783564 -109.176312) (xy 267.783564 -109.18444)
			(xy 267.783074 -109.214424) (xy 267.775246 -109.27388) (xy 267.759725 -109.331805) (xy 267.736776 -109.387209)
			(xy 267.706792 -109.439143) (xy 267.670286 -109.486719) (xy 267.627881 -109.529124) (xy 267.580305 -109.56563)
			(xy 267.528371 -109.595614) (xy 267.472967 -109.618563) (xy 267.415042 -109.634084) (xy 267.355586 -109.641912)
			(xy 267.295618 -109.641912) (xy 267.236162 -109.634084) (xy 267.178237 -109.618563) (xy 267.122833 -109.595614)
			(xy 267.070899 -109.56563) (xy 267.023323 -109.529124) (xy 266.980918 -109.486719) (xy 266.944412 -109.439143)
			(xy 266.914428 -109.387209) (xy 266.891479 -109.331805) (xy 266.875958 -109.27388) (xy 266.86813 -109.214424)
			(xy 266.86764 -109.18444) (xy 168.800647 -109.18444) (xy 168.80029 -109.206296) (xy 168.792462 -109.265752)
			(xy 168.776941 -109.323677) (xy 168.753992 -109.379081) (xy 168.724008 -109.431015) (xy 168.687502 -109.478591)
			(xy 168.645097 -109.520996) (xy 168.597521 -109.557502) (xy 168.545587 -109.587486) (xy 168.490183 -109.610435)
			(xy 168.432258 -109.625956) (xy 168.372802 -109.633784) (xy 168.312834 -109.633784) (xy 168.253378 -109.625956)
			(xy 168.195453 -109.610435) (xy 168.140049 -109.587486) (xy 168.088115 -109.557502) (xy 168.040539 -109.520996)
			(xy 167.998134 -109.478591) (xy 167.961628 -109.431015) (xy 167.931644 -109.379081) (xy 167.908695 -109.323677)
			(xy 167.893174 -109.265752) (xy 167.885346 -109.206296) (xy 167.884856 -109.176312) (xy 151.68372 -109.176312)
			(xy 151.68372 -109.18444) (xy 151.68323 -109.214424) (xy 151.675402 -109.27388) (xy 151.659881 -109.331805)
			(xy 151.636932 -109.387209) (xy 151.606948 -109.439143) (xy 151.570442 -109.486719) (xy 151.528037 -109.529124)
			(xy 151.480461 -109.56563) (xy 151.428527 -109.595614) (xy 151.373123 -109.618563) (xy 151.315198 -109.634084)
			(xy 151.255742 -109.641912) (xy 151.195774 -109.641912) (xy 151.136318 -109.634084) (xy 151.078393 -109.618563)
			(xy 151.022989 -109.595614) (xy 150.971055 -109.56563) (xy 150.923479 -109.529124) (xy 150.881074 -109.486719)
			(xy 150.844568 -109.439143) (xy 150.814584 -109.387209) (xy 150.791635 -109.331805) (xy 150.776114 -109.27388)
			(xy 150.768286 -109.214424) (xy 150.767796 -109.18444) (xy 52.700295 -109.18444) (xy 52.699938 -109.20628)
			(xy 52.692115 -109.265702) (xy 52.676602 -109.323595) (xy 52.653666 -109.378968) (xy 52.623699 -109.430874)
			(xy 52.587212 -109.478424) (xy 52.544832 -109.520804) (xy 52.497282 -109.557291) (xy 52.445376 -109.587258)
			(xy 52.390003 -109.610194) (xy 52.33211 -109.625707) (xy 52.272688 -109.63353) (xy 52.212752 -109.63353)
			(xy 52.15333 -109.625707) (xy 52.095437 -109.610194) (xy 52.040064 -109.587258) (xy 51.988158 -109.557291)
			(xy 51.940608 -109.520804) (xy 51.898228 -109.478424) (xy 51.861741 -109.430874) (xy 51.831774 -109.378968)
			(xy 51.808838 -109.323595) (xy 51.793325 -109.265702) (xy 51.785502 -109.20628) (xy 51.785012 -109.176312)
			(xy 35.583368 -109.176312) (xy 35.583368 -109.18444) (xy 35.582878 -109.214408) (xy 35.575055 -109.27383)
			(xy 35.559542 -109.331723) (xy 35.536606 -109.387096) (xy 35.506639 -109.439002) (xy 35.470152 -109.486552)
			(xy 35.427772 -109.528932) (xy 35.380222 -109.565419) (xy 35.328316 -109.595386) (xy 35.272943 -109.618322)
			(xy 35.21505 -109.633835) (xy 35.155628 -109.641658) (xy 35.095692 -109.641658) (xy 35.03627 -109.633835)
			(xy 34.978377 -109.618322) (xy 34.923004 -109.595386) (xy 34.871098 -109.565419) (xy 34.823548 -109.528932)
			(xy 34.781168 -109.486552) (xy 34.744681 -109.439002) (xy 34.714714 -109.387096) (xy 34.691778 -109.331723)
			(xy 34.676265 -109.27383) (xy 34.668442 -109.214408) (xy 34.667952 -109.18444) (xy 4.308094 -109.18444)
			(xy 4.308094 -110.977934) (xy 37.31006 -110.977934) (xy 37.31006 -110.114334) (xy 37.31055 -110.084366)
			(xy 37.318373 -110.024944) (xy 37.333886 -109.967051) (xy 37.356822 -109.911678) (xy 37.386789 -109.859772)
			(xy 37.423276 -109.812222) (xy 37.465656 -109.769842) (xy 37.513206 -109.733355) (xy 37.565112 -109.703388)
			(xy 37.620485 -109.680452) (xy 37.678378 -109.664939) (xy 37.7378 -109.657116) (xy 37.797736 -109.657116)
			(xy 37.857158 -109.664939) (xy 37.915051 -109.680452) (xy 37.970424 -109.703388) (xy 38.02233 -109.733355)
			(xy 38.06988 -109.769842) (xy 38.11226 -109.812222) (xy 38.148747 -109.859772) (xy 38.178714 -109.911678)
			(xy 38.20165 -109.967051) (xy 38.217163 -110.024944) (xy 38.224986 -110.084366) (xy 38.225476 -110.114334)
			(xy 38.225476 -110.97641) (xy 53.639212 -110.97641) (xy 53.639212 -110.11281) (xy 53.639702 -110.082842)
			(xy 53.647525 -110.02342) (xy 53.663038 -109.965527) (xy 53.685974 -109.910154) (xy 53.715941 -109.858248)
			(xy 53.752428 -109.810698) (xy 53.794808 -109.768318) (xy 53.842358 -109.731831) (xy 53.894264 -109.701864)
			(xy 53.949637 -109.678928) (xy 54.00753 -109.663415) (xy 54.066952 -109.655592) (xy 54.126888 -109.655592)
			(xy 54.18631 -109.663415) (xy 54.244203 -109.678928) (xy 54.299576 -109.701864) (xy 54.351482 -109.731831)
			(xy 54.399032 -109.768318) (xy 54.441412 -109.810698) (xy 54.477899 -109.858248) (xy 54.507866 -109.910154)
			(xy 54.530802 -109.965527) (xy 54.546315 -110.02342) (xy 54.554138 -110.082842) (xy 54.554628 -110.11281)
			(xy 54.554628 -110.97641) (xy 54.554603 -110.977934) (xy 153.409904 -110.977934) (xy 153.409904 -110.114334)
			(xy 153.410394 -110.08435) (xy 153.418222 -110.024894) (xy 153.433743 -109.966969) (xy 153.456692 -109.911565)
			(xy 153.486676 -109.859631) (xy 153.523182 -109.812055) (xy 153.565587 -109.76965) (xy 153.613163 -109.733144)
			(xy 153.665097 -109.70316) (xy 153.720501 -109.680211) (xy 153.778426 -109.66469) (xy 153.837882 -109.656862)
			(xy 153.89785 -109.656862) (xy 153.957306 -109.66469) (xy 154.015231 -109.680211) (xy 154.070635 -109.70316)
			(xy 154.122569 -109.733144) (xy 154.170145 -109.76965) (xy 154.21255 -109.812055) (xy 154.249056 -109.859631)
			(xy 154.27904 -109.911565) (xy 154.301989 -109.966969) (xy 154.31751 -110.024894) (xy 154.325338 -110.08435)
			(xy 154.325828 -110.114334) (xy 154.325828 -110.97641) (xy 169.739056 -110.97641) (xy 169.739056 -110.11281)
			(xy 169.739546 -110.082826) (xy 169.747374 -110.02337) (xy 169.762895 -109.965445) (xy 169.785844 -109.910041)
			(xy 169.815828 -109.858107) (xy 169.852334 -109.810531) (xy 169.894739 -109.768126) (xy 169.942315 -109.73162)
			(xy 169.994249 -109.701636) (xy 170.049653 -109.678687) (xy 170.107578 -109.663166) (xy 170.167034 -109.655338)
			(xy 170.227002 -109.655338) (xy 170.286458 -109.663166) (xy 170.344383 -109.678687) (xy 170.399787 -109.701636)
			(xy 170.451721 -109.73162) (xy 170.499297 -109.768126) (xy 170.541702 -109.810531) (xy 170.578208 -109.858107)
			(xy 170.608192 -109.910041) (xy 170.631141 -109.965445) (xy 170.646662 -110.02337) (xy 170.65449 -110.082826)
			(xy 170.65498 -110.11281) (xy 170.65498 -110.97641) (xy 170.654955 -110.977934) (xy 269.509748 -110.977934)
			(xy 269.509748 -110.114334) (xy 269.510238 -110.08435) (xy 269.518066 -110.024894) (xy 269.533587 -109.966969)
			(xy 269.556536 -109.911565) (xy 269.58652 -109.859631) (xy 269.623026 -109.812055) (xy 269.665431 -109.76965)
			(xy 269.713007 -109.733144) (xy 269.764941 -109.70316) (xy 269.820345 -109.680211) (xy 269.87827 -109.66469)
			(xy 269.937726 -109.656862) (xy 269.997694 -109.656862) (xy 270.05715 -109.66469) (xy 270.115075 -109.680211)
			(xy 270.170479 -109.70316) (xy 270.222413 -109.733144) (xy 270.269989 -109.76965) (xy 270.312394 -109.812055)
			(xy 270.3489 -109.859631) (xy 270.378884 -109.911565) (xy 270.401833 -109.966969) (xy 270.417354 -110.024894)
			(xy 270.425182 -110.08435) (xy 270.425672 -110.114334) (xy 270.425672 -110.97641) (xy 285.8389 -110.97641)
			(xy 285.8389 -110.11281) (xy 285.83939 -110.082826) (xy 285.847218 -110.02337) (xy 285.862739 -109.965445)
			(xy 285.885688 -109.910041) (xy 285.915672 -109.858107) (xy 285.952178 -109.810531) (xy 285.994583 -109.768126)
			(xy 286.042159 -109.73162) (xy 286.094093 -109.701636) (xy 286.149497 -109.678687) (xy 286.207422 -109.663166)
			(xy 286.266878 -109.655338) (xy 286.326846 -109.655338) (xy 286.386302 -109.663166) (xy 286.444227 -109.678687)
			(xy 286.499631 -109.701636) (xy 286.551565 -109.73162) (xy 286.599141 -109.768126) (xy 286.641546 -109.810531)
			(xy 286.678052 -109.858107) (xy 286.708036 -109.910041) (xy 286.730985 -109.965445) (xy 286.746506 -110.02337)
			(xy 286.754334 -110.082826) (xy 286.754824 -110.11281) (xy 286.754824 -110.97641) (xy 286.754799 -110.977934)
			(xy 385.6101 -110.977934) (xy 385.6101 -110.114334) (xy 385.61059 -110.084366) (xy 385.618413 -110.024944)
			(xy 385.633926 -109.967051) (xy 385.656862 -109.911678) (xy 385.686829 -109.859772) (xy 385.723316 -109.812222)
			(xy 385.765696 -109.769842) (xy 385.813246 -109.733355) (xy 385.865152 -109.703388) (xy 385.920525 -109.680452)
			(xy 385.978418 -109.664939) (xy 386.03784 -109.657116) (xy 386.097776 -109.657116) (xy 386.157198 -109.664939)
			(xy 386.215091 -109.680452) (xy 386.270464 -109.703388) (xy 386.32237 -109.733355) (xy 386.36992 -109.769842)
			(xy 386.4123 -109.812222) (xy 386.448787 -109.859772) (xy 386.478754 -109.911678) (xy 386.50169 -109.967051)
			(xy 386.517203 -110.024944) (xy 386.525026 -110.084366) (xy 386.525516 -110.114334) (xy 386.525516 -110.97641)
			(xy 401.939252 -110.97641) (xy 401.939252 -110.11281) (xy 401.939742 -110.082842) (xy 401.947565 -110.02342)
			(xy 401.963078 -109.965527) (xy 401.986014 -109.910154) (xy 402.015981 -109.858248) (xy 402.052468 -109.810698)
			(xy 402.094848 -109.768318) (xy 402.142398 -109.731831) (xy 402.194304 -109.701864) (xy 402.249677 -109.678928)
			(xy 402.30757 -109.663415) (xy 402.366992 -109.655592) (xy 402.426928 -109.655592) (xy 402.48635 -109.663415)
			(xy 402.544243 -109.678928) (xy 402.599616 -109.701864) (xy 402.651522 -109.731831) (xy 402.699072 -109.768318)
			(xy 402.741452 -109.810698) (xy 402.777939 -109.858248) (xy 402.807906 -109.910154) (xy 402.830842 -109.965527)
			(xy 402.846355 -110.02342) (xy 402.854178 -110.082842) (xy 402.854668 -110.11281) (xy 402.854668 -110.97641)
			(xy 402.854178 -111.006378) (xy 402.846355 -111.0658) (xy 402.830842 -111.123693) (xy 402.807906 -111.179066)
			(xy 402.777939 -111.230972) (xy 402.741452 -111.278522) (xy 402.699072 -111.320902) (xy 402.651522 -111.357389)
			(xy 402.599616 -111.387356) (xy 402.544243 -111.410292) (xy 402.48635 -111.425805) (xy 402.426928 -111.433628)
			(xy 402.366992 -111.433628) (xy 402.30757 -111.425805) (xy 402.249677 -111.410292) (xy 402.194304 -111.387356)
			(xy 402.142398 -111.357389) (xy 402.094848 -111.320902) (xy 402.052468 -111.278522) (xy 402.015981 -111.230972)
			(xy 401.986014 -111.179066) (xy 401.963078 -111.123693) (xy 401.947565 -111.0658) (xy 401.939742 -111.006378)
			(xy 401.939252 -110.97641) (xy 386.525516 -110.97641) (xy 386.525516 -110.977934) (xy 386.525026 -111.007902)
			(xy 386.517203 -111.067324) (xy 386.50169 -111.125217) (xy 386.478754 -111.18059) (xy 386.448787 -111.232496)
			(xy 386.4123 -111.280046) (xy 386.36992 -111.322426) (xy 386.32237 -111.358913) (xy 386.270464 -111.38888)
			(xy 386.215091 -111.411816) (xy 386.157198 -111.427329) (xy 386.097776 -111.435152) (xy 386.03784 -111.435152)
			(xy 385.978418 -111.427329) (xy 385.920525 -111.411816) (xy 385.865152 -111.38888) (xy 385.813246 -111.358913)
			(xy 385.765696 -111.322426) (xy 385.723316 -111.280046) (xy 385.686829 -111.232496) (xy 385.656862 -111.18059)
			(xy 385.633926 -111.125217) (xy 385.618413 -111.067324) (xy 385.61059 -111.007902) (xy 385.6101 -110.977934)
			(xy 286.754799 -110.977934) (xy 286.754334 -111.006394) (xy 286.746506 -111.06585) (xy 286.730985 -111.123775)
			(xy 286.708036 -111.179179) (xy 286.678052 -111.231113) (xy 286.641546 -111.278689) (xy 286.599141 -111.321094)
			(xy 286.551565 -111.3576) (xy 286.499631 -111.387584) (xy 286.444227 -111.410533) (xy 286.386302 -111.426054)
			(xy 286.326846 -111.433882) (xy 286.266878 -111.433882) (xy 286.207422 -111.426054) (xy 286.149497 -111.410533)
			(xy 286.094093 -111.387584) (xy 286.042159 -111.3576) (xy 285.994583 -111.321094) (xy 285.952178 -111.278689)
			(xy 285.915672 -111.231113) (xy 285.885688 -111.179179) (xy 285.862739 -111.123775) (xy 285.847218 -111.06585)
			(xy 285.83939 -111.006394) (xy 285.8389 -110.97641) (xy 270.425672 -110.97641) (xy 270.425672 -110.977934)
			(xy 270.425182 -111.007918) (xy 270.417354 -111.067374) (xy 270.401833 -111.125299) (xy 270.378884 -111.180703)
			(xy 270.3489 -111.232637) (xy 270.312394 -111.280213) (xy 270.269989 -111.322618) (xy 270.222413 -111.359124)
			(xy 270.170479 -111.389108) (xy 270.115075 -111.412057) (xy 270.05715 -111.427578) (xy 269.997694 -111.435406)
			(xy 269.937726 -111.435406) (xy 269.87827 -111.427578) (xy 269.820345 -111.412057) (xy 269.764941 -111.389108)
			(xy 269.713007 -111.359124) (xy 269.665431 -111.322618) (xy 269.623026 -111.280213) (xy 269.58652 -111.232637)
			(xy 269.556536 -111.180703) (xy 269.533587 -111.125299) (xy 269.518066 -111.067374) (xy 269.510238 -111.007918)
			(xy 269.509748 -110.977934) (xy 170.654955 -110.977934) (xy 170.65449 -111.006394) (xy 170.646662 -111.06585)
			(xy 170.631141 -111.123775) (xy 170.608192 -111.179179) (xy 170.578208 -111.231113) (xy 170.541702 -111.278689)
			(xy 170.499297 -111.321094) (xy 170.451721 -111.3576) (xy 170.399787 -111.387584) (xy 170.344383 -111.410533)
			(xy 170.286458 -111.426054) (xy 170.227002 -111.433882) (xy 170.167034 -111.433882) (xy 170.107578 -111.426054)
			(xy 170.049653 -111.410533) (xy 169.994249 -111.387584) (xy 169.942315 -111.3576) (xy 169.894739 -111.321094)
			(xy 169.852334 -111.278689) (xy 169.815828 -111.231113) (xy 169.785844 -111.179179) (xy 169.762895 -111.123775)
			(xy 169.747374 -111.06585) (xy 169.739546 -111.006394) (xy 169.739056 -110.97641) (xy 154.325828 -110.97641)
			(xy 154.325828 -110.977934) (xy 154.325338 -111.007918) (xy 154.31751 -111.067374) (xy 154.301989 -111.125299)
			(xy 154.27904 -111.180703) (xy 154.249056 -111.232637) (xy 154.21255 -111.280213) (xy 154.170145 -111.322618)
			(xy 154.122569 -111.359124) (xy 154.070635 -111.389108) (xy 154.015231 -111.412057) (xy 153.957306 -111.427578)
			(xy 153.89785 -111.435406) (xy 153.837882 -111.435406) (xy 153.778426 -111.427578) (xy 153.720501 -111.412057)
			(xy 153.665097 -111.389108) (xy 153.613163 -111.359124) (xy 153.565587 -111.322618) (xy 153.523182 -111.280213)
			(xy 153.486676 -111.232637) (xy 153.456692 -111.180703) (xy 153.433743 -111.125299) (xy 153.418222 -111.067374)
			(xy 153.410394 -111.007918) (xy 153.409904 -110.977934) (xy 54.554603 -110.977934) (xy 54.554138 -111.006378)
			(xy 54.546315 -111.0658) (xy 54.530802 -111.123693) (xy 54.507866 -111.179066) (xy 54.477899 -111.230972)
			(xy 54.441412 -111.278522) (xy 54.399032 -111.320902) (xy 54.351482 -111.357389) (xy 54.299576 -111.387356)
			(xy 54.244203 -111.410292) (xy 54.18631 -111.425805) (xy 54.126888 -111.433628) (xy 54.066952 -111.433628)
			(xy 54.00753 -111.425805) (xy 53.949637 -111.410292) (xy 53.894264 -111.387356) (xy 53.842358 -111.357389)
			(xy 53.794808 -111.320902) (xy 53.752428 -111.278522) (xy 53.715941 -111.230972) (xy 53.685974 -111.179066)
			(xy 53.663038 -111.123693) (xy 53.647525 -111.0658) (xy 53.639702 -111.006378) (xy 53.639212 -110.97641)
			(xy 38.225476 -110.97641) (xy 38.225476 -110.977934) (xy 38.224986 -111.007902) (xy 38.217163 -111.067324)
			(xy 38.20165 -111.125217) (xy 38.178714 -111.18059) (xy 38.148747 -111.232496) (xy 38.11226 -111.280046)
			(xy 38.06988 -111.322426) (xy 38.02233 -111.358913) (xy 37.970424 -111.38888) (xy 37.915051 -111.411816)
			(xy 37.857158 -111.427329) (xy 37.797736 -111.435152) (xy 37.7378 -111.435152) (xy 37.678378 -111.427329)
			(xy 37.620485 -111.411816) (xy 37.565112 -111.38888) (xy 37.513206 -111.358913) (xy 37.465656 -111.322426)
			(xy 37.423276 -111.280046) (xy 37.386789 -111.232496) (xy 37.356822 -111.18059) (xy 37.333886 -111.125217)
			(xy 37.318373 -111.067324) (xy 37.31055 -111.007902) (xy 37.31006 -110.977934) (xy 4.308094 -110.977934)
			(xy 4.308094 -112.784382) (xy 34.667952 -112.784382) (xy 34.667952 -111.920782) (xy 34.668442 -111.890814)
			(xy 34.676265 -111.831392) (xy 34.691778 -111.773499) (xy 34.714714 -111.718126) (xy 34.744681 -111.66622)
			(xy 34.781168 -111.61867) (xy 34.823548 -111.57629) (xy 34.871098 -111.539803) (xy 34.923004 -111.509836)
			(xy 34.978377 -111.4869) (xy 35.03627 -111.471387) (xy 35.095692 -111.463564) (xy 35.155628 -111.463564)
			(xy 35.21505 -111.471387) (xy 35.272943 -111.4869) (xy 35.328316 -111.509836) (xy 35.380222 -111.539803)
			(xy 35.427772 -111.57629) (xy 35.470152 -111.61867) (xy 35.506639 -111.66622) (xy 35.536606 -111.718126)
			(xy 35.559542 -111.773499) (xy 35.575055 -111.831392) (xy 35.582878 -111.890814) (xy 35.583368 -111.920782)
			(xy 35.583368 -112.776508) (xy 51.785012 -112.776508) (xy 51.785012 -111.912908) (xy 51.785502 -111.88294)
			(xy 51.793325 -111.823518) (xy 51.808838 -111.765625) (xy 51.831774 -111.710252) (xy 51.861741 -111.658346)
			(xy 51.898228 -111.610796) (xy 51.940608 -111.568416) (xy 51.988158 -111.531929) (xy 52.040064 -111.501962)
			(xy 52.095437 -111.479026) (xy 52.15333 -111.463513) (xy 52.212752 -111.45569) (xy 52.272688 -111.45569)
			(xy 52.33211 -111.463513) (xy 52.390003 -111.479026) (xy 52.445376 -111.501962) (xy 52.497282 -111.531929)
			(xy 52.544832 -111.568416) (xy 52.587212 -111.610796) (xy 52.623699 -111.658346) (xy 52.653666 -111.710252)
			(xy 52.676602 -111.765625) (xy 52.692115 -111.823518) (xy 52.699938 -111.88294) (xy 52.700428 -111.912908)
			(xy 52.700428 -112.776508) (xy 52.700299 -112.784382) (xy 150.767796 -112.784382) (xy 150.767796 -111.920782)
			(xy 150.768286 -111.890798) (xy 150.776114 -111.831342) (xy 150.791635 -111.773417) (xy 150.814584 -111.718013)
			(xy 150.844568 -111.666079) (xy 150.881074 -111.618503) (xy 150.923479 -111.576098) (xy 150.971055 -111.539592)
			(xy 151.022989 -111.509608) (xy 151.078393 -111.486659) (xy 151.136318 -111.471138) (xy 151.195774 -111.46331)
			(xy 151.255742 -111.46331) (xy 151.315198 -111.471138) (xy 151.373123 -111.486659) (xy 151.428527 -111.509608)
			(xy 151.480461 -111.539592) (xy 151.528037 -111.576098) (xy 151.570442 -111.618503) (xy 151.606948 -111.666079)
			(xy 151.636932 -111.718013) (xy 151.659881 -111.773417) (xy 151.675402 -111.831342) (xy 151.68323 -111.890798)
			(xy 151.68372 -111.920782) (xy 151.68372 -112.776508) (xy 167.884856 -112.776508) (xy 167.884856 -111.912908)
			(xy 167.885346 -111.882924) (xy 167.893174 -111.823468) (xy 167.908695 -111.765543) (xy 167.931644 -111.710139)
			(xy 167.961628 -111.658205) (xy 167.998134 -111.610629) (xy 168.040539 -111.568224) (xy 168.088115 -111.531718)
			(xy 168.140049 -111.501734) (xy 168.195453 -111.478785) (xy 168.253378 -111.463264) (xy 168.312834 -111.455436)
			(xy 168.372802 -111.455436) (xy 168.432258 -111.463264) (xy 168.490183 -111.478785) (xy 168.545587 -111.501734)
			(xy 168.597521 -111.531718) (xy 168.645097 -111.568224) (xy 168.687502 -111.610629) (xy 168.724008 -111.658205)
			(xy 168.753992 -111.710139) (xy 168.776941 -111.765543) (xy 168.792462 -111.823468) (xy 168.80029 -111.882924)
			(xy 168.80078 -111.912908) (xy 168.80078 -112.776508) (xy 168.800651 -112.784382) (xy 266.86764 -112.784382)
			(xy 266.86764 -111.920782) (xy 266.86813 -111.890798) (xy 266.875958 -111.831342) (xy 266.891479 -111.773417)
			(xy 266.914428 -111.718013) (xy 266.944412 -111.666079) (xy 266.980918 -111.618503) (xy 267.023323 -111.576098)
			(xy 267.070899 -111.539592) (xy 267.122833 -111.509608) (xy 267.178237 -111.486659) (xy 267.236162 -111.471138)
			(xy 267.295618 -111.46331) (xy 267.355586 -111.46331) (xy 267.415042 -111.471138) (xy 267.472967 -111.486659)
			(xy 267.528371 -111.509608) (xy 267.580305 -111.539592) (xy 267.627881 -111.576098) (xy 267.670286 -111.618503)
			(xy 267.706792 -111.666079) (xy 267.736776 -111.718013) (xy 267.759725 -111.773417) (xy 267.775246 -111.831342)
			(xy 267.783074 -111.890798) (xy 267.783564 -111.920782) (xy 267.783564 -112.776508) (xy 283.9847 -112.776508)
			(xy 283.9847 -111.912908) (xy 283.98519 -111.882924) (xy 283.993018 -111.823468) (xy 284.008539 -111.765543)
			(xy 284.031488 -111.710139) (xy 284.061472 -111.658205) (xy 284.097978 -111.610629) (xy 284.140383 -111.568224)
			(xy 284.187959 -111.531718) (xy 284.239893 -111.501734) (xy 284.295297 -111.478785) (xy 284.353222 -111.463264)
			(xy 284.412678 -111.455436) (xy 284.472646 -111.455436) (xy 284.532102 -111.463264) (xy 284.590027 -111.478785)
			(xy 284.645431 -111.501734) (xy 284.697365 -111.531718) (xy 284.744941 -111.568224) (xy 284.787346 -111.610629)
			(xy 284.823852 -111.658205) (xy 284.853836 -111.710139) (xy 284.876785 -111.765543) (xy 284.892306 -111.823468)
			(xy 284.900134 -111.882924) (xy 284.900624 -111.912908) (xy 284.900624 -112.776508) (xy 284.900495 -112.784382)
			(xy 382.967992 -112.784382) (xy 382.967992 -111.920782) (xy 382.968482 -111.890814) (xy 382.976305 -111.831392)
			(xy 382.991818 -111.773499) (xy 383.014754 -111.718126) (xy 383.044721 -111.66622) (xy 383.081208 -111.61867)
			(xy 383.123588 -111.57629) (xy 383.171138 -111.539803) (xy 383.223044 -111.509836) (xy 383.278417 -111.4869)
			(xy 383.33631 -111.471387) (xy 383.395732 -111.463564) (xy 383.455668 -111.463564) (xy 383.51509 -111.471387)
			(xy 383.572983 -111.4869) (xy 383.628356 -111.509836) (xy 383.680262 -111.539803) (xy 383.727812 -111.57629)
			(xy 383.770192 -111.61867) (xy 383.806679 -111.66622) (xy 383.836646 -111.718126) (xy 383.859582 -111.773499)
			(xy 383.875095 -111.831392) (xy 383.882918 -111.890814) (xy 383.883408 -111.920782) (xy 383.883408 -112.776508)
			(xy 400.085052 -112.776508) (xy 400.085052 -111.912908) (xy 400.085542 -111.88294) (xy 400.093365 -111.823518)
			(xy 400.108878 -111.765625) (xy 400.131814 -111.710252) (xy 400.161781 -111.658346) (xy 400.198268 -111.610796)
			(xy 400.240648 -111.568416) (xy 400.288198 -111.531929) (xy 400.340104 -111.501962) (xy 400.395477 -111.479026)
			(xy 400.45337 -111.463513) (xy 400.512792 -111.45569) (xy 400.572728 -111.45569) (xy 400.63215 -111.463513)
			(xy 400.690043 -111.479026) (xy 400.745416 -111.501962) (xy 400.797322 -111.531929) (xy 400.844872 -111.568416)
			(xy 400.887252 -111.610796) (xy 400.923739 -111.658346) (xy 400.953706 -111.710252) (xy 400.976642 -111.765625)
			(xy 400.992155 -111.823518) (xy 400.999978 -111.88294) (xy 401.000468 -111.912908) (xy 401.000468 -112.776508)
			(xy 400.999978 -112.806476) (xy 400.992155 -112.865898) (xy 400.976642 -112.923791) (xy 400.953706 -112.979164)
			(xy 400.923739 -113.03107) (xy 400.887252 -113.07862) (xy 400.844872 -113.121) (xy 400.797322 -113.157487)
			(xy 400.745416 -113.187454) (xy 400.690043 -113.21039) (xy 400.63215 -113.225903) (xy 400.572728 -113.233726)
			(xy 400.512792 -113.233726) (xy 400.45337 -113.225903) (xy 400.395477 -113.21039) (xy 400.340104 -113.187454)
			(xy 400.288198 -113.157487) (xy 400.240648 -113.121) (xy 400.198268 -113.07862) (xy 400.161781 -113.03107)
			(xy 400.131814 -112.979164) (xy 400.108878 -112.923791) (xy 400.093365 -112.865898) (xy 400.085542 -112.806476)
			(xy 400.085052 -112.776508) (xy 383.883408 -112.776508) (xy 383.883408 -112.784382) (xy 383.882918 -112.81435)
			(xy 383.875095 -112.873772) (xy 383.859582 -112.931665) (xy 383.836646 -112.987038) (xy 383.806679 -113.038944)
			(xy 383.770192 -113.086494) (xy 383.727812 -113.128874) (xy 383.680262 -113.165361) (xy 383.628356 -113.195328)
			(xy 383.572983 -113.218264) (xy 383.51509 -113.233777) (xy 383.455668 -113.2416) (xy 383.395732 -113.2416)
			(xy 383.33631 -113.233777) (xy 383.278417 -113.218264) (xy 383.223044 -113.195328) (xy 383.171138 -113.165361)
			(xy 383.123588 -113.128874) (xy 383.081208 -113.086494) (xy 383.044721 -113.038944) (xy 383.014754 -112.987038)
			(xy 382.991818 -112.931665) (xy 382.976305 -112.873772) (xy 382.968482 -112.81435) (xy 382.967992 -112.784382)
			(xy 284.900495 -112.784382) (xy 284.900134 -112.806492) (xy 284.892306 -112.865948) (xy 284.876785 -112.923873)
			(xy 284.853836 -112.979277) (xy 284.823852 -113.031211) (xy 284.787346 -113.078787) (xy 284.744941 -113.121192)
			(xy 284.697365 -113.157698) (xy 284.645431 -113.187682) (xy 284.590027 -113.210631) (xy 284.532102 -113.226152)
			(xy 284.472646 -113.23398) (xy 284.412678 -113.23398) (xy 284.353222 -113.226152) (xy 284.295297 -113.210631)
			(xy 284.239893 -113.187682) (xy 284.187959 -113.157698) (xy 284.140383 -113.121192) (xy 284.097978 -113.078787)
			(xy 284.061472 -113.031211) (xy 284.031488 -112.979277) (xy 284.008539 -112.923873) (xy 283.993018 -112.865948)
			(xy 283.98519 -112.806492) (xy 283.9847 -112.776508) (xy 267.783564 -112.776508) (xy 267.783564 -112.784382)
			(xy 267.783074 -112.814366) (xy 267.775246 -112.873822) (xy 267.759725 -112.931747) (xy 267.736776 -112.987151)
			(xy 267.706792 -113.039085) (xy 267.670286 -113.086661) (xy 267.627881 -113.129066) (xy 267.580305 -113.165572)
			(xy 267.528371 -113.195556) (xy 267.472967 -113.218505) (xy 267.415042 -113.234026) (xy 267.355586 -113.241854)
			(xy 267.295618 -113.241854) (xy 267.236162 -113.234026) (xy 267.178237 -113.218505) (xy 267.122833 -113.195556)
			(xy 267.070899 -113.165572) (xy 267.023323 -113.129066) (xy 266.980918 -113.086661) (xy 266.944412 -113.039085)
			(xy 266.914428 -112.987151) (xy 266.891479 -112.931747) (xy 266.875958 -112.873822) (xy 266.86813 -112.814366)
			(xy 266.86764 -112.784382) (xy 168.800651 -112.784382) (xy 168.80029 -112.806492) (xy 168.792462 -112.865948)
			(xy 168.776941 -112.923873) (xy 168.753992 -112.979277) (xy 168.724008 -113.031211) (xy 168.687502 -113.078787)
			(xy 168.645097 -113.121192) (xy 168.597521 -113.157698) (xy 168.545587 -113.187682) (xy 168.490183 -113.210631)
			(xy 168.432258 -113.226152) (xy 168.372802 -113.23398) (xy 168.312834 -113.23398) (xy 168.253378 -113.226152)
			(xy 168.195453 -113.210631) (xy 168.140049 -113.187682) (xy 168.088115 -113.157698) (xy 168.040539 -113.121192)
			(xy 167.998134 -113.078787) (xy 167.961628 -113.031211) (xy 167.931644 -112.979277) (xy 167.908695 -112.923873)
			(xy 167.893174 -112.865948) (xy 167.885346 -112.806492) (xy 167.884856 -112.776508) (xy 151.68372 -112.776508)
			(xy 151.68372 -112.784382) (xy 151.68323 -112.814366) (xy 151.675402 -112.873822) (xy 151.659881 -112.931747)
			(xy 151.636932 -112.987151) (xy 151.606948 -113.039085) (xy 151.570442 -113.086661) (xy 151.528037 -113.129066)
			(xy 151.480461 -113.165572) (xy 151.428527 -113.195556) (xy 151.373123 -113.218505) (xy 151.315198 -113.234026)
			(xy 151.255742 -113.241854) (xy 151.195774 -113.241854) (xy 151.136318 -113.234026) (xy 151.078393 -113.218505)
			(xy 151.022989 -113.195556) (xy 150.971055 -113.165572) (xy 150.923479 -113.129066) (xy 150.881074 -113.086661)
			(xy 150.844568 -113.039085) (xy 150.814584 -112.987151) (xy 150.791635 -112.931747) (xy 150.776114 -112.873822)
			(xy 150.768286 -112.814366) (xy 150.767796 -112.784382) (xy 52.700299 -112.784382) (xy 52.699938 -112.806476)
			(xy 52.692115 -112.865898) (xy 52.676602 -112.923791) (xy 52.653666 -112.979164) (xy 52.623699 -113.03107)
			(xy 52.587212 -113.07862) (xy 52.544832 -113.121) (xy 52.497282 -113.157487) (xy 52.445376 -113.187454)
			(xy 52.390003 -113.21039) (xy 52.33211 -113.225903) (xy 52.272688 -113.233726) (xy 52.212752 -113.233726)
			(xy 52.15333 -113.225903) (xy 52.095437 -113.21039) (xy 52.040064 -113.187454) (xy 51.988158 -113.157487)
			(xy 51.940608 -113.121) (xy 51.898228 -113.07862) (xy 51.861741 -113.03107) (xy 51.831774 -112.979164)
			(xy 51.808838 -112.923791) (xy 51.793325 -112.865898) (xy 51.785502 -112.806476) (xy 51.785012 -112.776508)
			(xy 35.583368 -112.776508) (xy 35.583368 -112.784382) (xy 35.582878 -112.81435) (xy 35.575055 -112.873772)
			(xy 35.559542 -112.931665) (xy 35.536606 -112.987038) (xy 35.506639 -113.038944) (xy 35.470152 -113.086494)
			(xy 35.427772 -113.128874) (xy 35.380222 -113.165361) (xy 35.328316 -113.195328) (xy 35.272943 -113.218264)
			(xy 35.21505 -113.233777) (xy 35.155628 -113.2416) (xy 35.095692 -113.2416) (xy 35.03627 -113.233777)
			(xy 34.978377 -113.218264) (xy 34.923004 -113.195328) (xy 34.871098 -113.165361) (xy 34.823548 -113.128874)
			(xy 34.781168 -113.086494) (xy 34.744681 -113.038944) (xy 34.714714 -112.987038) (xy 34.691778 -112.931665)
			(xy 34.676265 -112.873772) (xy 34.668442 -112.81435) (xy 34.667952 -112.784382) (xy 4.308094 -112.784382)
			(xy 4.308094 -117.758718) (xy 74.474832 -117.758718) (xy 74.474832 -116.895118) (xy 74.475322 -116.865134)
			(xy 74.48315 -116.805678) (xy 74.498671 -116.747753) (xy 74.52162 -116.692349) (xy 74.551604 -116.640415)
			(xy 74.58811 -116.592839) (xy 74.630515 -116.550434) (xy 74.678091 -116.513928) (xy 74.730025 -116.483944)
			(xy 74.785429 -116.460995) (xy 74.843354 -116.445474) (xy 74.90281 -116.437646) (xy 74.962778 -116.437646)
			(xy 75.022234 -116.445474) (xy 75.080159 -116.460995) (xy 75.135563 -116.483944) (xy 75.187497 -116.513928)
			(xy 75.235073 -116.550434) (xy 75.277478 -116.592839) (xy 75.313984 -116.640415) (xy 75.343968 -116.692349)
			(xy 75.366917 -116.747753) (xy 75.382438 -116.805678) (xy 75.390266 -116.865134) (xy 75.390756 -116.895118)
			(xy 75.390756 -117.758718) (xy 190.574676 -117.758718) (xy 190.574676 -116.895118) (xy 190.575166 -116.865134)
			(xy 190.582994 -116.805678) (xy 190.598515 -116.747753) (xy 190.621464 -116.692349) (xy 190.651448 -116.640415)
			(xy 190.687954 -116.592839) (xy 190.730359 -116.550434) (xy 190.777935 -116.513928) (xy 190.829869 -116.483944)
			(xy 190.885273 -116.460995) (xy 190.943198 -116.445474) (xy 191.002654 -116.437646) (xy 191.062622 -116.437646)
			(xy 191.122078 -116.445474) (xy 191.180003 -116.460995) (xy 191.235407 -116.483944) (xy 191.287341 -116.513928)
			(xy 191.334917 -116.550434) (xy 191.377322 -116.592839) (xy 191.413828 -116.640415) (xy 191.443812 -116.692349)
			(xy 191.466761 -116.747753) (xy 191.482282 -116.805678) (xy 191.49011 -116.865134) (xy 191.4906 -116.895118)
			(xy 191.4906 -117.758718) (xy 306.675028 -117.758718) (xy 306.675028 -116.895118) (xy 306.675518 -116.86515)
			(xy 306.683341 -116.805728) (xy 306.698854 -116.747835) (xy 306.72179 -116.692462) (xy 306.751757 -116.640556)
			(xy 306.788244 -116.593006) (xy 306.830624 -116.550626) (xy 306.878174 -116.514139) (xy 306.93008 -116.484172)
			(xy 306.985453 -116.461236) (xy 307.043346 -116.445723) (xy 307.102768 -116.4379) (xy 307.162704 -116.4379)
			(xy 307.222126 -116.445723) (xy 307.280019 -116.461236) (xy 307.335392 -116.484172) (xy 307.387298 -116.514139)
			(xy 307.434848 -116.550626) (xy 307.477228 -116.593006) (xy 307.513715 -116.640556) (xy 307.543682 -116.692462)
			(xy 307.566618 -116.747835) (xy 307.582131 -116.805728) (xy 307.589954 -116.86515) (xy 307.590444 -116.895118)
			(xy 307.590444 -117.758718) (xy 307.590436 -117.759226) (xy 422.774872 -117.759226) (xy 422.774872 -116.895626)
			(xy 422.775362 -116.865642) (xy 422.78319 -116.806186) (xy 422.798711 -116.748261) (xy 422.82166 -116.692857)
			(xy 422.851644 -116.640923) (xy 422.88815 -116.593347) (xy 422.930555 -116.550942) (xy 422.978131 -116.514436)
			(xy 423.030065 -116.484452) (xy 423.085469 -116.461503) (xy 423.143394 -116.445982) (xy 423.20285 -116.438154)
			(xy 423.262818 -116.438154) (xy 423.322274 -116.445982) (xy 423.380199 -116.461503) (xy 423.435603 -116.484452)
			(xy 423.487537 -116.514436) (xy 423.535113 -116.550942) (xy 423.577518 -116.593347) (xy 423.614024 -116.640923)
			(xy 423.644008 -116.692857) (xy 423.666957 -116.748261) (xy 423.682478 -116.806186) (xy 423.690306 -116.865642)
			(xy 423.690796 -116.895626) (xy 423.690796 -117.759226) (xy 423.690306 -117.78921) (xy 423.682478 -117.848666)
			(xy 423.666957 -117.906591) (xy 423.644008 -117.961995) (xy 423.614024 -118.013929) (xy 423.577518 -118.061505)
			(xy 423.535113 -118.10391) (xy 423.487537 -118.140416) (xy 423.435603 -118.1704) (xy 423.380199 -118.193349)
			(xy 423.322274 -118.20887) (xy 423.262818 -118.216698) (xy 423.20285 -118.216698) (xy 423.143394 -118.20887)
			(xy 423.085469 -118.193349) (xy 423.030065 -118.1704) (xy 422.978131 -118.140416) (xy 422.930555 -118.10391)
			(xy 422.88815 -118.061505) (xy 422.851644 -118.013929) (xy 422.82166 -117.961995) (xy 422.798711 -117.906591)
			(xy 422.78319 -117.848666) (xy 422.775362 -117.78921) (xy 422.774872 -117.759226) (xy 307.590436 -117.759226)
			(xy 307.589954 -117.788686) (xy 307.582131 -117.848108) (xy 307.566618 -117.906001) (xy 307.543682 -117.961374)
			(xy 307.513715 -118.01328) (xy 307.477228 -118.06083) (xy 307.434848 -118.10321) (xy 307.387298 -118.139697)
			(xy 307.335392 -118.169664) (xy 307.280019 -118.1926) (xy 307.222126 -118.208113) (xy 307.162704 -118.215936)
			(xy 307.102768 -118.215936) (xy 307.043346 -118.208113) (xy 306.985453 -118.1926) (xy 306.93008 -118.169664)
			(xy 306.878174 -118.139697) (xy 306.830624 -118.10321) (xy 306.788244 -118.06083) (xy 306.751757 -118.01328)
			(xy 306.72179 -117.961374) (xy 306.698854 -117.906001) (xy 306.683341 -117.848108) (xy 306.675518 -117.788686)
			(xy 306.675028 -117.758718) (xy 191.4906 -117.758718) (xy 191.49011 -117.788702) (xy 191.482282 -117.848158)
			(xy 191.466761 -117.906083) (xy 191.443812 -117.961487) (xy 191.413828 -118.013421) (xy 191.377322 -118.060997)
			(xy 191.334917 -118.103402) (xy 191.287341 -118.139908) (xy 191.235407 -118.169892) (xy 191.180003 -118.192841)
			(xy 191.122078 -118.208362) (xy 191.062622 -118.21619) (xy 191.002654 -118.21619) (xy 190.943198 -118.208362)
			(xy 190.885273 -118.192841) (xy 190.829869 -118.169892) (xy 190.777935 -118.139908) (xy 190.730359 -118.103402)
			(xy 190.687954 -118.060997) (xy 190.651448 -118.013421) (xy 190.621464 -117.961487) (xy 190.598515 -117.906083)
			(xy 190.582994 -117.848158) (xy 190.575166 -117.788702) (xy 190.574676 -117.758718) (xy 75.390756 -117.758718)
			(xy 75.390266 -117.788702) (xy 75.382438 -117.848158) (xy 75.366917 -117.906083) (xy 75.343968 -117.961487)
			(xy 75.313984 -118.013421) (xy 75.277478 -118.060997) (xy 75.235073 -118.103402) (xy 75.187497 -118.139908)
			(xy 75.135563 -118.169892) (xy 75.080159 -118.192841) (xy 75.022234 -118.208362) (xy 74.962778 -118.21619)
			(xy 74.90281 -118.21619) (xy 74.843354 -118.208362) (xy 74.785429 -118.192841) (xy 74.730025 -118.169892)
			(xy 74.678091 -118.139908) (xy 74.630515 -118.103402) (xy 74.58811 -118.060997) (xy 74.551604 -118.013421)
			(xy 74.52162 -117.961487) (xy 74.498671 -117.906083) (xy 74.48315 -117.848158) (xy 74.475322 -117.788702)
			(xy 74.474832 -117.758718) (xy 4.308094 -117.758718) (xy 4.308094 -120.087898) (xy 34.667952 -120.087898)
			(xy 34.667952 -119.224298) (xy 34.668442 -119.19433) (xy 34.676265 -119.134908) (xy 34.691778 -119.077015)
			(xy 34.714714 -119.021642) (xy 34.744681 -118.969736) (xy 34.781168 -118.922186) (xy 34.823548 -118.879806)
			(xy 34.871098 -118.843319) (xy 34.923004 -118.813352) (xy 34.978377 -118.790416) (xy 35.03627 -118.774903)
			(xy 35.095692 -118.76708) (xy 35.155628 -118.76708) (xy 35.21505 -118.774903) (xy 35.272943 -118.790416)
			(xy 35.328316 -118.813352) (xy 35.380222 -118.843319) (xy 35.427772 -118.879806) (xy 35.470152 -118.922186)
			(xy 35.506639 -118.969736) (xy 35.536606 -119.021642) (xy 35.559542 -119.077015) (xy 35.575055 -119.134908)
			(xy 35.582878 -119.19433) (xy 35.583368 -119.224298) (xy 35.583368 -120.086374) (xy 53.639212 -120.086374)
			(xy 53.639212 -119.222774) (xy 53.639702 -119.192806) (xy 53.647525 -119.133384) (xy 53.663038 -119.075491)
			(xy 53.685974 -119.020118) (xy 53.715941 -118.968212) (xy 53.752428 -118.920662) (xy 53.794808 -118.878282)
			(xy 53.842358 -118.841795) (xy 53.894264 -118.811828) (xy 53.949637 -118.788892) (xy 54.00753 -118.773379)
			(xy 54.066952 -118.765556) (xy 54.126888 -118.765556) (xy 54.18631 -118.773379) (xy 54.244203 -118.788892)
			(xy 54.299576 -118.811828) (xy 54.351482 -118.841795) (xy 54.399032 -118.878282) (xy 54.441412 -118.920662)
			(xy 54.477899 -118.968212) (xy 54.507866 -119.020118) (xy 54.530802 -119.075491) (xy 54.546315 -119.133384)
			(xy 54.554138 -119.192806) (xy 54.554628 -119.222774) (xy 54.554628 -119.567198) (xy 66.599308 -119.567198)
			(xy 66.599308 -118.703598) (xy 66.599798 -118.673614) (xy 66.607626 -118.614158) (xy 66.623147 -118.556233)
			(xy 66.646096 -118.500829) (xy 66.67608 -118.448895) (xy 66.712586 -118.401319) (xy 66.754991 -118.358914)
			(xy 66.802567 -118.322408) (xy 66.854501 -118.292424) (xy 66.909905 -118.269475) (xy 66.96783 -118.253954)
			(xy 67.027286 -118.246126) (xy 67.087254 -118.246126) (xy 67.14671 -118.253954) (xy 67.204635 -118.269475)
			(xy 67.260039 -118.292424) (xy 67.311973 -118.322408) (xy 67.359549 -118.358914) (xy 67.401954 -118.401319)
			(xy 67.43846 -118.448895) (xy 67.468444 -118.500829) (xy 67.491393 -118.556233) (xy 67.506914 -118.614158)
			(xy 67.514742 -118.673614) (xy 67.515232 -118.703598) (xy 67.515232 -119.55907) (xy 81.07426 -119.55907)
			(xy 81.07426 -118.69547) (xy 81.07475 -118.665486) (xy 81.082578 -118.60603) (xy 81.098099 -118.548105)
			(xy 81.121048 -118.492701) (xy 81.151032 -118.440767) (xy 81.187538 -118.393191) (xy 81.229943 -118.350786)
			(xy 81.277519 -118.31428) (xy 81.329453 -118.284296) (xy 81.384857 -118.261347) (xy 81.442782 -118.245826)
			(xy 81.502238 -118.237998) (xy 81.562206 -118.237998) (xy 81.621662 -118.245826) (xy 81.679587 -118.261347)
			(xy 81.734991 -118.284296) (xy 81.786925 -118.31428) (xy 81.834501 -118.350786) (xy 81.876906 -118.393191)
			(xy 81.913412 -118.440767) (xy 81.943396 -118.492701) (xy 81.966345 -118.548105) (xy 81.981866 -118.60603)
			(xy 81.989694 -118.665486) (xy 81.990184 -118.69547) (xy 81.990184 -119.55907) (xy 81.989694 -119.589054)
			(xy 81.981866 -119.64851) (xy 81.966345 -119.706435) (xy 81.943396 -119.761839) (xy 81.913412 -119.813773)
			(xy 81.876906 -119.861349) (xy 81.834501 -119.903754) (xy 81.786925 -119.94026) (xy 81.734991 -119.970244)
			(xy 81.679587 -119.993193) (xy 81.621662 -120.008714) (xy 81.562206 -120.016542) (xy 81.502238 -120.016542)
			(xy 81.442782 -120.008714) (xy 81.384857 -119.993193) (xy 81.329453 -119.970244) (xy 81.277519 -119.94026)
			(xy 81.229943 -119.903754) (xy 81.187538 -119.861349) (xy 81.151032 -119.813773) (xy 81.121048 -119.761839)
			(xy 81.098099 -119.706435) (xy 81.082578 -119.64851) (xy 81.07475 -119.589054) (xy 81.07426 -119.55907)
			(xy 67.515232 -119.55907) (xy 67.515232 -119.567198) (xy 67.514742 -119.597182) (xy 67.506914 -119.656638)
			(xy 67.491393 -119.714563) (xy 67.468444 -119.769967) (xy 67.43846 -119.821901) (xy 67.401954 -119.869477)
			(xy 67.359549 -119.911882) (xy 67.311973 -119.948388) (xy 67.260039 -119.978372) (xy 67.204635 -120.001321)
			(xy 67.14671 -120.016842) (xy 67.087254 -120.02467) (xy 67.027286 -120.02467) (xy 66.96783 -120.016842)
			(xy 66.909905 -120.001321) (xy 66.854501 -119.978372) (xy 66.802567 -119.948388) (xy 66.754991 -119.911882)
			(xy 66.712586 -119.869477) (xy 66.67608 -119.821901) (xy 66.646096 -119.769967) (xy 66.623147 -119.714563)
			(xy 66.607626 -119.656638) (xy 66.599798 -119.597182) (xy 66.599308 -119.567198) (xy 54.554628 -119.567198)
			(xy 54.554628 -120.086374) (xy 54.554138 -120.116342) (xy 54.546315 -120.175764) (xy 54.530802 -120.233657)
			(xy 54.507866 -120.28903) (xy 54.477899 -120.340936) (xy 54.441412 -120.388486) (xy 54.399032 -120.430866)
			(xy 54.351482 -120.467353) (xy 54.299576 -120.49732) (xy 54.244203 -120.520256) (xy 54.18631 -120.535769)
			(xy 54.126888 -120.543592) (xy 54.066952 -120.543592) (xy 54.00753 -120.535769) (xy 53.949637 -120.520256)
			(xy 53.894264 -120.49732) (xy 53.842358 -120.467353) (xy 53.794808 -120.430866) (xy 53.752428 -120.388486)
			(xy 53.715941 -120.340936) (xy 53.685974 -120.28903) (xy 53.663038 -120.233657) (xy 53.647525 -120.175764)
			(xy 53.639702 -120.116342) (xy 53.639212 -120.086374) (xy 35.583368 -120.086374) (xy 35.583368 -120.087898)
			(xy 35.582878 -120.117866) (xy 35.575055 -120.177288) (xy 35.559542 -120.235181) (xy 35.536606 -120.290554)
			(xy 35.506639 -120.34246) (xy 35.470152 -120.39001) (xy 35.427772 -120.43239) (xy 35.380222 -120.468877)
			(xy 35.328316 -120.498844) (xy 35.272943 -120.52178) (xy 35.21505 -120.537293) (xy 35.155628 -120.545116)
			(xy 35.095692 -120.545116) (xy 35.03627 -120.537293) (xy 34.978377 -120.52178) (xy 34.923004 -120.498844)
			(xy 34.871098 -120.468877) (xy 34.823548 -120.43239) (xy 34.781168 -120.39001) (xy 34.744681 -120.34246)
			(xy 34.714714 -120.290554) (xy 34.691778 -120.235181) (xy 34.676265 -120.177288) (xy 34.668442 -120.117866)
			(xy 34.667952 -120.087898) (xy 4.308094 -120.087898) (xy 4.308094 -121.894346) (xy 37.31006 -121.894346)
			(xy 37.31006 -121.030746) (xy 37.31055 -121.000778) (xy 37.318373 -120.941356) (xy 37.333886 -120.883463)
			(xy 37.356822 -120.82809) (xy 37.386789 -120.776184) (xy 37.423276 -120.728634) (xy 37.465656 -120.686254)
			(xy 37.513206 -120.649767) (xy 37.565112 -120.6198) (xy 37.620485 -120.596864) (xy 37.678378 -120.581351)
			(xy 37.7378 -120.573528) (xy 37.797736 -120.573528) (xy 37.857158 -120.581351) (xy 37.915051 -120.596864)
			(xy 37.970424 -120.6198) (xy 38.02233 -120.649767) (xy 38.06988 -120.686254) (xy 38.11226 -120.728634)
			(xy 38.148747 -120.776184) (xy 38.178714 -120.82809) (xy 38.20165 -120.883463) (xy 38.217163 -120.941356)
			(xy 38.224986 -121.000778) (xy 38.225476 -121.030746) (xy 38.225476 -121.886472) (xy 51.785012 -121.886472)
			(xy 51.785012 -121.022872) (xy 51.785502 -120.992904) (xy 51.793325 -120.933482) (xy 51.808838 -120.875589)
			(xy 51.831774 -120.820216) (xy 51.861741 -120.76831) (xy 51.898228 -120.72076) (xy 51.940608 -120.67838)
			(xy 51.988158 -120.641893) (xy 52.040064 -120.611926) (xy 52.095437 -120.58899) (xy 52.15333 -120.573477)
			(xy 52.212752 -120.565654) (xy 52.272688 -120.565654) (xy 52.33211 -120.573477) (xy 52.390003 -120.58899)
			(xy 52.445376 -120.611926) (xy 52.497282 -120.641893) (xy 52.544832 -120.67838) (xy 52.587212 -120.72076)
			(xy 52.623699 -120.76831) (xy 52.653666 -120.820216) (xy 52.676602 -120.875589) (xy 52.692115 -120.933482)
			(xy 52.699938 -120.992904) (xy 52.700428 -121.022872) (xy 52.700428 -121.367296) (xy 64.745108 -121.367296)
			(xy 64.745108 -120.503696) (xy 64.745598 -120.473712) (xy 64.753426 -120.414256) (xy 64.768947 -120.356331)
			(xy 64.791896 -120.300927) (xy 64.82188 -120.248993) (xy 64.858386 -120.201417) (xy 64.900791 -120.159012)
			(xy 64.948367 -120.122506) (xy 65.000301 -120.092522) (xy 65.055705 -120.069573) (xy 65.11363 -120.054052)
			(xy 65.173086 -120.046224) (xy 65.233054 -120.046224) (xy 65.29251 -120.054052) (xy 65.350435 -120.069573)
			(xy 65.405839 -120.092522) (xy 65.457773 -120.122506) (xy 65.505349 -120.159012) (xy 65.547754 -120.201417)
			(xy 65.58426 -120.248993) (xy 65.614244 -120.300927) (xy 65.637193 -120.356331) (xy 65.652714 -120.414256)
			(xy 65.660542 -120.473712) (xy 65.661032 -120.503696) (xy 65.661032 -121.365772) (xy 83.716368 -121.365772)
			(xy 83.716368 -120.502172) (xy 83.716858 -120.472188) (xy 83.724686 -120.412732) (xy 83.740207 -120.354807)
			(xy 83.763156 -120.299403) (xy 83.79314 -120.247469) (xy 83.829646 -120.199893) (xy 83.872051 -120.157488)
			(xy 83.919627 -120.120982) (xy 83.971561 -120.090998) (xy 84.026965 -120.068049) (xy 84.08489 -120.052528)
			(xy 84.144346 -120.0447) (xy 84.204314 -120.0447) (xy 84.26377 -120.052528) (xy 84.321695 -120.068049)
			(xy 84.369615 -120.087898) (xy 150.767796 -120.087898) (xy 150.767796 -119.224298) (xy 150.768286 -119.194314)
			(xy 150.776114 -119.134858) (xy 150.791635 -119.076933) (xy 150.814584 -119.021529) (xy 150.844568 -118.969595)
			(xy 150.881074 -118.922019) (xy 150.923479 -118.879614) (xy 150.971055 -118.843108) (xy 151.022989 -118.813124)
			(xy 151.078393 -118.790175) (xy 151.136318 -118.774654) (xy 151.195774 -118.766826) (xy 151.255742 -118.766826)
			(xy 151.315198 -118.774654) (xy 151.373123 -118.790175) (xy 151.428527 -118.813124) (xy 151.480461 -118.843108)
			(xy 151.528037 -118.879614) (xy 151.570442 -118.922019) (xy 151.606948 -118.969595) (xy 151.636932 -119.021529)
			(xy 151.659881 -119.076933) (xy 151.675402 -119.134858) (xy 151.68323 -119.194314) (xy 151.68372 -119.224298)
			(xy 151.68372 -120.086374) (xy 169.739056 -120.086374) (xy 169.739056 -119.222774) (xy 169.739546 -119.19279)
			(xy 169.747374 -119.133334) (xy 169.762895 -119.075409) (xy 169.785844 -119.020005) (xy 169.815828 -118.968071)
			(xy 169.852334 -118.920495) (xy 169.894739 -118.87809) (xy 169.942315 -118.841584) (xy 169.994249 -118.8116)
			(xy 170.049653 -118.788651) (xy 170.107578 -118.77313) (xy 170.167034 -118.765302) (xy 170.227002 -118.765302)
			(xy 170.286458 -118.77313) (xy 170.344383 -118.788651) (xy 170.399787 -118.8116) (xy 170.451721 -118.841584)
			(xy 170.499297 -118.87809) (xy 170.541702 -118.920495) (xy 170.578208 -118.968071) (xy 170.608192 -119.020005)
			(xy 170.631141 -119.075409) (xy 170.646662 -119.133334) (xy 170.65449 -119.19279) (xy 170.65498 -119.222774)
			(xy 170.65498 -119.567198) (xy 182.69966 -119.567198) (xy 182.69966 -118.703598) (xy 182.70015 -118.67363)
			(xy 182.707973 -118.614208) (xy 182.723486 -118.556315) (xy 182.746422 -118.500942) (xy 182.776389 -118.449036)
			(xy 182.812876 -118.401486) (xy 182.855256 -118.359106) (xy 182.902806 -118.322619) (xy 182.954712 -118.292652)
			(xy 183.010085 -118.269716) (xy 183.067978 -118.254203) (xy 183.1274 -118.24638) (xy 183.187336 -118.24638)
			(xy 183.246758 -118.254203) (xy 183.304651 -118.269716) (xy 183.360024 -118.292652) (xy 183.41193 -118.322619)
			(xy 183.45948 -118.359106) (xy 183.50186 -118.401486) (xy 183.538347 -118.449036) (xy 183.568314 -118.500942)
			(xy 183.59125 -118.556315) (xy 183.606763 -118.614208) (xy 183.614586 -118.67363) (xy 183.615076 -118.703598)
			(xy 183.615076 -119.559324) (xy 197.174612 -119.559324) (xy 197.174612 -118.695724) (xy 197.175102 -118.665756)
			(xy 197.182925 -118.606334) (xy 197.198438 -118.548441) (xy 197.221374 -118.493068) (xy 197.251341 -118.441162)
			(xy 197.287828 -118.393612) (xy 197.330208 -118.351232) (xy 197.377758 -118.314745) (xy 197.429664 -118.284778)
			(xy 197.485037 -118.261842) (xy 197.54293 -118.246329) (xy 197.602352 -118.238506) (xy 197.662288 -118.238506)
			(xy 197.72171 -118.246329) (xy 197.779603 -118.261842) (xy 197.834976 -118.284778) (xy 197.886882 -118.314745)
			(xy 197.934432 -118.351232) (xy 197.976812 -118.393612) (xy 198.013299 -118.441162) (xy 198.043266 -118.493068)
			(xy 198.066202 -118.548441) (xy 198.081715 -118.606334) (xy 198.089538 -118.665756) (xy 198.090028 -118.695724)
			(xy 198.090028 -119.559324) (xy 198.089538 -119.589292) (xy 198.081715 -119.648714) (xy 198.066202 -119.706607)
			(xy 198.043266 -119.76198) (xy 198.013299 -119.813886) (xy 197.976812 -119.861436) (xy 197.934432 -119.903816)
			(xy 197.886882 -119.940303) (xy 197.834976 -119.97027) (xy 197.779603 -119.993206) (xy 197.72171 -120.008719)
			(xy 197.662288 -120.016542) (xy 197.602352 -120.016542) (xy 197.54293 -120.008719) (xy 197.485037 -119.993206)
			(xy 197.429664 -119.97027) (xy 197.377758 -119.940303) (xy 197.330208 -119.903816) (xy 197.287828 -119.861436)
			(xy 197.251341 -119.813886) (xy 197.221374 -119.76198) (xy 197.198438 -119.706607) (xy 197.182925 -119.648714)
			(xy 197.175102 -119.589292) (xy 197.174612 -119.559324) (xy 183.615076 -119.559324) (xy 183.615076 -119.567198)
			(xy 183.614586 -119.597166) (xy 183.606763 -119.656588) (xy 183.59125 -119.714481) (xy 183.568314 -119.769854)
			(xy 183.538347 -119.82176) (xy 183.50186 -119.86931) (xy 183.45948 -119.91169) (xy 183.41193 -119.948177)
			(xy 183.360024 -119.978144) (xy 183.304651 -120.00108) (xy 183.246758 -120.016593) (xy 183.187336 -120.024416)
			(xy 183.1274 -120.024416) (xy 183.067978 -120.016593) (xy 183.010085 -120.00108) (xy 182.954712 -119.978144)
			(xy 182.902806 -119.948177) (xy 182.855256 -119.91169) (xy 182.812876 -119.86931) (xy 182.776389 -119.82176)
			(xy 182.746422 -119.769854) (xy 182.723486 -119.714481) (xy 182.707973 -119.656588) (xy 182.70015 -119.597166)
			(xy 182.69966 -119.567198) (xy 170.65498 -119.567198) (xy 170.65498 -120.086374) (xy 170.65449 -120.116358)
			(xy 170.646662 -120.175814) (xy 170.631141 -120.233739) (xy 170.608192 -120.289143) (xy 170.578208 -120.341077)
			(xy 170.541702 -120.388653) (xy 170.499297 -120.431058) (xy 170.451721 -120.467564) (xy 170.399787 -120.497548)
			(xy 170.344383 -120.520497) (xy 170.286458 -120.536018) (xy 170.227002 -120.543846) (xy 170.167034 -120.543846)
			(xy 170.107578 -120.536018) (xy 170.049653 -120.520497) (xy 169.994249 -120.497548) (xy 169.942315 -120.467564)
			(xy 169.894739 -120.431058) (xy 169.852334 -120.388653) (xy 169.815828 -120.341077) (xy 169.785844 -120.289143)
			(xy 169.762895 -120.233739) (xy 169.747374 -120.175814) (xy 169.739546 -120.116358) (xy 169.739056 -120.086374)
			(xy 151.68372 -120.086374) (xy 151.68372 -120.087898) (xy 151.68323 -120.117882) (xy 151.675402 -120.177338)
			(xy 151.659881 -120.235263) (xy 151.636932 -120.290667) (xy 151.606948 -120.342601) (xy 151.570442 -120.390177)
			(xy 151.528037 -120.432582) (xy 151.480461 -120.469088) (xy 151.428527 -120.499072) (xy 151.373123 -120.522021)
			(xy 151.315198 -120.537542) (xy 151.255742 -120.54537) (xy 151.195774 -120.54537) (xy 151.136318 -120.537542)
			(xy 151.078393 -120.522021) (xy 151.022989 -120.499072) (xy 150.971055 -120.469088) (xy 150.923479 -120.432582)
			(xy 150.881074 -120.390177) (xy 150.844568 -120.342601) (xy 150.814584 -120.290667) (xy 150.791635 -120.235263)
			(xy 150.776114 -120.177338) (xy 150.768286 -120.117882) (xy 150.767796 -120.087898) (xy 84.369615 -120.087898)
			(xy 84.377099 -120.090998) (xy 84.429033 -120.120982) (xy 84.476609 -120.157488) (xy 84.519014 -120.199893)
			(xy 84.55552 -120.247469) (xy 84.585504 -120.299403) (xy 84.608453 -120.354807) (xy 84.623974 -120.412732)
			(xy 84.631802 -120.472188) (xy 84.632292 -120.502172) (xy 84.632292 -121.365772) (xy 84.631802 -121.395756)
			(xy 84.623974 -121.455212) (xy 84.608453 -121.513137) (xy 84.585504 -121.568541) (xy 84.55552 -121.620475)
			(xy 84.519014 -121.668051) (xy 84.476609 -121.710456) (xy 84.429033 -121.746962) (xy 84.377099 -121.776946)
			(xy 84.321695 -121.799895) (xy 84.26377 -121.815416) (xy 84.204314 -121.823244) (xy 84.144346 -121.823244)
			(xy 84.08489 -121.815416) (xy 84.026965 -121.799895) (xy 83.971561 -121.776946) (xy 83.919627 -121.746962)
			(xy 83.872051 -121.710456) (xy 83.829646 -121.668051) (xy 83.79314 -121.620475) (xy 83.763156 -121.568541)
			(xy 83.740207 -121.513137) (xy 83.724686 -121.455212) (xy 83.716858 -121.395756) (xy 83.716368 -121.365772)
			(xy 65.661032 -121.365772) (xy 65.661032 -121.367296) (xy 65.660542 -121.39728) (xy 65.652714 -121.456736)
			(xy 65.637193 -121.514661) (xy 65.614244 -121.570065) (xy 65.58426 -121.621999) (xy 65.547754 -121.669575)
			(xy 65.505349 -121.71198) (xy 65.457773 -121.748486) (xy 65.405839 -121.77847) (xy 65.350435 -121.801419)
			(xy 65.29251 -121.81694) (xy 65.233054 -121.824768) (xy 65.173086 -121.824768) (xy 65.11363 -121.81694)
			(xy 65.055705 -121.801419) (xy 65.000301 -121.77847) (xy 64.948367 -121.748486) (xy 64.900791 -121.71198)
			(xy 64.858386 -121.669575) (xy 64.82188 -121.621999) (xy 64.791896 -121.570065) (xy 64.768947 -121.514661)
			(xy 64.753426 -121.456736) (xy 64.745598 -121.39728) (xy 64.745108 -121.367296) (xy 52.700428 -121.367296)
			(xy 52.700428 -121.886472) (xy 52.699938 -121.91644) (xy 52.692115 -121.975862) (xy 52.676602 -122.033755)
			(xy 52.653666 -122.089128) (xy 52.623699 -122.141034) (xy 52.587212 -122.188584) (xy 52.544832 -122.230964)
			(xy 52.497282 -122.267451) (xy 52.445376 -122.297418) (xy 52.390003 -122.320354) (xy 52.33211 -122.335867)
			(xy 52.272688 -122.34369) (xy 52.212752 -122.34369) (xy 52.15333 -122.335867) (xy 52.095437 -122.320354)
			(xy 52.040064 -122.297418) (xy 51.988158 -122.267451) (xy 51.940608 -122.230964) (xy 51.898228 -122.188584)
			(xy 51.861741 -122.141034) (xy 51.831774 -122.089128) (xy 51.808838 -122.033755) (xy 51.793325 -121.975862)
			(xy 51.785502 -121.91644) (xy 51.785012 -121.886472) (xy 38.225476 -121.886472) (xy 38.225476 -121.894346)
			(xy 38.224986 -121.924314) (xy 38.217163 -121.983736) (xy 38.20165 -122.041629) (xy 38.178714 -122.097002)
			(xy 38.148747 -122.148908) (xy 38.11226 -122.196458) (xy 38.06988 -122.238838) (xy 38.02233 -122.275325)
			(xy 37.970424 -122.305292) (xy 37.915051 -122.328228) (xy 37.857158 -122.343741) (xy 37.797736 -122.351564)
			(xy 37.7378 -122.351564) (xy 37.678378 -122.343741) (xy 37.620485 -122.328228) (xy 37.565112 -122.305292)
			(xy 37.513206 -122.275325) (xy 37.465656 -122.238838) (xy 37.423276 -122.196458) (xy 37.386789 -122.148908)
			(xy 37.356822 -122.097002) (xy 37.333886 -122.041629) (xy 37.318373 -121.983736) (xy 37.31055 -121.924314)
			(xy 37.31006 -121.894346) (xy 4.308094 -121.894346) (xy 4.308094 -123.68784) (xy 34.667952 -123.68784)
			(xy 34.667952 -122.82424) (xy 34.668442 -122.794272) (xy 34.676265 -122.73485) (xy 34.691778 -122.676957)
			(xy 34.714714 -122.621584) (xy 34.744681 -122.569678) (xy 34.781168 -122.522128) (xy 34.823548 -122.479748)
			(xy 34.871098 -122.443261) (xy 34.923004 -122.413294) (xy 34.978377 -122.390358) (xy 35.03627 -122.374845)
			(xy 35.095692 -122.367022) (xy 35.155628 -122.367022) (xy 35.21505 -122.374845) (xy 35.272943 -122.390358)
			(xy 35.328316 -122.413294) (xy 35.380222 -122.443261) (xy 35.427772 -122.479748) (xy 35.470152 -122.522128)
			(xy 35.506639 -122.569678) (xy 35.536606 -122.621584) (xy 35.559542 -122.676957) (xy 35.575055 -122.73485)
			(xy 35.582878 -122.794272) (xy 35.583368 -122.82424) (xy 35.583368 -123.686316) (xy 53.639212 -123.686316)
			(xy 53.639212 -122.822716) (xy 53.639702 -122.792748) (xy 53.647525 -122.733326) (xy 53.663038 -122.675433)
			(xy 53.685974 -122.62006) (xy 53.715941 -122.568154) (xy 53.752428 -122.520604) (xy 53.794808 -122.478224)
			(xy 53.842358 -122.441737) (xy 53.894264 -122.41177) (xy 53.949637 -122.388834) (xy 54.00753 -122.373321)
			(xy 54.066952 -122.365498) (xy 54.126888 -122.365498) (xy 54.18631 -122.373321) (xy 54.244203 -122.388834)
			(xy 54.299576 -122.41177) (xy 54.351482 -122.441737) (xy 54.399032 -122.478224) (xy 54.441412 -122.520604)
			(xy 54.477899 -122.568154) (xy 54.507866 -122.62006) (xy 54.530802 -122.675433) (xy 54.546315 -122.733326)
			(xy 54.554138 -122.792748) (xy 54.554628 -122.822716) (xy 54.554628 -123.16714) (xy 66.599308 -123.16714)
			(xy 66.599308 -122.30354) (xy 66.599798 -122.273556) (xy 66.607626 -122.2141) (xy 66.623147 -122.156175)
			(xy 66.646096 -122.100771) (xy 66.67608 -122.048837) (xy 66.712586 -122.001261) (xy 66.754991 -121.958856)
			(xy 66.802567 -121.92235) (xy 66.854501 -121.892366) (xy 66.909905 -121.869417) (xy 66.96783 -121.853896)
			(xy 67.027286 -121.846068) (xy 67.087254 -121.846068) (xy 67.14671 -121.853896) (xy 67.204635 -121.869417)
			(xy 67.260039 -121.892366) (xy 67.311973 -121.92235) (xy 67.359549 -121.958856) (xy 67.401954 -122.001261)
			(xy 67.43846 -122.048837) (xy 67.468444 -122.100771) (xy 67.491393 -122.156175) (xy 67.506914 -122.2141)
			(xy 67.514742 -122.273556) (xy 67.515232 -122.30354) (xy 67.515232 -123.159266) (xy 81.07426 -123.159266)
			(xy 81.07426 -122.295666) (xy 81.07475 -122.265682) (xy 81.082578 -122.206226) (xy 81.098099 -122.148301)
			(xy 81.121048 -122.092897) (xy 81.151032 -122.040963) (xy 81.187538 -121.993387) (xy 81.229943 -121.950982)
			(xy 81.277519 -121.914476) (xy 81.329453 -121.884492) (xy 81.384857 -121.861543) (xy 81.442782 -121.846022)
			(xy 81.502238 -121.838194) (xy 81.562206 -121.838194) (xy 81.621662 -121.846022) (xy 81.679587 -121.861543)
			(xy 81.734991 -121.884492) (xy 81.752059 -121.894346) (xy 153.409904 -121.894346) (xy 153.409904 -121.030746)
			(xy 153.410394 -121.000762) (xy 153.418222 -120.941306) (xy 153.433743 -120.883381) (xy 153.456692 -120.827977)
			(xy 153.486676 -120.776043) (xy 153.523182 -120.728467) (xy 153.565587 -120.686062) (xy 153.613163 -120.649556)
			(xy 153.665097 -120.619572) (xy 153.720501 -120.596623) (xy 153.778426 -120.581102) (xy 153.837882 -120.573274)
			(xy 153.89785 -120.573274) (xy 153.957306 -120.581102) (xy 154.015231 -120.596623) (xy 154.070635 -120.619572)
			(xy 154.122569 -120.649556) (xy 154.170145 -120.686062) (xy 154.21255 -120.728467) (xy 154.249056 -120.776043)
			(xy 154.27904 -120.827977) (xy 154.301989 -120.883381) (xy 154.31751 -120.941306) (xy 154.325338 -121.000762)
			(xy 154.325828 -121.030746) (xy 154.325828 -121.886472) (xy 167.884856 -121.886472) (xy 167.884856 -121.022872)
			(xy 167.885346 -120.992888) (xy 167.893174 -120.933432) (xy 167.908695 -120.875507) (xy 167.931644 -120.820103)
			(xy 167.961628 -120.768169) (xy 167.998134 -120.720593) (xy 168.040539 -120.678188) (xy 168.088115 -120.641682)
			(xy 168.140049 -120.611698) (xy 168.195453 -120.588749) (xy 168.253378 -120.573228) (xy 168.312834 -120.5654)
			(xy 168.372802 -120.5654) (xy 168.432258 -120.573228) (xy 168.490183 -120.588749) (xy 168.545587 -120.611698)
			(xy 168.597521 -120.641682) (xy 168.645097 -120.678188) (xy 168.687502 -120.720593) (xy 168.724008 -120.768169)
			(xy 168.753992 -120.820103) (xy 168.776941 -120.875507) (xy 168.792462 -120.933432) (xy 168.80029 -120.992888)
			(xy 168.80078 -121.022872) (xy 168.80078 -121.367296) (xy 180.84546 -121.367296) (xy 180.84546 -120.503696)
			(xy 180.84595 -120.473728) (xy 180.853773 -120.414306) (xy 180.869286 -120.356413) (xy 180.892222 -120.30104)
			(xy 180.922189 -120.249134) (xy 180.958676 -120.201584) (xy 181.001056 -120.159204) (xy 181.048606 -120.122717)
			(xy 181.100512 -120.09275) (xy 181.155885 -120.069814) (xy 181.213778 -120.054301) (xy 181.2732 -120.046478)
			(xy 181.333136 -120.046478) (xy 181.392558 -120.054301) (xy 181.450451 -120.069814) (xy 181.505824 -120.09275)
			(xy 181.55773 -120.122717) (xy 181.60528 -120.159204) (xy 181.64766 -120.201584) (xy 181.684147 -120.249134)
			(xy 181.714114 -120.30104) (xy 181.73705 -120.356413) (xy 181.752563 -120.414306) (xy 181.760386 -120.473728)
			(xy 181.760876 -120.503696) (xy 181.760876 -121.365772) (xy 199.81672 -121.365772) (xy 199.81672 -120.502172)
			(xy 199.81721 -120.472204) (xy 199.825033 -120.412782) (xy 199.840546 -120.354889) (xy 199.863482 -120.299516)
			(xy 199.893449 -120.24761) (xy 199.929936 -120.20006) (xy 199.972316 -120.15768) (xy 200.019866 -120.121193)
			(xy 200.071772 -120.091226) (xy 200.127145 -120.06829) (xy 200.185038 -120.052777) (xy 200.24446 -120.044954)
			(xy 200.304396 -120.044954) (xy 200.363818 -120.052777) (xy 200.421711 -120.06829) (xy 200.469049 -120.087898)
			(xy 266.86764 -120.087898) (xy 266.86764 -119.224298) (xy 266.86813 -119.194314) (xy 266.875958 -119.134858)
			(xy 266.891479 -119.076933) (xy 266.914428 -119.021529) (xy 266.944412 -118.969595) (xy 266.980918 -118.922019)
			(xy 267.023323 -118.879614) (xy 267.070899 -118.843108) (xy 267.122833 -118.813124) (xy 267.178237 -118.790175)
			(xy 267.236162 -118.774654) (xy 267.295618 -118.766826) (xy 267.355586 -118.766826) (xy 267.415042 -118.774654)
			(xy 267.472967 -118.790175) (xy 267.528371 -118.813124) (xy 267.580305 -118.843108) (xy 267.627881 -118.879614)
			(xy 267.670286 -118.922019) (xy 267.706792 -118.969595) (xy 267.736776 -119.021529) (xy 267.759725 -119.076933)
			(xy 267.775246 -119.134858) (xy 267.783074 -119.194314) (xy 267.783564 -119.224298) (xy 267.783564 -120.086374)
			(xy 285.8389 -120.086374) (xy 285.8389 -119.222774) (xy 285.83939 -119.19279) (xy 285.847218 -119.133334)
			(xy 285.862739 -119.075409) (xy 285.885688 -119.020005) (xy 285.915672 -118.968071) (xy 285.952178 -118.920495)
			(xy 285.994583 -118.87809) (xy 286.042159 -118.841584) (xy 286.094093 -118.8116) (xy 286.149497 -118.788651)
			(xy 286.207422 -118.77313) (xy 286.266878 -118.765302) (xy 286.326846 -118.765302) (xy 286.386302 -118.77313)
			(xy 286.444227 -118.788651) (xy 286.499631 -118.8116) (xy 286.551565 -118.841584) (xy 286.599141 -118.87809)
			(xy 286.641546 -118.920495) (xy 286.678052 -118.968071) (xy 286.708036 -119.020005) (xy 286.730985 -119.075409)
			(xy 286.746506 -119.133334) (xy 286.754334 -119.19279) (xy 286.754824 -119.222774) (xy 286.754824 -119.567198)
			(xy 298.799504 -119.567198) (xy 298.799504 -118.703598) (xy 298.799994 -118.67363) (xy 298.807817 -118.614208)
			(xy 298.82333 -118.556315) (xy 298.846266 -118.500942) (xy 298.876233 -118.449036) (xy 298.91272 -118.401486)
			(xy 298.9551 -118.359106) (xy 299.00265 -118.322619) (xy 299.054556 -118.292652) (xy 299.109929 -118.269716)
			(xy 299.167822 -118.254203) (xy 299.227244 -118.24638) (xy 299.28718 -118.24638) (xy 299.346602 -118.254203)
			(xy 299.404495 -118.269716) (xy 299.459868 -118.292652) (xy 299.511774 -118.322619) (xy 299.559324 -118.359106)
			(xy 299.601704 -118.401486) (xy 299.638191 -118.449036) (xy 299.668158 -118.500942) (xy 299.691094 -118.556315)
			(xy 299.706607 -118.614208) (xy 299.71443 -118.67363) (xy 299.71492 -118.703598) (xy 299.71492 -119.559324)
			(xy 313.274456 -119.559324) (xy 313.274456 -118.695724) (xy 313.274946 -118.665756) (xy 313.282769 -118.606334)
			(xy 313.298282 -118.548441) (xy 313.321218 -118.493068) (xy 313.351185 -118.441162) (xy 313.387672 -118.393612)
			(xy 313.430052 -118.351232) (xy 313.477602 -118.314745) (xy 313.529508 -118.284778) (xy 313.584881 -118.261842)
			(xy 313.642774 -118.246329) (xy 313.702196 -118.238506) (xy 313.762132 -118.238506) (xy 313.821554 -118.246329)
			(xy 313.879447 -118.261842) (xy 313.93482 -118.284778) (xy 313.986726 -118.314745) (xy 314.034276 -118.351232)
			(xy 314.076656 -118.393612) (xy 314.113143 -118.441162) (xy 314.14311 -118.493068) (xy 314.166046 -118.548441)
			(xy 314.181559 -118.606334) (xy 314.189382 -118.665756) (xy 314.189872 -118.695724) (xy 314.189872 -119.559324)
			(xy 314.189382 -119.589292) (xy 314.181559 -119.648714) (xy 314.166046 -119.706607) (xy 314.14311 -119.76198)
			(xy 314.113143 -119.813886) (xy 314.076656 -119.861436) (xy 314.034276 -119.903816) (xy 313.986726 -119.940303)
			(xy 313.93482 -119.97027) (xy 313.879447 -119.993206) (xy 313.821554 -120.008719) (xy 313.762132 -120.016542)
			(xy 313.702196 -120.016542) (xy 313.642774 -120.008719) (xy 313.584881 -119.993206) (xy 313.529508 -119.97027)
			(xy 313.477602 -119.940303) (xy 313.430052 -119.903816) (xy 313.387672 -119.861436) (xy 313.351185 -119.813886)
			(xy 313.321218 -119.76198) (xy 313.298282 -119.706607) (xy 313.282769 -119.648714) (xy 313.274946 -119.589292)
			(xy 313.274456 -119.559324) (xy 299.71492 -119.559324) (xy 299.71492 -119.567198) (xy 299.71443 -119.597166)
			(xy 299.706607 -119.656588) (xy 299.691094 -119.714481) (xy 299.668158 -119.769854) (xy 299.638191 -119.82176)
			(xy 299.601704 -119.86931) (xy 299.559324 -119.91169) (xy 299.511774 -119.948177) (xy 299.459868 -119.978144)
			(xy 299.404495 -120.00108) (xy 299.346602 -120.016593) (xy 299.28718 -120.024416) (xy 299.227244 -120.024416)
			(xy 299.167822 -120.016593) (xy 299.109929 -120.00108) (xy 299.054556 -119.978144) (xy 299.00265 -119.948177)
			(xy 298.9551 -119.91169) (xy 298.91272 -119.86931) (xy 298.876233 -119.82176) (xy 298.846266 -119.769854)
			(xy 298.82333 -119.714481) (xy 298.807817 -119.656588) (xy 298.799994 -119.597166) (xy 298.799504 -119.567198)
			(xy 286.754824 -119.567198) (xy 286.754824 -120.086374) (xy 286.754334 -120.116358) (xy 286.746506 -120.175814)
			(xy 286.730985 -120.233739) (xy 286.708036 -120.289143) (xy 286.678052 -120.341077) (xy 286.641546 -120.388653)
			(xy 286.599141 -120.431058) (xy 286.551565 -120.467564) (xy 286.499631 -120.497548) (xy 286.444227 -120.520497)
			(xy 286.386302 -120.536018) (xy 286.326846 -120.543846) (xy 286.266878 -120.543846) (xy 286.207422 -120.536018)
			(xy 286.149497 -120.520497) (xy 286.094093 -120.497548) (xy 286.042159 -120.467564) (xy 285.994583 -120.431058)
			(xy 285.952178 -120.388653) (xy 285.915672 -120.341077) (xy 285.885688 -120.289143) (xy 285.862739 -120.233739)
			(xy 285.847218 -120.175814) (xy 285.83939 -120.116358) (xy 285.8389 -120.086374) (xy 267.783564 -120.086374)
			(xy 267.783564 -120.087898) (xy 267.783074 -120.117882) (xy 267.775246 -120.177338) (xy 267.759725 -120.235263)
			(xy 267.736776 -120.290667) (xy 267.706792 -120.342601) (xy 267.670286 -120.390177) (xy 267.627881 -120.432582)
			(xy 267.580305 -120.469088) (xy 267.528371 -120.499072) (xy 267.472967 -120.522021) (xy 267.415042 -120.537542)
			(xy 267.355586 -120.54537) (xy 267.295618 -120.54537) (xy 267.236162 -120.537542) (xy 267.178237 -120.522021)
			(xy 267.122833 -120.499072) (xy 267.070899 -120.469088) (xy 267.023323 -120.432582) (xy 266.980918 -120.390177)
			(xy 266.944412 -120.342601) (xy 266.914428 -120.290667) (xy 266.891479 -120.235263) (xy 266.875958 -120.177338)
			(xy 266.86813 -120.117882) (xy 266.86764 -120.087898) (xy 200.469049 -120.087898) (xy 200.477084 -120.091226)
			(xy 200.52899 -120.121193) (xy 200.57654 -120.15768) (xy 200.61892 -120.20006) (xy 200.655407 -120.24761)
			(xy 200.685374 -120.299516) (xy 200.70831 -120.354889) (xy 200.723823 -120.412782) (xy 200.731646 -120.472204)
			(xy 200.732136 -120.502172) (xy 200.732136 -121.365772) (xy 200.731646 -121.39574) (xy 200.723823 -121.455162)
			(xy 200.70831 -121.513055) (xy 200.685374 -121.568428) (xy 200.655407 -121.620334) (xy 200.61892 -121.667884)
			(xy 200.57654 -121.710264) (xy 200.52899 -121.746751) (xy 200.477084 -121.776718) (xy 200.421711 -121.799654)
			(xy 200.363818 -121.815167) (xy 200.304396 -121.82299) (xy 200.24446 -121.82299) (xy 200.185038 -121.815167)
			(xy 200.127145 -121.799654) (xy 200.071772 -121.776718) (xy 200.019866 -121.746751) (xy 199.972316 -121.710264)
			(xy 199.929936 -121.667884) (xy 199.893449 -121.620334) (xy 199.863482 -121.568428) (xy 199.840546 -121.513055)
			(xy 199.825033 -121.455162) (xy 199.81721 -121.39574) (xy 199.81672 -121.365772) (xy 181.760876 -121.365772)
			(xy 181.760876 -121.367296) (xy 181.760386 -121.397264) (xy 181.752563 -121.456686) (xy 181.73705 -121.514579)
			(xy 181.714114 -121.569952) (xy 181.684147 -121.621858) (xy 181.64766 -121.669408) (xy 181.60528 -121.711788)
			(xy 181.55773 -121.748275) (xy 181.505824 -121.778242) (xy 181.450451 -121.801178) (xy 181.392558 -121.816691)
			(xy 181.333136 -121.824514) (xy 181.2732 -121.824514) (xy 181.213778 -121.816691) (xy 181.155885 -121.801178)
			(xy 181.100512 -121.778242) (xy 181.048606 -121.748275) (xy 181.001056 -121.711788) (xy 180.958676 -121.669408)
			(xy 180.922189 -121.621858) (xy 180.892222 -121.569952) (xy 180.869286 -121.514579) (xy 180.853773 -121.456686)
			(xy 180.84595 -121.397264) (xy 180.84546 -121.367296) (xy 168.80078 -121.367296) (xy 168.80078 -121.886472)
			(xy 168.80029 -121.916456) (xy 168.792462 -121.975912) (xy 168.776941 -122.033837) (xy 168.753992 -122.089241)
			(xy 168.724008 -122.141175) (xy 168.687502 -122.188751) (xy 168.645097 -122.231156) (xy 168.597521 -122.267662)
			(xy 168.545587 -122.297646) (xy 168.490183 -122.320595) (xy 168.432258 -122.336116) (xy 168.372802 -122.343944)
			(xy 168.312834 -122.343944) (xy 168.253378 -122.336116) (xy 168.195453 -122.320595) (xy 168.140049 -122.297646)
			(xy 168.088115 -122.267662) (xy 168.040539 -122.231156) (xy 167.998134 -122.188751) (xy 167.961628 -122.141175)
			(xy 167.931644 -122.089241) (xy 167.908695 -122.033837) (xy 167.893174 -121.975912) (xy 167.885346 -121.916456)
			(xy 167.884856 -121.886472) (xy 154.325828 -121.886472) (xy 154.325828 -121.894346) (xy 154.325338 -121.92433)
			(xy 154.31751 -121.983786) (xy 154.301989 -122.041711) (xy 154.27904 -122.097115) (xy 154.249056 -122.149049)
			(xy 154.21255 -122.196625) (xy 154.170145 -122.23903) (xy 154.122569 -122.275536) (xy 154.070635 -122.30552)
			(xy 154.015231 -122.328469) (xy 153.957306 -122.34399) (xy 153.89785 -122.351818) (xy 153.837882 -122.351818)
			(xy 153.778426 -122.34399) (xy 153.720501 -122.328469) (xy 153.665097 -122.30552) (xy 153.613163 -122.275536)
			(xy 153.565587 -122.23903) (xy 153.523182 -122.196625) (xy 153.486676 -122.149049) (xy 153.456692 -122.097115)
			(xy 153.433743 -122.041711) (xy 153.418222 -121.983786) (xy 153.410394 -121.92433) (xy 153.409904 -121.894346)
			(xy 81.752059 -121.894346) (xy 81.786925 -121.914476) (xy 81.834501 -121.950982) (xy 81.876906 -121.993387)
			(xy 81.913412 -122.040963) (xy 81.943396 -122.092897) (xy 81.966345 -122.148301) (xy 81.981866 -122.206226)
			(xy 81.989694 -122.265682) (xy 81.990184 -122.295666) (xy 81.990184 -123.159266) (xy 81.989694 -123.18925)
			(xy 81.981866 -123.248706) (xy 81.966345 -123.306631) (xy 81.943396 -123.362035) (xy 81.913412 -123.413969)
			(xy 81.876906 -123.461545) (xy 81.834501 -123.50395) (xy 81.786925 -123.540456) (xy 81.734991 -123.57044)
			(xy 81.679587 -123.593389) (xy 81.621662 -123.60891) (xy 81.562206 -123.616738) (xy 81.502238 -123.616738)
			(xy 81.442782 -123.60891) (xy 81.384857 -123.593389) (xy 81.329453 -123.57044) (xy 81.277519 -123.540456)
			(xy 81.229943 -123.50395) (xy 81.187538 -123.461545) (xy 81.151032 -123.413969) (xy 81.121048 -123.362035)
			(xy 81.098099 -123.306631) (xy 81.082578 -123.248706) (xy 81.07475 -123.18925) (xy 81.07426 -123.159266)
			(xy 67.515232 -123.159266) (xy 67.515232 -123.16714) (xy 67.514742 -123.197124) (xy 67.506914 -123.25658)
			(xy 67.491393 -123.314505) (xy 67.468444 -123.369909) (xy 67.43846 -123.421843) (xy 67.401954 -123.469419)
			(xy 67.359549 -123.511824) (xy 67.311973 -123.54833) (xy 67.260039 -123.578314) (xy 67.204635 -123.601263)
			(xy 67.14671 -123.616784) (xy 67.087254 -123.624612) (xy 67.027286 -123.624612) (xy 66.96783 -123.616784)
			(xy 66.909905 -123.601263) (xy 66.854501 -123.578314) (xy 66.802567 -123.54833) (xy 66.754991 -123.511824)
			(xy 66.712586 -123.469419) (xy 66.67608 -123.421843) (xy 66.646096 -123.369909) (xy 66.623147 -123.314505)
			(xy 66.607626 -123.25658) (xy 66.599798 -123.197124) (xy 66.599308 -123.16714) (xy 54.554628 -123.16714)
			(xy 54.554628 -123.686316) (xy 54.554138 -123.716284) (xy 54.546315 -123.775706) (xy 54.530802 -123.833599)
			(xy 54.507866 -123.888972) (xy 54.477899 -123.940878) (xy 54.441412 -123.988428) (xy 54.399032 -124.030808)
			(xy 54.351482 -124.067295) (xy 54.299576 -124.097262) (xy 54.244203 -124.120198) (xy 54.18631 -124.135711)
			(xy 54.126888 -124.143534) (xy 54.066952 -124.143534) (xy 54.00753 -124.135711) (xy 53.949637 -124.120198)
			(xy 53.894264 -124.097262) (xy 53.842358 -124.067295) (xy 53.794808 -124.030808) (xy 53.752428 -123.988428)
			(xy 53.715941 -123.940878) (xy 53.685974 -123.888972) (xy 53.663038 -123.833599) (xy 53.647525 -123.775706)
			(xy 53.639702 -123.716284) (xy 53.639212 -123.686316) (xy 35.583368 -123.686316) (xy 35.583368 -123.68784)
			(xy 35.582878 -123.717808) (xy 35.575055 -123.77723) (xy 35.559542 -123.835123) (xy 35.536606 -123.890496)
			(xy 35.506639 -123.942402) (xy 35.470152 -123.989952) (xy 35.427772 -124.032332) (xy 35.380222 -124.068819)
			(xy 35.328316 -124.098786) (xy 35.272943 -124.121722) (xy 35.21505 -124.137235) (xy 35.155628 -124.145058)
			(xy 35.095692 -124.145058) (xy 35.03627 -124.137235) (xy 34.978377 -124.121722) (xy 34.923004 -124.098786)
			(xy 34.871098 -124.068819) (xy 34.823548 -124.032332) (xy 34.781168 -123.989952) (xy 34.744681 -123.942402)
			(xy 34.714714 -123.890496) (xy 34.691778 -123.835123) (xy 34.676265 -123.77723) (xy 34.668442 -123.717808)
			(xy 34.667952 -123.68784) (xy 4.308094 -123.68784) (xy 4.308094 -125.494542) (xy 37.31006 -125.494542)
			(xy 37.31006 -124.630942) (xy 37.31055 -124.600974) (xy 37.318373 -124.541552) (xy 37.333886 -124.483659)
			(xy 37.356822 -124.428286) (xy 37.386789 -124.37638) (xy 37.423276 -124.32883) (xy 37.465656 -124.28645)
			(xy 37.513206 -124.249963) (xy 37.565112 -124.219996) (xy 37.620485 -124.19706) (xy 37.678378 -124.181547)
			(xy 37.7378 -124.173724) (xy 37.797736 -124.173724) (xy 37.857158 -124.181547) (xy 37.915051 -124.19706)
			(xy 37.970424 -124.219996) (xy 38.02233 -124.249963) (xy 38.06988 -124.28645) (xy 38.11226 -124.32883)
			(xy 38.148747 -124.37638) (xy 38.178714 -124.428286) (xy 38.20165 -124.483659) (xy 38.217163 -124.541552)
			(xy 38.224986 -124.600974) (xy 38.225476 -124.630942) (xy 38.225476 -125.486414) (xy 51.785012 -125.486414)
			(xy 51.785012 -124.622814) (xy 51.785502 -124.592846) (xy 51.793325 -124.533424) (xy 51.808838 -124.475531)
			(xy 51.831774 -124.420158) (xy 51.861741 -124.368252) (xy 51.898228 -124.320702) (xy 51.940608 -124.278322)
			(xy 51.988158 -124.241835) (xy 52.040064 -124.211868) (xy 52.095437 -124.188932) (xy 52.15333 -124.173419)
			(xy 52.212752 -124.165596) (xy 52.272688 -124.165596) (xy 52.33211 -124.173419) (xy 52.390003 -124.188932)
			(xy 52.445376 -124.211868) (xy 52.497282 -124.241835) (xy 52.544832 -124.278322) (xy 52.587212 -124.320702)
			(xy 52.623699 -124.368252) (xy 52.653666 -124.420158) (xy 52.676602 -124.475531) (xy 52.692115 -124.533424)
			(xy 52.699938 -124.592846) (xy 52.700428 -124.622814) (xy 52.700428 -124.967238) (xy 64.745108 -124.967238)
			(xy 64.745108 -124.103638) (xy 64.745598 -124.073654) (xy 64.753426 -124.014198) (xy 64.768947 -123.956273)
			(xy 64.791896 -123.900869) (xy 64.82188 -123.848935) (xy 64.858386 -123.801359) (xy 64.900791 -123.758954)
			(xy 64.948367 -123.722448) (xy 65.000301 -123.692464) (xy 65.055705 -123.669515) (xy 65.11363 -123.653994)
			(xy 65.173086 -123.646166) (xy 65.233054 -123.646166) (xy 65.29251 -123.653994) (xy 65.350435 -123.669515)
			(xy 65.405839 -123.692464) (xy 65.457773 -123.722448) (xy 65.505349 -123.758954) (xy 65.547754 -123.801359)
			(xy 65.58426 -123.848935) (xy 65.614244 -123.900869) (xy 65.637193 -123.956273) (xy 65.652714 -124.014198)
			(xy 65.660542 -124.073654) (xy 65.661032 -124.103638) (xy 65.661032 -124.965714) (xy 83.716368 -124.965714)
			(xy 83.716368 -124.102114) (xy 83.716858 -124.07213) (xy 83.724686 -124.012674) (xy 83.740207 -123.954749)
			(xy 83.763156 -123.899345) (xy 83.79314 -123.847411) (xy 83.829646 -123.799835) (xy 83.872051 -123.75743)
			(xy 83.919627 -123.720924) (xy 83.971561 -123.69094) (xy 84.026965 -123.667991) (xy 84.08489 -123.65247)
			(xy 84.144346 -123.644642) (xy 84.204314 -123.644642) (xy 84.26377 -123.65247) (xy 84.321695 -123.667991)
			(xy 84.369615 -123.68784) (xy 150.767796 -123.68784) (xy 150.767796 -122.82424) (xy 150.768286 -122.794256)
			(xy 150.776114 -122.7348) (xy 150.791635 -122.676875) (xy 150.814584 -122.621471) (xy 150.844568 -122.569537)
			(xy 150.881074 -122.521961) (xy 150.923479 -122.479556) (xy 150.971055 -122.44305) (xy 151.022989 -122.413066)
			(xy 151.078393 -122.390117) (xy 151.136318 -122.374596) (xy 151.195774 -122.366768) (xy 151.255742 -122.366768)
			(xy 151.315198 -122.374596) (xy 151.373123 -122.390117) (xy 151.428527 -122.413066) (xy 151.480461 -122.44305)
			(xy 151.528037 -122.479556) (xy 151.570442 -122.521961) (xy 151.606948 -122.569537) (xy 151.636932 -122.621471)
			(xy 151.659881 -122.676875) (xy 151.675402 -122.7348) (xy 151.68323 -122.794256) (xy 151.68372 -122.82424)
			(xy 151.68372 -123.686316) (xy 169.739056 -123.686316) (xy 169.739056 -122.822716) (xy 169.739546 -122.792732)
			(xy 169.747374 -122.733276) (xy 169.762895 -122.675351) (xy 169.785844 -122.619947) (xy 169.815828 -122.568013)
			(xy 169.852334 -122.520437) (xy 169.894739 -122.478032) (xy 169.942315 -122.441526) (xy 169.994249 -122.411542)
			(xy 170.049653 -122.388593) (xy 170.107578 -122.373072) (xy 170.167034 -122.365244) (xy 170.227002 -122.365244)
			(xy 170.286458 -122.373072) (xy 170.344383 -122.388593) (xy 170.399787 -122.411542) (xy 170.451721 -122.441526)
			(xy 170.499297 -122.478032) (xy 170.541702 -122.520437) (xy 170.578208 -122.568013) (xy 170.608192 -122.619947)
			(xy 170.631141 -122.675351) (xy 170.646662 -122.733276) (xy 170.65449 -122.792732) (xy 170.65498 -122.822716)
			(xy 170.65498 -123.16714) (xy 182.69966 -123.16714) (xy 182.69966 -122.30354) (xy 182.70015 -122.273572)
			(xy 182.707973 -122.21415) (xy 182.723486 -122.156257) (xy 182.746422 -122.100884) (xy 182.776389 -122.048978)
			(xy 182.812876 -122.001428) (xy 182.855256 -121.959048) (xy 182.902806 -121.922561) (xy 182.954712 -121.892594)
			(xy 183.010085 -121.869658) (xy 183.067978 -121.854145) (xy 183.1274 -121.846322) (xy 183.187336 -121.846322)
			(xy 183.246758 -121.854145) (xy 183.304651 -121.869658) (xy 183.360024 -121.892594) (xy 183.41193 -121.922561)
			(xy 183.45948 -121.959048) (xy 183.50186 -122.001428) (xy 183.538347 -122.048978) (xy 183.568314 -122.100884)
			(xy 183.59125 -122.156257) (xy 183.606763 -122.21415) (xy 183.614586 -122.273572) (xy 183.615076 -122.30354)
			(xy 183.615076 -123.159266) (xy 197.174612 -123.159266) (xy 197.174612 -122.295666) (xy 197.175102 -122.265698)
			(xy 197.182925 -122.206276) (xy 197.198438 -122.148383) (xy 197.221374 -122.09301) (xy 197.251341 -122.041104)
			(xy 197.287828 -121.993554) (xy 197.330208 -121.951174) (xy 197.377758 -121.914687) (xy 197.429664 -121.88472)
			(xy 197.485037 -121.861784) (xy 197.54293 -121.846271) (xy 197.602352 -121.838448) (xy 197.662288 -121.838448)
			(xy 197.72171 -121.846271) (xy 197.779603 -121.861784) (xy 197.834976 -121.88472) (xy 197.851649 -121.894346)
			(xy 269.509748 -121.894346) (xy 269.509748 -121.030746) (xy 269.510238 -121.000762) (xy 269.518066 -120.941306)
			(xy 269.533587 -120.883381) (xy 269.556536 -120.827977) (xy 269.58652 -120.776043) (xy 269.623026 -120.728467)
			(xy 269.665431 -120.686062) (xy 269.713007 -120.649556) (xy 269.764941 -120.619572) (xy 269.820345 -120.596623)
			(xy 269.87827 -120.581102) (xy 269.937726 -120.573274) (xy 269.997694 -120.573274) (xy 270.05715 -120.581102)
			(xy 270.115075 -120.596623) (xy 270.170479 -120.619572) (xy 270.222413 -120.649556) (xy 270.269989 -120.686062)
			(xy 270.312394 -120.728467) (xy 270.3489 -120.776043) (xy 270.378884 -120.827977) (xy 270.401833 -120.883381)
			(xy 270.417354 -120.941306) (xy 270.425182 -121.000762) (xy 270.425672 -121.030746) (xy 270.425672 -121.886472)
			(xy 283.9847 -121.886472) (xy 283.9847 -121.022872) (xy 283.98519 -120.992888) (xy 283.993018 -120.933432)
			(xy 284.008539 -120.875507) (xy 284.031488 -120.820103) (xy 284.061472 -120.768169) (xy 284.097978 -120.720593)
			(xy 284.140383 -120.678188) (xy 284.187959 -120.641682) (xy 284.239893 -120.611698) (xy 284.295297 -120.588749)
			(xy 284.353222 -120.573228) (xy 284.412678 -120.5654) (xy 284.472646 -120.5654) (xy 284.532102 -120.573228)
			(xy 284.590027 -120.588749) (xy 284.645431 -120.611698) (xy 284.697365 -120.641682) (xy 284.744941 -120.678188)
			(xy 284.787346 -120.720593) (xy 284.823852 -120.768169) (xy 284.853836 -120.820103) (xy 284.876785 -120.875507)
			(xy 284.892306 -120.933432) (xy 284.900134 -120.992888) (xy 284.900624 -121.022872) (xy 284.900624 -121.367296)
			(xy 296.945304 -121.367296) (xy 296.945304 -120.503696) (xy 296.945794 -120.473728) (xy 296.953617 -120.414306)
			(xy 296.96913 -120.356413) (xy 296.992066 -120.30104) (xy 297.022033 -120.249134) (xy 297.05852 -120.201584)
			(xy 297.1009 -120.159204) (xy 297.14845 -120.122717) (xy 297.200356 -120.09275) (xy 297.255729 -120.069814)
			(xy 297.313622 -120.054301) (xy 297.373044 -120.046478) (xy 297.43298 -120.046478) (xy 297.492402 -120.054301)
			(xy 297.550295 -120.069814) (xy 297.605668 -120.09275) (xy 297.657574 -120.122717) (xy 297.705124 -120.159204)
			(xy 297.747504 -120.201584) (xy 297.783991 -120.249134) (xy 297.813958 -120.30104) (xy 297.836894 -120.356413)
			(xy 297.852407 -120.414306) (xy 297.86023 -120.473728) (xy 297.86072 -120.503696) (xy 297.86072 -121.365772)
			(xy 315.916564 -121.365772) (xy 315.916564 -120.502172) (xy 315.917054 -120.472204) (xy 315.924877 -120.412782)
			(xy 315.94039 -120.354889) (xy 315.963326 -120.299516) (xy 315.993293 -120.24761) (xy 316.02978 -120.20006)
			(xy 316.07216 -120.15768) (xy 316.11971 -120.121193) (xy 316.171616 -120.091226) (xy 316.226989 -120.06829)
			(xy 316.284882 -120.052777) (xy 316.344304 -120.044954) (xy 316.40424 -120.044954) (xy 316.463662 -120.052777)
			(xy 316.521555 -120.06829) (xy 316.568893 -120.087898) (xy 382.967992 -120.087898) (xy 382.967992 -119.224298)
			(xy 382.968482 -119.19433) (xy 382.976305 -119.134908) (xy 382.991818 -119.077015) (xy 383.014754 -119.021642)
			(xy 383.044721 -118.969736) (xy 383.081208 -118.922186) (xy 383.123588 -118.879806) (xy 383.171138 -118.843319)
			(xy 383.223044 -118.813352) (xy 383.278417 -118.790416) (xy 383.33631 -118.774903) (xy 383.395732 -118.76708)
			(xy 383.455668 -118.76708) (xy 383.51509 -118.774903) (xy 383.572983 -118.790416) (xy 383.628356 -118.813352)
			(xy 383.680262 -118.843319) (xy 383.727812 -118.879806) (xy 383.770192 -118.922186) (xy 383.806679 -118.969736)
			(xy 383.836646 -119.021642) (xy 383.859582 -119.077015) (xy 383.875095 -119.134908) (xy 383.882918 -119.19433)
			(xy 383.883408 -119.224298) (xy 383.883408 -120.086374) (xy 401.939252 -120.086374) (xy 401.939252 -119.222774)
			(xy 401.939742 -119.192806) (xy 401.947565 -119.133384) (xy 401.963078 -119.075491) (xy 401.986014 -119.020118)
			(xy 402.015981 -118.968212) (xy 402.052468 -118.920662) (xy 402.094848 -118.878282) (xy 402.142398 -118.841795)
			(xy 402.194304 -118.811828) (xy 402.249677 -118.788892) (xy 402.30757 -118.773379) (xy 402.366992 -118.765556)
			(xy 402.426928 -118.765556) (xy 402.48635 -118.773379) (xy 402.544243 -118.788892) (xy 402.599616 -118.811828)
			(xy 402.651522 -118.841795) (xy 402.699072 -118.878282) (xy 402.741452 -118.920662) (xy 402.777939 -118.968212)
			(xy 402.807906 -119.020118) (xy 402.830842 -119.075491) (xy 402.846355 -119.133384) (xy 402.854178 -119.192806)
			(xy 402.854668 -119.222774) (xy 402.854668 -119.567198) (xy 414.899348 -119.567198) (xy 414.899348 -118.703598)
			(xy 414.899838 -118.673614) (xy 414.907666 -118.614158) (xy 414.923187 -118.556233) (xy 414.946136 -118.500829)
			(xy 414.97612 -118.448895) (xy 415.012626 -118.401319) (xy 415.055031 -118.358914) (xy 415.102607 -118.322408)
			(xy 415.154541 -118.292424) (xy 415.209945 -118.269475) (xy 415.26787 -118.253954) (xy 415.327326 -118.246126)
			(xy 415.387294 -118.246126) (xy 415.44675 -118.253954) (xy 415.504675 -118.269475) (xy 415.560079 -118.292424)
			(xy 415.612013 -118.322408) (xy 415.659589 -118.358914) (xy 415.701994 -118.401319) (xy 415.7385 -118.448895)
			(xy 415.768484 -118.500829) (xy 415.791433 -118.556233) (xy 415.806954 -118.614158) (xy 415.814782 -118.673614)
			(xy 415.815272 -118.703598) (xy 415.815272 -119.559324) (xy 429.3743 -119.559324) (xy 429.3743 -118.695724)
			(xy 429.37479 -118.66574) (xy 429.382618 -118.606284) (xy 429.398139 -118.548359) (xy 429.421088 -118.492955)
			(xy 429.451072 -118.441021) (xy 429.487578 -118.393445) (xy 429.529983 -118.35104) (xy 429.577559 -118.314534)
			(xy 429.629493 -118.28455) (xy 429.684897 -118.261601) (xy 429.742822 -118.24608) (xy 429.802278 -118.238252)
			(xy 429.862246 -118.238252) (xy 429.921702 -118.24608) (xy 429.979627 -118.261601) (xy 430.035031 -118.28455)
			(xy 430.086965 -118.314534) (xy 430.134541 -118.35104) (xy 430.176946 -118.393445) (xy 430.213452 -118.441021)
			(xy 430.243436 -118.492955) (xy 430.266385 -118.548359) (xy 430.281906 -118.606284) (xy 430.289734 -118.66574)
			(xy 430.290224 -118.695724) (xy 430.290224 -119.559324) (xy 430.289734 -119.589308) (xy 430.281906 -119.648764)
			(xy 430.266385 -119.706689) (xy 430.243436 -119.762093) (xy 430.213452 -119.814027) (xy 430.176946 -119.861603)
			(xy 430.134541 -119.904008) (xy 430.086965 -119.940514) (xy 430.035031 -119.970498) (xy 429.979627 -119.993447)
			(xy 429.921702 -120.008968) (xy 429.862246 -120.016796) (xy 429.802278 -120.016796) (xy 429.742822 -120.008968)
			(xy 429.684897 -119.993447) (xy 429.629493 -119.970498) (xy 429.577559 -119.940514) (xy 429.529983 -119.904008)
			(xy 429.487578 -119.861603) (xy 429.451072 -119.814027) (xy 429.421088 -119.762093) (xy 429.398139 -119.706689)
			(xy 429.382618 -119.648764) (xy 429.37479 -119.589308) (xy 429.3743 -119.559324) (xy 415.815272 -119.559324)
			(xy 415.815272 -119.567198) (xy 415.814782 -119.597182) (xy 415.806954 -119.656638) (xy 415.791433 -119.714563)
			(xy 415.768484 -119.769967) (xy 415.7385 -119.821901) (xy 415.701994 -119.869477) (xy 415.659589 -119.911882)
			(xy 415.612013 -119.948388) (xy 415.560079 -119.978372) (xy 415.504675 -120.001321) (xy 415.44675 -120.016842)
			(xy 415.387294 -120.02467) (xy 415.327326 -120.02467) (xy 415.26787 -120.016842) (xy 415.209945 -120.001321)
			(xy 415.154541 -119.978372) (xy 415.102607 -119.948388) (xy 415.055031 -119.911882) (xy 415.012626 -119.869477)
			(xy 414.97612 -119.821901) (xy 414.946136 -119.769967) (xy 414.923187 -119.714563) (xy 414.907666 -119.656638)
			(xy 414.899838 -119.597182) (xy 414.899348 -119.567198) (xy 402.854668 -119.567198) (xy 402.854668 -120.086374)
			(xy 402.854178 -120.116342) (xy 402.846355 -120.175764) (xy 402.830842 -120.233657) (xy 402.807906 -120.28903)
			(xy 402.777939 -120.340936) (xy 402.741452 -120.388486) (xy 402.699072 -120.430866) (xy 402.651522 -120.467353)
			(xy 402.599616 -120.49732) (xy 402.544243 -120.520256) (xy 402.48635 -120.535769) (xy 402.426928 -120.543592)
			(xy 402.366992 -120.543592) (xy 402.30757 -120.535769) (xy 402.249677 -120.520256) (xy 402.194304 -120.49732)
			(xy 402.142398 -120.467353) (xy 402.094848 -120.430866) (xy 402.052468 -120.388486) (xy 402.015981 -120.340936)
			(xy 401.986014 -120.28903) (xy 401.963078 -120.233657) (xy 401.947565 -120.175764) (xy 401.939742 -120.116342)
			(xy 401.939252 -120.086374) (xy 383.883408 -120.086374) (xy 383.883408 -120.087898) (xy 383.882918 -120.117866)
			(xy 383.875095 -120.177288) (xy 383.859582 -120.235181) (xy 383.836646 -120.290554) (xy 383.806679 -120.34246)
			(xy 383.770192 -120.39001) (xy 383.727812 -120.43239) (xy 383.680262 -120.468877) (xy 383.628356 -120.498844)
			(xy 383.572983 -120.52178) (xy 383.51509 -120.537293) (xy 383.455668 -120.545116) (xy 383.395732 -120.545116)
			(xy 383.33631 -120.537293) (xy 383.278417 -120.52178) (xy 383.223044 -120.498844) (xy 383.171138 -120.468877)
			(xy 383.123588 -120.43239) (xy 383.081208 -120.39001) (xy 383.044721 -120.34246) (xy 383.014754 -120.290554)
			(xy 382.991818 -120.235181) (xy 382.976305 -120.177288) (xy 382.968482 -120.117866) (xy 382.967992 -120.087898)
			(xy 316.568893 -120.087898) (xy 316.576928 -120.091226) (xy 316.628834 -120.121193) (xy 316.676384 -120.15768)
			(xy 316.718764 -120.20006) (xy 316.755251 -120.24761) (xy 316.785218 -120.299516) (xy 316.808154 -120.354889)
			(xy 316.823667 -120.412782) (xy 316.83149 -120.472204) (xy 316.83198 -120.502172) (xy 316.83198 -121.365772)
			(xy 316.83149 -121.39574) (xy 316.823667 -121.455162) (xy 316.808154 -121.513055) (xy 316.785218 -121.568428)
			(xy 316.755251 -121.620334) (xy 316.718764 -121.667884) (xy 316.676384 -121.710264) (xy 316.628834 -121.746751)
			(xy 316.576928 -121.776718) (xy 316.521555 -121.799654) (xy 316.463662 -121.815167) (xy 316.40424 -121.82299)
			(xy 316.344304 -121.82299) (xy 316.284882 -121.815167) (xy 316.226989 -121.799654) (xy 316.171616 -121.776718)
			(xy 316.11971 -121.746751) (xy 316.07216 -121.710264) (xy 316.02978 -121.667884) (xy 315.993293 -121.620334)
			(xy 315.963326 -121.568428) (xy 315.94039 -121.513055) (xy 315.924877 -121.455162) (xy 315.917054 -121.39574)
			(xy 315.916564 -121.365772) (xy 297.86072 -121.365772) (xy 297.86072 -121.367296) (xy 297.86023 -121.397264)
			(xy 297.852407 -121.456686) (xy 297.836894 -121.514579) (xy 297.813958 -121.569952) (xy 297.783991 -121.621858)
			(xy 297.747504 -121.669408) (xy 297.705124 -121.711788) (xy 297.657574 -121.748275) (xy 297.605668 -121.778242)
			(xy 297.550295 -121.801178) (xy 297.492402 -121.816691) (xy 297.43298 -121.824514) (xy 297.373044 -121.824514)
			(xy 297.313622 -121.816691) (xy 297.255729 -121.801178) (xy 297.200356 -121.778242) (xy 297.14845 -121.748275)
			(xy 297.1009 -121.711788) (xy 297.05852 -121.669408) (xy 297.022033 -121.621858) (xy 296.992066 -121.569952)
			(xy 296.96913 -121.514579) (xy 296.953617 -121.456686) (xy 296.945794 -121.397264) (xy 296.945304 -121.367296)
			(xy 284.900624 -121.367296) (xy 284.900624 -121.886472) (xy 284.900134 -121.916456) (xy 284.892306 -121.975912)
			(xy 284.876785 -122.033837) (xy 284.853836 -122.089241) (xy 284.823852 -122.141175) (xy 284.787346 -122.188751)
			(xy 284.744941 -122.231156) (xy 284.697365 -122.267662) (xy 284.645431 -122.297646) (xy 284.590027 -122.320595)
			(xy 284.532102 -122.336116) (xy 284.472646 -122.343944) (xy 284.412678 -122.343944) (xy 284.353222 -122.336116)
			(xy 284.295297 -122.320595) (xy 284.239893 -122.297646) (xy 284.187959 -122.267662) (xy 284.140383 -122.231156)
			(xy 284.097978 -122.188751) (xy 284.061472 -122.141175) (xy 284.031488 -122.089241) (xy 284.008539 -122.033837)
			(xy 283.993018 -121.975912) (xy 283.98519 -121.916456) (xy 283.9847 -121.886472) (xy 270.425672 -121.886472)
			(xy 270.425672 -121.894346) (xy 270.425182 -121.92433) (xy 270.417354 -121.983786) (xy 270.401833 -122.041711)
			(xy 270.378884 -122.097115) (xy 270.3489 -122.149049) (xy 270.312394 -122.196625) (xy 270.269989 -122.23903)
			(xy 270.222413 -122.275536) (xy 270.170479 -122.30552) (xy 270.115075 -122.328469) (xy 270.05715 -122.34399)
			(xy 269.997694 -122.351818) (xy 269.937726 -122.351818) (xy 269.87827 -122.34399) (xy 269.820345 -122.328469)
			(xy 269.764941 -122.30552) (xy 269.713007 -122.275536) (xy 269.665431 -122.23903) (xy 269.623026 -122.196625)
			(xy 269.58652 -122.149049) (xy 269.556536 -122.097115) (xy 269.533587 -122.041711) (xy 269.518066 -121.983786)
			(xy 269.510238 -121.92433) (xy 269.509748 -121.894346) (xy 197.851649 -121.894346) (xy 197.886882 -121.914687)
			(xy 197.934432 -121.951174) (xy 197.976812 -121.993554) (xy 198.013299 -122.041104) (xy 198.043266 -122.09301)
			(xy 198.066202 -122.148383) (xy 198.081715 -122.206276) (xy 198.089538 -122.265698) (xy 198.090028 -122.295666)
			(xy 198.090028 -123.159266) (xy 198.089538 -123.189234) (xy 198.081715 -123.248656) (xy 198.066202 -123.306549)
			(xy 198.043266 -123.361922) (xy 198.013299 -123.413828) (xy 197.976812 -123.461378) (xy 197.934432 -123.503758)
			(xy 197.886882 -123.540245) (xy 197.834976 -123.570212) (xy 197.779603 -123.593148) (xy 197.72171 -123.608661)
			(xy 197.662288 -123.616484) (xy 197.602352 -123.616484) (xy 197.54293 -123.608661) (xy 197.485037 -123.593148)
			(xy 197.429664 -123.570212) (xy 197.377758 -123.540245) (xy 197.330208 -123.503758) (xy 197.287828 -123.461378)
			(xy 197.251341 -123.413828) (xy 197.221374 -123.361922) (xy 197.198438 -123.306549) (xy 197.182925 -123.248656)
			(xy 197.175102 -123.189234) (xy 197.174612 -123.159266) (xy 183.615076 -123.159266) (xy 183.615076 -123.16714)
			(xy 183.614586 -123.197108) (xy 183.606763 -123.25653) (xy 183.59125 -123.314423) (xy 183.568314 -123.369796)
			(xy 183.538347 -123.421702) (xy 183.50186 -123.469252) (xy 183.45948 -123.511632) (xy 183.41193 -123.548119)
			(xy 183.360024 -123.578086) (xy 183.304651 -123.601022) (xy 183.246758 -123.616535) (xy 183.187336 -123.624358)
			(xy 183.1274 -123.624358) (xy 183.067978 -123.616535) (xy 183.010085 -123.601022) (xy 182.954712 -123.578086)
			(xy 182.902806 -123.548119) (xy 182.855256 -123.511632) (xy 182.812876 -123.469252) (xy 182.776389 -123.421702)
			(xy 182.746422 -123.369796) (xy 182.723486 -123.314423) (xy 182.707973 -123.25653) (xy 182.70015 -123.197108)
			(xy 182.69966 -123.16714) (xy 170.65498 -123.16714) (xy 170.65498 -123.686316) (xy 170.65449 -123.7163)
			(xy 170.646662 -123.775756) (xy 170.631141 -123.833681) (xy 170.608192 -123.889085) (xy 170.578208 -123.941019)
			(xy 170.541702 -123.988595) (xy 170.499297 -124.031) (xy 170.451721 -124.067506) (xy 170.399787 -124.09749)
			(xy 170.344383 -124.120439) (xy 170.286458 -124.13596) (xy 170.227002 -124.143788) (xy 170.167034 -124.143788)
			(xy 170.107578 -124.13596) (xy 170.049653 -124.120439) (xy 169.994249 -124.09749) (xy 169.942315 -124.067506)
			(xy 169.894739 -124.031) (xy 169.852334 -123.988595) (xy 169.815828 -123.941019) (xy 169.785844 -123.889085)
			(xy 169.762895 -123.833681) (xy 169.747374 -123.775756) (xy 169.739546 -123.7163) (xy 169.739056 -123.686316)
			(xy 151.68372 -123.686316) (xy 151.68372 -123.68784) (xy 151.68323 -123.717824) (xy 151.675402 -123.77728)
			(xy 151.659881 -123.835205) (xy 151.636932 -123.890609) (xy 151.606948 -123.942543) (xy 151.570442 -123.990119)
			(xy 151.528037 -124.032524) (xy 151.480461 -124.06903) (xy 151.428527 -124.099014) (xy 151.373123 -124.121963)
			(xy 151.315198 -124.137484) (xy 151.255742 -124.145312) (xy 151.195774 -124.145312) (xy 151.136318 -124.137484)
			(xy 151.078393 -124.121963) (xy 151.022989 -124.099014) (xy 150.971055 -124.06903) (xy 150.923479 -124.032524)
			(xy 150.881074 -123.990119) (xy 150.844568 -123.942543) (xy 150.814584 -123.890609) (xy 150.791635 -123.835205)
			(xy 150.776114 -123.77728) (xy 150.768286 -123.717824) (xy 150.767796 -123.68784) (xy 84.369615 -123.68784)
			(xy 84.377099 -123.69094) (xy 84.429033 -123.720924) (xy 84.476609 -123.75743) (xy 84.519014 -123.799835)
			(xy 84.55552 -123.847411) (xy 84.585504 -123.899345) (xy 84.608453 -123.954749) (xy 84.623974 -124.012674)
			(xy 84.631802 -124.07213) (xy 84.632292 -124.102114) (xy 84.632292 -124.965714) (xy 84.631802 -124.995698)
			(xy 84.623974 -125.055154) (xy 84.608453 -125.113079) (xy 84.585504 -125.168483) (xy 84.55552 -125.220417)
			(xy 84.519014 -125.267993) (xy 84.476609 -125.310398) (xy 84.429033 -125.346904) (xy 84.377099 -125.376888)
			(xy 84.321695 -125.399837) (xy 84.26377 -125.415358) (xy 84.204314 -125.423186) (xy 84.144346 -125.423186)
			(xy 84.08489 -125.415358) (xy 84.026965 -125.399837) (xy 83.971561 -125.376888) (xy 83.919627 -125.346904)
			(xy 83.872051 -125.310398) (xy 83.829646 -125.267993) (xy 83.79314 -125.220417) (xy 83.763156 -125.168483)
			(xy 83.740207 -125.113079) (xy 83.724686 -125.055154) (xy 83.716858 -124.995698) (xy 83.716368 -124.965714)
			(xy 65.661032 -124.965714) (xy 65.661032 -124.967238) (xy 65.660542 -124.997222) (xy 65.652714 -125.056678)
			(xy 65.637193 -125.114603) (xy 65.614244 -125.170007) (xy 65.58426 -125.221941) (xy 65.547754 -125.269517)
			(xy 65.505349 -125.311922) (xy 65.457773 -125.348428) (xy 65.405839 -125.378412) (xy 65.350435 -125.401361)
			(xy 65.29251 -125.416882) (xy 65.233054 -125.42471) (xy 65.173086 -125.42471) (xy 65.11363 -125.416882)
			(xy 65.055705 -125.401361) (xy 65.000301 -125.378412) (xy 64.948367 -125.348428) (xy 64.900791 -125.311922)
			(xy 64.858386 -125.269517) (xy 64.82188 -125.221941) (xy 64.791896 -125.170007) (xy 64.768947 -125.114603)
			(xy 64.753426 -125.056678) (xy 64.745598 -124.997222) (xy 64.745108 -124.967238) (xy 52.700428 -124.967238)
			(xy 52.700428 -125.486414) (xy 52.700295 -125.494542) (xy 153.409904 -125.494542) (xy 153.409904 -124.630942)
			(xy 153.410394 -124.600958) (xy 153.418222 -124.541502) (xy 153.433743 -124.483577) (xy 153.456692 -124.428173)
			(xy 153.486676 -124.376239) (xy 153.523182 -124.328663) (xy 153.565587 -124.286258) (xy 153.613163 -124.249752)
			(xy 153.665097 -124.219768) (xy 153.720501 -124.196819) (xy 153.778426 -124.181298) (xy 153.837882 -124.17347)
			(xy 153.89785 -124.17347) (xy 153.957306 -124.181298) (xy 154.015231 -124.196819) (xy 154.070635 -124.219768)
			(xy 154.122569 -124.249752) (xy 154.170145 -124.286258) (xy 154.21255 -124.328663) (xy 154.249056 -124.376239)
			(xy 154.27904 -124.428173) (xy 154.301989 -124.483577) (xy 154.31751 -124.541502) (xy 154.325338 -124.600958)
			(xy 154.325828 -124.630942) (xy 154.325828 -125.486414) (xy 167.884856 -125.486414) (xy 167.884856 -124.622814)
			(xy 167.885346 -124.59283) (xy 167.893174 -124.533374) (xy 167.908695 -124.475449) (xy 167.931644 -124.420045)
			(xy 167.961628 -124.368111) (xy 167.998134 -124.320535) (xy 168.040539 -124.27813) (xy 168.088115 -124.241624)
			(xy 168.140049 -124.21164) (xy 168.195453 -124.188691) (xy 168.253378 -124.17317) (xy 168.312834 -124.165342)
			(xy 168.372802 -124.165342) (xy 168.432258 -124.17317) (xy 168.490183 -124.188691) (xy 168.545587 -124.21164)
			(xy 168.597521 -124.241624) (xy 168.645097 -124.27813) (xy 168.687502 -124.320535) (xy 168.724008 -124.368111)
			(xy 168.753992 -124.420045) (xy 168.776941 -124.475449) (xy 168.792462 -124.533374) (xy 168.80029 -124.59283)
			(xy 168.80078 -124.622814) (xy 168.80078 -124.967238) (xy 180.84546 -124.967238) (xy 180.84546 -124.103638)
			(xy 180.84595 -124.07367) (xy 180.853773 -124.014248) (xy 180.869286 -123.956355) (xy 180.892222 -123.900982)
			(xy 180.922189 -123.849076) (xy 180.958676 -123.801526) (xy 181.001056 -123.759146) (xy 181.048606 -123.722659)
			(xy 181.100512 -123.692692) (xy 181.155885 -123.669756) (xy 181.213778 -123.654243) (xy 181.2732 -123.64642)
			(xy 181.333136 -123.64642) (xy 181.392558 -123.654243) (xy 181.450451 -123.669756) (xy 181.505824 -123.692692)
			(xy 181.55773 -123.722659) (xy 181.60528 -123.759146) (xy 181.64766 -123.801526) (xy 181.684147 -123.849076)
			(xy 181.714114 -123.900982) (xy 181.73705 -123.956355) (xy 181.752563 -124.014248) (xy 181.760386 -124.07367)
			(xy 181.760876 -124.103638) (xy 181.760876 -124.965714) (xy 199.81672 -124.965714) (xy 199.81672 -124.102114)
			(xy 199.81721 -124.072146) (xy 199.825033 -124.012724) (xy 199.840546 -123.954831) (xy 199.863482 -123.899458)
			(xy 199.893449 -123.847552) (xy 199.929936 -123.800002) (xy 199.972316 -123.757622) (xy 200.019866 -123.721135)
			(xy 200.071772 -123.691168) (xy 200.127145 -123.668232) (xy 200.185038 -123.652719) (xy 200.24446 -123.644896)
			(xy 200.304396 -123.644896) (xy 200.363818 -123.652719) (xy 200.421711 -123.668232) (xy 200.469049 -123.68784)
			(xy 266.86764 -123.68784) (xy 266.86764 -122.82424) (xy 266.86813 -122.794256) (xy 266.875958 -122.7348)
			(xy 266.891479 -122.676875) (xy 266.914428 -122.621471) (xy 266.944412 -122.569537) (xy 266.980918 -122.521961)
			(xy 267.023323 -122.479556) (xy 267.070899 -122.44305) (xy 267.122833 -122.413066) (xy 267.178237 -122.390117)
			(xy 267.236162 -122.374596) (xy 267.295618 -122.366768) (xy 267.355586 -122.366768) (xy 267.415042 -122.374596)
			(xy 267.472967 -122.390117) (xy 267.528371 -122.413066) (xy 267.580305 -122.44305) (xy 267.627881 -122.479556)
			(xy 267.670286 -122.521961) (xy 267.706792 -122.569537) (xy 267.736776 -122.621471) (xy 267.759725 -122.676875)
			(xy 267.775246 -122.7348) (xy 267.783074 -122.794256) (xy 267.783564 -122.82424) (xy 267.783564 -123.686316)
			(xy 285.8389 -123.686316) (xy 285.8389 -122.822716) (xy 285.83939 -122.792732) (xy 285.847218 -122.733276)
			(xy 285.862739 -122.675351) (xy 285.885688 -122.619947) (xy 285.915672 -122.568013) (xy 285.952178 -122.520437)
			(xy 285.994583 -122.478032) (xy 286.042159 -122.441526) (xy 286.094093 -122.411542) (xy 286.149497 -122.388593)
			(xy 286.207422 -122.373072) (xy 286.266878 -122.365244) (xy 286.326846 -122.365244) (xy 286.386302 -122.373072)
			(xy 286.444227 -122.388593) (xy 286.499631 -122.411542) (xy 286.551565 -122.441526) (xy 286.599141 -122.478032)
			(xy 286.641546 -122.520437) (xy 286.678052 -122.568013) (xy 286.708036 -122.619947) (xy 286.730985 -122.675351)
			(xy 286.746506 -122.733276) (xy 286.754334 -122.792732) (xy 286.754824 -122.822716) (xy 286.754824 -123.16714)
			(xy 298.799504 -123.16714) (xy 298.799504 -122.30354) (xy 298.799994 -122.273572) (xy 298.807817 -122.21415)
			(xy 298.82333 -122.156257) (xy 298.846266 -122.100884) (xy 298.876233 -122.048978) (xy 298.91272 -122.001428)
			(xy 298.9551 -121.959048) (xy 299.00265 -121.922561) (xy 299.054556 -121.892594) (xy 299.109929 -121.869658)
			(xy 299.167822 -121.854145) (xy 299.227244 -121.846322) (xy 299.28718 -121.846322) (xy 299.346602 -121.854145)
			(xy 299.404495 -121.869658) (xy 299.459868 -121.892594) (xy 299.511774 -121.922561) (xy 299.559324 -121.959048)
			(xy 299.601704 -122.001428) (xy 299.638191 -122.048978) (xy 299.668158 -122.100884) (xy 299.691094 -122.156257)
			(xy 299.706607 -122.21415) (xy 299.71443 -122.273572) (xy 299.71492 -122.30354) (xy 299.71492 -123.159266)
			(xy 313.274456 -123.159266) (xy 313.274456 -122.295666) (xy 313.274946 -122.265698) (xy 313.282769 -122.206276)
			(xy 313.298282 -122.148383) (xy 313.321218 -122.09301) (xy 313.351185 -122.041104) (xy 313.387672 -121.993554)
			(xy 313.430052 -121.951174) (xy 313.477602 -121.914687) (xy 313.529508 -121.88472) (xy 313.584881 -121.861784)
			(xy 313.642774 -121.846271) (xy 313.702196 -121.838448) (xy 313.762132 -121.838448) (xy 313.821554 -121.846271)
			(xy 313.879447 -121.861784) (xy 313.93482 -121.88472) (xy 313.951493 -121.894346) (xy 385.6101 -121.894346)
			(xy 385.6101 -121.030746) (xy 385.61059 -121.000778) (xy 385.618413 -120.941356) (xy 385.633926 -120.883463)
			(xy 385.656862 -120.82809) (xy 385.686829 -120.776184) (xy 385.723316 -120.728634) (xy 385.765696 -120.686254)
			(xy 385.813246 -120.649767) (xy 385.865152 -120.6198) (xy 385.920525 -120.596864) (xy 385.978418 -120.581351)
			(xy 386.03784 -120.573528) (xy 386.097776 -120.573528) (xy 386.157198 -120.581351) (xy 386.215091 -120.596864)
			(xy 386.270464 -120.6198) (xy 386.32237 -120.649767) (xy 386.36992 -120.686254) (xy 386.4123 -120.728634)
			(xy 386.448787 -120.776184) (xy 386.478754 -120.82809) (xy 386.50169 -120.883463) (xy 386.517203 -120.941356)
			(xy 386.525026 -121.000778) (xy 386.525516 -121.030746) (xy 386.525516 -121.886472) (xy 400.085052 -121.886472)
			(xy 400.085052 -121.022872) (xy 400.085542 -120.992904) (xy 400.093365 -120.933482) (xy 400.108878 -120.875589)
			(xy 400.131814 -120.820216) (xy 400.161781 -120.76831) (xy 400.198268 -120.72076) (xy 400.240648 -120.67838)
			(xy 400.288198 -120.641893) (xy 400.340104 -120.611926) (xy 400.395477 -120.58899) (xy 400.45337 -120.573477)
			(xy 400.512792 -120.565654) (xy 400.572728 -120.565654) (xy 400.63215 -120.573477) (xy 400.690043 -120.58899)
			(xy 400.745416 -120.611926) (xy 400.797322 -120.641893) (xy 400.844872 -120.67838) (xy 400.887252 -120.72076)
			(xy 400.923739 -120.76831) (xy 400.953706 -120.820216) (xy 400.976642 -120.875589) (xy 400.992155 -120.933482)
			(xy 400.999978 -120.992904) (xy 401.000468 -121.022872) (xy 401.000468 -121.367296) (xy 413.045148 -121.367296)
			(xy 413.045148 -120.503696) (xy 413.045638 -120.473712) (xy 413.053466 -120.414256) (xy 413.068987 -120.356331)
			(xy 413.091936 -120.300927) (xy 413.12192 -120.248993) (xy 413.158426 -120.201417) (xy 413.200831 -120.159012)
			(xy 413.248407 -120.122506) (xy 413.300341 -120.092522) (xy 413.355745 -120.069573) (xy 413.41367 -120.054052)
			(xy 413.473126 -120.046224) (xy 413.533094 -120.046224) (xy 413.59255 -120.054052) (xy 413.650475 -120.069573)
			(xy 413.705879 -120.092522) (xy 413.757813 -120.122506) (xy 413.805389 -120.159012) (xy 413.847794 -120.201417)
			(xy 413.8843 -120.248993) (xy 413.914284 -120.300927) (xy 413.937233 -120.356331) (xy 413.952754 -120.414256)
			(xy 413.960582 -120.473712) (xy 413.961072 -120.503696) (xy 413.961072 -121.365772) (xy 432.016408 -121.365772)
			(xy 432.016408 -120.502172) (xy 432.016898 -120.472188) (xy 432.024726 -120.412732) (xy 432.040247 -120.354807)
			(xy 432.063196 -120.299403) (xy 432.09318 -120.247469) (xy 432.129686 -120.199893) (xy 432.172091 -120.157488)
			(xy 432.219667 -120.120982) (xy 432.271601 -120.090998) (xy 432.327005 -120.068049) (xy 432.38493 -120.052528)
			(xy 432.444386 -120.0447) (xy 432.504354 -120.0447) (xy 432.56381 -120.052528) (xy 432.621735 -120.068049)
			(xy 432.677139 -120.090998) (xy 432.729073 -120.120982) (xy 432.776649 -120.157488) (xy 432.819054 -120.199893)
			(xy 432.85556 -120.247469) (xy 432.885544 -120.299403) (xy 432.908493 -120.354807) (xy 432.924014 -120.412732)
			(xy 432.931842 -120.472188) (xy 432.932332 -120.502172) (xy 432.932332 -121.365772) (xy 432.931842 -121.395756)
			(xy 432.924014 -121.455212) (xy 432.908493 -121.513137) (xy 432.885544 -121.568541) (xy 432.85556 -121.620475)
			(xy 432.819054 -121.668051) (xy 432.776649 -121.710456) (xy 432.729073 -121.746962) (xy 432.677139 -121.776946)
			(xy 432.621735 -121.799895) (xy 432.56381 -121.815416) (xy 432.504354 -121.823244) (xy 432.444386 -121.823244)
			(xy 432.38493 -121.815416) (xy 432.327005 -121.799895) (xy 432.271601 -121.776946) (xy 432.219667 -121.746962)
			(xy 432.172091 -121.710456) (xy 432.129686 -121.668051) (xy 432.09318 -121.620475) (xy 432.063196 -121.568541)
			(xy 432.040247 -121.513137) (xy 432.024726 -121.455212) (xy 432.016898 -121.395756) (xy 432.016408 -121.365772)
			(xy 413.961072 -121.365772) (xy 413.961072 -121.367296) (xy 413.960582 -121.39728) (xy 413.952754 -121.456736)
			(xy 413.937233 -121.514661) (xy 413.914284 -121.570065) (xy 413.8843 -121.621999) (xy 413.847794 -121.669575)
			(xy 413.805389 -121.71198) (xy 413.757813 -121.748486) (xy 413.705879 -121.77847) (xy 413.650475 -121.801419)
			(xy 413.59255 -121.81694) (xy 413.533094 -121.824768) (xy 413.473126 -121.824768) (xy 413.41367 -121.81694)
			(xy 413.355745 -121.801419) (xy 413.300341 -121.77847) (xy 413.248407 -121.748486) (xy 413.200831 -121.71198)
			(xy 413.158426 -121.669575) (xy 413.12192 -121.621999) (xy 413.091936 -121.570065) (xy 413.068987 -121.514661)
			(xy 413.053466 -121.456736) (xy 413.045638 -121.39728) (xy 413.045148 -121.367296) (xy 401.000468 -121.367296)
			(xy 401.000468 -121.886472) (xy 400.999978 -121.91644) (xy 400.992155 -121.975862) (xy 400.976642 -122.033755)
			(xy 400.953706 -122.089128) (xy 400.923739 -122.141034) (xy 400.887252 -122.188584) (xy 400.844872 -122.230964)
			(xy 400.797322 -122.267451) (xy 400.745416 -122.297418) (xy 400.690043 -122.320354) (xy 400.63215 -122.335867)
			(xy 400.572728 -122.34369) (xy 400.512792 -122.34369) (xy 400.45337 -122.335867) (xy 400.395477 -122.320354)
			(xy 400.340104 -122.297418) (xy 400.288198 -122.267451) (xy 400.240648 -122.230964) (xy 400.198268 -122.188584)
			(xy 400.161781 -122.141034) (xy 400.131814 -122.089128) (xy 400.108878 -122.033755) (xy 400.093365 -121.975862)
			(xy 400.085542 -121.91644) (xy 400.085052 -121.886472) (xy 386.525516 -121.886472) (xy 386.525516 -121.894346)
			(xy 386.525026 -121.924314) (xy 386.517203 -121.983736) (xy 386.50169 -122.041629) (xy 386.478754 -122.097002)
			(xy 386.448787 -122.148908) (xy 386.4123 -122.196458) (xy 386.36992 -122.238838) (xy 386.32237 -122.275325)
			(xy 386.270464 -122.305292) (xy 386.215091 -122.328228) (xy 386.157198 -122.343741) (xy 386.097776 -122.351564)
			(xy 386.03784 -122.351564) (xy 385.978418 -122.343741) (xy 385.920525 -122.328228) (xy 385.865152 -122.305292)
			(xy 385.813246 -122.275325) (xy 385.765696 -122.238838) (xy 385.723316 -122.196458) (xy 385.686829 -122.148908)
			(xy 385.656862 -122.097002) (xy 385.633926 -122.041629) (xy 385.618413 -121.983736) (xy 385.61059 -121.924314)
			(xy 385.6101 -121.894346) (xy 313.951493 -121.894346) (xy 313.986726 -121.914687) (xy 314.034276 -121.951174)
			(xy 314.076656 -121.993554) (xy 314.113143 -122.041104) (xy 314.14311 -122.09301) (xy 314.166046 -122.148383)
			(xy 314.181559 -122.206276) (xy 314.189382 -122.265698) (xy 314.189872 -122.295666) (xy 314.189872 -123.159266)
			(xy 314.189382 -123.189234) (xy 314.181559 -123.248656) (xy 314.166046 -123.306549) (xy 314.14311 -123.361922)
			(xy 314.113143 -123.413828) (xy 314.076656 -123.461378) (xy 314.034276 -123.503758) (xy 313.986726 -123.540245)
			(xy 313.93482 -123.570212) (xy 313.879447 -123.593148) (xy 313.821554 -123.608661) (xy 313.762132 -123.616484)
			(xy 313.702196 -123.616484) (xy 313.642774 -123.608661) (xy 313.584881 -123.593148) (xy 313.529508 -123.570212)
			(xy 313.477602 -123.540245) (xy 313.430052 -123.503758) (xy 313.387672 -123.461378) (xy 313.351185 -123.413828)
			(xy 313.321218 -123.361922) (xy 313.298282 -123.306549) (xy 313.282769 -123.248656) (xy 313.274946 -123.189234)
			(xy 313.274456 -123.159266) (xy 299.71492 -123.159266) (xy 299.71492 -123.16714) (xy 299.71443 -123.197108)
			(xy 299.706607 -123.25653) (xy 299.691094 -123.314423) (xy 299.668158 -123.369796) (xy 299.638191 -123.421702)
			(xy 299.601704 -123.469252) (xy 299.559324 -123.511632) (xy 299.511774 -123.548119) (xy 299.459868 -123.578086)
			(xy 299.404495 -123.601022) (xy 299.346602 -123.616535) (xy 299.28718 -123.624358) (xy 299.227244 -123.624358)
			(xy 299.167822 -123.616535) (xy 299.109929 -123.601022) (xy 299.054556 -123.578086) (xy 299.00265 -123.548119)
			(xy 298.9551 -123.511632) (xy 298.91272 -123.469252) (xy 298.876233 -123.421702) (xy 298.846266 -123.369796)
			(xy 298.82333 -123.314423) (xy 298.807817 -123.25653) (xy 298.799994 -123.197108) (xy 298.799504 -123.16714)
			(xy 286.754824 -123.16714) (xy 286.754824 -123.686316) (xy 286.754334 -123.7163) (xy 286.746506 -123.775756)
			(xy 286.730985 -123.833681) (xy 286.708036 -123.889085) (xy 286.678052 -123.941019) (xy 286.641546 -123.988595)
			(xy 286.599141 -124.031) (xy 286.551565 -124.067506) (xy 286.499631 -124.09749) (xy 286.444227 -124.120439)
			(xy 286.386302 -124.13596) (xy 286.326846 -124.143788) (xy 286.266878 -124.143788) (xy 286.207422 -124.13596)
			(xy 286.149497 -124.120439) (xy 286.094093 -124.09749) (xy 286.042159 -124.067506) (xy 285.994583 -124.031)
			(xy 285.952178 -123.988595) (xy 285.915672 -123.941019) (xy 285.885688 -123.889085) (xy 285.862739 -123.833681)
			(xy 285.847218 -123.775756) (xy 285.83939 -123.7163) (xy 285.8389 -123.686316) (xy 267.783564 -123.686316)
			(xy 267.783564 -123.68784) (xy 267.783074 -123.717824) (xy 267.775246 -123.77728) (xy 267.759725 -123.835205)
			(xy 267.736776 -123.890609) (xy 267.706792 -123.942543) (xy 267.670286 -123.990119) (xy 267.627881 -124.032524)
			(xy 267.580305 -124.06903) (xy 267.528371 -124.099014) (xy 267.472967 -124.121963) (xy 267.415042 -124.137484)
			(xy 267.355586 -124.145312) (xy 267.295618 -124.145312) (xy 267.236162 -124.137484) (xy 267.178237 -124.121963)
			(xy 267.122833 -124.099014) (xy 267.070899 -124.06903) (xy 267.023323 -124.032524) (xy 266.980918 -123.990119)
			(xy 266.944412 -123.942543) (xy 266.914428 -123.890609) (xy 266.891479 -123.835205) (xy 266.875958 -123.77728)
			(xy 266.86813 -123.717824) (xy 266.86764 -123.68784) (xy 200.469049 -123.68784) (xy 200.477084 -123.691168)
			(xy 200.52899 -123.721135) (xy 200.57654 -123.757622) (xy 200.61892 -123.800002) (xy 200.655407 -123.847552)
			(xy 200.685374 -123.899458) (xy 200.70831 -123.954831) (xy 200.723823 -124.012724) (xy 200.731646 -124.072146)
			(xy 200.732136 -124.102114) (xy 200.732136 -124.965714) (xy 200.731646 -124.995682) (xy 200.723823 -125.055104)
			(xy 200.70831 -125.112997) (xy 200.685374 -125.16837) (xy 200.655407 -125.220276) (xy 200.61892 -125.267826)
			(xy 200.57654 -125.310206) (xy 200.52899 -125.346693) (xy 200.477084 -125.37666) (xy 200.421711 -125.399596)
			(xy 200.363818 -125.415109) (xy 200.304396 -125.422932) (xy 200.24446 -125.422932) (xy 200.185038 -125.415109)
			(xy 200.127145 -125.399596) (xy 200.071772 -125.37666) (xy 200.019866 -125.346693) (xy 199.972316 -125.310206)
			(xy 199.929936 -125.267826) (xy 199.893449 -125.220276) (xy 199.863482 -125.16837) (xy 199.840546 -125.112997)
			(xy 199.825033 -125.055104) (xy 199.81721 -124.995682) (xy 199.81672 -124.965714) (xy 181.760876 -124.965714)
			(xy 181.760876 -124.967238) (xy 181.760386 -124.997206) (xy 181.752563 -125.056628) (xy 181.73705 -125.114521)
			(xy 181.714114 -125.169894) (xy 181.684147 -125.2218) (xy 181.64766 -125.26935) (xy 181.60528 -125.31173)
			(xy 181.55773 -125.348217) (xy 181.505824 -125.378184) (xy 181.450451 -125.40112) (xy 181.392558 -125.416633)
			(xy 181.333136 -125.424456) (xy 181.2732 -125.424456) (xy 181.213778 -125.416633) (xy 181.155885 -125.40112)
			(xy 181.100512 -125.378184) (xy 181.048606 -125.348217) (xy 181.001056 -125.31173) (xy 180.958676 -125.26935)
			(xy 180.922189 -125.2218) (xy 180.892222 -125.169894) (xy 180.869286 -125.114521) (xy 180.853773 -125.056628)
			(xy 180.84595 -124.997206) (xy 180.84546 -124.967238) (xy 168.80078 -124.967238) (xy 168.80078 -125.486414)
			(xy 168.800647 -125.494542) (xy 269.509748 -125.494542) (xy 269.509748 -124.630942) (xy 269.510238 -124.600958)
			(xy 269.518066 -124.541502) (xy 269.533587 -124.483577) (xy 269.556536 -124.428173) (xy 269.58652 -124.376239)
			(xy 269.623026 -124.328663) (xy 269.665431 -124.286258) (xy 269.713007 -124.249752) (xy 269.764941 -124.219768)
			(xy 269.820345 -124.196819) (xy 269.87827 -124.181298) (xy 269.937726 -124.17347) (xy 269.997694 -124.17347)
			(xy 270.05715 -124.181298) (xy 270.115075 -124.196819) (xy 270.170479 -124.219768) (xy 270.222413 -124.249752)
			(xy 270.269989 -124.286258) (xy 270.312394 -124.328663) (xy 270.3489 -124.376239) (xy 270.378884 -124.428173)
			(xy 270.401833 -124.483577) (xy 270.417354 -124.541502) (xy 270.425182 -124.600958) (xy 270.425672 -124.630942)
			(xy 270.425672 -125.486414) (xy 283.9847 -125.486414) (xy 283.9847 -124.622814) (xy 283.98519 -124.59283)
			(xy 283.993018 -124.533374) (xy 284.008539 -124.475449) (xy 284.031488 -124.420045) (xy 284.061472 -124.368111)
			(xy 284.097978 -124.320535) (xy 284.140383 -124.27813) (xy 284.187959 -124.241624) (xy 284.239893 -124.21164)
			(xy 284.295297 -124.188691) (xy 284.353222 -124.17317) (xy 284.412678 -124.165342) (xy 284.472646 -124.165342)
			(xy 284.532102 -124.17317) (xy 284.590027 -124.188691) (xy 284.645431 -124.21164) (xy 284.697365 -124.241624)
			(xy 284.744941 -124.27813) (xy 284.787346 -124.320535) (xy 284.823852 -124.368111) (xy 284.853836 -124.420045)
			(xy 284.876785 -124.475449) (xy 284.892306 -124.533374) (xy 284.900134 -124.59283) (xy 284.900624 -124.622814)
			(xy 284.900624 -124.967238) (xy 296.945304 -124.967238) (xy 296.945304 -124.103638) (xy 296.945794 -124.07367)
			(xy 296.953617 -124.014248) (xy 296.96913 -123.956355) (xy 296.992066 -123.900982) (xy 297.022033 -123.849076)
			(xy 297.05852 -123.801526) (xy 297.1009 -123.759146) (xy 297.14845 -123.722659) (xy 297.200356 -123.692692)
			(xy 297.255729 -123.669756) (xy 297.313622 -123.654243) (xy 297.373044 -123.64642) (xy 297.43298 -123.64642)
			(xy 297.492402 -123.654243) (xy 297.550295 -123.669756) (xy 297.605668 -123.692692) (xy 297.657574 -123.722659)
			(xy 297.705124 -123.759146) (xy 297.747504 -123.801526) (xy 297.783991 -123.849076) (xy 297.813958 -123.900982)
			(xy 297.836894 -123.956355) (xy 297.852407 -124.014248) (xy 297.86023 -124.07367) (xy 297.86072 -124.103638)
			(xy 297.86072 -124.965714) (xy 315.916564 -124.965714) (xy 315.916564 -124.102114) (xy 315.917054 -124.072146)
			(xy 315.924877 -124.012724) (xy 315.94039 -123.954831) (xy 315.963326 -123.899458) (xy 315.993293 -123.847552)
			(xy 316.02978 -123.800002) (xy 316.07216 -123.757622) (xy 316.11971 -123.721135) (xy 316.171616 -123.691168)
			(xy 316.226989 -123.668232) (xy 316.284882 -123.652719) (xy 316.344304 -123.644896) (xy 316.40424 -123.644896)
			(xy 316.463662 -123.652719) (xy 316.521555 -123.668232) (xy 316.568893 -123.68784) (xy 382.967992 -123.68784)
			(xy 382.967992 -122.82424) (xy 382.968482 -122.794272) (xy 382.976305 -122.73485) (xy 382.991818 -122.676957)
			(xy 383.014754 -122.621584) (xy 383.044721 -122.569678) (xy 383.081208 -122.522128) (xy 383.123588 -122.479748)
			(xy 383.171138 -122.443261) (xy 383.223044 -122.413294) (xy 383.278417 -122.390358) (xy 383.33631 -122.374845)
			(xy 383.395732 -122.367022) (xy 383.455668 -122.367022) (xy 383.51509 -122.374845) (xy 383.572983 -122.390358)
			(xy 383.628356 -122.413294) (xy 383.680262 -122.443261) (xy 383.727812 -122.479748) (xy 383.770192 -122.522128)
			(xy 383.806679 -122.569678) (xy 383.836646 -122.621584) (xy 383.859582 -122.676957) (xy 383.875095 -122.73485)
			(xy 383.882918 -122.794272) (xy 383.883408 -122.82424) (xy 383.883408 -123.686316) (xy 401.939252 -123.686316)
			(xy 401.939252 -122.822716) (xy 401.939742 -122.792748) (xy 401.947565 -122.733326) (xy 401.963078 -122.675433)
			(xy 401.986014 -122.62006) (xy 402.015981 -122.568154) (xy 402.052468 -122.520604) (xy 402.094848 -122.478224)
			(xy 402.142398 -122.441737) (xy 402.194304 -122.41177) (xy 402.249677 -122.388834) (xy 402.30757 -122.373321)
			(xy 402.366992 -122.365498) (xy 402.426928 -122.365498) (xy 402.48635 -122.373321) (xy 402.544243 -122.388834)
			(xy 402.599616 -122.41177) (xy 402.651522 -122.441737) (xy 402.699072 -122.478224) (xy 402.741452 -122.520604)
			(xy 402.777939 -122.568154) (xy 402.807906 -122.62006) (xy 402.830842 -122.675433) (xy 402.846355 -122.733326)
			(xy 402.854178 -122.792748) (xy 402.854668 -122.822716) (xy 402.854668 -123.16714) (xy 414.899348 -123.16714)
			(xy 414.899348 -122.30354) (xy 414.899838 -122.273556) (xy 414.907666 -122.2141) (xy 414.923187 -122.156175)
			(xy 414.946136 -122.100771) (xy 414.97612 -122.048837) (xy 415.012626 -122.001261) (xy 415.055031 -121.958856)
			(xy 415.102607 -121.92235) (xy 415.154541 -121.892366) (xy 415.209945 -121.869417) (xy 415.26787 -121.853896)
			(xy 415.327326 -121.846068) (xy 415.387294 -121.846068) (xy 415.44675 -121.853896) (xy 415.504675 -121.869417)
			(xy 415.560079 -121.892366) (xy 415.612013 -121.92235) (xy 415.659589 -121.958856) (xy 415.701994 -122.001261)
			(xy 415.7385 -122.048837) (xy 415.768484 -122.100771) (xy 415.791433 -122.156175) (xy 415.806954 -122.2141)
			(xy 415.814782 -122.273556) (xy 415.815272 -122.30354) (xy 415.815272 -123.159266) (xy 429.3743 -123.159266)
			(xy 429.3743 -122.295666) (xy 429.37479 -122.265682) (xy 429.382618 -122.206226) (xy 429.398139 -122.148301)
			(xy 429.421088 -122.092897) (xy 429.451072 -122.040963) (xy 429.487578 -121.993387) (xy 429.529983 -121.950982)
			(xy 429.577559 -121.914476) (xy 429.629493 -121.884492) (xy 429.684897 -121.861543) (xy 429.742822 -121.846022)
			(xy 429.802278 -121.838194) (xy 429.862246 -121.838194) (xy 429.921702 -121.846022) (xy 429.979627 -121.861543)
			(xy 430.035031 -121.884492) (xy 430.086965 -121.914476) (xy 430.134541 -121.950982) (xy 430.176946 -121.993387)
			(xy 430.213452 -122.040963) (xy 430.243436 -122.092897) (xy 430.266385 -122.148301) (xy 430.281906 -122.206226)
			(xy 430.289734 -122.265682) (xy 430.290224 -122.295666) (xy 430.290224 -123.159266) (xy 430.289734 -123.18925)
			(xy 430.281906 -123.248706) (xy 430.266385 -123.306631) (xy 430.243436 -123.362035) (xy 430.213452 -123.413969)
			(xy 430.176946 -123.461545) (xy 430.134541 -123.50395) (xy 430.086965 -123.540456) (xy 430.035031 -123.57044)
			(xy 429.979627 -123.593389) (xy 429.921702 -123.60891) (xy 429.862246 -123.616738) (xy 429.802278 -123.616738)
			(xy 429.742822 -123.60891) (xy 429.684897 -123.593389) (xy 429.629493 -123.57044) (xy 429.577559 -123.540456)
			(xy 429.529983 -123.50395) (xy 429.487578 -123.461545) (xy 429.451072 -123.413969) (xy 429.421088 -123.362035)
			(xy 429.398139 -123.306631) (xy 429.382618 -123.248706) (xy 429.37479 -123.18925) (xy 429.3743 -123.159266)
			(xy 415.815272 -123.159266) (xy 415.815272 -123.16714) (xy 415.814782 -123.197124) (xy 415.806954 -123.25658)
			(xy 415.791433 -123.314505) (xy 415.768484 -123.369909) (xy 415.7385 -123.421843) (xy 415.701994 -123.469419)
			(xy 415.659589 -123.511824) (xy 415.612013 -123.54833) (xy 415.560079 -123.578314) (xy 415.504675 -123.601263)
			(xy 415.44675 -123.616784) (xy 415.387294 -123.624612) (xy 415.327326 -123.624612) (xy 415.26787 -123.616784)
			(xy 415.209945 -123.601263) (xy 415.154541 -123.578314) (xy 415.102607 -123.54833) (xy 415.055031 -123.511824)
			(xy 415.012626 -123.469419) (xy 414.97612 -123.421843) (xy 414.946136 -123.369909) (xy 414.923187 -123.314505)
			(xy 414.907666 -123.25658) (xy 414.899838 -123.197124) (xy 414.899348 -123.16714) (xy 402.854668 -123.16714)
			(xy 402.854668 -123.686316) (xy 402.854178 -123.716284) (xy 402.846355 -123.775706) (xy 402.830842 -123.833599)
			(xy 402.807906 -123.888972) (xy 402.777939 -123.940878) (xy 402.741452 -123.988428) (xy 402.699072 -124.030808)
			(xy 402.651522 -124.067295) (xy 402.599616 -124.097262) (xy 402.544243 -124.120198) (xy 402.48635 -124.135711)
			(xy 402.426928 -124.143534) (xy 402.366992 -124.143534) (xy 402.30757 -124.135711) (xy 402.249677 -124.120198)
			(xy 402.194304 -124.097262) (xy 402.142398 -124.067295) (xy 402.094848 -124.030808) (xy 402.052468 -123.988428)
			(xy 402.015981 -123.940878) (xy 401.986014 -123.888972) (xy 401.963078 -123.833599) (xy 401.947565 -123.775706)
			(xy 401.939742 -123.716284) (xy 401.939252 -123.686316) (xy 383.883408 -123.686316) (xy 383.883408 -123.68784)
			(xy 383.882918 -123.717808) (xy 383.875095 -123.77723) (xy 383.859582 -123.835123) (xy 383.836646 -123.890496)
			(xy 383.806679 -123.942402) (xy 383.770192 -123.989952) (xy 383.727812 -124.032332) (xy 383.680262 -124.068819)
			(xy 383.628356 -124.098786) (xy 383.572983 -124.121722) (xy 383.51509 -124.137235) (xy 383.455668 -124.145058)
			(xy 383.395732 -124.145058) (xy 383.33631 -124.137235) (xy 383.278417 -124.121722) (xy 383.223044 -124.098786)
			(xy 383.171138 -124.068819) (xy 383.123588 -124.032332) (xy 383.081208 -123.989952) (xy 383.044721 -123.942402)
			(xy 383.014754 -123.890496) (xy 382.991818 -123.835123) (xy 382.976305 -123.77723) (xy 382.968482 -123.717808)
			(xy 382.967992 -123.68784) (xy 316.568893 -123.68784) (xy 316.576928 -123.691168) (xy 316.628834 -123.721135)
			(xy 316.676384 -123.757622) (xy 316.718764 -123.800002) (xy 316.755251 -123.847552) (xy 316.785218 -123.899458)
			(xy 316.808154 -123.954831) (xy 316.823667 -124.012724) (xy 316.83149 -124.072146) (xy 316.83198 -124.102114)
			(xy 316.83198 -124.965714) (xy 316.83149 -124.995682) (xy 316.823667 -125.055104) (xy 316.808154 -125.112997)
			(xy 316.785218 -125.16837) (xy 316.755251 -125.220276) (xy 316.718764 -125.267826) (xy 316.676384 -125.310206)
			(xy 316.628834 -125.346693) (xy 316.576928 -125.37666) (xy 316.521555 -125.399596) (xy 316.463662 -125.415109)
			(xy 316.40424 -125.422932) (xy 316.344304 -125.422932) (xy 316.284882 -125.415109) (xy 316.226989 -125.399596)
			(xy 316.171616 -125.37666) (xy 316.11971 -125.346693) (xy 316.07216 -125.310206) (xy 316.02978 -125.267826)
			(xy 315.993293 -125.220276) (xy 315.963326 -125.16837) (xy 315.94039 -125.112997) (xy 315.924877 -125.055104)
			(xy 315.917054 -124.995682) (xy 315.916564 -124.965714) (xy 297.86072 -124.965714) (xy 297.86072 -124.967238)
			(xy 297.86023 -124.997206) (xy 297.852407 -125.056628) (xy 297.836894 -125.114521) (xy 297.813958 -125.169894)
			(xy 297.783991 -125.2218) (xy 297.747504 -125.26935) (xy 297.705124 -125.31173) (xy 297.657574 -125.348217)
			(xy 297.605668 -125.378184) (xy 297.550295 -125.40112) (xy 297.492402 -125.416633) (xy 297.43298 -125.424456)
			(xy 297.373044 -125.424456) (xy 297.313622 -125.416633) (xy 297.255729 -125.40112) (xy 297.200356 -125.378184)
			(xy 297.14845 -125.348217) (xy 297.1009 -125.31173) (xy 297.05852 -125.26935) (xy 297.022033 -125.2218)
			(xy 296.992066 -125.169894) (xy 296.96913 -125.114521) (xy 296.953617 -125.056628) (xy 296.945794 -124.997206)
			(xy 296.945304 -124.967238) (xy 284.900624 -124.967238) (xy 284.900624 -125.486414) (xy 284.900491 -125.494542)
			(xy 385.6101 -125.494542) (xy 385.6101 -124.630942) (xy 385.61059 -124.600974) (xy 385.618413 -124.541552)
			(xy 385.633926 -124.483659) (xy 385.656862 -124.428286) (xy 385.686829 -124.37638) (xy 385.723316 -124.32883)
			(xy 385.765696 -124.28645) (xy 385.813246 -124.249963) (xy 385.865152 -124.219996) (xy 385.920525 -124.19706)
			(xy 385.978418 -124.181547) (xy 386.03784 -124.173724) (xy 386.097776 -124.173724) (xy 386.157198 -124.181547)
			(xy 386.215091 -124.19706) (xy 386.270464 -124.219996) (xy 386.32237 -124.249963) (xy 386.36992 -124.28645)
			(xy 386.4123 -124.32883) (xy 386.448787 -124.37638) (xy 386.478754 -124.428286) (xy 386.50169 -124.483659)
			(xy 386.517203 -124.541552) (xy 386.525026 -124.600974) (xy 386.525516 -124.630942) (xy 386.525516 -125.486414)
			(xy 400.085052 -125.486414) (xy 400.085052 -124.622814) (xy 400.085542 -124.592846) (xy 400.093365 -124.533424)
			(xy 400.108878 -124.475531) (xy 400.131814 -124.420158) (xy 400.161781 -124.368252) (xy 400.198268 -124.320702)
			(xy 400.240648 -124.278322) (xy 400.288198 -124.241835) (xy 400.340104 -124.211868) (xy 400.395477 -124.188932)
			(xy 400.45337 -124.173419) (xy 400.512792 -124.165596) (xy 400.572728 -124.165596) (xy 400.63215 -124.173419)
			(xy 400.690043 -124.188932) (xy 400.745416 -124.211868) (xy 400.797322 -124.241835) (xy 400.844872 -124.278322)
			(xy 400.887252 -124.320702) (xy 400.923739 -124.368252) (xy 400.953706 -124.420158) (xy 400.976642 -124.475531)
			(xy 400.992155 -124.533424) (xy 400.999978 -124.592846) (xy 401.000468 -124.622814) (xy 401.000468 -124.967238)
			(xy 413.045148 -124.967238) (xy 413.045148 -124.103638) (xy 413.045638 -124.073654) (xy 413.053466 -124.014198)
			(xy 413.068987 -123.956273) (xy 413.091936 -123.900869) (xy 413.12192 -123.848935) (xy 413.158426 -123.801359)
			(xy 413.200831 -123.758954) (xy 413.248407 -123.722448) (xy 413.300341 -123.692464) (xy 413.355745 -123.669515)
			(xy 413.41367 -123.653994) (xy 413.473126 -123.646166) (xy 413.533094 -123.646166) (xy 413.59255 -123.653994)
			(xy 413.650475 -123.669515) (xy 413.705879 -123.692464) (xy 413.757813 -123.722448) (xy 413.805389 -123.758954)
			(xy 413.847794 -123.801359) (xy 413.8843 -123.848935) (xy 413.914284 -123.900869) (xy 413.937233 -123.956273)
			(xy 413.952754 -124.014198) (xy 413.960582 -124.073654) (xy 413.961072 -124.103638) (xy 413.961072 -124.965714)
			(xy 432.016408 -124.965714) (xy 432.016408 -124.102114) (xy 432.016898 -124.07213) (xy 432.024726 -124.012674)
			(xy 432.040247 -123.954749) (xy 432.063196 -123.899345) (xy 432.09318 -123.847411) (xy 432.129686 -123.799835)
			(xy 432.172091 -123.75743) (xy 432.219667 -123.720924) (xy 432.271601 -123.69094) (xy 432.327005 -123.667991)
			(xy 432.38493 -123.65247) (xy 432.444386 -123.644642) (xy 432.504354 -123.644642) (xy 432.56381 -123.65247)
			(xy 432.621735 -123.667991) (xy 432.677139 -123.69094) (xy 432.729073 -123.720924) (xy 432.776649 -123.75743)
			(xy 432.819054 -123.799835) (xy 432.85556 -123.847411) (xy 432.885544 -123.899345) (xy 432.908493 -123.954749)
			(xy 432.924014 -124.012674) (xy 432.931842 -124.07213) (xy 432.932332 -124.102114) (xy 432.932332 -124.965714)
			(xy 432.931842 -124.995698) (xy 432.924014 -125.055154) (xy 432.908493 -125.113079) (xy 432.885544 -125.168483)
			(xy 432.85556 -125.220417) (xy 432.819054 -125.267993) (xy 432.776649 -125.310398) (xy 432.729073 -125.346904)
			(xy 432.677139 -125.376888) (xy 432.621735 -125.399837) (xy 432.56381 -125.415358) (xy 432.504354 -125.423186)
			(xy 432.444386 -125.423186) (xy 432.38493 -125.415358) (xy 432.327005 -125.399837) (xy 432.271601 -125.376888)
			(xy 432.219667 -125.346904) (xy 432.172091 -125.310398) (xy 432.129686 -125.267993) (xy 432.09318 -125.220417)
			(xy 432.063196 -125.168483) (xy 432.040247 -125.113079) (xy 432.024726 -125.055154) (xy 432.016898 -124.995698)
			(xy 432.016408 -124.965714) (xy 413.961072 -124.965714) (xy 413.961072 -124.967238) (xy 413.960582 -124.997222)
			(xy 413.952754 -125.056678) (xy 413.937233 -125.114603) (xy 413.914284 -125.170007) (xy 413.8843 -125.221941)
			(xy 413.847794 -125.269517) (xy 413.805389 -125.311922) (xy 413.757813 -125.348428) (xy 413.705879 -125.378412)
			(xy 413.650475 -125.401361) (xy 413.59255 -125.416882) (xy 413.533094 -125.42471) (xy 413.473126 -125.42471)
			(xy 413.41367 -125.416882) (xy 413.355745 -125.401361) (xy 413.300341 -125.378412) (xy 413.248407 -125.348428)
			(xy 413.200831 -125.311922) (xy 413.158426 -125.269517) (xy 413.12192 -125.221941) (xy 413.091936 -125.170007)
			(xy 413.068987 -125.114603) (xy 413.053466 -125.056678) (xy 413.045638 -124.997222) (xy 413.045148 -124.967238)
			(xy 401.000468 -124.967238) (xy 401.000468 -125.486414) (xy 400.999978 -125.516382) (xy 400.992155 -125.575804)
			(xy 400.976642 -125.633697) (xy 400.953706 -125.68907) (xy 400.923739 -125.740976) (xy 400.887252 -125.788526)
			(xy 400.844872 -125.830906) (xy 400.797322 -125.867393) (xy 400.745416 -125.89736) (xy 400.690043 -125.920296)
			(xy 400.63215 -125.935809) (xy 400.572728 -125.943632) (xy 400.512792 -125.943632) (xy 400.45337 -125.935809)
			(xy 400.395477 -125.920296) (xy 400.340104 -125.89736) (xy 400.288198 -125.867393) (xy 400.240648 -125.830906)
			(xy 400.198268 -125.788526) (xy 400.161781 -125.740976) (xy 400.131814 -125.68907) (xy 400.108878 -125.633697)
			(xy 400.093365 -125.575804) (xy 400.085542 -125.516382) (xy 400.085052 -125.486414) (xy 386.525516 -125.486414)
			(xy 386.525516 -125.494542) (xy 386.525026 -125.52451) (xy 386.517203 -125.583932) (xy 386.50169 -125.641825)
			(xy 386.478754 -125.697198) (xy 386.448787 -125.749104) (xy 386.4123 -125.796654) (xy 386.36992 -125.839034)
			(xy 386.32237 -125.875521) (xy 386.270464 -125.905488) (xy 386.215091 -125.928424) (xy 386.157198 -125.943937)
			(xy 386.097776 -125.95176) (xy 386.03784 -125.95176) (xy 385.978418 -125.943937) (xy 385.920525 -125.928424)
			(xy 385.865152 -125.905488) (xy 385.813246 -125.875521) (xy 385.765696 -125.839034) (xy 385.723316 -125.796654)
			(xy 385.686829 -125.749104) (xy 385.656862 -125.697198) (xy 385.633926 -125.641825) (xy 385.618413 -125.583932)
			(xy 385.61059 -125.52451) (xy 385.6101 -125.494542) (xy 284.900491 -125.494542) (xy 284.900134 -125.516398)
			(xy 284.892306 -125.575854) (xy 284.876785 -125.633779) (xy 284.853836 -125.689183) (xy 284.823852 -125.741117)
			(xy 284.787346 -125.788693) (xy 284.744941 -125.831098) (xy 284.697365 -125.867604) (xy 284.645431 -125.897588)
			(xy 284.590027 -125.920537) (xy 284.532102 -125.936058) (xy 284.472646 -125.943886) (xy 284.412678 -125.943886)
			(xy 284.353222 -125.936058) (xy 284.295297 -125.920537) (xy 284.239893 -125.897588) (xy 284.187959 -125.867604)
			(xy 284.140383 -125.831098) (xy 284.097978 -125.788693) (xy 284.061472 -125.741117) (xy 284.031488 -125.689183)
			(xy 284.008539 -125.633779) (xy 283.993018 -125.575854) (xy 283.98519 -125.516398) (xy 283.9847 -125.486414)
			(xy 270.425672 -125.486414) (xy 270.425672 -125.494542) (xy 270.425182 -125.524526) (xy 270.417354 -125.583982)
			(xy 270.401833 -125.641907) (xy 270.378884 -125.697311) (xy 270.3489 -125.749245) (xy 270.312394 -125.796821)
			(xy 270.269989 -125.839226) (xy 270.222413 -125.875732) (xy 270.170479 -125.905716) (xy 270.115075 -125.928665)
			(xy 270.05715 -125.944186) (xy 269.997694 -125.952014) (xy 269.937726 -125.952014) (xy 269.87827 -125.944186)
			(xy 269.820345 -125.928665) (xy 269.764941 -125.905716) (xy 269.713007 -125.875732) (xy 269.665431 -125.839226)
			(xy 269.623026 -125.796821) (xy 269.58652 -125.749245) (xy 269.556536 -125.697311) (xy 269.533587 -125.641907)
			(xy 269.518066 -125.583982) (xy 269.510238 -125.524526) (xy 269.509748 -125.494542) (xy 168.800647 -125.494542)
			(xy 168.80029 -125.516398) (xy 168.792462 -125.575854) (xy 168.776941 -125.633779) (xy 168.753992 -125.689183)
			(xy 168.724008 -125.741117) (xy 168.687502 -125.788693) (xy 168.645097 -125.831098) (xy 168.597521 -125.867604)
			(xy 168.545587 -125.897588) (xy 168.490183 -125.920537) (xy 168.432258 -125.936058) (xy 168.372802 -125.943886)
			(xy 168.312834 -125.943886) (xy 168.253378 -125.936058) (xy 168.195453 -125.920537) (xy 168.140049 -125.897588)
			(xy 168.088115 -125.867604) (xy 168.040539 -125.831098) (xy 167.998134 -125.788693) (xy 167.961628 -125.741117)
			(xy 167.931644 -125.689183) (xy 167.908695 -125.633779) (xy 167.893174 -125.575854) (xy 167.885346 -125.516398)
			(xy 167.884856 -125.486414) (xy 154.325828 -125.486414) (xy 154.325828 -125.494542) (xy 154.325338 -125.524526)
			(xy 154.31751 -125.583982) (xy 154.301989 -125.641907) (xy 154.27904 -125.697311) (xy 154.249056 -125.749245)
			(xy 154.21255 -125.796821) (xy 154.170145 -125.839226) (xy 154.122569 -125.875732) (xy 154.070635 -125.905716)
			(xy 154.015231 -125.928665) (xy 153.957306 -125.944186) (xy 153.89785 -125.952014) (xy 153.837882 -125.952014)
			(xy 153.778426 -125.944186) (xy 153.720501 -125.928665) (xy 153.665097 -125.905716) (xy 153.613163 -125.875732)
			(xy 153.565587 -125.839226) (xy 153.523182 -125.796821) (xy 153.486676 -125.749245) (xy 153.456692 -125.697311)
			(xy 153.433743 -125.641907) (xy 153.418222 -125.583982) (xy 153.410394 -125.524526) (xy 153.409904 -125.494542)
			(xy 52.700295 -125.494542) (xy 52.699938 -125.516382) (xy 52.692115 -125.575804) (xy 52.676602 -125.633697)
			(xy 52.653666 -125.68907) (xy 52.623699 -125.740976) (xy 52.587212 -125.788526) (xy 52.544832 -125.830906)
			(xy 52.497282 -125.867393) (xy 52.445376 -125.89736) (xy 52.390003 -125.920296) (xy 52.33211 -125.935809)
			(xy 52.272688 -125.943632) (xy 52.212752 -125.943632) (xy 52.15333 -125.935809) (xy 52.095437 -125.920296)
			(xy 52.040064 -125.89736) (xy 51.988158 -125.867393) (xy 51.940608 -125.830906) (xy 51.898228 -125.788526)
			(xy 51.861741 -125.740976) (xy 51.831774 -125.68907) (xy 51.808838 -125.633697) (xy 51.793325 -125.575804)
			(xy 51.785502 -125.516382) (xy 51.785012 -125.486414) (xy 38.225476 -125.486414) (xy 38.225476 -125.494542)
			(xy 38.224986 -125.52451) (xy 38.217163 -125.583932) (xy 38.20165 -125.641825) (xy 38.178714 -125.697198)
			(xy 38.148747 -125.749104) (xy 38.11226 -125.796654) (xy 38.06988 -125.839034) (xy 38.02233 -125.875521)
			(xy 37.970424 -125.905488) (xy 37.915051 -125.928424) (xy 37.857158 -125.943937) (xy 37.797736 -125.95176)
			(xy 37.7378 -125.95176) (xy 37.678378 -125.943937) (xy 37.620485 -125.928424) (xy 37.565112 -125.905488)
			(xy 37.513206 -125.875521) (xy 37.465656 -125.839034) (xy 37.423276 -125.796654) (xy 37.386789 -125.749104)
			(xy 37.356822 -125.697198) (xy 37.333886 -125.641825) (xy 37.318373 -125.583932) (xy 37.31055 -125.52451)
			(xy 37.31006 -125.494542) (xy 4.308094 -125.494542) (xy 4.308094 -131.297934) (xy 34.667952 -131.297934)
			(xy 34.667952 -130.434334) (xy 34.668442 -130.404366) (xy 34.676265 -130.344944) (xy 34.691778 -130.287051)
			(xy 34.714714 -130.231678) (xy 34.744681 -130.179772) (xy 34.781168 -130.132222) (xy 34.823548 -130.089842)
			(xy 34.871098 -130.053355) (xy 34.923004 -130.023388) (xy 34.978377 -130.000452) (xy 35.03627 -129.984939)
			(xy 35.095692 -129.977116) (xy 35.155628 -129.977116) (xy 35.21505 -129.984939) (xy 35.272943 -130.000452)
			(xy 35.328316 -130.023388) (xy 35.380222 -130.053355) (xy 35.427772 -130.089842) (xy 35.470152 -130.132222)
			(xy 35.506639 -130.179772) (xy 35.536606 -130.231678) (xy 35.559542 -130.287051) (xy 35.575055 -130.344944)
			(xy 35.582878 -130.404366) (xy 35.583368 -130.434334) (xy 35.583368 -131.29641) (xy 53.639212 -131.29641)
			(xy 53.639212 -130.43281) (xy 53.639702 -130.402842) (xy 53.647525 -130.34342) (xy 53.663038 -130.285527)
			(xy 53.685974 -130.230154) (xy 53.715941 -130.178248) (xy 53.752428 -130.130698) (xy 53.794808 -130.088318)
			(xy 53.842358 -130.051831) (xy 53.894264 -130.021864) (xy 53.949637 -129.998928) (xy 54.00753 -129.983415)
			(xy 54.066952 -129.975592) (xy 54.126888 -129.975592) (xy 54.18631 -129.983415) (xy 54.244203 -129.998928)
			(xy 54.299576 -130.021864) (xy 54.351482 -130.051831) (xy 54.399032 -130.088318) (xy 54.441412 -130.130698)
			(xy 54.477899 -130.178248) (xy 54.507866 -130.230154) (xy 54.530802 -130.285527) (xy 54.546315 -130.34342)
			(xy 54.554138 -130.402842) (xy 54.554628 -130.43281) (xy 54.554628 -130.777234) (xy 66.599308 -130.777234)
			(xy 66.599308 -129.913634) (xy 66.599798 -129.88365) (xy 66.607626 -129.824194) (xy 66.623147 -129.766269)
			(xy 66.646096 -129.710865) (xy 66.67608 -129.658931) (xy 66.712586 -129.611355) (xy 66.754991 -129.56895)
			(xy 66.802567 -129.532444) (xy 66.854501 -129.50246) (xy 66.909905 -129.479511) (xy 66.96783 -129.46399)
			(xy 67.027286 -129.456162) (xy 67.087254 -129.456162) (xy 67.14671 -129.46399) (xy 67.204635 -129.479511)
			(xy 67.260039 -129.50246) (xy 67.311973 -129.532444) (xy 67.359549 -129.56895) (xy 67.401954 -129.611355)
			(xy 67.43846 -129.658931) (xy 67.468444 -129.710865) (xy 67.491393 -129.766269) (xy 67.506914 -129.824194)
			(xy 67.514742 -129.88365) (xy 67.515232 -129.913634) (xy 67.515232 -130.769106) (xy 81.07426 -130.769106)
			(xy 81.07426 -129.905506) (xy 81.07475 -129.875522) (xy 81.082578 -129.816066) (xy 81.098099 -129.758141)
			(xy 81.121048 -129.702737) (xy 81.151032 -129.650803) (xy 81.187538 -129.603227) (xy 81.229943 -129.560822)
			(xy 81.277519 -129.524316) (xy 81.329453 -129.494332) (xy 81.384857 -129.471383) (xy 81.442782 -129.455862)
			(xy 81.502238 -129.448034) (xy 81.562206 -129.448034) (xy 81.621662 -129.455862) (xy 81.679587 -129.471383)
			(xy 81.734991 -129.494332) (xy 81.786925 -129.524316) (xy 81.834501 -129.560822) (xy 81.876906 -129.603227)
			(xy 81.913412 -129.650803) (xy 81.943396 -129.702737) (xy 81.966345 -129.758141) (xy 81.981866 -129.816066)
			(xy 81.989694 -129.875522) (xy 81.990184 -129.905506) (xy 81.990184 -130.769106) (xy 81.989694 -130.79909)
			(xy 81.981866 -130.858546) (xy 81.966345 -130.916471) (xy 81.943396 -130.971875) (xy 81.913412 -131.023809)
			(xy 81.876906 -131.071385) (xy 81.834501 -131.11379) (xy 81.786925 -131.150296) (xy 81.734991 -131.18028)
			(xy 81.679587 -131.203229) (xy 81.621662 -131.21875) (xy 81.562206 -131.226578) (xy 81.502238 -131.226578)
			(xy 81.442782 -131.21875) (xy 81.384857 -131.203229) (xy 81.329453 -131.18028) (xy 81.277519 -131.150296)
			(xy 81.229943 -131.11379) (xy 81.187538 -131.071385) (xy 81.151032 -131.023809) (xy 81.121048 -130.971875)
			(xy 81.098099 -130.916471) (xy 81.082578 -130.858546) (xy 81.07475 -130.79909) (xy 81.07426 -130.769106)
			(xy 67.515232 -130.769106) (xy 67.515232 -130.777234) (xy 67.514742 -130.807218) (xy 67.506914 -130.866674)
			(xy 67.491393 -130.924599) (xy 67.468444 -130.980003) (xy 67.43846 -131.031937) (xy 67.401954 -131.079513)
			(xy 67.359549 -131.121918) (xy 67.311973 -131.158424) (xy 67.260039 -131.188408) (xy 67.204635 -131.211357)
			(xy 67.14671 -131.226878) (xy 67.087254 -131.234706) (xy 67.027286 -131.234706) (xy 66.96783 -131.226878)
			(xy 66.909905 -131.211357) (xy 66.854501 -131.188408) (xy 66.802567 -131.158424) (xy 66.754991 -131.121918)
			(xy 66.712586 -131.079513) (xy 66.67608 -131.031937) (xy 66.646096 -130.980003) (xy 66.623147 -130.924599)
			(xy 66.607626 -130.866674) (xy 66.599798 -130.807218) (xy 66.599308 -130.777234) (xy 54.554628 -130.777234)
			(xy 54.554628 -131.29641) (xy 54.554138 -131.326378) (xy 54.546315 -131.3858) (xy 54.530802 -131.443693)
			(xy 54.507866 -131.499066) (xy 54.477899 -131.550972) (xy 54.441412 -131.598522) (xy 54.399032 -131.640902)
			(xy 54.351482 -131.677389) (xy 54.299576 -131.707356) (xy 54.244203 -131.730292) (xy 54.18631 -131.745805)
			(xy 54.126888 -131.753628) (xy 54.066952 -131.753628) (xy 54.00753 -131.745805) (xy 53.949637 -131.730292)
			(xy 53.894264 -131.707356) (xy 53.842358 -131.677389) (xy 53.794808 -131.640902) (xy 53.752428 -131.598522)
			(xy 53.715941 -131.550972) (xy 53.685974 -131.499066) (xy 53.663038 -131.443693) (xy 53.647525 -131.3858)
			(xy 53.639702 -131.326378) (xy 53.639212 -131.29641) (xy 35.583368 -131.29641) (xy 35.583368 -131.297934)
			(xy 35.582878 -131.327902) (xy 35.575055 -131.387324) (xy 35.559542 -131.445217) (xy 35.536606 -131.50059)
			(xy 35.506639 -131.552496) (xy 35.470152 -131.600046) (xy 35.427772 -131.642426) (xy 35.380222 -131.678913)
			(xy 35.328316 -131.70888) (xy 35.272943 -131.731816) (xy 35.21505 -131.747329) (xy 35.155628 -131.755152)
			(xy 35.095692 -131.755152) (xy 35.03627 -131.747329) (xy 34.978377 -131.731816) (xy 34.923004 -131.70888)
			(xy 34.871098 -131.678913) (xy 34.823548 -131.642426) (xy 34.781168 -131.600046) (xy 34.744681 -131.552496)
			(xy 34.714714 -131.50059) (xy 34.691778 -131.445217) (xy 34.676265 -131.387324) (xy 34.668442 -131.327902)
			(xy 34.667952 -131.297934) (xy 4.308094 -131.297934) (xy 4.308094 -133.104382) (xy 37.31006 -133.104382)
			(xy 37.31006 -132.240782) (xy 37.31055 -132.210814) (xy 37.318373 -132.151392) (xy 37.333886 -132.093499)
			(xy 37.356822 -132.038126) (xy 37.386789 -131.98622) (xy 37.423276 -131.93867) (xy 37.465656 -131.89629)
			(xy 37.513206 -131.859803) (xy 37.565112 -131.829836) (xy 37.620485 -131.8069) (xy 37.678378 -131.791387)
			(xy 37.7378 -131.783564) (xy 37.797736 -131.783564) (xy 37.857158 -131.791387) (xy 37.915051 -131.8069)
			(xy 37.970424 -131.829836) (xy 38.02233 -131.859803) (xy 38.06988 -131.89629) (xy 38.11226 -131.93867)
			(xy 38.148747 -131.98622) (xy 38.178714 -132.038126) (xy 38.20165 -132.093499) (xy 38.217163 -132.151392)
			(xy 38.224986 -132.210814) (xy 38.225476 -132.240782) (xy 38.225476 -133.096508) (xy 51.785012 -133.096508)
			(xy 51.785012 -132.232908) (xy 51.785502 -132.20294) (xy 51.793325 -132.143518) (xy 51.808838 -132.085625)
			(xy 51.831774 -132.030252) (xy 51.861741 -131.978346) (xy 51.898228 -131.930796) (xy 51.940608 -131.888416)
			(xy 51.988158 -131.851929) (xy 52.040064 -131.821962) (xy 52.095437 -131.799026) (xy 52.15333 -131.783513)
			(xy 52.212752 -131.77569) (xy 52.272688 -131.77569) (xy 52.33211 -131.783513) (xy 52.390003 -131.799026)
			(xy 52.445376 -131.821962) (xy 52.497282 -131.851929) (xy 52.544832 -131.888416) (xy 52.587212 -131.930796)
			(xy 52.623699 -131.978346) (xy 52.653666 -132.030252) (xy 52.676602 -132.085625) (xy 52.692115 -132.143518)
			(xy 52.699938 -132.20294) (xy 52.700428 -132.232908) (xy 52.700428 -132.577332) (xy 64.745108 -132.577332)
			(xy 64.745108 -131.713732) (xy 64.745598 -131.683748) (xy 64.753426 -131.624292) (xy 64.768947 -131.566367)
			(xy 64.791896 -131.510963) (xy 64.82188 -131.459029) (xy 64.858386 -131.411453) (xy 64.900791 -131.369048)
			(xy 64.948367 -131.332542) (xy 65.000301 -131.302558) (xy 65.055705 -131.279609) (xy 65.11363 -131.264088)
			(xy 65.173086 -131.25626) (xy 65.233054 -131.25626) (xy 65.29251 -131.264088) (xy 65.350435 -131.279609)
			(xy 65.405839 -131.302558) (xy 65.457773 -131.332542) (xy 65.505349 -131.369048) (xy 65.547754 -131.411453)
			(xy 65.58426 -131.459029) (xy 65.614244 -131.510963) (xy 65.637193 -131.566367) (xy 65.652714 -131.624292)
			(xy 65.660542 -131.683748) (xy 65.661032 -131.713732) (xy 65.661032 -132.575808) (xy 83.716368 -132.575808)
			(xy 83.716368 -131.712208) (xy 83.716858 -131.682224) (xy 83.724686 -131.622768) (xy 83.740207 -131.564843)
			(xy 83.763156 -131.509439) (xy 83.79314 -131.457505) (xy 83.829646 -131.409929) (xy 83.872051 -131.367524)
			(xy 83.919627 -131.331018) (xy 83.971561 -131.301034) (xy 84.026965 -131.278085) (xy 84.08489 -131.262564)
			(xy 84.144346 -131.254736) (xy 84.204314 -131.254736) (xy 84.26377 -131.262564) (xy 84.321695 -131.278085)
			(xy 84.369615 -131.297934) (xy 150.767796 -131.297934) (xy 150.767796 -130.434334) (xy 150.768286 -130.40435)
			(xy 150.776114 -130.344894) (xy 150.791635 -130.286969) (xy 150.814584 -130.231565) (xy 150.844568 -130.179631)
			(xy 150.881074 -130.132055) (xy 150.923479 -130.08965) (xy 150.971055 -130.053144) (xy 151.022989 -130.02316)
			(xy 151.078393 -130.000211) (xy 151.136318 -129.98469) (xy 151.195774 -129.976862) (xy 151.255742 -129.976862)
			(xy 151.315198 -129.98469) (xy 151.373123 -130.000211) (xy 151.428527 -130.02316) (xy 151.480461 -130.053144)
			(xy 151.528037 -130.08965) (xy 151.570442 -130.132055) (xy 151.606948 -130.179631) (xy 151.636932 -130.231565)
			(xy 151.659881 -130.286969) (xy 151.675402 -130.344894) (xy 151.68323 -130.40435) (xy 151.68372 -130.434334)
			(xy 151.68372 -131.29641) (xy 169.739056 -131.29641) (xy 169.739056 -130.43281) (xy 169.739546 -130.402826)
			(xy 169.747374 -130.34337) (xy 169.762895 -130.285445) (xy 169.785844 -130.230041) (xy 169.815828 -130.178107)
			(xy 169.852334 -130.130531) (xy 169.894739 -130.088126) (xy 169.942315 -130.05162) (xy 169.994249 -130.021636)
			(xy 170.049653 -129.998687) (xy 170.107578 -129.983166) (xy 170.167034 -129.975338) (xy 170.227002 -129.975338)
			(xy 170.286458 -129.983166) (xy 170.344383 -129.998687) (xy 170.399787 -130.021636) (xy 170.451721 -130.05162)
			(xy 170.499297 -130.088126) (xy 170.541702 -130.130531) (xy 170.578208 -130.178107) (xy 170.608192 -130.230041)
			(xy 170.631141 -130.285445) (xy 170.646662 -130.34337) (xy 170.65449 -130.402826) (xy 170.65498 -130.43281)
			(xy 170.65498 -130.777234) (xy 182.69966 -130.777234) (xy 182.69966 -129.913634) (xy 182.70015 -129.883666)
			(xy 182.707973 -129.824244) (xy 182.723486 -129.766351) (xy 182.746422 -129.710978) (xy 182.776389 -129.659072)
			(xy 182.812876 -129.611522) (xy 182.855256 -129.569142) (xy 182.902806 -129.532655) (xy 182.954712 -129.502688)
			(xy 183.010085 -129.479752) (xy 183.067978 -129.464239) (xy 183.1274 -129.456416) (xy 183.187336 -129.456416)
			(xy 183.246758 -129.464239) (xy 183.304651 -129.479752) (xy 183.360024 -129.502688) (xy 183.41193 -129.532655)
			(xy 183.45948 -129.569142) (xy 183.50186 -129.611522) (xy 183.538347 -129.659072) (xy 183.568314 -129.710978)
			(xy 183.59125 -129.766351) (xy 183.606763 -129.824244) (xy 183.614586 -129.883666) (xy 183.615076 -129.913634)
			(xy 183.615076 -130.769106) (xy 197.174612 -130.769106) (xy 197.174612 -129.905506) (xy 197.175102 -129.875538)
			(xy 197.182925 -129.816116) (xy 197.198438 -129.758223) (xy 197.221374 -129.70285) (xy 197.251341 -129.650944)
			(xy 197.287828 -129.603394) (xy 197.330208 -129.561014) (xy 197.377758 -129.524527) (xy 197.429664 -129.49456)
			(xy 197.485037 -129.471624) (xy 197.54293 -129.456111) (xy 197.602352 -129.448288) (xy 197.662288 -129.448288)
			(xy 197.72171 -129.456111) (xy 197.779603 -129.471624) (xy 197.834976 -129.49456) (xy 197.886882 -129.524527)
			(xy 197.934432 -129.561014) (xy 197.976812 -129.603394) (xy 198.013299 -129.650944) (xy 198.043266 -129.70285)
			(xy 198.066202 -129.758223) (xy 198.081715 -129.816116) (xy 198.089538 -129.875538) (xy 198.090028 -129.905506)
			(xy 198.090028 -130.769106) (xy 198.089538 -130.799074) (xy 198.081715 -130.858496) (xy 198.066202 -130.916389)
			(xy 198.043266 -130.971762) (xy 198.013299 -131.023668) (xy 197.976812 -131.071218) (xy 197.934432 -131.113598)
			(xy 197.886882 -131.150085) (xy 197.834976 -131.180052) (xy 197.779603 -131.202988) (xy 197.72171 -131.218501)
			(xy 197.662288 -131.226324) (xy 197.602352 -131.226324) (xy 197.54293 -131.218501) (xy 197.485037 -131.202988)
			(xy 197.429664 -131.180052) (xy 197.377758 -131.150085) (xy 197.330208 -131.113598) (xy 197.287828 -131.071218)
			(xy 197.251341 -131.023668) (xy 197.221374 -130.971762) (xy 197.198438 -130.916389) (xy 197.182925 -130.858496)
			(xy 197.175102 -130.799074) (xy 197.174612 -130.769106) (xy 183.615076 -130.769106) (xy 183.615076 -130.777234)
			(xy 183.614586 -130.807202) (xy 183.606763 -130.866624) (xy 183.59125 -130.924517) (xy 183.568314 -130.97989)
			(xy 183.538347 -131.031796) (xy 183.50186 -131.079346) (xy 183.45948 -131.121726) (xy 183.41193 -131.158213)
			(xy 183.360024 -131.18818) (xy 183.304651 -131.211116) (xy 183.246758 -131.226629) (xy 183.187336 -131.234452)
			(xy 183.1274 -131.234452) (xy 183.067978 -131.226629) (xy 183.010085 -131.211116) (xy 182.954712 -131.18818)
			(xy 182.902806 -131.158213) (xy 182.855256 -131.121726) (xy 182.812876 -131.079346) (xy 182.776389 -131.031796)
			(xy 182.746422 -130.97989) (xy 182.723486 -130.924517) (xy 182.707973 -130.866624) (xy 182.70015 -130.807202)
			(xy 182.69966 -130.777234) (xy 170.65498 -130.777234) (xy 170.65498 -131.29641) (xy 170.65449 -131.326394)
			(xy 170.646662 -131.38585) (xy 170.631141 -131.443775) (xy 170.608192 -131.499179) (xy 170.578208 -131.551113)
			(xy 170.541702 -131.598689) (xy 170.499297 -131.641094) (xy 170.451721 -131.6776) (xy 170.399787 -131.707584)
			(xy 170.344383 -131.730533) (xy 170.286458 -131.746054) (xy 170.227002 -131.753882) (xy 170.167034 -131.753882)
			(xy 170.107578 -131.746054) (xy 170.049653 -131.730533) (xy 169.994249 -131.707584) (xy 169.942315 -131.6776)
			(xy 169.894739 -131.641094) (xy 169.852334 -131.598689) (xy 169.815828 -131.551113) (xy 169.785844 -131.499179)
			(xy 169.762895 -131.443775) (xy 169.747374 -131.38585) (xy 169.739546 -131.326394) (xy 169.739056 -131.29641)
			(xy 151.68372 -131.29641) (xy 151.68372 -131.297934) (xy 151.68323 -131.327918) (xy 151.675402 -131.387374)
			(xy 151.659881 -131.445299) (xy 151.636932 -131.500703) (xy 151.606948 -131.552637) (xy 151.570442 -131.600213)
			(xy 151.528037 -131.642618) (xy 151.480461 -131.679124) (xy 151.428527 -131.709108) (xy 151.373123 -131.732057)
			(xy 151.315198 -131.747578) (xy 151.255742 -131.755406) (xy 151.195774 -131.755406) (xy 151.136318 -131.747578)
			(xy 151.078393 -131.732057) (xy 151.022989 -131.709108) (xy 150.971055 -131.679124) (xy 150.923479 -131.642618)
			(xy 150.881074 -131.600213) (xy 150.844568 -131.552637) (xy 150.814584 -131.500703) (xy 150.791635 -131.445299)
			(xy 150.776114 -131.387374) (xy 150.768286 -131.327918) (xy 150.767796 -131.297934) (xy 84.369615 -131.297934)
			(xy 84.377099 -131.301034) (xy 84.429033 -131.331018) (xy 84.476609 -131.367524) (xy 84.519014 -131.409929)
			(xy 84.55552 -131.457505) (xy 84.585504 -131.509439) (xy 84.608453 -131.564843) (xy 84.623974 -131.622768)
			(xy 84.631802 -131.682224) (xy 84.632292 -131.712208) (xy 84.632292 -132.575808) (xy 84.631802 -132.605792)
			(xy 84.623974 -132.665248) (xy 84.608453 -132.723173) (xy 84.585504 -132.778577) (xy 84.55552 -132.830511)
			(xy 84.519014 -132.878087) (xy 84.476609 -132.920492) (xy 84.429033 -132.956998) (xy 84.377099 -132.986982)
			(xy 84.321695 -133.009931) (xy 84.26377 -133.025452) (xy 84.204314 -133.03328) (xy 84.144346 -133.03328)
			(xy 84.08489 -133.025452) (xy 84.026965 -133.009931) (xy 83.971561 -132.986982) (xy 83.919627 -132.956998)
			(xy 83.872051 -132.920492) (xy 83.829646 -132.878087) (xy 83.79314 -132.830511) (xy 83.763156 -132.778577)
			(xy 83.740207 -132.723173) (xy 83.724686 -132.665248) (xy 83.716858 -132.605792) (xy 83.716368 -132.575808)
			(xy 65.661032 -132.575808) (xy 65.661032 -132.577332) (xy 65.660542 -132.607316) (xy 65.652714 -132.666772)
			(xy 65.637193 -132.724697) (xy 65.614244 -132.780101) (xy 65.58426 -132.832035) (xy 65.547754 -132.879611)
			(xy 65.505349 -132.922016) (xy 65.457773 -132.958522) (xy 65.405839 -132.988506) (xy 65.350435 -133.011455)
			(xy 65.29251 -133.026976) (xy 65.233054 -133.034804) (xy 65.173086 -133.034804) (xy 65.11363 -133.026976)
			(xy 65.055705 -133.011455) (xy 65.000301 -132.988506) (xy 64.948367 -132.958522) (xy 64.900791 -132.922016)
			(xy 64.858386 -132.879611) (xy 64.82188 -132.832035) (xy 64.791896 -132.780101) (xy 64.768947 -132.724697)
			(xy 64.753426 -132.666772) (xy 64.745598 -132.607316) (xy 64.745108 -132.577332) (xy 52.700428 -132.577332)
			(xy 52.700428 -133.096508) (xy 52.699938 -133.126476) (xy 52.692115 -133.185898) (xy 52.676602 -133.243791)
			(xy 52.653666 -133.299164) (xy 52.623699 -133.35107) (xy 52.587212 -133.39862) (xy 52.544832 -133.441)
			(xy 52.497282 -133.477487) (xy 52.445376 -133.507454) (xy 52.390003 -133.53039) (xy 52.33211 -133.545903)
			(xy 52.272688 -133.553726) (xy 52.212752 -133.553726) (xy 52.15333 -133.545903) (xy 52.095437 -133.53039)
			(xy 52.040064 -133.507454) (xy 51.988158 -133.477487) (xy 51.940608 -133.441) (xy 51.898228 -133.39862)
			(xy 51.861741 -133.35107) (xy 51.831774 -133.299164) (xy 51.808838 -133.243791) (xy 51.793325 -133.185898)
			(xy 51.785502 -133.126476) (xy 51.785012 -133.096508) (xy 38.225476 -133.096508) (xy 38.225476 -133.104382)
			(xy 38.224986 -133.13435) (xy 38.217163 -133.193772) (xy 38.20165 -133.251665) (xy 38.178714 -133.307038)
			(xy 38.148747 -133.358944) (xy 38.11226 -133.406494) (xy 38.06988 -133.448874) (xy 38.02233 -133.485361)
			(xy 37.970424 -133.515328) (xy 37.915051 -133.538264) (xy 37.857158 -133.553777) (xy 37.797736 -133.5616)
			(xy 37.7378 -133.5616) (xy 37.678378 -133.553777) (xy 37.620485 -133.538264) (xy 37.565112 -133.515328)
			(xy 37.513206 -133.485361) (xy 37.465656 -133.448874) (xy 37.423276 -133.406494) (xy 37.386789 -133.358944)
			(xy 37.356822 -133.307038) (xy 37.333886 -133.251665) (xy 37.318373 -133.193772) (xy 37.31055 -133.13435)
			(xy 37.31006 -133.104382) (xy 4.308094 -133.104382) (xy 4.308094 -134.897876) (xy 34.667952 -134.897876)
			(xy 34.667952 -134.034276) (xy 34.668442 -134.004308) (xy 34.676265 -133.944886) (xy 34.691778 -133.886993)
			(xy 34.714714 -133.83162) (xy 34.744681 -133.779714) (xy 34.781168 -133.732164) (xy 34.823548 -133.689784)
			(xy 34.871098 -133.653297) (xy 34.923004 -133.62333) (xy 34.978377 -133.600394) (xy 35.03627 -133.584881)
			(xy 35.095692 -133.577058) (xy 35.155628 -133.577058) (xy 35.21505 -133.584881) (xy 35.272943 -133.600394)
			(xy 35.328316 -133.62333) (xy 35.380222 -133.653297) (xy 35.427772 -133.689784) (xy 35.470152 -133.732164)
			(xy 35.506639 -133.779714) (xy 35.536606 -133.83162) (xy 35.559542 -133.886993) (xy 35.575055 -133.944886)
			(xy 35.582878 -134.004308) (xy 35.583368 -134.034276) (xy 35.583368 -134.896352) (xy 53.639212 -134.896352)
			(xy 53.639212 -134.032752) (xy 53.639702 -134.002784) (xy 53.647525 -133.943362) (xy 53.663038 -133.885469)
			(xy 53.685974 -133.830096) (xy 53.715941 -133.77819) (xy 53.752428 -133.73064) (xy 53.794808 -133.68826)
			(xy 53.842358 -133.651773) (xy 53.894264 -133.621806) (xy 53.949637 -133.59887) (xy 54.00753 -133.583357)
			(xy 54.066952 -133.575534) (xy 54.126888 -133.575534) (xy 54.18631 -133.583357) (xy 54.244203 -133.59887)
			(xy 54.299576 -133.621806) (xy 54.351482 -133.651773) (xy 54.399032 -133.68826) (xy 54.441412 -133.73064)
			(xy 54.477899 -133.77819) (xy 54.507866 -133.830096) (xy 54.530802 -133.885469) (xy 54.546315 -133.943362)
			(xy 54.554138 -134.002784) (xy 54.554628 -134.032752) (xy 54.554628 -134.377176) (xy 66.599308 -134.377176)
			(xy 66.599308 -133.513576) (xy 66.599798 -133.483592) (xy 66.607626 -133.424136) (xy 66.623147 -133.366211)
			(xy 66.646096 -133.310807) (xy 66.67608 -133.258873) (xy 66.712586 -133.211297) (xy 66.754991 -133.168892)
			(xy 66.802567 -133.132386) (xy 66.854501 -133.102402) (xy 66.909905 -133.079453) (xy 66.96783 -133.063932)
			(xy 67.027286 -133.056104) (xy 67.087254 -133.056104) (xy 67.14671 -133.063932) (xy 67.204635 -133.079453)
			(xy 67.260039 -133.102402) (xy 67.311973 -133.132386) (xy 67.359549 -133.168892) (xy 67.401954 -133.211297)
			(xy 67.43846 -133.258873) (xy 67.468444 -133.310807) (xy 67.491393 -133.366211) (xy 67.506914 -133.424136)
			(xy 67.514742 -133.483592) (xy 67.515232 -133.513576) (xy 67.515232 -134.369302) (xy 81.07426 -134.369302)
			(xy 81.07426 -133.505702) (xy 81.07475 -133.475718) (xy 81.082578 -133.416262) (xy 81.098099 -133.358337)
			(xy 81.121048 -133.302933) (xy 81.151032 -133.250999) (xy 81.187538 -133.203423) (xy 81.229943 -133.161018)
			(xy 81.277519 -133.124512) (xy 81.329453 -133.094528) (xy 81.384857 -133.071579) (xy 81.442782 -133.056058)
			(xy 81.502238 -133.04823) (xy 81.562206 -133.04823) (xy 81.621662 -133.056058) (xy 81.679587 -133.071579)
			(xy 81.734991 -133.094528) (xy 81.752059 -133.104382) (xy 153.409904 -133.104382) (xy 153.409904 -132.240782)
			(xy 153.410394 -132.210798) (xy 153.418222 -132.151342) (xy 153.433743 -132.093417) (xy 153.456692 -132.038013)
			(xy 153.486676 -131.986079) (xy 153.523182 -131.938503) (xy 153.565587 -131.896098) (xy 153.613163 -131.859592)
			(xy 153.665097 -131.829608) (xy 153.720501 -131.806659) (xy 153.778426 -131.791138) (xy 153.837882 -131.78331)
			(xy 153.89785 -131.78331) (xy 153.957306 -131.791138) (xy 154.015231 -131.806659) (xy 154.070635 -131.829608)
			(xy 154.122569 -131.859592) (xy 154.170145 -131.896098) (xy 154.21255 -131.938503) (xy 154.249056 -131.986079)
			(xy 154.27904 -132.038013) (xy 154.301989 -132.093417) (xy 154.31751 -132.151342) (xy 154.325338 -132.210798)
			(xy 154.325828 -132.240782) (xy 154.325828 -133.096508) (xy 167.884856 -133.096508) (xy 167.884856 -132.232908)
			(xy 167.885346 -132.202924) (xy 167.893174 -132.143468) (xy 167.908695 -132.085543) (xy 167.931644 -132.030139)
			(xy 167.961628 -131.978205) (xy 167.998134 -131.930629) (xy 168.040539 -131.888224) (xy 168.088115 -131.851718)
			(xy 168.140049 -131.821734) (xy 168.195453 -131.798785) (xy 168.253378 -131.783264) (xy 168.312834 -131.775436)
			(xy 168.372802 -131.775436) (xy 168.432258 -131.783264) (xy 168.490183 -131.798785) (xy 168.545587 -131.821734)
			(xy 168.597521 -131.851718) (xy 168.645097 -131.888224) (xy 168.687502 -131.930629) (xy 168.724008 -131.978205)
			(xy 168.753992 -132.030139) (xy 168.776941 -132.085543) (xy 168.792462 -132.143468) (xy 168.80029 -132.202924)
			(xy 168.80078 -132.232908) (xy 168.80078 -132.577332) (xy 180.84546 -132.577332) (xy 180.84546 -131.713732)
			(xy 180.84595 -131.683764) (xy 180.853773 -131.624342) (xy 180.869286 -131.566449) (xy 180.892222 -131.511076)
			(xy 180.922189 -131.45917) (xy 180.958676 -131.41162) (xy 181.001056 -131.36924) (xy 181.048606 -131.332753)
			(xy 181.100512 -131.302786) (xy 181.155885 -131.27985) (xy 181.213778 -131.264337) (xy 181.2732 -131.256514)
			(xy 181.333136 -131.256514) (xy 181.392558 -131.264337) (xy 181.450451 -131.27985) (xy 181.505824 -131.302786)
			(xy 181.55773 -131.332753) (xy 181.60528 -131.36924) (xy 181.64766 -131.41162) (xy 181.684147 -131.45917)
			(xy 181.714114 -131.511076) (xy 181.73705 -131.566449) (xy 181.752563 -131.624342) (xy 181.760386 -131.683764)
			(xy 181.760876 -131.713732) (xy 181.760876 -132.575808) (xy 199.81672 -132.575808) (xy 199.81672 -131.712208)
			(xy 199.81721 -131.68224) (xy 199.825033 -131.622818) (xy 199.840546 -131.564925) (xy 199.863482 -131.509552)
			(xy 199.893449 -131.457646) (xy 199.929936 -131.410096) (xy 199.972316 -131.367716) (xy 200.019866 -131.331229)
			(xy 200.071772 -131.301262) (xy 200.127145 -131.278326) (xy 200.185038 -131.262813) (xy 200.24446 -131.25499)
			(xy 200.304396 -131.25499) (xy 200.363818 -131.262813) (xy 200.421711 -131.278326) (xy 200.469049 -131.297934)
			(xy 266.86764 -131.297934) (xy 266.86764 -130.434334) (xy 266.86813 -130.40435) (xy 266.875958 -130.344894)
			(xy 266.891479 -130.286969) (xy 266.914428 -130.231565) (xy 266.944412 -130.179631) (xy 266.980918 -130.132055)
			(xy 267.023323 -130.08965) (xy 267.070899 -130.053144) (xy 267.122833 -130.02316) (xy 267.178237 -130.000211)
			(xy 267.236162 -129.98469) (xy 267.295618 -129.976862) (xy 267.355586 -129.976862) (xy 267.415042 -129.98469)
			(xy 267.472967 -130.000211) (xy 267.528371 -130.02316) (xy 267.580305 -130.053144) (xy 267.627881 -130.08965)
			(xy 267.670286 -130.132055) (xy 267.706792 -130.179631) (xy 267.736776 -130.231565) (xy 267.759725 -130.286969)
			(xy 267.775246 -130.344894) (xy 267.783074 -130.40435) (xy 267.783564 -130.434334) (xy 267.783564 -131.29641)
			(xy 285.8389 -131.29641) (xy 285.8389 -130.43281) (xy 285.83939 -130.402826) (xy 285.847218 -130.34337)
			(xy 285.862739 -130.285445) (xy 285.885688 -130.230041) (xy 285.915672 -130.178107) (xy 285.952178 -130.130531)
			(xy 285.994583 -130.088126) (xy 286.042159 -130.05162) (xy 286.094093 -130.021636) (xy 286.149497 -129.998687)
			(xy 286.207422 -129.983166) (xy 286.266878 -129.975338) (xy 286.326846 -129.975338) (xy 286.386302 -129.983166)
			(xy 286.444227 -129.998687) (xy 286.499631 -130.021636) (xy 286.551565 -130.05162) (xy 286.599141 -130.088126)
			(xy 286.641546 -130.130531) (xy 286.678052 -130.178107) (xy 286.708036 -130.230041) (xy 286.730985 -130.285445)
			(xy 286.746506 -130.34337) (xy 286.754334 -130.402826) (xy 286.754824 -130.43281) (xy 286.754824 -130.777234)
			(xy 298.799504 -130.777234) (xy 298.799504 -129.913634) (xy 298.799994 -129.883666) (xy 298.807817 -129.824244)
			(xy 298.82333 -129.766351) (xy 298.846266 -129.710978) (xy 298.876233 -129.659072) (xy 298.91272 -129.611522)
			(xy 298.9551 -129.569142) (xy 299.00265 -129.532655) (xy 299.054556 -129.502688) (xy 299.109929 -129.479752)
			(xy 299.167822 -129.464239) (xy 299.227244 -129.456416) (xy 299.28718 -129.456416) (xy 299.346602 -129.464239)
			(xy 299.404495 -129.479752) (xy 299.459868 -129.502688) (xy 299.511774 -129.532655) (xy 299.559324 -129.569142)
			(xy 299.601704 -129.611522) (xy 299.638191 -129.659072) (xy 299.668158 -129.710978) (xy 299.691094 -129.766351)
			(xy 299.706607 -129.824244) (xy 299.71443 -129.883666) (xy 299.71492 -129.913634) (xy 299.71492 -130.769106)
			(xy 313.274456 -130.769106) (xy 313.274456 -129.905506) (xy 313.274946 -129.875538) (xy 313.282769 -129.816116)
			(xy 313.298282 -129.758223) (xy 313.321218 -129.70285) (xy 313.351185 -129.650944) (xy 313.387672 -129.603394)
			(xy 313.430052 -129.561014) (xy 313.477602 -129.524527) (xy 313.529508 -129.49456) (xy 313.584881 -129.471624)
			(xy 313.642774 -129.456111) (xy 313.702196 -129.448288) (xy 313.762132 -129.448288) (xy 313.821554 -129.456111)
			(xy 313.879447 -129.471624) (xy 313.93482 -129.49456) (xy 313.986726 -129.524527) (xy 314.034276 -129.561014)
			(xy 314.076656 -129.603394) (xy 314.113143 -129.650944) (xy 314.14311 -129.70285) (xy 314.166046 -129.758223)
			(xy 314.181559 -129.816116) (xy 314.189382 -129.875538) (xy 314.189872 -129.905506) (xy 314.189872 -130.769106)
			(xy 314.189382 -130.799074) (xy 314.181559 -130.858496) (xy 314.166046 -130.916389) (xy 314.14311 -130.971762)
			(xy 314.113143 -131.023668) (xy 314.076656 -131.071218) (xy 314.034276 -131.113598) (xy 313.986726 -131.150085)
			(xy 313.93482 -131.180052) (xy 313.879447 -131.202988) (xy 313.821554 -131.218501) (xy 313.762132 -131.226324)
			(xy 313.702196 -131.226324) (xy 313.642774 -131.218501) (xy 313.584881 -131.202988) (xy 313.529508 -131.180052)
			(xy 313.477602 -131.150085) (xy 313.430052 -131.113598) (xy 313.387672 -131.071218) (xy 313.351185 -131.023668)
			(xy 313.321218 -130.971762) (xy 313.298282 -130.916389) (xy 313.282769 -130.858496) (xy 313.274946 -130.799074)
			(xy 313.274456 -130.769106) (xy 299.71492 -130.769106) (xy 299.71492 -130.777234) (xy 299.71443 -130.807202)
			(xy 299.706607 -130.866624) (xy 299.691094 -130.924517) (xy 299.668158 -130.97989) (xy 299.638191 -131.031796)
			(xy 299.601704 -131.079346) (xy 299.559324 -131.121726) (xy 299.511774 -131.158213) (xy 299.459868 -131.18818)
			(xy 299.404495 -131.211116) (xy 299.346602 -131.226629) (xy 299.28718 -131.234452) (xy 299.227244 -131.234452)
			(xy 299.167822 -131.226629) (xy 299.109929 -131.211116) (xy 299.054556 -131.18818) (xy 299.00265 -131.158213)
			(xy 298.9551 -131.121726) (xy 298.91272 -131.079346) (xy 298.876233 -131.031796) (xy 298.846266 -130.97989)
			(xy 298.82333 -130.924517) (xy 298.807817 -130.866624) (xy 298.799994 -130.807202) (xy 298.799504 -130.777234)
			(xy 286.754824 -130.777234) (xy 286.754824 -131.29641) (xy 286.754334 -131.326394) (xy 286.746506 -131.38585)
			(xy 286.730985 -131.443775) (xy 286.708036 -131.499179) (xy 286.678052 -131.551113) (xy 286.641546 -131.598689)
			(xy 286.599141 -131.641094) (xy 286.551565 -131.6776) (xy 286.499631 -131.707584) (xy 286.444227 -131.730533)
			(xy 286.386302 -131.746054) (xy 286.326846 -131.753882) (xy 286.266878 -131.753882) (xy 286.207422 -131.746054)
			(xy 286.149497 -131.730533) (xy 286.094093 -131.707584) (xy 286.042159 -131.6776) (xy 285.994583 -131.641094)
			(xy 285.952178 -131.598689) (xy 285.915672 -131.551113) (xy 285.885688 -131.499179) (xy 285.862739 -131.443775)
			(xy 285.847218 -131.38585) (xy 285.83939 -131.326394) (xy 285.8389 -131.29641) (xy 267.783564 -131.29641)
			(xy 267.783564 -131.297934) (xy 267.783074 -131.327918) (xy 267.775246 -131.387374) (xy 267.759725 -131.445299)
			(xy 267.736776 -131.500703) (xy 267.706792 -131.552637) (xy 267.670286 -131.600213) (xy 267.627881 -131.642618)
			(xy 267.580305 -131.679124) (xy 267.528371 -131.709108) (xy 267.472967 -131.732057) (xy 267.415042 -131.747578)
			(xy 267.355586 -131.755406) (xy 267.295618 -131.755406) (xy 267.236162 -131.747578) (xy 267.178237 -131.732057)
			(xy 267.122833 -131.709108) (xy 267.070899 -131.679124) (xy 267.023323 -131.642618) (xy 266.980918 -131.600213)
			(xy 266.944412 -131.552637) (xy 266.914428 -131.500703) (xy 266.891479 -131.445299) (xy 266.875958 -131.387374)
			(xy 266.86813 -131.327918) (xy 266.86764 -131.297934) (xy 200.469049 -131.297934) (xy 200.477084 -131.301262)
			(xy 200.52899 -131.331229) (xy 200.57654 -131.367716) (xy 200.61892 -131.410096) (xy 200.655407 -131.457646)
			(xy 200.685374 -131.509552) (xy 200.70831 -131.564925) (xy 200.723823 -131.622818) (xy 200.731646 -131.68224)
			(xy 200.732136 -131.712208) (xy 200.732136 -132.575808) (xy 200.731646 -132.605776) (xy 200.723823 -132.665198)
			(xy 200.70831 -132.723091) (xy 200.685374 -132.778464) (xy 200.655407 -132.83037) (xy 200.61892 -132.87792)
			(xy 200.57654 -132.9203) (xy 200.52899 -132.956787) (xy 200.477084 -132.986754) (xy 200.421711 -133.00969)
			(xy 200.363818 -133.025203) (xy 200.304396 -133.033026) (xy 200.24446 -133.033026) (xy 200.185038 -133.025203)
			(xy 200.127145 -133.00969) (xy 200.071772 -132.986754) (xy 200.019866 -132.956787) (xy 199.972316 -132.9203)
			(xy 199.929936 -132.87792) (xy 199.893449 -132.83037) (xy 199.863482 -132.778464) (xy 199.840546 -132.723091)
			(xy 199.825033 -132.665198) (xy 199.81721 -132.605776) (xy 199.81672 -132.575808) (xy 181.760876 -132.575808)
			(xy 181.760876 -132.577332) (xy 181.760386 -132.6073) (xy 181.752563 -132.666722) (xy 181.73705 -132.724615)
			(xy 181.714114 -132.779988) (xy 181.684147 -132.831894) (xy 181.64766 -132.879444) (xy 181.60528 -132.921824)
			(xy 181.55773 -132.958311) (xy 181.505824 -132.988278) (xy 181.450451 -133.011214) (xy 181.392558 -133.026727)
			(xy 181.333136 -133.03455) (xy 181.2732 -133.03455) (xy 181.213778 -133.026727) (xy 181.155885 -133.011214)
			(xy 181.100512 -132.988278) (xy 181.048606 -132.958311) (xy 181.001056 -132.921824) (xy 180.958676 -132.879444)
			(xy 180.922189 -132.831894) (xy 180.892222 -132.779988) (xy 180.869286 -132.724615) (xy 180.853773 -132.666722)
			(xy 180.84595 -132.6073) (xy 180.84546 -132.577332) (xy 168.80078 -132.577332) (xy 168.80078 -133.096508)
			(xy 168.80029 -133.126492) (xy 168.792462 -133.185948) (xy 168.776941 -133.243873) (xy 168.753992 -133.299277)
			(xy 168.724008 -133.351211) (xy 168.687502 -133.398787) (xy 168.645097 -133.441192) (xy 168.597521 -133.477698)
			(xy 168.545587 -133.507682) (xy 168.490183 -133.530631) (xy 168.432258 -133.546152) (xy 168.372802 -133.55398)
			(xy 168.312834 -133.55398) (xy 168.253378 -133.546152) (xy 168.195453 -133.530631) (xy 168.140049 -133.507682)
			(xy 168.088115 -133.477698) (xy 168.040539 -133.441192) (xy 167.998134 -133.398787) (xy 167.961628 -133.351211)
			(xy 167.931644 -133.299277) (xy 167.908695 -133.243873) (xy 167.893174 -133.185948) (xy 167.885346 -133.126492)
			(xy 167.884856 -133.096508) (xy 154.325828 -133.096508) (xy 154.325828 -133.104382) (xy 154.325338 -133.134366)
			(xy 154.31751 -133.193822) (xy 154.301989 -133.251747) (xy 154.27904 -133.307151) (xy 154.249056 -133.359085)
			(xy 154.21255 -133.406661) (xy 154.170145 -133.449066) (xy 154.122569 -133.485572) (xy 154.070635 -133.515556)
			(xy 154.015231 -133.538505) (xy 153.957306 -133.554026) (xy 153.89785 -133.561854) (xy 153.837882 -133.561854)
			(xy 153.778426 -133.554026) (xy 153.720501 -133.538505) (xy 153.665097 -133.515556) (xy 153.613163 -133.485572)
			(xy 153.565587 -133.449066) (xy 153.523182 -133.406661) (xy 153.486676 -133.359085) (xy 153.456692 -133.307151)
			(xy 153.433743 -133.251747) (xy 153.418222 -133.193822) (xy 153.410394 -133.134366) (xy 153.409904 -133.104382)
			(xy 81.752059 -133.104382) (xy 81.786925 -133.124512) (xy 81.834501 -133.161018) (xy 81.876906 -133.203423)
			(xy 81.913412 -133.250999) (xy 81.943396 -133.302933) (xy 81.966345 -133.358337) (xy 81.981866 -133.416262)
			(xy 81.989694 -133.475718) (xy 81.990184 -133.505702) (xy 81.990184 -134.369302) (xy 81.989694 -134.399286)
			(xy 81.981866 -134.458742) (xy 81.966345 -134.516667) (xy 81.943396 -134.572071) (xy 81.913412 -134.624005)
			(xy 81.876906 -134.671581) (xy 81.834501 -134.713986) (xy 81.786925 -134.750492) (xy 81.734991 -134.780476)
			(xy 81.679587 -134.803425) (xy 81.621662 -134.818946) (xy 81.562206 -134.826774) (xy 81.502238 -134.826774)
			(xy 81.442782 -134.818946) (xy 81.384857 -134.803425) (xy 81.329453 -134.780476) (xy 81.277519 -134.750492)
			(xy 81.229943 -134.713986) (xy 81.187538 -134.671581) (xy 81.151032 -134.624005) (xy 81.121048 -134.572071)
			(xy 81.098099 -134.516667) (xy 81.082578 -134.458742) (xy 81.07475 -134.399286) (xy 81.07426 -134.369302)
			(xy 67.515232 -134.369302) (xy 67.515232 -134.377176) (xy 67.514742 -134.40716) (xy 67.506914 -134.466616)
			(xy 67.491393 -134.524541) (xy 67.468444 -134.579945) (xy 67.43846 -134.631879) (xy 67.401954 -134.679455)
			(xy 67.359549 -134.72186) (xy 67.311973 -134.758366) (xy 67.260039 -134.78835) (xy 67.204635 -134.811299)
			(xy 67.14671 -134.82682) (xy 67.087254 -134.834648) (xy 67.027286 -134.834648) (xy 66.96783 -134.82682)
			(xy 66.909905 -134.811299) (xy 66.854501 -134.78835) (xy 66.802567 -134.758366) (xy 66.754991 -134.72186)
			(xy 66.712586 -134.679455) (xy 66.67608 -134.631879) (xy 66.646096 -134.579945) (xy 66.623147 -134.524541)
			(xy 66.607626 -134.466616) (xy 66.599798 -134.40716) (xy 66.599308 -134.377176) (xy 54.554628 -134.377176)
			(xy 54.554628 -134.896352) (xy 54.554138 -134.92632) (xy 54.546315 -134.985742) (xy 54.530802 -135.043635)
			(xy 54.507866 -135.099008) (xy 54.477899 -135.150914) (xy 54.441412 -135.198464) (xy 54.399032 -135.240844)
			(xy 54.351482 -135.277331) (xy 54.299576 -135.307298) (xy 54.244203 -135.330234) (xy 54.18631 -135.345747)
			(xy 54.126888 -135.35357) (xy 54.066952 -135.35357) (xy 54.00753 -135.345747) (xy 53.949637 -135.330234)
			(xy 53.894264 -135.307298) (xy 53.842358 -135.277331) (xy 53.794808 -135.240844) (xy 53.752428 -135.198464)
			(xy 53.715941 -135.150914) (xy 53.685974 -135.099008) (xy 53.663038 -135.043635) (xy 53.647525 -134.985742)
			(xy 53.639702 -134.92632) (xy 53.639212 -134.896352) (xy 35.583368 -134.896352) (xy 35.583368 -134.897876)
			(xy 35.582878 -134.927844) (xy 35.575055 -134.987266) (xy 35.559542 -135.045159) (xy 35.536606 -135.100532)
			(xy 35.506639 -135.152438) (xy 35.470152 -135.199988) (xy 35.427772 -135.242368) (xy 35.380222 -135.278855)
			(xy 35.328316 -135.308822) (xy 35.272943 -135.331758) (xy 35.21505 -135.347271) (xy 35.155628 -135.355094)
			(xy 35.095692 -135.355094) (xy 35.03627 -135.347271) (xy 34.978377 -135.331758) (xy 34.923004 -135.308822)
			(xy 34.871098 -135.278855) (xy 34.823548 -135.242368) (xy 34.781168 -135.199988) (xy 34.744681 -135.152438)
			(xy 34.714714 -135.100532) (xy 34.691778 -135.045159) (xy 34.676265 -134.987266) (xy 34.668442 -134.927844)
			(xy 34.667952 -134.897876) (xy 4.308094 -134.897876) (xy 4.308094 -136.704324) (xy 37.31006 -136.704324)
			(xy 37.31006 -135.840724) (xy 37.31055 -135.810756) (xy 37.318373 -135.751334) (xy 37.333886 -135.693441)
			(xy 37.356822 -135.638068) (xy 37.386789 -135.586162) (xy 37.423276 -135.538612) (xy 37.465656 -135.496232)
			(xy 37.513206 -135.459745) (xy 37.565112 -135.429778) (xy 37.620485 -135.406842) (xy 37.678378 -135.391329)
			(xy 37.7378 -135.383506) (xy 37.797736 -135.383506) (xy 37.857158 -135.391329) (xy 37.915051 -135.406842)
			(xy 37.970424 -135.429778) (xy 38.02233 -135.459745) (xy 38.06988 -135.496232) (xy 38.11226 -135.538612)
			(xy 38.148747 -135.586162) (xy 38.178714 -135.638068) (xy 38.20165 -135.693441) (xy 38.217163 -135.751334)
			(xy 38.224986 -135.810756) (xy 38.225476 -135.840724) (xy 38.225476 -136.69645) (xy 51.785012 -136.69645)
			(xy 51.785012 -135.83285) (xy 51.785502 -135.802882) (xy 51.793325 -135.74346) (xy 51.808838 -135.685567)
			(xy 51.831774 -135.630194) (xy 51.861741 -135.578288) (xy 51.898228 -135.530738) (xy 51.940608 -135.488358)
			(xy 51.988158 -135.451871) (xy 52.040064 -135.421904) (xy 52.095437 -135.398968) (xy 52.15333 -135.383455)
			(xy 52.212752 -135.375632) (xy 52.272688 -135.375632) (xy 52.33211 -135.383455) (xy 52.390003 -135.398968)
			(xy 52.445376 -135.421904) (xy 52.497282 -135.451871) (xy 52.544832 -135.488358) (xy 52.587212 -135.530738)
			(xy 52.623699 -135.578288) (xy 52.653666 -135.630194) (xy 52.676602 -135.685567) (xy 52.692115 -135.74346)
			(xy 52.699938 -135.802882) (xy 52.700428 -135.83285) (xy 52.700428 -136.177274) (xy 64.745108 -136.177274)
			(xy 64.745108 -135.313674) (xy 64.745598 -135.28369) (xy 64.753426 -135.224234) (xy 64.768947 -135.166309)
			(xy 64.791896 -135.110905) (xy 64.82188 -135.058971) (xy 64.858386 -135.011395) (xy 64.900791 -134.96899)
			(xy 64.948367 -134.932484) (xy 65.000301 -134.9025) (xy 65.055705 -134.879551) (xy 65.11363 -134.86403)
			(xy 65.173086 -134.856202) (xy 65.233054 -134.856202) (xy 65.29251 -134.86403) (xy 65.350435 -134.879551)
			(xy 65.405839 -134.9025) (xy 65.457773 -134.932484) (xy 65.505349 -134.96899) (xy 65.547754 -135.011395)
			(xy 65.58426 -135.058971) (xy 65.614244 -135.110905) (xy 65.637193 -135.166309) (xy 65.652714 -135.224234)
			(xy 65.660542 -135.28369) (xy 65.661032 -135.313674) (xy 65.661032 -136.17575) (xy 83.716368 -136.17575)
			(xy 83.716368 -135.31215) (xy 83.716858 -135.282166) (xy 83.724686 -135.22271) (xy 83.740207 -135.164785)
			(xy 83.763156 -135.109381) (xy 83.79314 -135.057447) (xy 83.829646 -135.009871) (xy 83.872051 -134.967466)
			(xy 83.919627 -134.93096) (xy 83.971561 -134.900976) (xy 84.026965 -134.878027) (xy 84.08489 -134.862506)
			(xy 84.144346 -134.854678) (xy 84.204314 -134.854678) (xy 84.26377 -134.862506) (xy 84.321695 -134.878027)
			(xy 84.369615 -134.897876) (xy 150.767796 -134.897876) (xy 150.767796 -134.034276) (xy 150.768286 -134.004292)
			(xy 150.776114 -133.944836) (xy 150.791635 -133.886911) (xy 150.814584 -133.831507) (xy 150.844568 -133.779573)
			(xy 150.881074 -133.731997) (xy 150.923479 -133.689592) (xy 150.971055 -133.653086) (xy 151.022989 -133.623102)
			(xy 151.078393 -133.600153) (xy 151.136318 -133.584632) (xy 151.195774 -133.576804) (xy 151.255742 -133.576804)
			(xy 151.315198 -133.584632) (xy 151.373123 -133.600153) (xy 151.428527 -133.623102) (xy 151.480461 -133.653086)
			(xy 151.528037 -133.689592) (xy 151.570442 -133.731997) (xy 151.606948 -133.779573) (xy 151.636932 -133.831507)
			(xy 151.659881 -133.886911) (xy 151.675402 -133.944836) (xy 151.68323 -134.004292) (xy 151.68372 -134.034276)
			(xy 151.68372 -134.896352) (xy 169.739056 -134.896352) (xy 169.739056 -134.032752) (xy 169.739546 -134.002768)
			(xy 169.747374 -133.943312) (xy 169.762895 -133.885387) (xy 169.785844 -133.829983) (xy 169.815828 -133.778049)
			(xy 169.852334 -133.730473) (xy 169.894739 -133.688068) (xy 169.942315 -133.651562) (xy 169.994249 -133.621578)
			(xy 170.049653 -133.598629) (xy 170.107578 -133.583108) (xy 170.167034 -133.57528) (xy 170.227002 -133.57528)
			(xy 170.286458 -133.583108) (xy 170.344383 -133.598629) (xy 170.399787 -133.621578) (xy 170.451721 -133.651562)
			(xy 170.499297 -133.688068) (xy 170.541702 -133.730473) (xy 170.578208 -133.778049) (xy 170.608192 -133.829983)
			(xy 170.631141 -133.885387) (xy 170.646662 -133.943312) (xy 170.65449 -134.002768) (xy 170.65498 -134.032752)
			(xy 170.65498 -134.377176) (xy 182.69966 -134.377176) (xy 182.69966 -133.513576) (xy 182.70015 -133.483608)
			(xy 182.707973 -133.424186) (xy 182.723486 -133.366293) (xy 182.746422 -133.31092) (xy 182.776389 -133.259014)
			(xy 182.812876 -133.211464) (xy 182.855256 -133.169084) (xy 182.902806 -133.132597) (xy 182.954712 -133.10263)
			(xy 183.010085 -133.079694) (xy 183.067978 -133.064181) (xy 183.1274 -133.056358) (xy 183.187336 -133.056358)
			(xy 183.246758 -133.064181) (xy 183.304651 -133.079694) (xy 183.360024 -133.10263) (xy 183.41193 -133.132597)
			(xy 183.45948 -133.169084) (xy 183.50186 -133.211464) (xy 183.538347 -133.259014) (xy 183.568314 -133.31092)
			(xy 183.59125 -133.366293) (xy 183.606763 -133.424186) (xy 183.614586 -133.483608) (xy 183.615076 -133.513576)
			(xy 183.615076 -134.369302) (xy 197.174612 -134.369302) (xy 197.174612 -133.505702) (xy 197.175102 -133.475734)
			(xy 197.182925 -133.416312) (xy 197.198438 -133.358419) (xy 197.221374 -133.303046) (xy 197.251341 -133.25114)
			(xy 197.287828 -133.20359) (xy 197.330208 -133.16121) (xy 197.377758 -133.124723) (xy 197.429664 -133.094756)
			(xy 197.485037 -133.07182) (xy 197.54293 -133.056307) (xy 197.602352 -133.048484) (xy 197.662288 -133.048484)
			(xy 197.72171 -133.056307) (xy 197.779603 -133.07182) (xy 197.834976 -133.094756) (xy 197.851649 -133.104382)
			(xy 269.509748 -133.104382) (xy 269.509748 -132.240782) (xy 269.510238 -132.210798) (xy 269.518066 -132.151342)
			(xy 269.533587 -132.093417) (xy 269.556536 -132.038013) (xy 269.58652 -131.986079) (xy 269.623026 -131.938503)
			(xy 269.665431 -131.896098) (xy 269.713007 -131.859592) (xy 269.764941 -131.829608) (xy 269.820345 -131.806659)
			(xy 269.87827 -131.791138) (xy 269.937726 -131.78331) (xy 269.997694 -131.78331) (xy 270.05715 -131.791138)
			(xy 270.115075 -131.806659) (xy 270.170479 -131.829608) (xy 270.222413 -131.859592) (xy 270.269989 -131.896098)
			(xy 270.312394 -131.938503) (xy 270.3489 -131.986079) (xy 270.378884 -132.038013) (xy 270.401833 -132.093417)
			(xy 270.417354 -132.151342) (xy 270.425182 -132.210798) (xy 270.425672 -132.240782) (xy 270.425672 -133.096508)
			(xy 283.9847 -133.096508) (xy 283.9847 -132.232908) (xy 283.98519 -132.202924) (xy 283.993018 -132.143468)
			(xy 284.008539 -132.085543) (xy 284.031488 -132.030139) (xy 284.061472 -131.978205) (xy 284.097978 -131.930629)
			(xy 284.140383 -131.888224) (xy 284.187959 -131.851718) (xy 284.239893 -131.821734) (xy 284.295297 -131.798785)
			(xy 284.353222 -131.783264) (xy 284.412678 -131.775436) (xy 284.472646 -131.775436) (xy 284.532102 -131.783264)
			(xy 284.590027 -131.798785) (xy 284.645431 -131.821734) (xy 284.697365 -131.851718) (xy 284.744941 -131.888224)
			(xy 284.787346 -131.930629) (xy 284.823852 -131.978205) (xy 284.853836 -132.030139) (xy 284.876785 -132.085543)
			(xy 284.892306 -132.143468) (xy 284.900134 -132.202924) (xy 284.900624 -132.232908) (xy 284.900624 -132.577332)
			(xy 296.945304 -132.577332) (xy 296.945304 -131.713732) (xy 296.945794 -131.683764) (xy 296.953617 -131.624342)
			(xy 296.96913 -131.566449) (xy 296.992066 -131.511076) (xy 297.022033 -131.45917) (xy 297.05852 -131.41162)
			(xy 297.1009 -131.36924) (xy 297.14845 -131.332753) (xy 297.200356 -131.302786) (xy 297.255729 -131.27985)
			(xy 297.313622 -131.264337) (xy 297.373044 -131.256514) (xy 297.43298 -131.256514) (xy 297.492402 -131.264337)
			(xy 297.550295 -131.27985) (xy 297.605668 -131.302786) (xy 297.657574 -131.332753) (xy 297.705124 -131.36924)
			(xy 297.747504 -131.41162) (xy 297.783991 -131.45917) (xy 297.813958 -131.511076) (xy 297.836894 -131.566449)
			(xy 297.852407 -131.624342) (xy 297.86023 -131.683764) (xy 297.86072 -131.713732) (xy 297.86072 -132.575808)
			(xy 315.916564 -132.575808) (xy 315.916564 -131.712208) (xy 315.917054 -131.68224) (xy 315.924877 -131.622818)
			(xy 315.94039 -131.564925) (xy 315.963326 -131.509552) (xy 315.993293 -131.457646) (xy 316.02978 -131.410096)
			(xy 316.07216 -131.367716) (xy 316.11971 -131.331229) (xy 316.171616 -131.301262) (xy 316.226989 -131.278326)
			(xy 316.284882 -131.262813) (xy 316.344304 -131.25499) (xy 316.40424 -131.25499) (xy 316.463662 -131.262813)
			(xy 316.521555 -131.278326) (xy 316.568893 -131.297934) (xy 382.967992 -131.297934) (xy 382.967992 -130.434334)
			(xy 382.968482 -130.404366) (xy 382.976305 -130.344944) (xy 382.991818 -130.287051) (xy 383.014754 -130.231678)
			(xy 383.044721 -130.179772) (xy 383.081208 -130.132222) (xy 383.123588 -130.089842) (xy 383.171138 -130.053355)
			(xy 383.223044 -130.023388) (xy 383.278417 -130.000452) (xy 383.33631 -129.984939) (xy 383.395732 -129.977116)
			(xy 383.455668 -129.977116) (xy 383.51509 -129.984939) (xy 383.572983 -130.000452) (xy 383.628356 -130.023388)
			(xy 383.680262 -130.053355) (xy 383.727812 -130.089842) (xy 383.770192 -130.132222) (xy 383.806679 -130.179772)
			(xy 383.836646 -130.231678) (xy 383.859582 -130.287051) (xy 383.875095 -130.344944) (xy 383.882918 -130.404366)
			(xy 383.883408 -130.434334) (xy 383.883408 -131.29641) (xy 401.939252 -131.29641) (xy 401.939252 -130.43281)
			(xy 401.939742 -130.402842) (xy 401.947565 -130.34342) (xy 401.963078 -130.285527) (xy 401.986014 -130.230154)
			(xy 402.015981 -130.178248) (xy 402.052468 -130.130698) (xy 402.094848 -130.088318) (xy 402.142398 -130.051831)
			(xy 402.194304 -130.021864) (xy 402.249677 -129.998928) (xy 402.30757 -129.983415) (xy 402.366992 -129.975592)
			(xy 402.426928 -129.975592) (xy 402.48635 -129.983415) (xy 402.544243 -129.998928) (xy 402.599616 -130.021864)
			(xy 402.651522 -130.051831) (xy 402.699072 -130.088318) (xy 402.741452 -130.130698) (xy 402.777939 -130.178248)
			(xy 402.807906 -130.230154) (xy 402.830842 -130.285527) (xy 402.846355 -130.34342) (xy 402.854178 -130.402842)
			(xy 402.854668 -130.43281) (xy 402.854668 -130.777234) (xy 414.899348 -130.777234) (xy 414.899348 -129.913634)
			(xy 414.899838 -129.88365) (xy 414.907666 -129.824194) (xy 414.923187 -129.766269) (xy 414.946136 -129.710865)
			(xy 414.97612 -129.658931) (xy 415.012626 -129.611355) (xy 415.055031 -129.56895) (xy 415.102607 -129.532444)
			(xy 415.154541 -129.50246) (xy 415.209945 -129.479511) (xy 415.26787 -129.46399) (xy 415.327326 -129.456162)
			(xy 415.387294 -129.456162) (xy 415.44675 -129.46399) (xy 415.504675 -129.479511) (xy 415.560079 -129.50246)
			(xy 415.612013 -129.532444) (xy 415.659589 -129.56895) (xy 415.701994 -129.611355) (xy 415.7385 -129.658931)
			(xy 415.768484 -129.710865) (xy 415.791433 -129.766269) (xy 415.806954 -129.824194) (xy 415.814782 -129.88365)
			(xy 415.815272 -129.913634) (xy 415.815272 -130.769106) (xy 429.3743 -130.769106) (xy 429.3743 -129.905506)
			(xy 429.37479 -129.875522) (xy 429.382618 -129.816066) (xy 429.398139 -129.758141) (xy 429.421088 -129.702737)
			(xy 429.451072 -129.650803) (xy 429.487578 -129.603227) (xy 429.529983 -129.560822) (xy 429.577559 -129.524316)
			(xy 429.629493 -129.494332) (xy 429.684897 -129.471383) (xy 429.742822 -129.455862) (xy 429.802278 -129.448034)
			(xy 429.862246 -129.448034) (xy 429.921702 -129.455862) (xy 429.979627 -129.471383) (xy 430.035031 -129.494332)
			(xy 430.086965 -129.524316) (xy 430.134541 -129.560822) (xy 430.176946 -129.603227) (xy 430.213452 -129.650803)
			(xy 430.243436 -129.702737) (xy 430.266385 -129.758141) (xy 430.281906 -129.816066) (xy 430.289734 -129.875522)
			(xy 430.290224 -129.905506) (xy 430.290224 -130.769106) (xy 430.289734 -130.79909) (xy 430.281906 -130.858546)
			(xy 430.266385 -130.916471) (xy 430.243436 -130.971875) (xy 430.213452 -131.023809) (xy 430.176946 -131.071385)
			(xy 430.134541 -131.11379) (xy 430.086965 -131.150296) (xy 430.035031 -131.18028) (xy 429.979627 -131.203229)
			(xy 429.921702 -131.21875) (xy 429.862246 -131.226578) (xy 429.802278 -131.226578) (xy 429.742822 -131.21875)
			(xy 429.684897 -131.203229) (xy 429.629493 -131.18028) (xy 429.577559 -131.150296) (xy 429.529983 -131.11379)
			(xy 429.487578 -131.071385) (xy 429.451072 -131.023809) (xy 429.421088 -130.971875) (xy 429.398139 -130.916471)
			(xy 429.382618 -130.858546) (xy 429.37479 -130.79909) (xy 429.3743 -130.769106) (xy 415.815272 -130.769106)
			(xy 415.815272 -130.777234) (xy 415.814782 -130.807218) (xy 415.806954 -130.866674) (xy 415.791433 -130.924599)
			(xy 415.768484 -130.980003) (xy 415.7385 -131.031937) (xy 415.701994 -131.079513) (xy 415.659589 -131.121918)
			(xy 415.612013 -131.158424) (xy 415.560079 -131.188408) (xy 415.504675 -131.211357) (xy 415.44675 -131.226878)
			(xy 415.387294 -131.234706) (xy 415.327326 -131.234706) (xy 415.26787 -131.226878) (xy 415.209945 -131.211357)
			(xy 415.154541 -131.188408) (xy 415.102607 -131.158424) (xy 415.055031 -131.121918) (xy 415.012626 -131.079513)
			(xy 414.97612 -131.031937) (xy 414.946136 -130.980003) (xy 414.923187 -130.924599) (xy 414.907666 -130.866674)
			(xy 414.899838 -130.807218) (xy 414.899348 -130.777234) (xy 402.854668 -130.777234) (xy 402.854668 -131.29641)
			(xy 402.854178 -131.326378) (xy 402.846355 -131.3858) (xy 402.830842 -131.443693) (xy 402.807906 -131.499066)
			(xy 402.777939 -131.550972) (xy 402.741452 -131.598522) (xy 402.699072 -131.640902) (xy 402.651522 -131.677389)
			(xy 402.599616 -131.707356) (xy 402.544243 -131.730292) (xy 402.48635 -131.745805) (xy 402.426928 -131.753628)
			(xy 402.366992 -131.753628) (xy 402.30757 -131.745805) (xy 402.249677 -131.730292) (xy 402.194304 -131.707356)
			(xy 402.142398 -131.677389) (xy 402.094848 -131.640902) (xy 402.052468 -131.598522) (xy 402.015981 -131.550972)
			(xy 401.986014 -131.499066) (xy 401.963078 -131.443693) (xy 401.947565 -131.3858) (xy 401.939742 -131.326378)
			(xy 401.939252 -131.29641) (xy 383.883408 -131.29641) (xy 383.883408 -131.297934) (xy 383.882918 -131.327902)
			(xy 383.875095 -131.387324) (xy 383.859582 -131.445217) (xy 383.836646 -131.50059) (xy 383.806679 -131.552496)
			(xy 383.770192 -131.600046) (xy 383.727812 -131.642426) (xy 383.680262 -131.678913) (xy 383.628356 -131.70888)
			(xy 383.572983 -131.731816) (xy 383.51509 -131.747329) (xy 383.455668 -131.755152) (xy 383.395732 -131.755152)
			(xy 383.33631 -131.747329) (xy 383.278417 -131.731816) (xy 383.223044 -131.70888) (xy 383.171138 -131.678913)
			(xy 383.123588 -131.642426) (xy 383.081208 -131.600046) (xy 383.044721 -131.552496) (xy 383.014754 -131.50059)
			(xy 382.991818 -131.445217) (xy 382.976305 -131.387324) (xy 382.968482 -131.327902) (xy 382.967992 -131.297934)
			(xy 316.568893 -131.297934) (xy 316.576928 -131.301262) (xy 316.628834 -131.331229) (xy 316.676384 -131.367716)
			(xy 316.718764 -131.410096) (xy 316.755251 -131.457646) (xy 316.785218 -131.509552) (xy 316.808154 -131.564925)
			(xy 316.823667 -131.622818) (xy 316.83149 -131.68224) (xy 316.83198 -131.712208) (xy 316.83198 -132.575808)
			(xy 316.83149 -132.605776) (xy 316.823667 -132.665198) (xy 316.808154 -132.723091) (xy 316.785218 -132.778464)
			(xy 316.755251 -132.83037) (xy 316.718764 -132.87792) (xy 316.676384 -132.9203) (xy 316.628834 -132.956787)
			(xy 316.576928 -132.986754) (xy 316.521555 -133.00969) (xy 316.463662 -133.025203) (xy 316.40424 -133.033026)
			(xy 316.344304 -133.033026) (xy 316.284882 -133.025203) (xy 316.226989 -133.00969) (xy 316.171616 -132.986754)
			(xy 316.11971 -132.956787) (xy 316.07216 -132.9203) (xy 316.02978 -132.87792) (xy 315.993293 -132.83037)
			(xy 315.963326 -132.778464) (xy 315.94039 -132.723091) (xy 315.924877 -132.665198) (xy 315.917054 -132.605776)
			(xy 315.916564 -132.575808) (xy 297.86072 -132.575808) (xy 297.86072 -132.577332) (xy 297.86023 -132.6073)
			(xy 297.852407 -132.666722) (xy 297.836894 -132.724615) (xy 297.813958 -132.779988) (xy 297.783991 -132.831894)
			(xy 297.747504 -132.879444) (xy 297.705124 -132.921824) (xy 297.657574 -132.958311) (xy 297.605668 -132.988278)
			(xy 297.550295 -133.011214) (xy 297.492402 -133.026727) (xy 297.43298 -133.03455) (xy 297.373044 -133.03455)
			(xy 297.313622 -133.026727) (xy 297.255729 -133.011214) (xy 297.200356 -132.988278) (xy 297.14845 -132.958311)
			(xy 297.1009 -132.921824) (xy 297.05852 -132.879444) (xy 297.022033 -132.831894) (xy 296.992066 -132.779988)
			(xy 296.96913 -132.724615) (xy 296.953617 -132.666722) (xy 296.945794 -132.6073) (xy 296.945304 -132.577332)
			(xy 284.900624 -132.577332) (xy 284.900624 -133.096508) (xy 284.900134 -133.126492) (xy 284.892306 -133.185948)
			(xy 284.876785 -133.243873) (xy 284.853836 -133.299277) (xy 284.823852 -133.351211) (xy 284.787346 -133.398787)
			(xy 284.744941 -133.441192) (xy 284.697365 -133.477698) (xy 284.645431 -133.507682) (xy 284.590027 -133.530631)
			(xy 284.532102 -133.546152) (xy 284.472646 -133.55398) (xy 284.412678 -133.55398) (xy 284.353222 -133.546152)
			(xy 284.295297 -133.530631) (xy 284.239893 -133.507682) (xy 284.187959 -133.477698) (xy 284.140383 -133.441192)
			(xy 284.097978 -133.398787) (xy 284.061472 -133.351211) (xy 284.031488 -133.299277) (xy 284.008539 -133.243873)
			(xy 283.993018 -133.185948) (xy 283.98519 -133.126492) (xy 283.9847 -133.096508) (xy 270.425672 -133.096508)
			(xy 270.425672 -133.104382) (xy 270.425182 -133.134366) (xy 270.417354 -133.193822) (xy 270.401833 -133.251747)
			(xy 270.378884 -133.307151) (xy 270.3489 -133.359085) (xy 270.312394 -133.406661) (xy 270.269989 -133.449066)
			(xy 270.222413 -133.485572) (xy 270.170479 -133.515556) (xy 270.115075 -133.538505) (xy 270.05715 -133.554026)
			(xy 269.997694 -133.561854) (xy 269.937726 -133.561854) (xy 269.87827 -133.554026) (xy 269.820345 -133.538505)
			(xy 269.764941 -133.515556) (xy 269.713007 -133.485572) (xy 269.665431 -133.449066) (xy 269.623026 -133.406661)
			(xy 269.58652 -133.359085) (xy 269.556536 -133.307151) (xy 269.533587 -133.251747) (xy 269.518066 -133.193822)
			(xy 269.510238 -133.134366) (xy 269.509748 -133.104382) (xy 197.851649 -133.104382) (xy 197.886882 -133.124723)
			(xy 197.934432 -133.16121) (xy 197.976812 -133.20359) (xy 198.013299 -133.25114) (xy 198.043266 -133.303046)
			(xy 198.066202 -133.358419) (xy 198.081715 -133.416312) (xy 198.089538 -133.475734) (xy 198.090028 -133.505702)
			(xy 198.090028 -134.369302) (xy 198.089538 -134.39927) (xy 198.081715 -134.458692) (xy 198.066202 -134.516585)
			(xy 198.043266 -134.571958) (xy 198.013299 -134.623864) (xy 197.976812 -134.671414) (xy 197.934432 -134.713794)
			(xy 197.886882 -134.750281) (xy 197.834976 -134.780248) (xy 197.779603 -134.803184) (xy 197.72171 -134.818697)
			(xy 197.662288 -134.82652) (xy 197.602352 -134.82652) (xy 197.54293 -134.818697) (xy 197.485037 -134.803184)
			(xy 197.429664 -134.780248) (xy 197.377758 -134.750281) (xy 197.330208 -134.713794) (xy 197.287828 -134.671414)
			(xy 197.251341 -134.623864) (xy 197.221374 -134.571958) (xy 197.198438 -134.516585) (xy 197.182925 -134.458692)
			(xy 197.175102 -134.39927) (xy 197.174612 -134.369302) (xy 183.615076 -134.369302) (xy 183.615076 -134.377176)
			(xy 183.614586 -134.407144) (xy 183.606763 -134.466566) (xy 183.59125 -134.524459) (xy 183.568314 -134.579832)
			(xy 183.538347 -134.631738) (xy 183.50186 -134.679288) (xy 183.45948 -134.721668) (xy 183.41193 -134.758155)
			(xy 183.360024 -134.788122) (xy 183.304651 -134.811058) (xy 183.246758 -134.826571) (xy 183.187336 -134.834394)
			(xy 183.1274 -134.834394) (xy 183.067978 -134.826571) (xy 183.010085 -134.811058) (xy 182.954712 -134.788122)
			(xy 182.902806 -134.758155) (xy 182.855256 -134.721668) (xy 182.812876 -134.679288) (xy 182.776389 -134.631738)
			(xy 182.746422 -134.579832) (xy 182.723486 -134.524459) (xy 182.707973 -134.466566) (xy 182.70015 -134.407144)
			(xy 182.69966 -134.377176) (xy 170.65498 -134.377176) (xy 170.65498 -134.896352) (xy 170.65449 -134.926336)
			(xy 170.646662 -134.985792) (xy 170.631141 -135.043717) (xy 170.608192 -135.099121) (xy 170.578208 -135.151055)
			(xy 170.541702 -135.198631) (xy 170.499297 -135.241036) (xy 170.451721 -135.277542) (xy 170.399787 -135.307526)
			(xy 170.344383 -135.330475) (xy 170.286458 -135.345996) (xy 170.227002 -135.353824) (xy 170.167034 -135.353824)
			(xy 170.107578 -135.345996) (xy 170.049653 -135.330475) (xy 169.994249 -135.307526) (xy 169.942315 -135.277542)
			(xy 169.894739 -135.241036) (xy 169.852334 -135.198631) (xy 169.815828 -135.151055) (xy 169.785844 -135.099121)
			(xy 169.762895 -135.043717) (xy 169.747374 -134.985792) (xy 169.739546 -134.926336) (xy 169.739056 -134.896352)
			(xy 151.68372 -134.896352) (xy 151.68372 -134.897876) (xy 151.68323 -134.92786) (xy 151.675402 -134.987316)
			(xy 151.659881 -135.045241) (xy 151.636932 -135.100645) (xy 151.606948 -135.152579) (xy 151.570442 -135.200155)
			(xy 151.528037 -135.24256) (xy 151.480461 -135.279066) (xy 151.428527 -135.30905) (xy 151.373123 -135.331999)
			(xy 151.315198 -135.34752) (xy 151.255742 -135.355348) (xy 151.195774 -135.355348) (xy 151.136318 -135.34752)
			(xy 151.078393 -135.331999) (xy 151.022989 -135.30905) (xy 150.971055 -135.279066) (xy 150.923479 -135.24256)
			(xy 150.881074 -135.200155) (xy 150.844568 -135.152579) (xy 150.814584 -135.100645) (xy 150.791635 -135.045241)
			(xy 150.776114 -134.987316) (xy 150.768286 -134.92786) (xy 150.767796 -134.897876) (xy 84.369615 -134.897876)
			(xy 84.377099 -134.900976) (xy 84.429033 -134.93096) (xy 84.476609 -134.967466) (xy 84.519014 -135.009871)
			(xy 84.55552 -135.057447) (xy 84.585504 -135.109381) (xy 84.608453 -135.164785) (xy 84.623974 -135.22271)
			(xy 84.631802 -135.282166) (xy 84.632292 -135.31215) (xy 84.632292 -136.17575) (xy 84.631802 -136.205734)
			(xy 84.623974 -136.26519) (xy 84.608453 -136.323115) (xy 84.585504 -136.378519) (xy 84.55552 -136.430453)
			(xy 84.519014 -136.478029) (xy 84.476609 -136.520434) (xy 84.429033 -136.55694) (xy 84.377099 -136.586924)
			(xy 84.321695 -136.609873) (xy 84.26377 -136.625394) (xy 84.204314 -136.633222) (xy 84.144346 -136.633222)
			(xy 84.08489 -136.625394) (xy 84.026965 -136.609873) (xy 83.971561 -136.586924) (xy 83.919627 -136.55694)
			(xy 83.872051 -136.520434) (xy 83.829646 -136.478029) (xy 83.79314 -136.430453) (xy 83.763156 -136.378519)
			(xy 83.740207 -136.323115) (xy 83.724686 -136.26519) (xy 83.716858 -136.205734) (xy 83.716368 -136.17575)
			(xy 65.661032 -136.17575) (xy 65.661032 -136.177274) (xy 65.660542 -136.207258) (xy 65.652714 -136.266714)
			(xy 65.637193 -136.324639) (xy 65.614244 -136.380043) (xy 65.58426 -136.431977) (xy 65.547754 -136.479553)
			(xy 65.505349 -136.521958) (xy 65.457773 -136.558464) (xy 65.405839 -136.588448) (xy 65.350435 -136.611397)
			(xy 65.29251 -136.626918) (xy 65.233054 -136.634746) (xy 65.173086 -136.634746) (xy 65.11363 -136.626918)
			(xy 65.055705 -136.611397) (xy 65.000301 -136.588448) (xy 64.948367 -136.558464) (xy 64.900791 -136.521958)
			(xy 64.858386 -136.479553) (xy 64.82188 -136.431977) (xy 64.791896 -136.380043) (xy 64.768947 -136.324639)
			(xy 64.753426 -136.266714) (xy 64.745598 -136.207258) (xy 64.745108 -136.177274) (xy 52.700428 -136.177274)
			(xy 52.700428 -136.69645) (xy 52.700299 -136.704324) (xy 153.409904 -136.704324) (xy 153.409904 -135.840724)
			(xy 153.410394 -135.81074) (xy 153.418222 -135.751284) (xy 153.433743 -135.693359) (xy 153.456692 -135.637955)
			(xy 153.486676 -135.586021) (xy 153.523182 -135.538445) (xy 153.565587 -135.49604) (xy 153.613163 -135.459534)
			(xy 153.665097 -135.42955) (xy 153.720501 -135.406601) (xy 153.778426 -135.39108) (xy 153.837882 -135.383252)
			(xy 153.89785 -135.383252) (xy 153.957306 -135.39108) (xy 154.015231 -135.406601) (xy 154.070635 -135.42955)
			(xy 154.122569 -135.459534) (xy 154.170145 -135.49604) (xy 154.21255 -135.538445) (xy 154.249056 -135.586021)
			(xy 154.27904 -135.637955) (xy 154.301989 -135.693359) (xy 154.31751 -135.751284) (xy 154.325338 -135.81074)
			(xy 154.325828 -135.840724) (xy 154.325828 -136.69645) (xy 167.884856 -136.69645) (xy 167.884856 -135.83285)
			(xy 167.885346 -135.802866) (xy 167.893174 -135.74341) (xy 167.908695 -135.685485) (xy 167.931644 -135.630081)
			(xy 167.961628 -135.578147) (xy 167.998134 -135.530571) (xy 168.040539 -135.488166) (xy 168.088115 -135.45166)
			(xy 168.140049 -135.421676) (xy 168.195453 -135.398727) (xy 168.253378 -135.383206) (xy 168.312834 -135.375378)
			(xy 168.372802 -135.375378) (xy 168.432258 -135.383206) (xy 168.490183 -135.398727) (xy 168.545587 -135.421676)
			(xy 168.597521 -135.45166) (xy 168.645097 -135.488166) (xy 168.687502 -135.530571) (xy 168.724008 -135.578147)
			(xy 168.753992 -135.630081) (xy 168.776941 -135.685485) (xy 168.792462 -135.74341) (xy 168.80029 -135.802866)
			(xy 168.80078 -135.83285) (xy 168.80078 -136.177274) (xy 180.84546 -136.177274) (xy 180.84546 -135.313674)
			(xy 180.84595 -135.283706) (xy 180.853773 -135.224284) (xy 180.869286 -135.166391) (xy 180.892222 -135.111018)
			(xy 180.922189 -135.059112) (xy 180.958676 -135.011562) (xy 181.001056 -134.969182) (xy 181.048606 -134.932695)
			(xy 181.100512 -134.902728) (xy 181.155885 -134.879792) (xy 181.213778 -134.864279) (xy 181.2732 -134.856456)
			(xy 181.333136 -134.856456) (xy 181.392558 -134.864279) (xy 181.450451 -134.879792) (xy 181.505824 -134.902728)
			(xy 181.55773 -134.932695) (xy 181.60528 -134.969182) (xy 181.64766 -135.011562) (xy 181.684147 -135.059112)
			(xy 181.714114 -135.111018) (xy 181.73705 -135.166391) (xy 181.752563 -135.224284) (xy 181.760386 -135.283706)
			(xy 181.760876 -135.313674) (xy 181.760876 -136.17575) (xy 199.81672 -136.17575) (xy 199.81672 -135.31215)
			(xy 199.81721 -135.282182) (xy 199.825033 -135.22276) (xy 199.840546 -135.164867) (xy 199.863482 -135.109494)
			(xy 199.893449 -135.057588) (xy 199.929936 -135.010038) (xy 199.972316 -134.967658) (xy 200.019866 -134.931171)
			(xy 200.071772 -134.901204) (xy 200.127145 -134.878268) (xy 200.185038 -134.862755) (xy 200.24446 -134.854932)
			(xy 200.304396 -134.854932) (xy 200.363818 -134.862755) (xy 200.421711 -134.878268) (xy 200.469049 -134.897876)
			(xy 266.86764 -134.897876) (xy 266.86764 -134.034276) (xy 266.86813 -134.004292) (xy 266.875958 -133.944836)
			(xy 266.891479 -133.886911) (xy 266.914428 -133.831507) (xy 266.944412 -133.779573) (xy 266.980918 -133.731997)
			(xy 267.023323 -133.689592) (xy 267.070899 -133.653086) (xy 267.122833 -133.623102) (xy 267.178237 -133.600153)
			(xy 267.236162 -133.584632) (xy 267.295618 -133.576804) (xy 267.355586 -133.576804) (xy 267.415042 -133.584632)
			(xy 267.472967 -133.600153) (xy 267.528371 -133.623102) (xy 267.580305 -133.653086) (xy 267.627881 -133.689592)
			(xy 267.670286 -133.731997) (xy 267.706792 -133.779573) (xy 267.736776 -133.831507) (xy 267.759725 -133.886911)
			(xy 267.775246 -133.944836) (xy 267.783074 -134.004292) (xy 267.783564 -134.034276) (xy 267.783564 -134.896352)
			(xy 285.8389 -134.896352) (xy 285.8389 -134.032752) (xy 285.83939 -134.002768) (xy 285.847218 -133.943312)
			(xy 285.862739 -133.885387) (xy 285.885688 -133.829983) (xy 285.915672 -133.778049) (xy 285.952178 -133.730473)
			(xy 285.994583 -133.688068) (xy 286.042159 -133.651562) (xy 286.094093 -133.621578) (xy 286.149497 -133.598629)
			(xy 286.207422 -133.583108) (xy 286.266878 -133.57528) (xy 286.326846 -133.57528) (xy 286.386302 -133.583108)
			(xy 286.444227 -133.598629) (xy 286.499631 -133.621578) (xy 286.551565 -133.651562) (xy 286.599141 -133.688068)
			(xy 286.641546 -133.730473) (xy 286.678052 -133.778049) (xy 286.708036 -133.829983) (xy 286.730985 -133.885387)
			(xy 286.746506 -133.943312) (xy 286.754334 -134.002768) (xy 286.754824 -134.032752) (xy 286.754824 -134.377176)
			(xy 298.799504 -134.377176) (xy 298.799504 -133.513576) (xy 298.799994 -133.483608) (xy 298.807817 -133.424186)
			(xy 298.82333 -133.366293) (xy 298.846266 -133.31092) (xy 298.876233 -133.259014) (xy 298.91272 -133.211464)
			(xy 298.9551 -133.169084) (xy 299.00265 -133.132597) (xy 299.054556 -133.10263) (xy 299.109929 -133.079694)
			(xy 299.167822 -133.064181) (xy 299.227244 -133.056358) (xy 299.28718 -133.056358) (xy 299.346602 -133.064181)
			(xy 299.404495 -133.079694) (xy 299.459868 -133.10263) (xy 299.511774 -133.132597) (xy 299.559324 -133.169084)
			(xy 299.601704 -133.211464) (xy 299.638191 -133.259014) (xy 299.668158 -133.31092) (xy 299.691094 -133.366293)
			(xy 299.706607 -133.424186) (xy 299.71443 -133.483608) (xy 299.71492 -133.513576) (xy 299.71492 -134.369302)
			(xy 313.274456 -134.369302) (xy 313.274456 -133.505702) (xy 313.274946 -133.475734) (xy 313.282769 -133.416312)
			(xy 313.298282 -133.358419) (xy 313.321218 -133.303046) (xy 313.351185 -133.25114) (xy 313.387672 -133.20359)
			(xy 313.430052 -133.16121) (xy 313.477602 -133.124723) (xy 313.529508 -133.094756) (xy 313.584881 -133.07182)
			(xy 313.642774 -133.056307) (xy 313.702196 -133.048484) (xy 313.762132 -133.048484) (xy 313.821554 -133.056307)
			(xy 313.879447 -133.07182) (xy 313.93482 -133.094756) (xy 313.951493 -133.104382) (xy 385.6101 -133.104382)
			(xy 385.6101 -132.240782) (xy 385.61059 -132.210814) (xy 385.618413 -132.151392) (xy 385.633926 -132.093499)
			(xy 385.656862 -132.038126) (xy 385.686829 -131.98622) (xy 385.723316 -131.93867) (xy 385.765696 -131.89629)
			(xy 385.813246 -131.859803) (xy 385.865152 -131.829836) (xy 385.920525 -131.8069) (xy 385.978418 -131.791387)
			(xy 386.03784 -131.783564) (xy 386.097776 -131.783564) (xy 386.157198 -131.791387) (xy 386.215091 -131.8069)
			(xy 386.270464 -131.829836) (xy 386.32237 -131.859803) (xy 386.36992 -131.89629) (xy 386.4123 -131.93867)
			(xy 386.448787 -131.98622) (xy 386.478754 -132.038126) (xy 386.50169 -132.093499) (xy 386.517203 -132.151392)
			(xy 386.525026 -132.210814) (xy 386.525516 -132.240782) (xy 386.525516 -133.096508) (xy 400.085052 -133.096508)
			(xy 400.085052 -132.232908) (xy 400.085542 -132.20294) (xy 400.093365 -132.143518) (xy 400.108878 -132.085625)
			(xy 400.131814 -132.030252) (xy 400.161781 -131.978346) (xy 400.198268 -131.930796) (xy 400.240648 -131.888416)
			(xy 400.288198 -131.851929) (xy 400.340104 -131.821962) (xy 400.395477 -131.799026) (xy 400.45337 -131.783513)
			(xy 400.512792 -131.77569) (xy 400.572728 -131.77569) (xy 400.63215 -131.783513) (xy 400.690043 -131.799026)
			(xy 400.745416 -131.821962) (xy 400.797322 -131.851929) (xy 400.844872 -131.888416) (xy 400.887252 -131.930796)
			(xy 400.923739 -131.978346) (xy 400.953706 -132.030252) (xy 400.976642 -132.085625) (xy 400.992155 -132.143518)
			(xy 400.999978 -132.20294) (xy 401.000468 -132.232908) (xy 401.000468 -132.577332) (xy 413.045148 -132.577332)
			(xy 413.045148 -131.713732) (xy 413.045638 -131.683748) (xy 413.053466 -131.624292) (xy 413.068987 -131.566367)
			(xy 413.091936 -131.510963) (xy 413.12192 -131.459029) (xy 413.158426 -131.411453) (xy 413.200831 -131.369048)
			(xy 413.248407 -131.332542) (xy 413.300341 -131.302558) (xy 413.355745 -131.279609) (xy 413.41367 -131.264088)
			(xy 413.473126 -131.25626) (xy 413.533094 -131.25626) (xy 413.59255 -131.264088) (xy 413.650475 -131.279609)
			(xy 413.705879 -131.302558) (xy 413.757813 -131.332542) (xy 413.805389 -131.369048) (xy 413.847794 -131.411453)
			(xy 413.8843 -131.459029) (xy 413.914284 -131.510963) (xy 413.937233 -131.566367) (xy 413.952754 -131.624292)
			(xy 413.960582 -131.683748) (xy 413.961072 -131.713732) (xy 413.961072 -132.575808) (xy 432.016408 -132.575808)
			(xy 432.016408 -131.712208) (xy 432.016898 -131.682224) (xy 432.024726 -131.622768) (xy 432.040247 -131.564843)
			(xy 432.063196 -131.509439) (xy 432.09318 -131.457505) (xy 432.129686 -131.409929) (xy 432.172091 -131.367524)
			(xy 432.219667 -131.331018) (xy 432.271601 -131.301034) (xy 432.327005 -131.278085) (xy 432.38493 -131.262564)
			(xy 432.444386 -131.254736) (xy 432.504354 -131.254736) (xy 432.56381 -131.262564) (xy 432.621735 -131.278085)
			(xy 432.677139 -131.301034) (xy 432.729073 -131.331018) (xy 432.776649 -131.367524) (xy 432.819054 -131.409929)
			(xy 432.85556 -131.457505) (xy 432.885544 -131.509439) (xy 432.908493 -131.564843) (xy 432.924014 -131.622768)
			(xy 432.931842 -131.682224) (xy 432.932332 -131.712208) (xy 432.932332 -132.575808) (xy 432.931842 -132.605792)
			(xy 432.924014 -132.665248) (xy 432.908493 -132.723173) (xy 432.885544 -132.778577) (xy 432.85556 -132.830511)
			(xy 432.819054 -132.878087) (xy 432.776649 -132.920492) (xy 432.729073 -132.956998) (xy 432.677139 -132.986982)
			(xy 432.621735 -133.009931) (xy 432.56381 -133.025452) (xy 432.504354 -133.03328) (xy 432.444386 -133.03328)
			(xy 432.38493 -133.025452) (xy 432.327005 -133.009931) (xy 432.271601 -132.986982) (xy 432.219667 -132.956998)
			(xy 432.172091 -132.920492) (xy 432.129686 -132.878087) (xy 432.09318 -132.830511) (xy 432.063196 -132.778577)
			(xy 432.040247 -132.723173) (xy 432.024726 -132.665248) (xy 432.016898 -132.605792) (xy 432.016408 -132.575808)
			(xy 413.961072 -132.575808) (xy 413.961072 -132.577332) (xy 413.960582 -132.607316) (xy 413.952754 -132.666772)
			(xy 413.937233 -132.724697) (xy 413.914284 -132.780101) (xy 413.8843 -132.832035) (xy 413.847794 -132.879611)
			(xy 413.805389 -132.922016) (xy 413.757813 -132.958522) (xy 413.705879 -132.988506) (xy 413.650475 -133.011455)
			(xy 413.59255 -133.026976) (xy 413.533094 -133.034804) (xy 413.473126 -133.034804) (xy 413.41367 -133.026976)
			(xy 413.355745 -133.011455) (xy 413.300341 -132.988506) (xy 413.248407 -132.958522) (xy 413.200831 -132.922016)
			(xy 413.158426 -132.879611) (xy 413.12192 -132.832035) (xy 413.091936 -132.780101) (xy 413.068987 -132.724697)
			(xy 413.053466 -132.666772) (xy 413.045638 -132.607316) (xy 413.045148 -132.577332) (xy 401.000468 -132.577332)
			(xy 401.000468 -133.096508) (xy 400.999978 -133.126476) (xy 400.992155 -133.185898) (xy 400.976642 -133.243791)
			(xy 400.953706 -133.299164) (xy 400.923739 -133.35107) (xy 400.887252 -133.39862) (xy 400.844872 -133.441)
			(xy 400.797322 -133.477487) (xy 400.745416 -133.507454) (xy 400.690043 -133.53039) (xy 400.63215 -133.545903)
			(xy 400.572728 -133.553726) (xy 400.512792 -133.553726) (xy 400.45337 -133.545903) (xy 400.395477 -133.53039)
			(xy 400.340104 -133.507454) (xy 400.288198 -133.477487) (xy 400.240648 -133.441) (xy 400.198268 -133.39862)
			(xy 400.161781 -133.35107) (xy 400.131814 -133.299164) (xy 400.108878 -133.243791) (xy 400.093365 -133.185898)
			(xy 400.085542 -133.126476) (xy 400.085052 -133.096508) (xy 386.525516 -133.096508) (xy 386.525516 -133.104382)
			(xy 386.525026 -133.13435) (xy 386.517203 -133.193772) (xy 386.50169 -133.251665) (xy 386.478754 -133.307038)
			(xy 386.448787 -133.358944) (xy 386.4123 -133.406494) (xy 386.36992 -133.448874) (xy 386.32237 -133.485361)
			(xy 386.270464 -133.515328) (xy 386.215091 -133.538264) (xy 386.157198 -133.553777) (xy 386.097776 -133.5616)
			(xy 386.03784 -133.5616) (xy 385.978418 -133.553777) (xy 385.920525 -133.538264) (xy 385.865152 -133.515328)
			(xy 385.813246 -133.485361) (xy 385.765696 -133.448874) (xy 385.723316 -133.406494) (xy 385.686829 -133.358944)
			(xy 385.656862 -133.307038) (xy 385.633926 -133.251665) (xy 385.618413 -133.193772) (xy 385.61059 -133.13435)
			(xy 385.6101 -133.104382) (xy 313.951493 -133.104382) (xy 313.986726 -133.124723) (xy 314.034276 -133.16121)
			(xy 314.076656 -133.20359) (xy 314.113143 -133.25114) (xy 314.14311 -133.303046) (xy 314.166046 -133.358419)
			(xy 314.181559 -133.416312) (xy 314.189382 -133.475734) (xy 314.189872 -133.505702) (xy 314.189872 -134.369302)
			(xy 314.189382 -134.39927) (xy 314.181559 -134.458692) (xy 314.166046 -134.516585) (xy 314.14311 -134.571958)
			(xy 314.113143 -134.623864) (xy 314.076656 -134.671414) (xy 314.034276 -134.713794) (xy 313.986726 -134.750281)
			(xy 313.93482 -134.780248) (xy 313.879447 -134.803184) (xy 313.821554 -134.818697) (xy 313.762132 -134.82652)
			(xy 313.702196 -134.82652) (xy 313.642774 -134.818697) (xy 313.584881 -134.803184) (xy 313.529508 -134.780248)
			(xy 313.477602 -134.750281) (xy 313.430052 -134.713794) (xy 313.387672 -134.671414) (xy 313.351185 -134.623864)
			(xy 313.321218 -134.571958) (xy 313.298282 -134.516585) (xy 313.282769 -134.458692) (xy 313.274946 -134.39927)
			(xy 313.274456 -134.369302) (xy 299.71492 -134.369302) (xy 299.71492 -134.377176) (xy 299.71443 -134.407144)
			(xy 299.706607 -134.466566) (xy 299.691094 -134.524459) (xy 299.668158 -134.579832) (xy 299.638191 -134.631738)
			(xy 299.601704 -134.679288) (xy 299.559324 -134.721668) (xy 299.511774 -134.758155) (xy 299.459868 -134.788122)
			(xy 299.404495 -134.811058) (xy 299.346602 -134.826571) (xy 299.28718 -134.834394) (xy 299.227244 -134.834394)
			(xy 299.167822 -134.826571) (xy 299.109929 -134.811058) (xy 299.054556 -134.788122) (xy 299.00265 -134.758155)
			(xy 298.9551 -134.721668) (xy 298.91272 -134.679288) (xy 298.876233 -134.631738) (xy 298.846266 -134.579832)
			(xy 298.82333 -134.524459) (xy 298.807817 -134.466566) (xy 298.799994 -134.407144) (xy 298.799504 -134.377176)
			(xy 286.754824 -134.377176) (xy 286.754824 -134.896352) (xy 286.754334 -134.926336) (xy 286.746506 -134.985792)
			(xy 286.730985 -135.043717) (xy 286.708036 -135.099121) (xy 286.678052 -135.151055) (xy 286.641546 -135.198631)
			(xy 286.599141 -135.241036) (xy 286.551565 -135.277542) (xy 286.499631 -135.307526) (xy 286.444227 -135.330475)
			(xy 286.386302 -135.345996) (xy 286.326846 -135.353824) (xy 286.266878 -135.353824) (xy 286.207422 -135.345996)
			(xy 286.149497 -135.330475) (xy 286.094093 -135.307526) (xy 286.042159 -135.277542) (xy 285.994583 -135.241036)
			(xy 285.952178 -135.198631) (xy 285.915672 -135.151055) (xy 285.885688 -135.099121) (xy 285.862739 -135.043717)
			(xy 285.847218 -134.985792) (xy 285.83939 -134.926336) (xy 285.8389 -134.896352) (xy 267.783564 -134.896352)
			(xy 267.783564 -134.897876) (xy 267.783074 -134.92786) (xy 267.775246 -134.987316) (xy 267.759725 -135.045241)
			(xy 267.736776 -135.100645) (xy 267.706792 -135.152579) (xy 267.670286 -135.200155) (xy 267.627881 -135.24256)
			(xy 267.580305 -135.279066) (xy 267.528371 -135.30905) (xy 267.472967 -135.331999) (xy 267.415042 -135.34752)
			(xy 267.355586 -135.355348) (xy 267.295618 -135.355348) (xy 267.236162 -135.34752) (xy 267.178237 -135.331999)
			(xy 267.122833 -135.30905) (xy 267.070899 -135.279066) (xy 267.023323 -135.24256) (xy 266.980918 -135.200155)
			(xy 266.944412 -135.152579) (xy 266.914428 -135.100645) (xy 266.891479 -135.045241) (xy 266.875958 -134.987316)
			(xy 266.86813 -134.92786) (xy 266.86764 -134.897876) (xy 200.469049 -134.897876) (xy 200.477084 -134.901204)
			(xy 200.52899 -134.931171) (xy 200.57654 -134.967658) (xy 200.61892 -135.010038) (xy 200.655407 -135.057588)
			(xy 200.685374 -135.109494) (xy 200.70831 -135.164867) (xy 200.723823 -135.22276) (xy 200.731646 -135.282182)
			(xy 200.732136 -135.31215) (xy 200.732136 -136.17575) (xy 200.731646 -136.205718) (xy 200.723823 -136.26514)
			(xy 200.70831 -136.323033) (xy 200.685374 -136.378406) (xy 200.655407 -136.430312) (xy 200.61892 -136.477862)
			(xy 200.57654 -136.520242) (xy 200.52899 -136.556729) (xy 200.477084 -136.586696) (xy 200.421711 -136.609632)
			(xy 200.363818 -136.625145) (xy 200.304396 -136.632968) (xy 200.24446 -136.632968) (xy 200.185038 -136.625145)
			(xy 200.127145 -136.609632) (xy 200.071772 -136.586696) (xy 200.019866 -136.556729) (xy 199.972316 -136.520242)
			(xy 199.929936 -136.477862) (xy 199.893449 -136.430312) (xy 199.863482 -136.378406) (xy 199.840546 -136.323033)
			(xy 199.825033 -136.26514) (xy 199.81721 -136.205718) (xy 199.81672 -136.17575) (xy 181.760876 -136.17575)
			(xy 181.760876 -136.177274) (xy 181.760386 -136.207242) (xy 181.752563 -136.266664) (xy 181.73705 -136.324557)
			(xy 181.714114 -136.37993) (xy 181.684147 -136.431836) (xy 181.64766 -136.479386) (xy 181.60528 -136.521766)
			(xy 181.55773 -136.558253) (xy 181.505824 -136.58822) (xy 181.450451 -136.611156) (xy 181.392558 -136.626669)
			(xy 181.333136 -136.634492) (xy 181.2732 -136.634492) (xy 181.213778 -136.626669) (xy 181.155885 -136.611156)
			(xy 181.100512 -136.58822) (xy 181.048606 -136.558253) (xy 181.001056 -136.521766) (xy 180.958676 -136.479386)
			(xy 180.922189 -136.431836) (xy 180.892222 -136.37993) (xy 180.869286 -136.324557) (xy 180.853773 -136.266664)
			(xy 180.84595 -136.207242) (xy 180.84546 -136.177274) (xy 168.80078 -136.177274) (xy 168.80078 -136.69645)
			(xy 168.800651 -136.704324) (xy 269.509748 -136.704324) (xy 269.509748 -135.840724) (xy 269.510238 -135.81074)
			(xy 269.518066 -135.751284) (xy 269.533587 -135.693359) (xy 269.556536 -135.637955) (xy 269.58652 -135.586021)
			(xy 269.623026 -135.538445) (xy 269.665431 -135.49604) (xy 269.713007 -135.459534) (xy 269.764941 -135.42955)
			(xy 269.820345 -135.406601) (xy 269.87827 -135.39108) (xy 269.937726 -135.383252) (xy 269.997694 -135.383252)
			(xy 270.05715 -135.39108) (xy 270.115075 -135.406601) (xy 270.170479 -135.42955) (xy 270.222413 -135.459534)
			(xy 270.269989 -135.49604) (xy 270.312394 -135.538445) (xy 270.3489 -135.586021) (xy 270.378884 -135.637955)
			(xy 270.401833 -135.693359) (xy 270.417354 -135.751284) (xy 270.425182 -135.81074) (xy 270.425672 -135.840724)
			(xy 270.425672 -136.69645) (xy 283.9847 -136.69645) (xy 283.9847 -135.83285) (xy 283.98519 -135.802866)
			(xy 283.993018 -135.74341) (xy 284.008539 -135.685485) (xy 284.031488 -135.630081) (xy 284.061472 -135.578147)
			(xy 284.097978 -135.530571) (xy 284.140383 -135.488166) (xy 284.187959 -135.45166) (xy 284.239893 -135.421676)
			(xy 284.295297 -135.398727) (xy 284.353222 -135.383206) (xy 284.412678 -135.375378) (xy 284.472646 -135.375378)
			(xy 284.532102 -135.383206) (xy 284.590027 -135.398727) (xy 284.645431 -135.421676) (xy 284.697365 -135.45166)
			(xy 284.744941 -135.488166) (xy 284.787346 -135.530571) (xy 284.823852 -135.578147) (xy 284.853836 -135.630081)
			(xy 284.876785 -135.685485) (xy 284.892306 -135.74341) (xy 284.900134 -135.802866) (xy 284.900624 -135.83285)
			(xy 284.900624 -136.177274) (xy 296.945304 -136.177274) (xy 296.945304 -135.313674) (xy 296.945794 -135.283706)
			(xy 296.953617 -135.224284) (xy 296.96913 -135.166391) (xy 296.992066 -135.111018) (xy 297.022033 -135.059112)
			(xy 297.05852 -135.011562) (xy 297.1009 -134.969182) (xy 297.14845 -134.932695) (xy 297.200356 -134.902728)
			(xy 297.255729 -134.879792) (xy 297.313622 -134.864279) (xy 297.373044 -134.856456) (xy 297.43298 -134.856456)
			(xy 297.492402 -134.864279) (xy 297.550295 -134.879792) (xy 297.605668 -134.902728) (xy 297.657574 -134.932695)
			(xy 297.705124 -134.969182) (xy 297.747504 -135.011562) (xy 297.783991 -135.059112) (xy 297.813958 -135.111018)
			(xy 297.836894 -135.166391) (xy 297.852407 -135.224284) (xy 297.86023 -135.283706) (xy 297.86072 -135.313674)
			(xy 297.86072 -136.17575) (xy 315.916564 -136.17575) (xy 315.916564 -135.31215) (xy 315.917054 -135.282182)
			(xy 315.924877 -135.22276) (xy 315.94039 -135.164867) (xy 315.963326 -135.109494) (xy 315.993293 -135.057588)
			(xy 316.02978 -135.010038) (xy 316.07216 -134.967658) (xy 316.11971 -134.931171) (xy 316.171616 -134.901204)
			(xy 316.226989 -134.878268) (xy 316.284882 -134.862755) (xy 316.344304 -134.854932) (xy 316.40424 -134.854932)
			(xy 316.463662 -134.862755) (xy 316.521555 -134.878268) (xy 316.568893 -134.897876) (xy 382.967992 -134.897876)
			(xy 382.967992 -134.034276) (xy 382.968482 -134.004308) (xy 382.976305 -133.944886) (xy 382.991818 -133.886993)
			(xy 383.014754 -133.83162) (xy 383.044721 -133.779714) (xy 383.081208 -133.732164) (xy 383.123588 -133.689784)
			(xy 383.171138 -133.653297) (xy 383.223044 -133.62333) (xy 383.278417 -133.600394) (xy 383.33631 -133.584881)
			(xy 383.395732 -133.577058) (xy 383.455668 -133.577058) (xy 383.51509 -133.584881) (xy 383.572983 -133.600394)
			(xy 383.628356 -133.62333) (xy 383.680262 -133.653297) (xy 383.727812 -133.689784) (xy 383.770192 -133.732164)
			(xy 383.806679 -133.779714) (xy 383.836646 -133.83162) (xy 383.859582 -133.886993) (xy 383.875095 -133.944886)
			(xy 383.882918 -134.004308) (xy 383.883408 -134.034276) (xy 383.883408 -134.896352) (xy 401.939252 -134.896352)
			(xy 401.939252 -134.032752) (xy 401.939742 -134.002784) (xy 401.947565 -133.943362) (xy 401.963078 -133.885469)
			(xy 401.986014 -133.830096) (xy 402.015981 -133.77819) (xy 402.052468 -133.73064) (xy 402.094848 -133.68826)
			(xy 402.142398 -133.651773) (xy 402.194304 -133.621806) (xy 402.249677 -133.59887) (xy 402.30757 -133.583357)
			(xy 402.366992 -133.575534) (xy 402.426928 -133.575534) (xy 402.48635 -133.583357) (xy 402.544243 -133.59887)
			(xy 402.599616 -133.621806) (xy 402.651522 -133.651773) (xy 402.699072 -133.68826) (xy 402.741452 -133.73064)
			(xy 402.777939 -133.77819) (xy 402.807906 -133.830096) (xy 402.830842 -133.885469) (xy 402.846355 -133.943362)
			(xy 402.854178 -134.002784) (xy 402.854668 -134.032752) (xy 402.854668 -134.377176) (xy 414.899348 -134.377176)
			(xy 414.899348 -133.513576) (xy 414.899838 -133.483592) (xy 414.907666 -133.424136) (xy 414.923187 -133.366211)
			(xy 414.946136 -133.310807) (xy 414.97612 -133.258873) (xy 415.012626 -133.211297) (xy 415.055031 -133.168892)
			(xy 415.102607 -133.132386) (xy 415.154541 -133.102402) (xy 415.209945 -133.079453) (xy 415.26787 -133.063932)
			(xy 415.327326 -133.056104) (xy 415.387294 -133.056104) (xy 415.44675 -133.063932) (xy 415.504675 -133.079453)
			(xy 415.560079 -133.102402) (xy 415.612013 -133.132386) (xy 415.659589 -133.168892) (xy 415.701994 -133.211297)
			(xy 415.7385 -133.258873) (xy 415.768484 -133.310807) (xy 415.791433 -133.366211) (xy 415.806954 -133.424136)
			(xy 415.814782 -133.483592) (xy 415.815272 -133.513576) (xy 415.815272 -134.369302) (xy 429.3743 -134.369302)
			(xy 429.3743 -133.505702) (xy 429.37479 -133.475718) (xy 429.382618 -133.416262) (xy 429.398139 -133.358337)
			(xy 429.421088 -133.302933) (xy 429.451072 -133.250999) (xy 429.487578 -133.203423) (xy 429.529983 -133.161018)
			(xy 429.577559 -133.124512) (xy 429.629493 -133.094528) (xy 429.684897 -133.071579) (xy 429.742822 -133.056058)
			(xy 429.802278 -133.04823) (xy 429.862246 -133.04823) (xy 429.921702 -133.056058) (xy 429.979627 -133.071579)
			(xy 430.035031 -133.094528) (xy 430.086965 -133.124512) (xy 430.134541 -133.161018) (xy 430.176946 -133.203423)
			(xy 430.213452 -133.250999) (xy 430.243436 -133.302933) (xy 430.266385 -133.358337) (xy 430.281906 -133.416262)
			(xy 430.289734 -133.475718) (xy 430.290224 -133.505702) (xy 430.290224 -134.369302) (xy 430.289734 -134.399286)
			(xy 430.281906 -134.458742) (xy 430.266385 -134.516667) (xy 430.243436 -134.572071) (xy 430.213452 -134.624005)
			(xy 430.176946 -134.671581) (xy 430.134541 -134.713986) (xy 430.086965 -134.750492) (xy 430.035031 -134.780476)
			(xy 429.979627 -134.803425) (xy 429.921702 -134.818946) (xy 429.862246 -134.826774) (xy 429.802278 -134.826774)
			(xy 429.742822 -134.818946) (xy 429.684897 -134.803425) (xy 429.629493 -134.780476) (xy 429.577559 -134.750492)
			(xy 429.529983 -134.713986) (xy 429.487578 -134.671581) (xy 429.451072 -134.624005) (xy 429.421088 -134.572071)
			(xy 429.398139 -134.516667) (xy 429.382618 -134.458742) (xy 429.37479 -134.399286) (xy 429.3743 -134.369302)
			(xy 415.815272 -134.369302) (xy 415.815272 -134.377176) (xy 415.814782 -134.40716) (xy 415.806954 -134.466616)
			(xy 415.791433 -134.524541) (xy 415.768484 -134.579945) (xy 415.7385 -134.631879) (xy 415.701994 -134.679455)
			(xy 415.659589 -134.72186) (xy 415.612013 -134.758366) (xy 415.560079 -134.78835) (xy 415.504675 -134.811299)
			(xy 415.44675 -134.82682) (xy 415.387294 -134.834648) (xy 415.327326 -134.834648) (xy 415.26787 -134.82682)
			(xy 415.209945 -134.811299) (xy 415.154541 -134.78835) (xy 415.102607 -134.758366) (xy 415.055031 -134.72186)
			(xy 415.012626 -134.679455) (xy 414.97612 -134.631879) (xy 414.946136 -134.579945) (xy 414.923187 -134.524541)
			(xy 414.907666 -134.466616) (xy 414.899838 -134.40716) (xy 414.899348 -134.377176) (xy 402.854668 -134.377176)
			(xy 402.854668 -134.896352) (xy 402.854178 -134.92632) (xy 402.846355 -134.985742) (xy 402.830842 -135.043635)
			(xy 402.807906 -135.099008) (xy 402.777939 -135.150914) (xy 402.741452 -135.198464) (xy 402.699072 -135.240844)
			(xy 402.651522 -135.277331) (xy 402.599616 -135.307298) (xy 402.544243 -135.330234) (xy 402.48635 -135.345747)
			(xy 402.426928 -135.35357) (xy 402.366992 -135.35357) (xy 402.30757 -135.345747) (xy 402.249677 -135.330234)
			(xy 402.194304 -135.307298) (xy 402.142398 -135.277331) (xy 402.094848 -135.240844) (xy 402.052468 -135.198464)
			(xy 402.015981 -135.150914) (xy 401.986014 -135.099008) (xy 401.963078 -135.043635) (xy 401.947565 -134.985742)
			(xy 401.939742 -134.92632) (xy 401.939252 -134.896352) (xy 383.883408 -134.896352) (xy 383.883408 -134.897876)
			(xy 383.882918 -134.927844) (xy 383.875095 -134.987266) (xy 383.859582 -135.045159) (xy 383.836646 -135.100532)
			(xy 383.806679 -135.152438) (xy 383.770192 -135.199988) (xy 383.727812 -135.242368) (xy 383.680262 -135.278855)
			(xy 383.628356 -135.308822) (xy 383.572983 -135.331758) (xy 383.51509 -135.347271) (xy 383.455668 -135.355094)
			(xy 383.395732 -135.355094) (xy 383.33631 -135.347271) (xy 383.278417 -135.331758) (xy 383.223044 -135.308822)
			(xy 383.171138 -135.278855) (xy 383.123588 -135.242368) (xy 383.081208 -135.199988) (xy 383.044721 -135.152438)
			(xy 383.014754 -135.100532) (xy 382.991818 -135.045159) (xy 382.976305 -134.987266) (xy 382.968482 -134.927844)
			(xy 382.967992 -134.897876) (xy 316.568893 -134.897876) (xy 316.576928 -134.901204) (xy 316.628834 -134.931171)
			(xy 316.676384 -134.967658) (xy 316.718764 -135.010038) (xy 316.755251 -135.057588) (xy 316.785218 -135.109494)
			(xy 316.808154 -135.164867) (xy 316.823667 -135.22276) (xy 316.83149 -135.282182) (xy 316.83198 -135.31215)
			(xy 316.83198 -136.17575) (xy 316.83149 -136.205718) (xy 316.823667 -136.26514) (xy 316.808154 -136.323033)
			(xy 316.785218 -136.378406) (xy 316.755251 -136.430312) (xy 316.718764 -136.477862) (xy 316.676384 -136.520242)
			(xy 316.628834 -136.556729) (xy 316.576928 -136.586696) (xy 316.521555 -136.609632) (xy 316.463662 -136.625145)
			(xy 316.40424 -136.632968) (xy 316.344304 -136.632968) (xy 316.284882 -136.625145) (xy 316.226989 -136.609632)
			(xy 316.171616 -136.586696) (xy 316.11971 -136.556729) (xy 316.07216 -136.520242) (xy 316.02978 -136.477862)
			(xy 315.993293 -136.430312) (xy 315.963326 -136.378406) (xy 315.94039 -136.323033) (xy 315.924877 -136.26514)
			(xy 315.917054 -136.205718) (xy 315.916564 -136.17575) (xy 297.86072 -136.17575) (xy 297.86072 -136.177274)
			(xy 297.86023 -136.207242) (xy 297.852407 -136.266664) (xy 297.836894 -136.324557) (xy 297.813958 -136.37993)
			(xy 297.783991 -136.431836) (xy 297.747504 -136.479386) (xy 297.705124 -136.521766) (xy 297.657574 -136.558253)
			(xy 297.605668 -136.58822) (xy 297.550295 -136.611156) (xy 297.492402 -136.626669) (xy 297.43298 -136.634492)
			(xy 297.373044 -136.634492) (xy 297.313622 -136.626669) (xy 297.255729 -136.611156) (xy 297.200356 -136.58822)
			(xy 297.14845 -136.558253) (xy 297.1009 -136.521766) (xy 297.05852 -136.479386) (xy 297.022033 -136.431836)
			(xy 296.992066 -136.37993) (xy 296.96913 -136.324557) (xy 296.953617 -136.266664) (xy 296.945794 -136.207242)
			(xy 296.945304 -136.177274) (xy 284.900624 -136.177274) (xy 284.900624 -136.69645) (xy 284.900495 -136.704324)
			(xy 385.6101 -136.704324) (xy 385.6101 -135.840724) (xy 385.61059 -135.810756) (xy 385.618413 -135.751334)
			(xy 385.633926 -135.693441) (xy 385.656862 -135.638068) (xy 385.686829 -135.586162) (xy 385.723316 -135.538612)
			(xy 385.765696 -135.496232) (xy 385.813246 -135.459745) (xy 385.865152 -135.429778) (xy 385.920525 -135.406842)
			(xy 385.978418 -135.391329) (xy 386.03784 -135.383506) (xy 386.097776 -135.383506) (xy 386.157198 -135.391329)
			(xy 386.215091 -135.406842) (xy 386.270464 -135.429778) (xy 386.32237 -135.459745) (xy 386.36992 -135.496232)
			(xy 386.4123 -135.538612) (xy 386.448787 -135.586162) (xy 386.478754 -135.638068) (xy 386.50169 -135.693441)
			(xy 386.517203 -135.751334) (xy 386.525026 -135.810756) (xy 386.525516 -135.840724) (xy 386.525516 -136.69645)
			(xy 400.085052 -136.69645) (xy 400.085052 -135.83285) (xy 400.085542 -135.802882) (xy 400.093365 -135.74346)
			(xy 400.108878 -135.685567) (xy 400.131814 -135.630194) (xy 400.161781 -135.578288) (xy 400.198268 -135.530738)
			(xy 400.240648 -135.488358) (xy 400.288198 -135.451871) (xy 400.340104 -135.421904) (xy 400.395477 -135.398968)
			(xy 400.45337 -135.383455) (xy 400.512792 -135.375632) (xy 400.572728 -135.375632) (xy 400.63215 -135.383455)
			(xy 400.690043 -135.398968) (xy 400.745416 -135.421904) (xy 400.797322 -135.451871) (xy 400.844872 -135.488358)
			(xy 400.887252 -135.530738) (xy 400.923739 -135.578288) (xy 400.953706 -135.630194) (xy 400.976642 -135.685567)
			(xy 400.992155 -135.74346) (xy 400.999978 -135.802882) (xy 401.000468 -135.83285) (xy 401.000468 -136.177274)
			(xy 413.045148 -136.177274) (xy 413.045148 -135.313674) (xy 413.045638 -135.28369) (xy 413.053466 -135.224234)
			(xy 413.068987 -135.166309) (xy 413.091936 -135.110905) (xy 413.12192 -135.058971) (xy 413.158426 -135.011395)
			(xy 413.200831 -134.96899) (xy 413.248407 -134.932484) (xy 413.300341 -134.9025) (xy 413.355745 -134.879551)
			(xy 413.41367 -134.86403) (xy 413.473126 -134.856202) (xy 413.533094 -134.856202) (xy 413.59255 -134.86403)
			(xy 413.650475 -134.879551) (xy 413.705879 -134.9025) (xy 413.757813 -134.932484) (xy 413.805389 -134.96899)
			(xy 413.847794 -135.011395) (xy 413.8843 -135.058971) (xy 413.914284 -135.110905) (xy 413.937233 -135.166309)
			(xy 413.952754 -135.224234) (xy 413.960582 -135.28369) (xy 413.961072 -135.313674) (xy 413.961072 -136.17575)
			(xy 432.016408 -136.17575) (xy 432.016408 -135.31215) (xy 432.016898 -135.282166) (xy 432.024726 -135.22271)
			(xy 432.040247 -135.164785) (xy 432.063196 -135.109381) (xy 432.09318 -135.057447) (xy 432.129686 -135.009871)
			(xy 432.172091 -134.967466) (xy 432.219667 -134.93096) (xy 432.271601 -134.900976) (xy 432.327005 -134.878027)
			(xy 432.38493 -134.862506) (xy 432.444386 -134.854678) (xy 432.504354 -134.854678) (xy 432.56381 -134.862506)
			(xy 432.621735 -134.878027) (xy 432.677139 -134.900976) (xy 432.729073 -134.93096) (xy 432.776649 -134.967466)
			(xy 432.819054 -135.009871) (xy 432.85556 -135.057447) (xy 432.885544 -135.109381) (xy 432.908493 -135.164785)
			(xy 432.924014 -135.22271) (xy 432.931842 -135.282166) (xy 432.932332 -135.31215) (xy 432.932332 -136.17575)
			(xy 432.931842 -136.205734) (xy 432.924014 -136.26519) (xy 432.908493 -136.323115) (xy 432.885544 -136.378519)
			(xy 432.85556 -136.430453) (xy 432.819054 -136.478029) (xy 432.776649 -136.520434) (xy 432.729073 -136.55694)
			(xy 432.677139 -136.586924) (xy 432.621735 -136.609873) (xy 432.56381 -136.625394) (xy 432.504354 -136.633222)
			(xy 432.444386 -136.633222) (xy 432.38493 -136.625394) (xy 432.327005 -136.609873) (xy 432.271601 -136.586924)
			(xy 432.219667 -136.55694) (xy 432.172091 -136.520434) (xy 432.129686 -136.478029) (xy 432.09318 -136.430453)
			(xy 432.063196 -136.378519) (xy 432.040247 -136.323115) (xy 432.024726 -136.26519) (xy 432.016898 -136.205734)
			(xy 432.016408 -136.17575) (xy 413.961072 -136.17575) (xy 413.961072 -136.177274) (xy 413.960582 -136.207258)
			(xy 413.952754 -136.266714) (xy 413.937233 -136.324639) (xy 413.914284 -136.380043) (xy 413.8843 -136.431977)
			(xy 413.847794 -136.479553) (xy 413.805389 -136.521958) (xy 413.757813 -136.558464) (xy 413.705879 -136.588448)
			(xy 413.650475 -136.611397) (xy 413.59255 -136.626918) (xy 413.533094 -136.634746) (xy 413.473126 -136.634746)
			(xy 413.41367 -136.626918) (xy 413.355745 -136.611397) (xy 413.300341 -136.588448) (xy 413.248407 -136.558464)
			(xy 413.200831 -136.521958) (xy 413.158426 -136.479553) (xy 413.12192 -136.431977) (xy 413.091936 -136.380043)
			(xy 413.068987 -136.324639) (xy 413.053466 -136.266714) (xy 413.045638 -136.207258) (xy 413.045148 -136.177274)
			(xy 401.000468 -136.177274) (xy 401.000468 -136.69645) (xy 400.999978 -136.726418) (xy 400.992155 -136.78584)
			(xy 400.976642 -136.843733) (xy 400.953706 -136.899106) (xy 400.923739 -136.951012) (xy 400.887252 -136.998562)
			(xy 400.844872 -137.040942) (xy 400.797322 -137.077429) (xy 400.745416 -137.107396) (xy 400.690043 -137.130332)
			(xy 400.63215 -137.145845) (xy 400.572728 -137.153668) (xy 400.512792 -137.153668) (xy 400.45337 -137.145845)
			(xy 400.395477 -137.130332) (xy 400.340104 -137.107396) (xy 400.288198 -137.077429) (xy 400.240648 -137.040942)
			(xy 400.198268 -136.998562) (xy 400.161781 -136.951012) (xy 400.131814 -136.899106) (xy 400.108878 -136.843733)
			(xy 400.093365 -136.78584) (xy 400.085542 -136.726418) (xy 400.085052 -136.69645) (xy 386.525516 -136.69645)
			(xy 386.525516 -136.704324) (xy 386.525026 -136.734292) (xy 386.517203 -136.793714) (xy 386.50169 -136.851607)
			(xy 386.478754 -136.90698) (xy 386.448787 -136.958886) (xy 386.4123 -137.006436) (xy 386.36992 -137.048816)
			(xy 386.32237 -137.085303) (xy 386.270464 -137.11527) (xy 386.215091 -137.138206) (xy 386.157198 -137.153719)
			(xy 386.097776 -137.161542) (xy 386.03784 -137.161542) (xy 385.978418 -137.153719) (xy 385.920525 -137.138206)
			(xy 385.865152 -137.11527) (xy 385.813246 -137.085303) (xy 385.765696 -137.048816) (xy 385.723316 -137.006436)
			(xy 385.686829 -136.958886) (xy 385.656862 -136.90698) (xy 385.633926 -136.851607) (xy 385.618413 -136.793714)
			(xy 385.61059 -136.734292) (xy 385.6101 -136.704324) (xy 284.900495 -136.704324) (xy 284.900134 -136.726434)
			(xy 284.892306 -136.78589) (xy 284.876785 -136.843815) (xy 284.853836 -136.899219) (xy 284.823852 -136.951153)
			(xy 284.787346 -136.998729) (xy 284.744941 -137.041134) (xy 284.697365 -137.07764) (xy 284.645431 -137.107624)
			(xy 284.590027 -137.130573) (xy 284.532102 -137.146094) (xy 284.472646 -137.153922) (xy 284.412678 -137.153922)
			(xy 284.353222 -137.146094) (xy 284.295297 -137.130573) (xy 284.239893 -137.107624) (xy 284.187959 -137.07764)
			(xy 284.140383 -137.041134) (xy 284.097978 -136.998729) (xy 284.061472 -136.951153) (xy 284.031488 -136.899219)
			(xy 284.008539 -136.843815) (xy 283.993018 -136.78589) (xy 283.98519 -136.726434) (xy 283.9847 -136.69645)
			(xy 270.425672 -136.69645) (xy 270.425672 -136.704324) (xy 270.425182 -136.734308) (xy 270.417354 -136.793764)
			(xy 270.401833 -136.851689) (xy 270.378884 -136.907093) (xy 270.3489 -136.959027) (xy 270.312394 -137.006603)
			(xy 270.269989 -137.049008) (xy 270.222413 -137.085514) (xy 270.170479 -137.115498) (xy 270.115075 -137.138447)
			(xy 270.05715 -137.153968) (xy 269.997694 -137.161796) (xy 269.937726 -137.161796) (xy 269.87827 -137.153968)
			(xy 269.820345 -137.138447) (xy 269.764941 -137.115498) (xy 269.713007 -137.085514) (xy 269.665431 -137.049008)
			(xy 269.623026 -137.006603) (xy 269.58652 -136.959027) (xy 269.556536 -136.907093) (xy 269.533587 -136.851689)
			(xy 269.518066 -136.793764) (xy 269.510238 -136.734308) (xy 269.509748 -136.704324) (xy 168.800651 -136.704324)
			(xy 168.80029 -136.726434) (xy 168.792462 -136.78589) (xy 168.776941 -136.843815) (xy 168.753992 -136.899219)
			(xy 168.724008 -136.951153) (xy 168.687502 -136.998729) (xy 168.645097 -137.041134) (xy 168.597521 -137.07764)
			(xy 168.545587 -137.107624) (xy 168.490183 -137.130573) (xy 168.432258 -137.146094) (xy 168.372802 -137.153922)
			(xy 168.312834 -137.153922) (xy 168.253378 -137.146094) (xy 168.195453 -137.130573) (xy 168.140049 -137.107624)
			(xy 168.088115 -137.07764) (xy 168.040539 -137.041134) (xy 167.998134 -136.998729) (xy 167.961628 -136.951153)
			(xy 167.931644 -136.899219) (xy 167.908695 -136.843815) (xy 167.893174 -136.78589) (xy 167.885346 -136.726434)
			(xy 167.884856 -136.69645) (xy 154.325828 -136.69645) (xy 154.325828 -136.704324) (xy 154.325338 -136.734308)
			(xy 154.31751 -136.793764) (xy 154.301989 -136.851689) (xy 154.27904 -136.907093) (xy 154.249056 -136.959027)
			(xy 154.21255 -137.006603) (xy 154.170145 -137.049008) (xy 154.122569 -137.085514) (xy 154.070635 -137.115498)
			(xy 154.015231 -137.138447) (xy 153.957306 -137.153968) (xy 153.89785 -137.161796) (xy 153.837882 -137.161796)
			(xy 153.778426 -137.153968) (xy 153.720501 -137.138447) (xy 153.665097 -137.115498) (xy 153.613163 -137.085514)
			(xy 153.565587 -137.049008) (xy 153.523182 -137.006603) (xy 153.486676 -136.959027) (xy 153.456692 -136.907093)
			(xy 153.433743 -136.851689) (xy 153.418222 -136.793764) (xy 153.410394 -136.734308) (xy 153.409904 -136.704324)
			(xy 52.700299 -136.704324) (xy 52.699938 -136.726418) (xy 52.692115 -136.78584) (xy 52.676602 -136.843733)
			(xy 52.653666 -136.899106) (xy 52.623699 -136.951012) (xy 52.587212 -136.998562) (xy 52.544832 -137.040942)
			(xy 52.497282 -137.077429) (xy 52.445376 -137.107396) (xy 52.390003 -137.130332) (xy 52.33211 -137.145845)
			(xy 52.272688 -137.153668) (xy 52.212752 -137.153668) (xy 52.15333 -137.145845) (xy 52.095437 -137.130332)
			(xy 52.040064 -137.107396) (xy 51.988158 -137.077429) (xy 51.940608 -137.040942) (xy 51.898228 -136.998562)
			(xy 51.861741 -136.951012) (xy 51.831774 -136.899106) (xy 51.808838 -136.843733) (xy 51.793325 -136.78584)
			(xy 51.785502 -136.726418) (xy 51.785012 -136.69645) (xy 38.225476 -136.69645) (xy 38.225476 -136.704324)
			(xy 38.224986 -136.734292) (xy 38.217163 -136.793714) (xy 38.20165 -136.851607) (xy 38.178714 -136.90698)
			(xy 38.148747 -136.958886) (xy 38.11226 -137.006436) (xy 38.06988 -137.048816) (xy 38.02233 -137.085303)
			(xy 37.970424 -137.11527) (xy 37.915051 -137.138206) (xy 37.857158 -137.153719) (xy 37.797736 -137.161542)
			(xy 37.7378 -137.161542) (xy 37.678378 -137.153719) (xy 37.620485 -137.138206) (xy 37.565112 -137.11527)
			(xy 37.513206 -137.085303) (xy 37.465656 -137.048816) (xy 37.423276 -137.006436) (xy 37.386789 -136.958886)
			(xy 37.356822 -136.90698) (xy 37.333886 -136.851607) (xy 37.318373 -136.793714) (xy 37.31055 -136.734292)
			(xy 37.31006 -136.704324) (xy 4.308094 -136.704324) (xy 4.308094 -138.496548) (xy 43.97248 -138.496548)
			(xy 43.97248 -137.632948) (xy 43.97297 -137.602964) (xy 43.980798 -137.543508) (xy 43.996319 -137.485583)
			(xy 44.019268 -137.430179) (xy 44.049252 -137.378245) (xy 44.085758 -137.330669) (xy 44.128163 -137.288264)
			(xy 44.175739 -137.251758) (xy 44.227673 -137.221774) (xy 44.283077 -137.198825) (xy 44.341002 -137.183304)
			(xy 44.400458 -137.175476) (xy 44.460426 -137.175476) (xy 44.519882 -137.183304) (xy 44.577807 -137.198825)
			(xy 44.633211 -137.221774) (xy 44.685145 -137.251758) (xy 44.732721 -137.288264) (xy 44.775126 -137.330669)
			(xy 44.811632 -137.378245) (xy 44.841616 -137.430179) (xy 44.864565 -137.485583) (xy 44.880086 -137.543508)
			(xy 44.887914 -137.602964) (xy 44.888404 -137.632948) (xy 44.888404 -138.496548) (xy 160.072324 -138.496548)
			(xy 160.072324 -137.632948) (xy 160.072814 -137.602964) (xy 160.080642 -137.543508) (xy 160.096163 -137.485583)
			(xy 160.119112 -137.430179) (xy 160.149096 -137.378245) (xy 160.185602 -137.330669) (xy 160.228007 -137.288264)
			(xy 160.275583 -137.251758) (xy 160.327517 -137.221774) (xy 160.382921 -137.198825) (xy 160.440846 -137.183304)
			(xy 160.500302 -137.175476) (xy 160.56027 -137.175476) (xy 160.619726 -137.183304) (xy 160.677651 -137.198825)
			(xy 160.733055 -137.221774) (xy 160.784989 -137.251758) (xy 160.832565 -137.288264) (xy 160.87497 -137.330669)
			(xy 160.911476 -137.378245) (xy 160.94146 -137.430179) (xy 160.964409 -137.485583) (xy 160.97993 -137.543508)
			(xy 160.987758 -137.602964) (xy 160.988248 -137.632948) (xy 160.988248 -138.496548) (xy 276.172676 -138.496548)
			(xy 276.172676 -137.632948) (xy 276.173166 -137.60298) (xy 276.180989 -137.543558) (xy 276.196502 -137.485665)
			(xy 276.219438 -137.430292) (xy 276.249405 -137.378386) (xy 276.285892 -137.330836) (xy 276.328272 -137.288456)
			(xy 276.375822 -137.251969) (xy 276.427728 -137.222002) (xy 276.483101 -137.199066) (xy 276.540994 -137.183553)
			(xy 276.600416 -137.17573) (xy 276.660352 -137.17573) (xy 276.719774 -137.183553) (xy 276.777667 -137.199066)
			(xy 276.83304 -137.222002) (xy 276.884946 -137.251969) (xy 276.932496 -137.288456) (xy 276.974876 -137.330836)
			(xy 277.011363 -137.378386) (xy 277.04133 -137.430292) (xy 277.064266 -137.485665) (xy 277.079779 -137.543558)
			(xy 277.087602 -137.60298) (xy 277.088092 -137.632948) (xy 277.088092 -138.496548) (xy 277.088084 -138.497056)
			(xy 392.27252 -138.497056) (xy 392.27252 -137.633456) (xy 392.27301 -137.603472) (xy 392.280838 -137.544016)
			(xy 392.296359 -137.486091) (xy 392.319308 -137.430687) (xy 392.349292 -137.378753) (xy 392.385798 -137.331177)
			(xy 392.428203 -137.288772) (xy 392.475779 -137.252266) (xy 392.527713 -137.222282) (xy 392.583117 -137.199333)
			(xy 392.641042 -137.183812) (xy 392.700498 -137.175984) (xy 392.760466 -137.175984) (xy 392.819922 -137.183812)
			(xy 392.877847 -137.199333) (xy 392.933251 -137.222282) (xy 392.985185 -137.252266) (xy 393.032761 -137.288772)
			(xy 393.075166 -137.331177) (xy 393.111672 -137.378753) (xy 393.141656 -137.430687) (xy 393.164605 -137.486091)
			(xy 393.180126 -137.544016) (xy 393.187954 -137.603472) (xy 393.188444 -137.633456) (xy 393.188444 -138.497056)
			(xy 393.187954 -138.52704) (xy 393.180126 -138.586496) (xy 393.164605 -138.644421) (xy 393.141656 -138.699825)
			(xy 393.111672 -138.751759) (xy 393.075166 -138.799335) (xy 393.032761 -138.84174) (xy 392.985185 -138.878246)
			(xy 392.933251 -138.90823) (xy 392.877847 -138.931179) (xy 392.819922 -138.9467) (xy 392.760466 -138.954528)
			(xy 392.700498 -138.954528) (xy 392.641042 -138.9467) (xy 392.583117 -138.931179) (xy 392.527713 -138.90823)
			(xy 392.475779 -138.878246) (xy 392.428203 -138.84174) (xy 392.385798 -138.799335) (xy 392.349292 -138.751759)
			(xy 392.319308 -138.699825) (xy 392.296359 -138.644421) (xy 392.280838 -138.586496) (xy 392.27301 -138.52704)
			(xy 392.27252 -138.497056) (xy 277.088084 -138.497056) (xy 277.087602 -138.526516) (xy 277.079779 -138.585938)
			(xy 277.064266 -138.643831) (xy 277.04133 -138.699204) (xy 277.011363 -138.75111) (xy 276.974876 -138.79866)
			(xy 276.932496 -138.84104) (xy 276.884946 -138.877527) (xy 276.83304 -138.907494) (xy 276.777667 -138.93043)
			(xy 276.719774 -138.945943) (xy 276.660352 -138.953766) (xy 276.600416 -138.953766) (xy 276.540994 -138.945943)
			(xy 276.483101 -138.93043) (xy 276.427728 -138.907494) (xy 276.375822 -138.877527) (xy 276.328272 -138.84104)
			(xy 276.285892 -138.79866) (xy 276.249405 -138.75111) (xy 276.219438 -138.699204) (xy 276.196502 -138.643831)
			(xy 276.180989 -138.585938) (xy 276.173166 -138.526516) (xy 276.172676 -138.496548) (xy 160.988248 -138.496548)
			(xy 160.987758 -138.526532) (xy 160.97993 -138.585988) (xy 160.964409 -138.643913) (xy 160.94146 -138.699317)
			(xy 160.911476 -138.751251) (xy 160.87497 -138.798827) (xy 160.832565 -138.841232) (xy 160.784989 -138.877738)
			(xy 160.733055 -138.907722) (xy 160.677651 -138.930671) (xy 160.619726 -138.946192) (xy 160.56027 -138.95402)
			(xy 160.500302 -138.95402) (xy 160.440846 -138.946192) (xy 160.382921 -138.930671) (xy 160.327517 -138.907722)
			(xy 160.275583 -138.877738) (xy 160.228007 -138.841232) (xy 160.185602 -138.798827) (xy 160.149096 -138.751251)
			(xy 160.119112 -138.699317) (xy 160.096163 -138.643913) (xy 160.080642 -138.585988) (xy 160.072814 -138.526532)
			(xy 160.072324 -138.496548) (xy 44.888404 -138.496548) (xy 44.887914 -138.526532) (xy 44.880086 -138.585988)
			(xy 44.864565 -138.643913) (xy 44.841616 -138.699317) (xy 44.811632 -138.751251) (xy 44.775126 -138.798827)
			(xy 44.732721 -138.841232) (xy 44.685145 -138.877738) (xy 44.633211 -138.907722) (xy 44.577807 -138.930671)
			(xy 44.519882 -138.946192) (xy 44.460426 -138.95402) (xy 44.400458 -138.95402) (xy 44.341002 -138.946192)
			(xy 44.283077 -138.930671) (xy 44.227673 -138.907722) (xy 44.175739 -138.877738) (xy 44.128163 -138.841232)
			(xy 44.085758 -138.798827) (xy 44.049252 -138.751251) (xy 44.019268 -138.699317) (xy 43.996319 -138.643913)
			(xy 43.980798 -138.585988) (xy 43.97297 -138.526532) (xy 43.97248 -138.496548) (xy 4.308094 -138.496548)
			(xy 4.308094 -143.48714) (xy 66.599308 -143.48714) (xy 66.599308 -142.62354) (xy 66.599798 -142.593556)
			(xy 66.607626 -142.5341) (xy 66.623147 -142.476175) (xy 66.646096 -142.420771) (xy 66.67608 -142.368837)
			(xy 66.712586 -142.321261) (xy 66.754991 -142.278856) (xy 66.802567 -142.24235) (xy 66.854501 -142.212366)
			(xy 66.909905 -142.189417) (xy 66.96783 -142.173896) (xy 67.027286 -142.166068) (xy 67.087254 -142.166068)
			(xy 67.14671 -142.173896) (xy 67.204635 -142.189417) (xy 67.260039 -142.212366) (xy 67.311973 -142.24235)
			(xy 67.359549 -142.278856) (xy 67.401954 -142.321261) (xy 67.43846 -142.368837) (xy 67.468444 -142.420771)
			(xy 67.491393 -142.476175) (xy 67.506914 -142.5341) (xy 67.514742 -142.593556) (xy 67.515232 -142.62354)
			(xy 67.515232 -143.479266) (xy 81.07426 -143.479266) (xy 81.07426 -142.615666) (xy 81.07475 -142.585682)
			(xy 81.082578 -142.526226) (xy 81.098099 -142.468301) (xy 81.121048 -142.412897) (xy 81.151032 -142.360963)
			(xy 81.187538 -142.313387) (xy 81.229943 -142.270982) (xy 81.277519 -142.234476) (xy 81.329453 -142.204492)
			(xy 81.384857 -142.181543) (xy 81.442782 -142.166022) (xy 81.502238 -142.158194) (xy 81.562206 -142.158194)
			(xy 81.621662 -142.166022) (xy 81.679587 -142.181543) (xy 81.734991 -142.204492) (xy 81.786925 -142.234476)
			(xy 81.834501 -142.270982) (xy 81.876906 -142.313387) (xy 81.913412 -142.360963) (xy 81.943396 -142.412897)
			(xy 81.966345 -142.468301) (xy 81.981866 -142.526226) (xy 81.989694 -142.585682) (xy 81.990184 -142.615666)
			(xy 81.990184 -143.479266) (xy 81.990055 -143.48714) (xy 182.69966 -143.48714) (xy 182.69966 -142.62354)
			(xy 182.70015 -142.593572) (xy 182.707973 -142.53415) (xy 182.723486 -142.476257) (xy 182.746422 -142.420884)
			(xy 182.776389 -142.368978) (xy 182.812876 -142.321428) (xy 182.855256 -142.279048) (xy 182.902806 -142.242561)
			(xy 182.954712 -142.212594) (xy 183.010085 -142.189658) (xy 183.067978 -142.174145) (xy 183.1274 -142.166322)
			(xy 183.187336 -142.166322) (xy 183.246758 -142.174145) (xy 183.304651 -142.189658) (xy 183.360024 -142.212594)
			(xy 183.41193 -142.242561) (xy 183.45948 -142.279048) (xy 183.50186 -142.321428) (xy 183.538347 -142.368978)
			(xy 183.568314 -142.420884) (xy 183.59125 -142.476257) (xy 183.606763 -142.53415) (xy 183.614586 -142.593572)
			(xy 183.615076 -142.62354) (xy 183.615076 -143.479266) (xy 197.174612 -143.479266) (xy 197.174612 -142.615666)
			(xy 197.175102 -142.585698) (xy 197.182925 -142.526276) (xy 197.198438 -142.468383) (xy 197.221374 -142.41301)
			(xy 197.251341 -142.361104) (xy 197.287828 -142.313554) (xy 197.330208 -142.271174) (xy 197.377758 -142.234687)
			(xy 197.429664 -142.20472) (xy 197.485037 -142.181784) (xy 197.54293 -142.166271) (xy 197.602352 -142.158448)
			(xy 197.662288 -142.158448) (xy 197.72171 -142.166271) (xy 197.779603 -142.181784) (xy 197.834976 -142.20472)
			(xy 197.886882 -142.234687) (xy 197.934432 -142.271174) (xy 197.976812 -142.313554) (xy 198.013299 -142.361104)
			(xy 198.043266 -142.41301) (xy 198.066202 -142.468383) (xy 198.081715 -142.526276) (xy 198.089538 -142.585698)
			(xy 198.090028 -142.615666) (xy 198.090028 -143.479266) (xy 198.089899 -143.48714) (xy 298.799504 -143.48714)
			(xy 298.799504 -142.62354) (xy 298.799994 -142.593572) (xy 298.807817 -142.53415) (xy 298.82333 -142.476257)
			(xy 298.846266 -142.420884) (xy 298.876233 -142.368978) (xy 298.91272 -142.321428) (xy 298.9551 -142.279048)
			(xy 299.00265 -142.242561) (xy 299.054556 -142.212594) (xy 299.109929 -142.189658) (xy 299.167822 -142.174145)
			(xy 299.227244 -142.166322) (xy 299.28718 -142.166322) (xy 299.346602 -142.174145) (xy 299.404495 -142.189658)
			(xy 299.459868 -142.212594) (xy 299.511774 -142.242561) (xy 299.559324 -142.279048) (xy 299.601704 -142.321428)
			(xy 299.638191 -142.368978) (xy 299.668158 -142.420884) (xy 299.691094 -142.476257) (xy 299.706607 -142.53415)
			(xy 299.71443 -142.593572) (xy 299.71492 -142.62354) (xy 299.71492 -143.479266) (xy 313.274456 -143.479266)
			(xy 313.274456 -142.615666) (xy 313.274946 -142.585698) (xy 313.282769 -142.526276) (xy 313.298282 -142.468383)
			(xy 313.321218 -142.41301) (xy 313.351185 -142.361104) (xy 313.387672 -142.313554) (xy 313.430052 -142.271174)
			(xy 313.477602 -142.234687) (xy 313.529508 -142.20472) (xy 313.584881 -142.181784) (xy 313.642774 -142.166271)
			(xy 313.702196 -142.158448) (xy 313.762132 -142.158448) (xy 313.821554 -142.166271) (xy 313.879447 -142.181784)
			(xy 313.93482 -142.20472) (xy 313.986726 -142.234687) (xy 314.034276 -142.271174) (xy 314.076656 -142.313554)
			(xy 314.113143 -142.361104) (xy 314.14311 -142.41301) (xy 314.166046 -142.468383) (xy 314.181559 -142.526276)
			(xy 314.189382 -142.585698) (xy 314.189872 -142.615666) (xy 314.189872 -143.479266) (xy 314.189743 -143.48714)
			(xy 414.899348 -143.48714) (xy 414.899348 -142.62354) (xy 414.899838 -142.593556) (xy 414.907666 -142.5341)
			(xy 414.923187 -142.476175) (xy 414.946136 -142.420771) (xy 414.97612 -142.368837) (xy 415.012626 -142.321261)
			(xy 415.055031 -142.278856) (xy 415.102607 -142.24235) (xy 415.154541 -142.212366) (xy 415.209945 -142.189417)
			(xy 415.26787 -142.173896) (xy 415.327326 -142.166068) (xy 415.387294 -142.166068) (xy 415.44675 -142.173896)
			(xy 415.504675 -142.189417) (xy 415.560079 -142.212366) (xy 415.612013 -142.24235) (xy 415.659589 -142.278856)
			(xy 415.701994 -142.321261) (xy 415.7385 -142.368837) (xy 415.768484 -142.420771) (xy 415.791433 -142.476175)
			(xy 415.806954 -142.5341) (xy 415.814782 -142.593556) (xy 415.815272 -142.62354) (xy 415.815272 -143.479266)
			(xy 429.3743 -143.479266) (xy 429.3743 -142.615666) (xy 429.37479 -142.585682) (xy 429.382618 -142.526226)
			(xy 429.398139 -142.468301) (xy 429.421088 -142.412897) (xy 429.451072 -142.360963) (xy 429.487578 -142.313387)
			(xy 429.529983 -142.270982) (xy 429.577559 -142.234476) (xy 429.629493 -142.204492) (xy 429.684897 -142.181543)
			(xy 429.742822 -142.166022) (xy 429.802278 -142.158194) (xy 429.862246 -142.158194) (xy 429.921702 -142.166022)
			(xy 429.979627 -142.181543) (xy 430.035031 -142.204492) (xy 430.086965 -142.234476) (xy 430.134541 -142.270982)
			(xy 430.176946 -142.313387) (xy 430.213452 -142.360963) (xy 430.243436 -142.412897) (xy 430.266385 -142.468301)
			(xy 430.281906 -142.526226) (xy 430.289734 -142.585682) (xy 430.290224 -142.615666) (xy 430.290224 -143.479266)
			(xy 430.289734 -143.50925) (xy 430.281906 -143.568706) (xy 430.266385 -143.626631) (xy 430.243436 -143.682035)
			(xy 430.213452 -143.733969) (xy 430.176946 -143.781545) (xy 430.134541 -143.82395) (xy 430.086965 -143.860456)
			(xy 430.035031 -143.89044) (xy 429.979627 -143.913389) (xy 429.921702 -143.92891) (xy 429.862246 -143.936738)
			(xy 429.802278 -143.936738) (xy 429.742822 -143.92891) (xy 429.684897 -143.913389) (xy 429.629493 -143.89044)
			(xy 429.577559 -143.860456) (xy 429.529983 -143.82395) (xy 429.487578 -143.781545) (xy 429.451072 -143.733969)
			(xy 429.421088 -143.682035) (xy 429.398139 -143.626631) (xy 429.382618 -143.568706) (xy 429.37479 -143.50925)
			(xy 429.3743 -143.479266) (xy 415.815272 -143.479266) (xy 415.815272 -143.48714) (xy 415.814782 -143.517124)
			(xy 415.806954 -143.57658) (xy 415.791433 -143.634505) (xy 415.768484 -143.689909) (xy 415.7385 -143.741843)
			(xy 415.701994 -143.789419) (xy 415.659589 -143.831824) (xy 415.612013 -143.86833) (xy 415.560079 -143.898314)
			(xy 415.504675 -143.921263) (xy 415.44675 -143.936784) (xy 415.387294 -143.944612) (xy 415.327326 -143.944612)
			(xy 415.26787 -143.936784) (xy 415.209945 -143.921263) (xy 415.154541 -143.898314) (xy 415.102607 -143.86833)
			(xy 415.055031 -143.831824) (xy 415.012626 -143.789419) (xy 414.97612 -143.741843) (xy 414.946136 -143.689909)
			(xy 414.923187 -143.634505) (xy 414.907666 -143.57658) (xy 414.899838 -143.517124) (xy 414.899348 -143.48714)
			(xy 314.189743 -143.48714) (xy 314.189382 -143.509234) (xy 314.181559 -143.568656) (xy 314.166046 -143.626549)
			(xy 314.14311 -143.681922) (xy 314.113143 -143.733828) (xy 314.076656 -143.781378) (xy 314.034276 -143.823758)
			(xy 313.986726 -143.860245) (xy 313.93482 -143.890212) (xy 313.879447 -143.913148) (xy 313.821554 -143.928661)
			(xy 313.762132 -143.936484) (xy 313.702196 -143.936484) (xy 313.642774 -143.928661) (xy 313.584881 -143.913148)
			(xy 313.529508 -143.890212) (xy 313.477602 -143.860245) (xy 313.430052 -143.823758) (xy 313.387672 -143.781378)
			(xy 313.351185 -143.733828) (xy 313.321218 -143.681922) (xy 313.298282 -143.626549) (xy 313.282769 -143.568656)
			(xy 313.274946 -143.509234) (xy 313.274456 -143.479266) (xy 299.71492 -143.479266) (xy 299.71492 -143.48714)
			(xy 299.71443 -143.517108) (xy 299.706607 -143.57653) (xy 299.691094 -143.634423) (xy 299.668158 -143.689796)
			(xy 299.638191 -143.741702) (xy 299.601704 -143.789252) (xy 299.559324 -143.831632) (xy 299.511774 -143.868119)
			(xy 299.459868 -143.898086) (xy 299.404495 -143.921022) (xy 299.346602 -143.936535) (xy 299.28718 -143.944358)
			(xy 299.227244 -143.944358) (xy 299.167822 -143.936535) (xy 299.109929 -143.921022) (xy 299.054556 -143.898086)
			(xy 299.00265 -143.868119) (xy 298.9551 -143.831632) (xy 298.91272 -143.789252) (xy 298.876233 -143.741702)
			(xy 298.846266 -143.689796) (xy 298.82333 -143.634423) (xy 298.807817 -143.57653) (xy 298.799994 -143.517108)
			(xy 298.799504 -143.48714) (xy 198.089899 -143.48714) (xy 198.089538 -143.509234) (xy 198.081715 -143.568656)
			(xy 198.066202 -143.626549) (xy 198.043266 -143.681922) (xy 198.013299 -143.733828) (xy 197.976812 -143.781378)
			(xy 197.934432 -143.823758) (xy 197.886882 -143.860245) (xy 197.834976 -143.890212) (xy 197.779603 -143.913148)
			(xy 197.72171 -143.928661) (xy 197.662288 -143.936484) (xy 197.602352 -143.936484) (xy 197.54293 -143.928661)
			(xy 197.485037 -143.913148) (xy 197.429664 -143.890212) (xy 197.377758 -143.860245) (xy 197.330208 -143.823758)
			(xy 197.287828 -143.781378) (xy 197.251341 -143.733828) (xy 197.221374 -143.681922) (xy 197.198438 -143.626549)
			(xy 197.182925 -143.568656) (xy 197.175102 -143.509234) (xy 197.174612 -143.479266) (xy 183.615076 -143.479266)
			(xy 183.615076 -143.48714) (xy 183.614586 -143.517108) (xy 183.606763 -143.57653) (xy 183.59125 -143.634423)
			(xy 183.568314 -143.689796) (xy 183.538347 -143.741702) (xy 183.50186 -143.789252) (xy 183.45948 -143.831632)
			(xy 183.41193 -143.868119) (xy 183.360024 -143.898086) (xy 183.304651 -143.921022) (xy 183.246758 -143.936535)
			(xy 183.187336 -143.944358) (xy 183.1274 -143.944358) (xy 183.067978 -143.936535) (xy 183.010085 -143.921022)
			(xy 182.954712 -143.898086) (xy 182.902806 -143.868119) (xy 182.855256 -143.831632) (xy 182.812876 -143.789252)
			(xy 182.776389 -143.741702) (xy 182.746422 -143.689796) (xy 182.723486 -143.634423) (xy 182.707973 -143.57653)
			(xy 182.70015 -143.517108) (xy 182.69966 -143.48714) (xy 81.990055 -143.48714) (xy 81.989694 -143.50925)
			(xy 81.981866 -143.568706) (xy 81.966345 -143.626631) (xy 81.943396 -143.682035) (xy 81.913412 -143.733969)
			(xy 81.876906 -143.781545) (xy 81.834501 -143.82395) (xy 81.786925 -143.860456) (xy 81.734991 -143.89044)
			(xy 81.679587 -143.913389) (xy 81.621662 -143.92891) (xy 81.562206 -143.936738) (xy 81.502238 -143.936738)
			(xy 81.442782 -143.92891) (xy 81.384857 -143.913389) (xy 81.329453 -143.89044) (xy 81.277519 -143.860456)
			(xy 81.229943 -143.82395) (xy 81.187538 -143.781545) (xy 81.151032 -143.733969) (xy 81.121048 -143.682035)
			(xy 81.098099 -143.626631) (xy 81.082578 -143.568706) (xy 81.07475 -143.50925) (xy 81.07426 -143.479266)
			(xy 67.515232 -143.479266) (xy 67.515232 -143.48714) (xy 67.514742 -143.517124) (xy 67.506914 -143.57658)
			(xy 67.491393 -143.634505) (xy 67.468444 -143.689909) (xy 67.43846 -143.741843) (xy 67.401954 -143.789419)
			(xy 67.359549 -143.831824) (xy 67.311973 -143.86833) (xy 67.260039 -143.898314) (xy 67.204635 -143.921263)
			(xy 67.14671 -143.936784) (xy 67.087254 -143.944612) (xy 67.027286 -143.944612) (xy 66.96783 -143.936784)
			(xy 66.909905 -143.921263) (xy 66.854501 -143.898314) (xy 66.802567 -143.86833) (xy 66.754991 -143.831824)
			(xy 66.712586 -143.789419) (xy 66.67608 -143.741843) (xy 66.646096 -143.689909) (xy 66.623147 -143.634505)
			(xy 66.607626 -143.57658) (xy 66.599798 -143.517124) (xy 66.599308 -143.48714) (xy 4.308094 -143.48714)
			(xy 4.308094 -145.287238) (xy 64.745108 -145.287238) (xy 64.745108 -144.423638) (xy 64.745598 -144.393654)
			(xy 64.753426 -144.334198) (xy 64.768947 -144.276273) (xy 64.791896 -144.220869) (xy 64.82188 -144.168935)
			(xy 64.858386 -144.121359) (xy 64.900791 -144.078954) (xy 64.948367 -144.042448) (xy 65.000301 -144.012464)
			(xy 65.055705 -143.989515) (xy 65.11363 -143.973994) (xy 65.173086 -143.966166) (xy 65.233054 -143.966166)
			(xy 65.29251 -143.973994) (xy 65.350435 -143.989515) (xy 65.405839 -144.012464) (xy 65.457773 -144.042448)
			(xy 65.505349 -144.078954) (xy 65.547754 -144.121359) (xy 65.58426 -144.168935) (xy 65.614244 -144.220869)
			(xy 65.637193 -144.276273) (xy 65.652714 -144.334198) (xy 65.660542 -144.393654) (xy 65.661032 -144.423638)
			(xy 65.661032 -145.285714) (xy 83.716368 -145.285714) (xy 83.716368 -144.422114) (xy 83.716858 -144.39213)
			(xy 83.724686 -144.332674) (xy 83.740207 -144.274749) (xy 83.763156 -144.219345) (xy 83.79314 -144.167411)
			(xy 83.829646 -144.119835) (xy 83.872051 -144.07743) (xy 83.919627 -144.040924) (xy 83.971561 -144.01094)
			(xy 84.026965 -143.987991) (xy 84.08489 -143.97247) (xy 84.144346 -143.964642) (xy 84.204314 -143.964642)
			(xy 84.26377 -143.97247) (xy 84.321695 -143.987991) (xy 84.377099 -144.01094) (xy 84.429033 -144.040924)
			(xy 84.476609 -144.07743) (xy 84.519014 -144.119835) (xy 84.55552 -144.167411) (xy 84.585504 -144.219345)
			(xy 84.608453 -144.274749) (xy 84.623974 -144.332674) (xy 84.631802 -144.39213) (xy 84.632292 -144.422114)
			(xy 84.632292 -145.285714) (xy 84.632267 -145.287238) (xy 180.84546 -145.287238) (xy 180.84546 -144.423638)
			(xy 180.84595 -144.39367) (xy 180.853773 -144.334248) (xy 180.869286 -144.276355) (xy 180.892222 -144.220982)
			(xy 180.922189 -144.169076) (xy 180.958676 -144.121526) (xy 181.001056 -144.079146) (xy 181.048606 -144.042659)
			(xy 181.100512 -144.012692) (xy 181.155885 -143.989756) (xy 181.213778 -143.974243) (xy 181.2732 -143.96642)
			(xy 181.333136 -143.96642) (xy 181.392558 -143.974243) (xy 181.450451 -143.989756) (xy 181.505824 -144.012692)
			(xy 181.55773 -144.042659) (xy 181.60528 -144.079146) (xy 181.64766 -144.121526) (xy 181.684147 -144.169076)
			(xy 181.714114 -144.220982) (xy 181.73705 -144.276355) (xy 181.752563 -144.334248) (xy 181.760386 -144.39367)
			(xy 181.760876 -144.423638) (xy 181.760876 -145.285714) (xy 199.81672 -145.285714) (xy 199.81672 -144.422114)
			(xy 199.81721 -144.392146) (xy 199.825033 -144.332724) (xy 199.840546 -144.274831) (xy 199.863482 -144.219458)
			(xy 199.893449 -144.167552) (xy 199.929936 -144.120002) (xy 199.972316 -144.077622) (xy 200.019866 -144.041135)
			(xy 200.071772 -144.011168) (xy 200.127145 -143.988232) (xy 200.185038 -143.972719) (xy 200.24446 -143.964896)
			(xy 200.304396 -143.964896) (xy 200.363818 -143.972719) (xy 200.421711 -143.988232) (xy 200.477084 -144.011168)
			(xy 200.52899 -144.041135) (xy 200.57654 -144.077622) (xy 200.61892 -144.120002) (xy 200.655407 -144.167552)
			(xy 200.685374 -144.219458) (xy 200.70831 -144.274831) (xy 200.723823 -144.332724) (xy 200.731646 -144.392146)
			(xy 200.732136 -144.422114) (xy 200.732136 -145.285714) (xy 200.732111 -145.287238) (xy 296.945304 -145.287238)
			(xy 296.945304 -144.423638) (xy 296.945794 -144.39367) (xy 296.953617 -144.334248) (xy 296.96913 -144.276355)
			(xy 296.992066 -144.220982) (xy 297.022033 -144.169076) (xy 297.05852 -144.121526) (xy 297.1009 -144.079146)
			(xy 297.14845 -144.042659) (xy 297.200356 -144.012692) (xy 297.255729 -143.989756) (xy 297.313622 -143.974243)
			(xy 297.373044 -143.96642) (xy 297.43298 -143.96642) (xy 297.492402 -143.974243) (xy 297.550295 -143.989756)
			(xy 297.605668 -144.012692) (xy 297.657574 -144.042659) (xy 297.705124 -144.079146) (xy 297.747504 -144.121526)
			(xy 297.783991 -144.169076) (xy 297.813958 -144.220982) (xy 297.836894 -144.276355) (xy 297.852407 -144.334248)
			(xy 297.86023 -144.39367) (xy 297.86072 -144.423638) (xy 297.86072 -145.285714) (xy 315.916564 -145.285714)
			(xy 315.916564 -144.422114) (xy 315.917054 -144.392146) (xy 315.924877 -144.332724) (xy 315.94039 -144.274831)
			(xy 315.963326 -144.219458) (xy 315.993293 -144.167552) (xy 316.02978 -144.120002) (xy 316.07216 -144.077622)
			(xy 316.11971 -144.041135) (xy 316.171616 -144.011168) (xy 316.226989 -143.988232) (xy 316.284882 -143.972719)
			(xy 316.344304 -143.964896) (xy 316.40424 -143.964896) (xy 316.463662 -143.972719) (xy 316.521555 -143.988232)
			(xy 316.576928 -144.011168) (xy 316.628834 -144.041135) (xy 316.676384 -144.077622) (xy 316.718764 -144.120002)
			(xy 316.755251 -144.167552) (xy 316.785218 -144.219458) (xy 316.808154 -144.274831) (xy 316.823667 -144.332724)
			(xy 316.83149 -144.392146) (xy 316.83198 -144.422114) (xy 316.83198 -145.285714) (xy 316.831955 -145.287238)
			(xy 413.045148 -145.287238) (xy 413.045148 -144.423638) (xy 413.045638 -144.393654) (xy 413.053466 -144.334198)
			(xy 413.068987 -144.276273) (xy 413.091936 -144.220869) (xy 413.12192 -144.168935) (xy 413.158426 -144.121359)
			(xy 413.200831 -144.078954) (xy 413.248407 -144.042448) (xy 413.300341 -144.012464) (xy 413.355745 -143.989515)
			(xy 413.41367 -143.973994) (xy 413.473126 -143.966166) (xy 413.533094 -143.966166) (xy 413.59255 -143.973994)
			(xy 413.650475 -143.989515) (xy 413.705879 -144.012464) (xy 413.757813 -144.042448) (xy 413.805389 -144.078954)
			(xy 413.847794 -144.121359) (xy 413.8843 -144.168935) (xy 413.914284 -144.220869) (xy 413.937233 -144.276273)
			(xy 413.952754 -144.334198) (xy 413.960582 -144.393654) (xy 413.961072 -144.423638) (xy 413.961072 -145.285714)
			(xy 432.016408 -145.285714) (xy 432.016408 -144.422114) (xy 432.016898 -144.39213) (xy 432.024726 -144.332674)
			(xy 432.040247 -144.274749) (xy 432.063196 -144.219345) (xy 432.09318 -144.167411) (xy 432.129686 -144.119835)
			(xy 432.172091 -144.07743) (xy 432.219667 -144.040924) (xy 432.271601 -144.01094) (xy 432.327005 -143.987991)
			(xy 432.38493 -143.97247) (xy 432.444386 -143.964642) (xy 432.504354 -143.964642) (xy 432.56381 -143.97247)
			(xy 432.621735 -143.987991) (xy 432.677139 -144.01094) (xy 432.729073 -144.040924) (xy 432.776649 -144.07743)
			(xy 432.819054 -144.119835) (xy 432.85556 -144.167411) (xy 432.885544 -144.219345) (xy 432.908493 -144.274749)
			(xy 432.924014 -144.332674) (xy 432.931842 -144.39213) (xy 432.932332 -144.422114) (xy 432.932332 -145.285714)
			(xy 432.931842 -145.315698) (xy 432.924014 -145.375154) (xy 432.908493 -145.433079) (xy 432.885544 -145.488483)
			(xy 432.85556 -145.540417) (xy 432.819054 -145.587993) (xy 432.776649 -145.630398) (xy 432.729073 -145.666904)
			(xy 432.677139 -145.696888) (xy 432.621735 -145.719837) (xy 432.56381 -145.735358) (xy 432.504354 -145.743186)
			(xy 432.444386 -145.743186) (xy 432.38493 -145.735358) (xy 432.327005 -145.719837) (xy 432.271601 -145.696888)
			(xy 432.219667 -145.666904) (xy 432.172091 -145.630398) (xy 432.129686 -145.587993) (xy 432.09318 -145.540417)
			(xy 432.063196 -145.488483) (xy 432.040247 -145.433079) (xy 432.024726 -145.375154) (xy 432.016898 -145.315698)
			(xy 432.016408 -145.285714) (xy 413.961072 -145.285714) (xy 413.961072 -145.287238) (xy 413.960582 -145.317222)
			(xy 413.952754 -145.376678) (xy 413.937233 -145.434603) (xy 413.914284 -145.490007) (xy 413.8843 -145.541941)
			(xy 413.847794 -145.589517) (xy 413.805389 -145.631922) (xy 413.757813 -145.668428) (xy 413.705879 -145.698412)
			(xy 413.650475 -145.721361) (xy 413.59255 -145.736882) (xy 413.533094 -145.74471) (xy 413.473126 -145.74471)
			(xy 413.41367 -145.736882) (xy 413.355745 -145.721361) (xy 413.300341 -145.698412) (xy 413.248407 -145.668428)
			(xy 413.200831 -145.631922) (xy 413.158426 -145.589517) (xy 413.12192 -145.541941) (xy 413.091936 -145.490007)
			(xy 413.068987 -145.434603) (xy 413.053466 -145.376678) (xy 413.045638 -145.317222) (xy 413.045148 -145.287238)
			(xy 316.831955 -145.287238) (xy 316.83149 -145.315682) (xy 316.823667 -145.375104) (xy 316.808154 -145.432997)
			(xy 316.785218 -145.48837) (xy 316.755251 -145.540276) (xy 316.718764 -145.587826) (xy 316.676384 -145.630206)
			(xy 316.628834 -145.666693) (xy 316.576928 -145.69666) (xy 316.521555 -145.719596) (xy 316.463662 -145.735109)
			(xy 316.40424 -145.742932) (xy 316.344304 -145.742932) (xy 316.284882 -145.735109) (xy 316.226989 -145.719596)
			(xy 316.171616 -145.69666) (xy 316.11971 -145.666693) (xy 316.07216 -145.630206) (xy 316.02978 -145.587826)
			(xy 315.993293 -145.540276) (xy 315.963326 -145.48837) (xy 315.94039 -145.432997) (xy 315.924877 -145.375104)
			(xy 315.917054 -145.315682) (xy 315.916564 -145.285714) (xy 297.86072 -145.285714) (xy 297.86072 -145.287238)
			(xy 297.86023 -145.317206) (xy 297.852407 -145.376628) (xy 297.836894 -145.434521) (xy 297.813958 -145.489894)
			(xy 297.783991 -145.5418) (xy 297.747504 -145.58935) (xy 297.705124 -145.63173) (xy 297.657574 -145.668217)
			(xy 297.605668 -145.698184) (xy 297.550295 -145.72112) (xy 297.492402 -145.736633) (xy 297.43298 -145.744456)
			(xy 297.373044 -145.744456) (xy 297.313622 -145.736633) (xy 297.255729 -145.72112) (xy 297.200356 -145.698184)
			(xy 297.14845 -145.668217) (xy 297.1009 -145.63173) (xy 297.05852 -145.58935) (xy 297.022033 -145.5418)
			(xy 296.992066 -145.489894) (xy 296.96913 -145.434521) (xy 296.953617 -145.376628) (xy 296.945794 -145.317206)
			(xy 296.945304 -145.287238) (xy 200.732111 -145.287238) (xy 200.731646 -145.315682) (xy 200.723823 -145.375104)
			(xy 200.70831 -145.432997) (xy 200.685374 -145.48837) (xy 200.655407 -145.540276) (xy 200.61892 -145.587826)
			(xy 200.57654 -145.630206) (xy 200.52899 -145.666693) (xy 200.477084 -145.69666) (xy 200.421711 -145.719596)
			(xy 200.363818 -145.735109) (xy 200.304396 -145.742932) (xy 200.24446 -145.742932) (xy 200.185038 -145.735109)
			(xy 200.127145 -145.719596) (xy 200.071772 -145.69666) (xy 200.019866 -145.666693) (xy 199.972316 -145.630206)
			(xy 199.929936 -145.587826) (xy 199.893449 -145.540276) (xy 199.863482 -145.48837) (xy 199.840546 -145.432997)
			(xy 199.825033 -145.375104) (xy 199.81721 -145.315682) (xy 199.81672 -145.285714) (xy 181.760876 -145.285714)
			(xy 181.760876 -145.287238) (xy 181.760386 -145.317206) (xy 181.752563 -145.376628) (xy 181.73705 -145.434521)
			(xy 181.714114 -145.489894) (xy 181.684147 -145.5418) (xy 181.64766 -145.58935) (xy 181.60528 -145.63173)
			(xy 181.55773 -145.668217) (xy 181.505824 -145.698184) (xy 181.450451 -145.72112) (xy 181.392558 -145.736633)
			(xy 181.333136 -145.744456) (xy 181.2732 -145.744456) (xy 181.213778 -145.736633) (xy 181.155885 -145.72112)
			(xy 181.100512 -145.698184) (xy 181.048606 -145.668217) (xy 181.001056 -145.63173) (xy 180.958676 -145.58935)
			(xy 180.922189 -145.5418) (xy 180.892222 -145.489894) (xy 180.869286 -145.434521) (xy 180.853773 -145.376628)
			(xy 180.84595 -145.317206) (xy 180.84546 -145.287238) (xy 84.632267 -145.287238) (xy 84.631802 -145.315698)
			(xy 84.623974 -145.375154) (xy 84.608453 -145.433079) (xy 84.585504 -145.488483) (xy 84.55552 -145.540417)
			(xy 84.519014 -145.587993) (xy 84.476609 -145.630398) (xy 84.429033 -145.666904) (xy 84.377099 -145.696888)
			(xy 84.321695 -145.719837) (xy 84.26377 -145.735358) (xy 84.204314 -145.743186) (xy 84.144346 -145.743186)
			(xy 84.08489 -145.735358) (xy 84.026965 -145.719837) (xy 83.971561 -145.696888) (xy 83.919627 -145.666904)
			(xy 83.872051 -145.630398) (xy 83.829646 -145.587993) (xy 83.79314 -145.540417) (xy 83.763156 -145.488483)
			(xy 83.740207 -145.433079) (xy 83.724686 -145.375154) (xy 83.716858 -145.315698) (xy 83.716368 -145.285714)
			(xy 65.661032 -145.285714) (xy 65.661032 -145.287238) (xy 65.660542 -145.317222) (xy 65.652714 -145.376678)
			(xy 65.637193 -145.434603) (xy 65.614244 -145.490007) (xy 65.58426 -145.541941) (xy 65.547754 -145.589517)
			(xy 65.505349 -145.631922) (xy 65.457773 -145.668428) (xy 65.405839 -145.698412) (xy 65.350435 -145.721361)
			(xy 65.29251 -145.736882) (xy 65.233054 -145.74471) (xy 65.173086 -145.74471) (xy 65.11363 -145.736882)
			(xy 65.055705 -145.721361) (xy 65.000301 -145.698412) (xy 64.948367 -145.668428) (xy 64.900791 -145.631922)
			(xy 64.858386 -145.589517) (xy 64.82188 -145.541941) (xy 64.791896 -145.490007) (xy 64.768947 -145.434603)
			(xy 64.753426 -145.376678) (xy 64.745598 -145.317222) (xy 64.745108 -145.287238) (xy 4.308094 -145.287238)
			(xy 4.308094 -147.087336) (xy 66.599308 -147.087336) (xy 66.599308 -146.223736) (xy 66.599798 -146.193752)
			(xy 66.607626 -146.134296) (xy 66.623147 -146.076371) (xy 66.646096 -146.020967) (xy 66.67608 -145.969033)
			(xy 66.712586 -145.921457) (xy 66.754991 -145.879052) (xy 66.802567 -145.842546) (xy 66.854501 -145.812562)
			(xy 66.909905 -145.789613) (xy 66.96783 -145.774092) (xy 67.027286 -145.766264) (xy 67.087254 -145.766264)
			(xy 67.14671 -145.774092) (xy 67.204635 -145.789613) (xy 67.260039 -145.812562) (xy 67.311973 -145.842546)
			(xy 67.359549 -145.879052) (xy 67.401954 -145.921457) (xy 67.43846 -145.969033) (xy 67.468444 -146.020967)
			(xy 67.491393 -146.076371) (xy 67.506914 -146.134296) (xy 67.514742 -146.193752) (xy 67.515232 -146.223736)
			(xy 67.515232 -147.079208) (xy 81.07426 -147.079208) (xy 81.07426 -146.215608) (xy 81.07475 -146.185624)
			(xy 81.082578 -146.126168) (xy 81.098099 -146.068243) (xy 81.121048 -146.012839) (xy 81.151032 -145.960905)
			(xy 81.187538 -145.913329) (xy 81.229943 -145.870924) (xy 81.277519 -145.834418) (xy 81.329453 -145.804434)
			(xy 81.384857 -145.781485) (xy 81.442782 -145.765964) (xy 81.502238 -145.758136) (xy 81.562206 -145.758136)
			(xy 81.621662 -145.765964) (xy 81.679587 -145.781485) (xy 81.734991 -145.804434) (xy 81.786925 -145.834418)
			(xy 81.834501 -145.870924) (xy 81.876906 -145.913329) (xy 81.913412 -145.960905) (xy 81.943396 -146.012839)
			(xy 81.966345 -146.068243) (xy 81.981866 -146.126168) (xy 81.989694 -146.185624) (xy 81.990184 -146.215608)
			(xy 81.990184 -147.079208) (xy 81.990051 -147.087336) (xy 182.69966 -147.087336) (xy 182.69966 -146.223736)
			(xy 182.70015 -146.193768) (xy 182.707973 -146.134346) (xy 182.723486 -146.076453) (xy 182.746422 -146.02108)
			(xy 182.776389 -145.969174) (xy 182.812876 -145.921624) (xy 182.855256 -145.879244) (xy 182.902806 -145.842757)
			(xy 182.954712 -145.81279) (xy 183.010085 -145.789854) (xy 183.067978 -145.774341) (xy 183.1274 -145.766518)
			(xy 183.187336 -145.766518) (xy 183.246758 -145.774341) (xy 183.304651 -145.789854) (xy 183.360024 -145.81279)
			(xy 183.41193 -145.842757) (xy 183.45948 -145.879244) (xy 183.50186 -145.921624) (xy 183.538347 -145.969174)
			(xy 183.568314 -146.02108) (xy 183.59125 -146.076453) (xy 183.606763 -146.134346) (xy 183.614586 -146.193768)
			(xy 183.615076 -146.223736) (xy 183.615076 -147.079208) (xy 197.174612 -147.079208) (xy 197.174612 -146.215608)
			(xy 197.175102 -146.18564) (xy 197.182925 -146.126218) (xy 197.198438 -146.068325) (xy 197.221374 -146.012952)
			(xy 197.251341 -145.961046) (xy 197.287828 -145.913496) (xy 197.330208 -145.871116) (xy 197.377758 -145.834629)
			(xy 197.429664 -145.804662) (xy 197.485037 -145.781726) (xy 197.54293 -145.766213) (xy 197.602352 -145.75839)
			(xy 197.662288 -145.75839) (xy 197.72171 -145.766213) (xy 197.779603 -145.781726) (xy 197.834976 -145.804662)
			(xy 197.886882 -145.834629) (xy 197.934432 -145.871116) (xy 197.976812 -145.913496) (xy 198.013299 -145.961046)
			(xy 198.043266 -146.012952) (xy 198.066202 -146.068325) (xy 198.081715 -146.126218) (xy 198.089538 -146.18564)
			(xy 198.090028 -146.215608) (xy 198.090028 -147.079208) (xy 198.089895 -147.087336) (xy 298.799504 -147.087336)
			(xy 298.799504 -146.223736) (xy 298.799994 -146.193768) (xy 298.807817 -146.134346) (xy 298.82333 -146.076453)
			(xy 298.846266 -146.02108) (xy 298.876233 -145.969174) (xy 298.91272 -145.921624) (xy 298.9551 -145.879244)
			(xy 299.00265 -145.842757) (xy 299.054556 -145.81279) (xy 299.109929 -145.789854) (xy 299.167822 -145.774341)
			(xy 299.227244 -145.766518) (xy 299.28718 -145.766518) (xy 299.346602 -145.774341) (xy 299.404495 -145.789854)
			(xy 299.459868 -145.81279) (xy 299.511774 -145.842757) (xy 299.559324 -145.879244) (xy 299.601704 -145.921624)
			(xy 299.638191 -145.969174) (xy 299.668158 -146.02108) (xy 299.691094 -146.076453) (xy 299.706607 -146.134346)
			(xy 299.71443 -146.193768) (xy 299.71492 -146.223736) (xy 299.71492 -147.079208) (xy 313.274456 -147.079208)
			(xy 313.274456 -146.215608) (xy 313.274946 -146.18564) (xy 313.282769 -146.126218) (xy 313.298282 -146.068325)
			(xy 313.321218 -146.012952) (xy 313.351185 -145.961046) (xy 313.387672 -145.913496) (xy 313.430052 -145.871116)
			(xy 313.477602 -145.834629) (xy 313.529508 -145.804662) (xy 313.584881 -145.781726) (xy 313.642774 -145.766213)
			(xy 313.702196 -145.75839) (xy 313.762132 -145.75839) (xy 313.821554 -145.766213) (xy 313.879447 -145.781726)
			(xy 313.93482 -145.804662) (xy 313.986726 -145.834629) (xy 314.034276 -145.871116) (xy 314.076656 -145.913496)
			(xy 314.113143 -145.961046) (xy 314.14311 -146.012952) (xy 314.166046 -146.068325) (xy 314.181559 -146.126218)
			(xy 314.189382 -146.18564) (xy 314.189872 -146.215608) (xy 314.189872 -147.079208) (xy 314.189739 -147.087336)
			(xy 414.899348 -147.087336) (xy 414.899348 -146.223736) (xy 414.899838 -146.193752) (xy 414.907666 -146.134296)
			(xy 414.923187 -146.076371) (xy 414.946136 -146.020967) (xy 414.97612 -145.969033) (xy 415.012626 -145.921457)
			(xy 415.055031 -145.879052) (xy 415.102607 -145.842546) (xy 415.154541 -145.812562) (xy 415.209945 -145.789613)
			(xy 415.26787 -145.774092) (xy 415.327326 -145.766264) (xy 415.387294 -145.766264) (xy 415.44675 -145.774092)
			(xy 415.504675 -145.789613) (xy 415.560079 -145.812562) (xy 415.612013 -145.842546) (xy 415.659589 -145.879052)
			(xy 415.701994 -145.921457) (xy 415.7385 -145.969033) (xy 415.768484 -146.020967) (xy 415.791433 -146.076371)
			(xy 415.806954 -146.134296) (xy 415.814782 -146.193752) (xy 415.815272 -146.223736) (xy 415.815272 -147.079208)
			(xy 429.3743 -147.079208) (xy 429.3743 -146.215608) (xy 429.37479 -146.185624) (xy 429.382618 -146.126168)
			(xy 429.398139 -146.068243) (xy 429.421088 -146.012839) (xy 429.451072 -145.960905) (xy 429.487578 -145.913329)
			(xy 429.529983 -145.870924) (xy 429.577559 -145.834418) (xy 429.629493 -145.804434) (xy 429.684897 -145.781485)
			(xy 429.742822 -145.765964) (xy 429.802278 -145.758136) (xy 429.862246 -145.758136) (xy 429.921702 -145.765964)
			(xy 429.979627 -145.781485) (xy 430.035031 -145.804434) (xy 430.086965 -145.834418) (xy 430.134541 -145.870924)
			(xy 430.176946 -145.913329) (xy 430.213452 -145.960905) (xy 430.243436 -146.012839) (xy 430.266385 -146.068243)
			(xy 430.281906 -146.126168) (xy 430.289734 -146.185624) (xy 430.290224 -146.215608) (xy 430.290224 -147.079208)
			(xy 430.289734 -147.109192) (xy 430.281906 -147.168648) (xy 430.266385 -147.226573) (xy 430.243436 -147.281977)
			(xy 430.213452 -147.333911) (xy 430.176946 -147.381487) (xy 430.134541 -147.423892) (xy 430.086965 -147.460398)
			(xy 430.035031 -147.490382) (xy 429.979627 -147.513331) (xy 429.921702 -147.528852) (xy 429.862246 -147.53668)
			(xy 429.802278 -147.53668) (xy 429.742822 -147.528852) (xy 429.684897 -147.513331) (xy 429.629493 -147.490382)
			(xy 429.577559 -147.460398) (xy 429.529983 -147.423892) (xy 429.487578 -147.381487) (xy 429.451072 -147.333911)
			(xy 429.421088 -147.281977) (xy 429.398139 -147.226573) (xy 429.382618 -147.168648) (xy 429.37479 -147.109192)
			(xy 429.3743 -147.079208) (xy 415.815272 -147.079208) (xy 415.815272 -147.087336) (xy 415.814782 -147.11732)
			(xy 415.806954 -147.176776) (xy 415.791433 -147.234701) (xy 415.768484 -147.290105) (xy 415.7385 -147.342039)
			(xy 415.701994 -147.389615) (xy 415.659589 -147.43202) (xy 415.612013 -147.468526) (xy 415.560079 -147.49851)
			(xy 415.504675 -147.521459) (xy 415.44675 -147.53698) (xy 415.387294 -147.544808) (xy 415.327326 -147.544808)
			(xy 415.26787 -147.53698) (xy 415.209945 -147.521459) (xy 415.154541 -147.49851) (xy 415.102607 -147.468526)
			(xy 415.055031 -147.43202) (xy 415.012626 -147.389615) (xy 414.97612 -147.342039) (xy 414.946136 -147.290105)
			(xy 414.923187 -147.234701) (xy 414.907666 -147.176776) (xy 414.899838 -147.11732) (xy 414.899348 -147.087336)
			(xy 314.189739 -147.087336) (xy 314.189382 -147.109176) (xy 314.181559 -147.168598) (xy 314.166046 -147.226491)
			(xy 314.14311 -147.281864) (xy 314.113143 -147.33377) (xy 314.076656 -147.38132) (xy 314.034276 -147.4237)
			(xy 313.986726 -147.460187) (xy 313.93482 -147.490154) (xy 313.879447 -147.51309) (xy 313.821554 -147.528603)
			(xy 313.762132 -147.536426) (xy 313.702196 -147.536426) (xy 313.642774 -147.528603) (xy 313.584881 -147.51309)
			(xy 313.529508 -147.490154) (xy 313.477602 -147.460187) (xy 313.430052 -147.4237) (xy 313.387672 -147.38132)
			(xy 313.351185 -147.33377) (xy 313.321218 -147.281864) (xy 313.298282 -147.226491) (xy 313.282769 -147.168598)
			(xy 313.274946 -147.109176) (xy 313.274456 -147.079208) (xy 299.71492 -147.079208) (xy 299.71492 -147.087336)
			(xy 299.71443 -147.117304) (xy 299.706607 -147.176726) (xy 299.691094 -147.234619) (xy 299.668158 -147.289992)
			(xy 299.638191 -147.341898) (xy 299.601704 -147.389448) (xy 299.559324 -147.431828) (xy 299.511774 -147.468315)
			(xy 299.459868 -147.498282) (xy 299.404495 -147.521218) (xy 299.346602 -147.536731) (xy 299.28718 -147.544554)
			(xy 299.227244 -147.544554) (xy 299.167822 -147.536731) (xy 299.109929 -147.521218) (xy 299.054556 -147.498282)
			(xy 299.00265 -147.468315) (xy 298.9551 -147.431828) (xy 298.91272 -147.389448) (xy 298.876233 -147.341898)
			(xy 298.846266 -147.289992) (xy 298.82333 -147.234619) (xy 298.807817 -147.176726) (xy 298.799994 -147.117304)
			(xy 298.799504 -147.087336) (xy 198.089895 -147.087336) (xy 198.089538 -147.109176) (xy 198.081715 -147.168598)
			(xy 198.066202 -147.226491) (xy 198.043266 -147.281864) (xy 198.013299 -147.33377) (xy 197.976812 -147.38132)
			(xy 197.934432 -147.4237) (xy 197.886882 -147.460187) (xy 197.834976 -147.490154) (xy 197.779603 -147.51309)
			(xy 197.72171 -147.528603) (xy 197.662288 -147.536426) (xy 197.602352 -147.536426) (xy 197.54293 -147.528603)
			(xy 197.485037 -147.51309) (xy 197.429664 -147.490154) (xy 197.377758 -147.460187) (xy 197.330208 -147.4237)
			(xy 197.287828 -147.38132) (xy 197.251341 -147.33377) (xy 197.221374 -147.281864) (xy 197.198438 -147.226491)
			(xy 197.182925 -147.168598) (xy 197.175102 -147.109176) (xy 197.174612 -147.079208) (xy 183.615076 -147.079208)
			(xy 183.615076 -147.087336) (xy 183.614586 -147.117304) (xy 183.606763 -147.176726) (xy 183.59125 -147.234619)
			(xy 183.568314 -147.289992) (xy 183.538347 -147.341898) (xy 183.50186 -147.389448) (xy 183.45948 -147.431828)
			(xy 183.41193 -147.468315) (xy 183.360024 -147.498282) (xy 183.304651 -147.521218) (xy 183.246758 -147.536731)
			(xy 183.187336 -147.544554) (xy 183.1274 -147.544554) (xy 183.067978 -147.536731) (xy 183.010085 -147.521218)
			(xy 182.954712 -147.498282) (xy 182.902806 -147.468315) (xy 182.855256 -147.431828) (xy 182.812876 -147.389448)
			(xy 182.776389 -147.341898) (xy 182.746422 -147.289992) (xy 182.723486 -147.234619) (xy 182.707973 -147.176726)
			(xy 182.70015 -147.117304) (xy 182.69966 -147.087336) (xy 81.990051 -147.087336) (xy 81.989694 -147.109192)
			(xy 81.981866 -147.168648) (xy 81.966345 -147.226573) (xy 81.943396 -147.281977) (xy 81.913412 -147.333911)
			(xy 81.876906 -147.381487) (xy 81.834501 -147.423892) (xy 81.786925 -147.460398) (xy 81.734991 -147.490382)
			(xy 81.679587 -147.513331) (xy 81.621662 -147.528852) (xy 81.562206 -147.53668) (xy 81.502238 -147.53668)
			(xy 81.442782 -147.528852) (xy 81.384857 -147.513331) (xy 81.329453 -147.490382) (xy 81.277519 -147.460398)
			(xy 81.229943 -147.423892) (xy 81.187538 -147.381487) (xy 81.151032 -147.333911) (xy 81.121048 -147.281977)
			(xy 81.098099 -147.226573) (xy 81.082578 -147.168648) (xy 81.07475 -147.109192) (xy 81.07426 -147.079208)
			(xy 67.515232 -147.079208) (xy 67.515232 -147.087336) (xy 67.514742 -147.11732) (xy 67.506914 -147.176776)
			(xy 67.491393 -147.234701) (xy 67.468444 -147.290105) (xy 67.43846 -147.342039) (xy 67.401954 -147.389615)
			(xy 67.359549 -147.43202) (xy 67.311973 -147.468526) (xy 67.260039 -147.49851) (xy 67.204635 -147.521459)
			(xy 67.14671 -147.53698) (xy 67.087254 -147.544808) (xy 67.027286 -147.544808) (xy 66.96783 -147.53698)
			(xy 66.909905 -147.521459) (xy 66.854501 -147.49851) (xy 66.802567 -147.468526) (xy 66.754991 -147.43202)
			(xy 66.712586 -147.389615) (xy 66.67608 -147.342039) (xy 66.646096 -147.290105) (xy 66.623147 -147.234701)
			(xy 66.607626 -147.176776) (xy 66.599798 -147.11732) (xy 66.599308 -147.087336) (xy 4.308094 -147.087336)
			(xy 4.308094 -148.887434) (xy 64.745108 -148.887434) (xy 64.745108 -148.023834) (xy 64.745598 -147.99385)
			(xy 64.753426 -147.934394) (xy 64.768947 -147.876469) (xy 64.791896 -147.821065) (xy 64.82188 -147.769131)
			(xy 64.858386 -147.721555) (xy 64.900791 -147.67915) (xy 64.948367 -147.642644) (xy 65.000301 -147.61266)
			(xy 65.055705 -147.589711) (xy 65.11363 -147.57419) (xy 65.173086 -147.566362) (xy 65.233054 -147.566362)
			(xy 65.29251 -147.57419) (xy 65.350435 -147.589711) (xy 65.405839 -147.61266) (xy 65.457773 -147.642644)
			(xy 65.505349 -147.67915) (xy 65.547754 -147.721555) (xy 65.58426 -147.769131) (xy 65.614244 -147.821065)
			(xy 65.637193 -147.876469) (xy 65.652714 -147.934394) (xy 65.660542 -147.99385) (xy 65.661032 -148.023834)
			(xy 65.661032 -148.88591) (xy 83.716368 -148.88591) (xy 83.716368 -148.02231) (xy 83.716858 -147.992326)
			(xy 83.724686 -147.93287) (xy 83.740207 -147.874945) (xy 83.763156 -147.819541) (xy 83.79314 -147.767607)
			(xy 83.829646 -147.720031) (xy 83.872051 -147.677626) (xy 83.919627 -147.64112) (xy 83.971561 -147.611136)
			(xy 84.026965 -147.588187) (xy 84.08489 -147.572666) (xy 84.144346 -147.564838) (xy 84.204314 -147.564838)
			(xy 84.26377 -147.572666) (xy 84.321695 -147.588187) (xy 84.377099 -147.611136) (xy 84.429033 -147.64112)
			(xy 84.476609 -147.677626) (xy 84.519014 -147.720031) (xy 84.55552 -147.767607) (xy 84.585504 -147.819541)
			(xy 84.608453 -147.874945) (xy 84.623974 -147.93287) (xy 84.631802 -147.992326) (xy 84.632292 -148.02231)
			(xy 84.632292 -148.88591) (xy 84.632267 -148.887434) (xy 180.84546 -148.887434) (xy 180.84546 -148.023834)
			(xy 180.84595 -147.993866) (xy 180.853773 -147.934444) (xy 180.869286 -147.876551) (xy 180.892222 -147.821178)
			(xy 180.922189 -147.769272) (xy 180.958676 -147.721722) (xy 181.001056 -147.679342) (xy 181.048606 -147.642855)
			(xy 181.100512 -147.612888) (xy 181.155885 -147.589952) (xy 181.213778 -147.574439) (xy 181.2732 -147.566616)
			(xy 181.333136 -147.566616) (xy 181.392558 -147.574439) (xy 181.450451 -147.589952) (xy 181.505824 -147.612888)
			(xy 181.55773 -147.642855) (xy 181.60528 -147.679342) (xy 181.64766 -147.721722) (xy 181.684147 -147.769272)
			(xy 181.714114 -147.821178) (xy 181.73705 -147.876551) (xy 181.752563 -147.934444) (xy 181.760386 -147.993866)
			(xy 181.760876 -148.023834) (xy 181.760876 -148.88591) (xy 199.81672 -148.88591) (xy 199.81672 -148.02231)
			(xy 199.81721 -147.992342) (xy 199.825033 -147.93292) (xy 199.840546 -147.875027) (xy 199.863482 -147.819654)
			(xy 199.893449 -147.767748) (xy 199.929936 -147.720198) (xy 199.972316 -147.677818) (xy 200.019866 -147.641331)
			(xy 200.071772 -147.611364) (xy 200.127145 -147.588428) (xy 200.185038 -147.572915) (xy 200.24446 -147.565092)
			(xy 200.304396 -147.565092) (xy 200.363818 -147.572915) (xy 200.421711 -147.588428) (xy 200.477084 -147.611364)
			(xy 200.52899 -147.641331) (xy 200.57654 -147.677818) (xy 200.61892 -147.720198) (xy 200.655407 -147.767748)
			(xy 200.685374 -147.819654) (xy 200.70831 -147.875027) (xy 200.723823 -147.93292) (xy 200.731646 -147.992342)
			(xy 200.732136 -148.02231) (xy 200.732136 -148.88591) (xy 200.731646 -148.915878) (xy 200.723823 -148.9753)
			(xy 200.70831 -149.033193) (xy 200.685374 -149.088566) (xy 200.655407 -149.140472) (xy 200.61892 -149.188022)
			(xy 200.57654 -149.230402) (xy 200.52899 -149.266889) (xy 200.477084 -149.296856) (xy 200.421711 -149.319792)
			(xy 200.363818 -149.335305) (xy 200.304396 -149.343128) (xy 200.24446 -149.343128) (xy 200.185038 -149.335305)
			(xy 200.127145 -149.319792) (xy 200.071772 -149.296856) (xy 200.019866 -149.266889) (xy 199.972316 -149.230402)
			(xy 199.929936 -149.188022) (xy 199.893449 -149.140472) (xy 199.863482 -149.088566) (xy 199.840546 -149.033193)
			(xy 199.825033 -148.9753) (xy 199.81721 -148.915878) (xy 199.81672 -148.88591) (xy 181.760876 -148.88591)
			(xy 181.760876 -148.887434) (xy 181.760386 -148.917402) (xy 181.752563 -148.976824) (xy 181.73705 -149.034717)
			(xy 181.714114 -149.09009) (xy 181.684147 -149.141996) (xy 181.64766 -149.189546) (xy 181.60528 -149.231926)
			(xy 181.55773 -149.268413) (xy 181.505824 -149.29838) (xy 181.450451 -149.321316) (xy 181.392558 -149.336829)
			(xy 181.333136 -149.344652) (xy 181.2732 -149.344652) (xy 181.213778 -149.336829) (xy 181.155885 -149.321316)
			(xy 181.100512 -149.29838) (xy 181.048606 -149.268413) (xy 181.001056 -149.231926) (xy 180.958676 -149.189546)
			(xy 180.922189 -149.141996) (xy 180.892222 -149.09009) (xy 180.869286 -149.034717) (xy 180.853773 -148.976824)
			(xy 180.84595 -148.917402) (xy 180.84546 -148.887434) (xy 84.632267 -148.887434) (xy 84.631802 -148.915894)
			(xy 84.623974 -148.97535) (xy 84.608453 -149.033275) (xy 84.585504 -149.088679) (xy 84.55552 -149.140613)
			(xy 84.519014 -149.188189) (xy 84.476609 -149.230594) (xy 84.429033 -149.2671) (xy 84.377099 -149.297084)
			(xy 84.321695 -149.320033) (xy 84.26377 -149.335554) (xy 84.204314 -149.343382) (xy 84.144346 -149.343382)
			(xy 84.08489 -149.335554) (xy 84.026965 -149.320033) (xy 83.971561 -149.297084) (xy 83.919627 -149.2671)
			(xy 83.872051 -149.230594) (xy 83.829646 -149.188189) (xy 83.79314 -149.140613) (xy 83.763156 -149.088679)
			(xy 83.740207 -149.033275) (xy 83.724686 -148.97535) (xy 83.716858 -148.915894) (xy 83.716368 -148.88591)
			(xy 65.661032 -148.88591) (xy 65.661032 -148.887434) (xy 65.660542 -148.917418) (xy 65.652714 -148.976874)
			(xy 65.637193 -149.034799) (xy 65.614244 -149.090203) (xy 65.58426 -149.142137) (xy 65.547754 -149.189713)
			(xy 65.505349 -149.232118) (xy 65.457773 -149.268624) (xy 65.405839 -149.298608) (xy 65.350435 -149.321557)
			(xy 65.29251 -149.337078) (xy 65.233054 -149.344906) (xy 65.173086 -149.344906) (xy 65.11363 -149.337078)
			(xy 65.055705 -149.321557) (xy 65.000301 -149.298608) (xy 64.948367 -149.268624) (xy 64.900791 -149.232118)
			(xy 64.858386 -149.189713) (xy 64.82188 -149.142137) (xy 64.791896 -149.090203) (xy 64.768947 -149.034799)
			(xy 64.753426 -148.976874) (xy 64.745598 -148.917418) (xy 64.745108 -148.887434) (xy 4.308094 -148.887434)
			(xy 4.308094 -150.687278) (xy 66.599308 -150.687278) (xy 66.599308 -149.823678) (xy 66.599798 -149.793694)
			(xy 66.607626 -149.734238) (xy 66.623147 -149.676313) (xy 66.646096 -149.620909) (xy 66.67608 -149.568975)
			(xy 66.712586 -149.521399) (xy 66.754991 -149.478994) (xy 66.802567 -149.442488) (xy 66.854501 -149.412504)
			(xy 66.909905 -149.389555) (xy 66.96783 -149.374034) (xy 67.027286 -149.366206) (xy 67.087254 -149.366206)
			(xy 67.14671 -149.374034) (xy 67.204635 -149.389555) (xy 67.260039 -149.412504) (xy 67.311973 -149.442488)
			(xy 67.359549 -149.478994) (xy 67.401954 -149.521399) (xy 67.43846 -149.568975) (xy 67.468444 -149.620909)
			(xy 67.491393 -149.676313) (xy 67.506914 -149.734238) (xy 67.514742 -149.793694) (xy 67.515232 -149.823678)
			(xy 67.515232 -150.67915) (xy 81.07426 -150.67915) (xy 81.07426 -149.81555) (xy 81.07475 -149.785566)
			(xy 81.082578 -149.72611) (xy 81.098099 -149.668185) (xy 81.121048 -149.612781) (xy 81.151032 -149.560847)
			(xy 81.187538 -149.513271) (xy 81.229943 -149.470866) (xy 81.277519 -149.43436) (xy 81.329453 -149.404376)
			(xy 81.384857 -149.381427) (xy 81.442782 -149.365906) (xy 81.502238 -149.358078) (xy 81.562206 -149.358078)
			(xy 81.621662 -149.365906) (xy 81.679587 -149.381427) (xy 81.734991 -149.404376) (xy 81.786925 -149.43436)
			(xy 81.834501 -149.470866) (xy 81.876906 -149.513271) (xy 81.913412 -149.560847) (xy 81.943396 -149.612781)
			(xy 81.966345 -149.668185) (xy 81.981866 -149.72611) (xy 81.989694 -149.785566) (xy 81.990184 -149.81555)
			(xy 81.990184 -150.67915) (xy 81.990051 -150.687278) (xy 182.69966 -150.687278) (xy 182.69966 -149.823678)
			(xy 182.70015 -149.79371) (xy 182.707973 -149.734288) (xy 182.723486 -149.676395) (xy 182.746422 -149.621022)
			(xy 182.776389 -149.569116) (xy 182.812876 -149.521566) (xy 182.855256 -149.479186) (xy 182.902806 -149.442699)
			(xy 182.954712 -149.412732) (xy 183.010085 -149.389796) (xy 183.067978 -149.374283) (xy 183.1274 -149.36646)
			(xy 183.187336 -149.36646) (xy 183.246758 -149.374283) (xy 183.304651 -149.389796) (xy 183.360024 -149.412732)
			(xy 183.41193 -149.442699) (xy 183.45948 -149.479186) (xy 183.50186 -149.521566) (xy 183.538347 -149.569116)
			(xy 183.568314 -149.621022) (xy 183.59125 -149.676395) (xy 183.606763 -149.734288) (xy 183.614586 -149.79371)
			(xy 183.615076 -149.823678) (xy 183.615076 -150.67915) (xy 197.174612 -150.67915) (xy 197.174612 -149.81555)
			(xy 197.175102 -149.785582) (xy 197.182925 -149.72616) (xy 197.198438 -149.668267) (xy 197.221374 -149.612894)
			(xy 197.251341 -149.560988) (xy 197.287828 -149.513438) (xy 197.330208 -149.471058) (xy 197.377758 -149.434571)
			(xy 197.429664 -149.404604) (xy 197.485037 -149.381668) (xy 197.54293 -149.366155) (xy 197.602352 -149.358332)
			(xy 197.662288 -149.358332) (xy 197.72171 -149.366155) (xy 197.779603 -149.381668) (xy 197.834976 -149.404604)
			(xy 197.886882 -149.434571) (xy 197.934432 -149.471058) (xy 197.976812 -149.513438) (xy 198.013299 -149.560988)
			(xy 198.043266 -149.612894) (xy 198.066202 -149.668267) (xy 198.072386 -149.691344) (xy 236.708188 -149.691344)
			(xy 236.708188 -148.827744) (xy 236.708678 -148.79776) (xy 236.716506 -148.738304) (xy 236.732027 -148.680379)
			(xy 236.754976 -148.624975) (xy 236.78496 -148.573041) (xy 236.821466 -148.525465) (xy 236.863871 -148.48306)
			(xy 236.911447 -148.446554) (xy 236.963381 -148.41657) (xy 237.018785 -148.393621) (xy 237.07671 -148.3781)
			(xy 237.136166 -148.370272) (xy 237.196134 -148.370272) (xy 237.25559 -148.3781) (xy 237.313515 -148.393621)
			(xy 237.368919 -148.41657) (xy 237.420853 -148.446554) (xy 237.468429 -148.48306) (xy 237.510834 -148.525465)
			(xy 237.54734 -148.573041) (xy 237.577324 -148.624975) (xy 237.600273 -148.680379) (xy 237.615794 -148.738304)
			(xy 237.623622 -148.79776) (xy 237.624112 -148.827744) (xy 237.624112 -148.887434) (xy 296.945304 -148.887434)
			(xy 296.945304 -148.023834) (xy 296.945794 -147.993866) (xy 296.953617 -147.934444) (xy 296.96913 -147.876551)
			(xy 296.992066 -147.821178) (xy 297.022033 -147.769272) (xy 297.05852 -147.721722) (xy 297.1009 -147.679342)
			(xy 297.14845 -147.642855) (xy 297.200356 -147.612888) (xy 297.255729 -147.589952) (xy 297.313622 -147.574439)
			(xy 297.373044 -147.566616) (xy 297.43298 -147.566616) (xy 297.492402 -147.574439) (xy 297.550295 -147.589952)
			(xy 297.605668 -147.612888) (xy 297.657574 -147.642855) (xy 297.705124 -147.679342) (xy 297.747504 -147.721722)
			(xy 297.783991 -147.769272) (xy 297.813958 -147.821178) (xy 297.836894 -147.876551) (xy 297.852407 -147.934444)
			(xy 297.86023 -147.993866) (xy 297.86072 -148.023834) (xy 297.86072 -148.88591) (xy 315.916564 -148.88591)
			(xy 315.916564 -148.02231) (xy 315.917054 -147.992342) (xy 315.924877 -147.93292) (xy 315.94039 -147.875027)
			(xy 315.963326 -147.819654) (xy 315.993293 -147.767748) (xy 316.02978 -147.720198) (xy 316.07216 -147.677818)
			(xy 316.11971 -147.641331) (xy 316.171616 -147.611364) (xy 316.226989 -147.588428) (xy 316.284882 -147.572915)
			(xy 316.344304 -147.565092) (xy 316.40424 -147.565092) (xy 316.463662 -147.572915) (xy 316.521555 -147.588428)
			(xy 316.576928 -147.611364) (xy 316.628834 -147.641331) (xy 316.676384 -147.677818) (xy 316.718764 -147.720198)
			(xy 316.755251 -147.767748) (xy 316.785218 -147.819654) (xy 316.808154 -147.875027) (xy 316.823667 -147.93292)
			(xy 316.83149 -147.992342) (xy 316.83198 -148.02231) (xy 316.83198 -148.88591) (xy 316.831955 -148.887434)
			(xy 413.045148 -148.887434) (xy 413.045148 -148.023834) (xy 413.045638 -147.99385) (xy 413.053466 -147.934394)
			(xy 413.068987 -147.876469) (xy 413.091936 -147.821065) (xy 413.12192 -147.769131) (xy 413.158426 -147.721555)
			(xy 413.200831 -147.67915) (xy 413.248407 -147.642644) (xy 413.300341 -147.61266) (xy 413.355745 -147.589711)
			(xy 413.41367 -147.57419) (xy 413.473126 -147.566362) (xy 413.533094 -147.566362) (xy 413.59255 -147.57419)
			(xy 413.650475 -147.589711) (xy 413.705879 -147.61266) (xy 413.757813 -147.642644) (xy 413.805389 -147.67915)
			(xy 413.847794 -147.721555) (xy 413.8843 -147.769131) (xy 413.914284 -147.821065) (xy 413.937233 -147.876469)
			(xy 413.952754 -147.934394) (xy 413.960582 -147.99385) (xy 413.961072 -148.023834) (xy 413.961072 -148.88591)
			(xy 432.016408 -148.88591) (xy 432.016408 -148.02231) (xy 432.016898 -147.992326) (xy 432.024726 -147.93287)
			(xy 432.040247 -147.874945) (xy 432.063196 -147.819541) (xy 432.09318 -147.767607) (xy 432.129686 -147.720031)
			(xy 432.172091 -147.677626) (xy 432.219667 -147.64112) (xy 432.271601 -147.611136) (xy 432.327005 -147.588187)
			(xy 432.38493 -147.572666) (xy 432.444386 -147.564838) (xy 432.504354 -147.564838) (xy 432.56381 -147.572666)
			(xy 432.621735 -147.588187) (xy 432.677139 -147.611136) (xy 432.729073 -147.64112) (xy 432.776649 -147.677626)
			(xy 432.819054 -147.720031) (xy 432.85556 -147.767607) (xy 432.885544 -147.819541) (xy 432.908493 -147.874945)
			(xy 432.924014 -147.93287) (xy 432.931842 -147.992326) (xy 432.932332 -148.02231) (xy 432.932332 -148.88591)
			(xy 432.931842 -148.915894) (xy 432.924014 -148.97535) (xy 432.908493 -149.033275) (xy 432.885544 -149.088679)
			(xy 432.85556 -149.140613) (xy 432.819054 -149.188189) (xy 432.776649 -149.230594) (xy 432.729073 -149.2671)
			(xy 432.677139 -149.297084) (xy 432.621735 -149.320033) (xy 432.56381 -149.335554) (xy 432.504354 -149.343382)
			(xy 432.444386 -149.343382) (xy 432.38493 -149.335554) (xy 432.327005 -149.320033) (xy 432.271601 -149.297084)
			(xy 432.219667 -149.2671) (xy 432.172091 -149.230594) (xy 432.129686 -149.188189) (xy 432.09318 -149.140613)
			(xy 432.063196 -149.088679) (xy 432.040247 -149.033275) (xy 432.024726 -148.97535) (xy 432.016898 -148.915894)
			(xy 432.016408 -148.88591) (xy 413.961072 -148.88591) (xy 413.961072 -148.887434) (xy 413.960582 -148.917418)
			(xy 413.952754 -148.976874) (xy 413.937233 -149.034799) (xy 413.914284 -149.090203) (xy 413.8843 -149.142137)
			(xy 413.847794 -149.189713) (xy 413.805389 -149.232118) (xy 413.757813 -149.268624) (xy 413.705879 -149.298608)
			(xy 413.650475 -149.321557) (xy 413.59255 -149.337078) (xy 413.533094 -149.344906) (xy 413.473126 -149.344906)
			(xy 413.41367 -149.337078) (xy 413.355745 -149.321557) (xy 413.300341 -149.298608) (xy 413.248407 -149.268624)
			(xy 413.200831 -149.232118) (xy 413.158426 -149.189713) (xy 413.12192 -149.142137) (xy 413.091936 -149.090203)
			(xy 413.068987 -149.034799) (xy 413.053466 -148.976874) (xy 413.045638 -148.917418) (xy 413.045148 -148.887434)
			(xy 316.831955 -148.887434) (xy 316.83149 -148.915878) (xy 316.823667 -148.9753) (xy 316.808154 -149.033193)
			(xy 316.785218 -149.088566) (xy 316.755251 -149.140472) (xy 316.718764 -149.188022) (xy 316.676384 -149.230402)
			(xy 316.628834 -149.266889) (xy 316.576928 -149.296856) (xy 316.521555 -149.319792) (xy 316.463662 -149.335305)
			(xy 316.40424 -149.343128) (xy 316.344304 -149.343128) (xy 316.284882 -149.335305) (xy 316.226989 -149.319792)
			(xy 316.171616 -149.296856) (xy 316.11971 -149.266889) (xy 316.07216 -149.230402) (xy 316.02978 -149.188022)
			(xy 315.993293 -149.140472) (xy 315.963326 -149.088566) (xy 315.94039 -149.033193) (xy 315.924877 -148.9753)
			(xy 315.917054 -148.915878) (xy 315.916564 -148.88591) (xy 297.86072 -148.88591) (xy 297.86072 -148.887434)
			(xy 297.86023 -148.917402) (xy 297.852407 -148.976824) (xy 297.836894 -149.034717) (xy 297.813958 -149.09009)
			(xy 297.783991 -149.141996) (xy 297.747504 -149.189546) (xy 297.705124 -149.231926) (xy 297.657574 -149.268413)
			(xy 297.605668 -149.29838) (xy 297.550295 -149.321316) (xy 297.492402 -149.336829) (xy 297.43298 -149.344652)
			(xy 297.373044 -149.344652) (xy 297.313622 -149.336829) (xy 297.255729 -149.321316) (xy 297.200356 -149.29838)
			(xy 297.14845 -149.268413) (xy 297.1009 -149.231926) (xy 297.05852 -149.189546) (xy 297.022033 -149.141996)
			(xy 296.992066 -149.09009) (xy 296.96913 -149.034717) (xy 296.953617 -148.976824) (xy 296.945794 -148.917402)
			(xy 296.945304 -148.887434) (xy 237.624112 -148.887434) (xy 237.624112 -149.691344) (xy 237.623622 -149.721328)
			(xy 237.615794 -149.780784) (xy 237.600273 -149.838709) (xy 237.577324 -149.894113) (xy 237.54734 -149.946047)
			(xy 237.510834 -149.993623) (xy 237.468429 -150.036028) (xy 237.420853 -150.072534) (xy 237.368919 -150.102518)
			(xy 237.313515 -150.125467) (xy 237.25559 -150.140988) (xy 237.196134 -150.148816) (xy 237.136166 -150.148816)
			(xy 237.07671 -150.140988) (xy 237.018785 -150.125467) (xy 236.963381 -150.102518) (xy 236.911447 -150.072534)
			(xy 236.863871 -150.036028) (xy 236.821466 -149.993623) (xy 236.78496 -149.946047) (xy 236.754976 -149.894113)
			(xy 236.732027 -149.838709) (xy 236.716506 -149.780784) (xy 236.708678 -149.721328) (xy 236.708188 -149.691344)
			(xy 198.072386 -149.691344) (xy 198.081715 -149.72616) (xy 198.089538 -149.785582) (xy 198.090028 -149.81555)
			(xy 198.090028 -150.67915) (xy 198.089538 -150.709118) (xy 198.081715 -150.76854) (xy 198.066202 -150.826433)
			(xy 198.043266 -150.881806) (xy 198.013299 -150.933712) (xy 197.976812 -150.981262) (xy 197.934432 -151.023642)
			(xy 197.886882 -151.060129) (xy 197.834976 -151.090096) (xy 197.779603 -151.113032) (xy 197.72171 -151.128545)
			(xy 197.662288 -151.136368) (xy 197.602352 -151.136368) (xy 197.54293 -151.128545) (xy 197.485037 -151.113032)
			(xy 197.429664 -151.090096) (xy 197.377758 -151.060129) (xy 197.330208 -151.023642) (xy 197.287828 -150.981262)
			(xy 197.251341 -150.933712) (xy 197.221374 -150.881806) (xy 197.198438 -150.826433) (xy 197.182925 -150.76854)
			(xy 197.175102 -150.709118) (xy 197.174612 -150.67915) (xy 183.615076 -150.67915) (xy 183.615076 -150.687278)
			(xy 183.614586 -150.717246) (xy 183.606763 -150.776668) (xy 183.59125 -150.834561) (xy 183.568314 -150.889934)
			(xy 183.538347 -150.94184) (xy 183.50186 -150.98939) (xy 183.45948 -151.03177) (xy 183.41193 -151.068257)
			(xy 183.360024 -151.098224) (xy 183.304651 -151.12116) (xy 183.246758 -151.136673) (xy 183.187336 -151.144496)
			(xy 183.1274 -151.144496) (xy 183.067978 -151.136673) (xy 183.010085 -151.12116) (xy 182.954712 -151.098224)
			(xy 182.902806 -151.068257) (xy 182.855256 -151.03177) (xy 182.812876 -150.98939) (xy 182.776389 -150.94184)
			(xy 182.746422 -150.889934) (xy 182.723486 -150.834561) (xy 182.707973 -150.776668) (xy 182.70015 -150.717246)
			(xy 182.69966 -150.687278) (xy 81.990051 -150.687278) (xy 81.989694 -150.709134) (xy 81.981866 -150.76859)
			(xy 81.966345 -150.826515) (xy 81.943396 -150.881919) (xy 81.913412 -150.933853) (xy 81.876906 -150.981429)
			(xy 81.834501 -151.023834) (xy 81.786925 -151.06034) (xy 81.734991 -151.090324) (xy 81.679587 -151.113273)
			(xy 81.621662 -151.128794) (xy 81.562206 -151.136622) (xy 81.502238 -151.136622) (xy 81.442782 -151.128794)
			(xy 81.384857 -151.113273) (xy 81.329453 -151.090324) (xy 81.277519 -151.06034) (xy 81.229943 -151.023834)
			(xy 81.187538 -150.981429) (xy 81.151032 -150.933853) (xy 81.121048 -150.881919) (xy 81.098099 -150.826515)
			(xy 81.082578 -150.76859) (xy 81.07475 -150.709134) (xy 81.07426 -150.67915) (xy 67.515232 -150.67915)
			(xy 67.515232 -150.687278) (xy 67.514742 -150.717262) (xy 67.506914 -150.776718) (xy 67.491393 -150.834643)
			(xy 67.468444 -150.890047) (xy 67.43846 -150.941981) (xy 67.401954 -150.989557) (xy 67.359549 -151.031962)
			(xy 67.311973 -151.068468) (xy 67.260039 -151.098452) (xy 67.204635 -151.121401) (xy 67.14671 -151.136922)
			(xy 67.087254 -151.14475) (xy 67.027286 -151.14475) (xy 66.96783 -151.136922) (xy 66.909905 -151.121401)
			(xy 66.854501 -151.098452) (xy 66.802567 -151.068468) (xy 66.754991 -151.031962) (xy 66.712586 -150.989557)
			(xy 66.67608 -150.941981) (xy 66.646096 -150.890047) (xy 66.623147 -150.834643) (xy 66.607626 -150.776718)
			(xy 66.599798 -150.717262) (xy 66.599308 -150.687278) (xy 4.308094 -150.687278) (xy 4.308094 -152.487376)
			(xy 64.745108 -152.487376) (xy 64.745108 -151.623776) (xy 64.745598 -151.593792) (xy 64.753426 -151.534336)
			(xy 64.768947 -151.476411) (xy 64.791896 -151.421007) (xy 64.82188 -151.369073) (xy 64.858386 -151.321497)
			(xy 64.900791 -151.279092) (xy 64.948367 -151.242586) (xy 65.000301 -151.212602) (xy 65.055705 -151.189653)
			(xy 65.11363 -151.174132) (xy 65.173086 -151.166304) (xy 65.233054 -151.166304) (xy 65.29251 -151.174132)
			(xy 65.350435 -151.189653) (xy 65.405839 -151.212602) (xy 65.457773 -151.242586) (xy 65.505349 -151.279092)
			(xy 65.547754 -151.321497) (xy 65.58426 -151.369073) (xy 65.614244 -151.421007) (xy 65.637193 -151.476411)
			(xy 65.652714 -151.534336) (xy 65.660542 -151.593792) (xy 65.661032 -151.623776) (xy 65.661032 -152.485852)
			(xy 83.716368 -152.485852) (xy 83.716368 -151.622252) (xy 83.716858 -151.592268) (xy 83.724686 -151.532812)
			(xy 83.740207 -151.474887) (xy 83.763156 -151.419483) (xy 83.79314 -151.367549) (xy 83.829646 -151.319973)
			(xy 83.872051 -151.277568) (xy 83.919627 -151.241062) (xy 83.971561 -151.211078) (xy 84.026965 -151.188129)
			(xy 84.08489 -151.172608) (xy 84.144346 -151.16478) (xy 84.204314 -151.16478) (xy 84.26377 -151.172608)
			(xy 84.321695 -151.188129) (xy 84.377099 -151.211078) (xy 84.429033 -151.241062) (xy 84.476609 -151.277568)
			(xy 84.519014 -151.319973) (xy 84.55552 -151.367549) (xy 84.585504 -151.419483) (xy 84.608453 -151.474887)
			(xy 84.623974 -151.532812) (xy 84.631802 -151.592268) (xy 84.632292 -151.622252) (xy 84.632292 -152.485852)
			(xy 84.632267 -152.487376) (xy 180.84546 -152.487376) (xy 180.84546 -151.623776) (xy 180.84595 -151.593808)
			(xy 180.853773 -151.534386) (xy 180.869286 -151.476493) (xy 180.892222 -151.42112) (xy 180.922189 -151.369214)
			(xy 180.958676 -151.321664) (xy 181.001056 -151.279284) (xy 181.048606 -151.242797) (xy 181.100512 -151.21283)
			(xy 181.155885 -151.189894) (xy 181.213778 -151.174381) (xy 181.2732 -151.166558) (xy 181.333136 -151.166558)
			(xy 181.392558 -151.174381) (xy 181.450451 -151.189894) (xy 181.505824 -151.21283) (xy 181.55773 -151.242797)
			(xy 181.60528 -151.279284) (xy 181.64766 -151.321664) (xy 181.684147 -151.369214) (xy 181.714114 -151.42112)
			(xy 181.73705 -151.476493) (xy 181.752563 -151.534386) (xy 181.760386 -151.593808) (xy 181.760876 -151.623776)
			(xy 181.760876 -152.485852) (xy 199.81672 -152.485852) (xy 199.81672 -151.622252) (xy 199.81721 -151.592284)
			(xy 199.825033 -151.532862) (xy 199.840546 -151.474969) (xy 199.863482 -151.419596) (xy 199.893449 -151.36769)
			(xy 199.929936 -151.32014) (xy 199.972316 -151.27776) (xy 200.019866 -151.241273) (xy 200.071772 -151.211306)
			(xy 200.127145 -151.18837) (xy 200.185038 -151.172857) (xy 200.24446 -151.165034) (xy 200.304396 -151.165034)
			(xy 200.363818 -151.172857) (xy 200.421711 -151.18837) (xy 200.477084 -151.211306) (xy 200.52899 -151.241273)
			(xy 200.57654 -151.27776) (xy 200.61892 -151.32014) (xy 200.655407 -151.36769) (xy 200.685374 -151.419596)
			(xy 200.70831 -151.474969) (xy 200.723823 -151.532862) (xy 200.731646 -151.592284) (xy 200.732136 -151.622252)
			(xy 200.732136 -151.914098) (xy 236.712252 -151.914098) (xy 236.712252 -151.050498) (xy 236.712742 -151.020514)
			(xy 236.72057 -150.961058) (xy 236.736091 -150.903133) (xy 236.75904 -150.847729) (xy 236.789024 -150.795795)
			(xy 236.82553 -150.748219) (xy 236.867935 -150.705814) (xy 236.915511 -150.669308) (xy 236.967445 -150.639324)
			(xy 237.022849 -150.616375) (xy 237.080774 -150.600854) (xy 237.14023 -150.593026) (xy 237.200198 -150.593026)
			(xy 237.259654 -150.600854) (xy 237.317579 -150.616375) (xy 237.372983 -150.639324) (xy 237.424917 -150.669308)
			(xy 237.448336 -150.687278) (xy 298.799504 -150.687278) (xy 298.799504 -149.823678) (xy 298.799994 -149.79371)
			(xy 298.807817 -149.734288) (xy 298.82333 -149.676395) (xy 298.846266 -149.621022) (xy 298.876233 -149.569116)
			(xy 298.91272 -149.521566) (xy 298.9551 -149.479186) (xy 299.00265 -149.442699) (xy 299.054556 -149.412732)
			(xy 299.109929 -149.389796) (xy 299.167822 -149.374283) (xy 299.227244 -149.36646) (xy 299.28718 -149.36646)
			(xy 299.346602 -149.374283) (xy 299.404495 -149.389796) (xy 299.459868 -149.412732) (xy 299.511774 -149.442699)
			(xy 299.559324 -149.479186) (xy 299.601704 -149.521566) (xy 299.638191 -149.569116) (xy 299.668158 -149.621022)
			(xy 299.691094 -149.676395) (xy 299.706607 -149.734288) (xy 299.71443 -149.79371) (xy 299.71492 -149.823678)
			(xy 299.71492 -150.67915) (xy 313.274456 -150.67915) (xy 313.274456 -149.81555) (xy 313.274946 -149.785582)
			(xy 313.282769 -149.72616) (xy 313.298282 -149.668267) (xy 313.321218 -149.612894) (xy 313.351185 -149.560988)
			(xy 313.387672 -149.513438) (xy 313.430052 -149.471058) (xy 313.477602 -149.434571) (xy 313.529508 -149.404604)
			(xy 313.584881 -149.381668) (xy 313.642774 -149.366155) (xy 313.702196 -149.358332) (xy 313.762132 -149.358332)
			(xy 313.821554 -149.366155) (xy 313.879447 -149.381668) (xy 313.93482 -149.404604) (xy 313.986726 -149.434571)
			(xy 314.034276 -149.471058) (xy 314.076656 -149.513438) (xy 314.113143 -149.560988) (xy 314.14311 -149.612894)
			(xy 314.166046 -149.668267) (xy 314.181559 -149.72616) (xy 314.189382 -149.785582) (xy 314.189872 -149.81555)
			(xy 314.189872 -150.67915) (xy 314.189739 -150.687278) (xy 414.899348 -150.687278) (xy 414.899348 -149.823678)
			(xy 414.899838 -149.793694) (xy 414.907666 -149.734238) (xy 414.923187 -149.676313) (xy 414.946136 -149.620909)
			(xy 414.97612 -149.568975) (xy 415.012626 -149.521399) (xy 415.055031 -149.478994) (xy 415.102607 -149.442488)
			(xy 415.154541 -149.412504) (xy 415.209945 -149.389555) (xy 415.26787 -149.374034) (xy 415.327326 -149.366206)
			(xy 415.387294 -149.366206) (xy 415.44675 -149.374034) (xy 415.504675 -149.389555) (xy 415.560079 -149.412504)
			(xy 415.612013 -149.442488) (xy 415.659589 -149.478994) (xy 415.701994 -149.521399) (xy 415.7385 -149.568975)
			(xy 415.768484 -149.620909) (xy 415.791433 -149.676313) (xy 415.806954 -149.734238) (xy 415.814782 -149.793694)
			(xy 415.815272 -149.823678) (xy 415.815272 -150.67915) (xy 429.3743 -150.67915) (xy 429.3743 -149.81555)
			(xy 429.37479 -149.785566) (xy 429.382618 -149.72611) (xy 429.398139 -149.668185) (xy 429.421088 -149.612781)
			(xy 429.451072 -149.560847) (xy 429.487578 -149.513271) (xy 429.529983 -149.470866) (xy 429.577559 -149.43436)
			(xy 429.629493 -149.404376) (xy 429.684897 -149.381427) (xy 429.742822 -149.365906) (xy 429.802278 -149.358078)
			(xy 429.862246 -149.358078) (xy 429.921702 -149.365906) (xy 429.979627 -149.381427) (xy 430.035031 -149.404376)
			(xy 430.086965 -149.43436) (xy 430.134541 -149.470866) (xy 430.176946 -149.513271) (xy 430.213452 -149.560847)
			(xy 430.243436 -149.612781) (xy 430.266385 -149.668185) (xy 430.281906 -149.72611) (xy 430.289734 -149.785566)
			(xy 430.290224 -149.81555) (xy 430.290224 -150.67915) (xy 430.289734 -150.709134) (xy 430.281906 -150.76859)
			(xy 430.266385 -150.826515) (xy 430.243436 -150.881919) (xy 430.213452 -150.933853) (xy 430.176946 -150.981429)
			(xy 430.134541 -151.023834) (xy 430.086965 -151.06034) (xy 430.035031 -151.090324) (xy 429.979627 -151.113273)
			(xy 429.921702 -151.128794) (xy 429.862246 -151.136622) (xy 429.802278 -151.136622) (xy 429.742822 -151.128794)
			(xy 429.684897 -151.113273) (xy 429.629493 -151.090324) (xy 429.577559 -151.06034) (xy 429.529983 -151.023834)
			(xy 429.487578 -150.981429) (xy 429.451072 -150.933853) (xy 429.421088 -150.881919) (xy 429.398139 -150.826515)
			(xy 429.382618 -150.76859) (xy 429.37479 -150.709134) (xy 429.3743 -150.67915) (xy 415.815272 -150.67915)
			(xy 415.815272 -150.687278) (xy 415.814782 -150.717262) (xy 415.806954 -150.776718) (xy 415.791433 -150.834643)
			(xy 415.768484 -150.890047) (xy 415.7385 -150.941981) (xy 415.701994 -150.989557) (xy 415.659589 -151.031962)
			(xy 415.612013 -151.068468) (xy 415.560079 -151.098452) (xy 415.504675 -151.121401) (xy 415.44675 -151.136922)
			(xy 415.387294 -151.14475) (xy 415.327326 -151.14475) (xy 415.26787 -151.136922) (xy 415.209945 -151.121401)
			(xy 415.154541 -151.098452) (xy 415.102607 -151.068468) (xy 415.055031 -151.031962) (xy 415.012626 -150.989557)
			(xy 414.97612 -150.941981) (xy 414.946136 -150.890047) (xy 414.923187 -150.834643) (xy 414.907666 -150.776718)
			(xy 414.899838 -150.717262) (xy 414.899348 -150.687278) (xy 314.189739 -150.687278) (xy 314.189382 -150.709118)
			(xy 314.181559 -150.76854) (xy 314.166046 -150.826433) (xy 314.14311 -150.881806) (xy 314.113143 -150.933712)
			(xy 314.076656 -150.981262) (xy 314.034276 -151.023642) (xy 313.986726 -151.060129) (xy 313.93482 -151.090096)
			(xy 313.879447 -151.113032) (xy 313.821554 -151.128545) (xy 313.762132 -151.136368) (xy 313.702196 -151.136368)
			(xy 313.642774 -151.128545) (xy 313.584881 -151.113032) (xy 313.529508 -151.090096) (xy 313.477602 -151.060129)
			(xy 313.430052 -151.023642) (xy 313.387672 -150.981262) (xy 313.351185 -150.933712) (xy 313.321218 -150.881806)
			(xy 313.298282 -150.826433) (xy 313.282769 -150.76854) (xy 313.274946 -150.709118) (xy 313.274456 -150.67915)
			(xy 299.71492 -150.67915) (xy 299.71492 -150.687278) (xy 299.71443 -150.717246) (xy 299.706607 -150.776668)
			(xy 299.691094 -150.834561) (xy 299.668158 -150.889934) (xy 299.638191 -150.94184) (xy 299.601704 -150.98939)
			(xy 299.559324 -151.03177) (xy 299.511774 -151.068257) (xy 299.459868 -151.098224) (xy 299.404495 -151.12116)
			(xy 299.346602 -151.136673) (xy 299.28718 -151.144496) (xy 299.227244 -151.144496) (xy 299.167822 -151.136673)
			(xy 299.109929 -151.12116) (xy 299.054556 -151.098224) (xy 299.00265 -151.068257) (xy 298.9551 -151.03177)
			(xy 298.91272 -150.98939) (xy 298.876233 -150.94184) (xy 298.846266 -150.889934) (xy 298.82333 -150.834561)
			(xy 298.807817 -150.776668) (xy 298.799994 -150.717246) (xy 298.799504 -150.687278) (xy 237.448336 -150.687278)
			(xy 237.472493 -150.705814) (xy 237.514898 -150.748219) (xy 237.551404 -150.795795) (xy 237.581388 -150.847729)
			(xy 237.604337 -150.903133) (xy 237.619858 -150.961058) (xy 237.627686 -151.020514) (xy 237.628176 -151.050498)
			(xy 237.628176 -151.914098) (xy 237.627686 -151.944082) (xy 237.619858 -152.003538) (xy 237.604337 -152.061463)
			(xy 237.581388 -152.116867) (xy 237.551404 -152.168801) (xy 237.514898 -152.216377) (xy 237.472493 -152.258782)
			(xy 237.424917 -152.295288) (xy 237.372983 -152.325272) (xy 237.317579 -152.348221) (xy 237.259654 -152.363742)
			(xy 237.200198 -152.37157) (xy 237.14023 -152.37157) (xy 237.080774 -152.363742) (xy 237.022849 -152.348221)
			(xy 236.967445 -152.325272) (xy 236.915511 -152.295288) (xy 236.867935 -152.258782) (xy 236.82553 -152.216377)
			(xy 236.789024 -152.168801) (xy 236.75904 -152.116867) (xy 236.736091 -152.061463) (xy 236.72057 -152.003538)
			(xy 236.712742 -151.944082) (xy 236.712252 -151.914098) (xy 200.732136 -151.914098) (xy 200.732136 -152.485852)
			(xy 200.732111 -152.487376) (xy 296.945304 -152.487376) (xy 296.945304 -151.623776) (xy 296.945794 -151.593808)
			(xy 296.953617 -151.534386) (xy 296.96913 -151.476493) (xy 296.992066 -151.42112) (xy 297.022033 -151.369214)
			(xy 297.05852 -151.321664) (xy 297.1009 -151.279284) (xy 297.14845 -151.242797) (xy 297.200356 -151.21283)
			(xy 297.255729 -151.189894) (xy 297.313622 -151.174381) (xy 297.373044 -151.166558) (xy 297.43298 -151.166558)
			(xy 297.492402 -151.174381) (xy 297.550295 -151.189894) (xy 297.605668 -151.21283) (xy 297.657574 -151.242797)
			(xy 297.705124 -151.279284) (xy 297.747504 -151.321664) (xy 297.783991 -151.369214) (xy 297.813958 -151.42112)
			(xy 297.836894 -151.476493) (xy 297.852407 -151.534386) (xy 297.86023 -151.593808) (xy 297.86072 -151.623776)
			(xy 297.86072 -152.485852) (xy 315.916564 -152.485852) (xy 315.916564 -151.622252) (xy 315.917054 -151.592284)
			(xy 315.924877 -151.532862) (xy 315.94039 -151.474969) (xy 315.963326 -151.419596) (xy 315.993293 -151.36769)
			(xy 316.02978 -151.32014) (xy 316.07216 -151.27776) (xy 316.11971 -151.241273) (xy 316.171616 -151.211306)
			(xy 316.226989 -151.18837) (xy 316.284882 -151.172857) (xy 316.344304 -151.165034) (xy 316.40424 -151.165034)
			(xy 316.463662 -151.172857) (xy 316.521555 -151.18837) (xy 316.576928 -151.211306) (xy 316.628834 -151.241273)
			(xy 316.676384 -151.27776) (xy 316.718764 -151.32014) (xy 316.755251 -151.36769) (xy 316.785218 -151.419596)
			(xy 316.808154 -151.474969) (xy 316.823667 -151.532862) (xy 316.83149 -151.592284) (xy 316.83198 -151.622252)
			(xy 316.83198 -152.485852) (xy 316.831955 -152.487376) (xy 413.045148 -152.487376) (xy 413.045148 -151.623776)
			(xy 413.045638 -151.593792) (xy 413.053466 -151.534336) (xy 413.068987 -151.476411) (xy 413.091936 -151.421007)
			(xy 413.12192 -151.369073) (xy 413.158426 -151.321497) (xy 413.200831 -151.279092) (xy 413.248407 -151.242586)
			(xy 413.300341 -151.212602) (xy 413.355745 -151.189653) (xy 413.41367 -151.174132) (xy 413.473126 -151.166304)
			(xy 413.533094 -151.166304) (xy 413.59255 -151.174132) (xy 413.650475 -151.189653) (xy 413.705879 -151.212602)
			(xy 413.757813 -151.242586) (xy 413.805389 -151.279092) (xy 413.847794 -151.321497) (xy 413.8843 -151.369073)
			(xy 413.914284 -151.421007) (xy 413.937233 -151.476411) (xy 413.952754 -151.534336) (xy 413.960582 -151.593792)
			(xy 413.961072 -151.623776) (xy 413.961072 -152.485852) (xy 432.016408 -152.485852) (xy 432.016408 -151.622252)
			(xy 432.016898 -151.592268) (xy 432.024726 -151.532812) (xy 432.040247 -151.474887) (xy 432.063196 -151.419483)
			(xy 432.09318 -151.367549) (xy 432.129686 -151.319973) (xy 432.172091 -151.277568) (xy 432.219667 -151.241062)
			(xy 432.271601 -151.211078) (xy 432.327005 -151.188129) (xy 432.38493 -151.172608) (xy 432.444386 -151.16478)
			(xy 432.504354 -151.16478) (xy 432.56381 -151.172608) (xy 432.621735 -151.188129) (xy 432.677139 -151.211078)
			(xy 432.729073 -151.241062) (xy 432.776649 -151.277568) (xy 432.819054 -151.319973) (xy 432.85556 -151.367549)
			(xy 432.885544 -151.419483) (xy 432.908493 -151.474887) (xy 432.924014 -151.532812) (xy 432.931842 -151.592268)
			(xy 432.932332 -151.622252) (xy 432.932332 -152.485852) (xy 432.931842 -152.515836) (xy 432.924014 -152.575292)
			(xy 432.908493 -152.633217) (xy 432.885544 -152.688621) (xy 432.85556 -152.740555) (xy 432.819054 -152.788131)
			(xy 432.776649 -152.830536) (xy 432.729073 -152.867042) (xy 432.677139 -152.897026) (xy 432.621735 -152.919975)
			(xy 432.56381 -152.935496) (xy 432.504354 -152.943324) (xy 432.444386 -152.943324) (xy 432.38493 -152.935496)
			(xy 432.327005 -152.919975) (xy 432.271601 -152.897026) (xy 432.219667 -152.867042) (xy 432.172091 -152.830536)
			(xy 432.129686 -152.788131) (xy 432.09318 -152.740555) (xy 432.063196 -152.688621) (xy 432.040247 -152.633217)
			(xy 432.024726 -152.575292) (xy 432.016898 -152.515836) (xy 432.016408 -152.485852) (xy 413.961072 -152.485852)
			(xy 413.961072 -152.487376) (xy 413.960582 -152.51736) (xy 413.952754 -152.576816) (xy 413.937233 -152.634741)
			(xy 413.914284 -152.690145) (xy 413.8843 -152.742079) (xy 413.847794 -152.789655) (xy 413.805389 -152.83206)
			(xy 413.757813 -152.868566) (xy 413.705879 -152.89855) (xy 413.650475 -152.921499) (xy 413.59255 -152.93702)
			(xy 413.533094 -152.944848) (xy 413.473126 -152.944848) (xy 413.41367 -152.93702) (xy 413.355745 -152.921499)
			(xy 413.300341 -152.89855) (xy 413.248407 -152.868566) (xy 413.200831 -152.83206) (xy 413.158426 -152.789655)
			(xy 413.12192 -152.742079) (xy 413.091936 -152.690145) (xy 413.068987 -152.634741) (xy 413.053466 -152.576816)
			(xy 413.045638 -152.51736) (xy 413.045148 -152.487376) (xy 316.831955 -152.487376) (xy 316.83149 -152.51582)
			(xy 316.823667 -152.575242) (xy 316.808154 -152.633135) (xy 316.785218 -152.688508) (xy 316.755251 -152.740414)
			(xy 316.718764 -152.787964) (xy 316.676384 -152.830344) (xy 316.628834 -152.866831) (xy 316.576928 -152.896798)
			(xy 316.521555 -152.919734) (xy 316.463662 -152.935247) (xy 316.40424 -152.94307) (xy 316.344304 -152.94307)
			(xy 316.284882 -152.935247) (xy 316.226989 -152.919734) (xy 316.171616 -152.896798) (xy 316.11971 -152.866831)
			(xy 316.07216 -152.830344) (xy 316.02978 -152.787964) (xy 315.993293 -152.740414) (xy 315.963326 -152.688508)
			(xy 315.94039 -152.633135) (xy 315.924877 -152.575242) (xy 315.917054 -152.51582) (xy 315.916564 -152.485852)
			(xy 297.86072 -152.485852) (xy 297.86072 -152.487376) (xy 297.86023 -152.517344) (xy 297.852407 -152.576766)
			(xy 297.836894 -152.634659) (xy 297.813958 -152.690032) (xy 297.783991 -152.741938) (xy 297.747504 -152.789488)
			(xy 297.705124 -152.831868) (xy 297.657574 -152.868355) (xy 297.605668 -152.898322) (xy 297.550295 -152.921258)
			(xy 297.492402 -152.936771) (xy 297.43298 -152.944594) (xy 297.373044 -152.944594) (xy 297.313622 -152.936771)
			(xy 297.255729 -152.921258) (xy 297.200356 -152.898322) (xy 297.14845 -152.868355) (xy 297.1009 -152.831868)
			(xy 297.05852 -152.789488) (xy 297.022033 -152.741938) (xy 296.992066 -152.690032) (xy 296.96913 -152.634659)
			(xy 296.953617 -152.576766) (xy 296.945794 -152.517344) (xy 296.945304 -152.487376) (xy 200.732111 -152.487376)
			(xy 200.731646 -152.51582) (xy 200.723823 -152.575242) (xy 200.70831 -152.633135) (xy 200.685374 -152.688508)
			(xy 200.655407 -152.740414) (xy 200.61892 -152.787964) (xy 200.57654 -152.830344) (xy 200.52899 -152.866831)
			(xy 200.477084 -152.896798) (xy 200.421711 -152.919734) (xy 200.363818 -152.935247) (xy 200.304396 -152.94307)
			(xy 200.24446 -152.94307) (xy 200.185038 -152.935247) (xy 200.127145 -152.919734) (xy 200.071772 -152.896798)
			(xy 200.019866 -152.866831) (xy 199.972316 -152.830344) (xy 199.929936 -152.787964) (xy 199.893449 -152.740414)
			(xy 199.863482 -152.688508) (xy 199.840546 -152.633135) (xy 199.825033 -152.575242) (xy 199.81721 -152.51582)
			(xy 199.81672 -152.485852) (xy 181.760876 -152.485852) (xy 181.760876 -152.487376) (xy 181.760386 -152.517344)
			(xy 181.752563 -152.576766) (xy 181.73705 -152.634659) (xy 181.714114 -152.690032) (xy 181.684147 -152.741938)
			(xy 181.64766 -152.789488) (xy 181.60528 -152.831868) (xy 181.55773 -152.868355) (xy 181.505824 -152.898322)
			(xy 181.450451 -152.921258) (xy 181.392558 -152.936771) (xy 181.333136 -152.944594) (xy 181.2732 -152.944594)
			(xy 181.213778 -152.936771) (xy 181.155885 -152.921258) (xy 181.100512 -152.898322) (xy 181.048606 -152.868355)
			(xy 181.001056 -152.831868) (xy 180.958676 -152.789488) (xy 180.922189 -152.741938) (xy 180.892222 -152.690032)
			(xy 180.869286 -152.634659) (xy 180.853773 -152.576766) (xy 180.84595 -152.517344) (xy 180.84546 -152.487376)
			(xy 84.632267 -152.487376) (xy 84.631802 -152.515836) (xy 84.623974 -152.575292) (xy 84.608453 -152.633217)
			(xy 84.585504 -152.688621) (xy 84.55552 -152.740555) (xy 84.519014 -152.788131) (xy 84.476609 -152.830536)
			(xy 84.429033 -152.867042) (xy 84.377099 -152.897026) (xy 84.321695 -152.919975) (xy 84.26377 -152.935496)
			(xy 84.204314 -152.943324) (xy 84.144346 -152.943324) (xy 84.08489 -152.935496) (xy 84.026965 -152.919975)
			(xy 83.971561 -152.897026) (xy 83.919627 -152.867042) (xy 83.872051 -152.830536) (xy 83.829646 -152.788131)
			(xy 83.79314 -152.740555) (xy 83.763156 -152.688621) (xy 83.740207 -152.633217) (xy 83.724686 -152.575292)
			(xy 83.716858 -152.515836) (xy 83.716368 -152.485852) (xy 65.661032 -152.485852) (xy 65.661032 -152.487376)
			(xy 65.660542 -152.51736) (xy 65.652714 -152.576816) (xy 65.637193 -152.634741) (xy 65.614244 -152.690145)
			(xy 65.58426 -152.742079) (xy 65.547754 -152.789655) (xy 65.505349 -152.83206) (xy 65.457773 -152.868566)
			(xy 65.405839 -152.89855) (xy 65.350435 -152.921499) (xy 65.29251 -152.93702) (xy 65.233054 -152.944848)
			(xy 65.173086 -152.944848) (xy 65.11363 -152.93702) (xy 65.055705 -152.921499) (xy 65.000301 -152.89855)
			(xy 64.948367 -152.868566) (xy 64.900791 -152.83206) (xy 64.858386 -152.789655) (xy 64.82188 -152.742079)
			(xy 64.791896 -152.690145) (xy 64.768947 -152.634741) (xy 64.753426 -152.576816) (xy 64.745598 -152.51736)
			(xy 64.745108 -152.487376) (xy 4.308094 -152.487376) (xy 4.308094 -154.28722) (xy 66.599308 -154.28722)
			(xy 66.599308 -153.42362) (xy 66.599798 -153.393636) (xy 66.607626 -153.33418) (xy 66.623147 -153.276255)
			(xy 66.646096 -153.220851) (xy 66.67608 -153.168917) (xy 66.712586 -153.121341) (xy 66.754991 -153.078936)
			(xy 66.802567 -153.04243) (xy 66.854501 -153.012446) (xy 66.909905 -152.989497) (xy 66.96783 -152.973976)
			(xy 67.027286 -152.966148) (xy 67.087254 -152.966148) (xy 67.14671 -152.973976) (xy 67.204635 -152.989497)
			(xy 67.260039 -153.012446) (xy 67.311973 -153.04243) (xy 67.359549 -153.078936) (xy 67.401954 -153.121341)
			(xy 67.43846 -153.168917) (xy 67.468444 -153.220851) (xy 67.491393 -153.276255) (xy 67.506914 -153.33418)
			(xy 67.514742 -153.393636) (xy 67.515232 -153.42362) (xy 67.515232 -154.279346) (xy 81.07426 -154.279346)
			(xy 81.07426 -153.415746) (xy 81.07475 -153.385762) (xy 81.082578 -153.326306) (xy 81.098099 -153.268381)
			(xy 81.121048 -153.212977) (xy 81.151032 -153.161043) (xy 81.187538 -153.113467) (xy 81.229943 -153.071062)
			(xy 81.277519 -153.034556) (xy 81.329453 -153.004572) (xy 81.384857 -152.981623) (xy 81.442782 -152.966102)
			(xy 81.502238 -152.958274) (xy 81.562206 -152.958274) (xy 81.621662 -152.966102) (xy 81.679587 -152.981623)
			(xy 81.734991 -153.004572) (xy 81.786925 -153.034556) (xy 81.834501 -153.071062) (xy 81.876906 -153.113467)
			(xy 81.913412 -153.161043) (xy 81.943396 -153.212977) (xy 81.966345 -153.268381) (xy 81.981866 -153.326306)
			(xy 81.989694 -153.385762) (xy 81.990184 -153.415746) (xy 81.990184 -154.279346) (xy 81.990055 -154.28722)
			(xy 182.69966 -154.28722) (xy 182.69966 -153.42362) (xy 182.70015 -153.393652) (xy 182.707973 -153.33423)
			(xy 182.723486 -153.276337) (xy 182.746422 -153.220964) (xy 182.776389 -153.169058) (xy 182.812876 -153.121508)
			(xy 182.855256 -153.079128) (xy 182.902806 -153.042641) (xy 182.954712 -153.012674) (xy 183.010085 -152.989738)
			(xy 183.067978 -152.974225) (xy 183.1274 -152.966402) (xy 183.187336 -152.966402) (xy 183.246758 -152.974225)
			(xy 183.304651 -152.989738) (xy 183.360024 -153.012674) (xy 183.41193 -153.042641) (xy 183.45948 -153.079128)
			(xy 183.50186 -153.121508) (xy 183.538347 -153.169058) (xy 183.568314 -153.220964) (xy 183.59125 -153.276337)
			(xy 183.606763 -153.33423) (xy 183.614586 -153.393652) (xy 183.615076 -153.42362) (xy 183.615076 -154.279346)
			(xy 197.174612 -154.279346) (xy 197.174612 -153.415746) (xy 197.175102 -153.385778) (xy 197.182925 -153.326356)
			(xy 197.198438 -153.268463) (xy 197.221374 -153.21309) (xy 197.251341 -153.161184) (xy 197.287828 -153.113634)
			(xy 197.330208 -153.071254) (xy 197.377758 -153.034767) (xy 197.429664 -153.0048) (xy 197.485037 -152.981864)
			(xy 197.54293 -152.966351) (xy 197.602352 -152.958528) (xy 197.662288 -152.958528) (xy 197.72171 -152.966351)
			(xy 197.779603 -152.981864) (xy 197.834976 -153.0048) (xy 197.886882 -153.034767) (xy 197.934432 -153.071254)
			(xy 197.976812 -153.113634) (xy 198.013299 -153.161184) (xy 198.043266 -153.21309) (xy 198.066202 -153.268463)
			(xy 198.081715 -153.326356) (xy 198.089538 -153.385778) (xy 198.090028 -153.415746) (xy 198.090028 -154.279346)
			(xy 198.089899 -154.28722) (xy 298.799504 -154.28722) (xy 298.799504 -153.42362) (xy 298.799994 -153.393652)
			(xy 298.807817 -153.33423) (xy 298.82333 -153.276337) (xy 298.846266 -153.220964) (xy 298.876233 -153.169058)
			(xy 298.91272 -153.121508) (xy 298.9551 -153.079128) (xy 299.00265 -153.042641) (xy 299.054556 -153.012674)
			(xy 299.109929 -152.989738) (xy 299.167822 -152.974225) (xy 299.227244 -152.966402) (xy 299.28718 -152.966402)
			(xy 299.346602 -152.974225) (xy 299.404495 -152.989738) (xy 299.459868 -153.012674) (xy 299.511774 -153.042641)
			(xy 299.559324 -153.079128) (xy 299.601704 -153.121508) (xy 299.638191 -153.169058) (xy 299.668158 -153.220964)
			(xy 299.691094 -153.276337) (xy 299.706607 -153.33423) (xy 299.71443 -153.393652) (xy 299.71492 -153.42362)
			(xy 299.71492 -154.279346) (xy 313.274456 -154.279346) (xy 313.274456 -153.415746) (xy 313.274946 -153.385778)
			(xy 313.282769 -153.326356) (xy 313.298282 -153.268463) (xy 313.321218 -153.21309) (xy 313.351185 -153.161184)
			(xy 313.387672 -153.113634) (xy 313.430052 -153.071254) (xy 313.477602 -153.034767) (xy 313.529508 -153.0048)
			(xy 313.584881 -152.981864) (xy 313.642774 -152.966351) (xy 313.702196 -152.958528) (xy 313.762132 -152.958528)
			(xy 313.821554 -152.966351) (xy 313.879447 -152.981864) (xy 313.93482 -153.0048) (xy 313.986726 -153.034767)
			(xy 314.034276 -153.071254) (xy 314.076656 -153.113634) (xy 314.113143 -153.161184) (xy 314.14311 -153.21309)
			(xy 314.166046 -153.268463) (xy 314.181559 -153.326356) (xy 314.189382 -153.385778) (xy 314.189872 -153.415746)
			(xy 314.189872 -154.279346) (xy 314.189743 -154.28722) (xy 414.899348 -154.28722) (xy 414.899348 -153.42362)
			(xy 414.899838 -153.393636) (xy 414.907666 -153.33418) (xy 414.923187 -153.276255) (xy 414.946136 -153.220851)
			(xy 414.97612 -153.168917) (xy 415.012626 -153.121341) (xy 415.055031 -153.078936) (xy 415.102607 -153.04243)
			(xy 415.154541 -153.012446) (xy 415.209945 -152.989497) (xy 415.26787 -152.973976) (xy 415.327326 -152.966148)
			(xy 415.387294 -152.966148) (xy 415.44675 -152.973976) (xy 415.504675 -152.989497) (xy 415.560079 -153.012446)
			(xy 415.612013 -153.04243) (xy 415.659589 -153.078936) (xy 415.701994 -153.121341) (xy 415.7385 -153.168917)
			(xy 415.768484 -153.220851) (xy 415.791433 -153.276255) (xy 415.806954 -153.33418) (xy 415.814782 -153.393636)
			(xy 415.815272 -153.42362) (xy 415.815272 -154.279346) (xy 429.3743 -154.279346) (xy 429.3743 -153.415746)
			(xy 429.37479 -153.385762) (xy 429.382618 -153.326306) (xy 429.398139 -153.268381) (xy 429.421088 -153.212977)
			(xy 429.451072 -153.161043) (xy 429.487578 -153.113467) (xy 429.529983 -153.071062) (xy 429.577559 -153.034556)
			(xy 429.629493 -153.004572) (xy 429.684897 -152.981623) (xy 429.742822 -152.966102) (xy 429.802278 -152.958274)
			(xy 429.862246 -152.958274) (xy 429.921702 -152.966102) (xy 429.979627 -152.981623) (xy 430.035031 -153.004572)
			(xy 430.086965 -153.034556) (xy 430.134541 -153.071062) (xy 430.176946 -153.113467) (xy 430.213452 -153.161043)
			(xy 430.243436 -153.212977) (xy 430.266385 -153.268381) (xy 430.281906 -153.326306) (xy 430.289734 -153.385762)
			(xy 430.290224 -153.415746) (xy 430.290224 -154.279346) (xy 430.289734 -154.30933) (xy 430.281906 -154.368786)
			(xy 430.266385 -154.426711) (xy 430.243436 -154.482115) (xy 430.213452 -154.534049) (xy 430.176946 -154.581625)
			(xy 430.134541 -154.62403) (xy 430.086965 -154.660536) (xy 430.035031 -154.69052) (xy 429.979627 -154.713469)
			(xy 429.921702 -154.72899) (xy 429.862246 -154.736818) (xy 429.802278 -154.736818) (xy 429.742822 -154.72899)
			(xy 429.684897 -154.713469) (xy 429.629493 -154.69052) (xy 429.577559 -154.660536) (xy 429.529983 -154.62403)
			(xy 429.487578 -154.581625) (xy 429.451072 -154.534049) (xy 429.421088 -154.482115) (xy 429.398139 -154.426711)
			(xy 429.382618 -154.368786) (xy 429.37479 -154.30933) (xy 429.3743 -154.279346) (xy 415.815272 -154.279346)
			(xy 415.815272 -154.28722) (xy 415.814782 -154.317204) (xy 415.806954 -154.37666) (xy 415.791433 -154.434585)
			(xy 415.768484 -154.489989) (xy 415.7385 -154.541923) (xy 415.701994 -154.589499) (xy 415.659589 -154.631904)
			(xy 415.612013 -154.66841) (xy 415.560079 -154.698394) (xy 415.504675 -154.721343) (xy 415.44675 -154.736864)
			(xy 415.387294 -154.744692) (xy 415.327326 -154.744692) (xy 415.26787 -154.736864) (xy 415.209945 -154.721343)
			(xy 415.154541 -154.698394) (xy 415.102607 -154.66841) (xy 415.055031 -154.631904) (xy 415.012626 -154.589499)
			(xy 414.97612 -154.541923) (xy 414.946136 -154.489989) (xy 414.923187 -154.434585) (xy 414.907666 -154.37666)
			(xy 414.899838 -154.317204) (xy 414.899348 -154.28722) (xy 314.189743 -154.28722) (xy 314.189382 -154.309314)
			(xy 314.181559 -154.368736) (xy 314.166046 -154.426629) (xy 314.14311 -154.482002) (xy 314.113143 -154.533908)
			(xy 314.076656 -154.581458) (xy 314.034276 -154.623838) (xy 313.986726 -154.660325) (xy 313.93482 -154.690292)
			(xy 313.879447 -154.713228) (xy 313.821554 -154.728741) (xy 313.762132 -154.736564) (xy 313.702196 -154.736564)
			(xy 313.642774 -154.728741) (xy 313.584881 -154.713228) (xy 313.529508 -154.690292) (xy 313.477602 -154.660325)
			(xy 313.430052 -154.623838) (xy 313.387672 -154.581458) (xy 313.351185 -154.533908) (xy 313.321218 -154.482002)
			(xy 313.298282 -154.426629) (xy 313.282769 -154.368736) (xy 313.274946 -154.309314) (xy 313.274456 -154.279346)
			(xy 299.71492 -154.279346) (xy 299.71492 -154.28722) (xy 299.71443 -154.317188) (xy 299.706607 -154.37661)
			(xy 299.691094 -154.434503) (xy 299.668158 -154.489876) (xy 299.638191 -154.541782) (xy 299.601704 -154.589332)
			(xy 299.559324 -154.631712) (xy 299.511774 -154.668199) (xy 299.459868 -154.698166) (xy 299.404495 -154.721102)
			(xy 299.346602 -154.736615) (xy 299.28718 -154.744438) (xy 299.227244 -154.744438) (xy 299.167822 -154.736615)
			(xy 299.109929 -154.721102) (xy 299.054556 -154.698166) (xy 299.00265 -154.668199) (xy 298.9551 -154.631712)
			(xy 298.91272 -154.589332) (xy 298.876233 -154.541782) (xy 298.846266 -154.489876) (xy 298.82333 -154.434503)
			(xy 298.807817 -154.37661) (xy 298.799994 -154.317188) (xy 298.799504 -154.28722) (xy 198.089899 -154.28722)
			(xy 198.089538 -154.309314) (xy 198.081715 -154.368736) (xy 198.066202 -154.426629) (xy 198.043266 -154.482002)
			(xy 198.013299 -154.533908) (xy 197.976812 -154.581458) (xy 197.934432 -154.623838) (xy 197.886882 -154.660325)
			(xy 197.834976 -154.690292) (xy 197.779603 -154.713228) (xy 197.72171 -154.728741) (xy 197.662288 -154.736564)
			(xy 197.602352 -154.736564) (xy 197.54293 -154.728741) (xy 197.485037 -154.713228) (xy 197.429664 -154.690292)
			(xy 197.377758 -154.660325) (xy 197.330208 -154.623838) (xy 197.287828 -154.581458) (xy 197.251341 -154.533908)
			(xy 197.221374 -154.482002) (xy 197.198438 -154.426629) (xy 197.182925 -154.368736) (xy 197.175102 -154.309314)
			(xy 197.174612 -154.279346) (xy 183.615076 -154.279346) (xy 183.615076 -154.28722) (xy 183.614586 -154.317188)
			(xy 183.606763 -154.37661) (xy 183.59125 -154.434503) (xy 183.568314 -154.489876) (xy 183.538347 -154.541782)
			(xy 183.50186 -154.589332) (xy 183.45948 -154.631712) (xy 183.41193 -154.668199) (xy 183.360024 -154.698166)
			(xy 183.304651 -154.721102) (xy 183.246758 -154.736615) (xy 183.187336 -154.744438) (xy 183.1274 -154.744438)
			(xy 183.067978 -154.736615) (xy 183.010085 -154.721102) (xy 182.954712 -154.698166) (xy 182.902806 -154.668199)
			(xy 182.855256 -154.631712) (xy 182.812876 -154.589332) (xy 182.776389 -154.541782) (xy 182.746422 -154.489876)
			(xy 182.723486 -154.434503) (xy 182.707973 -154.37661) (xy 182.70015 -154.317188) (xy 182.69966 -154.28722)
			(xy 81.990055 -154.28722) (xy 81.989694 -154.30933) (xy 81.981866 -154.368786) (xy 81.966345 -154.426711)
			(xy 81.943396 -154.482115) (xy 81.913412 -154.534049) (xy 81.876906 -154.581625) (xy 81.834501 -154.62403)
			(xy 81.786925 -154.660536) (xy 81.734991 -154.69052) (xy 81.679587 -154.713469) (xy 81.621662 -154.72899)
			(xy 81.562206 -154.736818) (xy 81.502238 -154.736818) (xy 81.442782 -154.72899) (xy 81.384857 -154.713469)
			(xy 81.329453 -154.69052) (xy 81.277519 -154.660536) (xy 81.229943 -154.62403) (xy 81.187538 -154.581625)
			(xy 81.151032 -154.534049) (xy 81.121048 -154.482115) (xy 81.098099 -154.426711) (xy 81.082578 -154.368786)
			(xy 81.07475 -154.30933) (xy 81.07426 -154.279346) (xy 67.515232 -154.279346) (xy 67.515232 -154.28722)
			(xy 67.514742 -154.317204) (xy 67.506914 -154.37666) (xy 67.491393 -154.434585) (xy 67.468444 -154.489989)
			(xy 67.43846 -154.541923) (xy 67.401954 -154.589499) (xy 67.359549 -154.631904) (xy 67.311973 -154.66841)
			(xy 67.260039 -154.698394) (xy 67.204635 -154.721343) (xy 67.14671 -154.736864) (xy 67.087254 -154.744692)
			(xy 67.027286 -154.744692) (xy 66.96783 -154.736864) (xy 66.909905 -154.721343) (xy 66.854501 -154.698394)
			(xy 66.802567 -154.66841) (xy 66.754991 -154.631904) (xy 66.712586 -154.589499) (xy 66.67608 -154.541923)
			(xy 66.646096 -154.489989) (xy 66.623147 -154.434585) (xy 66.607626 -154.37666) (xy 66.599798 -154.317204)
			(xy 66.599308 -154.28722) (xy 4.308094 -154.28722) (xy 4.308094 -156.087318) (xy 64.745108 -156.087318)
			(xy 64.745108 -155.223718) (xy 64.745598 -155.193734) (xy 64.753426 -155.134278) (xy 64.768947 -155.076353)
			(xy 64.791896 -155.020949) (xy 64.82188 -154.969015) (xy 64.858386 -154.921439) (xy 64.900791 -154.879034)
			(xy 64.948367 -154.842528) (xy 65.000301 -154.812544) (xy 65.055705 -154.789595) (xy 65.11363 -154.774074)
			(xy 65.173086 -154.766246) (xy 65.233054 -154.766246) (xy 65.29251 -154.774074) (xy 65.350435 -154.789595)
			(xy 65.405839 -154.812544) (xy 65.457773 -154.842528) (xy 65.505349 -154.879034) (xy 65.547754 -154.921439)
			(xy 65.58426 -154.969015) (xy 65.614244 -155.020949) (xy 65.637193 -155.076353) (xy 65.652714 -155.134278)
			(xy 65.660542 -155.193734) (xy 65.661032 -155.223718) (xy 65.661032 -156.085794) (xy 83.716368 -156.085794)
			(xy 83.716368 -155.222194) (xy 83.716858 -155.19221) (xy 83.724686 -155.132754) (xy 83.740207 -155.074829)
			(xy 83.763156 -155.019425) (xy 83.79314 -154.967491) (xy 83.829646 -154.919915) (xy 83.872051 -154.87751)
			(xy 83.919627 -154.841004) (xy 83.971561 -154.81102) (xy 84.026965 -154.788071) (xy 84.08489 -154.77255)
			(xy 84.144346 -154.764722) (xy 84.204314 -154.764722) (xy 84.26377 -154.77255) (xy 84.321695 -154.788071)
			(xy 84.377099 -154.81102) (xy 84.429033 -154.841004) (xy 84.476609 -154.87751) (xy 84.519014 -154.919915)
			(xy 84.55552 -154.967491) (xy 84.585504 -155.019425) (xy 84.608453 -155.074829) (xy 84.623974 -155.132754)
			(xy 84.631802 -155.19221) (xy 84.632292 -155.222194) (xy 84.632292 -156.085794) (xy 84.632267 -156.087318)
			(xy 180.84546 -156.087318) (xy 180.84546 -155.223718) (xy 180.84595 -155.19375) (xy 180.853773 -155.134328)
			(xy 180.869286 -155.076435) (xy 180.892222 -155.021062) (xy 180.922189 -154.969156) (xy 180.958676 -154.921606)
			(xy 181.001056 -154.879226) (xy 181.048606 -154.842739) (xy 181.100512 -154.812772) (xy 181.155885 -154.789836)
			(xy 181.213778 -154.774323) (xy 181.2732 -154.7665) (xy 181.333136 -154.7665) (xy 181.392558 -154.774323)
			(xy 181.450451 -154.789836) (xy 181.505824 -154.812772) (xy 181.55773 -154.842739) (xy 181.60528 -154.879226)
			(xy 181.64766 -154.921606) (xy 181.684147 -154.969156) (xy 181.714114 -155.021062) (xy 181.73705 -155.076435)
			(xy 181.752563 -155.134328) (xy 181.760386 -155.19375) (xy 181.760876 -155.223718) (xy 181.760876 -156.085794)
			(xy 199.81672 -156.085794) (xy 199.81672 -155.222194) (xy 199.81721 -155.192226) (xy 199.825033 -155.132804)
			(xy 199.840546 -155.074911) (xy 199.863482 -155.019538) (xy 199.893449 -154.967632) (xy 199.929936 -154.920082)
			(xy 199.972316 -154.877702) (xy 200.019866 -154.841215) (xy 200.071772 -154.811248) (xy 200.127145 -154.788312)
			(xy 200.185038 -154.772799) (xy 200.24446 -154.764976) (xy 200.304396 -154.764976) (xy 200.363818 -154.772799)
			(xy 200.421711 -154.788312) (xy 200.477084 -154.811248) (xy 200.52899 -154.841215) (xy 200.57654 -154.877702)
			(xy 200.61892 -154.920082) (xy 200.655407 -154.967632) (xy 200.685374 -155.019538) (xy 200.70831 -155.074911)
			(xy 200.723823 -155.132804) (xy 200.731646 -155.192226) (xy 200.732136 -155.222194) (xy 200.732136 -156.085794)
			(xy 200.732111 -156.087318) (xy 296.945304 -156.087318) (xy 296.945304 -155.223718) (xy 296.945794 -155.19375)
			(xy 296.953617 -155.134328) (xy 296.96913 -155.076435) (xy 296.992066 -155.021062) (xy 297.022033 -154.969156)
			(xy 297.05852 -154.921606) (xy 297.1009 -154.879226) (xy 297.14845 -154.842739) (xy 297.200356 -154.812772)
			(xy 297.255729 -154.789836) (xy 297.313622 -154.774323) (xy 297.373044 -154.7665) (xy 297.43298 -154.7665)
			(xy 297.492402 -154.774323) (xy 297.550295 -154.789836) (xy 297.605668 -154.812772) (xy 297.657574 -154.842739)
			(xy 297.705124 -154.879226) (xy 297.747504 -154.921606) (xy 297.783991 -154.969156) (xy 297.813958 -155.021062)
			(xy 297.836894 -155.076435) (xy 297.852407 -155.134328) (xy 297.86023 -155.19375) (xy 297.86072 -155.223718)
			(xy 297.86072 -156.085794) (xy 315.916564 -156.085794) (xy 315.916564 -155.222194) (xy 315.917054 -155.192226)
			(xy 315.924877 -155.132804) (xy 315.94039 -155.074911) (xy 315.963326 -155.019538) (xy 315.993293 -154.967632)
			(xy 316.02978 -154.920082) (xy 316.07216 -154.877702) (xy 316.11971 -154.841215) (xy 316.171616 -154.811248)
			(xy 316.226989 -154.788312) (xy 316.284882 -154.772799) (xy 316.344304 -154.764976) (xy 316.40424 -154.764976)
			(xy 316.463662 -154.772799) (xy 316.521555 -154.788312) (xy 316.576928 -154.811248) (xy 316.628834 -154.841215)
			(xy 316.676384 -154.877702) (xy 316.718764 -154.920082) (xy 316.755251 -154.967632) (xy 316.785218 -155.019538)
			(xy 316.808154 -155.074911) (xy 316.823667 -155.132804) (xy 316.83149 -155.192226) (xy 316.83198 -155.222194)
			(xy 316.83198 -156.085794) (xy 316.831955 -156.087318) (xy 413.045148 -156.087318) (xy 413.045148 -155.223718)
			(xy 413.045638 -155.193734) (xy 413.053466 -155.134278) (xy 413.068987 -155.076353) (xy 413.091936 -155.020949)
			(xy 413.12192 -154.969015) (xy 413.158426 -154.921439) (xy 413.200831 -154.879034) (xy 413.248407 -154.842528)
			(xy 413.300341 -154.812544) (xy 413.355745 -154.789595) (xy 413.41367 -154.774074) (xy 413.473126 -154.766246)
			(xy 413.533094 -154.766246) (xy 413.59255 -154.774074) (xy 413.650475 -154.789595) (xy 413.705879 -154.812544)
			(xy 413.757813 -154.842528) (xy 413.805389 -154.879034) (xy 413.847794 -154.921439) (xy 413.8843 -154.969015)
			(xy 413.914284 -155.020949) (xy 413.937233 -155.076353) (xy 413.952754 -155.134278) (xy 413.960582 -155.193734)
			(xy 413.961072 -155.223718) (xy 413.961072 -156.085794) (xy 432.016408 -156.085794) (xy 432.016408 -155.222194)
			(xy 432.016898 -155.19221) (xy 432.024726 -155.132754) (xy 432.040247 -155.074829) (xy 432.063196 -155.019425)
			(xy 432.09318 -154.967491) (xy 432.129686 -154.919915) (xy 432.172091 -154.87751) (xy 432.219667 -154.841004)
			(xy 432.271601 -154.81102) (xy 432.327005 -154.788071) (xy 432.38493 -154.77255) (xy 432.444386 -154.764722)
			(xy 432.504354 -154.764722) (xy 432.56381 -154.77255) (xy 432.621735 -154.788071) (xy 432.677139 -154.81102)
			(xy 432.729073 -154.841004) (xy 432.776649 -154.87751) (xy 432.819054 -154.919915) (xy 432.85556 -154.967491)
			(xy 432.885544 -155.019425) (xy 432.908493 -155.074829) (xy 432.924014 -155.132754) (xy 432.931842 -155.19221)
			(xy 432.932332 -155.222194) (xy 432.932332 -156.085794) (xy 432.931842 -156.115778) (xy 432.924014 -156.175234)
			(xy 432.908493 -156.233159) (xy 432.885544 -156.288563) (xy 432.85556 -156.340497) (xy 432.819054 -156.388073)
			(xy 432.776649 -156.430478) (xy 432.729073 -156.466984) (xy 432.677139 -156.496968) (xy 432.621735 -156.519917)
			(xy 432.56381 -156.535438) (xy 432.504354 -156.543266) (xy 432.444386 -156.543266) (xy 432.38493 -156.535438)
			(xy 432.327005 -156.519917) (xy 432.271601 -156.496968) (xy 432.219667 -156.466984) (xy 432.172091 -156.430478)
			(xy 432.129686 -156.388073) (xy 432.09318 -156.340497) (xy 432.063196 -156.288563) (xy 432.040247 -156.233159)
			(xy 432.024726 -156.175234) (xy 432.016898 -156.115778) (xy 432.016408 -156.085794) (xy 413.961072 -156.085794)
			(xy 413.961072 -156.087318) (xy 413.960582 -156.117302) (xy 413.952754 -156.176758) (xy 413.937233 -156.234683)
			(xy 413.914284 -156.290087) (xy 413.8843 -156.342021) (xy 413.847794 -156.389597) (xy 413.805389 -156.432002)
			(xy 413.757813 -156.468508) (xy 413.705879 -156.498492) (xy 413.650475 -156.521441) (xy 413.59255 -156.536962)
			(xy 413.533094 -156.54479) (xy 413.473126 -156.54479) (xy 413.41367 -156.536962) (xy 413.355745 -156.521441)
			(xy 413.300341 -156.498492) (xy 413.248407 -156.468508) (xy 413.200831 -156.432002) (xy 413.158426 -156.389597)
			(xy 413.12192 -156.342021) (xy 413.091936 -156.290087) (xy 413.068987 -156.234683) (xy 413.053466 -156.176758)
			(xy 413.045638 -156.117302) (xy 413.045148 -156.087318) (xy 316.831955 -156.087318) (xy 316.83149 -156.115762)
			(xy 316.823667 -156.175184) (xy 316.808154 -156.233077) (xy 316.785218 -156.28845) (xy 316.755251 -156.340356)
			(xy 316.718764 -156.387906) (xy 316.676384 -156.430286) (xy 316.628834 -156.466773) (xy 316.576928 -156.49674)
			(xy 316.521555 -156.519676) (xy 316.463662 -156.535189) (xy 316.40424 -156.543012) (xy 316.344304 -156.543012)
			(xy 316.284882 -156.535189) (xy 316.226989 -156.519676) (xy 316.171616 -156.49674) (xy 316.11971 -156.466773)
			(xy 316.07216 -156.430286) (xy 316.02978 -156.387906) (xy 315.993293 -156.340356) (xy 315.963326 -156.28845)
			(xy 315.94039 -156.233077) (xy 315.924877 -156.175184) (xy 315.917054 -156.115762) (xy 315.916564 -156.085794)
			(xy 297.86072 -156.085794) (xy 297.86072 -156.087318) (xy 297.86023 -156.117286) (xy 297.852407 -156.176708)
			(xy 297.836894 -156.234601) (xy 297.813958 -156.289974) (xy 297.783991 -156.34188) (xy 297.747504 -156.38943)
			(xy 297.705124 -156.43181) (xy 297.657574 -156.468297) (xy 297.605668 -156.498264) (xy 297.550295 -156.5212)
			(xy 297.492402 -156.536713) (xy 297.43298 -156.544536) (xy 297.373044 -156.544536) (xy 297.313622 -156.536713)
			(xy 297.255729 -156.5212) (xy 297.200356 -156.498264) (xy 297.14845 -156.468297) (xy 297.1009 -156.43181)
			(xy 297.05852 -156.38943) (xy 297.022033 -156.34188) (xy 296.992066 -156.289974) (xy 296.96913 -156.234601)
			(xy 296.953617 -156.176708) (xy 296.945794 -156.117286) (xy 296.945304 -156.087318) (xy 200.732111 -156.087318)
			(xy 200.731646 -156.115762) (xy 200.723823 -156.175184) (xy 200.70831 -156.233077) (xy 200.685374 -156.28845)
			(xy 200.655407 -156.340356) (xy 200.61892 -156.387906) (xy 200.57654 -156.430286) (xy 200.52899 -156.466773)
			(xy 200.477084 -156.49674) (xy 200.421711 -156.519676) (xy 200.363818 -156.535189) (xy 200.304396 -156.543012)
			(xy 200.24446 -156.543012) (xy 200.185038 -156.535189) (xy 200.127145 -156.519676) (xy 200.071772 -156.49674)
			(xy 200.019866 -156.466773) (xy 199.972316 -156.430286) (xy 199.929936 -156.387906) (xy 199.893449 -156.340356)
			(xy 199.863482 -156.28845) (xy 199.840546 -156.233077) (xy 199.825033 -156.175184) (xy 199.81721 -156.115762)
			(xy 199.81672 -156.085794) (xy 181.760876 -156.085794) (xy 181.760876 -156.087318) (xy 181.760386 -156.117286)
			(xy 181.752563 -156.176708) (xy 181.73705 -156.234601) (xy 181.714114 -156.289974) (xy 181.684147 -156.34188)
			(xy 181.64766 -156.38943) (xy 181.60528 -156.43181) (xy 181.55773 -156.468297) (xy 181.505824 -156.498264)
			(xy 181.450451 -156.5212) (xy 181.392558 -156.536713) (xy 181.333136 -156.544536) (xy 181.2732 -156.544536)
			(xy 181.213778 -156.536713) (xy 181.155885 -156.5212) (xy 181.100512 -156.498264) (xy 181.048606 -156.468297)
			(xy 181.001056 -156.43181) (xy 180.958676 -156.38943) (xy 180.922189 -156.34188) (xy 180.892222 -156.289974)
			(xy 180.869286 -156.234601) (xy 180.853773 -156.176708) (xy 180.84595 -156.117286) (xy 180.84546 -156.087318)
			(xy 84.632267 -156.087318) (xy 84.631802 -156.115778) (xy 84.623974 -156.175234) (xy 84.608453 -156.233159)
			(xy 84.585504 -156.288563) (xy 84.55552 -156.340497) (xy 84.519014 -156.388073) (xy 84.476609 -156.430478)
			(xy 84.429033 -156.466984) (xy 84.377099 -156.496968) (xy 84.321695 -156.519917) (xy 84.26377 -156.535438)
			(xy 84.204314 -156.543266) (xy 84.144346 -156.543266) (xy 84.08489 -156.535438) (xy 84.026965 -156.519917)
			(xy 83.971561 -156.496968) (xy 83.919627 -156.466984) (xy 83.872051 -156.430478) (xy 83.829646 -156.388073)
			(xy 83.79314 -156.340497) (xy 83.763156 -156.288563) (xy 83.740207 -156.233159) (xy 83.724686 -156.175234)
			(xy 83.716858 -156.115778) (xy 83.716368 -156.085794) (xy 65.661032 -156.085794) (xy 65.661032 -156.087318)
			(xy 65.660542 -156.117302) (xy 65.652714 -156.176758) (xy 65.637193 -156.234683) (xy 65.614244 -156.290087)
			(xy 65.58426 -156.342021) (xy 65.547754 -156.389597) (xy 65.505349 -156.432002) (xy 65.457773 -156.468508)
			(xy 65.405839 -156.498492) (xy 65.350435 -156.521441) (xy 65.29251 -156.536962) (xy 65.233054 -156.54479)
			(xy 65.173086 -156.54479) (xy 65.11363 -156.536962) (xy 65.055705 -156.521441) (xy 65.000301 -156.498492)
			(xy 64.948367 -156.468508) (xy 64.900791 -156.432002) (xy 64.858386 -156.389597) (xy 64.82188 -156.342021)
			(xy 64.791896 -156.290087) (xy 64.768947 -156.234683) (xy 64.753426 -156.176758) (xy 64.745598 -156.117302)
			(xy 64.745108 -156.087318) (xy 4.308094 -156.087318) (xy 4.308094 -157.900066) (xy 228.314505 -157.900066)
			(xy 228.314505 -157.840134) (xy 228.322328 -157.780714) (xy 228.33784 -157.722823) (xy 228.360775 -157.667453)
			(xy 228.390741 -157.61555) (xy 228.427226 -157.568002) (xy 228.469605 -157.525624) (xy 228.517153 -157.489139)
			(xy 228.569056 -157.459173) (xy 228.624427 -157.436238) (xy 228.682318 -157.420727) (xy 228.741738 -157.412905)
			(xy 228.771704 -157.412436) (xy 229.635304 -157.412436) (xy 229.665274 -157.412838) (xy 229.724702 -157.420663)
			(xy 229.7826 -157.436177) (xy 229.837978 -157.459116) (xy 229.889888 -157.489086) (xy 229.937442 -157.525576)
			(xy 229.979827 -157.567961) (xy 230.016316 -157.615515) (xy 230.046286 -157.667425) (xy 230.069224 -157.722803)
			(xy 230.084738 -157.780702) (xy 230.092562 -157.84013) (xy 230.092562 -157.90007) (xy 230.089876 -157.920473)
			(xy 230.557725 -157.920473) (xy 230.557725 -157.860527) (xy 230.56555 -157.801095) (xy 230.581066 -157.743192)
			(xy 230.604007 -157.68781) (xy 230.633981 -157.635897) (xy 230.670475 -157.58834) (xy 230.712864 -157.545953)
			(xy 230.760423 -157.509463) (xy 230.812339 -157.479493) (xy 230.867722 -157.456555) (xy 230.925626 -157.441044)
			(xy 230.985059 -157.433223) (xy 231.015032 -157.432756) (xy 231.878632 -157.432756) (xy 231.908596 -157.43332)
			(xy 231.968011 -157.441146) (xy 232.025896 -157.45666) (xy 232.081261 -157.479596) (xy 232.133158 -157.509563)
			(xy 232.180701 -157.546046) (xy 232.223075 -157.588423) (xy 232.259555 -157.635968) (xy 232.289518 -157.687868)
			(xy 232.31245 -157.743235) (xy 232.32796 -157.801121) (xy 232.335782 -157.860536) (xy 232.335782 -157.920464)
			(xy 232.32796 -157.979879) (xy 232.31245 -158.037765) (xy 232.289518 -158.093132) (xy 232.259555 -158.145032)
			(xy 232.223075 -158.192577) (xy 232.180701 -158.234954) (xy 232.133158 -158.271437) (xy 232.081261 -158.301404)
			(xy 232.025896 -158.32434) (xy 231.968011 -158.339854) (xy 231.908596 -158.34768) (xy 231.878632 -158.348172)
			(xy 231.015032 -158.348172) (xy 230.985059 -158.347777) (xy 230.925626 -158.339956) (xy 230.867722 -158.324445)
			(xy 230.812339 -158.301507) (xy 230.760423 -158.271537) (xy 230.712864 -158.235047) (xy 230.670475 -158.19266)
			(xy 230.633981 -158.145103) (xy 230.604007 -158.09319) (xy 230.581066 -158.037808) (xy 230.56555 -157.979905)
			(xy 230.557725 -157.920473) (xy 230.089876 -157.920473) (xy 230.084738 -157.959498) (xy 230.069224 -158.017397)
			(xy 230.046286 -158.072775) (xy 230.016316 -158.124685) (xy 229.979827 -158.172239) (xy 229.937442 -158.214624)
			(xy 229.889888 -158.251114) (xy 229.837978 -158.281084) (xy 229.7826 -158.304023) (xy 229.724702 -158.319537)
			(xy 229.665274 -158.327362) (xy 229.635304 -158.327852) (xy 228.771704 -158.327852) (xy 228.741738 -158.327295)
			(xy 228.682318 -158.319473) (xy 228.624427 -158.303962) (xy 228.569056 -158.281027) (xy 228.517153 -158.251061)
			(xy 228.469605 -158.214576) (xy 228.427226 -158.172198) (xy 228.390741 -158.12465) (xy 228.360775 -158.072747)
			(xy 228.33784 -158.017377) (xy 228.322328 -157.959486) (xy 228.314505 -157.900066) (xy 4.308094 -157.900066)
			(xy 4.308094 -160.1851) (xy 45.524179 -160.1851) (xy 45.528134 -160.093263) (xy 45.539969 -160.002106)
			(xy 45.559596 -159.912303) (xy 45.58687 -159.824521) (xy 45.62159 -159.739407) (xy 45.663498 -159.657594)
			(xy 45.712284 -159.579686) (xy 45.767587 -159.506261) (xy 45.828997 -159.437861) (xy 45.896059 -159.374994)
			(xy 45.968278 -159.318124) (xy 46.045118 -159.267673) (xy 46.126011 -159.224014) (xy 46.210357 -159.187471)
			(xy 46.297533 -159.158314) (xy 46.386892 -159.13676) (xy 46.477773 -159.122966) (xy 46.569504 -159.117036)
			(xy 46.661405 -159.119014) (xy 46.752796 -159.128885) (xy 46.843 -159.146575) (xy 46.931349 -159.171955)
			(xy 47.017189 -159.204835) (xy 47.099885 -159.244973) (xy 47.178825 -159.292072) (xy 47.253423 -159.345782)
			(xy 47.323129 -159.405706) (xy 47.387424 -159.4714) (xy 47.445835 -159.542378) (xy 47.497927 -159.618115)
			(xy 47.543316 -159.69805) (xy 47.581666 -159.78159) (xy 47.612691 -159.868118) (xy 47.636164 -159.956993)
			(xy 47.65191 -160.047557) (xy 47.659812 -160.139139) (xy 47.660306 -160.1851) (xy 69.888875 -160.1851)
			(xy 69.892831 -160.093241) (xy 69.904668 -160.002062) (xy 69.9243 -159.912238) (xy 69.951581 -159.824435)
			(xy 69.986309 -159.739302) (xy 70.028227 -159.657469) (xy 70.077025 -159.579542) (xy 70.13234 -159.506099)
			(xy 70.193765 -159.437683) (xy 70.260844 -159.374801) (xy 70.333079 -159.317918) (xy 70.409938 -159.267455)
			(xy 70.49085 -159.223786) (xy 70.575216 -159.187234) (xy 70.662412 -159.15807) (xy 70.751793 -159.13651)
			(xy 70.842696 -159.122714) (xy 70.934449 -159.116782) (xy 71.026371 -159.118761) (xy 71.117784 -159.128634)
			(xy 71.208009 -159.146329) (xy 71.29638 -159.171714) (xy 71.38224 -159.204602) (xy 71.464956 -159.24475)
			(xy 71.543914 -159.291859) (xy 71.618531 -159.345582) (xy 71.688252 -159.40552) (xy 71.752563 -159.47123)
			(xy 71.810988 -159.542226) (xy 71.863093 -159.61798) (xy 71.908492 -159.697934) (xy 71.946851 -159.781494)
			(xy 71.977884 -159.868043) (xy 72.001362 -159.956939) (xy 72.017112 -160.047524) (xy 72.025016 -160.139128)
			(xy 72.02551 -160.1851) (xy 161.624277 -160.1851) (xy 161.628232 -160.093263) (xy 161.640067 -160.002106)
			(xy 161.659694 -159.912303) (xy 161.686968 -159.824521) (xy 161.721688 -159.739407) (xy 161.763596 -159.657594)
			(xy 161.812382 -159.579686) (xy 161.867685 -159.506261) (xy 161.929095 -159.437861) (xy 161.996157 -159.374994)
			(xy 162.068376 -159.318124) (xy 162.145216 -159.267673) (xy 162.226109 -159.224014) (xy 162.310455 -159.187471)
			(xy 162.397631 -159.158314) (xy 162.48699 -159.13676) (xy 162.577871 -159.122966) (xy 162.669602 -159.117036)
			(xy 162.761503 -159.119014) (xy 162.852894 -159.128885) (xy 162.943098 -159.146575) (xy 163.031447 -159.171955)
			(xy 163.117287 -159.204835) (xy 163.199983 -159.244973) (xy 163.278923 -159.292072) (xy 163.353521 -159.345782)
			(xy 163.423227 -159.405706) (xy 163.487522 -159.4714) (xy 163.545933 -159.542378) (xy 163.598025 -159.618115)
			(xy 163.643414 -159.69805) (xy 163.681764 -159.78159) (xy 163.712789 -159.868118) (xy 163.736262 -159.956993)
			(xy 163.752008 -160.047557) (xy 163.75991 -160.139139) (xy 163.760404 -160.1851) (xy 185.988973 -160.1851)
			(xy 185.992929 -160.093241) (xy 186.004766 -160.002062) (xy 186.024398 -159.912238) (xy 186.051679 -159.824435)
			(xy 186.086407 -159.739302) (xy 186.128325 -159.657469) (xy 186.177123 -159.579542) (xy 186.232438 -159.506099)
			(xy 186.293863 -159.437683) (xy 186.360942 -159.374801) (xy 186.433177 -159.317918) (xy 186.510036 -159.267455)
			(xy 186.590948 -159.223786) (xy 186.675314 -159.187234) (xy 186.76251 -159.15807) (xy 186.851891 -159.13651)
			(xy 186.942794 -159.122714) (xy 187.034547 -159.116782) (xy 187.126469 -159.118761) (xy 187.217882 -159.128634)
			(xy 187.308107 -159.146329) (xy 187.396478 -159.171714) (xy 187.482338 -159.204602) (xy 187.565054 -159.24475)
			(xy 187.644012 -159.291859) (xy 187.718629 -159.345582) (xy 187.78835 -159.40552) (xy 187.852661 -159.47123)
			(xy 187.911086 -159.542226) (xy 187.963191 -159.61798) (xy 188.00859 -159.697934) (xy 188.046949 -159.781494)
			(xy 188.077982 -159.868043) (xy 188.10146 -159.956939) (xy 188.11721 -160.047524) (xy 188.125114 -160.139128)
			(xy 188.125608 -160.1851) (xy 277.724121 -160.1851) (xy 277.728076 -160.093263) (xy 277.739911 -160.002106)
			(xy 277.759538 -159.912303) (xy 277.786812 -159.824521) (xy 277.821532 -159.739407) (xy 277.86344 -159.657594)
			(xy 277.912226 -159.579686) (xy 277.967529 -159.506261) (xy 278.028939 -159.437861) (xy 278.096001 -159.374994)
			(xy 278.16822 -159.318124) (xy 278.24506 -159.267673) (xy 278.325953 -159.224014) (xy 278.410299 -159.187471)
			(xy 278.497475 -159.158314) (xy 278.586834 -159.13676) (xy 278.677715 -159.122966) (xy 278.769446 -159.117036)
			(xy 278.861347 -159.119014) (xy 278.952738 -159.128885) (xy 279.042942 -159.146575) (xy 279.131291 -159.171955)
			(xy 279.217131 -159.204835) (xy 279.299827 -159.244973) (xy 279.378767 -159.292072) (xy 279.453365 -159.345782)
			(xy 279.523071 -159.405706) (xy 279.587366 -159.4714) (xy 279.645777 -159.542378) (xy 279.697869 -159.618115)
			(xy 279.743258 -159.69805) (xy 279.781608 -159.78159) (xy 279.812633 -159.868118) (xy 279.836106 -159.956993)
			(xy 279.851852 -160.047557) (xy 279.859754 -160.139139) (xy 279.860248 -160.1851) (xy 302.088817 -160.1851)
			(xy 302.092773 -160.093241) (xy 302.10461 -160.002062) (xy 302.124242 -159.912238) (xy 302.151523 -159.824435)
			(xy 302.186251 -159.739302) (xy 302.228169 -159.657469) (xy 302.276967 -159.579542) (xy 302.332282 -159.506099)
			(xy 302.393707 -159.437683) (xy 302.460786 -159.374801) (xy 302.533021 -159.317918) (xy 302.60988 -159.267455)
			(xy 302.690792 -159.223786) (xy 302.775158 -159.187234) (xy 302.862354 -159.15807) (xy 302.951735 -159.13651)
			(xy 303.042638 -159.122714) (xy 303.134391 -159.116782) (xy 303.226313 -159.118761) (xy 303.317726 -159.128634)
			(xy 303.407951 -159.146329) (xy 303.496322 -159.171714) (xy 303.582182 -159.204602) (xy 303.664898 -159.24475)
			(xy 303.743856 -159.291859) (xy 303.818473 -159.345582) (xy 303.888194 -159.40552) (xy 303.952505 -159.47123)
			(xy 304.01093 -159.542226) (xy 304.063035 -159.61798) (xy 304.108434 -159.697934) (xy 304.146793 -159.781494)
			(xy 304.177826 -159.868043) (xy 304.201304 -159.956939) (xy 304.217054 -160.047524) (xy 304.224958 -160.139128)
			(xy 304.225452 -160.1851) (xy 393.824219 -160.1851) (xy 393.828174 -160.093263) (xy 393.840009 -160.002106)
			(xy 393.859636 -159.912303) (xy 393.88691 -159.824521) (xy 393.92163 -159.739407) (xy 393.963538 -159.657594)
			(xy 394.012324 -159.579686) (xy 394.067627 -159.506261) (xy 394.129037 -159.437861) (xy 394.196099 -159.374994)
			(xy 394.268318 -159.318124) (xy 394.345158 -159.267673) (xy 394.426051 -159.224014) (xy 394.510397 -159.187471)
			(xy 394.597573 -159.158314) (xy 394.686932 -159.13676) (xy 394.777813 -159.122966) (xy 394.869544 -159.117036)
			(xy 394.961445 -159.119014) (xy 395.052836 -159.128885) (xy 395.14304 -159.146575) (xy 395.231389 -159.171955)
			(xy 395.317229 -159.204835) (xy 395.399925 -159.244973) (xy 395.478865 -159.292072) (xy 395.553463 -159.345782)
			(xy 395.623169 -159.405706) (xy 395.687464 -159.4714) (xy 395.745875 -159.542378) (xy 395.797967 -159.618115)
			(xy 395.843356 -159.69805) (xy 395.881706 -159.78159) (xy 395.912731 -159.868118) (xy 395.936204 -159.956993)
			(xy 395.95195 -160.047557) (xy 395.959852 -160.139139) (xy 395.960346 -160.1851) (xy 418.188915 -160.1851)
			(xy 418.192871 -160.093241) (xy 418.204708 -160.002062) (xy 418.22434 -159.912238) (xy 418.251621 -159.824435)
			(xy 418.286349 -159.739302) (xy 418.328267 -159.657469) (xy 418.377065 -159.579542) (xy 418.43238 -159.506099)
			(xy 418.493805 -159.437683) (xy 418.560884 -159.374801) (xy 418.633119 -159.317918) (xy 418.709978 -159.267455)
			(xy 418.79089 -159.223786) (xy 418.875256 -159.187234) (xy 418.962452 -159.15807) (xy 419.051833 -159.13651)
			(xy 419.142736 -159.122714) (xy 419.234489 -159.116782) (xy 419.326411 -159.118761) (xy 419.417824 -159.128634)
			(xy 419.508049 -159.146329) (xy 419.59642 -159.171714) (xy 419.68228 -159.204602) (xy 419.764996 -159.24475)
			(xy 419.843954 -159.291859) (xy 419.918571 -159.345582) (xy 419.988292 -159.40552) (xy 420.052603 -159.47123)
			(xy 420.111028 -159.542226) (xy 420.163133 -159.61798) (xy 420.208532 -159.697934) (xy 420.246891 -159.781494)
			(xy 420.277924 -159.868043) (xy 420.301402 -159.956939) (xy 420.317152 -160.047524) (xy 420.325056 -160.139128)
			(xy 420.32555 -160.1851) (xy 420.325056 -160.231072) (xy 420.317152 -160.322676) (xy 420.301402 -160.413261)
			(xy 420.277924 -160.502157) (xy 420.246891 -160.588706) (xy 420.208532 -160.672266) (xy 420.163133 -160.75222)
			(xy 420.111028 -160.827974) (xy 420.052603 -160.89897) (xy 419.988292 -160.96468) (xy 419.918571 -161.024618)
			(xy 419.843954 -161.078341) (xy 419.764996 -161.12545) (xy 419.68228 -161.165598) (xy 419.59642 -161.198486)
			(xy 419.508049 -161.223871) (xy 419.417824 -161.241566) (xy 419.326411 -161.251439) (xy 419.234489 -161.253418)
			(xy 419.142736 -161.247486) (xy 419.051833 -161.23369) (xy 418.962452 -161.21213) (xy 418.875256 -161.182966)
			(xy 418.79089 -161.146414) (xy 418.709978 -161.102745) (xy 418.633119 -161.052282) (xy 418.560884 -160.995399)
			(xy 418.493805 -160.932517) (xy 418.43238 -160.864101) (xy 418.377065 -160.790658) (xy 418.328267 -160.712731)
			(xy 418.286349 -160.630898) (xy 418.251621 -160.545765) (xy 418.22434 -160.457962) (xy 418.204708 -160.368138)
			(xy 418.192871 -160.276959) (xy 418.188915 -160.1851) (xy 395.960346 -160.1851) (xy 395.959852 -160.231061)
			(xy 395.95195 -160.322643) (xy 395.936204 -160.413207) (xy 395.912731 -160.502082) (xy 395.881706 -160.58861)
			(xy 395.843356 -160.67215) (xy 395.797967 -160.752085) (xy 395.745875 -160.827822) (xy 395.687464 -160.8988)
			(xy 395.623169 -160.964494) (xy 395.553463 -161.024418) (xy 395.478865 -161.078128) (xy 395.399925 -161.125227)
			(xy 395.317229 -161.165365) (xy 395.231389 -161.198245) (xy 395.14304 -161.223625) (xy 395.052836 -161.241315)
			(xy 394.961445 -161.251186) (xy 394.869544 -161.253164) (xy 394.777813 -161.247234) (xy 394.686932 -161.23344)
			(xy 394.597573 -161.211886) (xy 394.510397 -161.182729) (xy 394.426051 -161.146186) (xy 394.345158 -161.102527)
			(xy 394.268318 -161.052076) (xy 394.196099 -160.995206) (xy 394.129037 -160.932339) (xy 394.067627 -160.863939)
			(xy 394.012324 -160.790514) (xy 393.963538 -160.712606) (xy 393.92163 -160.630793) (xy 393.88691 -160.545679)
			(xy 393.859636 -160.457897) (xy 393.840009 -160.368094) (xy 393.828174 -160.276937) (xy 393.824219 -160.1851)
			(xy 304.225452 -160.1851) (xy 304.224958 -160.231072) (xy 304.217054 -160.322676) (xy 304.201304 -160.413261)
			(xy 304.177826 -160.502157) (xy 304.146793 -160.588706) (xy 304.108434 -160.672266) (xy 304.063035 -160.75222)
			(xy 304.01093 -160.827974) (xy 303.952505 -160.89897) (xy 303.888194 -160.96468) (xy 303.818473 -161.024618)
			(xy 303.743856 -161.078341) (xy 303.664898 -161.12545) (xy 303.582182 -161.165598) (xy 303.496322 -161.198486)
			(xy 303.407951 -161.223871) (xy 303.317726 -161.241566) (xy 303.226313 -161.251439) (xy 303.134391 -161.253418)
			(xy 303.042638 -161.247486) (xy 302.951735 -161.23369) (xy 302.862354 -161.21213) (xy 302.775158 -161.182966)
			(xy 302.690792 -161.146414) (xy 302.60988 -161.102745) (xy 302.533021 -161.052282) (xy 302.460786 -160.995399)
			(xy 302.393707 -160.932517) (xy 302.332282 -160.864101) (xy 302.276967 -160.790658) (xy 302.228169 -160.712731)
			(xy 302.186251 -160.630898) (xy 302.151523 -160.545765) (xy 302.124242 -160.457962) (xy 302.10461 -160.368138)
			(xy 302.092773 -160.276959) (xy 302.088817 -160.1851) (xy 279.860248 -160.1851) (xy 279.859754 -160.231061)
			(xy 279.851852 -160.322643) (xy 279.836106 -160.413207) (xy 279.812633 -160.502082) (xy 279.781608 -160.58861)
			(xy 279.743258 -160.67215) (xy 279.697869 -160.752085) (xy 279.645777 -160.827822) (xy 279.587366 -160.8988)
			(xy 279.523071 -160.964494) (xy 279.453365 -161.024418) (xy 279.378767 -161.078128) (xy 279.299827 -161.125227)
			(xy 279.217131 -161.165365) (xy 279.131291 -161.198245) (xy 279.042942 -161.223625) (xy 278.952738 -161.241315)
			(xy 278.861347 -161.251186) (xy 278.769446 -161.253164) (xy 278.677715 -161.247234) (xy 278.586834 -161.23344)
			(xy 278.497475 -161.211886) (xy 278.410299 -161.182729) (xy 278.325953 -161.146186) (xy 278.24506 -161.102527)
			(xy 278.16822 -161.052076) (xy 278.096001 -160.995206) (xy 278.028939 -160.932339) (xy 277.967529 -160.863939)
			(xy 277.912226 -160.790514) (xy 277.86344 -160.712606) (xy 277.821532 -160.630793) (xy 277.786812 -160.545679)
			(xy 277.759538 -160.457897) (xy 277.739911 -160.368094) (xy 277.728076 -160.276937) (xy 277.724121 -160.1851)
			(xy 188.125608 -160.1851) (xy 188.125114 -160.231072) (xy 188.11721 -160.322676) (xy 188.10146 -160.413261)
			(xy 188.077982 -160.502157) (xy 188.046949 -160.588706) (xy 188.00859 -160.672266) (xy 187.963191 -160.75222)
			(xy 187.911086 -160.827974) (xy 187.852661 -160.89897) (xy 187.78835 -160.96468) (xy 187.718629 -161.024618)
			(xy 187.644012 -161.078341) (xy 187.565054 -161.12545) (xy 187.482338 -161.165598) (xy 187.396478 -161.198486)
			(xy 187.308107 -161.223871) (xy 187.217882 -161.241566) (xy 187.126469 -161.251439) (xy 187.034547 -161.253418)
			(xy 186.942794 -161.247486) (xy 186.851891 -161.23369) (xy 186.76251 -161.21213) (xy 186.675314 -161.182966)
			(xy 186.590948 -161.146414) (xy 186.510036 -161.102745) (xy 186.433177 -161.052282) (xy 186.360942 -160.995399)
			(xy 186.293863 -160.932517) (xy 186.232438 -160.864101) (xy 186.177123 -160.790658) (xy 186.128325 -160.712731)
			(xy 186.086407 -160.630898) (xy 186.051679 -160.545765) (xy 186.024398 -160.457962) (xy 186.004766 -160.368138)
			(xy 185.992929 -160.276959) (xy 185.988973 -160.1851) (xy 163.760404 -160.1851) (xy 163.75991 -160.231061)
			(xy 163.752008 -160.322643) (xy 163.736262 -160.413207) (xy 163.712789 -160.502082) (xy 163.681764 -160.58861)
			(xy 163.643414 -160.67215) (xy 163.598025 -160.752085) (xy 163.545933 -160.827822) (xy 163.487522 -160.8988)
			(xy 163.423227 -160.964494) (xy 163.353521 -161.024418) (xy 163.278923 -161.078128) (xy 163.199983 -161.125227)
			(xy 163.117287 -161.165365) (xy 163.031447 -161.198245) (xy 162.943098 -161.223625) (xy 162.852894 -161.241315)
			(xy 162.761503 -161.251186) (xy 162.669602 -161.253164) (xy 162.577871 -161.247234) (xy 162.48699 -161.23344)
			(xy 162.397631 -161.211886) (xy 162.310455 -161.182729) (xy 162.226109 -161.146186) (xy 162.145216 -161.102527)
			(xy 162.068376 -161.052076) (xy 161.996157 -160.995206) (xy 161.929095 -160.932339) (xy 161.867685 -160.863939)
			(xy 161.812382 -160.790514) (xy 161.763596 -160.712606) (xy 161.721688 -160.630793) (xy 161.686968 -160.545679)
			(xy 161.659694 -160.457897) (xy 161.640067 -160.368094) (xy 161.628232 -160.276937) (xy 161.624277 -160.1851)
			(xy 72.02551 -160.1851) (xy 72.025016 -160.231072) (xy 72.017112 -160.322676) (xy 72.001362 -160.413261)
			(xy 71.977884 -160.502157) (xy 71.946851 -160.588706) (xy 71.908492 -160.672266) (xy 71.863093 -160.75222)
			(xy 71.810988 -160.827974) (xy 71.752563 -160.89897) (xy 71.688252 -160.96468) (xy 71.618531 -161.024618)
			(xy 71.543914 -161.078341) (xy 71.464956 -161.12545) (xy 71.38224 -161.165598) (xy 71.29638 -161.198486)
			(xy 71.208009 -161.223871) (xy 71.117784 -161.241566) (xy 71.026371 -161.251439) (xy 70.934449 -161.253418)
			(xy 70.842696 -161.247486) (xy 70.751793 -161.23369) (xy 70.662412 -161.21213) (xy 70.575216 -161.182966)
			(xy 70.49085 -161.146414) (xy 70.409938 -161.102745) (xy 70.333079 -161.052282) (xy 70.260844 -160.995399)
			(xy 70.193765 -160.932517) (xy 70.13234 -160.864101) (xy 70.077025 -160.790658) (xy 70.028227 -160.712731)
			(xy 69.986309 -160.630898) (xy 69.951581 -160.545765) (xy 69.9243 -160.457962) (xy 69.904668 -160.368138)
			(xy 69.892831 -160.276959) (xy 69.888875 -160.1851) (xy 47.660306 -160.1851) (xy 47.659812 -160.231061)
			(xy 47.65191 -160.322643) (xy 47.636164 -160.413207) (xy 47.612691 -160.502082) (xy 47.581666 -160.58861)
			(xy 47.543316 -160.67215) (xy 47.497927 -160.752085) (xy 47.445835 -160.827822) (xy 47.387424 -160.8988)
			(xy 47.323129 -160.964494) (xy 47.253423 -161.024418) (xy 47.178825 -161.078128) (xy 47.099885 -161.125227)
			(xy 47.017189 -161.165365) (xy 46.931349 -161.198245) (xy 46.843 -161.223625) (xy 46.752796 -161.241315)
			(xy 46.661405 -161.251186) (xy 46.569504 -161.253164) (xy 46.477773 -161.247234) (xy 46.386892 -161.23344)
			(xy 46.297533 -161.211886) (xy 46.210357 -161.182729) (xy 46.126011 -161.146186) (xy 46.045118 -161.102527)
			(xy 45.968278 -161.052076) (xy 45.896059 -160.995206) (xy 45.828997 -160.932339) (xy 45.767587 -160.863939)
			(xy 45.712284 -160.790514) (xy 45.663498 -160.712606) (xy 45.62159 -160.630793) (xy 45.58687 -160.545679)
			(xy 45.559596 -160.457897) (xy 45.539969 -160.368094) (xy 45.528134 -160.276937) (xy 45.524179 -160.1851)
			(xy 4.308094 -160.1851) (xy 4.308094 -168.065164) (xy 135.245906 -168.065164) (xy 135.245906 -168.005236)
			(xy 135.253728 -167.94582) (xy 135.269237 -167.887933) (xy 135.29217 -167.832566) (xy 135.322132 -167.780665)
			(xy 135.358612 -167.733119) (xy 135.400986 -167.690742) (xy 135.448529 -167.654257) (xy 135.500426 -167.624289)
			(xy 135.555791 -167.601351) (xy 135.613677 -167.585836) (xy 135.673092 -167.578009) (xy 135.703056 -167.577516)
			(xy 136.566656 -167.577516) (xy 136.596628 -167.577934) (xy 136.656061 -167.585754) (xy 136.713965 -167.601264)
			(xy 136.769348 -167.6242) (xy 136.821264 -167.654169) (xy 136.868823 -167.690658) (xy 136.911213 -167.733044)
			(xy 136.947707 -167.7806) (xy 136.977681 -167.832512) (xy 137.000622 -167.887894) (xy 137.016138 -167.945796)
			(xy 137.023963 -168.005228) (xy 137.023963 -168.065172) (xy 137.016138 -168.124604) (xy 137.000622 -168.182506)
			(xy 136.977681 -168.237888) (xy 136.947707 -168.2898) (xy 136.911213 -168.337356) (xy 136.868823 -168.379742)
			(xy 136.821264 -168.416231) (xy 136.769348 -168.4462) (xy 136.713965 -168.469136) (xy 136.656061 -168.484646)
			(xy 136.596628 -168.492466) (xy 136.566656 -168.492932) (xy 135.703056 -168.492932) (xy 135.673092 -168.492391)
			(xy 135.613677 -168.484564) (xy 135.555791 -168.469049) (xy 135.500426 -168.446111) (xy 135.448529 -168.416143)
			(xy 135.400986 -168.379658) (xy 135.358612 -168.337281) (xy 135.322132 -168.289735) (xy 135.29217 -168.237834)
			(xy 135.269237 -168.182467) (xy 135.253728 -168.12458) (xy 135.245906 -168.065164) (xy 4.308094 -168.065164)
			(xy 4.308094 -168.700164) (xy 133.213906 -168.700164) (xy 133.213906 -168.640236) (xy 133.221728 -168.58082)
			(xy 133.237237 -168.522933) (xy 133.26017 -168.467566) (xy 133.290132 -168.415665) (xy 133.326612 -168.368119)
			(xy 133.368986 -168.325742) (xy 133.416529 -168.289257) (xy 133.468426 -168.259289) (xy 133.523791 -168.236351)
			(xy 133.581677 -168.220836) (xy 133.641092 -168.213009) (xy 133.671056 -168.212516) (xy 134.534656 -168.212516)
			(xy 134.564628 -168.212934) (xy 134.624061 -168.220754) (xy 134.681965 -168.236264) (xy 134.737348 -168.2592)
			(xy 134.789264 -168.289169) (xy 134.836823 -168.325658) (xy 134.879213 -168.368044) (xy 134.915707 -168.4156)
			(xy 134.945681 -168.467512) (xy 134.968622 -168.522894) (xy 134.984138 -168.580796) (xy 134.991963 -168.640228)
			(xy 134.991963 -168.700172) (xy 134.984138 -168.759604) (xy 134.968622 -168.817506) (xy 134.945681 -168.872888)
			(xy 134.915707 -168.9248) (xy 134.879213 -168.972356) (xy 134.836823 -169.014742) (xy 134.789264 -169.051231)
			(xy 134.737348 -169.0812) (xy 134.681965 -169.104136) (xy 134.624061 -169.119646) (xy 134.564628 -169.127466)
			(xy 134.534656 -169.127932) (xy 133.671056 -169.127932) (xy 133.641092 -169.127391) (xy 133.581677 -169.119564)
			(xy 133.523791 -169.104049) (xy 133.468426 -169.081111) (xy 133.416529 -169.051143) (xy 133.368986 -169.014658)
			(xy 133.326612 -168.972281) (xy 133.290132 -168.924735) (xy 133.26017 -168.872834) (xy 133.237237 -168.817467)
			(xy 133.221728 -168.75958) (xy 133.213906 -168.700164) (xy 4.308094 -168.700164) (xy 4.308094 -169.61389)
			(xy 245.108869 -169.61389) (xy 245.108869 -169.55391) (xy 245.116699 -169.494444) (xy 245.132223 -169.436508)
			(xy 245.155178 -169.381095) (xy 245.185169 -169.329152) (xy 245.221684 -169.281569) (xy 245.264097 -169.239158)
			(xy 245.311684 -169.202648) (xy 245.363629 -169.172661) (xy 245.419045 -169.149711) (xy 245.476981 -169.134191)
			(xy 245.536448 -169.126367) (xy 245.566438 -169.1259) (xy 246.430038 -169.1259) (xy 246.460018 -169.126468)
			(xy 246.519465 -169.134299) (xy 246.577381 -169.149822) (xy 246.632776 -169.172772) (xy 246.684702 -169.202755)
			(xy 246.73227 -169.239259) (xy 246.774667 -169.281659) (xy 246.811166 -169.32923) (xy 246.841145 -169.381158)
			(xy 246.86409 -169.436555) (xy 246.879608 -169.494472) (xy 246.887434 -169.55392) (xy 246.887434 -169.61388)
			(xy 246.879608 -169.673328) (xy 246.86409 -169.731245) (xy 246.841145 -169.786642) (xy 246.811166 -169.83857)
			(xy 246.774667 -169.886141) (xy 246.73227 -169.928541) (xy 246.684702 -169.965045) (xy 246.632776 -169.995028)
			(xy 246.577381 -170.017978) (xy 246.519465 -170.033501) (xy 246.460018 -170.041332) (xy 246.430038 -170.041824)
			(xy 245.566438 -170.041824) (xy 245.536448 -170.041433) (xy 245.476981 -170.033609) (xy 245.419045 -170.018089)
			(xy 245.363629 -169.995139) (xy 245.311684 -169.965152) (xy 245.264097 -169.928642) (xy 245.221684 -169.886231)
			(xy 245.185169 -169.838648) (xy 245.155178 -169.786705) (xy 245.132223 -169.731292) (xy 245.116699 -169.673356)
			(xy 245.108869 -169.61389) (xy 4.308094 -169.61389) (xy 4.308094 -174.805086) (xy 141.546072 -174.805086)
			(xy 141.546072 -173.941486) (xy 141.546562 -173.911518) (xy 141.554385 -173.852096) (xy 141.569898 -173.794203)
			(xy 141.592834 -173.73883) (xy 141.622801 -173.686924) (xy 141.659288 -173.639374) (xy 141.701668 -173.596994)
			(xy 141.749218 -173.560507) (xy 141.801124 -173.53054) (xy 141.856497 -173.507604) (xy 141.91439 -173.492091)
			(xy 141.973812 -173.484268) (xy 142.033748 -173.484268) (xy 142.09317 -173.492091) (xy 142.106698 -173.495716)
			(xy 257.519424 -173.495716) (xy 257.519424 -172.632116) (xy 257.519914 -172.602132) (xy 257.527742 -172.542676)
			(xy 257.543263 -172.484751) (xy 257.566212 -172.429347) (xy 257.596196 -172.377413) (xy 257.632702 -172.329837)
			(xy 257.675107 -172.287432) (xy 257.722683 -172.250926) (xy 257.774617 -172.220942) (xy 257.830021 -172.197993)
			(xy 257.887946 -172.182472) (xy 257.947402 -172.174644) (xy 258.00737 -172.174644) (xy 258.066826 -172.182472)
			(xy 258.124751 -172.197993) (xy 258.180155 -172.220942) (xy 258.232089 -172.250926) (xy 258.279665 -172.287432)
			(xy 258.32207 -172.329837) (xy 258.358576 -172.377413) (xy 258.38856 -172.429347) (xy 258.411509 -172.484751)
			(xy 258.42703 -172.542676) (xy 258.434858 -172.602132) (xy 258.435348 -172.632116) (xy 258.435348 -173.495716)
			(xy 258.434858 -173.5257) (xy 258.42703 -173.585156) (xy 258.411509 -173.643081) (xy 258.38856 -173.698485)
			(xy 258.358576 -173.750419) (xy 258.32207 -173.797995) (xy 258.279665 -173.8404) (xy 258.232089 -173.876906)
			(xy 258.180155 -173.90689) (xy 258.124751 -173.929839) (xy 258.066826 -173.94536) (xy 258.00737 -173.953188)
			(xy 257.947402 -173.953188) (xy 257.887946 -173.94536) (xy 257.830021 -173.929839) (xy 257.774617 -173.90689)
			(xy 257.722683 -173.876906) (xy 257.675107 -173.8404) (xy 257.632702 -173.797995) (xy 257.596196 -173.750419)
			(xy 257.566212 -173.698485) (xy 257.543263 -173.643081) (xy 257.527742 -173.585156) (xy 257.519914 -173.5257)
			(xy 257.519424 -173.495716) (xy 142.106698 -173.495716) (xy 142.151063 -173.507604) (xy 142.206436 -173.53054)
			(xy 142.258342 -173.560507) (xy 142.305892 -173.596994) (xy 142.348272 -173.639374) (xy 142.384759 -173.686924)
			(xy 142.414726 -173.73883) (xy 142.437662 -173.794203) (xy 142.453175 -173.852096) (xy 142.460998 -173.911518)
			(xy 142.461488 -173.941486) (xy 142.461488 -174.805086) (xy 142.460998 -174.835054) (xy 142.453175 -174.894476)
			(xy 142.437662 -174.952369) (xy 142.414726 -175.007742) (xy 142.384759 -175.059648) (xy 142.348272 -175.107198)
			(xy 142.305892 -175.149578) (xy 142.258342 -175.186065) (xy 142.206436 -175.216032) (xy 142.151063 -175.238968)
			(xy 142.09317 -175.254481) (xy 142.033748 -175.262304) (xy 141.973812 -175.262304) (xy 141.91439 -175.254481)
			(xy 141.856497 -175.238968) (xy 141.801124 -175.216032) (xy 141.749218 -175.186065) (xy 141.701668 -175.149578)
			(xy 141.659288 -175.107198) (xy 141.622801 -175.059648) (xy 141.592834 -175.007742) (xy 141.569898 -174.952369)
			(xy 141.554385 -174.894476) (xy 141.546562 -174.835054) (xy 141.546072 -174.805086) (xy 4.308094 -174.805086)
			(xy 4.308094 -176.837086) (xy 142.181072 -176.837086) (xy 142.181072 -175.973486) (xy 142.181562 -175.943518)
			(xy 142.189385 -175.884096) (xy 142.204898 -175.826203) (xy 142.227834 -175.77083) (xy 142.257801 -175.718924)
			(xy 142.294288 -175.671374) (xy 142.336668 -175.628994) (xy 142.384218 -175.592507) (xy 142.436124 -175.56254)
			(xy 142.491497 -175.539604) (xy 142.54939 -175.524091) (xy 142.608812 -175.516268) (xy 142.668748 -175.516268)
			(xy 142.72817 -175.524091) (xy 142.786063 -175.539604) (xy 142.841436 -175.56254) (xy 142.893342 -175.592507)
			(xy 142.940892 -175.628994) (xy 142.983272 -175.671374) (xy 143.019759 -175.718924) (xy 143.049726 -175.77083)
			(xy 143.072662 -175.826203) (xy 143.088175 -175.884096) (xy 143.095998 -175.943518) (xy 143.096488 -175.973486)
			(xy 143.096488 -176.837086) (xy 143.095998 -176.867054) (xy 143.088175 -176.926476) (xy 143.072662 -176.984369)
			(xy 143.049726 -177.039742) (xy 143.019759 -177.091648) (xy 142.983272 -177.139198) (xy 142.940892 -177.181578)
			(xy 142.893342 -177.218065) (xy 142.841436 -177.248032) (xy 142.786063 -177.270968) (xy 142.72817 -177.286481)
			(xy 142.668748 -177.294304) (xy 142.608812 -177.294304) (xy 142.54939 -177.286481) (xy 142.491497 -177.270968)
			(xy 142.436124 -177.248032) (xy 142.384218 -177.218065) (xy 142.336668 -177.181578) (xy 142.294288 -177.139198)
			(xy 142.257801 -177.091648) (xy 142.227834 -177.039742) (xy 142.204898 -176.984369) (xy 142.189385 -176.926476)
			(xy 142.181562 -176.867054) (xy 142.181072 -176.837086) (xy 4.308094 -176.837086) (xy 4.308094 -178.995324)
			(xy 123.198636 -178.995324) (xy 123.198636 -178.131724) (xy 123.199126 -178.10174) (xy 123.206954 -178.042284)
			(xy 123.222475 -177.984359) (xy 123.245424 -177.928955) (xy 123.275408 -177.877021) (xy 123.311914 -177.829445)
			(xy 123.354319 -177.78704) (xy 123.401895 -177.750534) (xy 123.453829 -177.72055) (xy 123.509233 -177.697601)
			(xy 123.567158 -177.68208) (xy 123.626614 -177.674252) (xy 123.686582 -177.674252) (xy 123.746038 -177.68208)
			(xy 123.803963 -177.697601) (xy 123.859367 -177.72055) (xy 123.911301 -177.750534) (xy 123.958877 -177.78704)
			(xy 124.001282 -177.829445) (xy 124.037788 -177.877021) (xy 124.067772 -177.928955) (xy 124.090721 -177.984359)
			(xy 124.106242 -178.042284) (xy 124.11407 -178.10174) (xy 124.11456 -178.131724) (xy 124.11456 -178.869086)
			(xy 141.546072 -178.869086) (xy 141.546072 -178.005486) (xy 141.546562 -177.975518) (xy 141.554385 -177.916096)
			(xy 141.569898 -177.858203) (xy 141.592834 -177.80283) (xy 141.622801 -177.750924) (xy 141.659288 -177.703374)
			(xy 141.701668 -177.660994) (xy 141.749218 -177.624507) (xy 141.801124 -177.59454) (xy 141.856497 -177.571604)
			(xy 141.91439 -177.556091) (xy 141.973812 -177.548268) (xy 142.033748 -177.548268) (xy 142.09317 -177.556091)
			(xy 142.151063 -177.571604) (xy 142.206436 -177.59454) (xy 142.258342 -177.624507) (xy 142.305892 -177.660994)
			(xy 142.348272 -177.703374) (xy 142.384759 -177.750924) (xy 142.414726 -177.80283) (xy 142.437662 -177.858203)
			(xy 142.453175 -177.916096) (xy 142.460998 -177.975518) (xy 142.461488 -178.005486) (xy 142.461488 -178.869086)
			(xy 142.460998 -178.899054) (xy 142.453175 -178.958476) (xy 142.437662 -179.016369) (xy 142.414726 -179.071742)
			(xy 142.384759 -179.123648) (xy 142.348272 -179.171198) (xy 142.305892 -179.213578) (xy 142.258342 -179.250065)
			(xy 142.206436 -179.280032) (xy 142.151063 -179.302968) (xy 142.09317 -179.318481) (xy 142.033748 -179.326304)
			(xy 141.973812 -179.326304) (xy 141.91439 -179.318481) (xy 141.856497 -179.302968) (xy 141.801124 -179.280032)
			(xy 141.749218 -179.250065) (xy 141.701668 -179.213578) (xy 141.659288 -179.171198) (xy 141.622801 -179.123648)
			(xy 141.592834 -179.071742) (xy 141.569898 -179.016369) (xy 141.554385 -178.958476) (xy 141.546562 -178.899054)
			(xy 141.546072 -178.869086) (xy 124.11456 -178.869086) (xy 124.11456 -178.995324) (xy 124.11407 -179.025308)
			(xy 124.106242 -179.084764) (xy 124.090721 -179.142689) (xy 124.067772 -179.198093) (xy 124.037788 -179.250027)
			(xy 124.001282 -179.297603) (xy 123.958877 -179.340008) (xy 123.911301 -179.376514) (xy 123.859367 -179.406498)
			(xy 123.803963 -179.429447) (xy 123.746038 -179.444968) (xy 123.686582 -179.452796) (xy 123.626614 -179.452796)
			(xy 123.567158 -179.444968) (xy 123.509233 -179.429447) (xy 123.453829 -179.406498) (xy 123.401895 -179.376514)
			(xy 123.354319 -179.340008) (xy 123.311914 -179.297603) (xy 123.275408 -179.250027) (xy 123.245424 -179.198093)
			(xy 123.222475 -179.142689) (xy 123.206954 -179.084764) (xy 123.199126 -179.025308) (xy 123.198636 -178.995324)
			(xy 4.308094 -178.995324) (xy 4.308094 -180.901086) (xy 142.181072 -180.901086) (xy 142.181072 -180.037486)
			(xy 142.181562 -180.007518) (xy 142.189385 -179.948096) (xy 142.204898 -179.890203) (xy 142.227834 -179.83483)
			(xy 142.257801 -179.782924) (xy 142.294288 -179.735374) (xy 142.336668 -179.692994) (xy 142.384218 -179.656507)
			(xy 142.436124 -179.62654) (xy 142.491497 -179.603604) (xy 142.54939 -179.588091) (xy 142.608812 -179.580268)
			(xy 142.668748 -179.580268) (xy 142.72817 -179.588091) (xy 142.786063 -179.603604) (xy 142.841436 -179.62654)
			(xy 142.893342 -179.656507) (xy 142.940892 -179.692994) (xy 142.983272 -179.735374) (xy 143.019759 -179.782924)
			(xy 143.049726 -179.83483) (xy 143.072662 -179.890203) (xy 143.088175 -179.948096) (xy 143.095998 -180.007518)
			(xy 143.096488 -180.037486) (xy 143.096488 -180.901086) (xy 143.095998 -180.931054) (xy 143.088175 -180.990476)
			(xy 143.072662 -181.048369) (xy 143.049726 -181.103742) (xy 143.019759 -181.155648) (xy 142.983272 -181.203198)
			(xy 142.940892 -181.245578) (xy 142.893342 -181.282065) (xy 142.841436 -181.312032) (xy 142.786063 -181.334968)
			(xy 142.72817 -181.350481) (xy 142.668748 -181.358304) (xy 142.608812 -181.358304) (xy 142.54939 -181.350481)
			(xy 142.491497 -181.334968) (xy 142.436124 -181.312032) (xy 142.384218 -181.282065) (xy 142.336668 -181.245578)
			(xy 142.294288 -181.203198) (xy 142.257801 -181.155648) (xy 142.227834 -181.103742) (xy 142.204898 -181.048369)
			(xy 142.189385 -180.990476) (xy 142.181562 -180.931054) (xy 142.181072 -180.901086) (xy 4.308094 -180.901086)
			(xy 4.308094 -182.933086) (xy 141.546072 -182.933086) (xy 141.546072 -182.069486) (xy 141.546562 -182.039518)
			(xy 141.554385 -181.980096) (xy 141.569898 -181.922203) (xy 141.592834 -181.86683) (xy 141.622801 -181.814924)
			(xy 141.659288 -181.767374) (xy 141.701668 -181.724994) (xy 141.749218 -181.688507) (xy 141.801124 -181.65854)
			(xy 141.856497 -181.635604) (xy 141.91439 -181.620091) (xy 141.973812 -181.612268) (xy 142.033748 -181.612268)
			(xy 142.09317 -181.620091) (xy 142.151063 -181.635604) (xy 142.206436 -181.65854) (xy 142.258342 -181.688507)
			(xy 142.305892 -181.724994) (xy 142.348272 -181.767374) (xy 142.384759 -181.814924) (xy 142.414726 -181.86683)
			(xy 142.437662 -181.922203) (xy 142.453175 -181.980096) (xy 142.460998 -182.039518) (xy 142.461488 -182.069486)
			(xy 142.461488 -182.933086) (xy 142.460998 -182.963054) (xy 142.453175 -183.022476) (xy 142.437662 -183.080369)
			(xy 142.414726 -183.135742) (xy 142.384759 -183.187648) (xy 142.348272 -183.235198) (xy 142.305892 -183.277578)
			(xy 142.258342 -183.314065) (xy 142.206436 -183.344032) (xy 142.151063 -183.366968) (xy 142.09317 -183.382481)
			(xy 142.033748 -183.390304) (xy 141.973812 -183.390304) (xy 141.91439 -183.382481) (xy 141.856497 -183.366968)
			(xy 141.801124 -183.344032) (xy 141.749218 -183.314065) (xy 141.701668 -183.277578) (xy 141.659288 -183.235198)
			(xy 141.622801 -183.187648) (xy 141.592834 -183.135742) (xy 141.569898 -183.080369) (xy 141.554385 -183.022476)
			(xy 141.546562 -182.963054) (xy 141.546072 -182.933086) (xy 4.308094 -182.933086) (xy 4.308094 -187.124582)
			(xy 135.58115 -187.124582) (xy 135.58115 -187.064618) (xy 135.588977 -187.005166) (xy 135.604497 -186.947244)
			(xy 135.627444 -186.891844) (xy 135.657426 -186.839912) (xy 135.69393 -186.792339) (xy 135.736331 -186.749937)
			(xy 135.783904 -186.713432) (xy 135.835835 -186.683448) (xy 135.891235 -186.6605) (xy 135.949156 -186.644979)
			(xy 136.008608 -186.637151) (xy 136.03859 -186.63666) (xy 136.90219 -186.63666) (xy 136.932178 -186.637085)
			(xy 136.99164 -186.644912) (xy 137.049571 -186.660433) (xy 137.104981 -186.683384) (xy 137.156922 -186.713371)
			(xy 137.204504 -186.749881) (xy 137.246913 -186.792289) (xy 137.283424 -186.83987) (xy 137.313412 -186.89181)
			(xy 137.336363 -186.947219) (xy 137.351886 -187.005151) (xy 137.359715 -187.064612) (xy 137.359715 -187.124588)
			(xy 137.351886 -187.184049) (xy 137.336363 -187.241981) (xy 137.313412 -187.29739) (xy 137.283424 -187.34933)
			(xy 137.246913 -187.396911) (xy 137.204504 -187.439319) (xy 137.156922 -187.475829) (xy 137.104981 -187.505816)
			(xy 137.049571 -187.528767) (xy 136.99164 -187.544288) (xy 136.932178 -187.552115) (xy 136.90219 -187.552584)
			(xy 136.03859 -187.552584) (xy 136.008608 -187.552049) (xy 135.949156 -187.544221) (xy 135.891235 -187.5287)
			(xy 135.835835 -187.505752) (xy 135.783904 -187.475768) (xy 135.736331 -187.439263) (xy 135.69393 -187.396861)
			(xy 135.657426 -187.349288) (xy 135.627444 -187.297356) (xy 135.604497 -187.241956) (xy 135.588977 -187.184034)
			(xy 135.58115 -187.124582) (xy 4.308094 -187.124582) (xy 4.308094 -188.252885) (xy 128.656818 -188.252885)
			(xy 128.656818 -188.192915) (xy 128.664646 -188.133459) (xy 128.680167 -188.075533) (xy 128.703116 -188.020128)
			(xy 128.733101 -187.968193) (xy 128.769608 -187.920615) (xy 128.812012 -187.87821) (xy 128.859589 -187.841703)
			(xy 128.911524 -187.811718) (xy 128.966929 -187.788768) (xy 129.024855 -187.773246) (xy 129.084311 -187.765418)
			(xy 129.114296 -187.764928) (xy 129.977896 -187.764928) (xy 130.007881 -187.765417) (xy 130.067339 -187.773244)
			(xy 130.125266 -187.788765) (xy 130.180671 -187.811714) (xy 130.232607 -187.841699) (xy 130.280185 -187.878207)
			(xy 130.322591 -187.920612) (xy 130.359098 -187.96819) (xy 130.389084 -188.020125) (xy 130.412034 -188.075531)
			(xy 130.427555 -188.133458) (xy 130.435383 -188.192915) (xy 130.435383 -188.252885) (xy 130.434185 -188.261981)
			(xy 131.046262 -188.261981) (xy 131.046262 -188.202019) (xy 131.054088 -188.14257) (xy 131.069607 -188.084651)
			(xy 131.092553 -188.029253) (xy 131.122533 -187.977324) (xy 131.159034 -187.929752) (xy 131.201432 -187.887351)
			(xy 131.249002 -187.850847) (xy 131.30093 -187.820864) (xy 131.356326 -187.797915) (xy 131.414244 -187.782393)
			(xy 131.473693 -187.774564) (xy 131.503674 -187.774072) (xy 132.367274 -187.774072) (xy 132.397263 -187.774472)
			(xy 132.456728 -187.782297) (xy 132.514663 -187.797818) (xy 132.570077 -187.820768) (xy 132.62202 -187.850755)
			(xy 132.669605 -187.887266) (xy 132.712017 -187.929675) (xy 132.74853 -187.977258) (xy 132.77852 -188.0292)
			(xy 132.801474 -188.084612) (xy 132.816998 -188.142546) (xy 132.824827 -188.202011) (xy 132.824827 -188.261989)
			(xy 132.816998 -188.321454) (xy 132.801474 -188.379388) (xy 132.79518 -188.394582) (xy 133.54915 -188.394582)
			(xy 133.54915 -188.334618) (xy 133.556977 -188.275166) (xy 133.572497 -188.217244) (xy 133.595444 -188.161844)
			(xy 133.625426 -188.109912) (xy 133.66193 -188.062339) (xy 133.704331 -188.019937) (xy 133.751904 -187.983432)
			(xy 133.803835 -187.953448) (xy 133.859235 -187.9305) (xy 133.917156 -187.914979) (xy 133.976608 -187.907151)
			(xy 134.00659 -187.90666) (xy 134.87019 -187.90666) (xy 134.900178 -187.907085) (xy 134.95964 -187.914912)
			(xy 135.017571 -187.930433) (xy 135.072981 -187.953384) (xy 135.124922 -187.983371) (xy 135.172504 -188.019881)
			(xy 135.214913 -188.062289) (xy 135.251424 -188.10987) (xy 135.281412 -188.16181) (xy 135.304363 -188.217219)
			(xy 135.319886 -188.275151) (xy 135.327715 -188.334612) (xy 135.327715 -188.394588) (xy 135.319886 -188.454049)
			(xy 135.304363 -188.511981) (xy 135.281412 -188.56739) (xy 135.251424 -188.61933) (xy 135.214913 -188.666911)
			(xy 135.172504 -188.709319) (xy 135.124922 -188.745829) (xy 135.072981 -188.775816) (xy 135.017571 -188.798767)
			(xy 134.95964 -188.814288) (xy 134.900178 -188.822115) (xy 134.87019 -188.822584) (xy 134.00659 -188.822584)
			(xy 133.976608 -188.822049) (xy 133.917156 -188.814221) (xy 133.859235 -188.7987) (xy 133.803835 -188.775752)
			(xy 133.751904 -188.745768) (xy 133.704331 -188.709263) (xy 133.66193 -188.666861) (xy 133.625426 -188.619288)
			(xy 133.595444 -188.567356) (xy 133.572497 -188.511956) (xy 133.556977 -188.454034) (xy 133.54915 -188.394582)
			(xy 132.79518 -188.394582) (xy 132.77852 -188.4348) (xy 132.74853 -188.486742) (xy 132.712017 -188.534325)
			(xy 132.669605 -188.576734) (xy 132.62202 -188.613245) (xy 132.570077 -188.643232) (xy 132.514663 -188.666182)
			(xy 132.456728 -188.681703) (xy 132.397263 -188.689528) (xy 132.367274 -188.689996) (xy 131.503674 -188.689996)
			(xy 131.473693 -188.689436) (xy 131.414244 -188.681607) (xy 131.356326 -188.666085) (xy 131.30093 -188.643136)
			(xy 131.249002 -188.613153) (xy 131.201432 -188.576649) (xy 131.159034 -188.534248) (xy 131.122533 -188.486676)
			(xy 131.092553 -188.434747) (xy 131.069607 -188.379349) (xy 131.054088 -188.32143) (xy 131.046262 -188.261981)
			(xy 130.434185 -188.261981) (xy 130.427555 -188.312342) (xy 130.412034 -188.370269) (xy 130.389084 -188.425675)
			(xy 130.359098 -188.47761) (xy 130.322591 -188.525188) (xy 130.280185 -188.567593) (xy 130.232607 -188.604101)
			(xy 130.180671 -188.634086) (xy 130.125266 -188.657035) (xy 130.067339 -188.672556) (xy 130.007881 -188.680383)
			(xy 129.977896 -188.680852) (xy 129.114296 -188.680852) (xy 129.084311 -188.680382) (xy 129.024855 -188.672554)
			(xy 128.966929 -188.657032) (xy 128.911524 -188.634082) (xy 128.859589 -188.604097) (xy 128.812012 -188.56759)
			(xy 128.769608 -188.525185) (xy 128.733101 -188.477607) (xy 128.703116 -188.425672) (xy 128.680167 -188.370267)
			(xy 128.664646 -188.312341) (xy 128.656818 -188.252885) (xy 4.308094 -188.252885) (xy 4.308094 -195.726088)
			(xy 126.922185 -195.726088) (xy 126.922185 -195.666112) (xy 126.930014 -195.606648) (xy 126.945538 -195.548715)
			(xy 126.968491 -195.493304) (xy 126.99848 -195.441364) (xy 127.034993 -195.393782) (xy 127.077404 -195.351373)
			(xy 127.124989 -195.314864) (xy 127.176931 -195.284878) (xy 127.232344 -195.261928) (xy 127.290278 -195.246408)
			(xy 127.349742 -195.238583) (xy 127.37973 -195.238116) (xy 128.24333 -195.238116) (xy 128.273312 -195.238652)
			(xy 128.332761 -195.246482) (xy 128.39068 -195.262005) (xy 128.446078 -195.284955) (xy 128.498007 -195.314939)
			(xy 128.545577 -195.351444) (xy 128.587976 -195.393845) (xy 128.624478 -195.441418) (xy 128.654459 -195.493349)
			(xy 128.677405 -195.548748) (xy 128.692924 -195.606668) (xy 128.70075 -195.666118) (xy 128.70075 -195.726082)
			(xy 128.692924 -195.785532) (xy 128.677405 -195.843452) (xy 128.654459 -195.898851) (xy 128.624478 -195.950782)
			(xy 128.587976 -195.998355) (xy 128.545577 -196.040756) (xy 128.498007 -196.077261) (xy 128.446078 -196.107245)
			(xy 128.39068 -196.130195) (xy 128.332761 -196.145718) (xy 128.273312 -196.153548) (xy 128.24333 -196.15404)
			(xy 127.37973 -196.15404) (xy 127.349742 -196.153617) (xy 127.290278 -196.145792) (xy 127.232344 -196.130272)
			(xy 127.176931 -196.107322) (xy 127.124989 -196.077336) (xy 127.077404 -196.040827) (xy 127.034993 -195.998418)
			(xy 126.99848 -195.950836) (xy 126.968491 -195.898896) (xy 126.945538 -195.843485) (xy 126.930014 -195.785552)
			(xy 126.922185 -195.726088) (xy 4.308094 -195.726088) (xy 4.308094 -198.543743) (xy 138.243774 -198.543743)
			(xy 138.24519 -198.489257) (xy 138.254343 -198.435528) (xy 138.271047 -198.383647) (xy 138.294963 -198.33467)
			(xy 138.325603 -198.289594) (xy 138.362344 -198.249336) (xy 138.40444 -198.214715) (xy 138.451033 -198.186434)
			(xy 138.501175 -198.165071) (xy 138.553847 -198.151058) (xy 138.607977 -198.144682) (xy 138.635232 -198.144892)
			(xy 138.636502 -198.144892) (xy 139.488672 -198.144892) (xy 139.515926 -198.145353) (xy 139.56988 -198.153107)
			(xy 139.622181 -198.168461) (xy 139.671765 -198.191102) (xy 139.717622 -198.220569) (xy 139.758818 -198.256263)
			(xy 139.794514 -198.297456) (xy 139.823985 -198.34331) (xy 139.846629 -198.392892) (xy 139.861987 -198.445192)
			(xy 139.869745 -198.499146) (xy 139.869745 -198.553654) (xy 139.861987 -198.607608) (xy 139.846629 -198.659908)
			(xy 139.823985 -198.70949) (xy 139.794514 -198.755344) (xy 139.758818 -198.796537) (xy 139.717622 -198.832231)
			(xy 139.671765 -198.861698) (xy 139.622181 -198.884339) (xy 139.56988 -198.899693) (xy 139.515926 -198.907447)
			(xy 139.488672 -198.907908) (xy 139.477343 -198.907862) (xy 139.454723 -198.90659) (xy 139.44346 -198.905368)
			(xy 139.440412 -198.90486) (xy 138.672824 -198.90486) (xy 138.669776 -198.905368) (xy 138.642662 -198.908134)
			(xy 138.588177 -198.906693) (xy 138.534452 -198.897514) (xy 138.482579 -198.880785) (xy 138.433613 -198.856847)
			(xy 138.388552 -198.826185) (xy 138.348311 -198.789424) (xy 138.31371 -198.747312) (xy 138.285452 -198.700706)
			(xy 138.264112 -198.650554) (xy 138.250125 -198.597875) (xy 138.243774 -198.543743) (xy 4.308094 -198.543743)
			(xy 4.308094 -201.379368) (xy 98.428551 -201.379368) (xy 98.428551 -201.324832) (xy 98.436313 -201.270851)
			(xy 98.451678 -201.218525) (xy 98.474333 -201.168917) (xy 98.503818 -201.123039) (xy 98.539531 -201.081824)
			(xy 98.580747 -201.046112) (xy 98.626626 -201.016628) (xy 98.676234 -200.993974) (xy 98.728561 -200.978611)
			(xy 98.782542 -200.970851) (xy 98.80981 -200.970388) (xy 99.67341 -200.970388) (xy 99.700682 -200.970775)
			(xy 99.754672 -200.978539) (xy 99.807007 -200.993907) (xy 99.856623 -201.016567) (xy 99.902508 -201.046057)
			(xy 99.94373 -201.081777) (xy 99.979449 -201.123) (xy 100.008938 -201.168886) (xy 100.031596 -201.218502)
			(xy 100.046963 -201.270838) (xy 100.054725 -201.324828) (xy 100.054725 -201.379372) (xy 100.046963 -201.433362)
			(xy 100.031596 -201.485698) (xy 100.008938 -201.535314) (xy 99.979449 -201.5812) (xy 99.94373 -201.622423)
			(xy 99.902508 -201.658143) (xy 99.856623 -201.687633) (xy 99.807007 -201.710293) (xy 99.754672 -201.725661)
			(xy 99.700682 -201.733425) (xy 99.67341 -201.733912) (xy 98.80981 -201.733912) (xy 98.782542 -201.733349)
			(xy 98.728561 -201.725589) (xy 98.676234 -201.710226) (xy 98.626626 -201.687572) (xy 98.580747 -201.658088)
			(xy 98.539531 -201.622376) (xy 98.503818 -201.581161) (xy 98.474333 -201.535283) (xy 98.451678 -201.485675)
			(xy 98.436313 -201.433349) (xy 98.428551 -201.379368) (xy 4.308094 -201.379368) (xy 4.308094 -209.380836)
			(xy 445.288416 -209.380836) (xy 445.288416 -208.517236) (xy 445.288906 -208.487268) (xy 445.296729 -208.427846)
			(xy 445.312242 -208.369953) (xy 445.335178 -208.31458) (xy 445.365145 -208.262674) (xy 445.401632 -208.215124)
			(xy 445.444012 -208.172744) (xy 445.491562 -208.136257) (xy 445.543468 -208.10629) (xy 445.598841 -208.083354)
			(xy 445.656734 -208.067841) (xy 445.716156 -208.060018) (xy 445.776092 -208.060018) (xy 445.835514 -208.067841)
			(xy 445.893407 -208.083354) (xy 445.94878 -208.10629) (xy 446.000686 -208.136257) (xy 446.048236 -208.172744)
			(xy 446.090616 -208.215124) (xy 446.127103 -208.262674) (xy 446.15707 -208.31458) (xy 446.180006 -208.369953)
			(xy 446.195519 -208.427846) (xy 446.203342 -208.487268) (xy 446.203832 -208.517236) (xy 446.203832 -209.380836)
			(xy 446.203342 -209.410804) (xy 446.195519 -209.470226) (xy 446.180006 -209.528119) (xy 446.15707 -209.583492)
			(xy 446.127103 -209.635398) (xy 446.090616 -209.682948) (xy 446.048236 -209.725328) (xy 446.000686 -209.761815)
			(xy 445.94878 -209.791782) (xy 445.893407 -209.814718) (xy 445.835514 -209.830231) (xy 445.776092 -209.838054)
			(xy 445.716156 -209.838054) (xy 445.656734 -209.830231) (xy 445.598841 -209.814718) (xy 445.543468 -209.791782)
			(xy 445.491562 -209.761815) (xy 445.444012 -209.725328) (xy 445.401632 -209.682948) (xy 445.365145 -209.635398)
			(xy 445.335178 -209.583492) (xy 445.312242 -209.528119) (xy 445.296729 -209.470226) (xy 445.288906 -209.410804)
			(xy 445.288416 -209.380836) (xy 4.308094 -209.380836) (xy 4.308094 -225.261473) (xy 239.822113 -225.261473)
			(xy 239.822113 -225.201527) (xy 239.829938 -225.142093) (xy 239.845454 -225.084189) (xy 239.868395 -225.028806)
			(xy 239.89837 -224.976891) (xy 239.934864 -224.929333) (xy 239.977254 -224.886945) (xy 240.024814 -224.850454)
			(xy 240.076731 -224.820483) (xy 240.132115 -224.797545) (xy 240.19002 -224.782032) (xy 240.249455 -224.774211)
			(xy 240.279428 -224.773744) (xy 241.143028 -224.773744) (xy 241.172991 -224.774332) (xy 241.232405 -224.782157)
			(xy 241.290289 -224.79767) (xy 241.345653 -224.820606) (xy 241.39755 -224.850571) (xy 241.445091 -224.887054)
			(xy 241.487465 -224.92943) (xy 241.523944 -224.976974) (xy 241.553907 -225.028872) (xy 241.576839 -225.084238)
			(xy 241.592348 -225.142123) (xy 241.60017 -225.201537) (xy 241.60017 -225.261463) (xy 241.592348 -225.320877)
			(xy 241.576839 -225.378762) (xy 241.553907 -225.434128) (xy 241.523944 -225.486026) (xy 241.487465 -225.53357)
			(xy 241.445091 -225.575946) (xy 241.39755 -225.612429) (xy 241.345653 -225.642394) (xy 241.290289 -225.66533)
			(xy 241.232405 -225.680843) (xy 241.172991 -225.688668) (xy 241.143028 -225.68916) (xy 240.279428 -225.68916)
			(xy 240.249455 -225.688789) (xy 240.19002 -225.680968) (xy 240.132115 -225.665455) (xy 240.076731 -225.642517)
			(xy 240.024814 -225.612546) (xy 239.977254 -225.576055) (xy 239.934864 -225.533667) (xy 239.89837 -225.486109)
			(xy 239.868395 -225.434194) (xy 239.845454 -225.378811) (xy 239.829938 -225.320907) (xy 239.822113 -225.261473)
			(xy 4.308094 -225.261473) (xy 4.308094 -230.903589) (xy 383.216061 -230.903589) (xy 383.216061 -230.843611)
			(xy 383.22389 -230.784147) (xy 383.239413 -230.726213) (xy 383.262366 -230.670801) (xy 383.292355 -230.618858)
			(xy 383.328867 -230.571275) (xy 383.371278 -230.528865) (xy 383.418862 -230.492353) (xy 383.470804 -230.462364)
			(xy 383.526216 -230.439412) (xy 383.584151 -230.423889) (xy 383.643615 -230.416061) (xy 383.673604 -230.415592)
			(xy 384.537204 -230.415592) (xy 384.567185 -230.416174) (xy 384.626634 -230.424001) (xy 384.684553 -230.439521)
			(xy 384.739951 -230.462468) (xy 384.79188 -230.492449) (xy 384.839451 -230.528952) (xy 384.88185 -230.571352)
			(xy 384.918353 -230.618924) (xy 384.948334 -230.670853) (xy 384.97128 -230.726251) (xy 384.986799 -230.78417)
			(xy 384.994626 -230.843619) (xy 384.994626 -230.903581) (xy 384.986799 -230.96303) (xy 384.97128 -231.020949)
			(xy 384.948334 -231.076347) (xy 384.918353 -231.128276) (xy 384.88185 -231.175848) (xy 384.839451 -231.218248)
			(xy 384.79188 -231.254751) (xy 384.739951 -231.284732) (xy 384.684553 -231.307679) (xy 384.626634 -231.323199)
			(xy 384.567185 -231.331026) (xy 384.537204 -231.331516) (xy 383.673604 -231.331516) (xy 383.643615 -231.331139)
			(xy 383.584151 -231.323311) (xy 383.526216 -231.307788) (xy 383.470804 -231.284836) (xy 383.418862 -231.254847)
			(xy 383.371278 -231.218335) (xy 383.328867 -231.175925) (xy 383.292355 -231.128342) (xy 383.262366 -231.076399)
			(xy 383.239413 -231.020987) (xy 383.22389 -230.963053) (xy 383.216061 -230.903589) (xy 4.308094 -230.903589)
			(xy 4.308094 -234.655869) (xy 448.021157 -234.655869) (xy 448.021157 -234.595931) (xy 448.028981 -234.536505)
			(xy 448.044494 -234.478608) (xy 448.067432 -234.423232) (xy 448.097401 -234.371324) (xy 448.13389 -234.323771)
			(xy 448.176273 -234.281388) (xy 448.223825 -234.2449) (xy 448.275734 -234.214931) (xy 448.33111 -234.191993)
			(xy 448.389007 -234.17648) (xy 448.448433 -234.168657) (xy 448.478402 -234.168188) (xy 449.342002 -234.168188)
			(xy 449.371969 -234.168686) (xy 449.431391 -234.176509) (xy 449.489283 -234.192022) (xy 449.544656 -234.214958)
			(xy 449.596561 -234.244925) (xy 449.64411 -234.281411) (xy 449.68649 -234.323792) (xy 449.722976 -234.371341)
			(xy 449.752943 -234.423246) (xy 449.775879 -234.478618) (xy 449.791391 -234.536511) (xy 449.799214 -234.595933)
			(xy 449.799214 -234.655867) (xy 449.791391 -234.715289) (xy 449.775879 -234.773182) (xy 449.752943 -234.828554)
			(xy 449.722976 -234.880459) (xy 449.68649 -234.928008) (xy 449.64411 -234.970389) (xy 449.596561 -235.006875)
			(xy 449.544656 -235.036842) (xy 449.489283 -235.059778) (xy 449.431391 -235.075291) (xy 449.371969 -235.083114)
			(xy 449.342002 -235.083604) (xy 448.478402 -235.083604) (xy 448.448433 -235.083143) (xy 448.389007 -235.07532)
			(xy 448.33111 -235.059807) (xy 448.275734 -235.036869) (xy 448.223825 -235.0069) (xy 448.176273 -234.970412)
			(xy 448.13389 -234.928029) (xy 448.097401 -234.880476) (xy 448.067432 -234.828568) (xy 448.044494 -234.773192)
			(xy 448.028981 -234.715295) (xy 448.021157 -234.655869) (xy 4.308094 -234.655869) (xy 4.308094 -239.07907)
			(xy 153.398934 -239.07907) (xy 153.398934 -239.01913) (xy 153.406758 -238.959703) (xy 153.422271 -238.901805)
			(xy 153.445208 -238.846427) (xy 153.475178 -238.794517) (xy 153.511666 -238.746963) (xy 153.554049 -238.704578)
			(xy 153.601602 -238.668088) (xy 153.653511 -238.638116) (xy 153.708888 -238.615177) (xy 153.766785 -238.599661)
			(xy 153.826212 -238.591835) (xy 153.856182 -238.591344) (xy 154.719782 -238.591344) (xy 154.749749 -238.591908)
			(xy 154.809169 -238.599729) (xy 154.867061 -238.615239) (xy 154.922433 -238.638172) (xy 154.974337 -238.668138)
			(xy 155.021886 -238.704622) (xy 155.064267 -238.747) (xy 155.100752 -238.794548) (xy 155.13072 -238.846451)
			(xy 155.153656 -238.901822) (xy 155.169168 -238.959713) (xy 155.176991 -239.019133) (xy 155.176991 -239.079067)
			(xy 155.169168 -239.138487) (xy 155.153656 -239.196378) (xy 155.13072 -239.251749) (xy 155.100752 -239.303652)
			(xy 155.064267 -239.3512) (xy 155.021886 -239.393578) (xy 154.974337 -239.430062) (xy 154.922433 -239.460028)
			(xy 154.867061 -239.482961) (xy 154.809169 -239.498471) (xy 154.749749 -239.506292) (xy 154.719782 -239.50676)
			(xy 153.856182 -239.50676) (xy 153.826212 -239.506365) (xy 153.766785 -239.498539) (xy 153.708888 -239.483023)
			(xy 153.653511 -239.460084) (xy 153.601602 -239.430112) (xy 153.554049 -239.393622) (xy 153.511666 -239.351237)
			(xy 153.475178 -239.303683) (xy 153.445208 -239.251773) (xy 153.422271 -239.196395) (xy 153.406758 -239.138497)
			(xy 153.398934 -239.07907) (xy 4.308094 -239.07907) (xy 4.308094 -241.031522) (xy 4.307605 -241.10188)
			(xy 4.299704 -241.242374) (xy 4.283937 -241.382205) (xy 4.260354 -241.52093) (xy 4.229028 -241.658116)
			(xy 4.190059 -241.793328) (xy 4.143568 -241.926143) (xy 4.089703 -242.056141) (xy 4.028633 -242.182915)
			(xy 3.960549 -242.306064) (xy 3.885667 -242.425201) (xy 3.804222 -242.539952) (xy 3.71647 -242.649955)
			(xy 3.622687 -242.754863) (xy 3.573272 -242.80495) (xy 0.94488 -245.433342) (xy 0.907568 -245.471336)
			(xy 0.837834 -245.55183) (xy 0.774017 -245.637091) (xy 0.716442 -245.726686) (xy 0.665403 -245.820159)
			(xy 0.62116 -245.917033) (xy 0.583936 -246.016815) (xy 0.553923 -246.118998) (xy 0.531273 -246.223061)
			(xy 0.5161 -246.328474) (xy 0.508483 -246.4347) (xy 0.508 -246.48795) (xy 0.508 -270.89989) (xy 26.882353 -270.89989)
			(xy 26.886342 -270.75135) (xy 26.898299 -270.603237) (xy 26.918189 -270.45598) (xy 26.945954 -270.310004)
			(xy 26.981515 -270.165727) (xy 27.024769 -270.023568) (xy 27.075591 -269.883935) (xy 27.133835 -269.747232)
			(xy 27.199333 -269.613852) (xy 27.271896 -269.48418) (xy 27.351314 -269.35859) (xy 27.437359 -269.237443)
			(xy 27.529783 -269.12109) (xy 27.628319 -269.009866) (xy 27.732683 -268.904091) (xy 27.842575 -268.804071)
			(xy 27.957676 -268.710093) (xy 28.077656 -268.622429) (xy 28.202169 -268.541332) (xy 28.330855 -268.467035)
			(xy 28.463344 -268.399753) (xy 28.599253 -268.339679) (xy 28.738191 -268.286987) (xy 28.879757 -268.241828)
			(xy 29.023543 -268.204333) (xy 29.169134 -268.174611) (xy 29.31611 -268.152746) (xy 29.464049 -268.138802)
			(xy 29.612522 -268.132818) (xy 29.761103 -268.134813) (xy 29.909362 -268.144781) (xy 30.056873 -268.162692)
			(xy 30.203209 -268.188495) (xy 30.34795 -268.222115) (xy 30.490677 -268.263457) (xy 30.63098 -268.3124)
			(xy 30.768453 -268.368803) (xy 30.9027 -268.432504) (xy 31.033335 -268.50332) (xy 31.15998 -268.581045)
			(xy 31.28227 -268.665456) (xy 31.399853 -268.756309) (xy 31.51239 -268.853343) (xy 31.619557 -268.956278)
			(xy 31.721044 -269.064817) (xy 31.816558 -269.178646) (xy 31.905825 -269.297439) (xy 31.988586 -269.420851)
			(xy 32.064604 -269.548529) (xy 32.133659 -269.680102) (xy 32.195552 -269.815193) (xy 32.250105 -269.95341)
			(xy 32.29716 -270.094357) (xy 32.336582 -270.237627) (xy 32.368256 -270.382806) (xy 32.392092 -270.529475)
			(xy 32.408021 -270.677213) (xy 32.415997 -270.825593) (xy 32.416496 -270.89989) (xy 86.882487 -270.89989)
			(xy 86.886476 -270.75135) (xy 86.898433 -270.603237) (xy 86.918323 -270.45598) (xy 86.946088 -270.310004)
			(xy 86.981649 -270.165727) (xy 87.024903 -270.023568) (xy 87.075725 -269.883935) (xy 87.133969 -269.747232)
			(xy 87.199467 -269.613852) (xy 87.27203 -269.48418) (xy 87.351448 -269.35859) (xy 87.437493 -269.237443)
			(xy 87.529917 -269.12109) (xy 87.628453 -269.009866) (xy 87.732817 -268.904091) (xy 87.842709 -268.804071)
			(xy 87.95781 -268.710093) (xy 88.07779 -268.622429) (xy 88.202303 -268.541332) (xy 88.330989 -268.467035)
			(xy 88.463478 -268.399753) (xy 88.599387 -268.339679) (xy 88.738325 -268.286987) (xy 88.879891 -268.241828)
			(xy 89.023677 -268.204333) (xy 89.169268 -268.174611) (xy 89.316244 -268.152746) (xy 89.464183 -268.138802)
			(xy 89.612656 -268.132818) (xy 89.761237 -268.134813) (xy 89.909496 -268.144781) (xy 90.057007 -268.162692)
			(xy 90.203343 -268.188495) (xy 90.348084 -268.222115) (xy 90.490811 -268.263457) (xy 90.631114 -268.3124)
			(xy 90.768587 -268.368803) (xy 90.902834 -268.432504) (xy 91.033469 -268.50332) (xy 91.160114 -268.581045)
			(xy 91.282404 -268.665456) (xy 91.399987 -268.756309) (xy 91.512524 -268.853343) (xy 91.619691 -268.956278)
			(xy 91.721178 -269.064817) (xy 91.816692 -269.178646) (xy 91.905959 -269.297439) (xy 91.98872 -269.420851)
			(xy 92.064738 -269.548529) (xy 92.133793 -269.680102) (xy 92.195686 -269.815193) (xy 92.250239 -269.95341)
			(xy 92.297294 -270.094357) (xy 92.336716 -270.237627) (xy 92.36839 -270.382806) (xy 92.392226 -270.529475)
			(xy 92.408155 -270.677213) (xy 92.416131 -270.825593) (xy 92.41663 -270.89989) (xy 142.982451 -270.89989)
			(xy 142.98644 -270.75135) (xy 142.998397 -270.603237) (xy 143.018287 -270.45598) (xy 143.046052 -270.310004)
			(xy 143.081613 -270.165727) (xy 143.124867 -270.023568) (xy 143.175689 -269.883935) (xy 143.233933 -269.747232)
			(xy 143.299431 -269.613852) (xy 143.371994 -269.48418) (xy 143.451412 -269.35859) (xy 143.537457 -269.237443)
			(xy 143.629881 -269.12109) (xy 143.728417 -269.009866) (xy 143.832781 -268.904091) (xy 143.942673 -268.804071)
			(xy 144.057774 -268.710093) (xy 144.177754 -268.622429) (xy 144.302267 -268.541332) (xy 144.430953 -268.467035)
			(xy 144.563442 -268.399753) (xy 144.699351 -268.339679) (xy 144.838289 -268.286987) (xy 144.979855 -268.241828)
			(xy 145.123641 -268.204333) (xy 145.269232 -268.174611) (xy 145.416208 -268.152746) (xy 145.564147 -268.138802)
			(xy 145.71262 -268.132818) (xy 145.861201 -268.134813) (xy 146.00946 -268.144781) (xy 146.156971 -268.162692)
			(xy 146.303307 -268.188495) (xy 146.448048 -268.222115) (xy 146.590775 -268.263457) (xy 146.731078 -268.3124)
			(xy 146.868551 -268.368803) (xy 147.002798 -268.432504) (xy 147.133433 -268.50332) (xy 147.260078 -268.581045)
			(xy 147.382368 -268.665456) (xy 147.499951 -268.756309) (xy 147.612488 -268.853343) (xy 147.719655 -268.956278)
			(xy 147.821142 -269.064817) (xy 147.916656 -269.178646) (xy 148.005923 -269.297439) (xy 148.088684 -269.420851)
			(xy 148.164702 -269.548529) (xy 148.233757 -269.680102) (xy 148.29565 -269.815193) (xy 148.350203 -269.95341)
			(xy 148.397258 -270.094357) (xy 148.43668 -270.237627) (xy 148.468354 -270.382806) (xy 148.49219 -270.529475)
			(xy 148.508119 -270.677213) (xy 148.516095 -270.825593) (xy 148.516594 -270.89989) (xy 202.982331 -270.89989)
			(xy 202.98632 -270.75135) (xy 202.998277 -270.603237) (xy 203.018167 -270.45598) (xy 203.045932 -270.310004)
			(xy 203.081493 -270.165727) (xy 203.124747 -270.023568) (xy 203.175569 -269.883935) (xy 203.233813 -269.747232)
			(xy 203.299311 -269.613852) (xy 203.371874 -269.48418) (xy 203.451292 -269.35859) (xy 203.537337 -269.237443)
			(xy 203.629761 -269.12109) (xy 203.728297 -269.009866) (xy 203.832661 -268.904091) (xy 203.942553 -268.804071)
			(xy 204.057654 -268.710093) (xy 204.177634 -268.622429) (xy 204.302147 -268.541332) (xy 204.430833 -268.467035)
			(xy 204.563322 -268.399753) (xy 204.699231 -268.339679) (xy 204.838169 -268.286987) (xy 204.979735 -268.241828)
			(xy 205.123521 -268.204333) (xy 205.269112 -268.174611) (xy 205.416088 -268.152746) (xy 205.564027 -268.138802)
			(xy 205.7125 -268.132818) (xy 205.861081 -268.134813) (xy 206.00934 -268.144781) (xy 206.156851 -268.162692)
			(xy 206.303187 -268.188495) (xy 206.447928 -268.222115) (xy 206.590655 -268.263457) (xy 206.730958 -268.3124)
			(xy 206.868431 -268.368803) (xy 207.002678 -268.432504) (xy 207.133313 -268.50332) (xy 207.259958 -268.581045)
			(xy 207.382248 -268.665456) (xy 207.499831 -268.756309) (xy 207.612368 -268.853343) (xy 207.719535 -268.956278)
			(xy 207.821022 -269.064817) (xy 207.916536 -269.178646) (xy 208.005803 -269.297439) (xy 208.088564 -269.420851)
			(xy 208.164582 -269.548529) (xy 208.233637 -269.680102) (xy 208.29553 -269.815193) (xy 208.350083 -269.95341)
			(xy 208.397138 -270.094357) (xy 208.43656 -270.237627) (xy 208.468234 -270.382806) (xy 208.49207 -270.529475)
			(xy 208.507999 -270.677213) (xy 208.515975 -270.825593) (xy 208.516474 -270.89989) (xy 259.082549 -270.89989)
			(xy 259.086538 -270.75135) (xy 259.098495 -270.603237) (xy 259.118385 -270.45598) (xy 259.14615 -270.310004)
			(xy 259.181711 -270.165727) (xy 259.224965 -270.023568) (xy 259.275787 -269.883935) (xy 259.334031 -269.747232)
			(xy 259.399529 -269.613852) (xy 259.472092 -269.48418) (xy 259.55151 -269.35859) (xy 259.637555 -269.237443)
			(xy 259.729979 -269.12109) (xy 259.828515 -269.009866) (xy 259.932879 -268.904091) (xy 260.042771 -268.804071)
			(xy 260.157872 -268.710093) (xy 260.277852 -268.622429) (xy 260.402365 -268.541332) (xy 260.531051 -268.467035)
			(xy 260.66354 -268.399753) (xy 260.799449 -268.339679) (xy 260.938387 -268.286987) (xy 261.079953 -268.241828)
			(xy 261.223739 -268.204333) (xy 261.36933 -268.174611) (xy 261.516306 -268.152746) (xy 261.664245 -268.138802)
			(xy 261.812718 -268.132818) (xy 261.961299 -268.134813) (xy 262.109558 -268.144781) (xy 262.257069 -268.162692)
			(xy 262.403405 -268.188495) (xy 262.548146 -268.222115) (xy 262.690873 -268.263457) (xy 262.831176 -268.3124)
			(xy 262.968649 -268.368803) (xy 263.102896 -268.432504) (xy 263.233531 -268.50332) (xy 263.360176 -268.581045)
			(xy 263.482466 -268.665456) (xy 263.600049 -268.756309) (xy 263.712586 -268.853343) (xy 263.819753 -268.956278)
			(xy 263.92124 -269.064817) (xy 264.016754 -269.178646) (xy 264.106021 -269.297439) (xy 264.188782 -269.420851)
			(xy 264.2648 -269.548529) (xy 264.333855 -269.680102) (xy 264.395748 -269.815193) (xy 264.450301 -269.95341)
			(xy 264.497356 -270.094357) (xy 264.536778 -270.237627) (xy 264.568452 -270.382806) (xy 264.592288 -270.529475)
			(xy 264.608217 -270.677213) (xy 264.616193 -270.825593) (xy 264.616692 -270.89989) (xy 319.082429 -270.89989)
			(xy 319.086418 -270.75135) (xy 319.098375 -270.603237) (xy 319.118265 -270.45598) (xy 319.14603 -270.310004)
			(xy 319.181591 -270.165727) (xy 319.224845 -270.023568) (xy 319.275667 -269.883935) (xy 319.333911 -269.747232)
			(xy 319.399409 -269.613852) (xy 319.471972 -269.48418) (xy 319.55139 -269.35859) (xy 319.637435 -269.237443)
			(xy 319.729859 -269.12109) (xy 319.828395 -269.009866) (xy 319.932759 -268.904091) (xy 320.042651 -268.804071)
			(xy 320.157752 -268.710093) (xy 320.277732 -268.622429) (xy 320.402245 -268.541332) (xy 320.530931 -268.467035)
			(xy 320.66342 -268.399753) (xy 320.799329 -268.339679) (xy 320.938267 -268.286987) (xy 321.079833 -268.241828)
			(xy 321.223619 -268.204333) (xy 321.36921 -268.174611) (xy 321.516186 -268.152746) (xy 321.664125 -268.138802)
			(xy 321.812598 -268.132818) (xy 321.961179 -268.134813) (xy 322.109438 -268.144781) (xy 322.256949 -268.162692)
			(xy 322.403285 -268.188495) (xy 322.548026 -268.222115) (xy 322.690753 -268.263457) (xy 322.831056 -268.3124)
			(xy 322.968529 -268.368803) (xy 323.102776 -268.432504) (xy 323.233411 -268.50332) (xy 323.360056 -268.581045)
			(xy 323.482346 -268.665456) (xy 323.599929 -268.756309) (xy 323.712466 -268.853343) (xy 323.819633 -268.956278)
			(xy 323.92112 -269.064817) (xy 324.016634 -269.178646) (xy 324.105901 -269.297439) (xy 324.188662 -269.420851)
			(xy 324.26468 -269.548529) (xy 324.333735 -269.680102) (xy 324.395628 -269.815193) (xy 324.450181 -269.95341)
			(xy 324.497236 -270.094357) (xy 324.536658 -270.237627) (xy 324.568332 -270.382806) (xy 324.592168 -270.529475)
			(xy 324.608097 -270.677213) (xy 324.616073 -270.825593) (xy 324.616572 -270.89989) (xy 375.182393 -270.89989)
			(xy 375.186382 -270.75135) (xy 375.198339 -270.603237) (xy 375.218229 -270.45598) (xy 375.245994 -270.310004)
			(xy 375.281555 -270.165727) (xy 375.324809 -270.023568) (xy 375.375631 -269.883935) (xy 375.433875 -269.747232)
			(xy 375.499373 -269.613852) (xy 375.571936 -269.48418) (xy 375.651354 -269.35859) (xy 375.737399 -269.237443)
			(xy 375.829823 -269.12109) (xy 375.928359 -269.009866) (xy 376.032723 -268.904091) (xy 376.142615 -268.804071)
			(xy 376.257716 -268.710093) (xy 376.377696 -268.622429) (xy 376.502209 -268.541332) (xy 376.630895 -268.467035)
			(xy 376.763384 -268.399753) (xy 376.899293 -268.339679) (xy 377.038231 -268.286987) (xy 377.179797 -268.241828)
			(xy 377.323583 -268.204333) (xy 377.469174 -268.174611) (xy 377.61615 -268.152746) (xy 377.764089 -268.138802)
			(xy 377.912562 -268.132818) (xy 378.061143 -268.134813) (xy 378.209402 -268.144781) (xy 378.356913 -268.162692)
			(xy 378.503249 -268.188495) (xy 378.64799 -268.222115) (xy 378.790717 -268.263457) (xy 378.93102 -268.3124)
			(xy 379.068493 -268.368803) (xy 379.20274 -268.432504) (xy 379.333375 -268.50332) (xy 379.46002 -268.581045)
			(xy 379.58231 -268.665456) (xy 379.699893 -268.756309) (xy 379.81243 -268.853343) (xy 379.919597 -268.956278)
			(xy 380.021084 -269.064817) (xy 380.116598 -269.178646) (xy 380.205865 -269.297439) (xy 380.288626 -269.420851)
			(xy 380.364644 -269.548529) (xy 380.433699 -269.680102) (xy 380.495592 -269.815193) (xy 380.550145 -269.95341)
			(xy 380.5972 -270.094357) (xy 380.636622 -270.237627) (xy 380.668296 -270.382806) (xy 380.692132 -270.529475)
			(xy 380.708061 -270.677213) (xy 380.716037 -270.825593) (xy 380.716536 -270.89989) (xy 435.182527 -270.89989)
			(xy 435.186516 -270.75135) (xy 435.198473 -270.603237) (xy 435.218363 -270.45598) (xy 435.246128 -270.310004)
			(xy 435.281689 -270.165727) (xy 435.324943 -270.023568) (xy 435.375765 -269.883935) (xy 435.434009 -269.747232)
			(xy 435.499507 -269.613852) (xy 435.57207 -269.48418) (xy 435.651488 -269.35859) (xy 435.737533 -269.237443)
			(xy 435.829957 -269.12109) (xy 435.928493 -269.009866) (xy 436.032857 -268.904091) (xy 436.142749 -268.804071)
			(xy 436.25785 -268.710093) (xy 436.37783 -268.622429) (xy 436.502343 -268.541332) (xy 436.631029 -268.467035)
			(xy 436.763518 -268.399753) (xy 436.899427 -268.339679) (xy 437.038365 -268.286987) (xy 437.179931 -268.241828)
			(xy 437.323717 -268.204333) (xy 437.469308 -268.174611) (xy 437.616284 -268.152746) (xy 437.764223 -268.138802)
			(xy 437.912696 -268.132818) (xy 438.061277 -268.134813) (xy 438.209536 -268.144781) (xy 438.357047 -268.162692)
			(xy 438.503383 -268.188495) (xy 438.648124 -268.222115) (xy 438.790851 -268.263457) (xy 438.931154 -268.3124)
			(xy 439.068627 -268.368803) (xy 439.202874 -268.432504) (xy 439.333509 -268.50332) (xy 439.460154 -268.581045)
			(xy 439.582444 -268.665456) (xy 439.700027 -268.756309) (xy 439.812564 -268.853343) (xy 439.919731 -268.956278)
			(xy 440.021218 -269.064817) (xy 440.116732 -269.178646) (xy 440.205999 -269.297439) (xy 440.28876 -269.420851)
			(xy 440.364778 -269.548529) (xy 440.433833 -269.680102) (xy 440.495726 -269.815193) (xy 440.550279 -269.95341)
			(xy 440.597334 -270.094357) (xy 440.636756 -270.237627) (xy 440.66843 -270.382806) (xy 440.692266 -270.529475)
			(xy 440.708195 -270.677213) (xy 440.716171 -270.825593) (xy 440.71667 -270.89989) (xy 440.716171 -270.974187)
			(xy 440.708195 -271.122567) (xy 440.692266 -271.270305) (xy 440.66843 -271.416974) (xy 440.636756 -271.562153)
			(xy 440.597334 -271.705423) (xy 440.550279 -271.84637) (xy 440.495726 -271.984587) (xy 440.433833 -272.119678)
			(xy 440.364778 -272.251251) (xy 440.28876 -272.378929) (xy 440.205999 -272.502341) (xy 440.116732 -272.621134)
			(xy 440.021218 -272.734963) (xy 439.919731 -272.843502) (xy 439.812564 -272.946437) (xy 439.700027 -273.043471)
			(xy 439.582444 -273.134324) (xy 439.460154 -273.218735) (xy 439.333509 -273.29646) (xy 439.202874 -273.367276)
			(xy 439.068627 -273.430977) (xy 438.931154 -273.48738) (xy 438.790851 -273.536323) (xy 438.648124 -273.577665)
			(xy 438.503383 -273.611285) (xy 438.357047 -273.637088) (xy 438.209536 -273.654999) (xy 438.061277 -273.664967)
			(xy 437.912696 -273.666962) (xy 437.764223 -273.660978) (xy 437.616284 -273.647034) (xy 437.469308 -273.625169)
			(xy 437.323717 -273.595447) (xy 437.179931 -273.557952) (xy 437.038365 -273.512793) (xy 436.899427 -273.460101)
			(xy 436.763518 -273.400027) (xy 436.631029 -273.332745) (xy 436.502343 -273.258448) (xy 436.37783 -273.177351)
			(xy 436.25785 -273.089687) (xy 436.142749 -272.995709) (xy 436.032857 -272.895689) (xy 435.928493 -272.789914)
			(xy 435.829957 -272.67869) (xy 435.737533 -272.562337) (xy 435.651488 -272.44119) (xy 435.57207 -272.3156)
			(xy 435.499507 -272.185928) (xy 435.434009 -272.052548) (xy 435.375765 -271.915845) (xy 435.324943 -271.776212)
			(xy 435.281689 -271.634053) (xy 435.246128 -271.489776) (xy 435.218363 -271.3438) (xy 435.198473 -271.196543)
			(xy 435.186516 -271.04843) (xy 435.182527 -270.89989) (xy 380.716536 -270.89989) (xy 380.716037 -270.974187)
			(xy 380.708061 -271.122567) (xy 380.692132 -271.270305) (xy 380.668296 -271.416974) (xy 380.636622 -271.562153)
			(xy 380.5972 -271.705423) (xy 380.550145 -271.84637) (xy 380.495592 -271.984587) (xy 380.433699 -272.119678)
			(xy 380.364644 -272.251251) (xy 380.288626 -272.378929) (xy 380.205865 -272.502341) (xy 380.116598 -272.621134)
			(xy 380.021084 -272.734963) (xy 379.919597 -272.843502) (xy 379.81243 -272.946437) (xy 379.699893 -273.043471)
			(xy 379.58231 -273.134324) (xy 379.46002 -273.218735) (xy 379.333375 -273.29646) (xy 379.20274 -273.367276)
			(xy 379.068493 -273.430977) (xy 378.93102 -273.48738) (xy 378.790717 -273.536323) (xy 378.64799 -273.577665)
			(xy 378.503249 -273.611285) (xy 378.356913 -273.637088) (xy 378.209402 -273.654999) (xy 378.061143 -273.664967)
			(xy 377.912562 -273.666962) (xy 377.764089 -273.660978) (xy 377.61615 -273.647034) (xy 377.469174 -273.625169)
			(xy 377.323583 -273.595447) (xy 377.179797 -273.557952) (xy 377.038231 -273.512793) (xy 376.899293 -273.460101)
			(xy 376.763384 -273.400027) (xy 376.630895 -273.332745) (xy 376.502209 -273.258448) (xy 376.377696 -273.177351)
			(xy 376.257716 -273.089687) (xy 376.142615 -272.995709) (xy 376.032723 -272.895689) (xy 375.928359 -272.789914)
			(xy 375.829823 -272.67869) (xy 375.737399 -272.562337) (xy 375.651354 -272.44119) (xy 375.571936 -272.3156)
			(xy 375.499373 -272.185928) (xy 375.433875 -272.052548) (xy 375.375631 -271.915845) (xy 375.324809 -271.776212)
			(xy 375.281555 -271.634053) (xy 375.245994 -271.489776) (xy 375.218229 -271.3438) (xy 375.198339 -271.196543)
			(xy 375.186382 -271.04843) (xy 375.182393 -270.89989) (xy 324.616572 -270.89989) (xy 324.616073 -270.974187)
			(xy 324.608097 -271.122567) (xy 324.592168 -271.270305) (xy 324.568332 -271.416974) (xy 324.536658 -271.562153)
			(xy 324.497236 -271.705423) (xy 324.450181 -271.84637) (xy 324.395628 -271.984587) (xy 324.333735 -272.119678)
			(xy 324.26468 -272.251251) (xy 324.188662 -272.378929) (xy 324.105901 -272.502341) (xy 324.016634 -272.621134)
			(xy 323.92112 -272.734963) (xy 323.819633 -272.843502) (xy 323.712466 -272.946437) (xy 323.599929 -273.043471)
			(xy 323.482346 -273.134324) (xy 323.360056 -273.218735) (xy 323.233411 -273.29646) (xy 323.102776 -273.367276)
			(xy 322.968529 -273.430977) (xy 322.831056 -273.48738) (xy 322.690753 -273.536323) (xy 322.548026 -273.577665)
			(xy 322.403285 -273.611285) (xy 322.256949 -273.637088) (xy 322.109438 -273.654999) (xy 321.961179 -273.664967)
			(xy 321.812598 -273.666962) (xy 321.664125 -273.660978) (xy 321.516186 -273.647034) (xy 321.36921 -273.625169)
			(xy 321.223619 -273.595447) (xy 321.079833 -273.557952) (xy 320.938267 -273.512793) (xy 320.799329 -273.460101)
			(xy 320.66342 -273.400027) (xy 320.530931 -273.332745) (xy 320.402245 -273.258448) (xy 320.277732 -273.177351)
			(xy 320.157752 -273.089687) (xy 320.042651 -272.995709) (xy 319.932759 -272.895689) (xy 319.828395 -272.789914)
			(xy 319.729859 -272.67869) (xy 319.637435 -272.562337) (xy 319.55139 -272.44119) (xy 319.471972 -272.3156)
			(xy 319.399409 -272.185928) (xy 319.333911 -272.052548) (xy 319.275667 -271.915845) (xy 319.224845 -271.776212)
			(xy 319.181591 -271.634053) (xy 319.14603 -271.489776) (xy 319.118265 -271.3438) (xy 319.098375 -271.196543)
			(xy 319.086418 -271.04843) (xy 319.082429 -270.89989) (xy 264.616692 -270.89989) (xy 264.616193 -270.974187)
			(xy 264.608217 -271.122567) (xy 264.592288 -271.270305) (xy 264.568452 -271.416974) (xy 264.536778 -271.562153)
			(xy 264.497356 -271.705423) (xy 264.450301 -271.84637) (xy 264.395748 -271.984587) (xy 264.333855 -272.119678)
			(xy 264.2648 -272.251251) (xy 264.188782 -272.378929) (xy 264.106021 -272.502341) (xy 264.016754 -272.621134)
			(xy 263.92124 -272.734963) (xy 263.819753 -272.843502) (xy 263.712586 -272.946437) (xy 263.600049 -273.043471)
			(xy 263.482466 -273.134324) (xy 263.360176 -273.218735) (xy 263.233531 -273.29646) (xy 263.102896 -273.367276)
			(xy 262.968649 -273.430977) (xy 262.831176 -273.48738) (xy 262.690873 -273.536323) (xy 262.548146 -273.577665)
			(xy 262.403405 -273.611285) (xy 262.257069 -273.637088) (xy 262.109558 -273.654999) (xy 261.961299 -273.664967)
			(xy 261.812718 -273.666962) (xy 261.664245 -273.660978) (xy 261.516306 -273.647034) (xy 261.36933 -273.625169)
			(xy 261.223739 -273.595447) (xy 261.079953 -273.557952) (xy 260.938387 -273.512793) (xy 260.799449 -273.460101)
			(xy 260.66354 -273.400027) (xy 260.531051 -273.332745) (xy 260.402365 -273.258448) (xy 260.277852 -273.177351)
			(xy 260.157872 -273.089687) (xy 260.042771 -272.995709) (xy 259.932879 -272.895689) (xy 259.828515 -272.789914)
			(xy 259.729979 -272.67869) (xy 259.637555 -272.562337) (xy 259.55151 -272.44119) (xy 259.472092 -272.3156)
			(xy 259.399529 -272.185928) (xy 259.334031 -272.052548) (xy 259.275787 -271.915845) (xy 259.224965 -271.776212)
			(xy 259.181711 -271.634053) (xy 259.14615 -271.489776) (xy 259.118385 -271.3438) (xy 259.098495 -271.196543)
			(xy 259.086538 -271.04843) (xy 259.082549 -270.89989) (xy 208.516474 -270.89989) (xy 208.515975 -270.974187)
			(xy 208.507999 -271.122567) (xy 208.49207 -271.270305) (xy 208.468234 -271.416974) (xy 208.43656 -271.562153)
			(xy 208.397138 -271.705423) (xy 208.350083 -271.84637) (xy 208.29553 -271.984587) (xy 208.233637 -272.119678)
			(xy 208.164582 -272.251251) (xy 208.088564 -272.378929) (xy 208.005803 -272.502341) (xy 207.916536 -272.621134)
			(xy 207.821022 -272.734963) (xy 207.719535 -272.843502) (xy 207.612368 -272.946437) (xy 207.499831 -273.043471)
			(xy 207.382248 -273.134324) (xy 207.259958 -273.218735) (xy 207.133313 -273.29646) (xy 207.002678 -273.367276)
			(xy 206.868431 -273.430977) (xy 206.730958 -273.48738) (xy 206.590655 -273.536323) (xy 206.447928 -273.577665)
			(xy 206.303187 -273.611285) (xy 206.156851 -273.637088) (xy 206.00934 -273.654999) (xy 205.861081 -273.664967)
			(xy 205.7125 -273.666962) (xy 205.564027 -273.660978) (xy 205.416088 -273.647034) (xy 205.269112 -273.625169)
			(xy 205.123521 -273.595447) (xy 204.979735 -273.557952) (xy 204.838169 -273.512793) (xy 204.699231 -273.460101)
			(xy 204.563322 -273.400027) (xy 204.430833 -273.332745) (xy 204.302147 -273.258448) (xy 204.177634 -273.177351)
			(xy 204.057654 -273.089687) (xy 203.942553 -272.995709) (xy 203.832661 -272.895689) (xy 203.728297 -272.789914)
			(xy 203.629761 -272.67869) (xy 203.537337 -272.562337) (xy 203.451292 -272.44119) (xy 203.371874 -272.3156)
			(xy 203.299311 -272.185928) (xy 203.233813 -272.052548) (xy 203.175569 -271.915845) (xy 203.124747 -271.776212)
			(xy 203.081493 -271.634053) (xy 203.045932 -271.489776) (xy 203.018167 -271.3438) (xy 202.998277 -271.196543)
			(xy 202.98632 -271.04843) (xy 202.982331 -270.89989) (xy 148.516594 -270.89989) (xy 148.516095 -270.974187)
			(xy 148.508119 -271.122567) (xy 148.49219 -271.270305) (xy 148.468354 -271.416974) (xy 148.43668 -271.562153)
			(xy 148.397258 -271.705423) (xy 148.350203 -271.84637) (xy 148.29565 -271.984587) (xy 148.233757 -272.119678)
			(xy 148.164702 -272.251251) (xy 148.088684 -272.378929) (xy 148.005923 -272.502341) (xy 147.916656 -272.621134)
			(xy 147.821142 -272.734963) (xy 147.719655 -272.843502) (xy 147.612488 -272.946437) (xy 147.499951 -273.043471)
			(xy 147.382368 -273.134324) (xy 147.260078 -273.218735) (xy 147.133433 -273.29646) (xy 147.002798 -273.367276)
			(xy 146.868551 -273.430977) (xy 146.731078 -273.48738) (xy 146.590775 -273.536323) (xy 146.448048 -273.577665)
			(xy 146.303307 -273.611285) (xy 146.156971 -273.637088) (xy 146.00946 -273.654999) (xy 145.861201 -273.664967)
			(xy 145.71262 -273.666962) (xy 145.564147 -273.660978) (xy 145.416208 -273.647034) (xy 145.269232 -273.625169)
			(xy 145.123641 -273.595447) (xy 144.979855 -273.557952) (xy 144.838289 -273.512793) (xy 144.699351 -273.460101)
			(xy 144.563442 -273.400027) (xy 144.430953 -273.332745) (xy 144.302267 -273.258448) (xy 144.177754 -273.177351)
			(xy 144.057774 -273.089687) (xy 143.942673 -272.995709) (xy 143.832781 -272.895689) (xy 143.728417 -272.789914)
			(xy 143.629881 -272.67869) (xy 143.537457 -272.562337) (xy 143.451412 -272.44119) (xy 143.371994 -272.3156)
			(xy 143.299431 -272.185928) (xy 143.233933 -272.052548) (xy 143.175689 -271.915845) (xy 143.124867 -271.776212)
			(xy 143.081613 -271.634053) (xy 143.046052 -271.489776) (xy 143.018287 -271.3438) (xy 142.998397 -271.196543)
			(xy 142.98644 -271.04843) (xy 142.982451 -270.89989) (xy 92.41663 -270.89989) (xy 92.416131 -270.974187)
			(xy 92.408155 -271.122567) (xy 92.392226 -271.270305) (xy 92.36839 -271.416974) (xy 92.336716 -271.562153)
			(xy 92.297294 -271.705423) (xy 92.250239 -271.84637) (xy 92.195686 -271.984587) (xy 92.133793 -272.119678)
			(xy 92.064738 -272.251251) (xy 91.98872 -272.378929) (xy 91.905959 -272.502341) (xy 91.816692 -272.621134)
			(xy 91.721178 -272.734963) (xy 91.619691 -272.843502) (xy 91.512524 -272.946437) (xy 91.399987 -273.043471)
			(xy 91.282404 -273.134324) (xy 91.160114 -273.218735) (xy 91.033469 -273.29646) (xy 90.902834 -273.367276)
			(xy 90.768587 -273.430977) (xy 90.631114 -273.48738) (xy 90.490811 -273.536323) (xy 90.348084 -273.577665)
			(xy 90.203343 -273.611285) (xy 90.057007 -273.637088) (xy 89.909496 -273.654999) (xy 89.761237 -273.664967)
			(xy 89.612656 -273.666962) (xy 89.464183 -273.660978) (xy 89.316244 -273.647034) (xy 89.169268 -273.625169)
			(xy 89.023677 -273.595447) (xy 88.879891 -273.557952) (xy 88.738325 -273.512793) (xy 88.599387 -273.460101)
			(xy 88.463478 -273.400027) (xy 88.330989 -273.332745) (xy 88.202303 -273.258448) (xy 88.07779 -273.177351)
			(xy 87.95781 -273.089687) (xy 87.842709 -272.995709) (xy 87.732817 -272.895689) (xy 87.628453 -272.789914)
			(xy 87.529917 -272.67869) (xy 87.437493 -272.562337) (xy 87.351448 -272.44119) (xy 87.27203 -272.3156)
			(xy 87.199467 -272.185928) (xy 87.133969 -272.052548) (xy 87.075725 -271.915845) (xy 87.024903 -271.776212)
			(xy 86.981649 -271.634053) (xy 86.946088 -271.489776) (xy 86.918323 -271.3438) (xy 86.898433 -271.196543)
			(xy 86.886476 -271.04843) (xy 86.882487 -270.89989) (xy 32.416496 -270.89989) (xy 32.415997 -270.974187)
			(xy 32.408021 -271.122567) (xy 32.392092 -271.270305) (xy 32.368256 -271.416974) (xy 32.336582 -271.562153)
			(xy 32.29716 -271.705423) (xy 32.250105 -271.84637) (xy 32.195552 -271.984587) (xy 32.133659 -272.119678)
			(xy 32.064604 -272.251251) (xy 31.988586 -272.378929) (xy 31.905825 -272.502341) (xy 31.816558 -272.621134)
			(xy 31.721044 -272.734963) (xy 31.619557 -272.843502) (xy 31.51239 -272.946437) (xy 31.399853 -273.043471)
			(xy 31.28227 -273.134324) (xy 31.15998 -273.218735) (xy 31.033335 -273.29646) (xy 30.9027 -273.367276)
			(xy 30.768453 -273.430977) (xy 30.63098 -273.48738) (xy 30.490677 -273.536323) (xy 30.34795 -273.577665)
			(xy 30.203209 -273.611285) (xy 30.056873 -273.637088) (xy 29.909362 -273.654999) (xy 29.761103 -273.664967)
			(xy 29.612522 -273.666962) (xy 29.464049 -273.660978) (xy 29.31611 -273.647034) (xy 29.169134 -273.625169)
			(xy 29.023543 -273.595447) (xy 28.879757 -273.557952) (xy 28.738191 -273.512793) (xy 28.599253 -273.460101)
			(xy 28.463344 -273.400027) (xy 28.330855 -273.332745) (xy 28.202169 -273.258448) (xy 28.077656 -273.177351)
			(xy 27.957676 -273.089687) (xy 27.842575 -272.995709) (xy 27.732683 -272.895689) (xy 27.628319 -272.789914)
			(xy 27.529783 -272.67869) (xy 27.437359 -272.562337) (xy 27.351314 -272.44119) (xy 27.271896 -272.3156)
			(xy 27.199333 -272.185928) (xy 27.133835 -272.052548) (xy 27.075591 -271.915845) (xy 27.024769 -271.776212)
			(xy 26.981515 -271.634053) (xy 26.945954 -271.489776) (xy 26.918189 -271.3438) (xy 26.898299 -271.196543)
			(xy 26.886342 -271.04843) (xy 26.882353 -270.89989) (xy 0.508 -270.89989) (xy 0.508 -287.850408)
			(xy 37.944539 -287.850408) (xy 37.944539 -287.798392) (xy 37.952677 -287.747016) (xy 37.968751 -287.697546)
			(xy 37.992366 -287.651199) (xy 38.02294 -287.609117) (xy 38.059722 -287.572337) (xy 38.101804 -287.541763)
			(xy 38.148151 -287.518148) (xy 38.197622 -287.502075) (xy 38.248998 -287.493939) (xy 38.275006 -287.493456)
			(xy 39.224966 -287.493456) (xy 39.250978 -287.493901) (xy 39.302363 -287.502035) (xy 39.351843 -287.518107)
			(xy 39.398199 -287.541722) (xy 39.44029 -287.572299) (xy 39.477079 -287.609084) (xy 39.50766 -287.651172)
			(xy 39.53128 -287.697525) (xy 39.547357 -287.747004) (xy 39.555496 -287.798388) (xy 39.555496 -287.850405)
			(xy 40.794466 -287.850405) (xy 40.794466 -287.798395) (xy 40.802602 -287.747025) (xy 40.818674 -287.697561)
			(xy 40.842285 -287.651219) (xy 40.872855 -287.609142) (xy 40.909631 -287.572364) (xy 40.951707 -287.541792)
			(xy 40.998048 -287.518179) (xy 41.047512 -287.502105) (xy 41.098881 -287.493967) (xy 41.124886 -287.493456)
			(xy 42.074846 -287.493456) (xy 42.100852 -287.493934) (xy 42.152223 -287.502077) (xy 42.201688 -287.518155)
			(xy 42.248029 -287.541773) (xy 42.290106 -287.572348) (xy 42.326882 -287.609129) (xy 42.357451 -287.65121)
			(xy 42.381063 -287.697554) (xy 42.397134 -287.747022) (xy 42.40527 -287.798394) (xy 42.40527 -287.850406)
			(xy 42.397134 -287.901778) (xy 42.381063 -287.951246) (xy 42.357451 -287.99759) (xy 42.326882 -288.039671)
			(xy 42.290106 -288.076452) (xy 42.248029 -288.107027) (xy 42.201688 -288.130645) (xy 42.152223 -288.146723)
			(xy 42.100852 -288.154866) (xy 42.074846 -288.15538) (xy 41.124886 -288.15538) (xy 41.098881 -288.154833)
			(xy 41.047512 -288.146695) (xy 40.998048 -288.130621) (xy 40.951707 -288.107008) (xy 40.909631 -288.076436)
			(xy 40.872855 -288.039658) (xy 40.842285 -287.997581) (xy 40.818674 -287.951239) (xy 40.802602 -287.901775)
			(xy 40.794466 -287.850405) (xy 39.555496 -287.850405) (xy 39.555496 -287.850412) (xy 39.547357 -287.901796)
			(xy 39.53128 -287.951275) (xy 39.50766 -287.997628) (xy 39.477079 -288.039716) (xy 39.44029 -288.076501)
			(xy 39.398199 -288.107078) (xy 39.351843 -288.130693) (xy 39.302363 -288.146765) (xy 39.250978 -288.154899)
			(xy 39.224966 -288.15538) (xy 38.275006 -288.15538) (xy 38.248998 -288.154861) (xy 38.197622 -288.146725)
			(xy 38.148151 -288.130652) (xy 38.101804 -288.107037) (xy 38.059722 -288.076463) (xy 38.02294 -288.039683)
			(xy 37.992366 -287.997601) (xy 37.968751 -287.951254) (xy 37.952677 -287.901784) (xy 37.944539 -287.850408)
			(xy 0.508 -287.850408) (xy 0.508 -288.800413) (xy 36.0443 -288.800413) (xy 36.0443 -288.748387) (xy 36.052439 -288.697003)
			(xy 36.068516 -288.647524) (xy 36.092136 -288.60117) (xy 36.122718 -288.559082) (xy 36.159507 -288.522297)
			(xy 36.201598 -288.49172) (xy 36.247954 -288.468104) (xy 36.297434 -288.452031) (xy 36.348819 -288.443897)
			(xy 36.374832 -288.443416) (xy 37.324792 -288.443416) (xy 37.3508 -288.443943) (xy 37.402175 -288.452079)
			(xy 37.451646 -288.468151) (xy 37.497993 -288.491765) (xy 37.540075 -288.522339) (xy 37.576856 -288.559119)
			(xy 37.60743 -288.601201) (xy 37.631045 -288.647547) (xy 37.647119 -288.697017) (xy 37.655257 -288.748392)
			(xy 37.655257 -288.800408) (xy 37.655257 -288.800411) (xy 42.694299 -288.800411) (xy 42.694299 -288.748389)
			(xy 42.702438 -288.697007) (xy 42.718514 -288.64753) (xy 42.742132 -288.601178) (xy 42.77271 -288.559091)
			(xy 42.809496 -288.522306) (xy 42.851583 -288.491729) (xy 42.897936 -288.468111) (xy 42.947413 -288.452036)
			(xy 42.998795 -288.443899) (xy 43.024806 -288.443416) (xy 43.974766 -288.443416) (xy 44.000775 -288.443941)
			(xy 44.052154 -288.452074) (xy 44.101628 -288.468144) (xy 44.147978 -288.491757) (xy 44.190064 -288.52233)
			(xy 44.226848 -288.55911) (xy 44.257426 -288.601193) (xy 44.281043 -288.647541) (xy 44.297119 -288.697013)
			(xy 44.305257 -288.748391) (xy 44.305257 -288.800409) (xy 44.297119 -288.851787) (xy 44.281043 -288.901259)
			(xy 44.257426 -288.947607) (xy 44.226848 -288.98969) (xy 44.190064 -289.02647) (xy 44.147978 -289.057043)
			(xy 44.101628 -289.080656) (xy 44.052154 -289.096726) (xy 44.000775 -289.104859) (xy 43.974766 -289.10534)
			(xy 43.024806 -289.10534) (xy 42.998795 -289.104901) (xy 42.947413 -289.096764) (xy 42.897936 -289.080689)
			(xy 42.851583 -289.057071) (xy 42.809496 -289.026494) (xy 42.77271 -288.989709) (xy 42.742132 -288.947622)
			(xy 42.718514 -288.90127) (xy 42.702438 -288.851793) (xy 42.694299 -288.800411) (xy 37.655257 -288.800411)
			(xy 37.647119 -288.851783) (xy 37.631045 -288.901253) (xy 37.60743 -288.947599) (xy 37.576856 -288.989681)
			(xy 37.540075 -289.026461) (xy 37.497993 -289.057035) (xy 37.451646 -289.080649) (xy 37.402175 -289.096721)
			(xy 37.3508 -289.104857) (xy 37.324792 -289.10534) (xy 36.374832 -289.10534) (xy 36.348819 -289.104903)
			(xy 36.297434 -289.096769) (xy 36.247954 -289.080696) (xy 36.201598 -289.05708) (xy 36.159507 -289.026503)
			(xy 36.122718 -288.989718) (xy 36.092136 -288.94763) (xy 36.068516 -288.901276) (xy 36.052439 -288.851797)
			(xy 36.0443 -288.800413) (xy 0.508 -288.800413) (xy 0.508 -297.350788) (xy 36.044382 -297.350788)
			(xy 36.044382 -297.298812) (xy 36.052512 -297.247477) (xy 36.068572 -297.198045) (xy 36.092168 -297.151734)
			(xy 36.122717 -297.109685) (xy 36.159468 -297.072931) (xy 36.201516 -297.042379) (xy 36.247825 -297.018781)
			(xy 36.297255 -297.002717) (xy 36.34859 -296.994583) (xy 36.374578 -296.994072) (xy 37.324538 -296.994072)
			(xy 37.350522 -296.994624) (xy 37.401848 -297.002759) (xy 37.451271 -297.018822) (xy 37.497572 -297.042419)
			(xy 37.539613 -297.072968) (xy 37.576357 -297.109716) (xy 37.606901 -297.15176) (xy 37.630492 -297.198064)
			(xy 37.64655 -297.247489) (xy 37.654679 -297.298816) (xy 37.654679 -297.350784) (xy 37.654678 -297.350788)
			(xy 152.144482 -297.350788) (xy 152.144482 -297.298812) (xy 152.152612 -297.247477) (xy 152.168672 -297.198046)
			(xy 152.192268 -297.151735) (xy 152.222816 -297.109685) (xy 152.259567 -297.072932) (xy 152.301615 -297.04238)
			(xy 152.347923 -297.018782) (xy 152.397354 -297.002717) (xy 152.448688 -296.994583) (xy 152.474676 -296.994072)
			(xy 153.424636 -296.994072) (xy 153.45062 -296.994624) (xy 153.501947 -297.002759) (xy 153.55137 -297.018822)
			(xy 153.597671 -297.042418) (xy 153.639712 -297.072967) (xy 153.676457 -297.109715) (xy 153.707001 -297.151759)
			(xy 153.730592 -297.198064) (xy 153.74665 -297.247488) (xy 153.754779 -297.298816) (xy 153.754779 -297.350784)
			(xy 153.754778 -297.350792) (xy 268.244255 -297.350792) (xy 268.244255 -297.298808) (xy 268.252388 -297.247465)
			(xy 268.268452 -297.198025) (xy 268.292053 -297.151708) (xy 268.322609 -297.109653) (xy 268.359368 -297.072896)
			(xy 268.401425 -297.042342) (xy 268.447744 -297.018744) (xy 268.497184 -297.002683) (xy 268.548528 -296.994554)
			(xy 268.57452 -296.994072) (xy 269.52448 -296.994072) (xy 269.550469 -296.994594) (xy 269.601807 -297.002722)
			(xy 269.651241 -297.018781) (xy 269.697554 -297.042377) (xy 269.739606 -297.072927) (xy 269.77636 -297.109679)
			(xy 269.806913 -297.151729) (xy 269.830511 -297.198041) (xy 269.846573 -297.247474) (xy 269.854705 -297.298811)
			(xy 269.854705 -297.350789) (xy 269.854705 -297.350792) (xy 384.344355 -297.350792) (xy 384.344355 -297.298808)
			(xy 384.352488 -297.247465) (xy 384.368552 -297.198026) (xy 384.392153 -297.151709) (xy 384.422709 -297.109654)
			(xy 384.459467 -297.072897) (xy 384.501524 -297.042343) (xy 384.547842 -297.018745) (xy 384.597282 -297.002683)
			(xy 384.648626 -296.994554) (xy 384.674618 -296.994072) (xy 385.624578 -296.994072) (xy 385.650567 -296.994593)
			(xy 385.701905 -297.002721) (xy 385.751339 -297.018781) (xy 385.797653 -297.042376) (xy 385.839705 -297.072926)
			(xy 385.87646 -297.109678) (xy 385.907013 -297.151728) (xy 385.930611 -297.19804) (xy 385.946673 -297.247474)
			(xy 385.954805 -297.298811) (xy 385.954805 -297.350789) (xy 385.946673 -297.402126) (xy 385.930611 -297.45156)
			(xy 385.907013 -297.497872) (xy 385.87646 -297.539922) (xy 385.839705 -297.576674) (xy 385.797653 -297.607224)
			(xy 385.751339 -297.630819) (xy 385.701905 -297.646879) (xy 385.650567 -297.655007) (xy 385.624578 -297.655488)
			(xy 384.674618 -297.655488) (xy 384.648626 -297.655046) (xy 384.597282 -297.646917) (xy 384.547842 -297.630855)
			(xy 384.501524 -297.607257) (xy 384.459467 -297.576703) (xy 384.422709 -297.539946) (xy 384.392153 -297.497891)
			(xy 384.368552 -297.451574) (xy 384.352488 -297.402135) (xy 384.344355 -297.350792) (xy 269.854705 -297.350792)
			(xy 269.846573 -297.402126) (xy 269.830511 -297.451559) (xy 269.806913 -297.497871) (xy 269.77636 -297.539921)
			(xy 269.739606 -297.576673) (xy 269.697554 -297.607223) (xy 269.651241 -297.630819) (xy 269.601807 -297.646878)
			(xy 269.550469 -297.655006) (xy 269.52448 -297.655488) (xy 268.57452 -297.655488) (xy 268.548528 -297.655046)
			(xy 268.497184 -297.646917) (xy 268.447744 -297.630856) (xy 268.401425 -297.607258) (xy 268.359368 -297.576704)
			(xy 268.322609 -297.539947) (xy 268.292053 -297.497892) (xy 268.268452 -297.451575) (xy 268.252388 -297.402135)
			(xy 268.244255 -297.350792) (xy 153.754778 -297.350792) (xy 153.74665 -297.402112) (xy 153.730592 -297.451536)
			(xy 153.707001 -297.497841) (xy 153.676457 -297.539885) (xy 153.639712 -297.576633) (xy 153.597671 -297.607182)
			(xy 153.55137 -297.630778) (xy 153.501947 -297.646841) (xy 153.45062 -297.654976) (xy 153.424636 -297.655488)
			(xy 152.474676 -297.655488) (xy 152.448688 -297.655017) (xy 152.397354 -297.646883) (xy 152.347923 -297.630818)
			(xy 152.301615 -297.60722) (xy 152.259567 -297.576668) (xy 152.222816 -297.539915) (xy 152.192268 -297.497865)
			(xy 152.168672 -297.451554) (xy 152.152612 -297.402123) (xy 152.144482 -297.350788) (xy 37.654678 -297.350788)
			(xy 37.64655 -297.402111) (xy 37.630492 -297.451536) (xy 37.606901 -297.49784) (xy 37.576357 -297.539884)
			(xy 37.539613 -297.576632) (xy 37.497572 -297.607181) (xy 37.451271 -297.630778) (xy 37.401848 -297.646841)
			(xy 37.350522 -297.654976) (xy 37.324538 -297.655488) (xy 36.374578 -297.655488) (xy 36.34859 -297.655017)
			(xy 36.297255 -297.646883) (xy 36.247825 -297.630819) (xy 36.201516 -297.607221) (xy 36.159468 -297.576669)
			(xy 36.122717 -297.539915) (xy 36.092168 -297.497866) (xy 36.068572 -297.451555) (xy 36.052512 -297.402123)
			(xy 36.044382 -297.350788) (xy 0.508 -297.350788) (xy 0.508 -298.77569) (xy 39.369695 -298.77569)
			(xy 39.369695 -298.72371) (xy 39.377827 -298.67237) (xy 39.393891 -298.622935) (xy 39.417492 -298.576621)
			(xy 39.448047 -298.53457) (xy 39.484805 -298.497817) (xy 39.52686 -298.467268) (xy 39.573177 -298.443674)
			(xy 39.622615 -298.427617) (xy 39.673956 -298.419492) (xy 39.699946 -298.419012) (xy 40.649906 -298.419012)
			(xy 40.675894 -298.419482) (xy 40.727231 -298.427614) (xy 40.776664 -298.443676) (xy 40.822975 -298.467274)
			(xy 40.865025 -298.497826) (xy 40.901778 -298.534579) (xy 40.932329 -298.57663) (xy 40.955926 -298.622942)
			(xy 40.971988 -298.672375) (xy 40.980118 -298.723712) (xy 40.980118 -298.775685) (xy 387.669821 -298.775685)
			(xy 387.669821 -298.723715) (xy 387.677951 -298.672385) (xy 387.69401 -298.622959) (xy 387.717603 -298.576653)
			(xy 387.74815 -298.534608) (xy 387.784897 -298.497859) (xy 387.826941 -298.467311) (xy 387.873246 -298.443716)
			(xy 387.922671 -298.427654) (xy 387.974001 -298.419523) (xy 387.999986 -298.419012) (xy 388.949946 -298.419012)
			(xy 388.975932 -298.419485) (xy 389.027264 -298.427622) (xy 389.076692 -298.443688) (xy 389.122998 -298.467288)
			(xy 389.165042 -298.49784) (xy 389.20179 -298.534593) (xy 389.232337 -298.576642) (xy 389.25593 -298.622951)
			(xy 389.271989 -298.67238) (xy 389.280119 -298.723714) (xy 389.280119 -298.775686) (xy 389.271989 -298.82702)
			(xy 389.25593 -298.876449) (xy 389.232337 -298.922758) (xy 389.20179 -298.964807) (xy 389.165042 -299.00156)
			(xy 389.122998 -299.032112) (xy 389.076692 -299.055712) (xy 389.027264 -299.071778) (xy 388.975932 -299.079915)
			(xy 388.949946 -299.080428) (xy 387.999986 -299.080428) (xy 387.974001 -299.079877) (xy 387.922671 -299.071746)
			(xy 387.873246 -299.055684) (xy 387.826941 -299.032089) (xy 387.784897 -299.001541) (xy 387.74815 -298.964792)
			(xy 387.717603 -298.922747) (xy 387.69401 -298.876441) (xy 387.677951 -298.827015) (xy 387.669821 -298.775685)
			(xy 40.980118 -298.775685) (xy 40.980118 -298.775688) (xy 40.971988 -298.827025) (xy 40.955926 -298.876458)
			(xy 40.932329 -298.92277) (xy 40.901778 -298.964821) (xy 40.865025 -299.001574) (xy 40.822975 -299.032126)
			(xy 40.776664 -299.055724) (xy 40.727231 -299.071786) (xy 40.675894 -299.079918) (xy 40.649906 -299.080428)
			(xy 39.699946 -299.080428) (xy 39.673956 -299.079908) (xy 39.622615 -299.071783) (xy 39.573177 -299.055726)
			(xy 39.52686 -299.032132) (xy 39.484805 -299.001583) (xy 39.448047 -298.96483) (xy 39.417492 -298.922779)
			(xy 39.393891 -298.876465) (xy 39.377827 -298.82703) (xy 39.369695 -298.77569) (xy 0.508 -298.77569)
			(xy 0.508 -299.25101) (xy 36.044102 -299.25101) (xy 36.044102 -299.19899) (xy 36.052239 -299.147611)
			(xy 36.068313 -299.098138) (xy 36.091929 -299.051788) (xy 36.122504 -299.009703) (xy 36.159286 -298.972918)
			(xy 36.201369 -298.94234) (xy 36.247718 -298.918722) (xy 36.29719 -298.902644) (xy 36.348568 -298.894504)
			(xy 36.374578 -298.893992) (xy 37.324538 -298.893992) (xy 37.35054 -298.894597) (xy 37.401902 -298.902737)
			(xy 37.451358 -298.918812) (xy 37.497691 -298.942425) (xy 37.539761 -298.972994) (xy 37.576531 -299.009768)
			(xy 37.607095 -299.051841) (xy 37.630703 -299.098177) (xy 37.646771 -299.147635) (xy 37.654906 -299.198998)
			(xy 37.654906 -299.251002) (xy 37.654905 -299.25101) (xy 152.144202 -299.25101) (xy 152.144202 -299.19899)
			(xy 152.152339 -299.147612) (xy 152.168413 -299.098138) (xy 152.192028 -299.051788) (xy 152.222603 -299.009703)
			(xy 152.259385 -298.972919) (xy 152.301468 -298.942341) (xy 152.347816 -298.918722) (xy 152.397288 -298.902645)
			(xy 152.448666 -298.894504) (xy 152.474676 -298.893992) (xy 153.424636 -298.893992) (xy 153.450638 -298.894597)
			(xy 153.502 -298.902737) (xy 153.551457 -298.918811) (xy 153.59779 -298.942424) (xy 153.63986 -298.972993)
			(xy 153.67663 -299.009767) (xy 153.707195 -299.05184) (xy 153.730803 -299.098177) (xy 153.746871 -299.147635)
			(xy 153.755006 -299.198998) (xy 153.755006 -299.251002) (xy 153.755005 -299.251009) (xy 154.994602 -299.251009)
			(xy 154.994602 -299.198991) (xy 155.002739 -299.147613) (xy 155.018812 -299.098141) (xy 155.042426 -299.051792)
			(xy 155.073 -299.009707) (xy 155.10978 -298.972923) (xy 155.151861 -298.942345) (xy 155.198208 -298.918726)
			(xy 155.247678 -298.902647) (xy 155.299055 -298.894505) (xy 155.325064 -298.893992) (xy 156.275024 -298.893992)
			(xy 156.301026 -298.894596) (xy 156.35239 -298.902735) (xy 156.401848 -298.918808) (xy 156.448184 -298.94242)
			(xy 156.490255 -298.972989) (xy 156.527026 -299.009763) (xy 156.557593 -299.051837) (xy 156.581201 -299.098174)
			(xy 156.597271 -299.147633) (xy 156.605406 -299.198998) (xy 156.605406 -299.251002) (xy 156.605404 -299.251014)
			(xy 268.243976 -299.251014) (xy 268.243976 -299.198986) (xy 268.252115 -299.147599) (xy 268.268193 -299.098118)
			(xy 268.291814 -299.051761) (xy 268.322396 -299.009671) (xy 268.359186 -298.972883) (xy 268.401279 -298.942303)
			(xy 268.447637 -298.918685) (xy 268.497119 -298.90261) (xy 268.548506 -298.894474) (xy 268.57452 -298.893992)
			(xy 269.52448 -298.893992) (xy 269.550487 -298.894566) (xy 269.60186 -298.9027) (xy 269.651328 -298.91877)
			(xy 269.697673 -298.942382) (xy 269.739754 -298.972953) (xy 269.776534 -299.009731) (xy 269.807108 -299.05181)
			(xy 269.830722 -299.098153) (xy 269.846796 -299.147621) (xy 269.854933 -299.198993) (xy 269.854933 -299.251007)
			(xy 269.854932 -299.251013) (xy 271.094376 -299.251013) (xy 271.094376 -299.198987) (xy 271.102514 -299.147601)
			(xy 271.118592 -299.098121) (xy 271.142212 -299.051765) (xy 271.172792 -299.009675) (xy 271.209581 -298.972887)
			(xy 271.251672 -298.942307) (xy 271.298028 -298.918689) (xy 271.347509 -298.902613) (xy 271.398895 -298.894475)
			(xy 271.424908 -298.893992) (xy 272.374868 -298.893992) (xy 272.400875 -298.894565) (xy 272.45225 -298.902697)
			(xy 272.50172 -298.918767) (xy 272.548067 -298.942378) (xy 272.590149 -298.972949) (xy 272.626931 -299.009727)
			(xy 272.657506 -299.051806) (xy 272.681121 -299.09815) (xy 272.697195 -299.147619) (xy 272.705333 -299.198993)
			(xy 272.705333 -299.251007) (xy 272.705332 -299.251014) (xy 384.344076 -299.251014) (xy 384.344076 -299.198986)
			(xy 384.352215 -299.147599) (xy 384.368293 -299.098118) (xy 384.391913 -299.051762) (xy 384.422495 -299.009672)
			(xy 384.459285 -298.972884) (xy 384.501377 -298.942304) (xy 384.547735 -298.918686) (xy 384.597217 -298.902611)
			(xy 384.648604 -298.894474) (xy 384.674618 -298.893992) (xy 385.624578 -298.893992) (xy 385.650585 -298.894566)
			(xy 385.701958 -298.902699) (xy 385.751427 -298.91877) (xy 385.797772 -298.942381) (xy 385.839853 -298.972952)
			(xy 385.876634 -299.00973) (xy 385.907207 -299.051809) (xy 385.930822 -299.098153) (xy 385.946896 -299.14762)
			(xy 385.955033 -299.198993) (xy 385.955033 -299.251007) (xy 385.946896 -299.30238) (xy 385.930822 -299.351847)
			(xy 385.907207 -299.398191) (xy 385.876634 -299.44027) (xy 385.839853 -299.477048) (xy 385.797772 -299.507619)
			(xy 385.751427 -299.53123) (xy 385.701958 -299.547301) (xy 385.650585 -299.555434) (xy 385.624578 -299.555916)
			(xy 384.674618 -299.555916) (xy 384.648604 -299.555526) (xy 384.597217 -299.547389) (xy 384.547735 -299.531314)
			(xy 384.501377 -299.507696) (xy 384.459285 -299.477116) (xy 384.422495 -299.440328) (xy 384.391913 -299.398238)
			(xy 384.368293 -299.351882) (xy 384.352215 -299.302401) (xy 384.344076 -299.251014) (xy 272.705332 -299.251014)
			(xy 272.697195 -299.302381) (xy 272.681121 -299.35185) (xy 272.657506 -299.398194) (xy 272.626931 -299.440273)
			(xy 272.590149 -299.477051) (xy 272.548067 -299.507622) (xy 272.50172 -299.531233) (xy 272.45225 -299.547303)
			(xy 272.400875 -299.555435) (xy 272.374868 -299.555916) (xy 271.424908 -299.555916) (xy 271.398895 -299.555525)
			(xy 271.347509 -299.547387) (xy 271.298028 -299.531311) (xy 271.251672 -299.507693) (xy 271.209581 -299.477113)
			(xy 271.172792 -299.440325) (xy 271.142212 -299.398235) (xy 271.118592 -299.351879) (xy 271.102514 -299.302399)
			(xy 271.094376 -299.251013) (xy 269.854932 -299.251013) (xy 269.846796 -299.302379) (xy 269.830722 -299.351847)
			(xy 269.807108 -299.39819) (xy 269.776534 -299.440269) (xy 269.739754 -299.477047) (xy 269.697673 -299.507618)
			(xy 269.651328 -299.53123) (xy 269.60186 -299.5473) (xy 269.550487 -299.555434) (xy 269.52448 -299.555916)
			(xy 268.57452 -299.555916) (xy 268.548506 -299.555526) (xy 268.497119 -299.54739) (xy 268.447637 -299.531315)
			(xy 268.401279 -299.507697) (xy 268.359186 -299.477117) (xy 268.322396 -299.440329) (xy 268.291814 -299.398239)
			(xy 268.268193 -299.351882) (xy 268.252115 -299.302401) (xy 268.243976 -299.251014) (xy 156.605404 -299.251014)
			(xy 156.597271 -299.302367) (xy 156.581201 -299.351826) (xy 156.557593 -299.398163) (xy 156.527026 -299.440237)
			(xy 156.490255 -299.477011) (xy 156.448184 -299.50758) (xy 156.401848 -299.531192) (xy 156.35239 -299.547265)
			(xy 156.301026 -299.555404) (xy 156.275024 -299.555916) (xy 155.325064 -299.555916) (xy 155.299055 -299.555495)
			(xy 155.247678 -299.547353) (xy 155.198208 -299.531274) (xy 155.151861 -299.507655) (xy 155.10978 -299.477077)
			(xy 155.073 -299.440293) (xy 155.042426 -299.398208) (xy 155.018812 -299.351859) (xy 155.002739 -299.302387)
			(xy 154.994602 -299.251009) (xy 153.755005 -299.251009) (xy 153.746871 -299.302365) (xy 153.730803 -299.351823)
			(xy 153.707195 -299.39816) (xy 153.67663 -299.440233) (xy 153.63986 -299.477007) (xy 153.59779 -299.507576)
			(xy 153.551457 -299.531189) (xy 153.502 -299.547263) (xy 153.450638 -299.555403) (xy 153.424636 -299.555916)
			(xy 152.474676 -299.555916) (xy 152.448666 -299.555496) (xy 152.397288 -299.547355) (xy 152.347816 -299.531278)
			(xy 152.301468 -299.507659) (xy 152.259385 -299.477081) (xy 152.222603 -299.440297) (xy 152.192028 -299.398212)
			(xy 152.168413 -299.351862) (xy 152.152339 -299.302388) (xy 152.144202 -299.25101) (xy 37.654905 -299.25101)
			(xy 37.646771 -299.302365) (xy 37.630703 -299.351823) (xy 37.607095 -299.398159) (xy 37.576531 -299.440232)
			(xy 37.539761 -299.477006) (xy 37.497691 -299.507575) (xy 37.451358 -299.531188) (xy 37.401902 -299.547263)
			(xy 37.35054 -299.555403) (xy 37.324538 -299.555916) (xy 36.374578 -299.555916) (xy 36.348568 -299.555496)
			(xy 36.29719 -299.547356) (xy 36.247718 -299.531278) (xy 36.201369 -299.50766) (xy 36.159286 -299.477082)
			(xy 36.122504 -299.440297) (xy 36.091929 -299.398212) (xy 36.068313 -299.351862) (xy 36.052239 -299.302389)
			(xy 36.044102 -299.25101) (xy 0.508 -299.25101) (xy 0.508 -304.449734) (xy 81.19416 -304.449734)
			(xy 81.19812 -304.40068) (xy 81.209897 -304.352896) (xy 81.229188 -304.30762) (xy 81.255491 -304.266024)
			(xy 81.288126 -304.229187) (xy 81.326247 -304.198062) (xy 81.368868 -304.173455) (xy 81.414884 -304.156003)
			(xy 81.463103 -304.146159) (xy 81.512278 -304.144178) (xy 81.561133 -304.15011) (xy 81.608404 -304.163802)
			(xy 81.652866 -304.1849) (xy 81.693369 -304.212856) (xy 81.728862 -304.246948) (xy 81.758427 -304.286292)
			(xy 81.781298 -304.329869) (xy 81.796882 -304.37655) (xy 81.804777 -304.425127) (xy 81.805272 -304.449734)
			(xy 82.14412 -304.449734) (xy 82.14808 -304.40068) (xy 82.159857 -304.352896) (xy 82.179148 -304.30762)
			(xy 82.205451 -304.266024) (xy 82.238086 -304.229187) (xy 82.276207 -304.198062) (xy 82.318828 -304.173455)
			(xy 82.364844 -304.156003) (xy 82.413063 -304.146159) (xy 82.462238 -304.144178) (xy 82.511093 -304.15011)
			(xy 82.558364 -304.163802) (xy 82.602826 -304.1849) (xy 82.643329 -304.212856) (xy 82.678822 -304.246948)
			(xy 82.708387 -304.286292) (xy 82.731258 -304.329869) (xy 82.746842 -304.37655) (xy 82.754737 -304.425127)
			(xy 82.755232 -304.449734) (xy 313.394102 -304.449734) (xy 313.398062 -304.40068) (xy 313.409839 -304.352896)
			(xy 313.42913 -304.30762) (xy 313.455433 -304.266024) (xy 313.488068 -304.229187) (xy 313.526189 -304.198062)
			(xy 313.56881 -304.173455) (xy 313.614826 -304.156003) (xy 313.663045 -304.146159) (xy 313.71222 -304.144178)
			(xy 313.761075 -304.15011) (xy 313.808346 -304.163802) (xy 313.852808 -304.1849) (xy 313.893311 -304.212856)
			(xy 313.928804 -304.246948) (xy 313.958369 -304.286292) (xy 313.98124 -304.329869) (xy 313.996824 -304.37655)
			(xy 314.004719 -304.425127) (xy 314.005214 -304.449734) (xy 314.344062 -304.449734) (xy 314.348022 -304.40068)
			(xy 314.359799 -304.352896) (xy 314.37909 -304.30762) (xy 314.405393 -304.266024) (xy 314.438028 -304.229187)
			(xy 314.476149 -304.198062) (xy 314.51877 -304.173455) (xy 314.564786 -304.156003) (xy 314.613005 -304.146159)
			(xy 314.66218 -304.144178) (xy 314.711035 -304.15011) (xy 314.758306 -304.163802) (xy 314.802768 -304.1849)
			(xy 314.843271 -304.212856) (xy 314.878764 -304.246948) (xy 314.908329 -304.286292) (xy 314.9312 -304.329869)
			(xy 314.946784 -304.37655) (xy 314.954679 -304.425127) (xy 314.955174 -304.449734) (xy 314.954679 -304.474341)
			(xy 314.946784 -304.522918) (xy 314.9312 -304.569599) (xy 314.908329 -304.613176) (xy 314.878764 -304.65252)
			(xy 314.843271 -304.686612) (xy 314.802768 -304.714568) (xy 314.758306 -304.735666) (xy 314.711035 -304.749358)
			(xy 314.66218 -304.75529) (xy 314.613005 -304.753309) (xy 314.564786 -304.743465) (xy 314.51877 -304.726013)
			(xy 314.476149 -304.701406) (xy 314.438028 -304.670281) (xy 314.405393 -304.633444) (xy 314.37909 -304.591848)
			(xy 314.359799 -304.546572) (xy 314.348022 -304.498788) (xy 314.344062 -304.449734) (xy 314.005214 -304.449734)
			(xy 314.004719 -304.474341) (xy 313.996824 -304.522918) (xy 313.98124 -304.569599) (xy 313.958369 -304.613176)
			(xy 313.928804 -304.65252) (xy 313.893311 -304.686612) (xy 313.852808 -304.714568) (xy 313.808346 -304.735666)
			(xy 313.761075 -304.749358) (xy 313.71222 -304.75529) (xy 313.663045 -304.753309) (xy 313.614826 -304.743465)
			(xy 313.56881 -304.726013) (xy 313.526189 -304.701406) (xy 313.488068 -304.670281) (xy 313.455433 -304.633444)
			(xy 313.42913 -304.591848) (xy 313.409839 -304.546572) (xy 313.398062 -304.498788) (xy 313.394102 -304.449734)
			(xy 82.755232 -304.449734) (xy 82.754737 -304.474341) (xy 82.746842 -304.522918) (xy 82.731258 -304.569599)
			(xy 82.708387 -304.613176) (xy 82.678822 -304.65252) (xy 82.643329 -304.686612) (xy 82.602826 -304.714568)
			(xy 82.558364 -304.735666) (xy 82.511093 -304.749358) (xy 82.462238 -304.75529) (xy 82.413063 -304.753309)
			(xy 82.364844 -304.743465) (xy 82.318828 -304.726013) (xy 82.276207 -304.701406) (xy 82.238086 -304.670281)
			(xy 82.205451 -304.633444) (xy 82.179148 -304.591848) (xy 82.159857 -304.546572) (xy 82.14808 -304.498788)
			(xy 82.14412 -304.449734) (xy 81.805272 -304.449734) (xy 81.804777 -304.474341) (xy 81.796882 -304.522918)
			(xy 81.781298 -304.569599) (xy 81.758427 -304.613176) (xy 81.728862 -304.65252) (xy 81.693369 -304.686612)
			(xy 81.652866 -304.714568) (xy 81.608404 -304.735666) (xy 81.561133 -304.749358) (xy 81.512278 -304.75529)
			(xy 81.463103 -304.753309) (xy 81.414884 -304.743465) (xy 81.368868 -304.726013) (xy 81.326247 -304.701406)
			(xy 81.288126 -304.670281) (xy 81.255491 -304.633444) (xy 81.229188 -304.591848) (xy 81.209897 -304.546572)
			(xy 81.19812 -304.498788) (xy 81.19416 -304.449734) (xy 0.508 -304.449734) (xy 0.508 -305.19751)
			(xy 17.638266 -305.19751) (xy 17.642339 -305.141851) (xy 17.654474 -305.087378) (xy 17.67441 -305.035252)
			(xy 17.701724 -304.986584) (xy 17.735832 -304.942412) (xy 17.776009 -304.903677) (xy 17.821397 -304.871205)
			(xy 17.871029 -304.845687) (xy 17.923849 -304.827668) (xy 17.978728 -304.817531) (xy 18.034499 -304.815493)
			(xy 18.089973 -304.821596) (xy 18.143966 -304.835712) (xy 18.195329 -304.857539) (xy 18.242967 -304.886612)
			(xy 18.285863 -304.922311) (xy 18.323105 -304.963875) (xy 18.353899 -305.010419) (xy 18.377587 -305.06095)
			(xy 18.393665 -305.114392) (xy 18.401791 -305.169606) (xy 18.4023 -305.19751) (xy 18.401791 -305.225414)
			(xy 18.393665 -305.280628) (xy 18.377587 -305.33407) (xy 18.353899 -305.384601) (xy 18.343745 -305.399948)
			(xy 79.293986 -305.399948) (xy 79.297946 -305.350894) (xy 79.309723 -305.30311) (xy 79.329014 -305.257834)
			(xy 79.355317 -305.216238) (xy 79.387952 -305.179401) (xy 79.426073 -305.148276) (xy 79.468694 -305.123669)
			(xy 79.51471 -305.106217) (xy 79.562929 -305.096373) (xy 79.612104 -305.094392) (xy 79.660959 -305.100324)
			(xy 79.70823 -305.114016) (xy 79.752692 -305.135114) (xy 79.793195 -305.16307) (xy 79.828688 -305.197162)
			(xy 79.858253 -305.236506) (xy 79.881124 -305.280083) (xy 79.896708 -305.326764) (xy 79.904603 -305.375341)
			(xy 79.905098 -305.399948) (xy 80.243946 -305.399948) (xy 80.247906 -305.350894) (xy 80.259683 -305.30311)
			(xy 80.278974 -305.257834) (xy 80.305277 -305.216238) (xy 80.337912 -305.179401) (xy 80.376033 -305.148276)
			(xy 80.418654 -305.123669) (xy 80.46467 -305.106217) (xy 80.512889 -305.096373) (xy 80.562064 -305.094392)
			(xy 80.610919 -305.100324) (xy 80.65819 -305.114016) (xy 80.702652 -305.135114) (xy 80.743155 -305.16307)
			(xy 80.778648 -305.197162) (xy 80.808213 -305.236506) (xy 80.831084 -305.280083) (xy 80.846668 -305.326764)
			(xy 80.854563 -305.375341) (xy 80.855058 -305.399948) (xy 311.493928 -305.399948) (xy 311.497888 -305.350894)
			(xy 311.509665 -305.30311) (xy 311.528956 -305.257834) (xy 311.555259 -305.216238) (xy 311.587894 -305.179401)
			(xy 311.626015 -305.148276) (xy 311.668636 -305.123669) (xy 311.714652 -305.106217) (xy 311.762871 -305.096373)
			(xy 311.812046 -305.094392) (xy 311.860901 -305.100324) (xy 311.908172 -305.114016) (xy 311.952634 -305.135114)
			(xy 311.993137 -305.16307) (xy 312.02863 -305.197162) (xy 312.058195 -305.236506) (xy 312.081066 -305.280083)
			(xy 312.09665 -305.326764) (xy 312.104545 -305.375341) (xy 312.10504 -305.399948) (xy 312.443888 -305.399948)
			(xy 312.447848 -305.350894) (xy 312.459625 -305.30311) (xy 312.478916 -305.257834) (xy 312.505219 -305.216238)
			(xy 312.537854 -305.179401) (xy 312.575975 -305.148276) (xy 312.618596 -305.123669) (xy 312.664612 -305.106217)
			(xy 312.712831 -305.096373) (xy 312.762006 -305.094392) (xy 312.810861 -305.100324) (xy 312.858132 -305.114016)
			(xy 312.902594 -305.135114) (xy 312.943097 -305.16307) (xy 312.97859 -305.197162) (xy 313.008155 -305.236506)
			(xy 313.031026 -305.280083) (xy 313.04661 -305.326764) (xy 313.054505 -305.375341) (xy 313.055 -305.399948)
			(xy 313.054505 -305.424555) (xy 313.04661 -305.473132) (xy 313.031026 -305.519813) (xy 313.008155 -305.56339)
			(xy 312.97859 -305.602734) (xy 312.943097 -305.636826) (xy 312.902594 -305.664782) (xy 312.858132 -305.68588)
			(xy 312.810861 -305.699572) (xy 312.762006 -305.705504) (xy 312.712831 -305.703523) (xy 312.664612 -305.693679)
			(xy 312.618596 -305.676227) (xy 312.575975 -305.65162) (xy 312.537854 -305.620495) (xy 312.505219 -305.583658)
			(xy 312.478916 -305.542062) (xy 312.459625 -305.496786) (xy 312.447848 -305.449002) (xy 312.443888 -305.399948)
			(xy 312.10504 -305.399948) (xy 312.104545 -305.424555) (xy 312.09665 -305.473132) (xy 312.081066 -305.519813)
			(xy 312.058195 -305.56339) (xy 312.02863 -305.602734) (xy 311.993137 -305.636826) (xy 311.952634 -305.664782)
			(xy 311.908172 -305.68588) (xy 311.860901 -305.699572) (xy 311.812046 -305.705504) (xy 311.762871 -305.703523)
			(xy 311.714652 -305.693679) (xy 311.668636 -305.676227) (xy 311.626015 -305.65162) (xy 311.587894 -305.620495)
			(xy 311.555259 -305.583658) (xy 311.528956 -305.542062) (xy 311.509665 -305.496786) (xy 311.497888 -305.449002)
			(xy 311.493928 -305.399948) (xy 80.855058 -305.399948) (xy 80.854563 -305.424555) (xy 80.846668 -305.473132)
			(xy 80.831084 -305.519813) (xy 80.808213 -305.56339) (xy 80.778648 -305.602734) (xy 80.743155 -305.636826)
			(xy 80.702652 -305.664782) (xy 80.65819 -305.68588) (xy 80.610919 -305.699572) (xy 80.562064 -305.705504)
			(xy 80.512889 -305.703523) (xy 80.46467 -305.693679) (xy 80.418654 -305.676227) (xy 80.376033 -305.65162)
			(xy 80.337912 -305.620495) (xy 80.305277 -305.583658) (xy 80.278974 -305.542062) (xy 80.259683 -305.496786)
			(xy 80.247906 -305.449002) (xy 80.243946 -305.399948) (xy 79.905098 -305.399948) (xy 79.904603 -305.424555)
			(xy 79.896708 -305.473132) (xy 79.881124 -305.519813) (xy 79.858253 -305.56339) (xy 79.828688 -305.602734)
			(xy 79.793195 -305.636826) (xy 79.752692 -305.664782) (xy 79.70823 -305.68588) (xy 79.660959 -305.699572)
			(xy 79.612104 -305.705504) (xy 79.562929 -305.703523) (xy 79.51471 -305.693679) (xy 79.468694 -305.676227)
			(xy 79.426073 -305.65162) (xy 79.387952 -305.620495) (xy 79.355317 -305.583658) (xy 79.329014 -305.542062)
			(xy 79.309723 -305.496786) (xy 79.297946 -305.449002) (xy 79.293986 -305.399948) (xy 18.343745 -305.399948)
			(xy 18.323105 -305.431145) (xy 18.285863 -305.472709) (xy 18.242967 -305.508408) (xy 18.195329 -305.537481)
			(xy 18.143966 -305.559308) (xy 18.089973 -305.573424) (xy 18.034499 -305.579527) (xy 17.978728 -305.577489)
			(xy 17.923849 -305.567352) (xy 17.871029 -305.549333) (xy 17.821397 -305.523815) (xy 17.776009 -305.491343)
			(xy 17.735832 -305.452608) (xy 17.701724 -305.408436) (xy 17.67441 -305.359768) (xy 17.654474 -305.307642)
			(xy 17.642339 -305.253169) (xy 17.638266 -305.19751) (xy 0.508 -305.19751) (xy 0.508 -306.28209)
			(xy 17.638266 -306.28209) (xy 17.642339 -306.226431) (xy 17.654474 -306.171958) (xy 17.67441 -306.119832)
			(xy 17.701724 -306.071164) (xy 17.735832 -306.026992) (xy 17.776009 -305.988257) (xy 17.821397 -305.955785)
			(xy 17.871029 -305.930267) (xy 17.923849 -305.912248) (xy 17.978728 -305.902111) (xy 18.034499 -305.900073)
			(xy 18.089973 -305.906176) (xy 18.143966 -305.920292) (xy 18.195329 -305.942119) (xy 18.242967 -305.971192)
			(xy 18.285863 -306.006891) (xy 18.323105 -306.048455) (xy 18.353899 -306.094999) (xy 18.377587 -306.14553)
			(xy 18.393665 -306.198972) (xy 18.401791 -306.254186) (xy 18.4023 -306.28209) (xy 18.401791 -306.309994)
			(xy 18.395917 -306.349908) (xy 81.19416 -306.349908) (xy 81.19812 -306.300854) (xy 81.209897 -306.25307)
			(xy 81.229188 -306.207794) (xy 81.255491 -306.166198) (xy 81.288126 -306.129361) (xy 81.326247 -306.098236)
			(xy 81.368868 -306.073629) (xy 81.414884 -306.056177) (xy 81.463103 -306.046333) (xy 81.512278 -306.044352)
			(xy 81.561133 -306.050284) (xy 81.608404 -306.063976) (xy 81.652866 -306.085074) (xy 81.693369 -306.11303)
			(xy 81.728862 -306.147122) (xy 81.758427 -306.186466) (xy 81.781298 -306.230043) (xy 81.796882 -306.276724)
			(xy 81.804777 -306.325301) (xy 81.805272 -306.349908) (xy 82.14412 -306.349908) (xy 82.14808 -306.300854)
			(xy 82.159857 -306.25307) (xy 82.179148 -306.207794) (xy 82.205451 -306.166198) (xy 82.238086 -306.129361)
			(xy 82.276207 -306.098236) (xy 82.318828 -306.073629) (xy 82.364844 -306.056177) (xy 82.413063 -306.046333)
			(xy 82.462238 -306.044352) (xy 82.511093 -306.050284) (xy 82.558364 -306.063976) (xy 82.602826 -306.085074)
			(xy 82.643329 -306.11303) (xy 82.678822 -306.147122) (xy 82.708387 -306.186466) (xy 82.731258 -306.230043)
			(xy 82.746842 -306.276724) (xy 82.754737 -306.325301) (xy 82.755232 -306.349908) (xy 313.394102 -306.349908)
			(xy 313.398062 -306.300854) (xy 313.409839 -306.25307) (xy 313.42913 -306.207794) (xy 313.455433 -306.166198)
			(xy 313.488068 -306.129361) (xy 313.526189 -306.098236) (xy 313.56881 -306.073629) (xy 313.614826 -306.056177)
			(xy 313.663045 -306.046333) (xy 313.71222 -306.044352) (xy 313.761075 -306.050284) (xy 313.808346 -306.063976)
			(xy 313.852808 -306.085074) (xy 313.893311 -306.11303) (xy 313.928804 -306.147122) (xy 313.958369 -306.186466)
			(xy 313.98124 -306.230043) (xy 313.996824 -306.276724) (xy 314.004719 -306.325301) (xy 314.005214 -306.349908)
			(xy 314.344062 -306.349908) (xy 314.348022 -306.300854) (xy 314.359799 -306.25307) (xy 314.37909 -306.207794)
			(xy 314.405393 -306.166198) (xy 314.438028 -306.129361) (xy 314.476149 -306.098236) (xy 314.51877 -306.073629)
			(xy 314.564786 -306.056177) (xy 314.613005 -306.046333) (xy 314.66218 -306.044352) (xy 314.711035 -306.050284)
			(xy 314.758306 -306.063976) (xy 314.802768 -306.085074) (xy 314.843271 -306.11303) (xy 314.878764 -306.147122)
			(xy 314.908329 -306.186466) (xy 314.9312 -306.230043) (xy 314.946784 -306.276724) (xy 314.954679 -306.325301)
			(xy 314.955174 -306.349908) (xy 314.954679 -306.374515) (xy 314.946784 -306.423092) (xy 314.9312 -306.469773)
			(xy 314.908329 -306.51335) (xy 314.878764 -306.552694) (xy 314.843271 -306.586786) (xy 314.802768 -306.614742)
			(xy 314.758306 -306.63584) (xy 314.711035 -306.649532) (xy 314.66218 -306.655464) (xy 314.613005 -306.653483)
			(xy 314.564786 -306.643639) (xy 314.51877 -306.626187) (xy 314.476149 -306.60158) (xy 314.438028 -306.570455)
			(xy 314.405393 -306.533618) (xy 314.37909 -306.492022) (xy 314.359799 -306.446746) (xy 314.348022 -306.398962)
			(xy 314.344062 -306.349908) (xy 314.005214 -306.349908) (xy 314.004719 -306.374515) (xy 313.996824 -306.423092)
			(xy 313.98124 -306.469773) (xy 313.958369 -306.51335) (xy 313.928804 -306.552694) (xy 313.893311 -306.586786)
			(xy 313.852808 -306.614742) (xy 313.808346 -306.63584) (xy 313.761075 -306.649532) (xy 313.71222 -306.655464)
			(xy 313.663045 -306.653483) (xy 313.614826 -306.643639) (xy 313.56881 -306.626187) (xy 313.526189 -306.60158)
			(xy 313.488068 -306.570455) (xy 313.455433 -306.533618) (xy 313.42913 -306.492022) (xy 313.409839 -306.446746)
			(xy 313.398062 -306.398962) (xy 313.394102 -306.349908) (xy 82.755232 -306.349908) (xy 82.754737 -306.374515)
			(xy 82.746842 -306.423092) (xy 82.731258 -306.469773) (xy 82.708387 -306.51335) (xy 82.678822 -306.552694)
			(xy 82.643329 -306.586786) (xy 82.602826 -306.614742) (xy 82.558364 -306.63584) (xy 82.511093 -306.649532)
			(xy 82.462238 -306.655464) (xy 82.413063 -306.653483) (xy 82.364844 -306.643639) (xy 82.318828 -306.626187)
			(xy 82.276207 -306.60158) (xy 82.238086 -306.570455) (xy 82.205451 -306.533618) (xy 82.179148 -306.492022)
			(xy 82.159857 -306.446746) (xy 82.14808 -306.398962) (xy 82.14412 -306.349908) (xy 81.805272 -306.349908)
			(xy 81.804777 -306.374515) (xy 81.796882 -306.423092) (xy 81.781298 -306.469773) (xy 81.758427 -306.51335)
			(xy 81.728862 -306.552694) (xy 81.693369 -306.586786) (xy 81.652866 -306.614742) (xy 81.608404 -306.63584)
			(xy 81.561133 -306.649532) (xy 81.512278 -306.655464) (xy 81.463103 -306.653483) (xy 81.414884 -306.643639)
			(xy 81.368868 -306.626187) (xy 81.326247 -306.60158) (xy 81.288126 -306.570455) (xy 81.255491 -306.533618)
			(xy 81.229188 -306.492022) (xy 81.209897 -306.446746) (xy 81.19812 -306.398962) (xy 81.19416 -306.349908)
			(xy 18.395917 -306.349908) (xy 18.393665 -306.365208) (xy 18.377587 -306.41865) (xy 18.353899 -306.469181)
			(xy 18.323105 -306.515725) (xy 18.285863 -306.557289) (xy 18.242967 -306.592988) (xy 18.195329 -306.622061)
			(xy 18.143966 -306.643888) (xy 18.089973 -306.658004) (xy 18.034499 -306.664107) (xy 17.978728 -306.662069)
			(xy 17.923849 -306.651932) (xy 17.871029 -306.633913) (xy 17.821397 -306.608395) (xy 17.776009 -306.575923)
			(xy 17.735832 -306.537188) (xy 17.701724 -306.493016) (xy 17.67441 -306.444348) (xy 17.654474 -306.392222)
			(xy 17.642339 -306.337749) (xy 17.638266 -306.28209) (xy 0.508 -306.28209) (xy 0.508 -307.299868)
			(xy 79.293986 -307.299868) (xy 79.297946 -307.250814) (xy 79.309723 -307.20303) (xy 79.329014 -307.157754)
			(xy 79.355317 -307.116158) (xy 79.387952 -307.079321) (xy 79.426073 -307.048196) (xy 79.468694 -307.023589)
			(xy 79.51471 -307.006137) (xy 79.562929 -306.996293) (xy 79.612104 -306.994312) (xy 79.660959 -307.000244)
			(xy 79.70823 -307.013936) (xy 79.752692 -307.035034) (xy 79.793195 -307.06299) (xy 79.828688 -307.097082)
			(xy 79.858253 -307.136426) (xy 79.881124 -307.180003) (xy 79.896708 -307.226684) (xy 79.904603 -307.275261)
			(xy 79.905098 -307.299868) (xy 80.243946 -307.299868) (xy 80.247906 -307.250814) (xy 80.259683 -307.20303)
			(xy 80.278974 -307.157754) (xy 80.305277 -307.116158) (xy 80.337912 -307.079321) (xy 80.376033 -307.048196)
			(xy 80.418654 -307.023589) (xy 80.46467 -307.006137) (xy 80.512889 -306.996293) (xy 80.562064 -306.994312)
			(xy 80.610919 -307.000244) (xy 80.65819 -307.013936) (xy 80.702652 -307.035034) (xy 80.743155 -307.06299)
			(xy 80.778648 -307.097082) (xy 80.808213 -307.136426) (xy 80.831084 -307.180003) (xy 80.846668 -307.226684)
			(xy 80.854563 -307.275261) (xy 80.855058 -307.299868) (xy 80.854563 -307.324475) (xy 80.846668 -307.373052)
			(xy 80.831084 -307.419733) (xy 80.808213 -307.46331) (xy 80.792461 -307.484272) (xy 231.935526 -307.484272)
			(xy 231.939599 -307.428613) (xy 231.951734 -307.37414) (xy 231.97167 -307.322014) (xy 231.998984 -307.273346)
			(xy 232.033092 -307.229174) (xy 232.073269 -307.190439) (xy 232.118657 -307.157967) (xy 232.168289 -307.132449)
			(xy 232.221109 -307.11443) (xy 232.275988 -307.104293) (xy 232.331759 -307.102255) (xy 232.387233 -307.108358)
			(xy 232.441226 -307.122474) (xy 232.492589 -307.144301) (xy 232.540227 -307.173374) (xy 232.583123 -307.209073)
			(xy 232.620365 -307.250637) (xy 232.651159 -307.297181) (xy 232.674847 -307.347712) (xy 232.690925 -307.401154)
			(xy 232.699051 -307.456368) (xy 232.69956 -307.484272) (xy 248.185684 -307.484272) (xy 248.189757 -307.428613)
			(xy 248.201892 -307.37414) (xy 248.221828 -307.322014) (xy 248.249142 -307.273346) (xy 248.28325 -307.229174)
			(xy 248.323427 -307.190439) (xy 248.368815 -307.157967) (xy 248.418447 -307.132449) (xy 248.471267 -307.11443)
			(xy 248.526146 -307.104293) (xy 248.581917 -307.102255) (xy 248.637391 -307.108358) (xy 248.691384 -307.122474)
			(xy 248.742747 -307.144301) (xy 248.790385 -307.173374) (xy 248.833281 -307.209073) (xy 248.870523 -307.250637)
			(xy 248.901317 -307.297181) (xy 248.902577 -307.299868) (xy 311.493928 -307.299868) (xy 311.497888 -307.250814)
			(xy 311.509665 -307.20303) (xy 311.528956 -307.157754) (xy 311.555259 -307.116158) (xy 311.587894 -307.079321)
			(xy 311.626015 -307.048196) (xy 311.668636 -307.023589) (xy 311.714652 -307.006137) (xy 311.762871 -306.996293)
			(xy 311.812046 -306.994312) (xy 311.860901 -307.000244) (xy 311.908172 -307.013936) (xy 311.952634 -307.035034)
			(xy 311.993137 -307.06299) (xy 312.02863 -307.097082) (xy 312.058195 -307.136426) (xy 312.081066 -307.180003)
			(xy 312.09665 -307.226684) (xy 312.104545 -307.275261) (xy 312.10504 -307.299868) (xy 312.443888 -307.299868)
			(xy 312.447848 -307.250814) (xy 312.459625 -307.20303) (xy 312.478916 -307.157754) (xy 312.505219 -307.116158)
			(xy 312.537854 -307.079321) (xy 312.575975 -307.048196) (xy 312.618596 -307.023589) (xy 312.664612 -307.006137)
			(xy 312.712831 -306.996293) (xy 312.762006 -306.994312) (xy 312.810861 -307.000244) (xy 312.858132 -307.013936)
			(xy 312.902594 -307.035034) (xy 312.943097 -307.06299) (xy 312.97859 -307.097082) (xy 313.008155 -307.136426)
			(xy 313.031026 -307.180003) (xy 313.04661 -307.226684) (xy 313.054505 -307.275261) (xy 313.055 -307.299868)
			(xy 313.054505 -307.324475) (xy 313.04661 -307.373052) (xy 313.031026 -307.419733) (xy 313.008155 -307.46331)
			(xy 312.97859 -307.502654) (xy 312.943097 -307.536746) (xy 312.902594 -307.564702) (xy 312.858132 -307.5858)
			(xy 312.810861 -307.599492) (xy 312.762006 -307.605424) (xy 312.712831 -307.603443) (xy 312.664612 -307.593599)
			(xy 312.618596 -307.576147) (xy 312.575975 -307.55154) (xy 312.537854 -307.520415) (xy 312.505219 -307.483578)
			(xy 312.478916 -307.441982) (xy 312.459625 -307.396706) (xy 312.447848 -307.348922) (xy 312.443888 -307.299868)
			(xy 312.10504 -307.299868) (xy 312.104545 -307.324475) (xy 312.09665 -307.373052) (xy 312.081066 -307.419733)
			(xy 312.058195 -307.46331) (xy 312.02863 -307.502654) (xy 311.993137 -307.536746) (xy 311.952634 -307.564702)
			(xy 311.908172 -307.5858) (xy 311.860901 -307.599492) (xy 311.812046 -307.605424) (xy 311.762871 -307.603443)
			(xy 311.714652 -307.593599) (xy 311.668636 -307.576147) (xy 311.626015 -307.55154) (xy 311.587894 -307.520415)
			(xy 311.555259 -307.483578) (xy 311.528956 -307.441982) (xy 311.509665 -307.396706) (xy 311.497888 -307.348922)
			(xy 311.493928 -307.299868) (xy 248.902577 -307.299868) (xy 248.925005 -307.347712) (xy 248.941083 -307.401154)
			(xy 248.949209 -307.456368) (xy 248.949718 -307.484272) (xy 248.949209 -307.512176) (xy 248.941083 -307.56739)
			(xy 248.928951 -307.607716) (xy 462.556604 -307.607716) (xy 462.560677 -307.552057) (xy 462.572812 -307.497584)
			(xy 462.592748 -307.445458) (xy 462.620062 -307.39679) (xy 462.65417 -307.352618) (xy 462.694347 -307.313883)
			(xy 462.739735 -307.281411) (xy 462.789367 -307.255893) (xy 462.842187 -307.237874) (xy 462.897066 -307.227737)
			(xy 462.952837 -307.225699) (xy 463.008311 -307.231802) (xy 463.062304 -307.245918) (xy 463.113667 -307.267745)
			(xy 463.161305 -307.296818) (xy 463.204201 -307.332517) (xy 463.241443 -307.374081) (xy 463.272237 -307.420625)
			(xy 463.295925 -307.471156) (xy 463.312003 -307.524598) (xy 463.320129 -307.579812) (xy 463.320638 -307.607716)
			(xy 463.320129 -307.63562) (xy 463.312003 -307.690834) (xy 463.295925 -307.744276) (xy 463.272237 -307.794807)
			(xy 463.241443 -307.841351) (xy 463.204201 -307.882915) (xy 463.161305 -307.918614) (xy 463.113667 -307.947687)
			(xy 463.062304 -307.969514) (xy 463.008311 -307.98363) (xy 462.952837 -307.989733) (xy 462.897066 -307.987695)
			(xy 462.842187 -307.977558) (xy 462.789367 -307.959539) (xy 462.739735 -307.934021) (xy 462.694347 -307.901549)
			(xy 462.65417 -307.862814) (xy 462.620062 -307.818642) (xy 462.592748 -307.769974) (xy 462.572812 -307.717848)
			(xy 462.560677 -307.663375) (xy 462.556604 -307.607716) (xy 248.928951 -307.607716) (xy 248.925005 -307.620832)
			(xy 248.901317 -307.671363) (xy 248.870523 -307.717907) (xy 248.833281 -307.759471) (xy 248.790385 -307.79517)
			(xy 248.742747 -307.824243) (xy 248.691384 -307.84607) (xy 248.637391 -307.860186) (xy 248.581917 -307.866289)
			(xy 248.526146 -307.864251) (xy 248.471267 -307.854114) (xy 248.418447 -307.836095) (xy 248.368815 -307.810577)
			(xy 248.323427 -307.778105) (xy 248.28325 -307.73937) (xy 248.249142 -307.695198) (xy 248.221828 -307.64653)
			(xy 248.201892 -307.594404) (xy 248.189757 -307.539931) (xy 248.185684 -307.484272) (xy 232.69956 -307.484272)
			(xy 232.699051 -307.512176) (xy 232.690925 -307.56739) (xy 232.674847 -307.620832) (xy 232.651159 -307.671363)
			(xy 232.620365 -307.717907) (xy 232.583123 -307.759471) (xy 232.540227 -307.79517) (xy 232.492589 -307.824243)
			(xy 232.441226 -307.84607) (xy 232.387233 -307.860186) (xy 232.331759 -307.866289) (xy 232.275988 -307.864251)
			(xy 232.221109 -307.854114) (xy 232.168289 -307.836095) (xy 232.118657 -307.810577) (xy 232.073269 -307.778105)
			(xy 232.033092 -307.73937) (xy 231.998984 -307.695198) (xy 231.97167 -307.64653) (xy 231.951734 -307.594404)
			(xy 231.939599 -307.539931) (xy 231.935526 -307.484272) (xy 80.792461 -307.484272) (xy 80.778648 -307.502654)
			(xy 80.743155 -307.536746) (xy 80.702652 -307.564702) (xy 80.65819 -307.5858) (xy 80.610919 -307.599492)
			(xy 80.562064 -307.605424) (xy 80.512889 -307.603443) (xy 80.46467 -307.593599) (xy 80.418654 -307.576147)
			(xy 80.376033 -307.55154) (xy 80.337912 -307.520415) (xy 80.305277 -307.483578) (xy 80.278974 -307.441982)
			(xy 80.259683 -307.396706) (xy 80.247906 -307.348922) (xy 80.243946 -307.299868) (xy 79.905098 -307.299868)
			(xy 79.904603 -307.324475) (xy 79.896708 -307.373052) (xy 79.881124 -307.419733) (xy 79.858253 -307.46331)
			(xy 79.828688 -307.502654) (xy 79.793195 -307.536746) (xy 79.752692 -307.564702) (xy 79.70823 -307.5858)
			(xy 79.660959 -307.599492) (xy 79.612104 -307.605424) (xy 79.562929 -307.603443) (xy 79.51471 -307.593599)
			(xy 79.468694 -307.576147) (xy 79.426073 -307.55154) (xy 79.387952 -307.520415) (xy 79.355317 -307.483578)
			(xy 79.329014 -307.441982) (xy 79.309723 -307.396706) (xy 79.297946 -307.348922) (xy 79.293986 -307.299868)
			(xy 0.508 -307.299868) (xy 0.508 -308.249828) (xy 81.19416 -308.249828) (xy 81.19812 -308.200774)
			(xy 81.209897 -308.15299) (xy 81.229188 -308.107714) (xy 81.255491 -308.066118) (xy 81.288126 -308.029281)
			(xy 81.326247 -307.998156) (xy 81.368868 -307.973549) (xy 81.414884 -307.956097) (xy 81.463103 -307.946253)
			(xy 81.512278 -307.944272) (xy 81.561133 -307.950204) (xy 81.608404 -307.963896) (xy 81.652866 -307.984994)
			(xy 81.693369 -308.01295) (xy 81.728862 -308.047042) (xy 81.758427 -308.086386) (xy 81.781298 -308.129963)
			(xy 81.796882 -308.176644) (xy 81.804777 -308.225221) (xy 81.805272 -308.249828) (xy 82.14412 -308.249828)
			(xy 82.14808 -308.200774) (xy 82.159857 -308.15299) (xy 82.179148 -308.107714) (xy 82.205451 -308.066118)
			(xy 82.238086 -308.029281) (xy 82.276207 -307.998156) (xy 82.318828 -307.973549) (xy 82.364844 -307.956097)
			(xy 82.413063 -307.946253) (xy 82.462238 -307.944272) (xy 82.511093 -307.950204) (xy 82.558364 -307.963896)
			(xy 82.602826 -307.984994) (xy 82.643329 -308.01295) (xy 82.678822 -308.047042) (xy 82.708387 -308.086386)
			(xy 82.731258 -308.129963) (xy 82.746842 -308.176644) (xy 82.754737 -308.225221) (xy 82.755232 -308.249828)
			(xy 82.754737 -308.274435) (xy 82.746842 -308.323012) (xy 82.731258 -308.369693) (xy 82.708387 -308.41327)
			(xy 82.678822 -308.452614) (xy 82.643329 -308.486706) (xy 82.602826 -308.514662) (xy 82.558364 -308.53576)
			(xy 82.511093 -308.549452) (xy 82.462238 -308.555384) (xy 82.413063 -308.553403) (xy 82.364844 -308.543559)
			(xy 82.318828 -308.526107) (xy 82.276207 -308.5015) (xy 82.238086 -308.470375) (xy 82.205451 -308.433538)
			(xy 82.179148 -308.391942) (xy 82.159857 -308.346666) (xy 82.14808 -308.298882) (xy 82.14412 -308.249828)
			(xy 81.805272 -308.249828) (xy 81.804777 -308.274435) (xy 81.796882 -308.323012) (xy 81.781298 -308.369693)
			(xy 81.758427 -308.41327) (xy 81.728862 -308.452614) (xy 81.693369 -308.486706) (xy 81.652866 -308.514662)
			(xy 81.608404 -308.53576) (xy 81.561133 -308.549452) (xy 81.512278 -308.555384) (xy 81.463103 -308.553403)
			(xy 81.414884 -308.543559) (xy 81.368868 -308.526107) (xy 81.326247 -308.5015) (xy 81.288126 -308.470375)
			(xy 81.255491 -308.433538) (xy 81.229188 -308.391942) (xy 81.209897 -308.346666) (xy 81.19812 -308.298882)
			(xy 81.19416 -308.249828) (xy 0.508 -308.249828) (xy 0.508 -308.568852) (xy 231.935526 -308.568852)
			(xy 231.939599 -308.513193) (xy 231.951734 -308.45872) (xy 231.97167 -308.406594) (xy 231.998984 -308.357926)
			(xy 232.033092 -308.313754) (xy 232.073269 -308.275019) (xy 232.118657 -308.242547) (xy 232.168289 -308.217029)
			(xy 232.221109 -308.19901) (xy 232.275988 -308.188873) (xy 232.331759 -308.186835) (xy 232.387233 -308.192938)
			(xy 232.441226 -308.207054) (xy 232.492589 -308.228881) (xy 232.540227 -308.257954) (xy 232.583123 -308.293653)
			(xy 232.620365 -308.335217) (xy 232.651159 -308.381761) (xy 232.674847 -308.432292) (xy 232.690925 -308.485734)
			(xy 232.699051 -308.540948) (xy 232.69956 -308.568852) (xy 248.185684 -308.568852) (xy 248.189757 -308.513193)
			(xy 248.201892 -308.45872) (xy 248.221828 -308.406594) (xy 248.249142 -308.357926) (xy 248.28325 -308.313754)
			(xy 248.323427 -308.275019) (xy 248.368815 -308.242547) (xy 248.418447 -308.217029) (xy 248.471267 -308.19901)
			(xy 248.526146 -308.188873) (xy 248.581917 -308.186835) (xy 248.637391 -308.192938) (xy 248.691384 -308.207054)
			(xy 248.742747 -308.228881) (xy 248.77707 -308.249828) (xy 313.394102 -308.249828) (xy 313.398062 -308.200774)
			(xy 313.409839 -308.15299) (xy 313.42913 -308.107714) (xy 313.455433 -308.066118) (xy 313.488068 -308.029281)
			(xy 313.526189 -307.998156) (xy 313.56881 -307.973549) (xy 313.614826 -307.956097) (xy 313.663045 -307.946253)
			(xy 313.71222 -307.944272) (xy 313.761075 -307.950204) (xy 313.808346 -307.963896) (xy 313.852808 -307.984994)
			(xy 313.893311 -308.01295) (xy 313.928804 -308.047042) (xy 313.958369 -308.086386) (xy 313.98124 -308.129963)
			(xy 313.996824 -308.176644) (xy 314.004719 -308.225221) (xy 314.005214 -308.249828) (xy 314.344062 -308.249828)
			(xy 314.348022 -308.200774) (xy 314.359799 -308.15299) (xy 314.37909 -308.107714) (xy 314.405393 -308.066118)
			(xy 314.438028 -308.029281) (xy 314.476149 -307.998156) (xy 314.51877 -307.973549) (xy 314.564786 -307.956097)
			(xy 314.613005 -307.946253) (xy 314.66218 -307.944272) (xy 314.711035 -307.950204) (xy 314.758306 -307.963896)
			(xy 314.802768 -307.984994) (xy 314.843271 -308.01295) (xy 314.878764 -308.047042) (xy 314.908329 -308.086386)
			(xy 314.9312 -308.129963) (xy 314.946784 -308.176644) (xy 314.954679 -308.225221) (xy 314.955174 -308.249828)
			(xy 314.954679 -308.274435) (xy 314.946784 -308.323012) (xy 314.9312 -308.369693) (xy 314.908329 -308.41327)
			(xy 314.878764 -308.452614) (xy 314.843271 -308.486706) (xy 314.802768 -308.514662) (xy 314.758306 -308.53576)
			(xy 314.711035 -308.549452) (xy 314.66218 -308.555384) (xy 314.613005 -308.553403) (xy 314.564786 -308.543559)
			(xy 314.51877 -308.526107) (xy 314.476149 -308.5015) (xy 314.438028 -308.470375) (xy 314.405393 -308.433538)
			(xy 314.37909 -308.391942) (xy 314.359799 -308.346666) (xy 314.348022 -308.298882) (xy 314.344062 -308.249828)
			(xy 314.005214 -308.249828) (xy 314.004719 -308.274435) (xy 313.996824 -308.323012) (xy 313.98124 -308.369693)
			(xy 313.958369 -308.41327) (xy 313.928804 -308.452614) (xy 313.893311 -308.486706) (xy 313.852808 -308.514662)
			(xy 313.808346 -308.53576) (xy 313.761075 -308.549452) (xy 313.71222 -308.555384) (xy 313.663045 -308.553403)
			(xy 313.614826 -308.543559) (xy 313.56881 -308.526107) (xy 313.526189 -308.5015) (xy 313.488068 -308.470375)
			(xy 313.455433 -308.433538) (xy 313.42913 -308.391942) (xy 313.409839 -308.346666) (xy 313.398062 -308.298882)
			(xy 313.394102 -308.249828) (xy 248.77707 -308.249828) (xy 248.790385 -308.257954) (xy 248.833281 -308.293653)
			(xy 248.870523 -308.335217) (xy 248.901317 -308.381761) (xy 248.925005 -308.432292) (xy 248.941083 -308.485734)
			(xy 248.949209 -308.540948) (xy 248.949718 -308.568852) (xy 248.949209 -308.596756) (xy 248.941083 -308.65197)
			(xy 248.928951 -308.692296) (xy 462.556604 -308.692296) (xy 462.560677 -308.636637) (xy 462.572812 -308.582164)
			(xy 462.592748 -308.530038) (xy 462.620062 -308.48137) (xy 462.65417 -308.437198) (xy 462.694347 -308.398463)
			(xy 462.739735 -308.365991) (xy 462.789367 -308.340473) (xy 462.842187 -308.322454) (xy 462.897066 -308.312317)
			(xy 462.952837 -308.310279) (xy 463.008311 -308.316382) (xy 463.062304 -308.330498) (xy 463.113667 -308.352325)
			(xy 463.161305 -308.381398) (xy 463.204201 -308.417097) (xy 463.241443 -308.458661) (xy 463.272237 -308.505205)
			(xy 463.295925 -308.555736) (xy 463.312003 -308.609178) (xy 463.320129 -308.664392) (xy 463.320638 -308.692296)
			(xy 463.320129 -308.7202) (xy 463.312003 -308.775414) (xy 463.295925 -308.828856) (xy 463.272237 -308.879387)
			(xy 463.241443 -308.925931) (xy 463.204201 -308.967495) (xy 463.161305 -309.003194) (xy 463.113667 -309.032267)
			(xy 463.062304 -309.054094) (xy 463.008311 -309.06821) (xy 462.952837 -309.074313) (xy 462.897066 -309.072275)
			(xy 462.842187 -309.062138) (xy 462.789367 -309.044119) (xy 462.739735 -309.018601) (xy 462.694347 -308.986129)
			(xy 462.65417 -308.947394) (xy 462.620062 -308.903222) (xy 462.592748 -308.854554) (xy 462.572812 -308.802428)
			(xy 462.560677 -308.747955) (xy 462.556604 -308.692296) (xy 248.928951 -308.692296) (xy 248.925005 -308.705412)
			(xy 248.901317 -308.755943) (xy 248.870523 -308.802487) (xy 248.833281 -308.844051) (xy 248.790385 -308.87975)
			(xy 248.742747 -308.908823) (xy 248.691384 -308.93065) (xy 248.637391 -308.944766) (xy 248.581917 -308.950869)
			(xy 248.526146 -308.948831) (xy 248.471267 -308.938694) (xy 248.418447 -308.920675) (xy 248.368815 -308.895157)
			(xy 248.323427 -308.862685) (xy 248.28325 -308.82395) (xy 248.249142 -308.779778) (xy 248.221828 -308.73111)
			(xy 248.201892 -308.678984) (xy 248.189757 -308.624511) (xy 248.185684 -308.568852) (xy 232.69956 -308.568852)
			(xy 232.699051 -308.596756) (xy 232.690925 -308.65197) (xy 232.674847 -308.705412) (xy 232.651159 -308.755943)
			(xy 232.620365 -308.802487) (xy 232.583123 -308.844051) (xy 232.540227 -308.87975) (xy 232.492589 -308.908823)
			(xy 232.441226 -308.93065) (xy 232.387233 -308.944766) (xy 232.331759 -308.950869) (xy 232.275988 -308.948831)
			(xy 232.221109 -308.938694) (xy 232.168289 -308.920675) (xy 232.118657 -308.895157) (xy 232.073269 -308.862685)
			(xy 232.033092 -308.82395) (xy 231.998984 -308.779778) (xy 231.97167 -308.73111) (xy 231.951734 -308.678984)
			(xy 231.939599 -308.624511) (xy 231.935526 -308.568852) (xy 0.508 -308.568852) (xy 0.508 -309.199788)
			(xy 79.293986 -309.199788) (xy 79.297946 -309.150734) (xy 79.309723 -309.10295) (xy 79.329014 -309.057674)
			(xy 79.355317 -309.016078) (xy 79.387952 -308.979241) (xy 79.426073 -308.948116) (xy 79.468694 -308.923509)
			(xy 79.51471 -308.906057) (xy 79.562929 -308.896213) (xy 79.612104 -308.894232) (xy 79.660959 -308.900164)
			(xy 79.70823 -308.913856) (xy 79.752692 -308.934954) (xy 79.793195 -308.96291) (xy 79.828688 -308.997002)
			(xy 79.858253 -309.036346) (xy 79.881124 -309.079923) (xy 79.896708 -309.126604) (xy 79.904603 -309.175181)
			(xy 79.905098 -309.199788) (xy 80.243946 -309.199788) (xy 80.247906 -309.150734) (xy 80.259683 -309.10295)
			(xy 80.278974 -309.057674) (xy 80.305277 -309.016078) (xy 80.337912 -308.979241) (xy 80.376033 -308.948116)
			(xy 80.418654 -308.923509) (xy 80.46467 -308.906057) (xy 80.512889 -308.896213) (xy 80.562064 -308.894232)
			(xy 80.610919 -308.900164) (xy 80.65819 -308.913856) (xy 80.702652 -308.934954) (xy 80.743155 -308.96291)
			(xy 80.778648 -308.997002) (xy 80.808213 -309.036346) (xy 80.831084 -309.079923) (xy 80.846668 -309.126604)
			(xy 80.854563 -309.175181) (xy 80.855058 -309.199788) (xy 311.493928 -309.199788) (xy 311.497888 -309.150734)
			(xy 311.509665 -309.10295) (xy 311.528956 -309.057674) (xy 311.555259 -309.016078) (xy 311.587894 -308.979241)
			(xy 311.626015 -308.948116) (xy 311.668636 -308.923509) (xy 311.714652 -308.906057) (xy 311.762871 -308.896213)
			(xy 311.812046 -308.894232) (xy 311.860901 -308.900164) (xy 311.908172 -308.913856) (xy 311.952634 -308.934954)
			(xy 311.993137 -308.96291) (xy 312.02863 -308.997002) (xy 312.058195 -309.036346) (xy 312.081066 -309.079923)
			(xy 312.09665 -309.126604) (xy 312.104545 -309.175181) (xy 312.10504 -309.199788) (xy 312.443888 -309.199788)
			(xy 312.447848 -309.150734) (xy 312.459625 -309.10295) (xy 312.478916 -309.057674) (xy 312.505219 -309.016078)
			(xy 312.537854 -308.979241) (xy 312.575975 -308.948116) (xy 312.618596 -308.923509) (xy 312.664612 -308.906057)
			(xy 312.712831 -308.896213) (xy 312.762006 -308.894232) (xy 312.810861 -308.900164) (xy 312.858132 -308.913856)
			(xy 312.902594 -308.934954) (xy 312.943097 -308.96291) (xy 312.97859 -308.997002) (xy 313.008155 -309.036346)
			(xy 313.031026 -309.079923) (xy 313.04661 -309.126604) (xy 313.054505 -309.175181) (xy 313.055 -309.199788)
			(xy 313.054505 -309.224395) (xy 313.04661 -309.272972) (xy 313.031026 -309.319653) (xy 313.008155 -309.36323)
			(xy 312.97859 -309.402574) (xy 312.943097 -309.436666) (xy 312.902594 -309.464622) (xy 312.858132 -309.48572)
			(xy 312.810861 -309.499412) (xy 312.762006 -309.505344) (xy 312.712831 -309.503363) (xy 312.664612 -309.493519)
			(xy 312.618596 -309.476067) (xy 312.575975 -309.45146) (xy 312.537854 -309.420335) (xy 312.505219 -309.383498)
			(xy 312.478916 -309.341902) (xy 312.459625 -309.296626) (xy 312.447848 -309.248842) (xy 312.443888 -309.199788)
			(xy 312.10504 -309.199788) (xy 312.104545 -309.224395) (xy 312.09665 -309.272972) (xy 312.081066 -309.319653)
			(xy 312.058195 -309.36323) (xy 312.02863 -309.402574) (xy 311.993137 -309.436666) (xy 311.952634 -309.464622)
			(xy 311.908172 -309.48572) (xy 311.860901 -309.499412) (xy 311.812046 -309.505344) (xy 311.762871 -309.503363)
			(xy 311.714652 -309.493519) (xy 311.668636 -309.476067) (xy 311.626015 -309.45146) (xy 311.587894 -309.420335)
			(xy 311.555259 -309.383498) (xy 311.528956 -309.341902) (xy 311.509665 -309.296626) (xy 311.497888 -309.248842)
			(xy 311.493928 -309.199788) (xy 80.855058 -309.199788) (xy 80.854563 -309.224395) (xy 80.846668 -309.272972)
			(xy 80.831084 -309.319653) (xy 80.808213 -309.36323) (xy 80.778648 -309.402574) (xy 80.743155 -309.436666)
			(xy 80.702652 -309.464622) (xy 80.65819 -309.48572) (xy 80.610919 -309.499412) (xy 80.562064 -309.505344)
			(xy 80.512889 -309.503363) (xy 80.46467 -309.493519) (xy 80.418654 -309.476067) (xy 80.376033 -309.45146)
			(xy 80.337912 -309.420335) (xy 80.305277 -309.383498) (xy 80.278974 -309.341902) (xy 80.259683 -309.296626)
			(xy 80.247906 -309.248842) (xy 80.243946 -309.199788) (xy 79.905098 -309.199788) (xy 79.904603 -309.224395)
			(xy 79.896708 -309.272972) (xy 79.881124 -309.319653) (xy 79.858253 -309.36323) (xy 79.828688 -309.402574)
			(xy 79.793195 -309.436666) (xy 79.752692 -309.464622) (xy 79.70823 -309.48572) (xy 79.660959 -309.499412)
			(xy 79.612104 -309.505344) (xy 79.562929 -309.503363) (xy 79.51471 -309.493519) (xy 79.468694 -309.476067)
			(xy 79.426073 -309.45146) (xy 79.387952 -309.420335) (xy 79.355317 -309.383498) (xy 79.329014 -309.341902)
			(xy 79.309723 -309.296626) (xy 79.297946 -309.248842) (xy 79.293986 -309.199788) (xy 0.508 -309.199788)
			(xy 0.508 -310.149748) (xy 81.19416 -310.149748) (xy 81.19812 -310.100694) (xy 81.209897 -310.05291)
			(xy 81.229188 -310.007634) (xy 81.255491 -309.966038) (xy 81.288126 -309.929201) (xy 81.326247 -309.898076)
			(xy 81.368868 -309.873469) (xy 81.414884 -309.856017) (xy 81.463103 -309.846173) (xy 81.512278 -309.844192)
			(xy 81.561133 -309.850124) (xy 81.608404 -309.863816) (xy 81.652866 -309.884914) (xy 81.693369 -309.91287)
			(xy 81.728862 -309.946962) (xy 81.758427 -309.986306) (xy 81.781298 -310.029883) (xy 81.796882 -310.076564)
			(xy 81.804777 -310.125141) (xy 81.805272 -310.149748) (xy 82.14412 -310.149748) (xy 82.14808 -310.100694)
			(xy 82.159857 -310.05291) (xy 82.179148 -310.007634) (xy 82.205451 -309.966038) (xy 82.238086 -309.929201)
			(xy 82.276207 -309.898076) (xy 82.318828 -309.873469) (xy 82.364844 -309.856017) (xy 82.413063 -309.846173)
			(xy 82.462238 -309.844192) (xy 82.511093 -309.850124) (xy 82.558364 -309.863816) (xy 82.602826 -309.884914)
			(xy 82.643329 -309.91287) (xy 82.678822 -309.946962) (xy 82.708387 -309.986306) (xy 82.731258 -310.029883)
			(xy 82.746842 -310.076564) (xy 82.754737 -310.125141) (xy 82.755232 -310.149748) (xy 313.394102 -310.149748)
			(xy 313.398062 -310.100694) (xy 313.409839 -310.05291) (xy 313.42913 -310.007634) (xy 313.455433 -309.966038)
			(xy 313.488068 -309.929201) (xy 313.526189 -309.898076) (xy 313.56881 -309.873469) (xy 313.614826 -309.856017)
			(xy 313.663045 -309.846173) (xy 313.71222 -309.844192) (xy 313.761075 -309.850124) (xy 313.808346 -309.863816)
			(xy 313.852808 -309.884914) (xy 313.893311 -309.91287) (xy 313.928804 -309.946962) (xy 313.958369 -309.986306)
			(xy 313.98124 -310.029883) (xy 313.996824 -310.076564) (xy 314.004719 -310.125141) (xy 314.005214 -310.149748)
			(xy 314.344062 -310.149748) (xy 314.348022 -310.100694) (xy 314.359799 -310.05291) (xy 314.37909 -310.007634)
			(xy 314.405393 -309.966038) (xy 314.438028 -309.929201) (xy 314.476149 -309.898076) (xy 314.51877 -309.873469)
			(xy 314.564786 -309.856017) (xy 314.613005 -309.846173) (xy 314.66218 -309.844192) (xy 314.711035 -309.850124)
			(xy 314.758306 -309.863816) (xy 314.802768 -309.884914) (xy 314.843271 -309.91287) (xy 314.878764 -309.946962)
			(xy 314.908329 -309.986306) (xy 314.9312 -310.029883) (xy 314.946784 -310.076564) (xy 314.954679 -310.125141)
			(xy 314.955174 -310.149748) (xy 314.954679 -310.174355) (xy 314.946784 -310.222932) (xy 314.9312 -310.269613)
			(xy 314.908329 -310.31319) (xy 314.878764 -310.352534) (xy 314.843271 -310.386626) (xy 314.802768 -310.414582)
			(xy 314.758306 -310.43568) (xy 314.711035 -310.449372) (xy 314.66218 -310.455304) (xy 314.613005 -310.453323)
			(xy 314.564786 -310.443479) (xy 314.51877 -310.426027) (xy 314.476149 -310.40142) (xy 314.438028 -310.370295)
			(xy 314.405393 -310.333458) (xy 314.37909 -310.291862) (xy 314.359799 -310.246586) (xy 314.348022 -310.198802)
			(xy 314.344062 -310.149748) (xy 314.005214 -310.149748) (xy 314.004719 -310.174355) (xy 313.996824 -310.222932)
			(xy 313.98124 -310.269613) (xy 313.958369 -310.31319) (xy 313.928804 -310.352534) (xy 313.893311 -310.386626)
			(xy 313.852808 -310.414582) (xy 313.808346 -310.43568) (xy 313.761075 -310.449372) (xy 313.71222 -310.455304)
			(xy 313.663045 -310.453323) (xy 313.614826 -310.443479) (xy 313.56881 -310.426027) (xy 313.526189 -310.40142)
			(xy 313.488068 -310.370295) (xy 313.455433 -310.333458) (xy 313.42913 -310.291862) (xy 313.409839 -310.246586)
			(xy 313.398062 -310.198802) (xy 313.394102 -310.149748) (xy 82.755232 -310.149748) (xy 82.754737 -310.174355)
			(xy 82.746842 -310.222932) (xy 82.731258 -310.269613) (xy 82.708387 -310.31319) (xy 82.678822 -310.352534)
			(xy 82.643329 -310.386626) (xy 82.602826 -310.414582) (xy 82.558364 -310.43568) (xy 82.511093 -310.449372)
			(xy 82.462238 -310.455304) (xy 82.413063 -310.453323) (xy 82.364844 -310.443479) (xy 82.318828 -310.426027)
			(xy 82.276207 -310.40142) (xy 82.238086 -310.370295) (xy 82.205451 -310.333458) (xy 82.179148 -310.291862)
			(xy 82.159857 -310.246586) (xy 82.14808 -310.198802) (xy 82.14412 -310.149748) (xy 81.805272 -310.149748)
			(xy 81.804777 -310.174355) (xy 81.796882 -310.222932) (xy 81.781298 -310.269613) (xy 81.758427 -310.31319)
			(xy 81.728862 -310.352534) (xy 81.693369 -310.386626) (xy 81.652866 -310.414582) (xy 81.608404 -310.43568)
			(xy 81.561133 -310.449372) (xy 81.512278 -310.455304) (xy 81.463103 -310.453323) (xy 81.414884 -310.443479)
			(xy 81.368868 -310.426027) (xy 81.326247 -310.40142) (xy 81.288126 -310.370295) (xy 81.255491 -310.333458)
			(xy 81.229188 -310.291862) (xy 81.209897 -310.246586) (xy 81.19812 -310.198802) (xy 81.19416 -310.149748)
			(xy 0.508 -310.149748) (xy 0.508 -311.099962) (xy 43.193982 -311.099962) (xy 43.197942 -311.050908)
			(xy 43.209719 -311.003124) (xy 43.22901 -310.957848) (xy 43.255313 -310.916252) (xy 43.287948 -310.879415)
			(xy 43.326069 -310.84829) (xy 43.36869 -310.823683) (xy 43.414706 -310.806231) (xy 43.462925 -310.796387)
			(xy 43.5121 -310.794406) (xy 43.560955 -310.800338) (xy 43.608226 -310.81403) (xy 43.652688 -310.835128)
			(xy 43.693191 -310.863084) (xy 43.728684 -310.897176) (xy 43.758249 -310.93652) (xy 43.78112 -310.980097)
			(xy 43.796704 -311.026778) (xy 43.804599 -311.075355) (xy 43.805094 -311.099962) (xy 45.094156 -311.099962)
			(xy 45.098116 -311.050908) (xy 45.109893 -311.003124) (xy 45.129184 -310.957848) (xy 45.155487 -310.916252)
			(xy 45.188122 -310.879415) (xy 45.226243 -310.84829) (xy 45.268864 -310.823683) (xy 45.31488 -310.806231)
			(xy 45.363099 -310.796387) (xy 45.412274 -310.794406) (xy 45.461129 -310.800338) (xy 45.5084 -310.81403)
			(xy 45.552862 -310.835128) (xy 45.593365 -310.863084) (xy 45.628858 -310.897176) (xy 45.658423 -310.93652)
			(xy 45.681294 -310.980097) (xy 45.696878 -311.026778) (xy 45.704773 -311.075355) (xy 45.705268 -311.099962)
			(xy 46.994076 -311.099962) (xy 46.998036 -311.050908) (xy 47.009813 -311.003124) (xy 47.029104 -310.957848)
			(xy 47.055407 -310.916252) (xy 47.088042 -310.879415) (xy 47.126163 -310.84829) (xy 47.168784 -310.823683)
			(xy 47.2148 -310.806231) (xy 47.263019 -310.796387) (xy 47.312194 -310.794406) (xy 47.361049 -310.800338)
			(xy 47.40832 -310.81403) (xy 47.452782 -310.835128) (xy 47.493285 -310.863084) (xy 47.528778 -310.897176)
			(xy 47.558343 -310.93652) (xy 47.581214 -310.980097) (xy 47.596798 -311.026778) (xy 47.604693 -311.075355)
			(xy 47.605188 -311.099962) (xy 48.893996 -311.099962) (xy 48.897956 -311.050908) (xy 48.909733 -311.003124)
			(xy 48.929024 -310.957848) (xy 48.955327 -310.916252) (xy 48.987962 -310.879415) (xy 49.026083 -310.84829)
			(xy 49.068704 -310.823683) (xy 49.11472 -310.806231) (xy 49.162939 -310.796387) (xy 49.212114 -310.794406)
			(xy 49.260969 -310.800338) (xy 49.30824 -310.81403) (xy 49.352702 -310.835128) (xy 49.393205 -310.863084)
			(xy 49.428698 -310.897176) (xy 49.458263 -310.93652) (xy 49.481134 -310.980097) (xy 49.496718 -311.026778)
			(xy 49.504613 -311.075355) (xy 49.505108 -311.099962) (xy 50.79417 -311.099962) (xy 50.79813 -311.050908)
			(xy 50.809907 -311.003124) (xy 50.829198 -310.957848) (xy 50.855501 -310.916252) (xy 50.888136 -310.879415)
			(xy 50.926257 -310.84829) (xy 50.968878 -310.823683) (xy 51.014894 -310.806231) (xy 51.063113 -310.796387)
			(xy 51.112288 -310.794406) (xy 51.161143 -310.800338) (xy 51.208414 -310.81403) (xy 51.252876 -310.835128)
			(xy 51.293379 -310.863084) (xy 51.328872 -310.897176) (xy 51.358437 -310.93652) (xy 51.381308 -310.980097)
			(xy 51.396892 -311.026778) (xy 51.404787 -311.075355) (xy 51.405282 -311.099962) (xy 52.69409 -311.099962)
			(xy 52.69805 -311.050908) (xy 52.709827 -311.003124) (xy 52.729118 -310.957848) (xy 52.755421 -310.916252)
			(xy 52.788056 -310.879415) (xy 52.826177 -310.84829) (xy 52.868798 -310.823683) (xy 52.914814 -310.806231)
			(xy 52.963033 -310.796387) (xy 53.012208 -310.794406) (xy 53.061063 -310.800338) (xy 53.108334 -310.81403)
			(xy 53.152796 -310.835128) (xy 53.193299 -310.863084) (xy 53.228792 -310.897176) (xy 53.258357 -310.93652)
			(xy 53.281228 -310.980097) (xy 53.296812 -311.026778) (xy 53.304707 -311.075355) (xy 53.305202 -311.099962)
			(xy 54.59401 -311.099962) (xy 54.59797 -311.050908) (xy 54.609747 -311.003124) (xy 54.629038 -310.957848)
			(xy 54.655341 -310.916252) (xy 54.687976 -310.879415) (xy 54.726097 -310.84829) (xy 54.768718 -310.823683)
			(xy 54.814734 -310.806231) (xy 54.862953 -310.796387) (xy 54.912128 -310.794406) (xy 54.960983 -310.800338)
			(xy 55.008254 -310.81403) (xy 55.052716 -310.835128) (xy 55.093219 -310.863084) (xy 55.128712 -310.897176)
			(xy 55.158277 -310.93652) (xy 55.181148 -310.980097) (xy 55.196732 -311.026778) (xy 55.204627 -311.075355)
			(xy 55.205122 -311.099962) (xy 56.494184 -311.099962) (xy 56.498144 -311.050908) (xy 56.509921 -311.003124)
			(xy 56.529212 -310.957848) (xy 56.555515 -310.916252) (xy 56.58815 -310.879415) (xy 56.626271 -310.84829)
			(xy 56.668892 -310.823683) (xy 56.714908 -310.806231) (xy 56.763127 -310.796387) (xy 56.812302 -310.794406)
			(xy 56.861157 -310.800338) (xy 56.908428 -310.81403) (xy 56.95289 -310.835128) (xy 56.993393 -310.863084)
			(xy 57.028886 -310.897176) (xy 57.058451 -310.93652) (xy 57.081322 -310.980097) (xy 57.096906 -311.026778)
			(xy 57.104801 -311.075355) (xy 57.105296 -311.099962) (xy 159.29408 -311.099962) (xy 159.29804 -311.050908)
			(xy 159.309817 -311.003124) (xy 159.329108 -310.957848) (xy 159.355411 -310.916252) (xy 159.388046 -310.879415)
			(xy 159.426167 -310.84829) (xy 159.468788 -310.823683) (xy 159.514804 -310.806231) (xy 159.563023 -310.796387)
			(xy 159.612198 -310.794406) (xy 159.661053 -310.800338) (xy 159.708324 -310.81403) (xy 159.752786 -310.835128)
			(xy 159.793289 -310.863084) (xy 159.828782 -310.897176) (xy 159.858347 -310.93652) (xy 159.881218 -310.980097)
			(xy 159.896802 -311.026778) (xy 159.904697 -311.075355) (xy 159.905192 -311.099962) (xy 161.194254 -311.099962)
			(xy 161.198214 -311.050908) (xy 161.209991 -311.003124) (xy 161.229282 -310.957848) (xy 161.255585 -310.916252)
			(xy 161.28822 -310.879415) (xy 161.326341 -310.84829) (xy 161.368962 -310.823683) (xy 161.414978 -310.806231)
			(xy 161.463197 -310.796387) (xy 161.512372 -310.794406) (xy 161.561227 -310.800338) (xy 161.608498 -310.81403)
			(xy 161.65296 -310.835128) (xy 161.693463 -310.863084) (xy 161.728956 -310.897176) (xy 161.758521 -310.93652)
			(xy 161.781392 -310.980097) (xy 161.796976 -311.026778) (xy 161.804871 -311.075355) (xy 161.805366 -311.099962)
			(xy 163.094174 -311.099962) (xy 163.098134 -311.050908) (xy 163.109911 -311.003124) (xy 163.129202 -310.957848)
			(xy 163.155505 -310.916252) (xy 163.18814 -310.879415) (xy 163.226261 -310.84829) (xy 163.268882 -310.823683)
			(xy 163.314898 -310.806231) (xy 163.363117 -310.796387) (xy 163.412292 -310.794406) (xy 163.461147 -310.800338)
			(xy 163.508418 -310.81403) (xy 163.55288 -310.835128) (xy 163.593383 -310.863084) (xy 163.628876 -310.897176)
			(xy 163.658441 -310.93652) (xy 163.681312 -310.980097) (xy 163.696896 -311.026778) (xy 163.704791 -311.075355)
			(xy 163.705286 -311.099962) (xy 164.994094 -311.099962) (xy 164.998054 -311.050908) (xy 165.009831 -311.003124)
			(xy 165.029122 -310.957848) (xy 165.055425 -310.916252) (xy 165.08806 -310.879415) (xy 165.126181 -310.84829)
			(xy 165.168802 -310.823683) (xy 165.214818 -310.806231) (xy 165.263037 -310.796387) (xy 165.312212 -310.794406)
			(xy 165.361067 -310.800338) (xy 165.408338 -310.81403) (xy 165.4528 -310.835128) (xy 165.493303 -310.863084)
			(xy 165.528796 -310.897176) (xy 165.558361 -310.93652) (xy 165.581232 -310.980097) (xy 165.596816 -311.026778)
			(xy 165.604711 -311.075355) (xy 165.605206 -311.099962) (xy 182.094136 -311.099962) (xy 182.098096 -311.050908)
			(xy 182.109873 -311.003124) (xy 182.129164 -310.957848) (xy 182.155467 -310.916252) (xy 182.188102 -310.879415)
			(xy 182.226223 -310.84829) (xy 182.268844 -310.823683) (xy 182.31486 -310.806231) (xy 182.363079 -310.796387)
			(xy 182.412254 -310.794406) (xy 182.461109 -310.800338) (xy 182.50838 -310.81403) (xy 182.552842 -310.835128)
			(xy 182.593345 -310.863084) (xy 182.628838 -310.897176) (xy 182.658403 -310.93652) (xy 182.681274 -310.980097)
			(xy 182.696858 -311.026778) (xy 182.704753 -311.075355) (xy 182.705248 -311.099962) (xy 183.994056 -311.099962)
			(xy 183.998016 -311.050908) (xy 184.009793 -311.003124) (xy 184.029084 -310.957848) (xy 184.055387 -310.916252)
			(xy 184.088022 -310.879415) (xy 184.126143 -310.84829) (xy 184.168764 -310.823683) (xy 184.21478 -310.806231)
			(xy 184.262999 -310.796387) (xy 184.312174 -310.794406) (xy 184.361029 -310.800338) (xy 184.4083 -310.81403)
			(xy 184.452762 -310.835128) (xy 184.493265 -310.863084) (xy 184.528758 -310.897176) (xy 184.558323 -310.93652)
			(xy 184.581194 -310.980097) (xy 184.596778 -311.026778) (xy 184.604673 -311.075355) (xy 184.605168 -311.099962)
			(xy 185.89423 -311.099962) (xy 185.89819 -311.050908) (xy 185.909967 -311.003124) (xy 185.929258 -310.957848)
			(xy 185.955561 -310.916252) (xy 185.988196 -310.879415) (xy 186.026317 -310.84829) (xy 186.068938 -310.823683)
			(xy 186.114954 -310.806231) (xy 186.163173 -310.796387) (xy 186.212348 -310.794406) (xy 186.261203 -310.800338)
			(xy 186.308474 -310.81403) (xy 186.352936 -310.835128) (xy 186.393439 -310.863084) (xy 186.428932 -310.897176)
			(xy 186.458497 -310.93652) (xy 186.481368 -310.980097) (xy 186.496952 -311.026778) (xy 186.504847 -311.075355)
			(xy 186.505342 -311.099962) (xy 187.79415 -311.099962) (xy 187.79811 -311.050908) (xy 187.809887 -311.003124)
			(xy 187.829178 -310.957848) (xy 187.855481 -310.916252) (xy 187.888116 -310.879415) (xy 187.926237 -310.84829)
			(xy 187.968858 -310.823683) (xy 188.014874 -310.806231) (xy 188.063093 -310.796387) (xy 188.112268 -310.794406)
			(xy 188.161123 -310.800338) (xy 188.208394 -310.81403) (xy 188.252856 -310.835128) (xy 188.293359 -310.863084)
			(xy 188.328852 -310.897176) (xy 188.358417 -310.93652) (xy 188.381288 -310.980097) (xy 188.396872 -311.026778)
			(xy 188.404767 -311.075355) (xy 188.405262 -311.099962) (xy 275.393924 -311.099962) (xy 275.397884 -311.050908)
			(xy 275.409661 -311.003124) (xy 275.428952 -310.957848) (xy 275.455255 -310.916252) (xy 275.48789 -310.879415)
			(xy 275.526011 -310.84829) (xy 275.568632 -310.823683) (xy 275.614648 -310.806231) (xy 275.662867 -310.796387)
			(xy 275.712042 -310.794406) (xy 275.760897 -310.800338) (xy 275.808168 -310.81403) (xy 275.85263 -310.835128)
			(xy 275.893133 -310.863084) (xy 275.928626 -310.897176) (xy 275.958191 -310.93652) (xy 275.981062 -310.980097)
			(xy 275.996646 -311.026778) (xy 276.004541 -311.075355) (xy 276.005036 -311.099962) (xy 277.294098 -311.099962)
			(xy 277.298058 -311.050908) (xy 277.309835 -311.003124) (xy 277.329126 -310.957848) (xy 277.355429 -310.916252)
			(xy 277.388064 -310.879415) (xy 277.426185 -310.84829) (xy 277.468806 -310.823683) (xy 277.514822 -310.806231)
			(xy 277.563041 -310.796387) (xy 277.612216 -310.794406) (xy 277.661071 -310.800338) (xy 277.708342 -310.81403)
			(xy 277.752804 -310.835128) (xy 277.793307 -310.863084) (xy 277.8288 -310.897176) (xy 277.858365 -310.93652)
			(xy 277.881236 -310.980097) (xy 277.89682 -311.026778) (xy 277.904715 -311.075355) (xy 277.90521 -311.099962)
			(xy 279.194018 -311.099962) (xy 279.197978 -311.050908) (xy 279.209755 -311.003124) (xy 279.229046 -310.957848)
			(xy 279.255349 -310.916252) (xy 279.287984 -310.879415) (xy 279.326105 -310.84829) (xy 279.368726 -310.823683)
			(xy 279.414742 -310.806231) (xy 279.462961 -310.796387) (xy 279.512136 -310.794406) (xy 279.560991 -310.800338)
			(xy 279.608262 -310.81403) (xy 279.652724 -310.835128) (xy 279.693227 -310.863084) (xy 279.72872 -310.897176)
			(xy 279.758285 -310.93652) (xy 279.781156 -310.980097) (xy 279.79674 -311.026778) (xy 279.804635 -311.075355)
			(xy 279.80513 -311.099962) (xy 281.093938 -311.099962) (xy 281.097898 -311.050908) (xy 281.109675 -311.003124)
			(xy 281.128966 -310.957848) (xy 281.155269 -310.916252) (xy 281.187904 -310.879415) (xy 281.226025 -310.84829)
			(xy 281.268646 -310.823683) (xy 281.314662 -310.806231) (xy 281.362881 -310.796387) (xy 281.412056 -310.794406)
			(xy 281.460911 -310.800338) (xy 281.508182 -310.81403) (xy 281.552644 -310.835128) (xy 281.593147 -310.863084)
			(xy 281.62864 -310.897176) (xy 281.658205 -310.93652) (xy 281.681076 -310.980097) (xy 281.69666 -311.026778)
			(xy 281.704555 -311.075355) (xy 281.70505 -311.099962) (xy 282.994112 -311.099962) (xy 282.998072 -311.050908)
			(xy 283.009849 -311.003124) (xy 283.02914 -310.957848) (xy 283.055443 -310.916252) (xy 283.088078 -310.879415)
			(xy 283.126199 -310.84829) (xy 283.16882 -310.823683) (xy 283.214836 -310.806231) (xy 283.263055 -310.796387)
			(xy 283.31223 -310.794406) (xy 283.361085 -310.800338) (xy 283.408356 -310.81403) (xy 283.452818 -310.835128)
			(xy 283.493321 -310.863084) (xy 283.528814 -310.897176) (xy 283.558379 -310.93652) (xy 283.58125 -310.980097)
			(xy 283.596834 -311.026778) (xy 283.604729 -311.075355) (xy 283.605224 -311.099962) (xy 284.894032 -311.099962)
			(xy 284.897992 -311.050908) (xy 284.909769 -311.003124) (xy 284.92906 -310.957848) (xy 284.955363 -310.916252)
			(xy 284.987998 -310.879415) (xy 285.026119 -310.84829) (xy 285.06874 -310.823683) (xy 285.114756 -310.806231)
			(xy 285.162975 -310.796387) (xy 285.21215 -310.794406) (xy 285.261005 -310.800338) (xy 285.308276 -310.81403)
			(xy 285.352738 -310.835128) (xy 285.393241 -310.863084) (xy 285.428734 -310.897176) (xy 285.458299 -310.93652)
			(xy 285.48117 -310.980097) (xy 285.496754 -311.026778) (xy 285.504649 -311.075355) (xy 285.505144 -311.099962)
			(xy 286.793952 -311.099962) (xy 286.797912 -311.050908) (xy 286.809689 -311.003124) (xy 286.82898 -310.957848)
			(xy 286.855283 -310.916252) (xy 286.887918 -310.879415) (xy 286.926039 -310.84829) (xy 286.96866 -310.823683)
			(xy 287.014676 -310.806231) (xy 287.062895 -310.796387) (xy 287.11207 -310.794406) (xy 287.160925 -310.800338)
			(xy 287.208196 -310.81403) (xy 287.252658 -310.835128) (xy 287.293161 -310.863084) (xy 287.328654 -310.897176)
			(xy 287.358219 -310.93652) (xy 287.38109 -310.980097) (xy 287.396674 -311.026778) (xy 287.404569 -311.075355)
			(xy 287.405064 -311.099962) (xy 288.694126 -311.099962) (xy 288.698086 -311.050908) (xy 288.709863 -311.003124)
			(xy 288.729154 -310.957848) (xy 288.755457 -310.916252) (xy 288.788092 -310.879415) (xy 288.826213 -310.84829)
			(xy 288.868834 -310.823683) (xy 288.91485 -310.806231) (xy 288.963069 -310.796387) (xy 289.012244 -310.794406)
			(xy 289.061099 -310.800338) (xy 289.10837 -310.81403) (xy 289.152832 -310.835128) (xy 289.193335 -310.863084)
			(xy 289.228828 -310.897176) (xy 289.258393 -310.93652) (xy 289.281264 -310.980097) (xy 289.296848 -311.026778)
			(xy 289.304743 -311.075355) (xy 289.305238 -311.099962) (xy 391.494022 -311.099962) (xy 391.497982 -311.050908)
			(xy 391.509759 -311.003124) (xy 391.52905 -310.957848) (xy 391.555353 -310.916252) (xy 391.587988 -310.879415)
			(xy 391.626109 -310.84829) (xy 391.66873 -310.823683) (xy 391.714746 -310.806231) (xy 391.762965 -310.796387)
			(xy 391.81214 -310.794406) (xy 391.860995 -310.800338) (xy 391.908266 -310.81403) (xy 391.952728 -310.835128)
			(xy 391.993231 -310.863084) (xy 392.028724 -310.897176) (xy 392.058289 -310.93652) (xy 392.08116 -310.980097)
			(xy 392.096744 -311.026778) (xy 392.104639 -311.075355) (xy 392.105134 -311.099962) (xy 393.394196 -311.099962)
			(xy 393.398156 -311.050908) (xy 393.409933 -311.003124) (xy 393.429224 -310.957848) (xy 393.455527 -310.916252)
			(xy 393.488162 -310.879415) (xy 393.526283 -310.84829) (xy 393.568904 -310.823683) (xy 393.61492 -310.806231)
			(xy 393.663139 -310.796387) (xy 393.712314 -310.794406) (xy 393.761169 -310.800338) (xy 393.80844 -310.81403)
			(xy 393.852902 -310.835128) (xy 393.893405 -310.863084) (xy 393.928898 -310.897176) (xy 393.958463 -310.93652)
			(xy 393.981334 -310.980097) (xy 393.996918 -311.026778) (xy 394.004813 -311.075355) (xy 394.005308 -311.099962)
			(xy 395.294116 -311.099962) (xy 395.298076 -311.050908) (xy 395.309853 -311.003124) (xy 395.329144 -310.957848)
			(xy 395.355447 -310.916252) (xy 395.388082 -310.879415) (xy 395.426203 -310.84829) (xy 395.468824 -310.823683)
			(xy 395.51484 -310.806231) (xy 395.563059 -310.796387) (xy 395.612234 -310.794406) (xy 395.661089 -310.800338)
			(xy 395.70836 -310.81403) (xy 395.752822 -310.835128) (xy 395.793325 -310.863084) (xy 395.828818 -310.897176)
			(xy 395.858383 -310.93652) (xy 395.881254 -310.980097) (xy 395.896838 -311.026778) (xy 395.904733 -311.075355)
			(xy 395.905228 -311.099962) (xy 397.194036 -311.099962) (xy 397.197996 -311.050908) (xy 397.209773 -311.003124)
			(xy 397.229064 -310.957848) (xy 397.255367 -310.916252) (xy 397.288002 -310.879415) (xy 397.326123 -310.84829)
			(xy 397.368744 -310.823683) (xy 397.41476 -310.806231) (xy 397.462979 -310.796387) (xy 397.512154 -310.794406)
			(xy 397.561009 -310.800338) (xy 397.60828 -310.81403) (xy 397.652742 -310.835128) (xy 397.693245 -310.863084)
			(xy 397.728738 -310.897176) (xy 397.758303 -310.93652) (xy 397.781174 -310.980097) (xy 397.796758 -311.026778)
			(xy 397.804653 -311.075355) (xy 397.805148 -311.099962) (xy 414.294078 -311.099962) (xy 414.298038 -311.050908)
			(xy 414.309815 -311.003124) (xy 414.329106 -310.957848) (xy 414.355409 -310.916252) (xy 414.388044 -310.879415)
			(xy 414.426165 -310.84829) (xy 414.468786 -310.823683) (xy 414.514802 -310.806231) (xy 414.563021 -310.796387)
			(xy 414.612196 -310.794406) (xy 414.661051 -310.800338) (xy 414.708322 -310.81403) (xy 414.752784 -310.835128)
			(xy 414.793287 -310.863084) (xy 414.82878 -310.897176) (xy 414.858345 -310.93652) (xy 414.881216 -310.980097)
			(xy 414.8968 -311.026778) (xy 414.904695 -311.075355) (xy 414.90519 -311.099962) (xy 416.193998 -311.099962)
			(xy 416.197958 -311.050908) (xy 416.209735 -311.003124) (xy 416.229026 -310.957848) (xy 416.255329 -310.916252)
			(xy 416.287964 -310.879415) (xy 416.326085 -310.84829) (xy 416.368706 -310.823683) (xy 416.414722 -310.806231)
			(xy 416.462941 -310.796387) (xy 416.512116 -310.794406) (xy 416.560971 -310.800338) (xy 416.608242 -310.81403)
			(xy 416.652704 -310.835128) (xy 416.693207 -310.863084) (xy 416.7287 -310.897176) (xy 416.758265 -310.93652)
			(xy 416.781136 -310.980097) (xy 416.79672 -311.026778) (xy 416.804615 -311.075355) (xy 416.80511 -311.099962)
			(xy 418.094172 -311.099962) (xy 418.098132 -311.050908) (xy 418.109909 -311.003124) (xy 418.1292 -310.957848)
			(xy 418.155503 -310.916252) (xy 418.188138 -310.879415) (xy 418.226259 -310.84829) (xy 418.26888 -310.823683)
			(xy 418.314896 -310.806231) (xy 418.363115 -310.796387) (xy 418.41229 -310.794406) (xy 418.461145 -310.800338)
			(xy 418.508416 -310.81403) (xy 418.552878 -310.835128) (xy 418.593381 -310.863084) (xy 418.628874 -310.897176)
			(xy 418.658439 -310.93652) (xy 418.68131 -310.980097) (xy 418.696894 -311.026778) (xy 418.704789 -311.075355)
			(xy 418.705284 -311.099962) (xy 419.994092 -311.099962) (xy 419.998052 -311.050908) (xy 420.009829 -311.003124)
			(xy 420.02912 -310.957848) (xy 420.055423 -310.916252) (xy 420.088058 -310.879415) (xy 420.126179 -310.84829)
			(xy 420.1688 -310.823683) (xy 420.214816 -310.806231) (xy 420.263035 -310.796387) (xy 420.31221 -310.794406)
			(xy 420.361065 -310.800338) (xy 420.408336 -310.81403) (xy 420.452798 -310.835128) (xy 420.493301 -310.863084)
			(xy 420.528794 -310.897176) (xy 420.558359 -310.93652) (xy 420.58123 -310.980097) (xy 420.596814 -311.026778)
			(xy 420.604709 -311.075355) (xy 420.605204 -311.099962) (xy 420.604709 -311.124569) (xy 420.596814 -311.173146)
			(xy 420.58123 -311.219827) (xy 420.558359 -311.263404) (xy 420.528794 -311.302748) (xy 420.493301 -311.33684)
			(xy 420.452798 -311.364796) (xy 420.408336 -311.385894) (xy 420.361065 -311.399586) (xy 420.31221 -311.405518)
			(xy 420.263035 -311.403537) (xy 420.214816 -311.393693) (xy 420.1688 -311.376241) (xy 420.126179 -311.351634)
			(xy 420.088058 -311.320509) (xy 420.055423 -311.283672) (xy 420.02912 -311.242076) (xy 420.009829 -311.1968)
			(xy 419.998052 -311.149016) (xy 419.994092 -311.099962) (xy 418.705284 -311.099962) (xy 418.704789 -311.124569)
			(xy 418.696894 -311.173146) (xy 418.68131 -311.219827) (xy 418.658439 -311.263404) (xy 418.628874 -311.302748)
			(xy 418.593381 -311.33684) (xy 418.552878 -311.364796) (xy 418.508416 -311.385894) (xy 418.461145 -311.399586)
			(xy 418.41229 -311.405518) (xy 418.363115 -311.403537) (xy 418.314896 -311.393693) (xy 418.26888 -311.376241)
			(xy 418.226259 -311.351634) (xy 418.188138 -311.320509) (xy 418.155503 -311.283672) (xy 418.1292 -311.242076)
			(xy 418.109909 -311.1968) (xy 418.098132 -311.149016) (xy 418.094172 -311.099962) (xy 416.80511 -311.099962)
			(xy 416.804615 -311.124569) (xy 416.79672 -311.173146) (xy 416.781136 -311.219827) (xy 416.758265 -311.263404)
			(xy 416.7287 -311.302748) (xy 416.693207 -311.33684) (xy 416.652704 -311.364796) (xy 416.608242 -311.385894)
			(xy 416.560971 -311.399586) (xy 416.512116 -311.405518) (xy 416.462941 -311.403537) (xy 416.414722 -311.393693)
			(xy 416.368706 -311.376241) (xy 416.326085 -311.351634) (xy 416.287964 -311.320509) (xy 416.255329 -311.283672)
			(xy 416.229026 -311.242076) (xy 416.209735 -311.1968) (xy 416.197958 -311.149016) (xy 416.193998 -311.099962)
			(xy 414.90519 -311.099962) (xy 414.904695 -311.124569) (xy 414.8968 -311.173146) (xy 414.881216 -311.219827)
			(xy 414.858345 -311.263404) (xy 414.82878 -311.302748) (xy 414.793287 -311.33684) (xy 414.752784 -311.364796)
			(xy 414.708322 -311.385894) (xy 414.661051 -311.399586) (xy 414.612196 -311.405518) (xy 414.563021 -311.403537)
			(xy 414.514802 -311.393693) (xy 414.468786 -311.376241) (xy 414.426165 -311.351634) (xy 414.388044 -311.320509)
			(xy 414.355409 -311.283672) (xy 414.329106 -311.242076) (xy 414.309815 -311.1968) (xy 414.298038 -311.149016)
			(xy 414.294078 -311.099962) (xy 397.805148 -311.099962) (xy 397.804653 -311.124569) (xy 397.796758 -311.173146)
			(xy 397.781174 -311.219827) (xy 397.758303 -311.263404) (xy 397.728738 -311.302748) (xy 397.693245 -311.33684)
			(xy 397.652742 -311.364796) (xy 397.60828 -311.385894) (xy 397.561009 -311.399586) (xy 397.512154 -311.405518)
			(xy 397.462979 -311.403537) (xy 397.41476 -311.393693) (xy 397.368744 -311.376241) (xy 397.326123 -311.351634)
			(xy 397.288002 -311.320509) (xy 397.255367 -311.283672) (xy 397.229064 -311.242076) (xy 397.209773 -311.1968)
			(xy 397.197996 -311.149016) (xy 397.194036 -311.099962) (xy 395.905228 -311.099962) (xy 395.904733 -311.124569)
			(xy 395.896838 -311.173146) (xy 395.881254 -311.219827) (xy 395.858383 -311.263404) (xy 395.828818 -311.302748)
			(xy 395.793325 -311.33684) (xy 395.752822 -311.364796) (xy 395.70836 -311.385894) (xy 395.661089 -311.399586)
			(xy 395.612234 -311.405518) (xy 395.563059 -311.403537) (xy 395.51484 -311.393693) (xy 395.468824 -311.376241)
			(xy 395.426203 -311.351634) (xy 395.388082 -311.320509) (xy 395.355447 -311.283672) (xy 395.329144 -311.242076)
			(xy 395.309853 -311.1968) (xy 395.298076 -311.149016) (xy 395.294116 -311.099962) (xy 394.005308 -311.099962)
			(xy 394.004813 -311.124569) (xy 393.996918 -311.173146) (xy 393.981334 -311.219827) (xy 393.958463 -311.263404)
			(xy 393.928898 -311.302748) (xy 393.893405 -311.33684) (xy 393.852902 -311.364796) (xy 393.80844 -311.385894)
			(xy 393.761169 -311.399586) (xy 393.712314 -311.405518) (xy 393.663139 -311.403537) (xy 393.61492 -311.393693)
			(xy 393.568904 -311.376241) (xy 393.526283 -311.351634) (xy 393.488162 -311.320509) (xy 393.455527 -311.283672)
			(xy 393.429224 -311.242076) (xy 393.409933 -311.1968) (xy 393.398156 -311.149016) (xy 393.394196 -311.099962)
			(xy 392.105134 -311.099962) (xy 392.104639 -311.124569) (xy 392.096744 -311.173146) (xy 392.08116 -311.219827)
			(xy 392.058289 -311.263404) (xy 392.028724 -311.302748) (xy 391.993231 -311.33684) (xy 391.952728 -311.364796)
			(xy 391.908266 -311.385894) (xy 391.860995 -311.399586) (xy 391.81214 -311.405518) (xy 391.762965 -311.403537)
			(xy 391.714746 -311.393693) (xy 391.66873 -311.376241) (xy 391.626109 -311.351634) (xy 391.587988 -311.320509)
			(xy 391.555353 -311.283672) (xy 391.52905 -311.242076) (xy 391.509759 -311.1968) (xy 391.497982 -311.149016)
			(xy 391.494022 -311.099962) (xy 289.305238 -311.099962) (xy 289.304743 -311.124569) (xy 289.296848 -311.173146)
			(xy 289.281264 -311.219827) (xy 289.258393 -311.263404) (xy 289.228828 -311.302748) (xy 289.193335 -311.33684)
			(xy 289.152832 -311.364796) (xy 289.10837 -311.385894) (xy 289.061099 -311.399586) (xy 289.012244 -311.405518)
			(xy 288.963069 -311.403537) (xy 288.91485 -311.393693) (xy 288.868834 -311.376241) (xy 288.826213 -311.351634)
			(xy 288.788092 -311.320509) (xy 288.755457 -311.283672) (xy 288.729154 -311.242076) (xy 288.709863 -311.1968)
			(xy 288.698086 -311.149016) (xy 288.694126 -311.099962) (xy 287.405064 -311.099962) (xy 287.404569 -311.124569)
			(xy 287.396674 -311.173146) (xy 287.38109 -311.219827) (xy 287.358219 -311.263404) (xy 287.328654 -311.302748)
			(xy 287.293161 -311.33684) (xy 287.252658 -311.364796) (xy 287.208196 -311.385894) (xy 287.160925 -311.399586)
			(xy 287.11207 -311.405518) (xy 287.062895 -311.403537) (xy 287.014676 -311.393693) (xy 286.96866 -311.376241)
			(xy 286.926039 -311.351634) (xy 286.887918 -311.320509) (xy 286.855283 -311.283672) (xy 286.82898 -311.242076)
			(xy 286.809689 -311.1968) (xy 286.797912 -311.149016) (xy 286.793952 -311.099962) (xy 285.505144 -311.099962)
			(xy 285.504649 -311.124569) (xy 285.496754 -311.173146) (xy 285.48117 -311.219827) (xy 285.458299 -311.263404)
			(xy 285.428734 -311.302748) (xy 285.393241 -311.33684) (xy 285.352738 -311.364796) (xy 285.308276 -311.385894)
			(xy 285.261005 -311.399586) (xy 285.21215 -311.405518) (xy 285.162975 -311.403537) (xy 285.114756 -311.393693)
			(xy 285.06874 -311.376241) (xy 285.026119 -311.351634) (xy 284.987998 -311.320509) (xy 284.955363 -311.283672)
			(xy 284.92906 -311.242076) (xy 284.909769 -311.1968) (xy 284.897992 -311.149016) (xy 284.894032 -311.099962)
			(xy 283.605224 -311.099962) (xy 283.604729 -311.124569) (xy 283.596834 -311.173146) (xy 283.58125 -311.219827)
			(xy 283.558379 -311.263404) (xy 283.528814 -311.302748) (xy 283.493321 -311.33684) (xy 283.452818 -311.364796)
			(xy 283.408356 -311.385894) (xy 283.361085 -311.399586) (xy 283.31223 -311.405518) (xy 283.263055 -311.403537)
			(xy 283.214836 -311.393693) (xy 283.16882 -311.376241) (xy 283.126199 -311.351634) (xy 283.088078 -311.320509)
			(xy 283.055443 -311.283672) (xy 283.02914 -311.242076) (xy 283.009849 -311.1968) (xy 282.998072 -311.149016)
			(xy 282.994112 -311.099962) (xy 281.70505 -311.099962) (xy 281.704555 -311.124569) (xy 281.69666 -311.173146)
			(xy 281.681076 -311.219827) (xy 281.658205 -311.263404) (xy 281.62864 -311.302748) (xy 281.593147 -311.33684)
			(xy 281.552644 -311.364796) (xy 281.508182 -311.385894) (xy 281.460911 -311.399586) (xy 281.412056 -311.405518)
			(xy 281.362881 -311.403537) (xy 281.314662 -311.393693) (xy 281.268646 -311.376241) (xy 281.226025 -311.351634)
			(xy 281.187904 -311.320509) (xy 281.155269 -311.283672) (xy 281.128966 -311.242076) (xy 281.109675 -311.1968)
			(xy 281.097898 -311.149016) (xy 281.093938 -311.099962) (xy 279.80513 -311.099962) (xy 279.804635 -311.124569)
			(xy 279.79674 -311.173146) (xy 279.781156 -311.219827) (xy 279.758285 -311.263404) (xy 279.72872 -311.302748)
			(xy 279.693227 -311.33684) (xy 279.652724 -311.364796) (xy 279.608262 -311.385894) (xy 279.560991 -311.399586)
			(xy 279.512136 -311.405518) (xy 279.462961 -311.403537) (xy 279.414742 -311.393693) (xy 279.368726 -311.376241)
			(xy 279.326105 -311.351634) (xy 279.287984 -311.320509) (xy 279.255349 -311.283672) (xy 279.229046 -311.242076)
			(xy 279.209755 -311.1968) (xy 279.197978 -311.149016) (xy 279.194018 -311.099962) (xy 277.90521 -311.099962)
			(xy 277.904715 -311.124569) (xy 277.89682 -311.173146) (xy 277.881236 -311.219827) (xy 277.858365 -311.263404)
			(xy 277.8288 -311.302748) (xy 277.793307 -311.33684) (xy 277.752804 -311.364796) (xy 277.708342 -311.385894)
			(xy 277.661071 -311.399586) (xy 277.612216 -311.405518) (xy 277.563041 -311.403537) (xy 277.514822 -311.393693)
			(xy 277.468806 -311.376241) (xy 277.426185 -311.351634) (xy 277.388064 -311.320509) (xy 277.355429 -311.283672)
			(xy 277.329126 -311.242076) (xy 277.309835 -311.1968) (xy 277.298058 -311.149016) (xy 277.294098 -311.099962)
			(xy 276.005036 -311.099962) (xy 276.004541 -311.124569) (xy 275.996646 -311.173146) (xy 275.981062 -311.219827)
			(xy 275.958191 -311.263404) (xy 275.928626 -311.302748) (xy 275.893133 -311.33684) (xy 275.85263 -311.364796)
			(xy 275.808168 -311.385894) (xy 275.760897 -311.399586) (xy 275.712042 -311.405518) (xy 275.662867 -311.403537)
			(xy 275.614648 -311.393693) (xy 275.568632 -311.376241) (xy 275.526011 -311.351634) (xy 275.48789 -311.320509)
			(xy 275.455255 -311.283672) (xy 275.428952 -311.242076) (xy 275.409661 -311.1968) (xy 275.397884 -311.149016)
			(xy 275.393924 -311.099962) (xy 188.405262 -311.099962) (xy 188.404767 -311.124569) (xy 188.396872 -311.173146)
			(xy 188.381288 -311.219827) (xy 188.358417 -311.263404) (xy 188.328852 -311.302748) (xy 188.293359 -311.33684)
			(xy 188.252856 -311.364796) (xy 188.208394 -311.385894) (xy 188.161123 -311.399586) (xy 188.112268 -311.405518)
			(xy 188.063093 -311.403537) (xy 188.014874 -311.393693) (xy 187.968858 -311.376241) (xy 187.926237 -311.351634)
			(xy 187.888116 -311.320509) (xy 187.855481 -311.283672) (xy 187.829178 -311.242076) (xy 187.809887 -311.1968)
			(xy 187.79811 -311.149016) (xy 187.79415 -311.099962) (xy 186.505342 -311.099962) (xy 186.504847 -311.124569)
			(xy 186.496952 -311.173146) (xy 186.481368 -311.219827) (xy 186.458497 -311.263404) (xy 186.428932 -311.302748)
			(xy 186.393439 -311.33684) (xy 186.352936 -311.364796) (xy 186.308474 -311.385894) (xy 186.261203 -311.399586)
			(xy 186.212348 -311.405518) (xy 186.163173 -311.403537) (xy 186.114954 -311.393693) (xy 186.068938 -311.376241)
			(xy 186.026317 -311.351634) (xy 185.988196 -311.320509) (xy 185.955561 -311.283672) (xy 185.929258 -311.242076)
			(xy 185.909967 -311.1968) (xy 185.89819 -311.149016) (xy 185.89423 -311.099962) (xy 184.605168 -311.099962)
			(xy 184.604673 -311.124569) (xy 184.596778 -311.173146) (xy 184.581194 -311.219827) (xy 184.558323 -311.263404)
			(xy 184.528758 -311.302748) (xy 184.493265 -311.33684) (xy 184.452762 -311.364796) (xy 184.4083 -311.385894)
			(xy 184.361029 -311.399586) (xy 184.312174 -311.405518) (xy 184.262999 -311.403537) (xy 184.21478 -311.393693)
			(xy 184.168764 -311.376241) (xy 184.126143 -311.351634) (xy 184.088022 -311.320509) (xy 184.055387 -311.283672)
			(xy 184.029084 -311.242076) (xy 184.009793 -311.1968) (xy 183.998016 -311.149016) (xy 183.994056 -311.099962)
			(xy 182.705248 -311.099962) (xy 182.704753 -311.124569) (xy 182.696858 -311.173146) (xy 182.681274 -311.219827)
			(xy 182.658403 -311.263404) (xy 182.628838 -311.302748) (xy 182.593345 -311.33684) (xy 182.552842 -311.364796)
			(xy 182.50838 -311.385894) (xy 182.461109 -311.399586) (xy 182.412254 -311.405518) (xy 182.363079 -311.403537)
			(xy 182.31486 -311.393693) (xy 182.268844 -311.376241) (xy 182.226223 -311.351634) (xy 182.188102 -311.320509)
			(xy 182.155467 -311.283672) (xy 182.129164 -311.242076) (xy 182.109873 -311.1968) (xy 182.098096 -311.149016)
			(xy 182.094136 -311.099962) (xy 165.605206 -311.099962) (xy 165.604711 -311.124569) (xy 165.596816 -311.173146)
			(xy 165.581232 -311.219827) (xy 165.558361 -311.263404) (xy 165.528796 -311.302748) (xy 165.493303 -311.33684)
			(xy 165.4528 -311.364796) (xy 165.408338 -311.385894) (xy 165.361067 -311.399586) (xy 165.312212 -311.405518)
			(xy 165.263037 -311.403537) (xy 165.214818 -311.393693) (xy 165.168802 -311.376241) (xy 165.126181 -311.351634)
			(xy 165.08806 -311.320509) (xy 165.055425 -311.283672) (xy 165.029122 -311.242076) (xy 165.009831 -311.1968)
			(xy 164.998054 -311.149016) (xy 164.994094 -311.099962) (xy 163.705286 -311.099962) (xy 163.704791 -311.124569)
			(xy 163.696896 -311.173146) (xy 163.681312 -311.219827) (xy 163.658441 -311.263404) (xy 163.628876 -311.302748)
			(xy 163.593383 -311.33684) (xy 163.55288 -311.364796) (xy 163.508418 -311.385894) (xy 163.461147 -311.399586)
			(xy 163.412292 -311.405518) (xy 163.363117 -311.403537) (xy 163.314898 -311.393693) (xy 163.268882 -311.376241)
			(xy 163.226261 -311.351634) (xy 163.18814 -311.320509) (xy 163.155505 -311.283672) (xy 163.129202 -311.242076)
			(xy 163.109911 -311.1968) (xy 163.098134 -311.149016) (xy 163.094174 -311.099962) (xy 161.805366 -311.099962)
			(xy 161.804871 -311.124569) (xy 161.796976 -311.173146) (xy 161.781392 -311.219827) (xy 161.758521 -311.263404)
			(xy 161.728956 -311.302748) (xy 161.693463 -311.33684) (xy 161.65296 -311.364796) (xy 161.608498 -311.385894)
			(xy 161.561227 -311.399586) (xy 161.512372 -311.405518) (xy 161.463197 -311.403537) (xy 161.414978 -311.393693)
			(xy 161.368962 -311.376241) (xy 161.326341 -311.351634) (xy 161.28822 -311.320509) (xy 161.255585 -311.283672)
			(xy 161.229282 -311.242076) (xy 161.209991 -311.1968) (xy 161.198214 -311.149016) (xy 161.194254 -311.099962)
			(xy 159.905192 -311.099962) (xy 159.904697 -311.124569) (xy 159.896802 -311.173146) (xy 159.881218 -311.219827)
			(xy 159.858347 -311.263404) (xy 159.828782 -311.302748) (xy 159.793289 -311.33684) (xy 159.752786 -311.364796)
			(xy 159.708324 -311.385894) (xy 159.661053 -311.399586) (xy 159.612198 -311.405518) (xy 159.563023 -311.403537)
			(xy 159.514804 -311.393693) (xy 159.468788 -311.376241) (xy 159.426167 -311.351634) (xy 159.388046 -311.320509)
			(xy 159.355411 -311.283672) (xy 159.329108 -311.242076) (xy 159.309817 -311.1968) (xy 159.29804 -311.149016)
			(xy 159.29408 -311.099962) (xy 57.105296 -311.099962) (xy 57.104801 -311.124569) (xy 57.096906 -311.173146)
			(xy 57.081322 -311.219827) (xy 57.058451 -311.263404) (xy 57.028886 -311.302748) (xy 56.993393 -311.33684)
			(xy 56.95289 -311.364796) (xy 56.908428 -311.385894) (xy 56.861157 -311.399586) (xy 56.812302 -311.405518)
			(xy 56.763127 -311.403537) (xy 56.714908 -311.393693) (xy 56.668892 -311.376241) (xy 56.626271 -311.351634)
			(xy 56.58815 -311.320509) (xy 56.555515 -311.283672) (xy 56.529212 -311.242076) (xy 56.509921 -311.1968)
			(xy 56.498144 -311.149016) (xy 56.494184 -311.099962) (xy 55.205122 -311.099962) (xy 55.204627 -311.124569)
			(xy 55.196732 -311.173146) (xy 55.181148 -311.219827) (xy 55.158277 -311.263404) (xy 55.128712 -311.302748)
			(xy 55.093219 -311.33684) (xy 55.052716 -311.364796) (xy 55.008254 -311.385894) (xy 54.960983 -311.399586)
			(xy 54.912128 -311.405518) (xy 54.862953 -311.403537) (xy 54.814734 -311.393693) (xy 54.768718 -311.376241)
			(xy 54.726097 -311.351634) (xy 54.687976 -311.320509) (xy 54.655341 -311.283672) (xy 54.629038 -311.242076)
			(xy 54.609747 -311.1968) (xy 54.59797 -311.149016) (xy 54.59401 -311.099962) (xy 53.305202 -311.099962)
			(xy 53.304707 -311.124569) (xy 53.296812 -311.173146) (xy 53.281228 -311.219827) (xy 53.258357 -311.263404)
			(xy 53.228792 -311.302748) (xy 53.193299 -311.33684) (xy 53.152796 -311.364796) (xy 53.108334 -311.385894)
			(xy 53.061063 -311.399586) (xy 53.012208 -311.405518) (xy 52.963033 -311.403537) (xy 52.914814 -311.393693)
			(xy 52.868798 -311.376241) (xy 52.826177 -311.351634) (xy 52.788056 -311.320509) (xy 52.755421 -311.283672)
			(xy 52.729118 -311.242076) (xy 52.709827 -311.1968) (xy 52.69805 -311.149016) (xy 52.69409 -311.099962)
			(xy 51.405282 -311.099962) (xy 51.404787 -311.124569) (xy 51.396892 -311.173146) (xy 51.381308 -311.219827)
			(xy 51.358437 -311.263404) (xy 51.328872 -311.302748) (xy 51.293379 -311.33684) (xy 51.252876 -311.364796)
			(xy 51.208414 -311.385894) (xy 51.161143 -311.399586) (xy 51.112288 -311.405518) (xy 51.063113 -311.403537)
			(xy 51.014894 -311.393693) (xy 50.968878 -311.376241) (xy 50.926257 -311.351634) (xy 50.888136 -311.320509)
			(xy 50.855501 -311.283672) (xy 50.829198 -311.242076) (xy 50.809907 -311.1968) (xy 50.79813 -311.149016)
			(xy 50.79417 -311.099962) (xy 49.505108 -311.099962) (xy 49.504613 -311.124569) (xy 49.496718 -311.173146)
			(xy 49.481134 -311.219827) (xy 49.458263 -311.263404) (xy 49.428698 -311.302748) (xy 49.393205 -311.33684)
			(xy 49.352702 -311.364796) (xy 49.30824 -311.385894) (xy 49.260969 -311.399586) (xy 49.212114 -311.405518)
			(xy 49.162939 -311.403537) (xy 49.11472 -311.393693) (xy 49.068704 -311.376241) (xy 49.026083 -311.351634)
			(xy 48.987962 -311.320509) (xy 48.955327 -311.283672) (xy 48.929024 -311.242076) (xy 48.909733 -311.1968)
			(xy 48.897956 -311.149016) (xy 48.893996 -311.099962) (xy 47.605188 -311.099962) (xy 47.604693 -311.124569)
			(xy 47.596798 -311.173146) (xy 47.581214 -311.219827) (xy 47.558343 -311.263404) (xy 47.528778 -311.302748)
			(xy 47.493285 -311.33684) (xy 47.452782 -311.364796) (xy 47.40832 -311.385894) (xy 47.361049 -311.399586)
			(xy 47.312194 -311.405518) (xy 47.263019 -311.403537) (xy 47.2148 -311.393693) (xy 47.168784 -311.376241)
			(xy 47.126163 -311.351634) (xy 47.088042 -311.320509) (xy 47.055407 -311.283672) (xy 47.029104 -311.242076)
			(xy 47.009813 -311.1968) (xy 46.998036 -311.149016) (xy 46.994076 -311.099962) (xy 45.705268 -311.099962)
			(xy 45.704773 -311.124569) (xy 45.696878 -311.173146) (xy 45.681294 -311.219827) (xy 45.658423 -311.263404)
			(xy 45.628858 -311.302748) (xy 45.593365 -311.33684) (xy 45.552862 -311.364796) (xy 45.5084 -311.385894)
			(xy 45.461129 -311.399586) (xy 45.412274 -311.405518) (xy 45.363099 -311.403537) (xy 45.31488 -311.393693)
			(xy 45.268864 -311.376241) (xy 45.226243 -311.351634) (xy 45.188122 -311.320509) (xy 45.155487 -311.283672)
			(xy 45.129184 -311.242076) (xy 45.109893 -311.1968) (xy 45.098116 -311.149016) (xy 45.094156 -311.099962)
			(xy 43.805094 -311.099962) (xy 43.804599 -311.124569) (xy 43.796704 -311.173146) (xy 43.78112 -311.219827)
			(xy 43.758249 -311.263404) (xy 43.728684 -311.302748) (xy 43.693191 -311.33684) (xy 43.652688 -311.364796)
			(xy 43.608226 -311.385894) (xy 43.560955 -311.399586) (xy 43.5121 -311.405518) (xy 43.462925 -311.403537)
			(xy 43.414706 -311.393693) (xy 43.36869 -311.376241) (xy 43.326069 -311.351634) (xy 43.287948 -311.320509)
			(xy 43.255313 -311.283672) (xy 43.22901 -311.242076) (xy 43.209719 -311.1968) (xy 43.197942 -311.149016)
			(xy 43.193982 -311.099962) (xy 0.508 -311.099962) (xy 0.508 -312.049922) (xy 43.193982 -312.049922)
			(xy 43.197942 -312.000868) (xy 43.209719 -311.953084) (xy 43.22901 -311.907808) (xy 43.255313 -311.866212)
			(xy 43.287948 -311.829375) (xy 43.326069 -311.79825) (xy 43.36869 -311.773643) (xy 43.414706 -311.756191)
			(xy 43.462925 -311.746347) (xy 43.5121 -311.744366) (xy 43.560955 -311.750298) (xy 43.608226 -311.76399)
			(xy 43.652688 -311.785088) (xy 43.693191 -311.813044) (xy 43.728684 -311.847136) (xy 43.758249 -311.88648)
			(xy 43.78112 -311.930057) (xy 43.796704 -311.976738) (xy 43.804599 -312.025315) (xy 43.805094 -312.049922)
			(xy 45.094156 -312.049922) (xy 45.098116 -312.000868) (xy 45.109893 -311.953084) (xy 45.129184 -311.907808)
			(xy 45.155487 -311.866212) (xy 45.188122 -311.829375) (xy 45.226243 -311.79825) (xy 45.268864 -311.773643)
			(xy 45.31488 -311.756191) (xy 45.363099 -311.746347) (xy 45.412274 -311.744366) (xy 45.461129 -311.750298)
			(xy 45.5084 -311.76399) (xy 45.552862 -311.785088) (xy 45.593365 -311.813044) (xy 45.628858 -311.847136)
			(xy 45.658423 -311.88648) (xy 45.681294 -311.930057) (xy 45.696878 -311.976738) (xy 45.704773 -312.025315)
			(xy 45.705268 -312.049922) (xy 46.994076 -312.049922) (xy 46.998036 -312.000868) (xy 47.009813 -311.953084)
			(xy 47.029104 -311.907808) (xy 47.055407 -311.866212) (xy 47.088042 -311.829375) (xy 47.126163 -311.79825)
			(xy 47.168784 -311.773643) (xy 47.2148 -311.756191) (xy 47.263019 -311.746347) (xy 47.312194 -311.744366)
			(xy 47.361049 -311.750298) (xy 47.40832 -311.76399) (xy 47.452782 -311.785088) (xy 47.493285 -311.813044)
			(xy 47.528778 -311.847136) (xy 47.558343 -311.88648) (xy 47.581214 -311.930057) (xy 47.596798 -311.976738)
			(xy 47.604693 -312.025315) (xy 47.605188 -312.049922) (xy 48.893996 -312.049922) (xy 48.897956 -312.000868)
			(xy 48.909733 -311.953084) (xy 48.929024 -311.907808) (xy 48.955327 -311.866212) (xy 48.987962 -311.829375)
			(xy 49.026083 -311.79825) (xy 49.068704 -311.773643) (xy 49.11472 -311.756191) (xy 49.162939 -311.746347)
			(xy 49.212114 -311.744366) (xy 49.260969 -311.750298) (xy 49.30824 -311.76399) (xy 49.352702 -311.785088)
			(xy 49.393205 -311.813044) (xy 49.428698 -311.847136) (xy 49.458263 -311.88648) (xy 49.481134 -311.930057)
			(xy 49.496718 -311.976738) (xy 49.504613 -312.025315) (xy 49.505108 -312.049922) (xy 50.79417 -312.049922)
			(xy 50.79813 -312.000868) (xy 50.809907 -311.953084) (xy 50.829198 -311.907808) (xy 50.855501 -311.866212)
			(xy 50.888136 -311.829375) (xy 50.926257 -311.79825) (xy 50.968878 -311.773643) (xy 51.014894 -311.756191)
			(xy 51.063113 -311.746347) (xy 51.112288 -311.744366) (xy 51.161143 -311.750298) (xy 51.208414 -311.76399)
			(xy 51.252876 -311.785088) (xy 51.293379 -311.813044) (xy 51.328872 -311.847136) (xy 51.358437 -311.88648)
			(xy 51.381308 -311.930057) (xy 51.396892 -311.976738) (xy 51.404787 -312.025315) (xy 51.405282 -312.049922)
			(xy 52.69409 -312.049922) (xy 52.69805 -312.000868) (xy 52.709827 -311.953084) (xy 52.729118 -311.907808)
			(xy 52.755421 -311.866212) (xy 52.788056 -311.829375) (xy 52.826177 -311.79825) (xy 52.868798 -311.773643)
			(xy 52.914814 -311.756191) (xy 52.963033 -311.746347) (xy 53.012208 -311.744366) (xy 53.061063 -311.750298)
			(xy 53.108334 -311.76399) (xy 53.152796 -311.785088) (xy 53.193299 -311.813044) (xy 53.228792 -311.847136)
			(xy 53.258357 -311.88648) (xy 53.281228 -311.930057) (xy 53.296812 -311.976738) (xy 53.304707 -312.025315)
			(xy 53.305202 -312.049922) (xy 54.59401 -312.049922) (xy 54.59797 -312.000868) (xy 54.609747 -311.953084)
			(xy 54.629038 -311.907808) (xy 54.655341 -311.866212) (xy 54.687976 -311.829375) (xy 54.726097 -311.79825)
			(xy 54.768718 -311.773643) (xy 54.814734 -311.756191) (xy 54.862953 -311.746347) (xy 54.912128 -311.744366)
			(xy 54.960983 -311.750298) (xy 55.008254 -311.76399) (xy 55.052716 -311.785088) (xy 55.093219 -311.813044)
			(xy 55.128712 -311.847136) (xy 55.158277 -311.88648) (xy 55.181148 -311.930057) (xy 55.196732 -311.976738)
			(xy 55.204627 -312.025315) (xy 55.205122 -312.049922) (xy 56.494184 -312.049922) (xy 56.498144 -312.000868)
			(xy 56.509921 -311.953084) (xy 56.529212 -311.907808) (xy 56.555515 -311.866212) (xy 56.58815 -311.829375)
			(xy 56.626271 -311.79825) (xy 56.668892 -311.773643) (xy 56.714908 -311.756191) (xy 56.763127 -311.746347)
			(xy 56.812302 -311.744366) (xy 56.861157 -311.750298) (xy 56.908428 -311.76399) (xy 56.95289 -311.785088)
			(xy 56.993393 -311.813044) (xy 57.028886 -311.847136) (xy 57.058451 -311.88648) (xy 57.081322 -311.930057)
			(xy 57.096906 -311.976738) (xy 57.104801 -312.025315) (xy 57.105296 -312.049922) (xy 159.29408 -312.049922)
			(xy 159.29804 -312.000868) (xy 159.309817 -311.953084) (xy 159.329108 -311.907808) (xy 159.355411 -311.866212)
			(xy 159.388046 -311.829375) (xy 159.426167 -311.79825) (xy 159.468788 -311.773643) (xy 159.514804 -311.756191)
			(xy 159.563023 -311.746347) (xy 159.612198 -311.744366) (xy 159.661053 -311.750298) (xy 159.708324 -311.76399)
			(xy 159.752786 -311.785088) (xy 159.793289 -311.813044) (xy 159.828782 -311.847136) (xy 159.858347 -311.88648)
			(xy 159.881218 -311.930057) (xy 159.896802 -311.976738) (xy 159.904697 -312.025315) (xy 159.905192 -312.049922)
			(xy 161.194254 -312.049922) (xy 161.198214 -312.000868) (xy 161.209991 -311.953084) (xy 161.229282 -311.907808)
			(xy 161.255585 -311.866212) (xy 161.28822 -311.829375) (xy 161.326341 -311.79825) (xy 161.368962 -311.773643)
			(xy 161.414978 -311.756191) (xy 161.463197 -311.746347) (xy 161.512372 -311.744366) (xy 161.561227 -311.750298)
			(xy 161.608498 -311.76399) (xy 161.65296 -311.785088) (xy 161.693463 -311.813044) (xy 161.728956 -311.847136)
			(xy 161.758521 -311.88648) (xy 161.781392 -311.930057) (xy 161.796976 -311.976738) (xy 161.804871 -312.025315)
			(xy 161.805366 -312.049922) (xy 163.094174 -312.049922) (xy 163.098134 -312.000868) (xy 163.109911 -311.953084)
			(xy 163.129202 -311.907808) (xy 163.155505 -311.866212) (xy 163.18814 -311.829375) (xy 163.226261 -311.79825)
			(xy 163.268882 -311.773643) (xy 163.314898 -311.756191) (xy 163.363117 -311.746347) (xy 163.412292 -311.744366)
			(xy 163.461147 -311.750298) (xy 163.508418 -311.76399) (xy 163.55288 -311.785088) (xy 163.593383 -311.813044)
			(xy 163.628876 -311.847136) (xy 163.658441 -311.88648) (xy 163.681312 -311.930057) (xy 163.696896 -311.976738)
			(xy 163.704791 -312.025315) (xy 163.705286 -312.049922) (xy 164.994094 -312.049922) (xy 164.998054 -312.000868)
			(xy 165.009831 -311.953084) (xy 165.029122 -311.907808) (xy 165.055425 -311.866212) (xy 165.08806 -311.829375)
			(xy 165.126181 -311.79825) (xy 165.168802 -311.773643) (xy 165.214818 -311.756191) (xy 165.263037 -311.746347)
			(xy 165.312212 -311.744366) (xy 165.361067 -311.750298) (xy 165.408338 -311.76399) (xy 165.4528 -311.785088)
			(xy 165.493303 -311.813044) (xy 165.528796 -311.847136) (xy 165.558361 -311.88648) (xy 165.581232 -311.930057)
			(xy 165.596816 -311.976738) (xy 165.604711 -312.025315) (xy 165.605206 -312.049922) (xy 182.094136 -312.049922)
			(xy 182.098096 -312.000868) (xy 182.109873 -311.953084) (xy 182.129164 -311.907808) (xy 182.155467 -311.866212)
			(xy 182.188102 -311.829375) (xy 182.226223 -311.79825) (xy 182.268844 -311.773643) (xy 182.31486 -311.756191)
			(xy 182.363079 -311.746347) (xy 182.412254 -311.744366) (xy 182.461109 -311.750298) (xy 182.50838 -311.76399)
			(xy 182.552842 -311.785088) (xy 182.593345 -311.813044) (xy 182.628838 -311.847136) (xy 182.658403 -311.88648)
			(xy 182.681274 -311.930057) (xy 182.696858 -311.976738) (xy 182.704753 -312.025315) (xy 182.705248 -312.049922)
			(xy 183.994056 -312.049922) (xy 183.998016 -312.000868) (xy 184.009793 -311.953084) (xy 184.029084 -311.907808)
			(xy 184.055387 -311.866212) (xy 184.088022 -311.829375) (xy 184.126143 -311.79825) (xy 184.168764 -311.773643)
			(xy 184.21478 -311.756191) (xy 184.262999 -311.746347) (xy 184.312174 -311.744366) (xy 184.361029 -311.750298)
			(xy 184.4083 -311.76399) (xy 184.452762 -311.785088) (xy 184.493265 -311.813044) (xy 184.528758 -311.847136)
			(xy 184.558323 -311.88648) (xy 184.581194 -311.930057) (xy 184.596778 -311.976738) (xy 184.604673 -312.025315)
			(xy 184.605168 -312.049922) (xy 185.89423 -312.049922) (xy 185.89819 -312.000868) (xy 185.909967 -311.953084)
			(xy 185.929258 -311.907808) (xy 185.955561 -311.866212) (xy 185.988196 -311.829375) (xy 186.026317 -311.79825)
			(xy 186.068938 -311.773643) (xy 186.114954 -311.756191) (xy 186.163173 -311.746347) (xy 186.212348 -311.744366)
			(xy 186.261203 -311.750298) (xy 186.308474 -311.76399) (xy 186.352936 -311.785088) (xy 186.393439 -311.813044)
			(xy 186.428932 -311.847136) (xy 186.458497 -311.88648) (xy 186.481368 -311.930057) (xy 186.496952 -311.976738)
			(xy 186.504847 -312.025315) (xy 186.505342 -312.049922) (xy 187.79415 -312.049922) (xy 187.79811 -312.000868)
			(xy 187.809887 -311.953084) (xy 187.829178 -311.907808) (xy 187.855481 -311.866212) (xy 187.888116 -311.829375)
			(xy 187.926237 -311.79825) (xy 187.968858 -311.773643) (xy 188.014874 -311.756191) (xy 188.063093 -311.746347)
			(xy 188.112268 -311.744366) (xy 188.161123 -311.750298) (xy 188.208394 -311.76399) (xy 188.252856 -311.785088)
			(xy 188.293359 -311.813044) (xy 188.328852 -311.847136) (xy 188.358417 -311.88648) (xy 188.381288 -311.930057)
			(xy 188.396872 -311.976738) (xy 188.404767 -312.025315) (xy 188.405262 -312.049922) (xy 275.393924 -312.049922)
			(xy 275.397884 -312.000868) (xy 275.409661 -311.953084) (xy 275.428952 -311.907808) (xy 275.455255 -311.866212)
			(xy 275.48789 -311.829375) (xy 275.526011 -311.79825) (xy 275.568632 -311.773643) (xy 275.614648 -311.756191)
			(xy 275.662867 -311.746347) (xy 275.712042 -311.744366) (xy 275.760897 -311.750298) (xy 275.808168 -311.76399)
			(xy 275.85263 -311.785088) (xy 275.893133 -311.813044) (xy 275.928626 -311.847136) (xy 275.958191 -311.88648)
			(xy 275.981062 -311.930057) (xy 275.996646 -311.976738) (xy 276.004541 -312.025315) (xy 276.005036 -312.049922)
			(xy 277.294098 -312.049922) (xy 277.298058 -312.000868) (xy 277.309835 -311.953084) (xy 277.329126 -311.907808)
			(xy 277.355429 -311.866212) (xy 277.388064 -311.829375) (xy 277.426185 -311.79825) (xy 277.468806 -311.773643)
			(xy 277.514822 -311.756191) (xy 277.563041 -311.746347) (xy 277.612216 -311.744366) (xy 277.661071 -311.750298)
			(xy 277.708342 -311.76399) (xy 277.752804 -311.785088) (xy 277.793307 -311.813044) (xy 277.8288 -311.847136)
			(xy 277.858365 -311.88648) (xy 277.881236 -311.930057) (xy 277.89682 -311.976738) (xy 277.904715 -312.025315)
			(xy 277.90521 -312.049922) (xy 279.194018 -312.049922) (xy 279.197978 -312.000868) (xy 279.209755 -311.953084)
			(xy 279.229046 -311.907808) (xy 279.255349 -311.866212) (xy 279.287984 -311.829375) (xy 279.326105 -311.79825)
			(xy 279.368726 -311.773643) (xy 279.414742 -311.756191) (xy 279.462961 -311.746347) (xy 279.512136 -311.744366)
			(xy 279.560991 -311.750298) (xy 279.608262 -311.76399) (xy 279.652724 -311.785088) (xy 279.693227 -311.813044)
			(xy 279.72872 -311.847136) (xy 279.758285 -311.88648) (xy 279.781156 -311.930057) (xy 279.79674 -311.976738)
			(xy 279.804635 -312.025315) (xy 279.80513 -312.049922) (xy 281.093938 -312.049922) (xy 281.097898 -312.000868)
			(xy 281.109675 -311.953084) (xy 281.128966 -311.907808) (xy 281.155269 -311.866212) (xy 281.187904 -311.829375)
			(xy 281.226025 -311.79825) (xy 281.268646 -311.773643) (xy 281.314662 -311.756191) (xy 281.362881 -311.746347)
			(xy 281.412056 -311.744366) (xy 281.460911 -311.750298) (xy 281.508182 -311.76399) (xy 281.552644 -311.785088)
			(xy 281.593147 -311.813044) (xy 281.62864 -311.847136) (xy 281.658205 -311.88648) (xy 281.681076 -311.930057)
			(xy 281.69666 -311.976738) (xy 281.704555 -312.025315) (xy 281.70505 -312.049922) (xy 282.994112 -312.049922)
			(xy 282.998072 -312.000868) (xy 283.009849 -311.953084) (xy 283.02914 -311.907808) (xy 283.055443 -311.866212)
			(xy 283.088078 -311.829375) (xy 283.126199 -311.79825) (xy 283.16882 -311.773643) (xy 283.214836 -311.756191)
			(xy 283.263055 -311.746347) (xy 283.31223 -311.744366) (xy 283.361085 -311.750298) (xy 283.408356 -311.76399)
			(xy 283.452818 -311.785088) (xy 283.493321 -311.813044) (xy 283.528814 -311.847136) (xy 283.558379 -311.88648)
			(xy 283.58125 -311.930057) (xy 283.596834 -311.976738) (xy 283.604729 -312.025315) (xy 283.605224 -312.049922)
			(xy 284.894032 -312.049922) (xy 284.897992 -312.000868) (xy 284.909769 -311.953084) (xy 284.92906 -311.907808)
			(xy 284.955363 -311.866212) (xy 284.987998 -311.829375) (xy 285.026119 -311.79825) (xy 285.06874 -311.773643)
			(xy 285.114756 -311.756191) (xy 285.162975 -311.746347) (xy 285.21215 -311.744366) (xy 285.261005 -311.750298)
			(xy 285.308276 -311.76399) (xy 285.352738 -311.785088) (xy 285.393241 -311.813044) (xy 285.428734 -311.847136)
			(xy 285.458299 -311.88648) (xy 285.48117 -311.930057) (xy 285.496754 -311.976738) (xy 285.504649 -312.025315)
			(xy 285.505144 -312.049922) (xy 286.793952 -312.049922) (xy 286.797912 -312.000868) (xy 286.809689 -311.953084)
			(xy 286.82898 -311.907808) (xy 286.855283 -311.866212) (xy 286.887918 -311.829375) (xy 286.926039 -311.79825)
			(xy 286.96866 -311.773643) (xy 287.014676 -311.756191) (xy 287.062895 -311.746347) (xy 287.11207 -311.744366)
			(xy 287.160925 -311.750298) (xy 287.208196 -311.76399) (xy 287.252658 -311.785088) (xy 287.293161 -311.813044)
			(xy 287.328654 -311.847136) (xy 287.358219 -311.88648) (xy 287.38109 -311.930057) (xy 287.396674 -311.976738)
			(xy 287.404569 -312.025315) (xy 287.405064 -312.049922) (xy 288.694126 -312.049922) (xy 288.698086 -312.000868)
			(xy 288.709863 -311.953084) (xy 288.729154 -311.907808) (xy 288.755457 -311.866212) (xy 288.788092 -311.829375)
			(xy 288.826213 -311.79825) (xy 288.868834 -311.773643) (xy 288.91485 -311.756191) (xy 288.963069 -311.746347)
			(xy 289.012244 -311.744366) (xy 289.061099 -311.750298) (xy 289.10837 -311.76399) (xy 289.152832 -311.785088)
			(xy 289.193335 -311.813044) (xy 289.228828 -311.847136) (xy 289.258393 -311.88648) (xy 289.281264 -311.930057)
			(xy 289.296848 -311.976738) (xy 289.304743 -312.025315) (xy 289.305238 -312.049922) (xy 391.494022 -312.049922)
			(xy 391.497982 -312.000868) (xy 391.509759 -311.953084) (xy 391.52905 -311.907808) (xy 391.555353 -311.866212)
			(xy 391.587988 -311.829375) (xy 391.626109 -311.79825) (xy 391.66873 -311.773643) (xy 391.714746 -311.756191)
			(xy 391.762965 -311.746347) (xy 391.81214 -311.744366) (xy 391.860995 -311.750298) (xy 391.908266 -311.76399)
			(xy 391.952728 -311.785088) (xy 391.993231 -311.813044) (xy 392.028724 -311.847136) (xy 392.058289 -311.88648)
			(xy 392.08116 -311.930057) (xy 392.096744 -311.976738) (xy 392.104639 -312.025315) (xy 392.105134 -312.049922)
			(xy 393.394196 -312.049922) (xy 393.398156 -312.000868) (xy 393.409933 -311.953084) (xy 393.429224 -311.907808)
			(xy 393.455527 -311.866212) (xy 393.488162 -311.829375) (xy 393.526283 -311.79825) (xy 393.568904 -311.773643)
			(xy 393.61492 -311.756191) (xy 393.663139 -311.746347) (xy 393.712314 -311.744366) (xy 393.761169 -311.750298)
			(xy 393.80844 -311.76399) (xy 393.852902 -311.785088) (xy 393.893405 -311.813044) (xy 393.928898 -311.847136)
			(xy 393.958463 -311.88648) (xy 393.981334 -311.930057) (xy 393.996918 -311.976738) (xy 394.004813 -312.025315)
			(xy 394.005308 -312.049922) (xy 395.294116 -312.049922) (xy 395.298076 -312.000868) (xy 395.309853 -311.953084)
			(xy 395.329144 -311.907808) (xy 395.355447 -311.866212) (xy 395.388082 -311.829375) (xy 395.426203 -311.79825)
			(xy 395.468824 -311.773643) (xy 395.51484 -311.756191) (xy 395.563059 -311.746347) (xy 395.612234 -311.744366)
			(xy 395.661089 -311.750298) (xy 395.70836 -311.76399) (xy 395.752822 -311.785088) (xy 395.793325 -311.813044)
			(xy 395.828818 -311.847136) (xy 395.858383 -311.88648) (xy 395.881254 -311.930057) (xy 395.896838 -311.976738)
			(xy 395.904733 -312.025315) (xy 395.905228 -312.049922) (xy 397.194036 -312.049922) (xy 397.197996 -312.000868)
			(xy 397.209773 -311.953084) (xy 397.229064 -311.907808) (xy 397.255367 -311.866212) (xy 397.288002 -311.829375)
			(xy 397.326123 -311.79825) (xy 397.368744 -311.773643) (xy 397.41476 -311.756191) (xy 397.462979 -311.746347)
			(xy 397.512154 -311.744366) (xy 397.561009 -311.750298) (xy 397.60828 -311.76399) (xy 397.652742 -311.785088)
			(xy 397.693245 -311.813044) (xy 397.728738 -311.847136) (xy 397.758303 -311.88648) (xy 397.781174 -311.930057)
			(xy 397.796758 -311.976738) (xy 397.804653 -312.025315) (xy 397.805148 -312.049922) (xy 414.294078 -312.049922)
			(xy 414.298038 -312.000868) (xy 414.309815 -311.953084) (xy 414.329106 -311.907808) (xy 414.355409 -311.866212)
			(xy 414.388044 -311.829375) (xy 414.426165 -311.79825) (xy 414.468786 -311.773643) (xy 414.514802 -311.756191)
			(xy 414.563021 -311.746347) (xy 414.612196 -311.744366) (xy 414.661051 -311.750298) (xy 414.708322 -311.76399)
			(xy 414.752784 -311.785088) (xy 414.793287 -311.813044) (xy 414.82878 -311.847136) (xy 414.858345 -311.88648)
			(xy 414.881216 -311.930057) (xy 414.8968 -311.976738) (xy 414.904695 -312.025315) (xy 414.90519 -312.049922)
			(xy 416.193998 -312.049922) (xy 416.197958 -312.000868) (xy 416.209735 -311.953084) (xy 416.229026 -311.907808)
			(xy 416.255329 -311.866212) (xy 416.287964 -311.829375) (xy 416.326085 -311.79825) (xy 416.368706 -311.773643)
			(xy 416.414722 -311.756191) (xy 416.462941 -311.746347) (xy 416.512116 -311.744366) (xy 416.560971 -311.750298)
			(xy 416.608242 -311.76399) (xy 416.652704 -311.785088) (xy 416.693207 -311.813044) (xy 416.7287 -311.847136)
			(xy 416.758265 -311.88648) (xy 416.781136 -311.930057) (xy 416.79672 -311.976738) (xy 416.804615 -312.025315)
			(xy 416.80511 -312.049922) (xy 418.094172 -312.049922) (xy 418.098132 -312.000868) (xy 418.109909 -311.953084)
			(xy 418.1292 -311.907808) (xy 418.155503 -311.866212) (xy 418.188138 -311.829375) (xy 418.226259 -311.79825)
			(xy 418.26888 -311.773643) (xy 418.314896 -311.756191) (xy 418.363115 -311.746347) (xy 418.41229 -311.744366)
			(xy 418.461145 -311.750298) (xy 418.508416 -311.76399) (xy 418.552878 -311.785088) (xy 418.593381 -311.813044)
			(xy 418.628874 -311.847136) (xy 418.658439 -311.88648) (xy 418.68131 -311.930057) (xy 418.696894 -311.976738)
			(xy 418.704789 -312.025315) (xy 418.705284 -312.049922) (xy 419.994092 -312.049922) (xy 419.998052 -312.000868)
			(xy 420.009829 -311.953084) (xy 420.02912 -311.907808) (xy 420.055423 -311.866212) (xy 420.088058 -311.829375)
			(xy 420.126179 -311.79825) (xy 420.1688 -311.773643) (xy 420.214816 -311.756191) (xy 420.263035 -311.746347)
			(xy 420.31221 -311.744366) (xy 420.361065 -311.750298) (xy 420.408336 -311.76399) (xy 420.452798 -311.785088)
			(xy 420.493301 -311.813044) (xy 420.528794 -311.847136) (xy 420.558359 -311.88648) (xy 420.58123 -311.930057)
			(xy 420.596814 -311.976738) (xy 420.604709 -312.025315) (xy 420.605204 -312.049922) (xy 420.604709 -312.074529)
			(xy 420.596814 -312.123106) (xy 420.58123 -312.169787) (xy 420.558359 -312.213364) (xy 420.528794 -312.252708)
			(xy 420.493301 -312.2868) (xy 420.452798 -312.314756) (xy 420.408336 -312.335854) (xy 420.361065 -312.349546)
			(xy 420.31221 -312.355478) (xy 420.263035 -312.353497) (xy 420.214816 -312.343653) (xy 420.1688 -312.326201)
			(xy 420.126179 -312.301594) (xy 420.088058 -312.270469) (xy 420.055423 -312.233632) (xy 420.02912 -312.192036)
			(xy 420.009829 -312.14676) (xy 419.998052 -312.098976) (xy 419.994092 -312.049922) (xy 418.705284 -312.049922)
			(xy 418.704789 -312.074529) (xy 418.696894 -312.123106) (xy 418.68131 -312.169787) (xy 418.658439 -312.213364)
			(xy 418.628874 -312.252708) (xy 418.593381 -312.2868) (xy 418.552878 -312.314756) (xy 418.508416 -312.335854)
			(xy 418.461145 -312.349546) (xy 418.41229 -312.355478) (xy 418.363115 -312.353497) (xy 418.314896 -312.343653)
			(xy 418.26888 -312.326201) (xy 418.226259 -312.301594) (xy 418.188138 -312.270469) (xy 418.155503 -312.233632)
			(xy 418.1292 -312.192036) (xy 418.109909 -312.14676) (xy 418.098132 -312.098976) (xy 418.094172 -312.049922)
			(xy 416.80511 -312.049922) (xy 416.804615 -312.074529) (xy 416.79672 -312.123106) (xy 416.781136 -312.169787)
			(xy 416.758265 -312.213364) (xy 416.7287 -312.252708) (xy 416.693207 -312.2868) (xy 416.652704 -312.314756)
			(xy 416.608242 -312.335854) (xy 416.560971 -312.349546) (xy 416.512116 -312.355478) (xy 416.462941 -312.353497)
			(xy 416.414722 -312.343653) (xy 416.368706 -312.326201) (xy 416.326085 -312.301594) (xy 416.287964 -312.270469)
			(xy 416.255329 -312.233632) (xy 416.229026 -312.192036) (xy 416.209735 -312.14676) (xy 416.197958 -312.098976)
			(xy 416.193998 -312.049922) (xy 414.90519 -312.049922) (xy 414.904695 -312.074529) (xy 414.8968 -312.123106)
			(xy 414.881216 -312.169787) (xy 414.858345 -312.213364) (xy 414.82878 -312.252708) (xy 414.793287 -312.2868)
			(xy 414.752784 -312.314756) (xy 414.708322 -312.335854) (xy 414.661051 -312.349546) (xy 414.612196 -312.355478)
			(xy 414.563021 -312.353497) (xy 414.514802 -312.343653) (xy 414.468786 -312.326201) (xy 414.426165 -312.301594)
			(xy 414.388044 -312.270469) (xy 414.355409 -312.233632) (xy 414.329106 -312.192036) (xy 414.309815 -312.14676)
			(xy 414.298038 -312.098976) (xy 414.294078 -312.049922) (xy 397.805148 -312.049922) (xy 397.804653 -312.074529)
			(xy 397.796758 -312.123106) (xy 397.781174 -312.169787) (xy 397.758303 -312.213364) (xy 397.728738 -312.252708)
			(xy 397.693245 -312.2868) (xy 397.652742 -312.314756) (xy 397.60828 -312.335854) (xy 397.561009 -312.349546)
			(xy 397.512154 -312.355478) (xy 397.462979 -312.353497) (xy 397.41476 -312.343653) (xy 397.368744 -312.326201)
			(xy 397.326123 -312.301594) (xy 397.288002 -312.270469) (xy 397.255367 -312.233632) (xy 397.229064 -312.192036)
			(xy 397.209773 -312.14676) (xy 397.197996 -312.098976) (xy 397.194036 -312.049922) (xy 395.905228 -312.049922)
			(xy 395.904733 -312.074529) (xy 395.896838 -312.123106) (xy 395.881254 -312.169787) (xy 395.858383 -312.213364)
			(xy 395.828818 -312.252708) (xy 395.793325 -312.2868) (xy 395.752822 -312.314756) (xy 395.70836 -312.335854)
			(xy 395.661089 -312.349546) (xy 395.612234 -312.355478) (xy 395.563059 -312.353497) (xy 395.51484 -312.343653)
			(xy 395.468824 -312.326201) (xy 395.426203 -312.301594) (xy 395.388082 -312.270469) (xy 395.355447 -312.233632)
			(xy 395.329144 -312.192036) (xy 395.309853 -312.14676) (xy 395.298076 -312.098976) (xy 395.294116 -312.049922)
			(xy 394.005308 -312.049922) (xy 394.004813 -312.074529) (xy 393.996918 -312.123106) (xy 393.981334 -312.169787)
			(xy 393.958463 -312.213364) (xy 393.928898 -312.252708) (xy 393.893405 -312.2868) (xy 393.852902 -312.314756)
			(xy 393.80844 -312.335854) (xy 393.761169 -312.349546) (xy 393.712314 -312.355478) (xy 393.663139 -312.353497)
			(xy 393.61492 -312.343653) (xy 393.568904 -312.326201) (xy 393.526283 -312.301594) (xy 393.488162 -312.270469)
			(xy 393.455527 -312.233632) (xy 393.429224 -312.192036) (xy 393.409933 -312.14676) (xy 393.398156 -312.098976)
			(xy 393.394196 -312.049922) (xy 392.105134 -312.049922) (xy 392.104639 -312.074529) (xy 392.096744 -312.123106)
			(xy 392.08116 -312.169787) (xy 392.058289 -312.213364) (xy 392.028724 -312.252708) (xy 391.993231 -312.2868)
			(xy 391.952728 -312.314756) (xy 391.908266 -312.335854) (xy 391.860995 -312.349546) (xy 391.81214 -312.355478)
			(xy 391.762965 -312.353497) (xy 391.714746 -312.343653) (xy 391.66873 -312.326201) (xy 391.626109 -312.301594)
			(xy 391.587988 -312.270469) (xy 391.555353 -312.233632) (xy 391.52905 -312.192036) (xy 391.509759 -312.14676)
			(xy 391.497982 -312.098976) (xy 391.494022 -312.049922) (xy 289.305238 -312.049922) (xy 289.304743 -312.074529)
			(xy 289.296848 -312.123106) (xy 289.281264 -312.169787) (xy 289.258393 -312.213364) (xy 289.228828 -312.252708)
			(xy 289.193335 -312.2868) (xy 289.152832 -312.314756) (xy 289.10837 -312.335854) (xy 289.061099 -312.349546)
			(xy 289.012244 -312.355478) (xy 288.963069 -312.353497) (xy 288.91485 -312.343653) (xy 288.868834 -312.326201)
			(xy 288.826213 -312.301594) (xy 288.788092 -312.270469) (xy 288.755457 -312.233632) (xy 288.729154 -312.192036)
			(xy 288.709863 -312.14676) (xy 288.698086 -312.098976) (xy 288.694126 -312.049922) (xy 287.405064 -312.049922)
			(xy 287.404569 -312.074529) (xy 287.396674 -312.123106) (xy 287.38109 -312.169787) (xy 287.358219 -312.213364)
			(xy 287.328654 -312.252708) (xy 287.293161 -312.2868) (xy 287.252658 -312.314756) (xy 287.208196 -312.335854)
			(xy 287.160925 -312.349546) (xy 287.11207 -312.355478) (xy 287.062895 -312.353497) (xy 287.014676 -312.343653)
			(xy 286.96866 -312.326201) (xy 286.926039 -312.301594) (xy 286.887918 -312.270469) (xy 286.855283 -312.233632)
			(xy 286.82898 -312.192036) (xy 286.809689 -312.14676) (xy 286.797912 -312.098976) (xy 286.793952 -312.049922)
			(xy 285.505144 -312.049922) (xy 285.504649 -312.074529) (xy 285.496754 -312.123106) (xy 285.48117 -312.169787)
			(xy 285.458299 -312.213364) (xy 285.428734 -312.252708) (xy 285.393241 -312.2868) (xy 285.352738 -312.314756)
			(xy 285.308276 -312.335854) (xy 285.261005 -312.349546) (xy 285.21215 -312.355478) (xy 285.162975 -312.353497)
			(xy 285.114756 -312.343653) (xy 285.06874 -312.326201) (xy 285.026119 -312.301594) (xy 284.987998 -312.270469)
			(xy 284.955363 -312.233632) (xy 284.92906 -312.192036) (xy 284.909769 -312.14676) (xy 284.897992 -312.098976)
			(xy 284.894032 -312.049922) (xy 283.605224 -312.049922) (xy 283.604729 -312.074529) (xy 283.596834 -312.123106)
			(xy 283.58125 -312.169787) (xy 283.558379 -312.213364) (xy 283.528814 -312.252708) (xy 283.493321 -312.2868)
			(xy 283.452818 -312.314756) (xy 283.408356 -312.335854) (xy 283.361085 -312.349546) (xy 283.31223 -312.355478)
			(xy 283.263055 -312.353497) (xy 283.214836 -312.343653) (xy 283.16882 -312.326201) (xy 283.126199 -312.301594)
			(xy 283.088078 -312.270469) (xy 283.055443 -312.233632) (xy 283.02914 -312.192036) (xy 283.009849 -312.14676)
			(xy 282.998072 -312.098976) (xy 282.994112 -312.049922) (xy 281.70505 -312.049922) (xy 281.704555 -312.074529)
			(xy 281.69666 -312.123106) (xy 281.681076 -312.169787) (xy 281.658205 -312.213364) (xy 281.62864 -312.252708)
			(xy 281.593147 -312.2868) (xy 281.552644 -312.314756) (xy 281.508182 -312.335854) (xy 281.460911 -312.349546)
			(xy 281.412056 -312.355478) (xy 281.362881 -312.353497) (xy 281.314662 -312.343653) (xy 281.268646 -312.326201)
			(xy 281.226025 -312.301594) (xy 281.187904 -312.270469) (xy 281.155269 -312.233632) (xy 281.128966 -312.192036)
			(xy 281.109675 -312.14676) (xy 281.097898 -312.098976) (xy 281.093938 -312.049922) (xy 279.80513 -312.049922)
			(xy 279.804635 -312.074529) (xy 279.79674 -312.123106) (xy 279.781156 -312.169787) (xy 279.758285 -312.213364)
			(xy 279.72872 -312.252708) (xy 279.693227 -312.2868) (xy 279.652724 -312.314756) (xy 279.608262 -312.335854)
			(xy 279.560991 -312.349546) (xy 279.512136 -312.355478) (xy 279.462961 -312.353497) (xy 279.414742 -312.343653)
			(xy 279.368726 -312.326201) (xy 279.326105 -312.301594) (xy 279.287984 -312.270469) (xy 279.255349 -312.233632)
			(xy 279.229046 -312.192036) (xy 279.209755 -312.14676) (xy 279.197978 -312.098976) (xy 279.194018 -312.049922)
			(xy 277.90521 -312.049922) (xy 277.904715 -312.074529) (xy 277.89682 -312.123106) (xy 277.881236 -312.169787)
			(xy 277.858365 -312.213364) (xy 277.8288 -312.252708) (xy 277.793307 -312.2868) (xy 277.752804 -312.314756)
			(xy 277.708342 -312.335854) (xy 277.661071 -312.349546) (xy 277.612216 -312.355478) (xy 277.563041 -312.353497)
			(xy 277.514822 -312.343653) (xy 277.468806 -312.326201) (xy 277.426185 -312.301594) (xy 277.388064 -312.270469)
			(xy 277.355429 -312.233632) (xy 277.329126 -312.192036) (xy 277.309835 -312.14676) (xy 277.298058 -312.098976)
			(xy 277.294098 -312.049922) (xy 276.005036 -312.049922) (xy 276.004541 -312.074529) (xy 275.996646 -312.123106)
			(xy 275.981062 -312.169787) (xy 275.958191 -312.213364) (xy 275.928626 -312.252708) (xy 275.893133 -312.2868)
			(xy 275.85263 -312.314756) (xy 275.808168 -312.335854) (xy 275.760897 -312.349546) (xy 275.712042 -312.355478)
			(xy 275.662867 -312.353497) (xy 275.614648 -312.343653) (xy 275.568632 -312.326201) (xy 275.526011 -312.301594)
			(xy 275.48789 -312.270469) (xy 275.455255 -312.233632) (xy 275.428952 -312.192036) (xy 275.409661 -312.14676)
			(xy 275.397884 -312.098976) (xy 275.393924 -312.049922) (xy 188.405262 -312.049922) (xy 188.404767 -312.074529)
			(xy 188.396872 -312.123106) (xy 188.381288 -312.169787) (xy 188.358417 -312.213364) (xy 188.328852 -312.252708)
			(xy 188.293359 -312.2868) (xy 188.252856 -312.314756) (xy 188.208394 -312.335854) (xy 188.161123 -312.349546)
			(xy 188.112268 -312.355478) (xy 188.063093 -312.353497) (xy 188.014874 -312.343653) (xy 187.968858 -312.326201)
			(xy 187.926237 -312.301594) (xy 187.888116 -312.270469) (xy 187.855481 -312.233632) (xy 187.829178 -312.192036)
			(xy 187.809887 -312.14676) (xy 187.79811 -312.098976) (xy 187.79415 -312.049922) (xy 186.505342 -312.049922)
			(xy 186.504847 -312.074529) (xy 186.496952 -312.123106) (xy 186.481368 -312.169787) (xy 186.458497 -312.213364)
			(xy 186.428932 -312.252708) (xy 186.393439 -312.2868) (xy 186.352936 -312.314756) (xy 186.308474 -312.335854)
			(xy 186.261203 -312.349546) (xy 186.212348 -312.355478) (xy 186.163173 -312.353497) (xy 186.114954 -312.343653)
			(xy 186.068938 -312.326201) (xy 186.026317 -312.301594) (xy 185.988196 -312.270469) (xy 185.955561 -312.233632)
			(xy 185.929258 -312.192036) (xy 185.909967 -312.14676) (xy 185.89819 -312.098976) (xy 185.89423 -312.049922)
			(xy 184.605168 -312.049922) (xy 184.604673 -312.074529) (xy 184.596778 -312.123106) (xy 184.581194 -312.169787)
			(xy 184.558323 -312.213364) (xy 184.528758 -312.252708) (xy 184.493265 -312.2868) (xy 184.452762 -312.314756)
			(xy 184.4083 -312.335854) (xy 184.361029 -312.349546) (xy 184.312174 -312.355478) (xy 184.262999 -312.353497)
			(xy 184.21478 -312.343653) (xy 184.168764 -312.326201) (xy 184.126143 -312.301594) (xy 184.088022 -312.270469)
			(xy 184.055387 -312.233632) (xy 184.029084 -312.192036) (xy 184.009793 -312.14676) (xy 183.998016 -312.098976)
			(xy 183.994056 -312.049922) (xy 182.705248 -312.049922) (xy 182.704753 -312.074529) (xy 182.696858 -312.123106)
			(xy 182.681274 -312.169787) (xy 182.658403 -312.213364) (xy 182.628838 -312.252708) (xy 182.593345 -312.2868)
			(xy 182.552842 -312.314756) (xy 182.50838 -312.335854) (xy 182.461109 -312.349546) (xy 182.412254 -312.355478)
			(xy 182.363079 -312.353497) (xy 182.31486 -312.343653) (xy 182.268844 -312.326201) (xy 182.226223 -312.301594)
			(xy 182.188102 -312.270469) (xy 182.155467 -312.233632) (xy 182.129164 -312.192036) (xy 182.109873 -312.14676)
			(xy 182.098096 -312.098976) (xy 182.094136 -312.049922) (xy 165.605206 -312.049922) (xy 165.604711 -312.074529)
			(xy 165.596816 -312.123106) (xy 165.581232 -312.169787) (xy 165.558361 -312.213364) (xy 165.528796 -312.252708)
			(xy 165.493303 -312.2868) (xy 165.4528 -312.314756) (xy 165.408338 -312.335854) (xy 165.361067 -312.349546)
			(xy 165.312212 -312.355478) (xy 165.263037 -312.353497) (xy 165.214818 -312.343653) (xy 165.168802 -312.326201)
			(xy 165.126181 -312.301594) (xy 165.08806 -312.270469) (xy 165.055425 -312.233632) (xy 165.029122 -312.192036)
			(xy 165.009831 -312.14676) (xy 164.998054 -312.098976) (xy 164.994094 -312.049922) (xy 163.705286 -312.049922)
			(xy 163.704791 -312.074529) (xy 163.696896 -312.123106) (xy 163.681312 -312.169787) (xy 163.658441 -312.213364)
			(xy 163.628876 -312.252708) (xy 163.593383 -312.2868) (xy 163.55288 -312.314756) (xy 163.508418 -312.335854)
			(xy 163.461147 -312.349546) (xy 163.412292 -312.355478) (xy 163.363117 -312.353497) (xy 163.314898 -312.343653)
			(xy 163.268882 -312.326201) (xy 163.226261 -312.301594) (xy 163.18814 -312.270469) (xy 163.155505 -312.233632)
			(xy 163.129202 -312.192036) (xy 163.109911 -312.14676) (xy 163.098134 -312.098976) (xy 163.094174 -312.049922)
			(xy 161.805366 -312.049922) (xy 161.804871 -312.074529) (xy 161.796976 -312.123106) (xy 161.781392 -312.169787)
			(xy 161.758521 -312.213364) (xy 161.728956 -312.252708) (xy 161.693463 -312.2868) (xy 161.65296 -312.314756)
			(xy 161.608498 -312.335854) (xy 161.561227 -312.349546) (xy 161.512372 -312.355478) (xy 161.463197 -312.353497)
			(xy 161.414978 -312.343653) (xy 161.368962 -312.326201) (xy 161.326341 -312.301594) (xy 161.28822 -312.270469)
			(xy 161.255585 -312.233632) (xy 161.229282 -312.192036) (xy 161.209991 -312.14676) (xy 161.198214 -312.098976)
			(xy 161.194254 -312.049922) (xy 159.905192 -312.049922) (xy 159.904697 -312.074529) (xy 159.896802 -312.123106)
			(xy 159.881218 -312.169787) (xy 159.858347 -312.213364) (xy 159.828782 -312.252708) (xy 159.793289 -312.2868)
			(xy 159.752786 -312.314756) (xy 159.708324 -312.335854) (xy 159.661053 -312.349546) (xy 159.612198 -312.355478)
			(xy 159.563023 -312.353497) (xy 159.514804 -312.343653) (xy 159.468788 -312.326201) (xy 159.426167 -312.301594)
			(xy 159.388046 -312.270469) (xy 159.355411 -312.233632) (xy 159.329108 -312.192036) (xy 159.309817 -312.14676)
			(xy 159.29804 -312.098976) (xy 159.29408 -312.049922) (xy 57.105296 -312.049922) (xy 57.104801 -312.074529)
			(xy 57.096906 -312.123106) (xy 57.081322 -312.169787) (xy 57.058451 -312.213364) (xy 57.028886 -312.252708)
			(xy 56.993393 -312.2868) (xy 56.95289 -312.314756) (xy 56.908428 -312.335854) (xy 56.861157 -312.349546)
			(xy 56.812302 -312.355478) (xy 56.763127 -312.353497) (xy 56.714908 -312.343653) (xy 56.668892 -312.326201)
			(xy 56.626271 -312.301594) (xy 56.58815 -312.270469) (xy 56.555515 -312.233632) (xy 56.529212 -312.192036)
			(xy 56.509921 -312.14676) (xy 56.498144 -312.098976) (xy 56.494184 -312.049922) (xy 55.205122 -312.049922)
			(xy 55.204627 -312.074529) (xy 55.196732 -312.123106) (xy 55.181148 -312.169787) (xy 55.158277 -312.213364)
			(xy 55.128712 -312.252708) (xy 55.093219 -312.2868) (xy 55.052716 -312.314756) (xy 55.008254 -312.335854)
			(xy 54.960983 -312.349546) (xy 54.912128 -312.355478) (xy 54.862953 -312.353497) (xy 54.814734 -312.343653)
			(xy 54.768718 -312.326201) (xy 54.726097 -312.301594) (xy 54.687976 -312.270469) (xy 54.655341 -312.233632)
			(xy 54.629038 -312.192036) (xy 54.609747 -312.14676) (xy 54.59797 -312.098976) (xy 54.59401 -312.049922)
			(xy 53.305202 -312.049922) (xy 53.304707 -312.074529) (xy 53.296812 -312.123106) (xy 53.281228 -312.169787)
			(xy 53.258357 -312.213364) (xy 53.228792 -312.252708) (xy 53.193299 -312.2868) (xy 53.152796 -312.314756)
			(xy 53.108334 -312.335854) (xy 53.061063 -312.349546) (xy 53.012208 -312.355478) (xy 52.963033 -312.353497)
			(xy 52.914814 -312.343653) (xy 52.868798 -312.326201) (xy 52.826177 -312.301594) (xy 52.788056 -312.270469)
			(xy 52.755421 -312.233632) (xy 52.729118 -312.192036) (xy 52.709827 -312.14676) (xy 52.69805 -312.098976)
			(xy 52.69409 -312.049922) (xy 51.405282 -312.049922) (xy 51.404787 -312.074529) (xy 51.396892 -312.123106)
			(xy 51.381308 -312.169787) (xy 51.358437 -312.213364) (xy 51.328872 -312.252708) (xy 51.293379 -312.2868)
			(xy 51.252876 -312.314756) (xy 51.208414 -312.335854) (xy 51.161143 -312.349546) (xy 51.112288 -312.355478)
			(xy 51.063113 -312.353497) (xy 51.014894 -312.343653) (xy 50.968878 -312.326201) (xy 50.926257 -312.301594)
			(xy 50.888136 -312.270469) (xy 50.855501 -312.233632) (xy 50.829198 -312.192036) (xy 50.809907 -312.14676)
			(xy 50.79813 -312.098976) (xy 50.79417 -312.049922) (xy 49.505108 -312.049922) (xy 49.504613 -312.074529)
			(xy 49.496718 -312.123106) (xy 49.481134 -312.169787) (xy 49.458263 -312.213364) (xy 49.428698 -312.252708)
			(xy 49.393205 -312.2868) (xy 49.352702 -312.314756) (xy 49.30824 -312.335854) (xy 49.260969 -312.349546)
			(xy 49.212114 -312.355478) (xy 49.162939 -312.353497) (xy 49.11472 -312.343653) (xy 49.068704 -312.326201)
			(xy 49.026083 -312.301594) (xy 48.987962 -312.270469) (xy 48.955327 -312.233632) (xy 48.929024 -312.192036)
			(xy 48.909733 -312.14676) (xy 48.897956 -312.098976) (xy 48.893996 -312.049922) (xy 47.605188 -312.049922)
			(xy 47.604693 -312.074529) (xy 47.596798 -312.123106) (xy 47.581214 -312.169787) (xy 47.558343 -312.213364)
			(xy 47.528778 -312.252708) (xy 47.493285 -312.2868) (xy 47.452782 -312.314756) (xy 47.40832 -312.335854)
			(xy 47.361049 -312.349546) (xy 47.312194 -312.355478) (xy 47.263019 -312.353497) (xy 47.2148 -312.343653)
			(xy 47.168784 -312.326201) (xy 47.126163 -312.301594) (xy 47.088042 -312.270469) (xy 47.055407 -312.233632)
			(xy 47.029104 -312.192036) (xy 47.009813 -312.14676) (xy 46.998036 -312.098976) (xy 46.994076 -312.049922)
			(xy 45.705268 -312.049922) (xy 45.704773 -312.074529) (xy 45.696878 -312.123106) (xy 45.681294 -312.169787)
			(xy 45.658423 -312.213364) (xy 45.628858 -312.252708) (xy 45.593365 -312.2868) (xy 45.552862 -312.314756)
			(xy 45.5084 -312.335854) (xy 45.461129 -312.349546) (xy 45.412274 -312.355478) (xy 45.363099 -312.353497)
			(xy 45.31488 -312.343653) (xy 45.268864 -312.326201) (xy 45.226243 -312.301594) (xy 45.188122 -312.270469)
			(xy 45.155487 -312.233632) (xy 45.129184 -312.192036) (xy 45.109893 -312.14676) (xy 45.098116 -312.098976)
			(xy 45.094156 -312.049922) (xy 43.805094 -312.049922) (xy 43.804599 -312.074529) (xy 43.796704 -312.123106)
			(xy 43.78112 -312.169787) (xy 43.758249 -312.213364) (xy 43.728684 -312.252708) (xy 43.693191 -312.2868)
			(xy 43.652688 -312.314756) (xy 43.608226 -312.335854) (xy 43.560955 -312.349546) (xy 43.5121 -312.355478)
			(xy 43.462925 -312.353497) (xy 43.414706 -312.343653) (xy 43.36869 -312.326201) (xy 43.326069 -312.301594)
			(xy 43.287948 -312.270469) (xy 43.255313 -312.233632) (xy 43.22901 -312.192036) (xy 43.209719 -312.14676)
			(xy 43.197942 -312.098976) (xy 43.193982 -312.049922) (xy 0.508 -312.049922) (xy 0.508 -312.999882)
			(xy 44.143942 -312.999882) (xy 44.147902 -312.950828) (xy 44.159679 -312.903044) (xy 44.17897 -312.857768)
			(xy 44.205273 -312.816172) (xy 44.237908 -312.779335) (xy 44.276029 -312.74821) (xy 44.31865 -312.723603)
			(xy 44.364666 -312.706151) (xy 44.412885 -312.696307) (xy 44.46206 -312.694326) (xy 44.510915 -312.700258)
			(xy 44.558186 -312.71395) (xy 44.602648 -312.735048) (xy 44.643151 -312.763004) (xy 44.678644 -312.797096)
			(xy 44.708209 -312.83644) (xy 44.73108 -312.880017) (xy 44.746664 -312.926698) (xy 44.754559 -312.975275)
			(xy 44.755054 -312.999882) (xy 46.044116 -312.999882) (xy 46.048076 -312.950828) (xy 46.059853 -312.903044)
			(xy 46.079144 -312.857768) (xy 46.105447 -312.816172) (xy 46.138082 -312.779335) (xy 46.176203 -312.74821)
			(xy 46.218824 -312.723603) (xy 46.26484 -312.706151) (xy 46.313059 -312.696307) (xy 46.362234 -312.694326)
			(xy 46.411089 -312.700258) (xy 46.45836 -312.71395) (xy 46.502822 -312.735048) (xy 46.543325 -312.763004)
			(xy 46.578818 -312.797096) (xy 46.608383 -312.83644) (xy 46.631254 -312.880017) (xy 46.646838 -312.926698)
			(xy 46.654733 -312.975275) (xy 46.655228 -312.999882) (xy 47.944036 -312.999882) (xy 47.947996 -312.950828)
			(xy 47.959773 -312.903044) (xy 47.979064 -312.857768) (xy 48.005367 -312.816172) (xy 48.038002 -312.779335)
			(xy 48.076123 -312.74821) (xy 48.118744 -312.723603) (xy 48.16476 -312.706151) (xy 48.212979 -312.696307)
			(xy 48.262154 -312.694326) (xy 48.311009 -312.700258) (xy 48.35828 -312.71395) (xy 48.402742 -312.735048)
			(xy 48.443245 -312.763004) (xy 48.478738 -312.797096) (xy 48.508303 -312.83644) (xy 48.531174 -312.880017)
			(xy 48.546758 -312.926698) (xy 48.554653 -312.975275) (xy 48.555148 -312.999882) (xy 49.843956 -312.999882)
			(xy 49.847916 -312.950828) (xy 49.859693 -312.903044) (xy 49.878984 -312.857768) (xy 49.905287 -312.816172)
			(xy 49.937922 -312.779335) (xy 49.976043 -312.74821) (xy 50.018664 -312.723603) (xy 50.06468 -312.706151)
			(xy 50.112899 -312.696307) (xy 50.162074 -312.694326) (xy 50.210929 -312.700258) (xy 50.2582 -312.71395)
			(xy 50.302662 -312.735048) (xy 50.343165 -312.763004) (xy 50.378658 -312.797096) (xy 50.408223 -312.83644)
			(xy 50.431094 -312.880017) (xy 50.446678 -312.926698) (xy 50.454573 -312.975275) (xy 50.455068 -312.999882)
			(xy 51.74413 -312.999882) (xy 51.74809 -312.950828) (xy 51.759867 -312.903044) (xy 51.779158 -312.857768)
			(xy 51.805461 -312.816172) (xy 51.838096 -312.779335) (xy 51.876217 -312.74821) (xy 51.918838 -312.723603)
			(xy 51.964854 -312.706151) (xy 52.013073 -312.696307) (xy 52.062248 -312.694326) (xy 52.111103 -312.700258)
			(xy 52.158374 -312.71395) (xy 52.202836 -312.735048) (xy 52.243339 -312.763004) (xy 52.278832 -312.797096)
			(xy 52.308397 -312.83644) (xy 52.331268 -312.880017) (xy 52.346852 -312.926698) (xy 52.354747 -312.975275)
			(xy 52.355242 -312.999882) (xy 53.64405 -312.999882) (xy 53.64801 -312.950828) (xy 53.659787 -312.903044)
			(xy 53.679078 -312.857768) (xy 53.705381 -312.816172) (xy 53.738016 -312.779335) (xy 53.776137 -312.74821)
			(xy 53.818758 -312.723603) (xy 53.864774 -312.706151) (xy 53.912993 -312.696307) (xy 53.962168 -312.694326)
			(xy 54.011023 -312.700258) (xy 54.058294 -312.71395) (xy 54.102756 -312.735048) (xy 54.143259 -312.763004)
			(xy 54.178752 -312.797096) (xy 54.208317 -312.83644) (xy 54.231188 -312.880017) (xy 54.246772 -312.926698)
			(xy 54.254667 -312.975275) (xy 54.255162 -312.999882) (xy 55.54397 -312.999882) (xy 55.54793 -312.950828)
			(xy 55.559707 -312.903044) (xy 55.578998 -312.857768) (xy 55.605301 -312.816172) (xy 55.637936 -312.779335)
			(xy 55.676057 -312.74821) (xy 55.718678 -312.723603) (xy 55.764694 -312.706151) (xy 55.812913 -312.696307)
			(xy 55.862088 -312.694326) (xy 55.910943 -312.700258) (xy 55.958214 -312.71395) (xy 56.002676 -312.735048)
			(xy 56.043179 -312.763004) (xy 56.078672 -312.797096) (xy 56.108237 -312.83644) (xy 56.131108 -312.880017)
			(xy 56.146692 -312.926698) (xy 56.154587 -312.975275) (xy 56.155082 -312.999882) (xy 57.444144 -312.999882)
			(xy 57.448104 -312.950828) (xy 57.459881 -312.903044) (xy 57.479172 -312.857768) (xy 57.505475 -312.816172)
			(xy 57.53811 -312.779335) (xy 57.576231 -312.74821) (xy 57.618852 -312.723603) (xy 57.664868 -312.706151)
			(xy 57.713087 -312.696307) (xy 57.762262 -312.694326) (xy 57.811117 -312.700258) (xy 57.858388 -312.71395)
			(xy 57.90285 -312.735048) (xy 57.943353 -312.763004) (xy 57.978846 -312.797096) (xy 58.008411 -312.83644)
			(xy 58.031282 -312.880017) (xy 58.046866 -312.926698) (xy 58.054761 -312.975275) (xy 58.055256 -312.999882)
			(xy 160.24404 -312.999882) (xy 160.248 -312.950828) (xy 160.259777 -312.903044) (xy 160.279068 -312.857768)
			(xy 160.305371 -312.816172) (xy 160.338006 -312.779335) (xy 160.376127 -312.74821) (xy 160.418748 -312.723603)
			(xy 160.464764 -312.706151) (xy 160.512983 -312.696307) (xy 160.562158 -312.694326) (xy 160.611013 -312.700258)
			(xy 160.658284 -312.71395) (xy 160.702746 -312.735048) (xy 160.743249 -312.763004) (xy 160.778742 -312.797096)
			(xy 160.808307 -312.83644) (xy 160.831178 -312.880017) (xy 160.846762 -312.926698) (xy 160.854657 -312.975275)
			(xy 160.855152 -312.999882) (xy 162.144214 -312.999882) (xy 162.148174 -312.950828) (xy 162.159951 -312.903044)
			(xy 162.179242 -312.857768) (xy 162.205545 -312.816172) (xy 162.23818 -312.779335) (xy 162.276301 -312.74821)
			(xy 162.318922 -312.723603) (xy 162.364938 -312.706151) (xy 162.413157 -312.696307) (xy 162.462332 -312.694326)
			(xy 162.511187 -312.700258) (xy 162.558458 -312.71395) (xy 162.60292 -312.735048) (xy 162.643423 -312.763004)
			(xy 162.678916 -312.797096) (xy 162.708481 -312.83644) (xy 162.731352 -312.880017) (xy 162.746936 -312.926698)
			(xy 162.754831 -312.975275) (xy 162.755326 -312.999882) (xy 164.044134 -312.999882) (xy 164.048094 -312.950828)
			(xy 164.059871 -312.903044) (xy 164.079162 -312.857768) (xy 164.105465 -312.816172) (xy 164.1381 -312.779335)
			(xy 164.176221 -312.74821) (xy 164.218842 -312.723603) (xy 164.264858 -312.706151) (xy 164.313077 -312.696307)
			(xy 164.362252 -312.694326) (xy 164.411107 -312.700258) (xy 164.458378 -312.71395) (xy 164.50284 -312.735048)
			(xy 164.543343 -312.763004) (xy 164.578836 -312.797096) (xy 164.608401 -312.83644) (xy 164.631272 -312.880017)
			(xy 164.646856 -312.926698) (xy 164.654751 -312.975275) (xy 164.655246 -312.999882) (xy 165.944054 -312.999882)
			(xy 165.948014 -312.950828) (xy 165.959791 -312.903044) (xy 165.979082 -312.857768) (xy 166.005385 -312.816172)
			(xy 166.03802 -312.779335) (xy 166.076141 -312.74821) (xy 166.118762 -312.723603) (xy 166.164778 -312.706151)
			(xy 166.212997 -312.696307) (xy 166.262172 -312.694326) (xy 166.311027 -312.700258) (xy 166.358298 -312.71395)
			(xy 166.40276 -312.735048) (xy 166.443263 -312.763004) (xy 166.478756 -312.797096) (xy 166.508321 -312.83644)
			(xy 166.531192 -312.880017) (xy 166.546776 -312.926698) (xy 166.554671 -312.975275) (xy 166.555166 -312.999882)
			(xy 183.044096 -312.999882) (xy 183.048056 -312.950828) (xy 183.059833 -312.903044) (xy 183.079124 -312.857768)
			(xy 183.105427 -312.816172) (xy 183.138062 -312.779335) (xy 183.176183 -312.74821) (xy 183.218804 -312.723603)
			(xy 183.26482 -312.706151) (xy 183.313039 -312.696307) (xy 183.362214 -312.694326) (xy 183.411069 -312.700258)
			(xy 183.45834 -312.71395) (xy 183.502802 -312.735048) (xy 183.543305 -312.763004) (xy 183.578798 -312.797096)
			(xy 183.608363 -312.83644) (xy 183.631234 -312.880017) (xy 183.646818 -312.926698) (xy 183.654713 -312.975275)
			(xy 183.655208 -312.999882) (xy 184.94427 -312.999882) (xy 184.94823 -312.950828) (xy 184.960007 -312.903044)
			(xy 184.979298 -312.857768) (xy 185.005601 -312.816172) (xy 185.038236 -312.779335) (xy 185.076357 -312.74821)
			(xy 185.118978 -312.723603) (xy 185.164994 -312.706151) (xy 185.213213 -312.696307) (xy 185.262388 -312.694326)
			(xy 185.311243 -312.700258) (xy 185.358514 -312.71395) (xy 185.402976 -312.735048) (xy 185.443479 -312.763004)
			(xy 185.478972 -312.797096) (xy 185.508537 -312.83644) (xy 185.531408 -312.880017) (xy 185.546992 -312.926698)
			(xy 185.554887 -312.975275) (xy 185.555382 -312.999882) (xy 186.84419 -312.999882) (xy 186.84815 -312.950828)
			(xy 186.859927 -312.903044) (xy 186.879218 -312.857768) (xy 186.905521 -312.816172) (xy 186.938156 -312.779335)
			(xy 186.976277 -312.74821) (xy 187.018898 -312.723603) (xy 187.064914 -312.706151) (xy 187.113133 -312.696307)
			(xy 187.162308 -312.694326) (xy 187.211163 -312.700258) (xy 187.258434 -312.71395) (xy 187.302896 -312.735048)
			(xy 187.343399 -312.763004) (xy 187.378892 -312.797096) (xy 187.408457 -312.83644) (xy 187.431328 -312.880017)
			(xy 187.446912 -312.926698) (xy 187.454807 -312.975275) (xy 187.455302 -312.999882) (xy 188.74411 -312.999882)
			(xy 188.74807 -312.950828) (xy 188.759847 -312.903044) (xy 188.779138 -312.857768) (xy 188.805441 -312.816172)
			(xy 188.838076 -312.779335) (xy 188.876197 -312.74821) (xy 188.918818 -312.723603) (xy 188.964834 -312.706151)
			(xy 189.013053 -312.696307) (xy 189.062228 -312.694326) (xy 189.111083 -312.700258) (xy 189.158354 -312.71395)
			(xy 189.202816 -312.735048) (xy 189.243319 -312.763004) (xy 189.278812 -312.797096) (xy 189.308377 -312.83644)
			(xy 189.331248 -312.880017) (xy 189.346832 -312.926698) (xy 189.354727 -312.975275) (xy 189.355222 -312.999882)
			(xy 276.343884 -312.999882) (xy 276.347844 -312.950828) (xy 276.359621 -312.903044) (xy 276.378912 -312.857768)
			(xy 276.405215 -312.816172) (xy 276.43785 -312.779335) (xy 276.475971 -312.74821) (xy 276.518592 -312.723603)
			(xy 276.564608 -312.706151) (xy 276.612827 -312.696307) (xy 276.662002 -312.694326) (xy 276.710857 -312.700258)
			(xy 276.758128 -312.71395) (xy 276.80259 -312.735048) (xy 276.843093 -312.763004) (xy 276.878586 -312.797096)
			(xy 276.908151 -312.83644) (xy 276.931022 -312.880017) (xy 276.946606 -312.926698) (xy 276.954501 -312.975275)
			(xy 276.954996 -312.999882) (xy 278.244058 -312.999882) (xy 278.248018 -312.950828) (xy 278.259795 -312.903044)
			(xy 278.279086 -312.857768) (xy 278.305389 -312.816172) (xy 278.338024 -312.779335) (xy 278.376145 -312.74821)
			(xy 278.418766 -312.723603) (xy 278.464782 -312.706151) (xy 278.513001 -312.696307) (xy 278.562176 -312.694326)
			(xy 278.611031 -312.700258) (xy 278.658302 -312.71395) (xy 278.702764 -312.735048) (xy 278.743267 -312.763004)
			(xy 278.77876 -312.797096) (xy 278.808325 -312.83644) (xy 278.831196 -312.880017) (xy 278.84678 -312.926698)
			(xy 278.854675 -312.975275) (xy 278.85517 -312.999882) (xy 280.143978 -312.999882) (xy 280.147938 -312.950828)
			(xy 280.159715 -312.903044) (xy 280.179006 -312.857768) (xy 280.205309 -312.816172) (xy 280.237944 -312.779335)
			(xy 280.276065 -312.74821) (xy 280.318686 -312.723603) (xy 280.364702 -312.706151) (xy 280.412921 -312.696307)
			(xy 280.462096 -312.694326) (xy 280.510951 -312.700258) (xy 280.558222 -312.71395) (xy 280.602684 -312.735048)
			(xy 280.643187 -312.763004) (xy 280.67868 -312.797096) (xy 280.708245 -312.83644) (xy 280.731116 -312.880017)
			(xy 280.7467 -312.926698) (xy 280.754595 -312.975275) (xy 280.75509 -312.999882) (xy 282.043898 -312.999882)
			(xy 282.047858 -312.950828) (xy 282.059635 -312.903044) (xy 282.078926 -312.857768) (xy 282.105229 -312.816172)
			(xy 282.137864 -312.779335) (xy 282.175985 -312.74821) (xy 282.218606 -312.723603) (xy 282.264622 -312.706151)
			(xy 282.312841 -312.696307) (xy 282.362016 -312.694326) (xy 282.410871 -312.700258) (xy 282.458142 -312.71395)
			(xy 282.502604 -312.735048) (xy 282.543107 -312.763004) (xy 282.5786 -312.797096) (xy 282.608165 -312.83644)
			(xy 282.631036 -312.880017) (xy 282.64662 -312.926698) (xy 282.654515 -312.975275) (xy 282.65501 -312.999882)
			(xy 283.944072 -312.999882) (xy 283.948032 -312.950828) (xy 283.959809 -312.903044) (xy 283.9791 -312.857768)
			(xy 284.005403 -312.816172) (xy 284.038038 -312.779335) (xy 284.076159 -312.74821) (xy 284.11878 -312.723603)
			(xy 284.164796 -312.706151) (xy 284.213015 -312.696307) (xy 284.26219 -312.694326) (xy 284.311045 -312.700258)
			(xy 284.358316 -312.71395) (xy 284.402778 -312.735048) (xy 284.443281 -312.763004) (xy 284.478774 -312.797096)
			(xy 284.508339 -312.83644) (xy 284.53121 -312.880017) (xy 284.546794 -312.926698) (xy 284.554689 -312.975275)
			(xy 284.555184 -312.999882) (xy 285.843992 -312.999882) (xy 285.847952 -312.950828) (xy 285.859729 -312.903044)
			(xy 285.87902 -312.857768) (xy 285.905323 -312.816172) (xy 285.937958 -312.779335) (xy 285.976079 -312.74821)
			(xy 286.0187 -312.723603) (xy 286.064716 -312.706151) (xy 286.112935 -312.696307) (xy 286.16211 -312.694326)
			(xy 286.210965 -312.700258) (xy 286.258236 -312.71395) (xy 286.302698 -312.735048) (xy 286.343201 -312.763004)
			(xy 286.378694 -312.797096) (xy 286.408259 -312.83644) (xy 286.43113 -312.880017) (xy 286.446714 -312.926698)
			(xy 286.454609 -312.975275) (xy 286.455104 -312.999882) (xy 287.743912 -312.999882) (xy 287.747872 -312.950828)
			(xy 287.759649 -312.903044) (xy 287.77894 -312.857768) (xy 287.805243 -312.816172) (xy 287.837878 -312.779335)
			(xy 287.875999 -312.74821) (xy 287.91862 -312.723603) (xy 287.964636 -312.706151) (xy 288.012855 -312.696307)
			(xy 288.06203 -312.694326) (xy 288.110885 -312.700258) (xy 288.158156 -312.71395) (xy 288.202618 -312.735048)
			(xy 288.243121 -312.763004) (xy 288.278614 -312.797096) (xy 288.308179 -312.83644) (xy 288.33105 -312.880017)
			(xy 288.346634 -312.926698) (xy 288.354529 -312.975275) (xy 288.355024 -312.999882) (xy 289.644086 -312.999882)
			(xy 289.648046 -312.950828) (xy 289.659823 -312.903044) (xy 289.679114 -312.857768) (xy 289.705417 -312.816172)
			(xy 289.738052 -312.779335) (xy 289.776173 -312.74821) (xy 289.818794 -312.723603) (xy 289.86481 -312.706151)
			(xy 289.913029 -312.696307) (xy 289.962204 -312.694326) (xy 290.011059 -312.700258) (xy 290.05833 -312.71395)
			(xy 290.102792 -312.735048) (xy 290.143295 -312.763004) (xy 290.178788 -312.797096) (xy 290.208353 -312.83644)
			(xy 290.231224 -312.880017) (xy 290.246808 -312.926698) (xy 290.254703 -312.975275) (xy 290.255198 -312.999882)
			(xy 392.443982 -312.999882) (xy 392.447942 -312.950828) (xy 392.459719 -312.903044) (xy 392.47901 -312.857768)
			(xy 392.505313 -312.816172) (xy 392.537948 -312.779335) (xy 392.576069 -312.74821) (xy 392.61869 -312.723603)
			(xy 392.664706 -312.706151) (xy 392.712925 -312.696307) (xy 392.7621 -312.694326) (xy 392.810955 -312.700258)
			(xy 392.858226 -312.71395) (xy 392.902688 -312.735048) (xy 392.943191 -312.763004) (xy 392.978684 -312.797096)
			(xy 393.008249 -312.83644) (xy 393.03112 -312.880017) (xy 393.046704 -312.926698) (xy 393.054599 -312.975275)
			(xy 393.055094 -312.999882) (xy 394.344156 -312.999882) (xy 394.348116 -312.950828) (xy 394.359893 -312.903044)
			(xy 394.379184 -312.857768) (xy 394.405487 -312.816172) (xy 394.438122 -312.779335) (xy 394.476243 -312.74821)
			(xy 394.518864 -312.723603) (xy 394.56488 -312.706151) (xy 394.613099 -312.696307) (xy 394.662274 -312.694326)
			(xy 394.711129 -312.700258) (xy 394.7584 -312.71395) (xy 394.802862 -312.735048) (xy 394.843365 -312.763004)
			(xy 394.878858 -312.797096) (xy 394.908423 -312.83644) (xy 394.931294 -312.880017) (xy 394.946878 -312.926698)
			(xy 394.954773 -312.975275) (xy 394.955268 -312.999882) (xy 396.244076 -312.999882) (xy 396.248036 -312.950828)
			(xy 396.259813 -312.903044) (xy 396.279104 -312.857768) (xy 396.305407 -312.816172) (xy 396.338042 -312.779335)
			(xy 396.376163 -312.74821) (xy 396.418784 -312.723603) (xy 396.4648 -312.706151) (xy 396.513019 -312.696307)
			(xy 396.562194 -312.694326) (xy 396.611049 -312.700258) (xy 396.65832 -312.71395) (xy 396.702782 -312.735048)
			(xy 396.743285 -312.763004) (xy 396.778778 -312.797096) (xy 396.808343 -312.83644) (xy 396.831214 -312.880017)
			(xy 396.846798 -312.926698) (xy 396.854693 -312.975275) (xy 396.855188 -312.999882) (xy 398.143996 -312.999882)
			(xy 398.147956 -312.950828) (xy 398.159733 -312.903044) (xy 398.179024 -312.857768) (xy 398.205327 -312.816172)
			(xy 398.237962 -312.779335) (xy 398.276083 -312.74821) (xy 398.318704 -312.723603) (xy 398.36472 -312.706151)
			(xy 398.412939 -312.696307) (xy 398.462114 -312.694326) (xy 398.510969 -312.700258) (xy 398.55824 -312.71395)
			(xy 398.602702 -312.735048) (xy 398.643205 -312.763004) (xy 398.678698 -312.797096) (xy 398.708263 -312.83644)
			(xy 398.731134 -312.880017) (xy 398.746718 -312.926698) (xy 398.754613 -312.975275) (xy 398.755108 -312.999882)
			(xy 415.244038 -312.999882) (xy 415.247998 -312.950828) (xy 415.259775 -312.903044) (xy 415.279066 -312.857768)
			(xy 415.305369 -312.816172) (xy 415.338004 -312.779335) (xy 415.376125 -312.74821) (xy 415.418746 -312.723603)
			(xy 415.464762 -312.706151) (xy 415.512981 -312.696307) (xy 415.562156 -312.694326) (xy 415.611011 -312.700258)
			(xy 415.658282 -312.71395) (xy 415.702744 -312.735048) (xy 415.743247 -312.763004) (xy 415.77874 -312.797096)
			(xy 415.808305 -312.83644) (xy 415.831176 -312.880017) (xy 415.84676 -312.926698) (xy 415.854655 -312.975275)
			(xy 415.85515 -312.999882) (xy 417.144212 -312.999882) (xy 417.148172 -312.950828) (xy 417.159949 -312.903044)
			(xy 417.17924 -312.857768) (xy 417.205543 -312.816172) (xy 417.238178 -312.779335) (xy 417.276299 -312.74821)
			(xy 417.31892 -312.723603) (xy 417.364936 -312.706151) (xy 417.413155 -312.696307) (xy 417.46233 -312.694326)
			(xy 417.511185 -312.700258) (xy 417.558456 -312.71395) (xy 417.602918 -312.735048) (xy 417.643421 -312.763004)
			(xy 417.678914 -312.797096) (xy 417.708479 -312.83644) (xy 417.73135 -312.880017) (xy 417.746934 -312.926698)
			(xy 417.754829 -312.975275) (xy 417.755324 -312.999882) (xy 419.044132 -312.999882) (xy 419.048092 -312.950828)
			(xy 419.059869 -312.903044) (xy 419.07916 -312.857768) (xy 419.105463 -312.816172) (xy 419.138098 -312.779335)
			(xy 419.176219 -312.74821) (xy 419.21884 -312.723603) (xy 419.264856 -312.706151) (xy 419.313075 -312.696307)
			(xy 419.36225 -312.694326) (xy 419.411105 -312.700258) (xy 419.458376 -312.71395) (xy 419.502838 -312.735048)
			(xy 419.543341 -312.763004) (xy 419.578834 -312.797096) (xy 419.608399 -312.83644) (xy 419.63127 -312.880017)
			(xy 419.646854 -312.926698) (xy 419.654749 -312.975275) (xy 419.655244 -312.999882) (xy 420.944052 -312.999882)
			(xy 420.948012 -312.950828) (xy 420.959789 -312.903044) (xy 420.97908 -312.857768) (xy 421.005383 -312.816172)
			(xy 421.038018 -312.779335) (xy 421.076139 -312.74821) (xy 421.11876 -312.723603) (xy 421.164776 -312.706151)
			(xy 421.212995 -312.696307) (xy 421.26217 -312.694326) (xy 421.311025 -312.700258) (xy 421.358296 -312.71395)
			(xy 421.402758 -312.735048) (xy 421.443261 -312.763004) (xy 421.478754 -312.797096) (xy 421.508319 -312.83644)
			(xy 421.53119 -312.880017) (xy 421.546774 -312.926698) (xy 421.554669 -312.975275) (xy 421.555164 -312.999882)
			(xy 421.554669 -313.024489) (xy 421.546774 -313.073066) (xy 421.53119 -313.119747) (xy 421.508319 -313.163324)
			(xy 421.478754 -313.202668) (xy 421.443261 -313.23676) (xy 421.402758 -313.264716) (xy 421.358296 -313.285814)
			(xy 421.311025 -313.299506) (xy 421.26217 -313.305438) (xy 421.212995 -313.303457) (xy 421.164776 -313.293613)
			(xy 421.11876 -313.276161) (xy 421.076139 -313.251554) (xy 421.038018 -313.220429) (xy 421.005383 -313.183592)
			(xy 420.97908 -313.141996) (xy 420.959789 -313.09672) (xy 420.948012 -313.048936) (xy 420.944052 -312.999882)
			(xy 419.655244 -312.999882) (xy 419.654749 -313.024489) (xy 419.646854 -313.073066) (xy 419.63127 -313.119747)
			(xy 419.608399 -313.163324) (xy 419.578834 -313.202668) (xy 419.543341 -313.23676) (xy 419.502838 -313.264716)
			(xy 419.458376 -313.285814) (xy 419.411105 -313.299506) (xy 419.36225 -313.305438) (xy 419.313075 -313.303457)
			(xy 419.264856 -313.293613) (xy 419.21884 -313.276161) (xy 419.176219 -313.251554) (xy 419.138098 -313.220429)
			(xy 419.105463 -313.183592) (xy 419.07916 -313.141996) (xy 419.059869 -313.09672) (xy 419.048092 -313.048936)
			(xy 419.044132 -312.999882) (xy 417.755324 -312.999882) (xy 417.754829 -313.024489) (xy 417.746934 -313.073066)
			(xy 417.73135 -313.119747) (xy 417.708479 -313.163324) (xy 417.678914 -313.202668) (xy 417.643421 -313.23676)
			(xy 417.602918 -313.264716) (xy 417.558456 -313.285814) (xy 417.511185 -313.299506) (xy 417.46233 -313.305438)
			(xy 417.413155 -313.303457) (xy 417.364936 -313.293613) (xy 417.31892 -313.276161) (xy 417.276299 -313.251554)
			(xy 417.238178 -313.220429) (xy 417.205543 -313.183592) (xy 417.17924 -313.141996) (xy 417.159949 -313.09672)
			(xy 417.148172 -313.048936) (xy 417.144212 -312.999882) (xy 415.85515 -312.999882) (xy 415.854655 -313.024489)
			(xy 415.84676 -313.073066) (xy 415.831176 -313.119747) (xy 415.808305 -313.163324) (xy 415.77874 -313.202668)
			(xy 415.743247 -313.23676) (xy 415.702744 -313.264716) (xy 415.658282 -313.285814) (xy 415.611011 -313.299506)
			(xy 415.562156 -313.305438) (xy 415.512981 -313.303457) (xy 415.464762 -313.293613) (xy 415.418746 -313.276161)
			(xy 415.376125 -313.251554) (xy 415.338004 -313.220429) (xy 415.305369 -313.183592) (xy 415.279066 -313.141996)
			(xy 415.259775 -313.09672) (xy 415.247998 -313.048936) (xy 415.244038 -312.999882) (xy 398.755108 -312.999882)
			(xy 398.754613 -313.024489) (xy 398.746718 -313.073066) (xy 398.731134 -313.119747) (xy 398.708263 -313.163324)
			(xy 398.678698 -313.202668) (xy 398.643205 -313.23676) (xy 398.602702 -313.264716) (xy 398.55824 -313.285814)
			(xy 398.510969 -313.299506) (xy 398.462114 -313.305438) (xy 398.412939 -313.303457) (xy 398.36472 -313.293613)
			(xy 398.318704 -313.276161) (xy 398.276083 -313.251554) (xy 398.237962 -313.220429) (xy 398.205327 -313.183592)
			(xy 398.179024 -313.141996) (xy 398.159733 -313.09672) (xy 398.147956 -313.048936) (xy 398.143996 -312.999882)
			(xy 396.855188 -312.999882) (xy 396.854693 -313.024489) (xy 396.846798 -313.073066) (xy 396.831214 -313.119747)
			(xy 396.808343 -313.163324) (xy 396.778778 -313.202668) (xy 396.743285 -313.23676) (xy 396.702782 -313.264716)
			(xy 396.65832 -313.285814) (xy 396.611049 -313.299506) (xy 396.562194 -313.305438) (xy 396.513019 -313.303457)
			(xy 396.4648 -313.293613) (xy 396.418784 -313.276161) (xy 396.376163 -313.251554) (xy 396.338042 -313.220429)
			(xy 396.305407 -313.183592) (xy 396.279104 -313.141996) (xy 396.259813 -313.09672) (xy 396.248036 -313.048936)
			(xy 396.244076 -312.999882) (xy 394.955268 -312.999882) (xy 394.954773 -313.024489) (xy 394.946878 -313.073066)
			(xy 394.931294 -313.119747) (xy 394.908423 -313.163324) (xy 394.878858 -313.202668) (xy 394.843365 -313.23676)
			(xy 394.802862 -313.264716) (xy 394.7584 -313.285814) (xy 394.711129 -313.299506) (xy 394.662274 -313.305438)
			(xy 394.613099 -313.303457) (xy 394.56488 -313.293613) (xy 394.518864 -313.276161) (xy 394.476243 -313.251554)
			(xy 394.438122 -313.220429) (xy 394.405487 -313.183592) (xy 394.379184 -313.141996) (xy 394.359893 -313.09672)
			(xy 394.348116 -313.048936) (xy 394.344156 -312.999882) (xy 393.055094 -312.999882) (xy 393.054599 -313.024489)
			(xy 393.046704 -313.073066) (xy 393.03112 -313.119747) (xy 393.008249 -313.163324) (xy 392.978684 -313.202668)
			(xy 392.943191 -313.23676) (xy 392.902688 -313.264716) (xy 392.858226 -313.285814) (xy 392.810955 -313.299506)
			(xy 392.7621 -313.305438) (xy 392.712925 -313.303457) (xy 392.664706 -313.293613) (xy 392.61869 -313.276161)
			(xy 392.576069 -313.251554) (xy 392.537948 -313.220429) (xy 392.505313 -313.183592) (xy 392.47901 -313.141996)
			(xy 392.459719 -313.09672) (xy 392.447942 -313.048936) (xy 392.443982 -312.999882) (xy 290.255198 -312.999882)
			(xy 290.254703 -313.024489) (xy 290.246808 -313.073066) (xy 290.231224 -313.119747) (xy 290.208353 -313.163324)
			(xy 290.178788 -313.202668) (xy 290.143295 -313.23676) (xy 290.102792 -313.264716) (xy 290.05833 -313.285814)
			(xy 290.011059 -313.299506) (xy 289.962204 -313.305438) (xy 289.913029 -313.303457) (xy 289.86481 -313.293613)
			(xy 289.818794 -313.276161) (xy 289.776173 -313.251554) (xy 289.738052 -313.220429) (xy 289.705417 -313.183592)
			(xy 289.679114 -313.141996) (xy 289.659823 -313.09672) (xy 289.648046 -313.048936) (xy 289.644086 -312.999882)
			(xy 288.355024 -312.999882) (xy 288.354529 -313.024489) (xy 288.346634 -313.073066) (xy 288.33105 -313.119747)
			(xy 288.308179 -313.163324) (xy 288.278614 -313.202668) (xy 288.243121 -313.23676) (xy 288.202618 -313.264716)
			(xy 288.158156 -313.285814) (xy 288.110885 -313.299506) (xy 288.06203 -313.305438) (xy 288.012855 -313.303457)
			(xy 287.964636 -313.293613) (xy 287.91862 -313.276161) (xy 287.875999 -313.251554) (xy 287.837878 -313.220429)
			(xy 287.805243 -313.183592) (xy 287.77894 -313.141996) (xy 287.759649 -313.09672) (xy 287.747872 -313.048936)
			(xy 287.743912 -312.999882) (xy 286.455104 -312.999882) (xy 286.454609 -313.024489) (xy 286.446714 -313.073066)
			(xy 286.43113 -313.119747) (xy 286.408259 -313.163324) (xy 286.378694 -313.202668) (xy 286.343201 -313.23676)
			(xy 286.302698 -313.264716) (xy 286.258236 -313.285814) (xy 286.210965 -313.299506) (xy 286.16211 -313.305438)
			(xy 286.112935 -313.303457) (xy 286.064716 -313.293613) (xy 286.0187 -313.276161) (xy 285.976079 -313.251554)
			(xy 285.937958 -313.220429) (xy 285.905323 -313.183592) (xy 285.87902 -313.141996) (xy 285.859729 -313.09672)
			(xy 285.847952 -313.048936) (xy 285.843992 -312.999882) (xy 284.555184 -312.999882) (xy 284.554689 -313.024489)
			(xy 284.546794 -313.073066) (xy 284.53121 -313.119747) (xy 284.508339 -313.163324) (xy 284.478774 -313.202668)
			(xy 284.443281 -313.23676) (xy 284.402778 -313.264716) (xy 284.358316 -313.285814) (xy 284.311045 -313.299506)
			(xy 284.26219 -313.305438) (xy 284.213015 -313.303457) (xy 284.164796 -313.293613) (xy 284.11878 -313.276161)
			(xy 284.076159 -313.251554) (xy 284.038038 -313.220429) (xy 284.005403 -313.183592) (xy 283.9791 -313.141996)
			(xy 283.959809 -313.09672) (xy 283.948032 -313.048936) (xy 283.944072 -312.999882) (xy 282.65501 -312.999882)
			(xy 282.654515 -313.024489) (xy 282.64662 -313.073066) (xy 282.631036 -313.119747) (xy 282.608165 -313.163324)
			(xy 282.5786 -313.202668) (xy 282.543107 -313.23676) (xy 282.502604 -313.264716) (xy 282.458142 -313.285814)
			(xy 282.410871 -313.299506) (xy 282.362016 -313.305438) (xy 282.312841 -313.303457) (xy 282.264622 -313.293613)
			(xy 282.218606 -313.276161) (xy 282.175985 -313.251554) (xy 282.137864 -313.220429) (xy 282.105229 -313.183592)
			(xy 282.078926 -313.141996) (xy 282.059635 -313.09672) (xy 282.047858 -313.048936) (xy 282.043898 -312.999882)
			(xy 280.75509 -312.999882) (xy 280.754595 -313.024489) (xy 280.7467 -313.073066) (xy 280.731116 -313.119747)
			(xy 280.708245 -313.163324) (xy 280.67868 -313.202668) (xy 280.643187 -313.23676) (xy 280.602684 -313.264716)
			(xy 280.558222 -313.285814) (xy 280.510951 -313.299506) (xy 280.462096 -313.305438) (xy 280.412921 -313.303457)
			(xy 280.364702 -313.293613) (xy 280.318686 -313.276161) (xy 280.276065 -313.251554) (xy 280.237944 -313.220429)
			(xy 280.205309 -313.183592) (xy 280.179006 -313.141996) (xy 280.159715 -313.09672) (xy 280.147938 -313.048936)
			(xy 280.143978 -312.999882) (xy 278.85517 -312.999882) (xy 278.854675 -313.024489) (xy 278.84678 -313.073066)
			(xy 278.831196 -313.119747) (xy 278.808325 -313.163324) (xy 278.77876 -313.202668) (xy 278.743267 -313.23676)
			(xy 278.702764 -313.264716) (xy 278.658302 -313.285814) (xy 278.611031 -313.299506) (xy 278.562176 -313.305438)
			(xy 278.513001 -313.303457) (xy 278.464782 -313.293613) (xy 278.418766 -313.276161) (xy 278.376145 -313.251554)
			(xy 278.338024 -313.220429) (xy 278.305389 -313.183592) (xy 278.279086 -313.141996) (xy 278.259795 -313.09672)
			(xy 278.248018 -313.048936) (xy 278.244058 -312.999882) (xy 276.954996 -312.999882) (xy 276.954501 -313.024489)
			(xy 276.946606 -313.073066) (xy 276.931022 -313.119747) (xy 276.908151 -313.163324) (xy 276.878586 -313.202668)
			(xy 276.843093 -313.23676) (xy 276.80259 -313.264716) (xy 276.758128 -313.285814) (xy 276.710857 -313.299506)
			(xy 276.662002 -313.305438) (xy 276.612827 -313.303457) (xy 276.564608 -313.293613) (xy 276.518592 -313.276161)
			(xy 276.475971 -313.251554) (xy 276.43785 -313.220429) (xy 276.405215 -313.183592) (xy 276.378912 -313.141996)
			(xy 276.359621 -313.09672) (xy 276.347844 -313.048936) (xy 276.343884 -312.999882) (xy 189.355222 -312.999882)
			(xy 189.354727 -313.024489) (xy 189.346832 -313.073066) (xy 189.331248 -313.119747) (xy 189.308377 -313.163324)
			(xy 189.278812 -313.202668) (xy 189.243319 -313.23676) (xy 189.202816 -313.264716) (xy 189.158354 -313.285814)
			(xy 189.111083 -313.299506) (xy 189.062228 -313.305438) (xy 189.013053 -313.303457) (xy 188.964834 -313.293613)
			(xy 188.918818 -313.276161) (xy 188.876197 -313.251554) (xy 188.838076 -313.220429) (xy 188.805441 -313.183592)
			(xy 188.779138 -313.141996) (xy 188.759847 -313.09672) (xy 188.74807 -313.048936) (xy 188.74411 -312.999882)
			(xy 187.455302 -312.999882) (xy 187.454807 -313.024489) (xy 187.446912 -313.073066) (xy 187.431328 -313.119747)
			(xy 187.408457 -313.163324) (xy 187.378892 -313.202668) (xy 187.343399 -313.23676) (xy 187.302896 -313.264716)
			(xy 187.258434 -313.285814) (xy 187.211163 -313.299506) (xy 187.162308 -313.305438) (xy 187.113133 -313.303457)
			(xy 187.064914 -313.293613) (xy 187.018898 -313.276161) (xy 186.976277 -313.251554) (xy 186.938156 -313.220429)
			(xy 186.905521 -313.183592) (xy 186.879218 -313.141996) (xy 186.859927 -313.09672) (xy 186.84815 -313.048936)
			(xy 186.84419 -312.999882) (xy 185.555382 -312.999882) (xy 185.554887 -313.024489) (xy 185.546992 -313.073066)
			(xy 185.531408 -313.119747) (xy 185.508537 -313.163324) (xy 185.478972 -313.202668) (xy 185.443479 -313.23676)
			(xy 185.402976 -313.264716) (xy 185.358514 -313.285814) (xy 185.311243 -313.299506) (xy 185.262388 -313.305438)
			(xy 185.213213 -313.303457) (xy 185.164994 -313.293613) (xy 185.118978 -313.276161) (xy 185.076357 -313.251554)
			(xy 185.038236 -313.220429) (xy 185.005601 -313.183592) (xy 184.979298 -313.141996) (xy 184.960007 -313.09672)
			(xy 184.94823 -313.048936) (xy 184.94427 -312.999882) (xy 183.655208 -312.999882) (xy 183.654713 -313.024489)
			(xy 183.646818 -313.073066) (xy 183.631234 -313.119747) (xy 183.608363 -313.163324) (xy 183.578798 -313.202668)
			(xy 183.543305 -313.23676) (xy 183.502802 -313.264716) (xy 183.45834 -313.285814) (xy 183.411069 -313.299506)
			(xy 183.362214 -313.305438) (xy 183.313039 -313.303457) (xy 183.26482 -313.293613) (xy 183.218804 -313.276161)
			(xy 183.176183 -313.251554) (xy 183.138062 -313.220429) (xy 183.105427 -313.183592) (xy 183.079124 -313.141996)
			(xy 183.059833 -313.09672) (xy 183.048056 -313.048936) (xy 183.044096 -312.999882) (xy 166.555166 -312.999882)
			(xy 166.554671 -313.024489) (xy 166.546776 -313.073066) (xy 166.531192 -313.119747) (xy 166.508321 -313.163324)
			(xy 166.478756 -313.202668) (xy 166.443263 -313.23676) (xy 166.40276 -313.264716) (xy 166.358298 -313.285814)
			(xy 166.311027 -313.299506) (xy 166.262172 -313.305438) (xy 166.212997 -313.303457) (xy 166.164778 -313.293613)
			(xy 166.118762 -313.276161) (xy 166.076141 -313.251554) (xy 166.03802 -313.220429) (xy 166.005385 -313.183592)
			(xy 165.979082 -313.141996) (xy 165.959791 -313.09672) (xy 165.948014 -313.048936) (xy 165.944054 -312.999882)
			(xy 164.655246 -312.999882) (xy 164.654751 -313.024489) (xy 164.646856 -313.073066) (xy 164.631272 -313.119747)
			(xy 164.608401 -313.163324) (xy 164.578836 -313.202668) (xy 164.543343 -313.23676) (xy 164.50284 -313.264716)
			(xy 164.458378 -313.285814) (xy 164.411107 -313.299506) (xy 164.362252 -313.305438) (xy 164.313077 -313.303457)
			(xy 164.264858 -313.293613) (xy 164.218842 -313.276161) (xy 164.176221 -313.251554) (xy 164.1381 -313.220429)
			(xy 164.105465 -313.183592) (xy 164.079162 -313.141996) (xy 164.059871 -313.09672) (xy 164.048094 -313.048936)
			(xy 164.044134 -312.999882) (xy 162.755326 -312.999882) (xy 162.754831 -313.024489) (xy 162.746936 -313.073066)
			(xy 162.731352 -313.119747) (xy 162.708481 -313.163324) (xy 162.678916 -313.202668) (xy 162.643423 -313.23676)
			(xy 162.60292 -313.264716) (xy 162.558458 -313.285814) (xy 162.511187 -313.299506) (xy 162.462332 -313.305438)
			(xy 162.413157 -313.303457) (xy 162.364938 -313.293613) (xy 162.318922 -313.276161) (xy 162.276301 -313.251554)
			(xy 162.23818 -313.220429) (xy 162.205545 -313.183592) (xy 162.179242 -313.141996) (xy 162.159951 -313.09672)
			(xy 162.148174 -313.048936) (xy 162.144214 -312.999882) (xy 160.855152 -312.999882) (xy 160.854657 -313.024489)
			(xy 160.846762 -313.073066) (xy 160.831178 -313.119747) (xy 160.808307 -313.163324) (xy 160.778742 -313.202668)
			(xy 160.743249 -313.23676) (xy 160.702746 -313.264716) (xy 160.658284 -313.285814) (xy 160.611013 -313.299506)
			(xy 160.562158 -313.305438) (xy 160.512983 -313.303457) (xy 160.464764 -313.293613) (xy 160.418748 -313.276161)
			(xy 160.376127 -313.251554) (xy 160.338006 -313.220429) (xy 160.305371 -313.183592) (xy 160.279068 -313.141996)
			(xy 160.259777 -313.09672) (xy 160.248 -313.048936) (xy 160.24404 -312.999882) (xy 58.055256 -312.999882)
			(xy 58.054761 -313.024489) (xy 58.046866 -313.073066) (xy 58.031282 -313.119747) (xy 58.008411 -313.163324)
			(xy 57.978846 -313.202668) (xy 57.943353 -313.23676) (xy 57.90285 -313.264716) (xy 57.858388 -313.285814)
			(xy 57.811117 -313.299506) (xy 57.762262 -313.305438) (xy 57.713087 -313.303457) (xy 57.664868 -313.293613)
			(xy 57.618852 -313.276161) (xy 57.576231 -313.251554) (xy 57.53811 -313.220429) (xy 57.505475 -313.183592)
			(xy 57.479172 -313.141996) (xy 57.459881 -313.09672) (xy 57.448104 -313.048936) (xy 57.444144 -312.999882)
			(xy 56.155082 -312.999882) (xy 56.154587 -313.024489) (xy 56.146692 -313.073066) (xy 56.131108 -313.119747)
			(xy 56.108237 -313.163324) (xy 56.078672 -313.202668) (xy 56.043179 -313.23676) (xy 56.002676 -313.264716)
			(xy 55.958214 -313.285814) (xy 55.910943 -313.299506) (xy 55.862088 -313.305438) (xy 55.812913 -313.303457)
			(xy 55.764694 -313.293613) (xy 55.718678 -313.276161) (xy 55.676057 -313.251554) (xy 55.637936 -313.220429)
			(xy 55.605301 -313.183592) (xy 55.578998 -313.141996) (xy 55.559707 -313.09672) (xy 55.54793 -313.048936)
			(xy 55.54397 -312.999882) (xy 54.255162 -312.999882) (xy 54.254667 -313.024489) (xy 54.246772 -313.073066)
			(xy 54.231188 -313.119747) (xy 54.208317 -313.163324) (xy 54.178752 -313.202668) (xy 54.143259 -313.23676)
			(xy 54.102756 -313.264716) (xy 54.058294 -313.285814) (xy 54.011023 -313.299506) (xy 53.962168 -313.305438)
			(xy 53.912993 -313.303457) (xy 53.864774 -313.293613) (xy 53.818758 -313.276161) (xy 53.776137 -313.251554)
			(xy 53.738016 -313.220429) (xy 53.705381 -313.183592) (xy 53.679078 -313.141996) (xy 53.659787 -313.09672)
			(xy 53.64801 -313.048936) (xy 53.64405 -312.999882) (xy 52.355242 -312.999882) (xy 52.354747 -313.024489)
			(xy 52.346852 -313.073066) (xy 52.331268 -313.119747) (xy 52.308397 -313.163324) (xy 52.278832 -313.202668)
			(xy 52.243339 -313.23676) (xy 52.202836 -313.264716) (xy 52.158374 -313.285814) (xy 52.111103 -313.299506)
			(xy 52.062248 -313.305438) (xy 52.013073 -313.303457) (xy 51.964854 -313.293613) (xy 51.918838 -313.276161)
			(xy 51.876217 -313.251554) (xy 51.838096 -313.220429) (xy 51.805461 -313.183592) (xy 51.779158 -313.141996)
			(xy 51.759867 -313.09672) (xy 51.74809 -313.048936) (xy 51.74413 -312.999882) (xy 50.455068 -312.999882)
			(xy 50.454573 -313.024489) (xy 50.446678 -313.073066) (xy 50.431094 -313.119747) (xy 50.408223 -313.163324)
			(xy 50.378658 -313.202668) (xy 50.343165 -313.23676) (xy 50.302662 -313.264716) (xy 50.2582 -313.285814)
			(xy 50.210929 -313.299506) (xy 50.162074 -313.305438) (xy 50.112899 -313.303457) (xy 50.06468 -313.293613)
			(xy 50.018664 -313.276161) (xy 49.976043 -313.251554) (xy 49.937922 -313.220429) (xy 49.905287 -313.183592)
			(xy 49.878984 -313.141996) (xy 49.859693 -313.09672) (xy 49.847916 -313.048936) (xy 49.843956 -312.999882)
			(xy 48.555148 -312.999882) (xy 48.554653 -313.024489) (xy 48.546758 -313.073066) (xy 48.531174 -313.119747)
			(xy 48.508303 -313.163324) (xy 48.478738 -313.202668) (xy 48.443245 -313.23676) (xy 48.402742 -313.264716)
			(xy 48.35828 -313.285814) (xy 48.311009 -313.299506) (xy 48.262154 -313.305438) (xy 48.212979 -313.303457)
			(xy 48.16476 -313.293613) (xy 48.118744 -313.276161) (xy 48.076123 -313.251554) (xy 48.038002 -313.220429)
			(xy 48.005367 -313.183592) (xy 47.979064 -313.141996) (xy 47.959773 -313.09672) (xy 47.947996 -313.048936)
			(xy 47.944036 -312.999882) (xy 46.655228 -312.999882) (xy 46.654733 -313.024489) (xy 46.646838 -313.073066)
			(xy 46.631254 -313.119747) (xy 46.608383 -313.163324) (xy 46.578818 -313.202668) (xy 46.543325 -313.23676)
			(xy 46.502822 -313.264716) (xy 46.45836 -313.285814) (xy 46.411089 -313.299506) (xy 46.362234 -313.305438)
			(xy 46.313059 -313.303457) (xy 46.26484 -313.293613) (xy 46.218824 -313.276161) (xy 46.176203 -313.251554)
			(xy 46.138082 -313.220429) (xy 46.105447 -313.183592) (xy 46.079144 -313.141996) (xy 46.059853 -313.09672)
			(xy 46.048076 -313.048936) (xy 46.044116 -312.999882) (xy 44.755054 -312.999882) (xy 44.754559 -313.024489)
			(xy 44.746664 -313.073066) (xy 44.73108 -313.119747) (xy 44.708209 -313.163324) (xy 44.678644 -313.202668)
			(xy 44.643151 -313.23676) (xy 44.602648 -313.264716) (xy 44.558186 -313.285814) (xy 44.510915 -313.299506)
			(xy 44.46206 -313.305438) (xy 44.412885 -313.303457) (xy 44.364666 -313.293613) (xy 44.31865 -313.276161)
			(xy 44.276029 -313.251554) (xy 44.237908 -313.220429) (xy 44.205273 -313.183592) (xy 44.17897 -313.141996)
			(xy 44.159679 -313.09672) (xy 44.147902 -313.048936) (xy 44.143942 -312.999882) (xy 0.508 -312.999882)
			(xy 0.508 -313.949842) (xy 44.143942 -313.949842) (xy 44.147902 -313.900788) (xy 44.159679 -313.853004)
			(xy 44.17897 -313.807728) (xy 44.205273 -313.766132) (xy 44.237908 -313.729295) (xy 44.276029 -313.69817)
			(xy 44.31865 -313.673563) (xy 44.364666 -313.656111) (xy 44.412885 -313.646267) (xy 44.46206 -313.644286)
			(xy 44.510915 -313.650218) (xy 44.558186 -313.66391) (xy 44.602648 -313.685008) (xy 44.643151 -313.712964)
			(xy 44.678644 -313.747056) (xy 44.708209 -313.7864) (xy 44.73108 -313.829977) (xy 44.746664 -313.876658)
			(xy 44.754559 -313.925235) (xy 44.755054 -313.949842) (xy 46.044116 -313.949842) (xy 46.048076 -313.900788)
			(xy 46.059853 -313.853004) (xy 46.079144 -313.807728) (xy 46.105447 -313.766132) (xy 46.138082 -313.729295)
			(xy 46.176203 -313.69817) (xy 46.218824 -313.673563) (xy 46.26484 -313.656111) (xy 46.313059 -313.646267)
			(xy 46.362234 -313.644286) (xy 46.411089 -313.650218) (xy 46.45836 -313.66391) (xy 46.502822 -313.685008)
			(xy 46.543325 -313.712964) (xy 46.578818 -313.747056) (xy 46.608383 -313.7864) (xy 46.631254 -313.829977)
			(xy 46.646838 -313.876658) (xy 46.654733 -313.925235) (xy 46.655228 -313.949842) (xy 47.944036 -313.949842)
			(xy 47.947996 -313.900788) (xy 47.959773 -313.853004) (xy 47.979064 -313.807728) (xy 48.005367 -313.766132)
			(xy 48.038002 -313.729295) (xy 48.076123 -313.69817) (xy 48.118744 -313.673563) (xy 48.16476 -313.656111)
			(xy 48.212979 -313.646267) (xy 48.262154 -313.644286) (xy 48.311009 -313.650218) (xy 48.35828 -313.66391)
			(xy 48.402742 -313.685008) (xy 48.443245 -313.712964) (xy 48.478738 -313.747056) (xy 48.508303 -313.7864)
			(xy 48.531174 -313.829977) (xy 48.546758 -313.876658) (xy 48.554653 -313.925235) (xy 48.555148 -313.949842)
			(xy 49.843956 -313.949842) (xy 49.847916 -313.900788) (xy 49.859693 -313.853004) (xy 49.878984 -313.807728)
			(xy 49.905287 -313.766132) (xy 49.937922 -313.729295) (xy 49.976043 -313.69817) (xy 50.018664 -313.673563)
			(xy 50.06468 -313.656111) (xy 50.112899 -313.646267) (xy 50.162074 -313.644286) (xy 50.210929 -313.650218)
			(xy 50.2582 -313.66391) (xy 50.302662 -313.685008) (xy 50.343165 -313.712964) (xy 50.378658 -313.747056)
			(xy 50.408223 -313.7864) (xy 50.431094 -313.829977) (xy 50.446678 -313.876658) (xy 50.454573 -313.925235)
			(xy 50.455068 -313.949842) (xy 51.74413 -313.949842) (xy 51.74809 -313.900788) (xy 51.759867 -313.853004)
			(xy 51.779158 -313.807728) (xy 51.805461 -313.766132) (xy 51.838096 -313.729295) (xy 51.876217 -313.69817)
			(xy 51.918838 -313.673563) (xy 51.964854 -313.656111) (xy 52.013073 -313.646267) (xy 52.062248 -313.644286)
			(xy 52.111103 -313.650218) (xy 52.158374 -313.66391) (xy 52.202836 -313.685008) (xy 52.243339 -313.712964)
			(xy 52.278832 -313.747056) (xy 52.308397 -313.7864) (xy 52.331268 -313.829977) (xy 52.346852 -313.876658)
			(xy 52.354747 -313.925235) (xy 52.355242 -313.949842) (xy 53.64405 -313.949842) (xy 53.64801 -313.900788)
			(xy 53.659787 -313.853004) (xy 53.679078 -313.807728) (xy 53.705381 -313.766132) (xy 53.738016 -313.729295)
			(xy 53.776137 -313.69817) (xy 53.818758 -313.673563) (xy 53.864774 -313.656111) (xy 53.912993 -313.646267)
			(xy 53.962168 -313.644286) (xy 54.011023 -313.650218) (xy 54.058294 -313.66391) (xy 54.102756 -313.685008)
			(xy 54.143259 -313.712964) (xy 54.178752 -313.747056) (xy 54.208317 -313.7864) (xy 54.231188 -313.829977)
			(xy 54.246772 -313.876658) (xy 54.254667 -313.925235) (xy 54.255162 -313.949842) (xy 55.54397 -313.949842)
			(xy 55.54793 -313.900788) (xy 55.559707 -313.853004) (xy 55.578998 -313.807728) (xy 55.605301 -313.766132)
			(xy 55.637936 -313.729295) (xy 55.676057 -313.69817) (xy 55.718678 -313.673563) (xy 55.764694 -313.656111)
			(xy 55.812913 -313.646267) (xy 55.862088 -313.644286) (xy 55.910943 -313.650218) (xy 55.958214 -313.66391)
			(xy 56.002676 -313.685008) (xy 56.043179 -313.712964) (xy 56.078672 -313.747056) (xy 56.108237 -313.7864)
			(xy 56.131108 -313.829977) (xy 56.146692 -313.876658) (xy 56.154587 -313.925235) (xy 56.155082 -313.949842)
			(xy 57.444144 -313.949842) (xy 57.448104 -313.900788) (xy 57.459881 -313.853004) (xy 57.479172 -313.807728)
			(xy 57.505475 -313.766132) (xy 57.53811 -313.729295) (xy 57.576231 -313.69817) (xy 57.618852 -313.673563)
			(xy 57.664868 -313.656111) (xy 57.713087 -313.646267) (xy 57.762262 -313.644286) (xy 57.811117 -313.650218)
			(xy 57.858388 -313.66391) (xy 57.90285 -313.685008) (xy 57.943353 -313.712964) (xy 57.978846 -313.747056)
			(xy 58.008411 -313.7864) (xy 58.031282 -313.829977) (xy 58.046866 -313.876658) (xy 58.054761 -313.925235)
			(xy 58.055256 -313.949842) (xy 160.24404 -313.949842) (xy 160.248 -313.900788) (xy 160.259777 -313.853004)
			(xy 160.279068 -313.807728) (xy 160.305371 -313.766132) (xy 160.338006 -313.729295) (xy 160.376127 -313.69817)
			(xy 160.418748 -313.673563) (xy 160.464764 -313.656111) (xy 160.512983 -313.646267) (xy 160.562158 -313.644286)
			(xy 160.611013 -313.650218) (xy 160.658284 -313.66391) (xy 160.702746 -313.685008) (xy 160.743249 -313.712964)
			(xy 160.778742 -313.747056) (xy 160.808307 -313.7864) (xy 160.831178 -313.829977) (xy 160.846762 -313.876658)
			(xy 160.854657 -313.925235) (xy 160.855152 -313.949842) (xy 162.144214 -313.949842) (xy 162.148174 -313.900788)
			(xy 162.159951 -313.853004) (xy 162.179242 -313.807728) (xy 162.205545 -313.766132) (xy 162.23818 -313.729295)
			(xy 162.276301 -313.69817) (xy 162.318922 -313.673563) (xy 162.364938 -313.656111) (xy 162.413157 -313.646267)
			(xy 162.462332 -313.644286) (xy 162.511187 -313.650218) (xy 162.558458 -313.66391) (xy 162.60292 -313.685008)
			(xy 162.643423 -313.712964) (xy 162.678916 -313.747056) (xy 162.708481 -313.7864) (xy 162.731352 -313.829977)
			(xy 162.746936 -313.876658) (xy 162.754831 -313.925235) (xy 162.755326 -313.949842) (xy 164.044134 -313.949842)
			(xy 164.048094 -313.900788) (xy 164.059871 -313.853004) (xy 164.079162 -313.807728) (xy 164.105465 -313.766132)
			(xy 164.1381 -313.729295) (xy 164.176221 -313.69817) (xy 164.218842 -313.673563) (xy 164.264858 -313.656111)
			(xy 164.313077 -313.646267) (xy 164.362252 -313.644286) (xy 164.411107 -313.650218) (xy 164.458378 -313.66391)
			(xy 164.50284 -313.685008) (xy 164.543343 -313.712964) (xy 164.578836 -313.747056) (xy 164.608401 -313.7864)
			(xy 164.631272 -313.829977) (xy 164.646856 -313.876658) (xy 164.654751 -313.925235) (xy 164.655246 -313.949842)
			(xy 165.944054 -313.949842) (xy 165.948014 -313.900788) (xy 165.959791 -313.853004) (xy 165.979082 -313.807728)
			(xy 166.005385 -313.766132) (xy 166.03802 -313.729295) (xy 166.076141 -313.69817) (xy 166.118762 -313.673563)
			(xy 166.164778 -313.656111) (xy 166.212997 -313.646267) (xy 166.262172 -313.644286) (xy 166.311027 -313.650218)
			(xy 166.358298 -313.66391) (xy 166.40276 -313.685008) (xy 166.443263 -313.712964) (xy 166.478756 -313.747056)
			(xy 166.508321 -313.7864) (xy 166.531192 -313.829977) (xy 166.546776 -313.876658) (xy 166.554671 -313.925235)
			(xy 166.555166 -313.949842) (xy 183.044096 -313.949842) (xy 183.048056 -313.900788) (xy 183.059833 -313.853004)
			(xy 183.079124 -313.807728) (xy 183.105427 -313.766132) (xy 183.138062 -313.729295) (xy 183.176183 -313.69817)
			(xy 183.218804 -313.673563) (xy 183.26482 -313.656111) (xy 183.313039 -313.646267) (xy 183.362214 -313.644286)
			(xy 183.411069 -313.650218) (xy 183.45834 -313.66391) (xy 183.502802 -313.685008) (xy 183.543305 -313.712964)
			(xy 183.578798 -313.747056) (xy 183.608363 -313.7864) (xy 183.631234 -313.829977) (xy 183.646818 -313.876658)
			(xy 183.654713 -313.925235) (xy 183.655208 -313.949842) (xy 184.94427 -313.949842) (xy 184.94823 -313.900788)
			(xy 184.960007 -313.853004) (xy 184.979298 -313.807728) (xy 185.005601 -313.766132) (xy 185.038236 -313.729295)
			(xy 185.076357 -313.69817) (xy 185.118978 -313.673563) (xy 185.164994 -313.656111) (xy 185.213213 -313.646267)
			(xy 185.262388 -313.644286) (xy 185.311243 -313.650218) (xy 185.358514 -313.66391) (xy 185.402976 -313.685008)
			(xy 185.443479 -313.712964) (xy 185.478972 -313.747056) (xy 185.508537 -313.7864) (xy 185.531408 -313.829977)
			(xy 185.546992 -313.876658) (xy 185.554887 -313.925235) (xy 185.555382 -313.949842) (xy 186.84419 -313.949842)
			(xy 186.84815 -313.900788) (xy 186.859927 -313.853004) (xy 186.879218 -313.807728) (xy 186.905521 -313.766132)
			(xy 186.938156 -313.729295) (xy 186.976277 -313.69817) (xy 187.018898 -313.673563) (xy 187.064914 -313.656111)
			(xy 187.113133 -313.646267) (xy 187.162308 -313.644286) (xy 187.211163 -313.650218) (xy 187.258434 -313.66391)
			(xy 187.302896 -313.685008) (xy 187.343399 -313.712964) (xy 187.378892 -313.747056) (xy 187.408457 -313.7864)
			(xy 187.431328 -313.829977) (xy 187.446912 -313.876658) (xy 187.454807 -313.925235) (xy 187.455302 -313.949842)
			(xy 188.74411 -313.949842) (xy 188.74807 -313.900788) (xy 188.759847 -313.853004) (xy 188.779138 -313.807728)
			(xy 188.805441 -313.766132) (xy 188.838076 -313.729295) (xy 188.876197 -313.69817) (xy 188.918818 -313.673563)
			(xy 188.964834 -313.656111) (xy 189.013053 -313.646267) (xy 189.062228 -313.644286) (xy 189.111083 -313.650218)
			(xy 189.158354 -313.66391) (xy 189.202816 -313.685008) (xy 189.243319 -313.712964) (xy 189.278812 -313.747056)
			(xy 189.308377 -313.7864) (xy 189.331248 -313.829977) (xy 189.346832 -313.876658) (xy 189.354727 -313.925235)
			(xy 189.355222 -313.949842) (xy 276.343884 -313.949842) (xy 276.347844 -313.900788) (xy 276.359621 -313.853004)
			(xy 276.378912 -313.807728) (xy 276.405215 -313.766132) (xy 276.43785 -313.729295) (xy 276.475971 -313.69817)
			(xy 276.518592 -313.673563) (xy 276.564608 -313.656111) (xy 276.612827 -313.646267) (xy 276.662002 -313.644286)
			(xy 276.710857 -313.650218) (xy 276.758128 -313.66391) (xy 276.80259 -313.685008) (xy 276.843093 -313.712964)
			(xy 276.878586 -313.747056) (xy 276.908151 -313.7864) (xy 276.931022 -313.829977) (xy 276.946606 -313.876658)
			(xy 276.954501 -313.925235) (xy 276.954996 -313.949842) (xy 278.244058 -313.949842) (xy 278.248018 -313.900788)
			(xy 278.259795 -313.853004) (xy 278.279086 -313.807728) (xy 278.305389 -313.766132) (xy 278.338024 -313.729295)
			(xy 278.376145 -313.69817) (xy 278.418766 -313.673563) (xy 278.464782 -313.656111) (xy 278.513001 -313.646267)
			(xy 278.562176 -313.644286) (xy 278.611031 -313.650218) (xy 278.658302 -313.66391) (xy 278.702764 -313.685008)
			(xy 278.743267 -313.712964) (xy 278.77876 -313.747056) (xy 278.808325 -313.7864) (xy 278.831196 -313.829977)
			(xy 278.84678 -313.876658) (xy 278.854675 -313.925235) (xy 278.85517 -313.949842) (xy 280.143978 -313.949842)
			(xy 280.147938 -313.900788) (xy 280.159715 -313.853004) (xy 280.179006 -313.807728) (xy 280.205309 -313.766132)
			(xy 280.237944 -313.729295) (xy 280.276065 -313.69817) (xy 280.318686 -313.673563) (xy 280.364702 -313.656111)
			(xy 280.412921 -313.646267) (xy 280.462096 -313.644286) (xy 280.510951 -313.650218) (xy 280.558222 -313.66391)
			(xy 280.602684 -313.685008) (xy 280.643187 -313.712964) (xy 280.67868 -313.747056) (xy 280.708245 -313.7864)
			(xy 280.731116 -313.829977) (xy 280.7467 -313.876658) (xy 280.754595 -313.925235) (xy 280.75509 -313.949842)
			(xy 282.043898 -313.949842) (xy 282.047858 -313.900788) (xy 282.059635 -313.853004) (xy 282.078926 -313.807728)
			(xy 282.105229 -313.766132) (xy 282.137864 -313.729295) (xy 282.175985 -313.69817) (xy 282.218606 -313.673563)
			(xy 282.264622 -313.656111) (xy 282.312841 -313.646267) (xy 282.362016 -313.644286) (xy 282.410871 -313.650218)
			(xy 282.458142 -313.66391) (xy 282.502604 -313.685008) (xy 282.543107 -313.712964) (xy 282.5786 -313.747056)
			(xy 282.608165 -313.7864) (xy 282.631036 -313.829977) (xy 282.64662 -313.876658) (xy 282.654515 -313.925235)
			(xy 282.65501 -313.949842) (xy 283.944072 -313.949842) (xy 283.948032 -313.900788) (xy 283.959809 -313.853004)
			(xy 283.9791 -313.807728) (xy 284.005403 -313.766132) (xy 284.038038 -313.729295) (xy 284.076159 -313.69817)
			(xy 284.11878 -313.673563) (xy 284.164796 -313.656111) (xy 284.213015 -313.646267) (xy 284.26219 -313.644286)
			(xy 284.311045 -313.650218) (xy 284.358316 -313.66391) (xy 284.402778 -313.685008) (xy 284.443281 -313.712964)
			(xy 284.478774 -313.747056) (xy 284.508339 -313.7864) (xy 284.53121 -313.829977) (xy 284.546794 -313.876658)
			(xy 284.554689 -313.925235) (xy 284.555184 -313.949842) (xy 285.843992 -313.949842) (xy 285.847952 -313.900788)
			(xy 285.859729 -313.853004) (xy 285.87902 -313.807728) (xy 285.905323 -313.766132) (xy 285.937958 -313.729295)
			(xy 285.976079 -313.69817) (xy 286.0187 -313.673563) (xy 286.064716 -313.656111) (xy 286.112935 -313.646267)
			(xy 286.16211 -313.644286) (xy 286.210965 -313.650218) (xy 286.258236 -313.66391) (xy 286.302698 -313.685008)
			(xy 286.343201 -313.712964) (xy 286.378694 -313.747056) (xy 286.408259 -313.7864) (xy 286.43113 -313.829977)
			(xy 286.446714 -313.876658) (xy 286.454609 -313.925235) (xy 286.455104 -313.949842) (xy 287.743912 -313.949842)
			(xy 287.747872 -313.900788) (xy 287.759649 -313.853004) (xy 287.77894 -313.807728) (xy 287.805243 -313.766132)
			(xy 287.837878 -313.729295) (xy 287.875999 -313.69817) (xy 287.91862 -313.673563) (xy 287.964636 -313.656111)
			(xy 288.012855 -313.646267) (xy 288.06203 -313.644286) (xy 288.110885 -313.650218) (xy 288.158156 -313.66391)
			(xy 288.202618 -313.685008) (xy 288.243121 -313.712964) (xy 288.278614 -313.747056) (xy 288.308179 -313.7864)
			(xy 288.33105 -313.829977) (xy 288.346634 -313.876658) (xy 288.354529 -313.925235) (xy 288.355024 -313.949842)
			(xy 289.644086 -313.949842) (xy 289.648046 -313.900788) (xy 289.659823 -313.853004) (xy 289.679114 -313.807728)
			(xy 289.705417 -313.766132) (xy 289.738052 -313.729295) (xy 289.776173 -313.69817) (xy 289.818794 -313.673563)
			(xy 289.86481 -313.656111) (xy 289.913029 -313.646267) (xy 289.962204 -313.644286) (xy 290.011059 -313.650218)
			(xy 290.05833 -313.66391) (xy 290.102792 -313.685008) (xy 290.143295 -313.712964) (xy 290.178788 -313.747056)
			(xy 290.208353 -313.7864) (xy 290.231224 -313.829977) (xy 290.246808 -313.876658) (xy 290.254703 -313.925235)
			(xy 290.255198 -313.949842) (xy 392.443982 -313.949842) (xy 392.447942 -313.900788) (xy 392.459719 -313.853004)
			(xy 392.47901 -313.807728) (xy 392.505313 -313.766132) (xy 392.537948 -313.729295) (xy 392.576069 -313.69817)
			(xy 392.61869 -313.673563) (xy 392.664706 -313.656111) (xy 392.712925 -313.646267) (xy 392.7621 -313.644286)
			(xy 392.810955 -313.650218) (xy 392.858226 -313.66391) (xy 392.902688 -313.685008) (xy 392.943191 -313.712964)
			(xy 392.978684 -313.747056) (xy 393.008249 -313.7864) (xy 393.03112 -313.829977) (xy 393.046704 -313.876658)
			(xy 393.054599 -313.925235) (xy 393.055094 -313.949842) (xy 394.344156 -313.949842) (xy 394.348116 -313.900788)
			(xy 394.359893 -313.853004) (xy 394.379184 -313.807728) (xy 394.405487 -313.766132) (xy 394.438122 -313.729295)
			(xy 394.476243 -313.69817) (xy 394.518864 -313.673563) (xy 394.56488 -313.656111) (xy 394.613099 -313.646267)
			(xy 394.662274 -313.644286) (xy 394.711129 -313.650218) (xy 394.7584 -313.66391) (xy 394.802862 -313.685008)
			(xy 394.843365 -313.712964) (xy 394.878858 -313.747056) (xy 394.908423 -313.7864) (xy 394.931294 -313.829977)
			(xy 394.946878 -313.876658) (xy 394.954773 -313.925235) (xy 394.955268 -313.949842) (xy 396.244076 -313.949842)
			(xy 396.248036 -313.900788) (xy 396.259813 -313.853004) (xy 396.279104 -313.807728) (xy 396.305407 -313.766132)
			(xy 396.338042 -313.729295) (xy 396.376163 -313.69817) (xy 396.418784 -313.673563) (xy 396.4648 -313.656111)
			(xy 396.513019 -313.646267) (xy 396.562194 -313.644286) (xy 396.611049 -313.650218) (xy 396.65832 -313.66391)
			(xy 396.702782 -313.685008) (xy 396.743285 -313.712964) (xy 396.778778 -313.747056) (xy 396.808343 -313.7864)
			(xy 396.831214 -313.829977) (xy 396.846798 -313.876658) (xy 396.854693 -313.925235) (xy 396.855188 -313.949842)
			(xy 398.143996 -313.949842) (xy 398.147956 -313.900788) (xy 398.159733 -313.853004) (xy 398.179024 -313.807728)
			(xy 398.205327 -313.766132) (xy 398.237962 -313.729295) (xy 398.276083 -313.69817) (xy 398.318704 -313.673563)
			(xy 398.36472 -313.656111) (xy 398.412939 -313.646267) (xy 398.462114 -313.644286) (xy 398.510969 -313.650218)
			(xy 398.55824 -313.66391) (xy 398.602702 -313.685008) (xy 398.643205 -313.712964) (xy 398.678698 -313.747056)
			(xy 398.708263 -313.7864) (xy 398.731134 -313.829977) (xy 398.746718 -313.876658) (xy 398.754613 -313.925235)
			(xy 398.755108 -313.949842) (xy 415.244038 -313.949842) (xy 415.247998 -313.900788) (xy 415.259775 -313.853004)
			(xy 415.279066 -313.807728) (xy 415.305369 -313.766132) (xy 415.338004 -313.729295) (xy 415.376125 -313.69817)
			(xy 415.418746 -313.673563) (xy 415.464762 -313.656111) (xy 415.512981 -313.646267) (xy 415.562156 -313.644286)
			(xy 415.611011 -313.650218) (xy 415.658282 -313.66391) (xy 415.702744 -313.685008) (xy 415.743247 -313.712964)
			(xy 415.77874 -313.747056) (xy 415.808305 -313.7864) (xy 415.831176 -313.829977) (xy 415.84676 -313.876658)
			(xy 415.854655 -313.925235) (xy 415.85515 -313.949842) (xy 417.144212 -313.949842) (xy 417.148172 -313.900788)
			(xy 417.159949 -313.853004) (xy 417.17924 -313.807728) (xy 417.205543 -313.766132) (xy 417.238178 -313.729295)
			(xy 417.276299 -313.69817) (xy 417.31892 -313.673563) (xy 417.364936 -313.656111) (xy 417.413155 -313.646267)
			(xy 417.46233 -313.644286) (xy 417.511185 -313.650218) (xy 417.558456 -313.66391) (xy 417.602918 -313.685008)
			(xy 417.643421 -313.712964) (xy 417.678914 -313.747056) (xy 417.708479 -313.7864) (xy 417.73135 -313.829977)
			(xy 417.746934 -313.876658) (xy 417.754829 -313.925235) (xy 417.755324 -313.949842) (xy 419.044132 -313.949842)
			(xy 419.048092 -313.900788) (xy 419.059869 -313.853004) (xy 419.07916 -313.807728) (xy 419.105463 -313.766132)
			(xy 419.138098 -313.729295) (xy 419.176219 -313.69817) (xy 419.21884 -313.673563) (xy 419.264856 -313.656111)
			(xy 419.313075 -313.646267) (xy 419.36225 -313.644286) (xy 419.411105 -313.650218) (xy 419.458376 -313.66391)
			(xy 419.502838 -313.685008) (xy 419.543341 -313.712964) (xy 419.578834 -313.747056) (xy 419.608399 -313.7864)
			(xy 419.63127 -313.829977) (xy 419.646854 -313.876658) (xy 419.654749 -313.925235) (xy 419.655244 -313.949842)
			(xy 420.944052 -313.949842) (xy 420.948012 -313.900788) (xy 420.959789 -313.853004) (xy 420.97908 -313.807728)
			(xy 421.005383 -313.766132) (xy 421.038018 -313.729295) (xy 421.076139 -313.69817) (xy 421.11876 -313.673563)
			(xy 421.164776 -313.656111) (xy 421.212995 -313.646267) (xy 421.26217 -313.644286) (xy 421.311025 -313.650218)
			(xy 421.358296 -313.66391) (xy 421.402758 -313.685008) (xy 421.443261 -313.712964) (xy 421.478754 -313.747056)
			(xy 421.508319 -313.7864) (xy 421.53119 -313.829977) (xy 421.546774 -313.876658) (xy 421.554669 -313.925235)
			(xy 421.555164 -313.949842) (xy 421.554669 -313.974449) (xy 421.546774 -314.023026) (xy 421.53119 -314.069707)
			(xy 421.508319 -314.113284) (xy 421.478754 -314.152628) (xy 421.443261 -314.18672) (xy 421.402758 -314.214676)
			(xy 421.358296 -314.235774) (xy 421.311025 -314.249466) (xy 421.26217 -314.255398) (xy 421.212995 -314.253417)
			(xy 421.164776 -314.243573) (xy 421.11876 -314.226121) (xy 421.076139 -314.201514) (xy 421.038018 -314.170389)
			(xy 421.005383 -314.133552) (xy 420.97908 -314.091956) (xy 420.959789 -314.04668) (xy 420.948012 -313.998896)
			(xy 420.944052 -313.949842) (xy 419.655244 -313.949842) (xy 419.654749 -313.974449) (xy 419.646854 -314.023026)
			(xy 419.63127 -314.069707) (xy 419.608399 -314.113284) (xy 419.578834 -314.152628) (xy 419.543341 -314.18672)
			(xy 419.502838 -314.214676) (xy 419.458376 -314.235774) (xy 419.411105 -314.249466) (xy 419.36225 -314.255398)
			(xy 419.313075 -314.253417) (xy 419.264856 -314.243573) (xy 419.21884 -314.226121) (xy 419.176219 -314.201514)
			(xy 419.138098 -314.170389) (xy 419.105463 -314.133552) (xy 419.07916 -314.091956) (xy 419.059869 -314.04668)
			(xy 419.048092 -313.998896) (xy 419.044132 -313.949842) (xy 417.755324 -313.949842) (xy 417.754829 -313.974449)
			(xy 417.746934 -314.023026) (xy 417.73135 -314.069707) (xy 417.708479 -314.113284) (xy 417.678914 -314.152628)
			(xy 417.643421 -314.18672) (xy 417.602918 -314.214676) (xy 417.558456 -314.235774) (xy 417.511185 -314.249466)
			(xy 417.46233 -314.255398) (xy 417.413155 -314.253417) (xy 417.364936 -314.243573) (xy 417.31892 -314.226121)
			(xy 417.276299 -314.201514) (xy 417.238178 -314.170389) (xy 417.205543 -314.133552) (xy 417.17924 -314.091956)
			(xy 417.159949 -314.04668) (xy 417.148172 -313.998896) (xy 417.144212 -313.949842) (xy 415.85515 -313.949842)
			(xy 415.854655 -313.974449) (xy 415.84676 -314.023026) (xy 415.831176 -314.069707) (xy 415.808305 -314.113284)
			(xy 415.77874 -314.152628) (xy 415.743247 -314.18672) (xy 415.702744 -314.214676) (xy 415.658282 -314.235774)
			(xy 415.611011 -314.249466) (xy 415.562156 -314.255398) (xy 415.512981 -314.253417) (xy 415.464762 -314.243573)
			(xy 415.418746 -314.226121) (xy 415.376125 -314.201514) (xy 415.338004 -314.170389) (xy 415.305369 -314.133552)
			(xy 415.279066 -314.091956) (xy 415.259775 -314.04668) (xy 415.247998 -313.998896) (xy 415.244038 -313.949842)
			(xy 398.755108 -313.949842) (xy 398.754613 -313.974449) (xy 398.746718 -314.023026) (xy 398.731134 -314.069707)
			(xy 398.708263 -314.113284) (xy 398.678698 -314.152628) (xy 398.643205 -314.18672) (xy 398.602702 -314.214676)
			(xy 398.55824 -314.235774) (xy 398.510969 -314.249466) (xy 398.462114 -314.255398) (xy 398.412939 -314.253417)
			(xy 398.36472 -314.243573) (xy 398.318704 -314.226121) (xy 398.276083 -314.201514) (xy 398.237962 -314.170389)
			(xy 398.205327 -314.133552) (xy 398.179024 -314.091956) (xy 398.159733 -314.04668) (xy 398.147956 -313.998896)
			(xy 398.143996 -313.949842) (xy 396.855188 -313.949842) (xy 396.854693 -313.974449) (xy 396.846798 -314.023026)
			(xy 396.831214 -314.069707) (xy 396.808343 -314.113284) (xy 396.778778 -314.152628) (xy 396.743285 -314.18672)
			(xy 396.702782 -314.214676) (xy 396.65832 -314.235774) (xy 396.611049 -314.249466) (xy 396.562194 -314.255398)
			(xy 396.513019 -314.253417) (xy 396.4648 -314.243573) (xy 396.418784 -314.226121) (xy 396.376163 -314.201514)
			(xy 396.338042 -314.170389) (xy 396.305407 -314.133552) (xy 396.279104 -314.091956) (xy 396.259813 -314.04668)
			(xy 396.248036 -313.998896) (xy 396.244076 -313.949842) (xy 394.955268 -313.949842) (xy 394.954773 -313.974449)
			(xy 394.946878 -314.023026) (xy 394.931294 -314.069707) (xy 394.908423 -314.113284) (xy 394.878858 -314.152628)
			(xy 394.843365 -314.18672) (xy 394.802862 -314.214676) (xy 394.7584 -314.235774) (xy 394.711129 -314.249466)
			(xy 394.662274 -314.255398) (xy 394.613099 -314.253417) (xy 394.56488 -314.243573) (xy 394.518864 -314.226121)
			(xy 394.476243 -314.201514) (xy 394.438122 -314.170389) (xy 394.405487 -314.133552) (xy 394.379184 -314.091956)
			(xy 394.359893 -314.04668) (xy 394.348116 -313.998896) (xy 394.344156 -313.949842) (xy 393.055094 -313.949842)
			(xy 393.054599 -313.974449) (xy 393.046704 -314.023026) (xy 393.03112 -314.069707) (xy 393.008249 -314.113284)
			(xy 392.978684 -314.152628) (xy 392.943191 -314.18672) (xy 392.902688 -314.214676) (xy 392.858226 -314.235774)
			(xy 392.810955 -314.249466) (xy 392.7621 -314.255398) (xy 392.712925 -314.253417) (xy 392.664706 -314.243573)
			(xy 392.61869 -314.226121) (xy 392.576069 -314.201514) (xy 392.537948 -314.170389) (xy 392.505313 -314.133552)
			(xy 392.47901 -314.091956) (xy 392.459719 -314.04668) (xy 392.447942 -313.998896) (xy 392.443982 -313.949842)
			(xy 290.255198 -313.949842) (xy 290.254703 -313.974449) (xy 290.246808 -314.023026) (xy 290.231224 -314.069707)
			(xy 290.208353 -314.113284) (xy 290.178788 -314.152628) (xy 290.143295 -314.18672) (xy 290.102792 -314.214676)
			(xy 290.05833 -314.235774) (xy 290.011059 -314.249466) (xy 289.962204 -314.255398) (xy 289.913029 -314.253417)
			(xy 289.86481 -314.243573) (xy 289.818794 -314.226121) (xy 289.776173 -314.201514) (xy 289.738052 -314.170389)
			(xy 289.705417 -314.133552) (xy 289.679114 -314.091956) (xy 289.659823 -314.04668) (xy 289.648046 -313.998896)
			(xy 289.644086 -313.949842) (xy 288.355024 -313.949842) (xy 288.354529 -313.974449) (xy 288.346634 -314.023026)
			(xy 288.33105 -314.069707) (xy 288.308179 -314.113284) (xy 288.278614 -314.152628) (xy 288.243121 -314.18672)
			(xy 288.202618 -314.214676) (xy 288.158156 -314.235774) (xy 288.110885 -314.249466) (xy 288.06203 -314.255398)
			(xy 288.012855 -314.253417) (xy 287.964636 -314.243573) (xy 287.91862 -314.226121) (xy 287.875999 -314.201514)
			(xy 287.837878 -314.170389) (xy 287.805243 -314.133552) (xy 287.77894 -314.091956) (xy 287.759649 -314.04668)
			(xy 287.747872 -313.998896) (xy 287.743912 -313.949842) (xy 286.455104 -313.949842) (xy 286.454609 -313.974449)
			(xy 286.446714 -314.023026) (xy 286.43113 -314.069707) (xy 286.408259 -314.113284) (xy 286.378694 -314.152628)
			(xy 286.343201 -314.18672) (xy 286.302698 -314.214676) (xy 286.258236 -314.235774) (xy 286.210965 -314.249466)
			(xy 286.16211 -314.255398) (xy 286.112935 -314.253417) (xy 286.064716 -314.243573) (xy 286.0187 -314.226121)
			(xy 285.976079 -314.201514) (xy 285.937958 -314.170389) (xy 285.905323 -314.133552) (xy 285.87902 -314.091956)
			(xy 285.859729 -314.04668) (xy 285.847952 -313.998896) (xy 285.843992 -313.949842) (xy 284.555184 -313.949842)
			(xy 284.554689 -313.974449) (xy 284.546794 -314.023026) (xy 284.53121 -314.069707) (xy 284.508339 -314.113284)
			(xy 284.478774 -314.152628) (xy 284.443281 -314.18672) (xy 284.402778 -314.214676) (xy 284.358316 -314.235774)
			(xy 284.311045 -314.249466) (xy 284.26219 -314.255398) (xy 284.213015 -314.253417) (xy 284.164796 -314.243573)
			(xy 284.11878 -314.226121) (xy 284.076159 -314.201514) (xy 284.038038 -314.170389) (xy 284.005403 -314.133552)
			(xy 283.9791 -314.091956) (xy 283.959809 -314.04668) (xy 283.948032 -313.998896) (xy 283.944072 -313.949842)
			(xy 282.65501 -313.949842) (xy 282.654515 -313.974449) (xy 282.64662 -314.023026) (xy 282.631036 -314.069707)
			(xy 282.608165 -314.113284) (xy 282.5786 -314.152628) (xy 282.543107 -314.18672) (xy 282.502604 -314.214676)
			(xy 282.458142 -314.235774) (xy 282.410871 -314.249466) (xy 282.362016 -314.255398) (xy 282.312841 -314.253417)
			(xy 282.264622 -314.243573) (xy 282.218606 -314.226121) (xy 282.175985 -314.201514) (xy 282.137864 -314.170389)
			(xy 282.105229 -314.133552) (xy 282.078926 -314.091956) (xy 282.059635 -314.04668) (xy 282.047858 -313.998896)
			(xy 282.043898 -313.949842) (xy 280.75509 -313.949842) (xy 280.754595 -313.974449) (xy 280.7467 -314.023026)
			(xy 280.731116 -314.069707) (xy 280.708245 -314.113284) (xy 280.67868 -314.152628) (xy 280.643187 -314.18672)
			(xy 280.602684 -314.214676) (xy 280.558222 -314.235774) (xy 280.510951 -314.249466) (xy 280.462096 -314.255398)
			(xy 280.412921 -314.253417) (xy 280.364702 -314.243573) (xy 280.318686 -314.226121) (xy 280.276065 -314.201514)
			(xy 280.237944 -314.170389) (xy 280.205309 -314.133552) (xy 280.179006 -314.091956) (xy 280.159715 -314.04668)
			(xy 280.147938 -313.998896) (xy 280.143978 -313.949842) (xy 278.85517 -313.949842) (xy 278.854675 -313.974449)
			(xy 278.84678 -314.023026) (xy 278.831196 -314.069707) (xy 278.808325 -314.113284) (xy 278.77876 -314.152628)
			(xy 278.743267 -314.18672) (xy 278.702764 -314.214676) (xy 278.658302 -314.235774) (xy 278.611031 -314.249466)
			(xy 278.562176 -314.255398) (xy 278.513001 -314.253417) (xy 278.464782 -314.243573) (xy 278.418766 -314.226121)
			(xy 278.376145 -314.201514) (xy 278.338024 -314.170389) (xy 278.305389 -314.133552) (xy 278.279086 -314.091956)
			(xy 278.259795 -314.04668) (xy 278.248018 -313.998896) (xy 278.244058 -313.949842) (xy 276.954996 -313.949842)
			(xy 276.954501 -313.974449) (xy 276.946606 -314.023026) (xy 276.931022 -314.069707) (xy 276.908151 -314.113284)
			(xy 276.878586 -314.152628) (xy 276.843093 -314.18672) (xy 276.80259 -314.214676) (xy 276.758128 -314.235774)
			(xy 276.710857 -314.249466) (xy 276.662002 -314.255398) (xy 276.612827 -314.253417) (xy 276.564608 -314.243573)
			(xy 276.518592 -314.226121) (xy 276.475971 -314.201514) (xy 276.43785 -314.170389) (xy 276.405215 -314.133552)
			(xy 276.378912 -314.091956) (xy 276.359621 -314.04668) (xy 276.347844 -313.998896) (xy 276.343884 -313.949842)
			(xy 189.355222 -313.949842) (xy 189.354727 -313.974449) (xy 189.346832 -314.023026) (xy 189.331248 -314.069707)
			(xy 189.308377 -314.113284) (xy 189.278812 -314.152628) (xy 189.243319 -314.18672) (xy 189.202816 -314.214676)
			(xy 189.158354 -314.235774) (xy 189.111083 -314.249466) (xy 189.062228 -314.255398) (xy 189.013053 -314.253417)
			(xy 188.964834 -314.243573) (xy 188.918818 -314.226121) (xy 188.876197 -314.201514) (xy 188.838076 -314.170389)
			(xy 188.805441 -314.133552) (xy 188.779138 -314.091956) (xy 188.759847 -314.04668) (xy 188.74807 -313.998896)
			(xy 188.74411 -313.949842) (xy 187.455302 -313.949842) (xy 187.454807 -313.974449) (xy 187.446912 -314.023026)
			(xy 187.431328 -314.069707) (xy 187.408457 -314.113284) (xy 187.378892 -314.152628) (xy 187.343399 -314.18672)
			(xy 187.302896 -314.214676) (xy 187.258434 -314.235774) (xy 187.211163 -314.249466) (xy 187.162308 -314.255398)
			(xy 187.113133 -314.253417) (xy 187.064914 -314.243573) (xy 187.018898 -314.226121) (xy 186.976277 -314.201514)
			(xy 186.938156 -314.170389) (xy 186.905521 -314.133552) (xy 186.879218 -314.091956) (xy 186.859927 -314.04668)
			(xy 186.84815 -313.998896) (xy 186.84419 -313.949842) (xy 185.555382 -313.949842) (xy 185.554887 -313.974449)
			(xy 185.546992 -314.023026) (xy 185.531408 -314.069707) (xy 185.508537 -314.113284) (xy 185.478972 -314.152628)
			(xy 185.443479 -314.18672) (xy 185.402976 -314.214676) (xy 185.358514 -314.235774) (xy 185.311243 -314.249466)
			(xy 185.262388 -314.255398) (xy 185.213213 -314.253417) (xy 185.164994 -314.243573) (xy 185.118978 -314.226121)
			(xy 185.076357 -314.201514) (xy 185.038236 -314.170389) (xy 185.005601 -314.133552) (xy 184.979298 -314.091956)
			(xy 184.960007 -314.04668) (xy 184.94823 -313.998896) (xy 184.94427 -313.949842) (xy 183.655208 -313.949842)
			(xy 183.654713 -313.974449) (xy 183.646818 -314.023026) (xy 183.631234 -314.069707) (xy 183.608363 -314.113284)
			(xy 183.578798 -314.152628) (xy 183.543305 -314.18672) (xy 183.502802 -314.214676) (xy 183.45834 -314.235774)
			(xy 183.411069 -314.249466) (xy 183.362214 -314.255398) (xy 183.313039 -314.253417) (xy 183.26482 -314.243573)
			(xy 183.218804 -314.226121) (xy 183.176183 -314.201514) (xy 183.138062 -314.170389) (xy 183.105427 -314.133552)
			(xy 183.079124 -314.091956) (xy 183.059833 -314.04668) (xy 183.048056 -313.998896) (xy 183.044096 -313.949842)
			(xy 166.555166 -313.949842) (xy 166.554671 -313.974449) (xy 166.546776 -314.023026) (xy 166.531192 -314.069707)
			(xy 166.508321 -314.113284) (xy 166.478756 -314.152628) (xy 166.443263 -314.18672) (xy 166.40276 -314.214676)
			(xy 166.358298 -314.235774) (xy 166.311027 -314.249466) (xy 166.262172 -314.255398) (xy 166.212997 -314.253417)
			(xy 166.164778 -314.243573) (xy 166.118762 -314.226121) (xy 166.076141 -314.201514) (xy 166.03802 -314.170389)
			(xy 166.005385 -314.133552) (xy 165.979082 -314.091956) (xy 165.959791 -314.04668) (xy 165.948014 -313.998896)
			(xy 165.944054 -313.949842) (xy 164.655246 -313.949842) (xy 164.654751 -313.974449) (xy 164.646856 -314.023026)
			(xy 164.631272 -314.069707) (xy 164.608401 -314.113284) (xy 164.578836 -314.152628) (xy 164.543343 -314.18672)
			(xy 164.50284 -314.214676) (xy 164.458378 -314.235774) (xy 164.411107 -314.249466) (xy 164.362252 -314.255398)
			(xy 164.313077 -314.253417) (xy 164.264858 -314.243573) (xy 164.218842 -314.226121) (xy 164.176221 -314.201514)
			(xy 164.1381 -314.170389) (xy 164.105465 -314.133552) (xy 164.079162 -314.091956) (xy 164.059871 -314.04668)
			(xy 164.048094 -313.998896) (xy 164.044134 -313.949842) (xy 162.755326 -313.949842) (xy 162.754831 -313.974449)
			(xy 162.746936 -314.023026) (xy 162.731352 -314.069707) (xy 162.708481 -314.113284) (xy 162.678916 -314.152628)
			(xy 162.643423 -314.18672) (xy 162.60292 -314.214676) (xy 162.558458 -314.235774) (xy 162.511187 -314.249466)
			(xy 162.462332 -314.255398) (xy 162.413157 -314.253417) (xy 162.364938 -314.243573) (xy 162.318922 -314.226121)
			(xy 162.276301 -314.201514) (xy 162.23818 -314.170389) (xy 162.205545 -314.133552) (xy 162.179242 -314.091956)
			(xy 162.159951 -314.04668) (xy 162.148174 -313.998896) (xy 162.144214 -313.949842) (xy 160.855152 -313.949842)
			(xy 160.854657 -313.974449) (xy 160.846762 -314.023026) (xy 160.831178 -314.069707) (xy 160.808307 -314.113284)
			(xy 160.778742 -314.152628) (xy 160.743249 -314.18672) (xy 160.702746 -314.214676) (xy 160.658284 -314.235774)
			(xy 160.611013 -314.249466) (xy 160.562158 -314.255398) (xy 160.512983 -314.253417) (xy 160.464764 -314.243573)
			(xy 160.418748 -314.226121) (xy 160.376127 -314.201514) (xy 160.338006 -314.170389) (xy 160.305371 -314.133552)
			(xy 160.279068 -314.091956) (xy 160.259777 -314.04668) (xy 160.248 -313.998896) (xy 160.24404 -313.949842)
			(xy 58.055256 -313.949842) (xy 58.054761 -313.974449) (xy 58.046866 -314.023026) (xy 58.031282 -314.069707)
			(xy 58.008411 -314.113284) (xy 57.978846 -314.152628) (xy 57.943353 -314.18672) (xy 57.90285 -314.214676)
			(xy 57.858388 -314.235774) (xy 57.811117 -314.249466) (xy 57.762262 -314.255398) (xy 57.713087 -314.253417)
			(xy 57.664868 -314.243573) (xy 57.618852 -314.226121) (xy 57.576231 -314.201514) (xy 57.53811 -314.170389)
			(xy 57.505475 -314.133552) (xy 57.479172 -314.091956) (xy 57.459881 -314.04668) (xy 57.448104 -313.998896)
			(xy 57.444144 -313.949842) (xy 56.155082 -313.949842) (xy 56.154587 -313.974449) (xy 56.146692 -314.023026)
			(xy 56.131108 -314.069707) (xy 56.108237 -314.113284) (xy 56.078672 -314.152628) (xy 56.043179 -314.18672)
			(xy 56.002676 -314.214676) (xy 55.958214 -314.235774) (xy 55.910943 -314.249466) (xy 55.862088 -314.255398)
			(xy 55.812913 -314.253417) (xy 55.764694 -314.243573) (xy 55.718678 -314.226121) (xy 55.676057 -314.201514)
			(xy 55.637936 -314.170389) (xy 55.605301 -314.133552) (xy 55.578998 -314.091956) (xy 55.559707 -314.04668)
			(xy 55.54793 -313.998896) (xy 55.54397 -313.949842) (xy 54.255162 -313.949842) (xy 54.254667 -313.974449)
			(xy 54.246772 -314.023026) (xy 54.231188 -314.069707) (xy 54.208317 -314.113284) (xy 54.178752 -314.152628)
			(xy 54.143259 -314.18672) (xy 54.102756 -314.214676) (xy 54.058294 -314.235774) (xy 54.011023 -314.249466)
			(xy 53.962168 -314.255398) (xy 53.912993 -314.253417) (xy 53.864774 -314.243573) (xy 53.818758 -314.226121)
			(xy 53.776137 -314.201514) (xy 53.738016 -314.170389) (xy 53.705381 -314.133552) (xy 53.679078 -314.091956)
			(xy 53.659787 -314.04668) (xy 53.64801 -313.998896) (xy 53.64405 -313.949842) (xy 52.355242 -313.949842)
			(xy 52.354747 -313.974449) (xy 52.346852 -314.023026) (xy 52.331268 -314.069707) (xy 52.308397 -314.113284)
			(xy 52.278832 -314.152628) (xy 52.243339 -314.18672) (xy 52.202836 -314.214676) (xy 52.158374 -314.235774)
			(xy 52.111103 -314.249466) (xy 52.062248 -314.255398) (xy 52.013073 -314.253417) (xy 51.964854 -314.243573)
			(xy 51.918838 -314.226121) (xy 51.876217 -314.201514) (xy 51.838096 -314.170389) (xy 51.805461 -314.133552)
			(xy 51.779158 -314.091956) (xy 51.759867 -314.04668) (xy 51.74809 -313.998896) (xy 51.74413 -313.949842)
			(xy 50.455068 -313.949842) (xy 50.454573 -313.974449) (xy 50.446678 -314.023026) (xy 50.431094 -314.069707)
			(xy 50.408223 -314.113284) (xy 50.378658 -314.152628) (xy 50.343165 -314.18672) (xy 50.302662 -314.214676)
			(xy 50.2582 -314.235774) (xy 50.210929 -314.249466) (xy 50.162074 -314.255398) (xy 50.112899 -314.253417)
			(xy 50.06468 -314.243573) (xy 50.018664 -314.226121) (xy 49.976043 -314.201514) (xy 49.937922 -314.170389)
			(xy 49.905287 -314.133552) (xy 49.878984 -314.091956) (xy 49.859693 -314.04668) (xy 49.847916 -313.998896)
			(xy 49.843956 -313.949842) (xy 48.555148 -313.949842) (xy 48.554653 -313.974449) (xy 48.546758 -314.023026)
			(xy 48.531174 -314.069707) (xy 48.508303 -314.113284) (xy 48.478738 -314.152628) (xy 48.443245 -314.18672)
			(xy 48.402742 -314.214676) (xy 48.35828 -314.235774) (xy 48.311009 -314.249466) (xy 48.262154 -314.255398)
			(xy 48.212979 -314.253417) (xy 48.16476 -314.243573) (xy 48.118744 -314.226121) (xy 48.076123 -314.201514)
			(xy 48.038002 -314.170389) (xy 48.005367 -314.133552) (xy 47.979064 -314.091956) (xy 47.959773 -314.04668)
			(xy 47.947996 -313.998896) (xy 47.944036 -313.949842) (xy 46.655228 -313.949842) (xy 46.654733 -313.974449)
			(xy 46.646838 -314.023026) (xy 46.631254 -314.069707) (xy 46.608383 -314.113284) (xy 46.578818 -314.152628)
			(xy 46.543325 -314.18672) (xy 46.502822 -314.214676) (xy 46.45836 -314.235774) (xy 46.411089 -314.249466)
			(xy 46.362234 -314.255398) (xy 46.313059 -314.253417) (xy 46.26484 -314.243573) (xy 46.218824 -314.226121)
			(xy 46.176203 -314.201514) (xy 46.138082 -314.170389) (xy 46.105447 -314.133552) (xy 46.079144 -314.091956)
			(xy 46.059853 -314.04668) (xy 46.048076 -313.998896) (xy 46.044116 -313.949842) (xy 44.755054 -313.949842)
			(xy 44.754559 -313.974449) (xy 44.746664 -314.023026) (xy 44.73108 -314.069707) (xy 44.708209 -314.113284)
			(xy 44.678644 -314.152628) (xy 44.643151 -314.18672) (xy 44.602648 -314.214676) (xy 44.558186 -314.235774)
			(xy 44.510915 -314.249466) (xy 44.46206 -314.255398) (xy 44.412885 -314.253417) (xy 44.364666 -314.243573)
			(xy 44.31865 -314.226121) (xy 44.276029 -314.201514) (xy 44.237908 -314.170389) (xy 44.205273 -314.133552)
			(xy 44.17897 -314.091956) (xy 44.159679 -314.04668) (xy 44.147902 -313.998896) (xy 44.143942 -313.949842)
			(xy 0.508 -313.949842) (xy 0.508 -315.849762) (xy 73.593972 -315.849762) (xy 73.597932 -315.800708)
			(xy 73.609709 -315.752924) (xy 73.629 -315.707648) (xy 73.655303 -315.666052) (xy 73.687938 -315.629215)
			(xy 73.726059 -315.59809) (xy 73.76868 -315.573483) (xy 73.814696 -315.556031) (xy 73.862915 -315.546187)
			(xy 73.91209 -315.544206) (xy 73.960945 -315.550138) (xy 74.008216 -315.56383) (xy 74.052678 -315.584928)
			(xy 74.093181 -315.612884) (xy 74.128674 -315.646976) (xy 74.158239 -315.68632) (xy 74.18111 -315.729897)
			(xy 74.196694 -315.776578) (xy 74.204589 -315.825155) (xy 74.205084 -315.849762) (xy 75.494146 -315.849762)
			(xy 75.498106 -315.800708) (xy 75.509883 -315.752924) (xy 75.529174 -315.707648) (xy 75.555477 -315.666052)
			(xy 75.588112 -315.629215) (xy 75.626233 -315.59809) (xy 75.668854 -315.573483) (xy 75.71487 -315.556031)
			(xy 75.763089 -315.546187) (xy 75.812264 -315.544206) (xy 75.861119 -315.550138) (xy 75.90839 -315.56383)
			(xy 75.952852 -315.584928) (xy 75.993355 -315.612884) (xy 76.028848 -315.646976) (xy 76.058413 -315.68632)
			(xy 76.081284 -315.729897) (xy 76.096868 -315.776578) (xy 76.104763 -315.825155) (xy 76.105258 -315.849762)
			(xy 77.394066 -315.849762) (xy 77.398026 -315.800708) (xy 77.409803 -315.752924) (xy 77.429094 -315.707648)
			(xy 77.455397 -315.666052) (xy 77.488032 -315.629215) (xy 77.526153 -315.59809) (xy 77.568774 -315.573483)
			(xy 77.61479 -315.556031) (xy 77.663009 -315.546187) (xy 77.712184 -315.544206) (xy 77.761039 -315.550138)
			(xy 77.80831 -315.56383) (xy 77.852772 -315.584928) (xy 77.893275 -315.612884) (xy 77.928768 -315.646976)
			(xy 77.958333 -315.68632) (xy 77.981204 -315.729897) (xy 77.996788 -315.776578) (xy 78.004683 -315.825155)
			(xy 78.005178 -315.849762) (xy 79.293986 -315.849762) (xy 79.297946 -315.800708) (xy 79.309723 -315.752924)
			(xy 79.329014 -315.707648) (xy 79.355317 -315.666052) (xy 79.387952 -315.629215) (xy 79.426073 -315.59809)
			(xy 79.468694 -315.573483) (xy 79.51471 -315.556031) (xy 79.562929 -315.546187) (xy 79.612104 -315.544206)
			(xy 79.660959 -315.550138) (xy 79.70823 -315.56383) (xy 79.752692 -315.584928) (xy 79.793195 -315.612884)
			(xy 79.828688 -315.646976) (xy 79.858253 -315.68632) (xy 79.881124 -315.729897) (xy 79.896708 -315.776578)
			(xy 79.904603 -315.825155) (xy 79.905098 -315.849762) (xy 159.29408 -315.849762) (xy 159.29804 -315.800708)
			(xy 159.309817 -315.752924) (xy 159.329108 -315.707648) (xy 159.355411 -315.666052) (xy 159.388046 -315.629215)
			(xy 159.426167 -315.59809) (xy 159.468788 -315.573483) (xy 159.514804 -315.556031) (xy 159.563023 -315.546187)
			(xy 159.612198 -315.544206) (xy 159.661053 -315.550138) (xy 159.708324 -315.56383) (xy 159.752786 -315.584928)
			(xy 159.793289 -315.612884) (xy 159.828782 -315.646976) (xy 159.858347 -315.68632) (xy 159.881218 -315.729897)
			(xy 159.896802 -315.776578) (xy 159.904697 -315.825155) (xy 159.905192 -315.849762) (xy 161.194254 -315.849762)
			(xy 161.198214 -315.800708) (xy 161.209991 -315.752924) (xy 161.229282 -315.707648) (xy 161.255585 -315.666052)
			(xy 161.28822 -315.629215) (xy 161.326341 -315.59809) (xy 161.368962 -315.573483) (xy 161.414978 -315.556031)
			(xy 161.463197 -315.546187) (xy 161.512372 -315.544206) (xy 161.561227 -315.550138) (xy 161.608498 -315.56383)
			(xy 161.65296 -315.584928) (xy 161.693463 -315.612884) (xy 161.728956 -315.646976) (xy 161.758521 -315.68632)
			(xy 161.781392 -315.729897) (xy 161.796976 -315.776578) (xy 161.804871 -315.825155) (xy 161.805366 -315.849762)
			(xy 163.094174 -315.849762) (xy 163.098134 -315.800708) (xy 163.109911 -315.752924) (xy 163.129202 -315.707648)
			(xy 163.155505 -315.666052) (xy 163.18814 -315.629215) (xy 163.226261 -315.59809) (xy 163.268882 -315.573483)
			(xy 163.314898 -315.556031) (xy 163.363117 -315.546187) (xy 163.412292 -315.544206) (xy 163.461147 -315.550138)
			(xy 163.508418 -315.56383) (xy 163.55288 -315.584928) (xy 163.593383 -315.612884) (xy 163.628876 -315.646976)
			(xy 163.658441 -315.68632) (xy 163.681312 -315.729897) (xy 163.696896 -315.776578) (xy 163.704791 -315.825155)
			(xy 163.705286 -315.849762) (xy 164.994094 -315.849762) (xy 164.998054 -315.800708) (xy 165.009831 -315.752924)
			(xy 165.029122 -315.707648) (xy 165.055425 -315.666052) (xy 165.08806 -315.629215) (xy 165.126181 -315.59809)
			(xy 165.168802 -315.573483) (xy 165.214818 -315.556031) (xy 165.263037 -315.546187) (xy 165.312212 -315.544206)
			(xy 165.361067 -315.550138) (xy 165.408338 -315.56383) (xy 165.4528 -315.584928) (xy 165.493303 -315.612884)
			(xy 165.528796 -315.646976) (xy 165.558361 -315.68632) (xy 165.581232 -315.729897) (xy 165.596816 -315.776578)
			(xy 165.604711 -315.825155) (xy 165.605206 -315.849762) (xy 182.094136 -315.849762) (xy 182.098096 -315.800708)
			(xy 182.109873 -315.752924) (xy 182.129164 -315.707648) (xy 182.155467 -315.666052) (xy 182.188102 -315.629215)
			(xy 182.226223 -315.59809) (xy 182.268844 -315.573483) (xy 182.31486 -315.556031) (xy 182.363079 -315.546187)
			(xy 182.412254 -315.544206) (xy 182.461109 -315.550138) (xy 182.50838 -315.56383) (xy 182.552842 -315.584928)
			(xy 182.593345 -315.612884) (xy 182.628838 -315.646976) (xy 182.658403 -315.68632) (xy 182.681274 -315.729897)
			(xy 182.696858 -315.776578) (xy 182.704753 -315.825155) (xy 182.705248 -315.849762) (xy 183.994056 -315.849762)
			(xy 183.998016 -315.800708) (xy 184.009793 -315.752924) (xy 184.029084 -315.707648) (xy 184.055387 -315.666052)
			(xy 184.088022 -315.629215) (xy 184.126143 -315.59809) (xy 184.168764 -315.573483) (xy 184.21478 -315.556031)
			(xy 184.262999 -315.546187) (xy 184.312174 -315.544206) (xy 184.361029 -315.550138) (xy 184.4083 -315.56383)
			(xy 184.452762 -315.584928) (xy 184.493265 -315.612884) (xy 184.528758 -315.646976) (xy 184.558323 -315.68632)
			(xy 184.581194 -315.729897) (xy 184.596778 -315.776578) (xy 184.604673 -315.825155) (xy 184.605168 -315.849762)
			(xy 185.89423 -315.849762) (xy 185.89819 -315.800708) (xy 185.909967 -315.752924) (xy 185.929258 -315.707648)
			(xy 185.955561 -315.666052) (xy 185.988196 -315.629215) (xy 186.026317 -315.59809) (xy 186.068938 -315.573483)
			(xy 186.114954 -315.556031) (xy 186.163173 -315.546187) (xy 186.212348 -315.544206) (xy 186.261203 -315.550138)
			(xy 186.308474 -315.56383) (xy 186.352936 -315.584928) (xy 186.393439 -315.612884) (xy 186.428932 -315.646976)
			(xy 186.458497 -315.68632) (xy 186.481368 -315.729897) (xy 186.496952 -315.776578) (xy 186.504847 -315.825155)
			(xy 186.505342 -315.849762) (xy 187.79415 -315.849762) (xy 187.79811 -315.800708) (xy 187.809887 -315.752924)
			(xy 187.829178 -315.707648) (xy 187.855481 -315.666052) (xy 187.888116 -315.629215) (xy 187.926237 -315.59809)
			(xy 187.968858 -315.573483) (xy 188.014874 -315.556031) (xy 188.063093 -315.546187) (xy 188.112268 -315.544206)
			(xy 188.161123 -315.550138) (xy 188.208394 -315.56383) (xy 188.252856 -315.584928) (xy 188.293359 -315.612884)
			(xy 188.328852 -315.646976) (xy 188.358417 -315.68632) (xy 188.381288 -315.729897) (xy 188.396872 -315.776578)
			(xy 188.404767 -315.825155) (xy 188.405262 -315.849762) (xy 305.793914 -315.849762) (xy 305.797874 -315.800708)
			(xy 305.809651 -315.752924) (xy 305.828942 -315.707648) (xy 305.855245 -315.666052) (xy 305.88788 -315.629215)
			(xy 305.926001 -315.59809) (xy 305.968622 -315.573483) (xy 306.014638 -315.556031) (xy 306.062857 -315.546187)
			(xy 306.112032 -315.544206) (xy 306.160887 -315.550138) (xy 306.208158 -315.56383) (xy 306.25262 -315.584928)
			(xy 306.293123 -315.612884) (xy 306.328616 -315.646976) (xy 306.358181 -315.68632) (xy 306.381052 -315.729897)
			(xy 306.396636 -315.776578) (xy 306.404531 -315.825155) (xy 306.405026 -315.849762) (xy 307.694088 -315.849762)
			(xy 307.698048 -315.800708) (xy 307.709825 -315.752924) (xy 307.729116 -315.707648) (xy 307.755419 -315.666052)
			(xy 307.788054 -315.629215) (xy 307.826175 -315.59809) (xy 307.868796 -315.573483) (xy 307.914812 -315.556031)
			(xy 307.963031 -315.546187) (xy 308.012206 -315.544206) (xy 308.061061 -315.550138) (xy 308.108332 -315.56383)
			(xy 308.152794 -315.584928) (xy 308.193297 -315.612884) (xy 308.22879 -315.646976) (xy 308.258355 -315.68632)
			(xy 308.281226 -315.729897) (xy 308.29681 -315.776578) (xy 308.304705 -315.825155) (xy 308.3052 -315.849762)
			(xy 309.594008 -315.849762) (xy 309.597968 -315.800708) (xy 309.609745 -315.752924) (xy 309.629036 -315.707648)
			(xy 309.655339 -315.666052) (xy 309.687974 -315.629215) (xy 309.726095 -315.59809) (xy 309.768716 -315.573483)
			(xy 309.814732 -315.556031) (xy 309.862951 -315.546187) (xy 309.912126 -315.544206) (xy 309.960981 -315.550138)
			(xy 310.008252 -315.56383) (xy 310.052714 -315.584928) (xy 310.093217 -315.612884) (xy 310.12871 -315.646976)
			(xy 310.158275 -315.68632) (xy 310.181146 -315.729897) (xy 310.19673 -315.776578) (xy 310.204625 -315.825155)
			(xy 310.20512 -315.849762) (xy 311.493928 -315.849762) (xy 311.497888 -315.800708) (xy 311.509665 -315.752924)
			(xy 311.528956 -315.707648) (xy 311.555259 -315.666052) (xy 311.587894 -315.629215) (xy 311.626015 -315.59809)
			(xy 311.668636 -315.573483) (xy 311.714652 -315.556031) (xy 311.762871 -315.546187) (xy 311.812046 -315.544206)
			(xy 311.860901 -315.550138) (xy 311.908172 -315.56383) (xy 311.952634 -315.584928) (xy 311.993137 -315.612884)
			(xy 312.02863 -315.646976) (xy 312.058195 -315.68632) (xy 312.081066 -315.729897) (xy 312.09665 -315.776578)
			(xy 312.104545 -315.825155) (xy 312.10504 -315.849762) (xy 391.494022 -315.849762) (xy 391.497982 -315.800708)
			(xy 391.509759 -315.752924) (xy 391.52905 -315.707648) (xy 391.555353 -315.666052) (xy 391.587988 -315.629215)
			(xy 391.626109 -315.59809) (xy 391.66873 -315.573483) (xy 391.714746 -315.556031) (xy 391.762965 -315.546187)
			(xy 391.81214 -315.544206) (xy 391.860995 -315.550138) (xy 391.908266 -315.56383) (xy 391.952728 -315.584928)
			(xy 391.993231 -315.612884) (xy 392.028724 -315.646976) (xy 392.058289 -315.68632) (xy 392.08116 -315.729897)
			(xy 392.096744 -315.776578) (xy 392.104639 -315.825155) (xy 392.105134 -315.849762) (xy 393.394196 -315.849762)
			(xy 393.398156 -315.800708) (xy 393.409933 -315.752924) (xy 393.429224 -315.707648) (xy 393.455527 -315.666052)
			(xy 393.488162 -315.629215) (xy 393.526283 -315.59809) (xy 393.568904 -315.573483) (xy 393.61492 -315.556031)
			(xy 393.663139 -315.546187) (xy 393.712314 -315.544206) (xy 393.761169 -315.550138) (xy 393.80844 -315.56383)
			(xy 393.852902 -315.584928) (xy 393.893405 -315.612884) (xy 393.928898 -315.646976) (xy 393.958463 -315.68632)
			(xy 393.981334 -315.729897) (xy 393.996918 -315.776578) (xy 394.004813 -315.825155) (xy 394.005308 -315.849762)
			(xy 395.294116 -315.849762) (xy 395.298076 -315.800708) (xy 395.309853 -315.752924) (xy 395.329144 -315.707648)
			(xy 395.355447 -315.666052) (xy 395.388082 -315.629215) (xy 395.426203 -315.59809) (xy 395.468824 -315.573483)
			(xy 395.51484 -315.556031) (xy 395.563059 -315.546187) (xy 395.612234 -315.544206) (xy 395.661089 -315.550138)
			(xy 395.70836 -315.56383) (xy 395.752822 -315.584928) (xy 395.793325 -315.612884) (xy 395.828818 -315.646976)
			(xy 395.858383 -315.68632) (xy 395.881254 -315.729897) (xy 395.896838 -315.776578) (xy 395.904733 -315.825155)
			(xy 395.905228 -315.849762) (xy 397.194036 -315.849762) (xy 397.197996 -315.800708) (xy 397.209773 -315.752924)
			(xy 397.229064 -315.707648) (xy 397.255367 -315.666052) (xy 397.288002 -315.629215) (xy 397.326123 -315.59809)
			(xy 397.368744 -315.573483) (xy 397.41476 -315.556031) (xy 397.462979 -315.546187) (xy 397.512154 -315.544206)
			(xy 397.561009 -315.550138) (xy 397.60828 -315.56383) (xy 397.652742 -315.584928) (xy 397.693245 -315.612884)
			(xy 397.728738 -315.646976) (xy 397.758303 -315.68632) (xy 397.781174 -315.729897) (xy 397.796758 -315.776578)
			(xy 397.804653 -315.825155) (xy 397.805148 -315.849762) (xy 414.294078 -315.849762) (xy 414.298038 -315.800708)
			(xy 414.309815 -315.752924) (xy 414.329106 -315.707648) (xy 414.355409 -315.666052) (xy 414.388044 -315.629215)
			(xy 414.426165 -315.59809) (xy 414.468786 -315.573483) (xy 414.514802 -315.556031) (xy 414.563021 -315.546187)
			(xy 414.612196 -315.544206) (xy 414.661051 -315.550138) (xy 414.708322 -315.56383) (xy 414.752784 -315.584928)
			(xy 414.793287 -315.612884) (xy 414.82878 -315.646976) (xy 414.858345 -315.68632) (xy 414.881216 -315.729897)
			(xy 414.8968 -315.776578) (xy 414.904695 -315.825155) (xy 414.90519 -315.849762) (xy 416.193998 -315.849762)
			(xy 416.197958 -315.800708) (xy 416.209735 -315.752924) (xy 416.229026 -315.707648) (xy 416.255329 -315.666052)
			(xy 416.287964 -315.629215) (xy 416.326085 -315.59809) (xy 416.368706 -315.573483) (xy 416.414722 -315.556031)
			(xy 416.462941 -315.546187) (xy 416.512116 -315.544206) (xy 416.560971 -315.550138) (xy 416.608242 -315.56383)
			(xy 416.652704 -315.584928) (xy 416.693207 -315.612884) (xy 416.7287 -315.646976) (xy 416.758265 -315.68632)
			(xy 416.781136 -315.729897) (xy 416.79672 -315.776578) (xy 416.804615 -315.825155) (xy 416.80511 -315.849762)
			(xy 418.094172 -315.849762) (xy 418.098132 -315.800708) (xy 418.109909 -315.752924) (xy 418.1292 -315.707648)
			(xy 418.155503 -315.666052) (xy 418.188138 -315.629215) (xy 418.226259 -315.59809) (xy 418.26888 -315.573483)
			(xy 418.314896 -315.556031) (xy 418.363115 -315.546187) (xy 418.41229 -315.544206) (xy 418.461145 -315.550138)
			(xy 418.508416 -315.56383) (xy 418.552878 -315.584928) (xy 418.593381 -315.612884) (xy 418.628874 -315.646976)
			(xy 418.658439 -315.68632) (xy 418.68131 -315.729897) (xy 418.696894 -315.776578) (xy 418.704789 -315.825155)
			(xy 418.705284 -315.849762) (xy 419.994092 -315.849762) (xy 419.998052 -315.800708) (xy 420.009829 -315.752924)
			(xy 420.02912 -315.707648) (xy 420.055423 -315.666052) (xy 420.088058 -315.629215) (xy 420.126179 -315.59809)
			(xy 420.1688 -315.573483) (xy 420.214816 -315.556031) (xy 420.263035 -315.546187) (xy 420.31221 -315.544206)
			(xy 420.361065 -315.550138) (xy 420.408336 -315.56383) (xy 420.452798 -315.584928) (xy 420.493301 -315.612884)
			(xy 420.528794 -315.646976) (xy 420.558359 -315.68632) (xy 420.58123 -315.729897) (xy 420.596814 -315.776578)
			(xy 420.604709 -315.825155) (xy 420.605204 -315.849762) (xy 420.604709 -315.874369) (xy 420.596814 -315.922946)
			(xy 420.58123 -315.969627) (xy 420.558359 -316.013204) (xy 420.528794 -316.052548) (xy 420.493301 -316.08664)
			(xy 420.452798 -316.114596) (xy 420.408336 -316.135694) (xy 420.361065 -316.149386) (xy 420.31221 -316.155318)
			(xy 420.263035 -316.153337) (xy 420.214816 -316.143493) (xy 420.1688 -316.126041) (xy 420.126179 -316.101434)
			(xy 420.088058 -316.070309) (xy 420.055423 -316.033472) (xy 420.02912 -315.991876) (xy 420.009829 -315.9466)
			(xy 419.998052 -315.898816) (xy 419.994092 -315.849762) (xy 418.705284 -315.849762) (xy 418.704789 -315.874369)
			(xy 418.696894 -315.922946) (xy 418.68131 -315.969627) (xy 418.658439 -316.013204) (xy 418.628874 -316.052548)
			(xy 418.593381 -316.08664) (xy 418.552878 -316.114596) (xy 418.508416 -316.135694) (xy 418.461145 -316.149386)
			(xy 418.41229 -316.155318) (xy 418.363115 -316.153337) (xy 418.314896 -316.143493) (xy 418.26888 -316.126041)
			(xy 418.226259 -316.101434) (xy 418.188138 -316.070309) (xy 418.155503 -316.033472) (xy 418.1292 -315.991876)
			(xy 418.109909 -315.9466) (xy 418.098132 -315.898816) (xy 418.094172 -315.849762) (xy 416.80511 -315.849762)
			(xy 416.804615 -315.874369) (xy 416.79672 -315.922946) (xy 416.781136 -315.969627) (xy 416.758265 -316.013204)
			(xy 416.7287 -316.052548) (xy 416.693207 -316.08664) (xy 416.652704 -316.114596) (xy 416.608242 -316.135694)
			(xy 416.560971 -316.149386) (xy 416.512116 -316.155318) (xy 416.462941 -316.153337) (xy 416.414722 -316.143493)
			(xy 416.368706 -316.126041) (xy 416.326085 -316.101434) (xy 416.287964 -316.070309) (xy 416.255329 -316.033472)
			(xy 416.229026 -315.991876) (xy 416.209735 -315.9466) (xy 416.197958 -315.898816) (xy 416.193998 -315.849762)
			(xy 414.90519 -315.849762) (xy 414.904695 -315.874369) (xy 414.8968 -315.922946) (xy 414.881216 -315.969627)
			(xy 414.858345 -316.013204) (xy 414.82878 -316.052548) (xy 414.793287 -316.08664) (xy 414.752784 -316.114596)
			(xy 414.708322 -316.135694) (xy 414.661051 -316.149386) (xy 414.612196 -316.155318) (xy 414.563021 -316.153337)
			(xy 414.514802 -316.143493) (xy 414.468786 -316.126041) (xy 414.426165 -316.101434) (xy 414.388044 -316.070309)
			(xy 414.355409 -316.033472) (xy 414.329106 -315.991876) (xy 414.309815 -315.9466) (xy 414.298038 -315.898816)
			(xy 414.294078 -315.849762) (xy 397.805148 -315.849762) (xy 397.804653 -315.874369) (xy 397.796758 -315.922946)
			(xy 397.781174 -315.969627) (xy 397.758303 -316.013204) (xy 397.728738 -316.052548) (xy 397.693245 -316.08664)
			(xy 397.652742 -316.114596) (xy 397.60828 -316.135694) (xy 397.561009 -316.149386) (xy 397.512154 -316.155318)
			(xy 397.462979 -316.153337) (xy 397.41476 -316.143493) (xy 397.368744 -316.126041) (xy 397.326123 -316.101434)
			(xy 397.288002 -316.070309) (xy 397.255367 -316.033472) (xy 397.229064 -315.991876) (xy 397.209773 -315.9466)
			(xy 397.197996 -315.898816) (xy 397.194036 -315.849762) (xy 395.905228 -315.849762) (xy 395.904733 -315.874369)
			(xy 395.896838 -315.922946) (xy 395.881254 -315.969627) (xy 395.858383 -316.013204) (xy 395.828818 -316.052548)
			(xy 395.793325 -316.08664) (xy 395.752822 -316.114596) (xy 395.70836 -316.135694) (xy 395.661089 -316.149386)
			(xy 395.612234 -316.155318) (xy 395.563059 -316.153337) (xy 395.51484 -316.143493) (xy 395.468824 -316.126041)
			(xy 395.426203 -316.101434) (xy 395.388082 -316.070309) (xy 395.355447 -316.033472) (xy 395.329144 -315.991876)
			(xy 395.309853 -315.9466) (xy 395.298076 -315.898816) (xy 395.294116 -315.849762) (xy 394.005308 -315.849762)
			(xy 394.004813 -315.874369) (xy 393.996918 -315.922946) (xy 393.981334 -315.969627) (xy 393.958463 -316.013204)
			(xy 393.928898 -316.052548) (xy 393.893405 -316.08664) (xy 393.852902 -316.114596) (xy 393.80844 -316.135694)
			(xy 393.761169 -316.149386) (xy 393.712314 -316.155318) (xy 393.663139 -316.153337) (xy 393.61492 -316.143493)
			(xy 393.568904 -316.126041) (xy 393.526283 -316.101434) (xy 393.488162 -316.070309) (xy 393.455527 -316.033472)
			(xy 393.429224 -315.991876) (xy 393.409933 -315.9466) (xy 393.398156 -315.898816) (xy 393.394196 -315.849762)
			(xy 392.105134 -315.849762) (xy 392.104639 -315.874369) (xy 392.096744 -315.922946) (xy 392.08116 -315.969627)
			(xy 392.058289 -316.013204) (xy 392.028724 -316.052548) (xy 391.993231 -316.08664) (xy 391.952728 -316.114596)
			(xy 391.908266 -316.135694) (xy 391.860995 -316.149386) (xy 391.81214 -316.155318) (xy 391.762965 -316.153337)
			(xy 391.714746 -316.143493) (xy 391.66873 -316.126041) (xy 391.626109 -316.101434) (xy 391.587988 -316.070309)
			(xy 391.555353 -316.033472) (xy 391.52905 -315.991876) (xy 391.509759 -315.9466) (xy 391.497982 -315.898816)
			(xy 391.494022 -315.849762) (xy 312.10504 -315.849762) (xy 312.104545 -315.874369) (xy 312.09665 -315.922946)
			(xy 312.081066 -315.969627) (xy 312.058195 -316.013204) (xy 312.02863 -316.052548) (xy 311.993137 -316.08664)
			(xy 311.952634 -316.114596) (xy 311.908172 -316.135694) (xy 311.860901 -316.149386) (xy 311.812046 -316.155318)
			(xy 311.762871 -316.153337) (xy 311.714652 -316.143493) (xy 311.668636 -316.126041) (xy 311.626015 -316.101434)
			(xy 311.587894 -316.070309) (xy 311.555259 -316.033472) (xy 311.528956 -315.991876) (xy 311.509665 -315.9466)
			(xy 311.497888 -315.898816) (xy 311.493928 -315.849762) (xy 310.20512 -315.849762) (xy 310.204625 -315.874369)
			(xy 310.19673 -315.922946) (xy 310.181146 -315.969627) (xy 310.158275 -316.013204) (xy 310.12871 -316.052548)
			(xy 310.093217 -316.08664) (xy 310.052714 -316.114596) (xy 310.008252 -316.135694) (xy 309.960981 -316.149386)
			(xy 309.912126 -316.155318) (xy 309.862951 -316.153337) (xy 309.814732 -316.143493) (xy 309.768716 -316.126041)
			(xy 309.726095 -316.101434) (xy 309.687974 -316.070309) (xy 309.655339 -316.033472) (xy 309.629036 -315.991876)
			(xy 309.609745 -315.9466) (xy 309.597968 -315.898816) (xy 309.594008 -315.849762) (xy 308.3052 -315.849762)
			(xy 308.304705 -315.874369) (xy 308.29681 -315.922946) (xy 308.281226 -315.969627) (xy 308.258355 -316.013204)
			(xy 308.22879 -316.052548) (xy 308.193297 -316.08664) (xy 308.152794 -316.114596) (xy 308.108332 -316.135694)
			(xy 308.061061 -316.149386) (xy 308.012206 -316.155318) (xy 307.963031 -316.153337) (xy 307.914812 -316.143493)
			(xy 307.868796 -316.126041) (xy 307.826175 -316.101434) (xy 307.788054 -316.070309) (xy 307.755419 -316.033472)
			(xy 307.729116 -315.991876) (xy 307.709825 -315.9466) (xy 307.698048 -315.898816) (xy 307.694088 -315.849762)
			(xy 306.405026 -315.849762) (xy 306.404531 -315.874369) (xy 306.396636 -315.922946) (xy 306.381052 -315.969627)
			(xy 306.358181 -316.013204) (xy 306.328616 -316.052548) (xy 306.293123 -316.08664) (xy 306.25262 -316.114596)
			(xy 306.208158 -316.135694) (xy 306.160887 -316.149386) (xy 306.112032 -316.155318) (xy 306.062857 -316.153337)
			(xy 306.014638 -316.143493) (xy 305.968622 -316.126041) (xy 305.926001 -316.101434) (xy 305.88788 -316.070309)
			(xy 305.855245 -316.033472) (xy 305.828942 -315.991876) (xy 305.809651 -315.9466) (xy 305.797874 -315.898816)
			(xy 305.793914 -315.849762) (xy 188.405262 -315.849762) (xy 188.404767 -315.874369) (xy 188.396872 -315.922946)
			(xy 188.381288 -315.969627) (xy 188.358417 -316.013204) (xy 188.328852 -316.052548) (xy 188.293359 -316.08664)
			(xy 188.252856 -316.114596) (xy 188.208394 -316.135694) (xy 188.161123 -316.149386) (xy 188.112268 -316.155318)
			(xy 188.063093 -316.153337) (xy 188.014874 -316.143493) (xy 187.968858 -316.126041) (xy 187.926237 -316.101434)
			(xy 187.888116 -316.070309) (xy 187.855481 -316.033472) (xy 187.829178 -315.991876) (xy 187.809887 -315.9466)
			(xy 187.79811 -315.898816) (xy 187.79415 -315.849762) (xy 186.505342 -315.849762) (xy 186.504847 -315.874369)
			(xy 186.496952 -315.922946) (xy 186.481368 -315.969627) (xy 186.458497 -316.013204) (xy 186.428932 -316.052548)
			(xy 186.393439 -316.08664) (xy 186.352936 -316.114596) (xy 186.308474 -316.135694) (xy 186.261203 -316.149386)
			(xy 186.212348 -316.155318) (xy 186.163173 -316.153337) (xy 186.114954 -316.143493) (xy 186.068938 -316.126041)
			(xy 186.026317 -316.101434) (xy 185.988196 -316.070309) (xy 185.955561 -316.033472) (xy 185.929258 -315.991876)
			(xy 185.909967 -315.9466) (xy 185.89819 -315.898816) (xy 185.89423 -315.849762) (xy 184.605168 -315.849762)
			(xy 184.604673 -315.874369) (xy 184.596778 -315.922946) (xy 184.581194 -315.969627) (xy 184.558323 -316.013204)
			(xy 184.528758 -316.052548) (xy 184.493265 -316.08664) (xy 184.452762 -316.114596) (xy 184.4083 -316.135694)
			(xy 184.361029 -316.149386) (xy 184.312174 -316.155318) (xy 184.262999 -316.153337) (xy 184.21478 -316.143493)
			(xy 184.168764 -316.126041) (xy 184.126143 -316.101434) (xy 184.088022 -316.070309) (xy 184.055387 -316.033472)
			(xy 184.029084 -315.991876) (xy 184.009793 -315.9466) (xy 183.998016 -315.898816) (xy 183.994056 -315.849762)
			(xy 182.705248 -315.849762) (xy 182.704753 -315.874369) (xy 182.696858 -315.922946) (xy 182.681274 -315.969627)
			(xy 182.658403 -316.013204) (xy 182.628838 -316.052548) (xy 182.593345 -316.08664) (xy 182.552842 -316.114596)
			(xy 182.50838 -316.135694) (xy 182.461109 -316.149386) (xy 182.412254 -316.155318) (xy 182.363079 -316.153337)
			(xy 182.31486 -316.143493) (xy 182.268844 -316.126041) (xy 182.226223 -316.101434) (xy 182.188102 -316.070309)
			(xy 182.155467 -316.033472) (xy 182.129164 -315.991876) (xy 182.109873 -315.9466) (xy 182.098096 -315.898816)
			(xy 182.094136 -315.849762) (xy 165.605206 -315.849762) (xy 165.604711 -315.874369) (xy 165.596816 -315.922946)
			(xy 165.581232 -315.969627) (xy 165.558361 -316.013204) (xy 165.528796 -316.052548) (xy 165.493303 -316.08664)
			(xy 165.4528 -316.114596) (xy 165.408338 -316.135694) (xy 165.361067 -316.149386) (xy 165.312212 -316.155318)
			(xy 165.263037 -316.153337) (xy 165.214818 -316.143493) (xy 165.168802 -316.126041) (xy 165.126181 -316.101434)
			(xy 165.08806 -316.070309) (xy 165.055425 -316.033472) (xy 165.029122 -315.991876) (xy 165.009831 -315.9466)
			(xy 164.998054 -315.898816) (xy 164.994094 -315.849762) (xy 163.705286 -315.849762) (xy 163.704791 -315.874369)
			(xy 163.696896 -315.922946) (xy 163.681312 -315.969627) (xy 163.658441 -316.013204) (xy 163.628876 -316.052548)
			(xy 163.593383 -316.08664) (xy 163.55288 -316.114596) (xy 163.508418 -316.135694) (xy 163.461147 -316.149386)
			(xy 163.412292 -316.155318) (xy 163.363117 -316.153337) (xy 163.314898 -316.143493) (xy 163.268882 -316.126041)
			(xy 163.226261 -316.101434) (xy 163.18814 -316.070309) (xy 163.155505 -316.033472) (xy 163.129202 -315.991876)
			(xy 163.109911 -315.9466) (xy 163.098134 -315.898816) (xy 163.094174 -315.849762) (xy 161.805366 -315.849762)
			(xy 161.804871 -315.874369) (xy 161.796976 -315.922946) (xy 161.781392 -315.969627) (xy 161.758521 -316.013204)
			(xy 161.728956 -316.052548) (xy 161.693463 -316.08664) (xy 161.65296 -316.114596) (xy 161.608498 -316.135694)
			(xy 161.561227 -316.149386) (xy 161.512372 -316.155318) (xy 161.463197 -316.153337) (xy 161.414978 -316.143493)
			(xy 161.368962 -316.126041) (xy 161.326341 -316.101434) (xy 161.28822 -316.070309) (xy 161.255585 -316.033472)
			(xy 161.229282 -315.991876) (xy 161.209991 -315.9466) (xy 161.198214 -315.898816) (xy 161.194254 -315.849762)
			(xy 159.905192 -315.849762) (xy 159.904697 -315.874369) (xy 159.896802 -315.922946) (xy 159.881218 -315.969627)
			(xy 159.858347 -316.013204) (xy 159.828782 -316.052548) (xy 159.793289 -316.08664) (xy 159.752786 -316.114596)
			(xy 159.708324 -316.135694) (xy 159.661053 -316.149386) (xy 159.612198 -316.155318) (xy 159.563023 -316.153337)
			(xy 159.514804 -316.143493) (xy 159.468788 -316.126041) (xy 159.426167 -316.101434) (xy 159.388046 -316.070309)
			(xy 159.355411 -316.033472) (xy 159.329108 -315.991876) (xy 159.309817 -315.9466) (xy 159.29804 -315.898816)
			(xy 159.29408 -315.849762) (xy 79.905098 -315.849762) (xy 79.904603 -315.874369) (xy 79.896708 -315.922946)
			(xy 79.881124 -315.969627) (xy 79.858253 -316.013204) (xy 79.828688 -316.052548) (xy 79.793195 -316.08664)
			(xy 79.752692 -316.114596) (xy 79.70823 -316.135694) (xy 79.660959 -316.149386) (xy 79.612104 -316.155318)
			(xy 79.562929 -316.153337) (xy 79.51471 -316.143493) (xy 79.468694 -316.126041) (xy 79.426073 -316.101434)
			(xy 79.387952 -316.070309) (xy 79.355317 -316.033472) (xy 79.329014 -315.991876) (xy 79.309723 -315.9466)
			(xy 79.297946 -315.898816) (xy 79.293986 -315.849762) (xy 78.005178 -315.849762) (xy 78.004683 -315.874369)
			(xy 77.996788 -315.922946) (xy 77.981204 -315.969627) (xy 77.958333 -316.013204) (xy 77.928768 -316.052548)
			(xy 77.893275 -316.08664) (xy 77.852772 -316.114596) (xy 77.80831 -316.135694) (xy 77.761039 -316.149386)
			(xy 77.712184 -316.155318) (xy 77.663009 -316.153337) (xy 77.61479 -316.143493) (xy 77.568774 -316.126041)
			(xy 77.526153 -316.101434) (xy 77.488032 -316.070309) (xy 77.455397 -316.033472) (xy 77.429094 -315.991876)
			(xy 77.409803 -315.9466) (xy 77.398026 -315.898816) (xy 77.394066 -315.849762) (xy 76.105258 -315.849762)
			(xy 76.104763 -315.874369) (xy 76.096868 -315.922946) (xy 76.081284 -315.969627) (xy 76.058413 -316.013204)
			(xy 76.028848 -316.052548) (xy 75.993355 -316.08664) (xy 75.952852 -316.114596) (xy 75.90839 -316.135694)
			(xy 75.861119 -316.149386) (xy 75.812264 -316.155318) (xy 75.763089 -316.153337) (xy 75.71487 -316.143493)
			(xy 75.668854 -316.126041) (xy 75.626233 -316.101434) (xy 75.588112 -316.070309) (xy 75.555477 -316.033472)
			(xy 75.529174 -315.991876) (xy 75.509883 -315.9466) (xy 75.498106 -315.898816) (xy 75.494146 -315.849762)
			(xy 74.205084 -315.849762) (xy 74.204589 -315.874369) (xy 74.196694 -315.922946) (xy 74.18111 -315.969627)
			(xy 74.158239 -316.013204) (xy 74.128674 -316.052548) (xy 74.093181 -316.08664) (xy 74.052678 -316.114596)
			(xy 74.008216 -316.135694) (xy 73.960945 -316.149386) (xy 73.91209 -316.155318) (xy 73.862915 -316.153337)
			(xy 73.814696 -316.143493) (xy 73.76868 -316.126041) (xy 73.726059 -316.101434) (xy 73.687938 -316.070309)
			(xy 73.655303 -316.033472) (xy 73.629 -315.991876) (xy 73.609709 -315.9466) (xy 73.597932 -315.898816)
			(xy 73.593972 -315.849762) (xy 0.508 -315.849762) (xy 0.508 -316.799722) (xy 73.593972 -316.799722)
			(xy 73.597932 -316.750668) (xy 73.609709 -316.702884) (xy 73.629 -316.657608) (xy 73.655303 -316.616012)
			(xy 73.687938 -316.579175) (xy 73.726059 -316.54805) (xy 73.76868 -316.523443) (xy 73.814696 -316.505991)
			(xy 73.862915 -316.496147) (xy 73.91209 -316.494166) (xy 73.960945 -316.500098) (xy 74.008216 -316.51379)
			(xy 74.052678 -316.534888) (xy 74.093181 -316.562844) (xy 74.128674 -316.596936) (xy 74.158239 -316.63628)
			(xy 74.18111 -316.679857) (xy 74.196694 -316.726538) (xy 74.204589 -316.775115) (xy 74.205084 -316.799722)
			(xy 75.494146 -316.799722) (xy 75.498106 -316.750668) (xy 75.509883 -316.702884) (xy 75.529174 -316.657608)
			(xy 75.555477 -316.616012) (xy 75.588112 -316.579175) (xy 75.626233 -316.54805) (xy 75.668854 -316.523443)
			(xy 75.71487 -316.505991) (xy 75.763089 -316.496147) (xy 75.812264 -316.494166) (xy 75.861119 -316.500098)
			(xy 75.90839 -316.51379) (xy 75.952852 -316.534888) (xy 75.993355 -316.562844) (xy 76.028848 -316.596936)
			(xy 76.058413 -316.63628) (xy 76.081284 -316.679857) (xy 76.096868 -316.726538) (xy 76.104763 -316.775115)
			(xy 76.105258 -316.799722) (xy 77.394066 -316.799722) (xy 77.398026 -316.750668) (xy 77.409803 -316.702884)
			(xy 77.429094 -316.657608) (xy 77.455397 -316.616012) (xy 77.488032 -316.579175) (xy 77.526153 -316.54805)
			(xy 77.568774 -316.523443) (xy 77.61479 -316.505991) (xy 77.663009 -316.496147) (xy 77.712184 -316.494166)
			(xy 77.761039 -316.500098) (xy 77.80831 -316.51379) (xy 77.852772 -316.534888) (xy 77.893275 -316.562844)
			(xy 77.928768 -316.596936) (xy 77.958333 -316.63628) (xy 77.981204 -316.679857) (xy 77.996788 -316.726538)
			(xy 78.004683 -316.775115) (xy 78.005178 -316.799722) (xy 79.293986 -316.799722) (xy 79.297946 -316.750668)
			(xy 79.309723 -316.702884) (xy 79.329014 -316.657608) (xy 79.355317 -316.616012) (xy 79.387952 -316.579175)
			(xy 79.426073 -316.54805) (xy 79.468694 -316.523443) (xy 79.51471 -316.505991) (xy 79.562929 -316.496147)
			(xy 79.612104 -316.494166) (xy 79.660959 -316.500098) (xy 79.70823 -316.51379) (xy 79.752692 -316.534888)
			(xy 79.793195 -316.562844) (xy 79.828688 -316.596936) (xy 79.858253 -316.63628) (xy 79.881124 -316.679857)
			(xy 79.896708 -316.726538) (xy 79.904603 -316.775115) (xy 79.905098 -316.799722) (xy 81.19416 -316.799722)
			(xy 81.19812 -316.750668) (xy 81.209897 -316.702884) (xy 81.229188 -316.657608) (xy 81.255491 -316.616012)
			(xy 81.288126 -316.579175) (xy 81.326247 -316.54805) (xy 81.368868 -316.523443) (xy 81.414884 -316.505991)
			(xy 81.463103 -316.496147) (xy 81.512278 -316.494166) (xy 81.561133 -316.500098) (xy 81.608404 -316.51379)
			(xy 81.652866 -316.534888) (xy 81.693369 -316.562844) (xy 81.728862 -316.596936) (xy 81.758427 -316.63628)
			(xy 81.781298 -316.679857) (xy 81.796882 -316.726538) (xy 81.804777 -316.775115) (xy 81.805272 -316.799722)
			(xy 82.14412 -316.799722) (xy 82.14808 -316.750668) (xy 82.159857 -316.702884) (xy 82.179148 -316.657608)
			(xy 82.205451 -316.616012) (xy 82.238086 -316.579175) (xy 82.276207 -316.54805) (xy 82.318828 -316.523443)
			(xy 82.364844 -316.505991) (xy 82.413063 -316.496147) (xy 82.462238 -316.494166) (xy 82.511093 -316.500098)
			(xy 82.558364 -316.51379) (xy 82.602826 -316.534888) (xy 82.643329 -316.562844) (xy 82.678822 -316.596936)
			(xy 82.708387 -316.63628) (xy 82.731258 -316.679857) (xy 82.746842 -316.726538) (xy 82.754737 -316.775115)
			(xy 82.755232 -316.799722) (xy 159.29408 -316.799722) (xy 159.29804 -316.750668) (xy 159.309817 -316.702884)
			(xy 159.329108 -316.657608) (xy 159.355411 -316.616012) (xy 159.388046 -316.579175) (xy 159.426167 -316.54805)
			(xy 159.468788 -316.523443) (xy 159.514804 -316.505991) (xy 159.563023 -316.496147) (xy 159.612198 -316.494166)
			(xy 159.661053 -316.500098) (xy 159.708324 -316.51379) (xy 159.752786 -316.534888) (xy 159.793289 -316.562844)
			(xy 159.828782 -316.596936) (xy 159.858347 -316.63628) (xy 159.881218 -316.679857) (xy 159.896802 -316.726538)
			(xy 159.904697 -316.775115) (xy 159.905192 -316.799722) (xy 161.194254 -316.799722) (xy 161.198214 -316.750668)
			(xy 161.209991 -316.702884) (xy 161.229282 -316.657608) (xy 161.255585 -316.616012) (xy 161.28822 -316.579175)
			(xy 161.326341 -316.54805) (xy 161.368962 -316.523443) (xy 161.414978 -316.505991) (xy 161.463197 -316.496147)
			(xy 161.512372 -316.494166) (xy 161.561227 -316.500098) (xy 161.608498 -316.51379) (xy 161.65296 -316.534888)
			(xy 161.693463 -316.562844) (xy 161.728956 -316.596936) (xy 161.758521 -316.63628) (xy 161.781392 -316.679857)
			(xy 161.796976 -316.726538) (xy 161.804871 -316.775115) (xy 161.805366 -316.799722) (xy 163.094174 -316.799722)
			(xy 163.098134 -316.750668) (xy 163.109911 -316.702884) (xy 163.129202 -316.657608) (xy 163.155505 -316.616012)
			(xy 163.18814 -316.579175) (xy 163.226261 -316.54805) (xy 163.268882 -316.523443) (xy 163.314898 -316.505991)
			(xy 163.363117 -316.496147) (xy 163.412292 -316.494166) (xy 163.461147 -316.500098) (xy 163.508418 -316.51379)
			(xy 163.55288 -316.534888) (xy 163.593383 -316.562844) (xy 163.628876 -316.596936) (xy 163.658441 -316.63628)
			(xy 163.681312 -316.679857) (xy 163.696896 -316.726538) (xy 163.704791 -316.775115) (xy 163.705286 -316.799722)
			(xy 164.994094 -316.799722) (xy 164.998054 -316.750668) (xy 165.009831 -316.702884) (xy 165.029122 -316.657608)
			(xy 165.055425 -316.616012) (xy 165.08806 -316.579175) (xy 165.126181 -316.54805) (xy 165.168802 -316.523443)
			(xy 165.214818 -316.505991) (xy 165.263037 -316.496147) (xy 165.312212 -316.494166) (xy 165.361067 -316.500098)
			(xy 165.408338 -316.51379) (xy 165.4528 -316.534888) (xy 165.493303 -316.562844) (xy 165.528796 -316.596936)
			(xy 165.558361 -316.63628) (xy 165.581232 -316.679857) (xy 165.596816 -316.726538) (xy 165.604711 -316.775115)
			(xy 165.605206 -316.799722) (xy 182.094136 -316.799722) (xy 182.098096 -316.750668) (xy 182.109873 -316.702884)
			(xy 182.129164 -316.657608) (xy 182.155467 -316.616012) (xy 182.188102 -316.579175) (xy 182.226223 -316.54805)
			(xy 182.268844 -316.523443) (xy 182.31486 -316.505991) (xy 182.363079 -316.496147) (xy 182.412254 -316.494166)
			(xy 182.461109 -316.500098) (xy 182.50838 -316.51379) (xy 182.552842 -316.534888) (xy 182.593345 -316.562844)
			(xy 182.628838 -316.596936) (xy 182.658403 -316.63628) (xy 182.681274 -316.679857) (xy 182.696858 -316.726538)
			(xy 182.704753 -316.775115) (xy 182.705248 -316.799722) (xy 183.994056 -316.799722) (xy 183.998016 -316.750668)
			(xy 184.009793 -316.702884) (xy 184.029084 -316.657608) (xy 184.055387 -316.616012) (xy 184.088022 -316.579175)
			(xy 184.126143 -316.54805) (xy 184.168764 -316.523443) (xy 184.21478 -316.505991) (xy 184.262999 -316.496147)
			(xy 184.312174 -316.494166) (xy 184.361029 -316.500098) (xy 184.4083 -316.51379) (xy 184.452762 -316.534888)
			(xy 184.493265 -316.562844) (xy 184.528758 -316.596936) (xy 184.558323 -316.63628) (xy 184.581194 -316.679857)
			(xy 184.596778 -316.726538) (xy 184.604673 -316.775115) (xy 184.605168 -316.799722) (xy 185.89423 -316.799722)
			(xy 185.89819 -316.750668) (xy 185.909967 -316.702884) (xy 185.929258 -316.657608) (xy 185.955561 -316.616012)
			(xy 185.988196 -316.579175) (xy 186.026317 -316.54805) (xy 186.068938 -316.523443) (xy 186.114954 -316.505991)
			(xy 186.163173 -316.496147) (xy 186.212348 -316.494166) (xy 186.261203 -316.500098) (xy 186.308474 -316.51379)
			(xy 186.352936 -316.534888) (xy 186.393439 -316.562844) (xy 186.428932 -316.596936) (xy 186.458497 -316.63628)
			(xy 186.481368 -316.679857) (xy 186.496952 -316.726538) (xy 186.504847 -316.775115) (xy 186.505342 -316.799722)
			(xy 187.79415 -316.799722) (xy 187.79811 -316.750668) (xy 187.809887 -316.702884) (xy 187.829178 -316.657608)
			(xy 187.855481 -316.616012) (xy 187.888116 -316.579175) (xy 187.926237 -316.54805) (xy 187.968858 -316.523443)
			(xy 188.014874 -316.505991) (xy 188.063093 -316.496147) (xy 188.112268 -316.494166) (xy 188.161123 -316.500098)
			(xy 188.208394 -316.51379) (xy 188.252856 -316.534888) (xy 188.293359 -316.562844) (xy 188.328852 -316.596936)
			(xy 188.358417 -316.63628) (xy 188.381288 -316.679857) (xy 188.396872 -316.726538) (xy 188.404767 -316.775115)
			(xy 188.405262 -316.799722) (xy 305.793914 -316.799722) (xy 305.797874 -316.750668) (xy 305.809651 -316.702884)
			(xy 305.828942 -316.657608) (xy 305.855245 -316.616012) (xy 305.88788 -316.579175) (xy 305.926001 -316.54805)
			(xy 305.968622 -316.523443) (xy 306.014638 -316.505991) (xy 306.062857 -316.496147) (xy 306.112032 -316.494166)
			(xy 306.160887 -316.500098) (xy 306.208158 -316.51379) (xy 306.25262 -316.534888) (xy 306.293123 -316.562844)
			(xy 306.328616 -316.596936) (xy 306.358181 -316.63628) (xy 306.381052 -316.679857) (xy 306.396636 -316.726538)
			(xy 306.404531 -316.775115) (xy 306.405026 -316.799722) (xy 307.694088 -316.799722) (xy 307.698048 -316.750668)
			(xy 307.709825 -316.702884) (xy 307.729116 -316.657608) (xy 307.755419 -316.616012) (xy 307.788054 -316.579175)
			(xy 307.826175 -316.54805) (xy 307.868796 -316.523443) (xy 307.914812 -316.505991) (xy 307.963031 -316.496147)
			(xy 308.012206 -316.494166) (xy 308.061061 -316.500098) (xy 308.108332 -316.51379) (xy 308.152794 -316.534888)
			(xy 308.193297 -316.562844) (xy 308.22879 -316.596936) (xy 308.258355 -316.63628) (xy 308.281226 -316.679857)
			(xy 308.29681 -316.726538) (xy 308.304705 -316.775115) (xy 308.3052 -316.799722) (xy 309.594008 -316.799722)
			(xy 309.597968 -316.750668) (xy 309.609745 -316.702884) (xy 309.629036 -316.657608) (xy 309.655339 -316.616012)
			(xy 309.687974 -316.579175) (xy 309.726095 -316.54805) (xy 309.768716 -316.523443) (xy 309.814732 -316.505991)
			(xy 309.862951 -316.496147) (xy 309.912126 -316.494166) (xy 309.960981 -316.500098) (xy 310.008252 -316.51379)
			(xy 310.052714 -316.534888) (xy 310.093217 -316.562844) (xy 310.12871 -316.596936) (xy 310.158275 -316.63628)
			(xy 310.181146 -316.679857) (xy 310.19673 -316.726538) (xy 310.204625 -316.775115) (xy 310.20512 -316.799722)
			(xy 311.493928 -316.799722) (xy 311.497888 -316.750668) (xy 311.509665 -316.702884) (xy 311.528956 -316.657608)
			(xy 311.555259 -316.616012) (xy 311.587894 -316.579175) (xy 311.626015 -316.54805) (xy 311.668636 -316.523443)
			(xy 311.714652 -316.505991) (xy 311.762871 -316.496147) (xy 311.812046 -316.494166) (xy 311.860901 -316.500098)
			(xy 311.908172 -316.51379) (xy 311.952634 -316.534888) (xy 311.993137 -316.562844) (xy 312.02863 -316.596936)
			(xy 312.058195 -316.63628) (xy 312.081066 -316.679857) (xy 312.09665 -316.726538) (xy 312.104545 -316.775115)
			(xy 312.10504 -316.799722) (xy 313.394102 -316.799722) (xy 313.398062 -316.750668) (xy 313.409839 -316.702884)
			(xy 313.42913 -316.657608) (xy 313.455433 -316.616012) (xy 313.488068 -316.579175) (xy 313.526189 -316.54805)
			(xy 313.56881 -316.523443) (xy 313.614826 -316.505991) (xy 313.663045 -316.496147) (xy 313.71222 -316.494166)
			(xy 313.761075 -316.500098) (xy 313.808346 -316.51379) (xy 313.852808 -316.534888) (xy 313.893311 -316.562844)
			(xy 313.928804 -316.596936) (xy 313.958369 -316.63628) (xy 313.98124 -316.679857) (xy 313.996824 -316.726538)
			(xy 314.004719 -316.775115) (xy 314.005214 -316.799722) (xy 314.344062 -316.799722) (xy 314.348022 -316.750668)
			(xy 314.359799 -316.702884) (xy 314.37909 -316.657608) (xy 314.405393 -316.616012) (xy 314.438028 -316.579175)
			(xy 314.476149 -316.54805) (xy 314.51877 -316.523443) (xy 314.564786 -316.505991) (xy 314.613005 -316.496147)
			(xy 314.66218 -316.494166) (xy 314.711035 -316.500098) (xy 314.758306 -316.51379) (xy 314.802768 -316.534888)
			(xy 314.843271 -316.562844) (xy 314.878764 -316.596936) (xy 314.908329 -316.63628) (xy 314.9312 -316.679857)
			(xy 314.946784 -316.726538) (xy 314.954679 -316.775115) (xy 314.955174 -316.799722) (xy 391.494022 -316.799722)
			(xy 391.497982 -316.750668) (xy 391.509759 -316.702884) (xy 391.52905 -316.657608) (xy 391.555353 -316.616012)
			(xy 391.587988 -316.579175) (xy 391.626109 -316.54805) (xy 391.66873 -316.523443) (xy 391.714746 -316.505991)
			(xy 391.762965 -316.496147) (xy 391.81214 -316.494166) (xy 391.860995 -316.500098) (xy 391.908266 -316.51379)
			(xy 391.952728 -316.534888) (xy 391.993231 -316.562844) (xy 392.028724 -316.596936) (xy 392.058289 -316.63628)
			(xy 392.08116 -316.679857) (xy 392.096744 -316.726538) (xy 392.104639 -316.775115) (xy 392.105134 -316.799722)
			(xy 393.394196 -316.799722) (xy 393.398156 -316.750668) (xy 393.409933 -316.702884) (xy 393.429224 -316.657608)
			(xy 393.455527 -316.616012) (xy 393.488162 -316.579175) (xy 393.526283 -316.54805) (xy 393.568904 -316.523443)
			(xy 393.61492 -316.505991) (xy 393.663139 -316.496147) (xy 393.712314 -316.494166) (xy 393.761169 -316.500098)
			(xy 393.80844 -316.51379) (xy 393.852902 -316.534888) (xy 393.893405 -316.562844) (xy 393.928898 -316.596936)
			(xy 393.958463 -316.63628) (xy 393.981334 -316.679857) (xy 393.996918 -316.726538) (xy 394.004813 -316.775115)
			(xy 394.005308 -316.799722) (xy 395.294116 -316.799722) (xy 395.298076 -316.750668) (xy 395.309853 -316.702884)
			(xy 395.329144 -316.657608) (xy 395.355447 -316.616012) (xy 395.388082 -316.579175) (xy 395.426203 -316.54805)
			(xy 395.468824 -316.523443) (xy 395.51484 -316.505991) (xy 395.563059 -316.496147) (xy 395.612234 -316.494166)
			(xy 395.661089 -316.500098) (xy 395.70836 -316.51379) (xy 395.752822 -316.534888) (xy 395.793325 -316.562844)
			(xy 395.828818 -316.596936) (xy 395.858383 -316.63628) (xy 395.881254 -316.679857) (xy 395.896838 -316.726538)
			(xy 395.904733 -316.775115) (xy 395.905228 -316.799722) (xy 397.194036 -316.799722) (xy 397.197996 -316.750668)
			(xy 397.209773 -316.702884) (xy 397.229064 -316.657608) (xy 397.255367 -316.616012) (xy 397.288002 -316.579175)
			(xy 397.326123 -316.54805) (xy 397.368744 -316.523443) (xy 397.41476 -316.505991) (xy 397.462979 -316.496147)
			(xy 397.512154 -316.494166) (xy 397.561009 -316.500098) (xy 397.60828 -316.51379) (xy 397.652742 -316.534888)
			(xy 397.693245 -316.562844) (xy 397.728738 -316.596936) (xy 397.758303 -316.63628) (xy 397.781174 -316.679857)
			(xy 397.796758 -316.726538) (xy 397.804653 -316.775115) (xy 397.805148 -316.799722) (xy 414.294078 -316.799722)
			(xy 414.298038 -316.750668) (xy 414.309815 -316.702884) (xy 414.329106 -316.657608) (xy 414.355409 -316.616012)
			(xy 414.388044 -316.579175) (xy 414.426165 -316.54805) (xy 414.468786 -316.523443) (xy 414.514802 -316.505991)
			(xy 414.563021 -316.496147) (xy 414.612196 -316.494166) (xy 414.661051 -316.500098) (xy 414.708322 -316.51379)
			(xy 414.752784 -316.534888) (xy 414.793287 -316.562844) (xy 414.82878 -316.596936) (xy 414.858345 -316.63628)
			(xy 414.881216 -316.679857) (xy 414.8968 -316.726538) (xy 414.904695 -316.775115) (xy 414.90519 -316.799722)
			(xy 416.193998 -316.799722) (xy 416.197958 -316.750668) (xy 416.209735 -316.702884) (xy 416.229026 -316.657608)
			(xy 416.255329 -316.616012) (xy 416.287964 -316.579175) (xy 416.326085 -316.54805) (xy 416.368706 -316.523443)
			(xy 416.414722 -316.505991) (xy 416.462941 -316.496147) (xy 416.512116 -316.494166) (xy 416.560971 -316.500098)
			(xy 416.608242 -316.51379) (xy 416.652704 -316.534888) (xy 416.693207 -316.562844) (xy 416.7287 -316.596936)
			(xy 416.758265 -316.63628) (xy 416.781136 -316.679857) (xy 416.79672 -316.726538) (xy 416.804615 -316.775115)
			(xy 416.80511 -316.799722) (xy 418.094172 -316.799722) (xy 418.098132 -316.750668) (xy 418.109909 -316.702884)
			(xy 418.1292 -316.657608) (xy 418.155503 -316.616012) (xy 418.188138 -316.579175) (xy 418.226259 -316.54805)
			(xy 418.26888 -316.523443) (xy 418.314896 -316.505991) (xy 418.363115 -316.496147) (xy 418.41229 -316.494166)
			(xy 418.461145 -316.500098) (xy 418.508416 -316.51379) (xy 418.552878 -316.534888) (xy 418.593381 -316.562844)
			(xy 418.628874 -316.596936) (xy 418.658439 -316.63628) (xy 418.68131 -316.679857) (xy 418.696894 -316.726538)
			(xy 418.704789 -316.775115) (xy 418.705284 -316.799722) (xy 419.994092 -316.799722) (xy 419.998052 -316.750668)
			(xy 420.009829 -316.702884) (xy 420.02912 -316.657608) (xy 420.055423 -316.616012) (xy 420.088058 -316.579175)
			(xy 420.126179 -316.54805) (xy 420.1688 -316.523443) (xy 420.214816 -316.505991) (xy 420.263035 -316.496147)
			(xy 420.31221 -316.494166) (xy 420.361065 -316.500098) (xy 420.408336 -316.51379) (xy 420.452798 -316.534888)
			(xy 420.493301 -316.562844) (xy 420.528794 -316.596936) (xy 420.558359 -316.63628) (xy 420.58123 -316.679857)
			(xy 420.596814 -316.726538) (xy 420.604709 -316.775115) (xy 420.605204 -316.799722) (xy 420.604709 -316.824329)
			(xy 420.596814 -316.872906) (xy 420.58123 -316.919587) (xy 420.558359 -316.963164) (xy 420.528794 -317.002508)
			(xy 420.493301 -317.0366) (xy 420.452798 -317.064556) (xy 420.408336 -317.085654) (xy 420.361065 -317.099346)
			(xy 420.31221 -317.105278) (xy 420.263035 -317.103297) (xy 420.214816 -317.093453) (xy 420.1688 -317.076001)
			(xy 420.126179 -317.051394) (xy 420.088058 -317.020269) (xy 420.055423 -316.983432) (xy 420.02912 -316.941836)
			(xy 420.009829 -316.89656) (xy 419.998052 -316.848776) (xy 419.994092 -316.799722) (xy 418.705284 -316.799722)
			(xy 418.704789 -316.824329) (xy 418.696894 -316.872906) (xy 418.68131 -316.919587) (xy 418.658439 -316.963164)
			(xy 418.628874 -317.002508) (xy 418.593381 -317.0366) (xy 418.552878 -317.064556) (xy 418.508416 -317.085654)
			(xy 418.461145 -317.099346) (xy 418.41229 -317.105278) (xy 418.363115 -317.103297) (xy 418.314896 -317.093453)
			(xy 418.26888 -317.076001) (xy 418.226259 -317.051394) (xy 418.188138 -317.020269) (xy 418.155503 -316.983432)
			(xy 418.1292 -316.941836) (xy 418.109909 -316.89656) (xy 418.098132 -316.848776) (xy 418.094172 -316.799722)
			(xy 416.80511 -316.799722) (xy 416.804615 -316.824329) (xy 416.79672 -316.872906) (xy 416.781136 -316.919587)
			(xy 416.758265 -316.963164) (xy 416.7287 -317.002508) (xy 416.693207 -317.0366) (xy 416.652704 -317.064556)
			(xy 416.608242 -317.085654) (xy 416.560971 -317.099346) (xy 416.512116 -317.105278) (xy 416.462941 -317.103297)
			(xy 416.414722 -317.093453) (xy 416.368706 -317.076001) (xy 416.326085 -317.051394) (xy 416.287964 -317.020269)
			(xy 416.255329 -316.983432) (xy 416.229026 -316.941836) (xy 416.209735 -316.89656) (xy 416.197958 -316.848776)
			(xy 416.193998 -316.799722) (xy 414.90519 -316.799722) (xy 414.904695 -316.824329) (xy 414.8968 -316.872906)
			(xy 414.881216 -316.919587) (xy 414.858345 -316.963164) (xy 414.82878 -317.002508) (xy 414.793287 -317.0366)
			(xy 414.752784 -317.064556) (xy 414.708322 -317.085654) (xy 414.661051 -317.099346) (xy 414.612196 -317.105278)
			(xy 414.563021 -317.103297) (xy 414.514802 -317.093453) (xy 414.468786 -317.076001) (xy 414.426165 -317.051394)
			(xy 414.388044 -317.020269) (xy 414.355409 -316.983432) (xy 414.329106 -316.941836) (xy 414.309815 -316.89656)
			(xy 414.298038 -316.848776) (xy 414.294078 -316.799722) (xy 397.805148 -316.799722) (xy 397.804653 -316.824329)
			(xy 397.796758 -316.872906) (xy 397.781174 -316.919587) (xy 397.758303 -316.963164) (xy 397.728738 -317.002508)
			(xy 397.693245 -317.0366) (xy 397.652742 -317.064556) (xy 397.60828 -317.085654) (xy 397.561009 -317.099346)
			(xy 397.512154 -317.105278) (xy 397.462979 -317.103297) (xy 397.41476 -317.093453) (xy 397.368744 -317.076001)
			(xy 397.326123 -317.051394) (xy 397.288002 -317.020269) (xy 397.255367 -316.983432) (xy 397.229064 -316.941836)
			(xy 397.209773 -316.89656) (xy 397.197996 -316.848776) (xy 397.194036 -316.799722) (xy 395.905228 -316.799722)
			(xy 395.904733 -316.824329) (xy 395.896838 -316.872906) (xy 395.881254 -316.919587) (xy 395.858383 -316.963164)
			(xy 395.828818 -317.002508) (xy 395.793325 -317.0366) (xy 395.752822 -317.064556) (xy 395.70836 -317.085654)
			(xy 395.661089 -317.099346) (xy 395.612234 -317.105278) (xy 395.563059 -317.103297) (xy 395.51484 -317.093453)
			(xy 395.468824 -317.076001) (xy 395.426203 -317.051394) (xy 395.388082 -317.020269) (xy 395.355447 -316.983432)
			(xy 395.329144 -316.941836) (xy 395.309853 -316.89656) (xy 395.298076 -316.848776) (xy 395.294116 -316.799722)
			(xy 394.005308 -316.799722) (xy 394.004813 -316.824329) (xy 393.996918 -316.872906) (xy 393.981334 -316.919587)
			(xy 393.958463 -316.963164) (xy 393.928898 -317.002508) (xy 393.893405 -317.0366) (xy 393.852902 -317.064556)
			(xy 393.80844 -317.085654) (xy 393.761169 -317.099346) (xy 393.712314 -317.105278) (xy 393.663139 -317.103297)
			(xy 393.61492 -317.093453) (xy 393.568904 -317.076001) (xy 393.526283 -317.051394) (xy 393.488162 -317.020269)
			(xy 393.455527 -316.983432) (xy 393.429224 -316.941836) (xy 393.409933 -316.89656) (xy 393.398156 -316.848776)
			(xy 393.394196 -316.799722) (xy 392.105134 -316.799722) (xy 392.104639 -316.824329) (xy 392.096744 -316.872906)
			(xy 392.08116 -316.919587) (xy 392.058289 -316.963164) (xy 392.028724 -317.002508) (xy 391.993231 -317.0366)
			(xy 391.952728 -317.064556) (xy 391.908266 -317.085654) (xy 391.860995 -317.099346) (xy 391.81214 -317.105278)
			(xy 391.762965 -317.103297) (xy 391.714746 -317.093453) (xy 391.66873 -317.076001) (xy 391.626109 -317.051394)
			(xy 391.587988 -317.020269) (xy 391.555353 -316.983432) (xy 391.52905 -316.941836) (xy 391.509759 -316.89656)
			(xy 391.497982 -316.848776) (xy 391.494022 -316.799722) (xy 314.955174 -316.799722) (xy 314.954679 -316.824329)
			(xy 314.946784 -316.872906) (xy 314.9312 -316.919587) (xy 314.908329 -316.963164) (xy 314.878764 -317.002508)
			(xy 314.843271 -317.0366) (xy 314.802768 -317.064556) (xy 314.758306 -317.085654) (xy 314.711035 -317.099346)
			(xy 314.66218 -317.105278) (xy 314.613005 -317.103297) (xy 314.564786 -317.093453) (xy 314.51877 -317.076001)
			(xy 314.476149 -317.051394) (xy 314.438028 -317.020269) (xy 314.405393 -316.983432) (xy 314.37909 -316.941836)
			(xy 314.359799 -316.89656) (xy 314.348022 -316.848776) (xy 314.344062 -316.799722) (xy 314.005214 -316.799722)
			(xy 314.004719 -316.824329) (xy 313.996824 -316.872906) (xy 313.98124 -316.919587) (xy 313.958369 -316.963164)
			(xy 313.928804 -317.002508) (xy 313.893311 -317.0366) (xy 313.852808 -317.064556) (xy 313.808346 -317.085654)
			(xy 313.761075 -317.099346) (xy 313.71222 -317.105278) (xy 313.663045 -317.103297) (xy 313.614826 -317.093453)
			(xy 313.56881 -317.076001) (xy 313.526189 -317.051394) (xy 313.488068 -317.020269) (xy 313.455433 -316.983432)
			(xy 313.42913 -316.941836) (xy 313.409839 -316.89656) (xy 313.398062 -316.848776) (xy 313.394102 -316.799722)
			(xy 312.10504 -316.799722) (xy 312.104545 -316.824329) (xy 312.09665 -316.872906) (xy 312.081066 -316.919587)
			(xy 312.058195 -316.963164) (xy 312.02863 -317.002508) (xy 311.993137 -317.0366) (xy 311.952634 -317.064556)
			(xy 311.908172 -317.085654) (xy 311.860901 -317.099346) (xy 311.812046 -317.105278) (xy 311.762871 -317.103297)
			(xy 311.714652 -317.093453) (xy 311.668636 -317.076001) (xy 311.626015 -317.051394) (xy 311.587894 -317.020269)
			(xy 311.555259 -316.983432) (xy 311.528956 -316.941836) (xy 311.509665 -316.89656) (xy 311.497888 -316.848776)
			(xy 311.493928 -316.799722) (xy 310.20512 -316.799722) (xy 310.204625 -316.824329) (xy 310.19673 -316.872906)
			(xy 310.181146 -316.919587) (xy 310.158275 -316.963164) (xy 310.12871 -317.002508) (xy 310.093217 -317.0366)
			(xy 310.052714 -317.064556) (xy 310.008252 -317.085654) (xy 309.960981 -317.099346) (xy 309.912126 -317.105278)
			(xy 309.862951 -317.103297) (xy 309.814732 -317.093453) (xy 309.768716 -317.076001) (xy 309.726095 -317.051394)
			(xy 309.687974 -317.020269) (xy 309.655339 -316.983432) (xy 309.629036 -316.941836) (xy 309.609745 -316.89656)
			(xy 309.597968 -316.848776) (xy 309.594008 -316.799722) (xy 308.3052 -316.799722) (xy 308.304705 -316.824329)
			(xy 308.29681 -316.872906) (xy 308.281226 -316.919587) (xy 308.258355 -316.963164) (xy 308.22879 -317.002508)
			(xy 308.193297 -317.0366) (xy 308.152794 -317.064556) (xy 308.108332 -317.085654) (xy 308.061061 -317.099346)
			(xy 308.012206 -317.105278) (xy 307.963031 -317.103297) (xy 307.914812 -317.093453) (xy 307.868796 -317.076001)
			(xy 307.826175 -317.051394) (xy 307.788054 -317.020269) (xy 307.755419 -316.983432) (xy 307.729116 -316.941836)
			(xy 307.709825 -316.89656) (xy 307.698048 -316.848776) (xy 307.694088 -316.799722) (xy 306.405026 -316.799722)
			(xy 306.404531 -316.824329) (xy 306.396636 -316.872906) (xy 306.381052 -316.919587) (xy 306.358181 -316.963164)
			(xy 306.328616 -317.002508) (xy 306.293123 -317.0366) (xy 306.25262 -317.064556) (xy 306.208158 -317.085654)
			(xy 306.160887 -317.099346) (xy 306.112032 -317.105278) (xy 306.062857 -317.103297) (xy 306.014638 -317.093453)
			(xy 305.968622 -317.076001) (xy 305.926001 -317.051394) (xy 305.88788 -317.020269) (xy 305.855245 -316.983432)
			(xy 305.828942 -316.941836) (xy 305.809651 -316.89656) (xy 305.797874 -316.848776) (xy 305.793914 -316.799722)
			(xy 188.405262 -316.799722) (xy 188.404767 -316.824329) (xy 188.396872 -316.872906) (xy 188.381288 -316.919587)
			(xy 188.358417 -316.963164) (xy 188.328852 -317.002508) (xy 188.293359 -317.0366) (xy 188.252856 -317.064556)
			(xy 188.208394 -317.085654) (xy 188.161123 -317.099346) (xy 188.112268 -317.105278) (xy 188.063093 -317.103297)
			(xy 188.014874 -317.093453) (xy 187.968858 -317.076001) (xy 187.926237 -317.051394) (xy 187.888116 -317.020269)
			(xy 187.855481 -316.983432) (xy 187.829178 -316.941836) (xy 187.809887 -316.89656) (xy 187.79811 -316.848776)
			(xy 187.79415 -316.799722) (xy 186.505342 -316.799722) (xy 186.504847 -316.824329) (xy 186.496952 -316.872906)
			(xy 186.481368 -316.919587) (xy 186.458497 -316.963164) (xy 186.428932 -317.002508) (xy 186.393439 -317.0366)
			(xy 186.352936 -317.064556) (xy 186.308474 -317.085654) (xy 186.261203 -317.099346) (xy 186.212348 -317.105278)
			(xy 186.163173 -317.103297) (xy 186.114954 -317.093453) (xy 186.068938 -317.076001) (xy 186.026317 -317.051394)
			(xy 185.988196 -317.020269) (xy 185.955561 -316.983432) (xy 185.929258 -316.941836) (xy 185.909967 -316.89656)
			(xy 185.89819 -316.848776) (xy 185.89423 -316.799722) (xy 184.605168 -316.799722) (xy 184.604673 -316.824329)
			(xy 184.596778 -316.872906) (xy 184.581194 -316.919587) (xy 184.558323 -316.963164) (xy 184.528758 -317.002508)
			(xy 184.493265 -317.0366) (xy 184.452762 -317.064556) (xy 184.4083 -317.085654) (xy 184.361029 -317.099346)
			(xy 184.312174 -317.105278) (xy 184.262999 -317.103297) (xy 184.21478 -317.093453) (xy 184.168764 -317.076001)
			(xy 184.126143 -317.051394) (xy 184.088022 -317.020269) (xy 184.055387 -316.983432) (xy 184.029084 -316.941836)
			(xy 184.009793 -316.89656) (xy 183.998016 -316.848776) (xy 183.994056 -316.799722) (xy 182.705248 -316.799722)
			(xy 182.704753 -316.824329) (xy 182.696858 -316.872906) (xy 182.681274 -316.919587) (xy 182.658403 -316.963164)
			(xy 182.628838 -317.002508) (xy 182.593345 -317.0366) (xy 182.552842 -317.064556) (xy 182.50838 -317.085654)
			(xy 182.461109 -317.099346) (xy 182.412254 -317.105278) (xy 182.363079 -317.103297) (xy 182.31486 -317.093453)
			(xy 182.268844 -317.076001) (xy 182.226223 -317.051394) (xy 182.188102 -317.020269) (xy 182.155467 -316.983432)
			(xy 182.129164 -316.941836) (xy 182.109873 -316.89656) (xy 182.098096 -316.848776) (xy 182.094136 -316.799722)
			(xy 165.605206 -316.799722) (xy 165.604711 -316.824329) (xy 165.596816 -316.872906) (xy 165.581232 -316.919587)
			(xy 165.558361 -316.963164) (xy 165.528796 -317.002508) (xy 165.493303 -317.0366) (xy 165.4528 -317.064556)
			(xy 165.408338 -317.085654) (xy 165.361067 -317.099346) (xy 165.312212 -317.105278) (xy 165.263037 -317.103297)
			(xy 165.214818 -317.093453) (xy 165.168802 -317.076001) (xy 165.126181 -317.051394) (xy 165.08806 -317.020269)
			(xy 165.055425 -316.983432) (xy 165.029122 -316.941836) (xy 165.009831 -316.89656) (xy 164.998054 -316.848776)
			(xy 164.994094 -316.799722) (xy 163.705286 -316.799722) (xy 163.704791 -316.824329) (xy 163.696896 -316.872906)
			(xy 163.681312 -316.919587) (xy 163.658441 -316.963164) (xy 163.628876 -317.002508) (xy 163.593383 -317.0366)
			(xy 163.55288 -317.064556) (xy 163.508418 -317.085654) (xy 163.461147 -317.099346) (xy 163.412292 -317.105278)
			(xy 163.363117 -317.103297) (xy 163.314898 -317.093453) (xy 163.268882 -317.076001) (xy 163.226261 -317.051394)
			(xy 163.18814 -317.020269) (xy 163.155505 -316.983432) (xy 163.129202 -316.941836) (xy 163.109911 -316.89656)
			(xy 163.098134 -316.848776) (xy 163.094174 -316.799722) (xy 161.805366 -316.799722) (xy 161.804871 -316.824329)
			(xy 161.796976 -316.872906) (xy 161.781392 -316.919587) (xy 161.758521 -316.963164) (xy 161.728956 -317.002508)
			(xy 161.693463 -317.0366) (xy 161.65296 -317.064556) (xy 161.608498 -317.085654) (xy 161.561227 -317.099346)
			(xy 161.512372 -317.105278) (xy 161.463197 -317.103297) (xy 161.414978 -317.093453) (xy 161.368962 -317.076001)
			(xy 161.326341 -317.051394) (xy 161.28822 -317.020269) (xy 161.255585 -316.983432) (xy 161.229282 -316.941836)
			(xy 161.209991 -316.89656) (xy 161.198214 -316.848776) (xy 161.194254 -316.799722) (xy 159.905192 -316.799722)
			(xy 159.904697 -316.824329) (xy 159.896802 -316.872906) (xy 159.881218 -316.919587) (xy 159.858347 -316.963164)
			(xy 159.828782 -317.002508) (xy 159.793289 -317.0366) (xy 159.752786 -317.064556) (xy 159.708324 -317.085654)
			(xy 159.661053 -317.099346) (xy 159.612198 -317.105278) (xy 159.563023 -317.103297) (xy 159.514804 -317.093453)
			(xy 159.468788 -317.076001) (xy 159.426167 -317.051394) (xy 159.388046 -317.020269) (xy 159.355411 -316.983432)
			(xy 159.329108 -316.941836) (xy 159.309817 -316.89656) (xy 159.29804 -316.848776) (xy 159.29408 -316.799722)
			(xy 82.755232 -316.799722) (xy 82.754737 -316.824329) (xy 82.746842 -316.872906) (xy 82.731258 -316.919587)
			(xy 82.708387 -316.963164) (xy 82.678822 -317.002508) (xy 82.643329 -317.0366) (xy 82.602826 -317.064556)
			(xy 82.558364 -317.085654) (xy 82.511093 -317.099346) (xy 82.462238 -317.105278) (xy 82.413063 -317.103297)
			(xy 82.364844 -317.093453) (xy 82.318828 -317.076001) (xy 82.276207 -317.051394) (xy 82.238086 -317.020269)
			(xy 82.205451 -316.983432) (xy 82.179148 -316.941836) (xy 82.159857 -316.89656) (xy 82.14808 -316.848776)
			(xy 82.14412 -316.799722) (xy 81.805272 -316.799722) (xy 81.804777 -316.824329) (xy 81.796882 -316.872906)
			(xy 81.781298 -316.919587) (xy 81.758427 -316.963164) (xy 81.728862 -317.002508) (xy 81.693369 -317.0366)
			(xy 81.652866 -317.064556) (xy 81.608404 -317.085654) (xy 81.561133 -317.099346) (xy 81.512278 -317.105278)
			(xy 81.463103 -317.103297) (xy 81.414884 -317.093453) (xy 81.368868 -317.076001) (xy 81.326247 -317.051394)
			(xy 81.288126 -317.020269) (xy 81.255491 -316.983432) (xy 81.229188 -316.941836) (xy 81.209897 -316.89656)
			(xy 81.19812 -316.848776) (xy 81.19416 -316.799722) (xy 79.905098 -316.799722) (xy 79.904603 -316.824329)
			(xy 79.896708 -316.872906) (xy 79.881124 -316.919587) (xy 79.858253 -316.963164) (xy 79.828688 -317.002508)
			(xy 79.793195 -317.0366) (xy 79.752692 -317.064556) (xy 79.70823 -317.085654) (xy 79.660959 -317.099346)
			(xy 79.612104 -317.105278) (xy 79.562929 -317.103297) (xy 79.51471 -317.093453) (xy 79.468694 -317.076001)
			(xy 79.426073 -317.051394) (xy 79.387952 -317.020269) (xy 79.355317 -316.983432) (xy 79.329014 -316.941836)
			(xy 79.309723 -316.89656) (xy 79.297946 -316.848776) (xy 79.293986 -316.799722) (xy 78.005178 -316.799722)
			(xy 78.004683 -316.824329) (xy 77.996788 -316.872906) (xy 77.981204 -316.919587) (xy 77.958333 -316.963164)
			(xy 77.928768 -317.002508) (xy 77.893275 -317.0366) (xy 77.852772 -317.064556) (xy 77.80831 -317.085654)
			(xy 77.761039 -317.099346) (xy 77.712184 -317.105278) (xy 77.663009 -317.103297) (xy 77.61479 -317.093453)
			(xy 77.568774 -317.076001) (xy 77.526153 -317.051394) (xy 77.488032 -317.020269) (xy 77.455397 -316.983432)
			(xy 77.429094 -316.941836) (xy 77.409803 -316.89656) (xy 77.398026 -316.848776) (xy 77.394066 -316.799722)
			(xy 76.105258 -316.799722) (xy 76.104763 -316.824329) (xy 76.096868 -316.872906) (xy 76.081284 -316.919587)
			(xy 76.058413 -316.963164) (xy 76.028848 -317.002508) (xy 75.993355 -317.0366) (xy 75.952852 -317.064556)
			(xy 75.90839 -317.085654) (xy 75.861119 -317.099346) (xy 75.812264 -317.105278) (xy 75.763089 -317.103297)
			(xy 75.71487 -317.093453) (xy 75.668854 -317.076001) (xy 75.626233 -317.051394) (xy 75.588112 -317.020269)
			(xy 75.555477 -316.983432) (xy 75.529174 -316.941836) (xy 75.509883 -316.89656) (xy 75.498106 -316.848776)
			(xy 75.494146 -316.799722) (xy 74.205084 -316.799722) (xy 74.204589 -316.824329) (xy 74.196694 -316.872906)
			(xy 74.18111 -316.919587) (xy 74.158239 -316.963164) (xy 74.128674 -317.002508) (xy 74.093181 -317.0366)
			(xy 74.052678 -317.064556) (xy 74.008216 -317.085654) (xy 73.960945 -317.099346) (xy 73.91209 -317.105278)
			(xy 73.862915 -317.103297) (xy 73.814696 -317.093453) (xy 73.76868 -317.076001) (xy 73.726059 -317.051394)
			(xy 73.687938 -317.020269) (xy 73.655303 -316.983432) (xy 73.629 -316.941836) (xy 73.609709 -316.89656)
			(xy 73.597932 -316.848776) (xy 73.593972 -316.799722) (xy 0.508 -316.799722) (xy 0.508 -317.749936)
			(xy 74.544186 -317.749936) (xy 74.548146 -317.700882) (xy 74.559923 -317.653098) (xy 74.579214 -317.607822)
			(xy 74.605517 -317.566226) (xy 74.638152 -317.529389) (xy 74.676273 -317.498264) (xy 74.718894 -317.473657)
			(xy 74.76491 -317.456205) (xy 74.813129 -317.446361) (xy 74.862304 -317.44438) (xy 74.911159 -317.450312)
			(xy 74.95843 -317.464004) (xy 75.002892 -317.485102) (xy 75.043395 -317.513058) (xy 75.078888 -317.54715)
			(xy 75.108453 -317.586494) (xy 75.131324 -317.630071) (xy 75.146908 -317.676752) (xy 75.154803 -317.725329)
			(xy 75.155298 -317.749936) (xy 76.444106 -317.749936) (xy 76.448066 -317.700882) (xy 76.459843 -317.653098)
			(xy 76.479134 -317.607822) (xy 76.505437 -317.566226) (xy 76.538072 -317.529389) (xy 76.576193 -317.498264)
			(xy 76.618814 -317.473657) (xy 76.66483 -317.456205) (xy 76.713049 -317.446361) (xy 76.762224 -317.44438)
			(xy 76.811079 -317.450312) (xy 76.85835 -317.464004) (xy 76.902812 -317.485102) (xy 76.943315 -317.513058)
			(xy 76.978808 -317.54715) (xy 77.008373 -317.586494) (xy 77.031244 -317.630071) (xy 77.046828 -317.676752)
			(xy 77.054723 -317.725329) (xy 77.055218 -317.749936) (xy 78.344026 -317.749936) (xy 78.347986 -317.700882)
			(xy 78.359763 -317.653098) (xy 78.379054 -317.607822) (xy 78.405357 -317.566226) (xy 78.437992 -317.529389)
			(xy 78.476113 -317.498264) (xy 78.518734 -317.473657) (xy 78.56475 -317.456205) (xy 78.612969 -317.446361)
			(xy 78.662144 -317.44438) (xy 78.710999 -317.450312) (xy 78.75827 -317.464004) (xy 78.802732 -317.485102)
			(xy 78.843235 -317.513058) (xy 78.878728 -317.54715) (xy 78.908293 -317.586494) (xy 78.931164 -317.630071)
			(xy 78.946748 -317.676752) (xy 78.954643 -317.725329) (xy 78.955138 -317.749936) (xy 80.243946 -317.749936)
			(xy 80.247906 -317.700882) (xy 80.259683 -317.653098) (xy 80.278974 -317.607822) (xy 80.305277 -317.566226)
			(xy 80.337912 -317.529389) (xy 80.376033 -317.498264) (xy 80.418654 -317.473657) (xy 80.46467 -317.456205)
			(xy 80.512889 -317.446361) (xy 80.562064 -317.44438) (xy 80.610919 -317.450312) (xy 80.65819 -317.464004)
			(xy 80.702652 -317.485102) (xy 80.743155 -317.513058) (xy 80.778648 -317.54715) (xy 80.808213 -317.586494)
			(xy 80.831084 -317.630071) (xy 80.846668 -317.676752) (xy 80.854563 -317.725329) (xy 80.855058 -317.749936)
			(xy 160.24404 -317.749936) (xy 160.248 -317.700882) (xy 160.259777 -317.653098) (xy 160.279068 -317.607822)
			(xy 160.305371 -317.566226) (xy 160.338006 -317.529389) (xy 160.376127 -317.498264) (xy 160.418748 -317.473657)
			(xy 160.464764 -317.456205) (xy 160.512983 -317.446361) (xy 160.562158 -317.44438) (xy 160.611013 -317.450312)
			(xy 160.658284 -317.464004) (xy 160.702746 -317.485102) (xy 160.743249 -317.513058) (xy 160.778742 -317.54715)
			(xy 160.808307 -317.586494) (xy 160.831178 -317.630071) (xy 160.846762 -317.676752) (xy 160.854657 -317.725329)
			(xy 160.855152 -317.749936) (xy 162.144214 -317.749936) (xy 162.148174 -317.700882) (xy 162.159951 -317.653098)
			(xy 162.179242 -317.607822) (xy 162.205545 -317.566226) (xy 162.23818 -317.529389) (xy 162.276301 -317.498264)
			(xy 162.318922 -317.473657) (xy 162.364938 -317.456205) (xy 162.413157 -317.446361) (xy 162.462332 -317.44438)
			(xy 162.511187 -317.450312) (xy 162.558458 -317.464004) (xy 162.60292 -317.485102) (xy 162.643423 -317.513058)
			(xy 162.678916 -317.54715) (xy 162.708481 -317.586494) (xy 162.731352 -317.630071) (xy 162.746936 -317.676752)
			(xy 162.754831 -317.725329) (xy 162.755326 -317.749936) (xy 164.044134 -317.749936) (xy 164.048094 -317.700882)
			(xy 164.059871 -317.653098) (xy 164.079162 -317.607822) (xy 164.105465 -317.566226) (xy 164.1381 -317.529389)
			(xy 164.176221 -317.498264) (xy 164.218842 -317.473657) (xy 164.264858 -317.456205) (xy 164.313077 -317.446361)
			(xy 164.362252 -317.44438) (xy 164.411107 -317.450312) (xy 164.458378 -317.464004) (xy 164.50284 -317.485102)
			(xy 164.543343 -317.513058) (xy 164.578836 -317.54715) (xy 164.608401 -317.586494) (xy 164.631272 -317.630071)
			(xy 164.646856 -317.676752) (xy 164.654751 -317.725329) (xy 164.655246 -317.749936) (xy 165.944054 -317.749936)
			(xy 165.948014 -317.700882) (xy 165.959791 -317.653098) (xy 165.979082 -317.607822) (xy 166.005385 -317.566226)
			(xy 166.03802 -317.529389) (xy 166.076141 -317.498264) (xy 166.118762 -317.473657) (xy 166.164778 -317.456205)
			(xy 166.212997 -317.446361) (xy 166.262172 -317.44438) (xy 166.311027 -317.450312) (xy 166.358298 -317.464004)
			(xy 166.40276 -317.485102) (xy 166.443263 -317.513058) (xy 166.478756 -317.54715) (xy 166.508321 -317.586494)
			(xy 166.531192 -317.630071) (xy 166.546776 -317.676752) (xy 166.554671 -317.725329) (xy 166.555166 -317.749936)
			(xy 183.044096 -317.749936) (xy 183.048056 -317.700882) (xy 183.059833 -317.653098) (xy 183.079124 -317.607822)
			(xy 183.105427 -317.566226) (xy 183.138062 -317.529389) (xy 183.176183 -317.498264) (xy 183.218804 -317.473657)
			(xy 183.26482 -317.456205) (xy 183.313039 -317.446361) (xy 183.362214 -317.44438) (xy 183.411069 -317.450312)
			(xy 183.45834 -317.464004) (xy 183.502802 -317.485102) (xy 183.543305 -317.513058) (xy 183.578798 -317.54715)
			(xy 183.608363 -317.586494) (xy 183.631234 -317.630071) (xy 183.646818 -317.676752) (xy 183.654713 -317.725329)
			(xy 183.655208 -317.749936) (xy 184.94427 -317.749936) (xy 184.94823 -317.700882) (xy 184.960007 -317.653098)
			(xy 184.979298 -317.607822) (xy 185.005601 -317.566226) (xy 185.038236 -317.529389) (xy 185.076357 -317.498264)
			(xy 185.118978 -317.473657) (xy 185.164994 -317.456205) (xy 185.213213 -317.446361) (xy 185.262388 -317.44438)
			(xy 185.311243 -317.450312) (xy 185.358514 -317.464004) (xy 185.402976 -317.485102) (xy 185.443479 -317.513058)
			(xy 185.478972 -317.54715) (xy 185.508537 -317.586494) (xy 185.531408 -317.630071) (xy 185.546992 -317.676752)
			(xy 185.554887 -317.725329) (xy 185.555382 -317.749936) (xy 186.84419 -317.749936) (xy 186.84815 -317.700882)
			(xy 186.859927 -317.653098) (xy 186.879218 -317.607822) (xy 186.905521 -317.566226) (xy 186.938156 -317.529389)
			(xy 186.976277 -317.498264) (xy 187.018898 -317.473657) (xy 187.064914 -317.456205) (xy 187.113133 -317.446361)
			(xy 187.162308 -317.44438) (xy 187.211163 -317.450312) (xy 187.258434 -317.464004) (xy 187.302896 -317.485102)
			(xy 187.343399 -317.513058) (xy 187.378892 -317.54715) (xy 187.408457 -317.586494) (xy 187.431328 -317.630071)
			(xy 187.446912 -317.676752) (xy 187.454807 -317.725329) (xy 187.455302 -317.749936) (xy 188.74411 -317.749936)
			(xy 188.74807 -317.700882) (xy 188.759847 -317.653098) (xy 188.779138 -317.607822) (xy 188.805441 -317.566226)
			(xy 188.838076 -317.529389) (xy 188.876197 -317.498264) (xy 188.918818 -317.473657) (xy 188.964834 -317.456205)
			(xy 189.013053 -317.446361) (xy 189.062228 -317.44438) (xy 189.111083 -317.450312) (xy 189.158354 -317.464004)
			(xy 189.202816 -317.485102) (xy 189.243319 -317.513058) (xy 189.278812 -317.54715) (xy 189.308377 -317.586494)
			(xy 189.331248 -317.630071) (xy 189.346832 -317.676752) (xy 189.354727 -317.725329) (xy 189.355222 -317.749936)
			(xy 306.744128 -317.749936) (xy 306.748088 -317.700882) (xy 306.759865 -317.653098) (xy 306.779156 -317.607822)
			(xy 306.805459 -317.566226) (xy 306.838094 -317.529389) (xy 306.876215 -317.498264) (xy 306.918836 -317.473657)
			(xy 306.964852 -317.456205) (xy 307.013071 -317.446361) (xy 307.062246 -317.44438) (xy 307.111101 -317.450312)
			(xy 307.158372 -317.464004) (xy 307.202834 -317.485102) (xy 307.243337 -317.513058) (xy 307.27883 -317.54715)
			(xy 307.308395 -317.586494) (xy 307.331266 -317.630071) (xy 307.34685 -317.676752) (xy 307.354745 -317.725329)
			(xy 307.35524 -317.749936) (xy 308.644048 -317.749936) (xy 308.648008 -317.700882) (xy 308.659785 -317.653098)
			(xy 308.679076 -317.607822) (xy 308.705379 -317.566226) (xy 308.738014 -317.529389) (xy 308.776135 -317.498264)
			(xy 308.818756 -317.473657) (xy 308.864772 -317.456205) (xy 308.912991 -317.446361) (xy 308.962166 -317.44438)
			(xy 309.011021 -317.450312) (xy 309.058292 -317.464004) (xy 309.102754 -317.485102) (xy 309.143257 -317.513058)
			(xy 309.17875 -317.54715) (xy 309.208315 -317.586494) (xy 309.231186 -317.630071) (xy 309.24677 -317.676752)
			(xy 309.254665 -317.725329) (xy 309.25516 -317.749936) (xy 310.543968 -317.749936) (xy 310.547928 -317.700882)
			(xy 310.559705 -317.653098) (xy 310.578996 -317.607822) (xy 310.605299 -317.566226) (xy 310.637934 -317.529389)
			(xy 310.676055 -317.498264) (xy 310.718676 -317.473657) (xy 310.764692 -317.456205) (xy 310.812911 -317.446361)
			(xy 310.862086 -317.44438) (xy 310.910941 -317.450312) (xy 310.958212 -317.464004) (xy 311.002674 -317.485102)
			(xy 311.043177 -317.513058) (xy 311.07867 -317.54715) (xy 311.108235 -317.586494) (xy 311.131106 -317.630071)
			(xy 311.14669 -317.676752) (xy 311.154585 -317.725329) (xy 311.15508 -317.749936) (xy 312.443888 -317.749936)
			(xy 312.447848 -317.700882) (xy 312.459625 -317.653098) (xy 312.478916 -317.607822) (xy 312.505219 -317.566226)
			(xy 312.537854 -317.529389) (xy 312.575975 -317.498264) (xy 312.618596 -317.473657) (xy 312.664612 -317.456205)
			(xy 312.712831 -317.446361) (xy 312.762006 -317.44438) (xy 312.810861 -317.450312) (xy 312.858132 -317.464004)
			(xy 312.902594 -317.485102) (xy 312.943097 -317.513058) (xy 312.97859 -317.54715) (xy 313.008155 -317.586494)
			(xy 313.031026 -317.630071) (xy 313.04661 -317.676752) (xy 313.054505 -317.725329) (xy 313.055 -317.749936)
			(xy 392.443982 -317.749936) (xy 392.447942 -317.700882) (xy 392.459719 -317.653098) (xy 392.47901 -317.607822)
			(xy 392.505313 -317.566226) (xy 392.537948 -317.529389) (xy 392.576069 -317.498264) (xy 392.61869 -317.473657)
			(xy 392.664706 -317.456205) (xy 392.712925 -317.446361) (xy 392.7621 -317.44438) (xy 392.810955 -317.450312)
			(xy 392.858226 -317.464004) (xy 392.902688 -317.485102) (xy 392.943191 -317.513058) (xy 392.978684 -317.54715)
			(xy 393.008249 -317.586494) (xy 393.03112 -317.630071) (xy 393.046704 -317.676752) (xy 393.054599 -317.725329)
			(xy 393.055094 -317.749936) (xy 394.344156 -317.749936) (xy 394.348116 -317.700882) (xy 394.359893 -317.653098)
			(xy 394.379184 -317.607822) (xy 394.405487 -317.566226) (xy 394.438122 -317.529389) (xy 394.476243 -317.498264)
			(xy 394.518864 -317.473657) (xy 394.56488 -317.456205) (xy 394.613099 -317.446361) (xy 394.662274 -317.44438)
			(xy 394.711129 -317.450312) (xy 394.7584 -317.464004) (xy 394.802862 -317.485102) (xy 394.843365 -317.513058)
			(xy 394.878858 -317.54715) (xy 394.908423 -317.586494) (xy 394.931294 -317.630071) (xy 394.946878 -317.676752)
			(xy 394.954773 -317.725329) (xy 394.955268 -317.749936) (xy 396.244076 -317.749936) (xy 396.248036 -317.700882)
			(xy 396.259813 -317.653098) (xy 396.279104 -317.607822) (xy 396.305407 -317.566226) (xy 396.338042 -317.529389)
			(xy 396.376163 -317.498264) (xy 396.418784 -317.473657) (xy 396.4648 -317.456205) (xy 396.513019 -317.446361)
			(xy 396.562194 -317.44438) (xy 396.611049 -317.450312) (xy 396.65832 -317.464004) (xy 396.702782 -317.485102)
			(xy 396.743285 -317.513058) (xy 396.778778 -317.54715) (xy 396.808343 -317.586494) (xy 396.831214 -317.630071)
			(xy 396.846798 -317.676752) (xy 396.854693 -317.725329) (xy 396.855188 -317.749936) (xy 398.143996 -317.749936)
			(xy 398.147956 -317.700882) (xy 398.159733 -317.653098) (xy 398.179024 -317.607822) (xy 398.205327 -317.566226)
			(xy 398.237962 -317.529389) (xy 398.276083 -317.498264) (xy 398.318704 -317.473657) (xy 398.36472 -317.456205)
			(xy 398.412939 -317.446361) (xy 398.462114 -317.44438) (xy 398.510969 -317.450312) (xy 398.55824 -317.464004)
			(xy 398.602702 -317.485102) (xy 398.643205 -317.513058) (xy 398.678698 -317.54715) (xy 398.708263 -317.586494)
			(xy 398.731134 -317.630071) (xy 398.746718 -317.676752) (xy 398.754613 -317.725329) (xy 398.755108 -317.749936)
			(xy 415.244038 -317.749936) (xy 415.247998 -317.700882) (xy 415.259775 -317.653098) (xy 415.279066 -317.607822)
			(xy 415.305369 -317.566226) (xy 415.338004 -317.529389) (xy 415.376125 -317.498264) (xy 415.418746 -317.473657)
			(xy 415.464762 -317.456205) (xy 415.512981 -317.446361) (xy 415.562156 -317.44438) (xy 415.611011 -317.450312)
			(xy 415.658282 -317.464004) (xy 415.702744 -317.485102) (xy 415.743247 -317.513058) (xy 415.77874 -317.54715)
			(xy 415.808305 -317.586494) (xy 415.831176 -317.630071) (xy 415.84676 -317.676752) (xy 415.854655 -317.725329)
			(xy 415.85515 -317.749936) (xy 417.144212 -317.749936) (xy 417.148172 -317.700882) (xy 417.159949 -317.653098)
			(xy 417.17924 -317.607822) (xy 417.205543 -317.566226) (xy 417.238178 -317.529389) (xy 417.276299 -317.498264)
			(xy 417.31892 -317.473657) (xy 417.364936 -317.456205) (xy 417.413155 -317.446361) (xy 417.46233 -317.44438)
			(xy 417.511185 -317.450312) (xy 417.558456 -317.464004) (xy 417.602918 -317.485102) (xy 417.643421 -317.513058)
			(xy 417.678914 -317.54715) (xy 417.708479 -317.586494) (xy 417.73135 -317.630071) (xy 417.746934 -317.676752)
			(xy 417.754829 -317.725329) (xy 417.755324 -317.749936) (xy 419.044132 -317.749936) (xy 419.048092 -317.700882)
			(xy 419.059869 -317.653098) (xy 419.07916 -317.607822) (xy 419.105463 -317.566226) (xy 419.138098 -317.529389)
			(xy 419.176219 -317.498264) (xy 419.21884 -317.473657) (xy 419.264856 -317.456205) (xy 419.313075 -317.446361)
			(xy 419.36225 -317.44438) (xy 419.411105 -317.450312) (xy 419.458376 -317.464004) (xy 419.502838 -317.485102)
			(xy 419.543341 -317.513058) (xy 419.578834 -317.54715) (xy 419.608399 -317.586494) (xy 419.63127 -317.630071)
			(xy 419.646854 -317.676752) (xy 419.654749 -317.725329) (xy 419.655244 -317.749936) (xy 420.944052 -317.749936)
			(xy 420.948012 -317.700882) (xy 420.959789 -317.653098) (xy 420.97908 -317.607822) (xy 421.005383 -317.566226)
			(xy 421.038018 -317.529389) (xy 421.076139 -317.498264) (xy 421.11876 -317.473657) (xy 421.164776 -317.456205)
			(xy 421.212995 -317.446361) (xy 421.26217 -317.44438) (xy 421.311025 -317.450312) (xy 421.358296 -317.464004)
			(xy 421.402758 -317.485102) (xy 421.443261 -317.513058) (xy 421.478754 -317.54715) (xy 421.508319 -317.586494)
			(xy 421.53119 -317.630071) (xy 421.546774 -317.676752) (xy 421.554669 -317.725329) (xy 421.555164 -317.749936)
			(xy 421.554669 -317.774543) (xy 421.546774 -317.82312) (xy 421.53119 -317.869801) (xy 421.508319 -317.913378)
			(xy 421.478754 -317.952722) (xy 421.443261 -317.986814) (xy 421.402758 -318.01477) (xy 421.358296 -318.035868)
			(xy 421.311025 -318.04956) (xy 421.26217 -318.055492) (xy 421.212995 -318.053511) (xy 421.164776 -318.043667)
			(xy 421.11876 -318.026215) (xy 421.076139 -318.001608) (xy 421.038018 -317.970483) (xy 421.005383 -317.933646)
			(xy 420.97908 -317.89205) (xy 420.959789 -317.846774) (xy 420.948012 -317.79899) (xy 420.944052 -317.749936)
			(xy 419.655244 -317.749936) (xy 419.654749 -317.774543) (xy 419.646854 -317.82312) (xy 419.63127 -317.869801)
			(xy 419.608399 -317.913378) (xy 419.578834 -317.952722) (xy 419.543341 -317.986814) (xy 419.502838 -318.01477)
			(xy 419.458376 -318.035868) (xy 419.411105 -318.04956) (xy 419.36225 -318.055492) (xy 419.313075 -318.053511)
			(xy 419.264856 -318.043667) (xy 419.21884 -318.026215) (xy 419.176219 -318.001608) (xy 419.138098 -317.970483)
			(xy 419.105463 -317.933646) (xy 419.07916 -317.89205) (xy 419.059869 -317.846774) (xy 419.048092 -317.79899)
			(xy 419.044132 -317.749936) (xy 417.755324 -317.749936) (xy 417.754829 -317.774543) (xy 417.746934 -317.82312)
			(xy 417.73135 -317.869801) (xy 417.708479 -317.913378) (xy 417.678914 -317.952722) (xy 417.643421 -317.986814)
			(xy 417.602918 -318.01477) (xy 417.558456 -318.035868) (xy 417.511185 -318.04956) (xy 417.46233 -318.055492)
			(xy 417.413155 -318.053511) (xy 417.364936 -318.043667) (xy 417.31892 -318.026215) (xy 417.276299 -318.001608)
			(xy 417.238178 -317.970483) (xy 417.205543 -317.933646) (xy 417.17924 -317.89205) (xy 417.159949 -317.846774)
			(xy 417.148172 -317.79899) (xy 417.144212 -317.749936) (xy 415.85515 -317.749936) (xy 415.854655 -317.774543)
			(xy 415.84676 -317.82312) (xy 415.831176 -317.869801) (xy 415.808305 -317.913378) (xy 415.77874 -317.952722)
			(xy 415.743247 -317.986814) (xy 415.702744 -318.01477) (xy 415.658282 -318.035868) (xy 415.611011 -318.04956)
			(xy 415.562156 -318.055492) (xy 415.512981 -318.053511) (xy 415.464762 -318.043667) (xy 415.418746 -318.026215)
			(xy 415.376125 -318.001608) (xy 415.338004 -317.970483) (xy 415.305369 -317.933646) (xy 415.279066 -317.89205)
			(xy 415.259775 -317.846774) (xy 415.247998 -317.79899) (xy 415.244038 -317.749936) (xy 398.755108 -317.749936)
			(xy 398.754613 -317.774543) (xy 398.746718 -317.82312) (xy 398.731134 -317.869801) (xy 398.708263 -317.913378)
			(xy 398.678698 -317.952722) (xy 398.643205 -317.986814) (xy 398.602702 -318.01477) (xy 398.55824 -318.035868)
			(xy 398.510969 -318.04956) (xy 398.462114 -318.055492) (xy 398.412939 -318.053511) (xy 398.36472 -318.043667)
			(xy 398.318704 -318.026215) (xy 398.276083 -318.001608) (xy 398.237962 -317.970483) (xy 398.205327 -317.933646)
			(xy 398.179024 -317.89205) (xy 398.159733 -317.846774) (xy 398.147956 -317.79899) (xy 398.143996 -317.749936)
			(xy 396.855188 -317.749936) (xy 396.854693 -317.774543) (xy 396.846798 -317.82312) (xy 396.831214 -317.869801)
			(xy 396.808343 -317.913378) (xy 396.778778 -317.952722) (xy 396.743285 -317.986814) (xy 396.702782 -318.01477)
			(xy 396.65832 -318.035868) (xy 396.611049 -318.04956) (xy 396.562194 -318.055492) (xy 396.513019 -318.053511)
			(xy 396.4648 -318.043667) (xy 396.418784 -318.026215) (xy 396.376163 -318.001608) (xy 396.338042 -317.970483)
			(xy 396.305407 -317.933646) (xy 396.279104 -317.89205) (xy 396.259813 -317.846774) (xy 396.248036 -317.79899)
			(xy 396.244076 -317.749936) (xy 394.955268 -317.749936) (xy 394.954773 -317.774543) (xy 394.946878 -317.82312)
			(xy 394.931294 -317.869801) (xy 394.908423 -317.913378) (xy 394.878858 -317.952722) (xy 394.843365 -317.986814)
			(xy 394.802862 -318.01477) (xy 394.7584 -318.035868) (xy 394.711129 -318.04956) (xy 394.662274 -318.055492)
			(xy 394.613099 -318.053511) (xy 394.56488 -318.043667) (xy 394.518864 -318.026215) (xy 394.476243 -318.001608)
			(xy 394.438122 -317.970483) (xy 394.405487 -317.933646) (xy 394.379184 -317.89205) (xy 394.359893 -317.846774)
			(xy 394.348116 -317.79899) (xy 394.344156 -317.749936) (xy 393.055094 -317.749936) (xy 393.054599 -317.774543)
			(xy 393.046704 -317.82312) (xy 393.03112 -317.869801) (xy 393.008249 -317.913378) (xy 392.978684 -317.952722)
			(xy 392.943191 -317.986814) (xy 392.902688 -318.01477) (xy 392.858226 -318.035868) (xy 392.810955 -318.04956)
			(xy 392.7621 -318.055492) (xy 392.712925 -318.053511) (xy 392.664706 -318.043667) (xy 392.61869 -318.026215)
			(xy 392.576069 -318.001608) (xy 392.537948 -317.970483) (xy 392.505313 -317.933646) (xy 392.47901 -317.89205)
			(xy 392.459719 -317.846774) (xy 392.447942 -317.79899) (xy 392.443982 -317.749936) (xy 313.055 -317.749936)
			(xy 313.054505 -317.774543) (xy 313.04661 -317.82312) (xy 313.031026 -317.869801) (xy 313.008155 -317.913378)
			(xy 312.97859 -317.952722) (xy 312.943097 -317.986814) (xy 312.902594 -318.01477) (xy 312.858132 -318.035868)
			(xy 312.810861 -318.04956) (xy 312.762006 -318.055492) (xy 312.712831 -318.053511) (xy 312.664612 -318.043667)
			(xy 312.618596 -318.026215) (xy 312.575975 -318.001608) (xy 312.537854 -317.970483) (xy 312.505219 -317.933646)
			(xy 312.478916 -317.89205) (xy 312.459625 -317.846774) (xy 312.447848 -317.79899) (xy 312.443888 -317.749936)
			(xy 311.15508 -317.749936) (xy 311.154585 -317.774543) (xy 311.14669 -317.82312) (xy 311.131106 -317.869801)
			(xy 311.108235 -317.913378) (xy 311.07867 -317.952722) (xy 311.043177 -317.986814) (xy 311.002674 -318.01477)
			(xy 310.958212 -318.035868) (xy 310.910941 -318.04956) (xy 310.862086 -318.055492) (xy 310.812911 -318.053511)
			(xy 310.764692 -318.043667) (xy 310.718676 -318.026215) (xy 310.676055 -318.001608) (xy 310.637934 -317.970483)
			(xy 310.605299 -317.933646) (xy 310.578996 -317.89205) (xy 310.559705 -317.846774) (xy 310.547928 -317.79899)
			(xy 310.543968 -317.749936) (xy 309.25516 -317.749936) (xy 309.254665 -317.774543) (xy 309.24677 -317.82312)
			(xy 309.231186 -317.869801) (xy 309.208315 -317.913378) (xy 309.17875 -317.952722) (xy 309.143257 -317.986814)
			(xy 309.102754 -318.01477) (xy 309.058292 -318.035868) (xy 309.011021 -318.04956) (xy 308.962166 -318.055492)
			(xy 308.912991 -318.053511) (xy 308.864772 -318.043667) (xy 308.818756 -318.026215) (xy 308.776135 -318.001608)
			(xy 308.738014 -317.970483) (xy 308.705379 -317.933646) (xy 308.679076 -317.89205) (xy 308.659785 -317.846774)
			(xy 308.648008 -317.79899) (xy 308.644048 -317.749936) (xy 307.35524 -317.749936) (xy 307.354745 -317.774543)
			(xy 307.34685 -317.82312) (xy 307.331266 -317.869801) (xy 307.308395 -317.913378) (xy 307.27883 -317.952722)
			(xy 307.243337 -317.986814) (xy 307.202834 -318.01477) (xy 307.158372 -318.035868) (xy 307.111101 -318.04956)
			(xy 307.062246 -318.055492) (xy 307.013071 -318.053511) (xy 306.964852 -318.043667) (xy 306.918836 -318.026215)
			(xy 306.876215 -318.001608) (xy 306.838094 -317.970483) (xy 306.805459 -317.933646) (xy 306.779156 -317.89205)
			(xy 306.759865 -317.846774) (xy 306.748088 -317.79899) (xy 306.744128 -317.749936) (xy 189.355222 -317.749936)
			(xy 189.354727 -317.774543) (xy 189.346832 -317.82312) (xy 189.331248 -317.869801) (xy 189.308377 -317.913378)
			(xy 189.278812 -317.952722) (xy 189.243319 -317.986814) (xy 189.202816 -318.01477) (xy 189.158354 -318.035868)
			(xy 189.111083 -318.04956) (xy 189.062228 -318.055492) (xy 189.013053 -318.053511) (xy 188.964834 -318.043667)
			(xy 188.918818 -318.026215) (xy 188.876197 -318.001608) (xy 188.838076 -317.970483) (xy 188.805441 -317.933646)
			(xy 188.779138 -317.89205) (xy 188.759847 -317.846774) (xy 188.74807 -317.79899) (xy 188.74411 -317.749936)
			(xy 187.455302 -317.749936) (xy 187.454807 -317.774543) (xy 187.446912 -317.82312) (xy 187.431328 -317.869801)
			(xy 187.408457 -317.913378) (xy 187.378892 -317.952722) (xy 187.343399 -317.986814) (xy 187.302896 -318.01477)
			(xy 187.258434 -318.035868) (xy 187.211163 -318.04956) (xy 187.162308 -318.055492) (xy 187.113133 -318.053511)
			(xy 187.064914 -318.043667) (xy 187.018898 -318.026215) (xy 186.976277 -318.001608) (xy 186.938156 -317.970483)
			(xy 186.905521 -317.933646) (xy 186.879218 -317.89205) (xy 186.859927 -317.846774) (xy 186.84815 -317.79899)
			(xy 186.84419 -317.749936) (xy 185.555382 -317.749936) (xy 185.554887 -317.774543) (xy 185.546992 -317.82312)
			(xy 185.531408 -317.869801) (xy 185.508537 -317.913378) (xy 185.478972 -317.952722) (xy 185.443479 -317.986814)
			(xy 185.402976 -318.01477) (xy 185.358514 -318.035868) (xy 185.311243 -318.04956) (xy 185.262388 -318.055492)
			(xy 185.213213 -318.053511) (xy 185.164994 -318.043667) (xy 185.118978 -318.026215) (xy 185.076357 -318.001608)
			(xy 185.038236 -317.970483) (xy 185.005601 -317.933646) (xy 184.979298 -317.89205) (xy 184.960007 -317.846774)
			(xy 184.94823 -317.79899) (xy 184.94427 -317.749936) (xy 183.655208 -317.749936) (xy 183.654713 -317.774543)
			(xy 183.646818 -317.82312) (xy 183.631234 -317.869801) (xy 183.608363 -317.913378) (xy 183.578798 -317.952722)
			(xy 183.543305 -317.986814) (xy 183.502802 -318.01477) (xy 183.45834 -318.035868) (xy 183.411069 -318.04956)
			(xy 183.362214 -318.055492) (xy 183.313039 -318.053511) (xy 183.26482 -318.043667) (xy 183.218804 -318.026215)
			(xy 183.176183 -318.001608) (xy 183.138062 -317.970483) (xy 183.105427 -317.933646) (xy 183.079124 -317.89205)
			(xy 183.059833 -317.846774) (xy 183.048056 -317.79899) (xy 183.044096 -317.749936) (xy 166.555166 -317.749936)
			(xy 166.554671 -317.774543) (xy 166.546776 -317.82312) (xy 166.531192 -317.869801) (xy 166.508321 -317.913378)
			(xy 166.478756 -317.952722) (xy 166.443263 -317.986814) (xy 166.40276 -318.01477) (xy 166.358298 -318.035868)
			(xy 166.311027 -318.04956) (xy 166.262172 -318.055492) (xy 166.212997 -318.053511) (xy 166.164778 -318.043667)
			(xy 166.118762 -318.026215) (xy 166.076141 -318.001608) (xy 166.03802 -317.970483) (xy 166.005385 -317.933646)
			(xy 165.979082 -317.89205) (xy 165.959791 -317.846774) (xy 165.948014 -317.79899) (xy 165.944054 -317.749936)
			(xy 164.655246 -317.749936) (xy 164.654751 -317.774543) (xy 164.646856 -317.82312) (xy 164.631272 -317.869801)
			(xy 164.608401 -317.913378) (xy 164.578836 -317.952722) (xy 164.543343 -317.986814) (xy 164.50284 -318.01477)
			(xy 164.458378 -318.035868) (xy 164.411107 -318.04956) (xy 164.362252 -318.055492) (xy 164.313077 -318.053511)
			(xy 164.264858 -318.043667) (xy 164.218842 -318.026215) (xy 164.176221 -318.001608) (xy 164.1381 -317.970483)
			(xy 164.105465 -317.933646) (xy 164.079162 -317.89205) (xy 164.059871 -317.846774) (xy 164.048094 -317.79899)
			(xy 164.044134 -317.749936) (xy 162.755326 -317.749936) (xy 162.754831 -317.774543) (xy 162.746936 -317.82312)
			(xy 162.731352 -317.869801) (xy 162.708481 -317.913378) (xy 162.678916 -317.952722) (xy 162.643423 -317.986814)
			(xy 162.60292 -318.01477) (xy 162.558458 -318.035868) (xy 162.511187 -318.04956) (xy 162.462332 -318.055492)
			(xy 162.413157 -318.053511) (xy 162.364938 -318.043667) (xy 162.318922 -318.026215) (xy 162.276301 -318.001608)
			(xy 162.23818 -317.970483) (xy 162.205545 -317.933646) (xy 162.179242 -317.89205) (xy 162.159951 -317.846774)
			(xy 162.148174 -317.79899) (xy 162.144214 -317.749936) (xy 160.855152 -317.749936) (xy 160.854657 -317.774543)
			(xy 160.846762 -317.82312) (xy 160.831178 -317.869801) (xy 160.808307 -317.913378) (xy 160.778742 -317.952722)
			(xy 160.743249 -317.986814) (xy 160.702746 -318.01477) (xy 160.658284 -318.035868) (xy 160.611013 -318.04956)
			(xy 160.562158 -318.055492) (xy 160.512983 -318.053511) (xy 160.464764 -318.043667) (xy 160.418748 -318.026215)
			(xy 160.376127 -318.001608) (xy 160.338006 -317.970483) (xy 160.305371 -317.933646) (xy 160.279068 -317.89205)
			(xy 160.259777 -317.846774) (xy 160.248 -317.79899) (xy 160.24404 -317.749936) (xy 80.855058 -317.749936)
			(xy 80.854563 -317.774543) (xy 80.846668 -317.82312) (xy 80.831084 -317.869801) (xy 80.808213 -317.913378)
			(xy 80.778648 -317.952722) (xy 80.743155 -317.986814) (xy 80.702652 -318.01477) (xy 80.65819 -318.035868)
			(xy 80.610919 -318.04956) (xy 80.562064 -318.055492) (xy 80.512889 -318.053511) (xy 80.46467 -318.043667)
			(xy 80.418654 -318.026215) (xy 80.376033 -318.001608) (xy 80.337912 -317.970483) (xy 80.305277 -317.933646)
			(xy 80.278974 -317.89205) (xy 80.259683 -317.846774) (xy 80.247906 -317.79899) (xy 80.243946 -317.749936)
			(xy 78.955138 -317.749936) (xy 78.954643 -317.774543) (xy 78.946748 -317.82312) (xy 78.931164 -317.869801)
			(xy 78.908293 -317.913378) (xy 78.878728 -317.952722) (xy 78.843235 -317.986814) (xy 78.802732 -318.01477)
			(xy 78.75827 -318.035868) (xy 78.710999 -318.04956) (xy 78.662144 -318.055492) (xy 78.612969 -318.053511)
			(xy 78.56475 -318.043667) (xy 78.518734 -318.026215) (xy 78.476113 -318.001608) (xy 78.437992 -317.970483)
			(xy 78.405357 -317.933646) (xy 78.379054 -317.89205) (xy 78.359763 -317.846774) (xy 78.347986 -317.79899)
			(xy 78.344026 -317.749936) (xy 77.055218 -317.749936) (xy 77.054723 -317.774543) (xy 77.046828 -317.82312)
			(xy 77.031244 -317.869801) (xy 77.008373 -317.913378) (xy 76.978808 -317.952722) (xy 76.943315 -317.986814)
			(xy 76.902812 -318.01477) (xy 76.85835 -318.035868) (xy 76.811079 -318.04956) (xy 76.762224 -318.055492)
			(xy 76.713049 -318.053511) (xy 76.66483 -318.043667) (xy 76.618814 -318.026215) (xy 76.576193 -318.001608)
			(xy 76.538072 -317.970483) (xy 76.505437 -317.933646) (xy 76.479134 -317.89205) (xy 76.459843 -317.846774)
			(xy 76.448066 -317.79899) (xy 76.444106 -317.749936) (xy 75.155298 -317.749936) (xy 75.154803 -317.774543)
			(xy 75.146908 -317.82312) (xy 75.131324 -317.869801) (xy 75.108453 -317.913378) (xy 75.078888 -317.952722)
			(xy 75.043395 -317.986814) (xy 75.002892 -318.01477) (xy 74.95843 -318.035868) (xy 74.911159 -318.04956)
			(xy 74.862304 -318.055492) (xy 74.813129 -318.053511) (xy 74.76491 -318.043667) (xy 74.718894 -318.026215)
			(xy 74.676273 -318.001608) (xy 74.638152 -317.970483) (xy 74.605517 -317.933646) (xy 74.579214 -317.89205)
			(xy 74.559923 -317.846774) (xy 74.548146 -317.79899) (xy 74.544186 -317.749936) (xy 0.508 -317.749936)
			(xy 0.508 -320.900044) (xy 26.882353 -320.900044) (xy 26.886342 -320.751504) (xy 26.898299 -320.603391)
			(xy 26.918189 -320.456134) (xy 26.945954 -320.310158) (xy 26.981515 -320.165881) (xy 27.024769 -320.023722)
			(xy 27.075591 -319.884089) (xy 27.133835 -319.747386) (xy 27.199333 -319.614006) (xy 27.271896 -319.484334)
			(xy 27.351314 -319.358744) (xy 27.437359 -319.237597) (xy 27.529783 -319.121244) (xy 27.628319 -319.01002)
			(xy 27.732683 -318.904245) (xy 27.842575 -318.804225) (xy 27.957676 -318.710247) (xy 28.077656 -318.622583)
			(xy 28.202169 -318.541486) (xy 28.330855 -318.467189) (xy 28.463344 -318.399907) (xy 28.599253 -318.339833)
			(xy 28.738191 -318.287141) (xy 28.879757 -318.241982) (xy 29.023543 -318.204487) (xy 29.169134 -318.174765)
			(xy 29.31611 -318.1529) (xy 29.464049 -318.138956) (xy 29.612522 -318.132972) (xy 29.761103 -318.134967)
			(xy 29.909362 -318.144935) (xy 30.056873 -318.162846) (xy 30.203209 -318.188649) (xy 30.34795 -318.222269)
			(xy 30.490677 -318.263611) (xy 30.63098 -318.312554) (xy 30.768453 -318.368957) (xy 30.9027 -318.432658)
			(xy 31.033335 -318.503474) (xy 31.15998 -318.581199) (xy 31.28227 -318.66561) (xy 31.326643 -318.699896)
			(xy 74.544186 -318.699896) (xy 74.548146 -318.650842) (xy 74.559923 -318.603058) (xy 74.579214 -318.557782)
			(xy 74.605517 -318.516186) (xy 74.638152 -318.479349) (xy 74.676273 -318.448224) (xy 74.718894 -318.423617)
			(xy 74.76491 -318.406165) (xy 74.813129 -318.396321) (xy 74.862304 -318.39434) (xy 74.911159 -318.400272)
			(xy 74.95843 -318.413964) (xy 75.002892 -318.435062) (xy 75.043395 -318.463018) (xy 75.078888 -318.49711)
			(xy 75.108453 -318.536454) (xy 75.131324 -318.580031) (xy 75.146908 -318.626712) (xy 75.154803 -318.675289)
			(xy 75.155298 -318.699896) (xy 76.444106 -318.699896) (xy 76.448066 -318.650842) (xy 76.459843 -318.603058)
			(xy 76.479134 -318.557782) (xy 76.505437 -318.516186) (xy 76.538072 -318.479349) (xy 76.576193 -318.448224)
			(xy 76.618814 -318.423617) (xy 76.66483 -318.406165) (xy 76.713049 -318.396321) (xy 76.762224 -318.39434)
			(xy 76.811079 -318.400272) (xy 76.85835 -318.413964) (xy 76.902812 -318.435062) (xy 76.943315 -318.463018)
			(xy 76.978808 -318.49711) (xy 77.008373 -318.536454) (xy 77.031244 -318.580031) (xy 77.046828 -318.626712)
			(xy 77.054723 -318.675289) (xy 77.055218 -318.699896) (xy 78.344026 -318.699896) (xy 78.347986 -318.650842)
			(xy 78.359763 -318.603058) (xy 78.379054 -318.557782) (xy 78.405357 -318.516186) (xy 78.437992 -318.479349)
			(xy 78.476113 -318.448224) (xy 78.518734 -318.423617) (xy 78.56475 -318.406165) (xy 78.612969 -318.396321)
			(xy 78.662144 -318.39434) (xy 78.710999 -318.400272) (xy 78.75827 -318.413964) (xy 78.802732 -318.435062)
			(xy 78.843235 -318.463018) (xy 78.878728 -318.49711) (xy 78.908293 -318.536454) (xy 78.931164 -318.580031)
			(xy 78.946748 -318.626712) (xy 78.954643 -318.675289) (xy 78.955138 -318.699896) (xy 80.243946 -318.699896)
			(xy 80.247906 -318.650842) (xy 80.259683 -318.603058) (xy 80.278974 -318.557782) (xy 80.305277 -318.516186)
			(xy 80.337912 -318.479349) (xy 80.376033 -318.448224) (xy 80.418654 -318.423617) (xy 80.46467 -318.406165)
			(xy 80.512889 -318.396321) (xy 80.562064 -318.39434) (xy 80.610919 -318.400272) (xy 80.65819 -318.413964)
			(xy 80.702652 -318.435062) (xy 80.743155 -318.463018) (xy 80.778648 -318.49711) (xy 80.808213 -318.536454)
			(xy 80.831084 -318.580031) (xy 80.846668 -318.626712) (xy 80.854563 -318.675289) (xy 80.855058 -318.699896)
			(xy 80.854563 -318.724503) (xy 80.846668 -318.77308) (xy 80.831084 -318.819761) (xy 80.808213 -318.863338)
			(xy 80.778648 -318.902682) (xy 80.743155 -318.936774) (xy 80.702652 -318.96473) (xy 80.65819 -318.985828)
			(xy 80.610919 -318.99952) (xy 80.562064 -319.005452) (xy 80.512889 -319.003471) (xy 80.46467 -318.993627)
			(xy 80.418654 -318.976175) (xy 80.376033 -318.951568) (xy 80.337912 -318.920443) (xy 80.305277 -318.883606)
			(xy 80.278974 -318.84201) (xy 80.259683 -318.796734) (xy 80.247906 -318.74895) (xy 80.243946 -318.699896)
			(xy 78.955138 -318.699896) (xy 78.954643 -318.724503) (xy 78.946748 -318.77308) (xy 78.931164 -318.819761)
			(xy 78.908293 -318.863338) (xy 78.878728 -318.902682) (xy 78.843235 -318.936774) (xy 78.802732 -318.96473)
			(xy 78.75827 -318.985828) (xy 78.710999 -318.99952) (xy 78.662144 -319.005452) (xy 78.612969 -319.003471)
			(xy 78.56475 -318.993627) (xy 78.518734 -318.976175) (xy 78.476113 -318.951568) (xy 78.437992 -318.920443)
			(xy 78.405357 -318.883606) (xy 78.379054 -318.84201) (xy 78.359763 -318.796734) (xy 78.347986 -318.74895)
			(xy 78.344026 -318.699896) (xy 77.055218 -318.699896) (xy 77.054723 -318.724503) (xy 77.046828 -318.77308)
			(xy 77.031244 -318.819761) (xy 77.008373 -318.863338) (xy 76.978808 -318.902682) (xy 76.943315 -318.936774)
			(xy 76.902812 -318.96473) (xy 76.85835 -318.985828) (xy 76.811079 -318.99952) (xy 76.762224 -319.005452)
			(xy 76.713049 -319.003471) (xy 76.66483 -318.993627) (xy 76.618814 -318.976175) (xy 76.576193 -318.951568)
			(xy 76.538072 -318.920443) (xy 76.505437 -318.883606) (xy 76.479134 -318.84201) (xy 76.459843 -318.796734)
			(xy 76.448066 -318.74895) (xy 76.444106 -318.699896) (xy 75.155298 -318.699896) (xy 75.154803 -318.724503)
			(xy 75.146908 -318.77308) (xy 75.131324 -318.819761) (xy 75.108453 -318.863338) (xy 75.078888 -318.902682)
			(xy 75.043395 -318.936774) (xy 75.002892 -318.96473) (xy 74.95843 -318.985828) (xy 74.911159 -318.99952)
			(xy 74.862304 -319.005452) (xy 74.813129 -319.003471) (xy 74.76491 -318.993627) (xy 74.718894 -318.976175)
			(xy 74.676273 -318.951568) (xy 74.638152 -318.920443) (xy 74.605517 -318.883606) (xy 74.579214 -318.84201)
			(xy 74.559923 -318.796734) (xy 74.548146 -318.74895) (xy 74.544186 -318.699896) (xy 31.326643 -318.699896)
			(xy 31.399853 -318.756463) (xy 31.51239 -318.853497) (xy 31.619557 -318.956432) (xy 31.721044 -319.064971)
			(xy 31.816558 -319.1788) (xy 31.905825 -319.297593) (xy 31.988586 -319.421005) (xy 32.064604 -319.548683)
			(xy 32.133659 -319.680256) (xy 32.195552 -319.815347) (xy 32.250105 -319.953564) (xy 32.29716 -320.094511)
			(xy 32.336582 -320.237781) (xy 32.368256 -320.38296) (xy 32.392092 -320.529629) (xy 32.408021 -320.677367)
			(xy 32.415997 -320.825747) (xy 32.416496 -320.900044) (xy 86.882487 -320.900044) (xy 86.886476 -320.751504)
			(xy 86.898433 -320.603391) (xy 86.918323 -320.456134) (xy 86.946088 -320.310158) (xy 86.981649 -320.165881)
			(xy 87.024903 -320.023722) (xy 87.075725 -319.884089) (xy 87.133969 -319.747386) (xy 87.199467 -319.614006)
			(xy 87.27203 -319.484334) (xy 87.351448 -319.358744) (xy 87.437493 -319.237597) (xy 87.529917 -319.121244)
			(xy 87.628453 -319.01002) (xy 87.732817 -318.904245) (xy 87.842709 -318.804225) (xy 87.95781 -318.710247)
			(xy 88.07779 -318.622583) (xy 88.202303 -318.541486) (xy 88.330989 -318.467189) (xy 88.463478 -318.399907)
			(xy 88.599387 -318.339833) (xy 88.738325 -318.287141) (xy 88.879891 -318.241982) (xy 89.023677 -318.204487)
			(xy 89.169268 -318.174765) (xy 89.316244 -318.1529) (xy 89.464183 -318.138956) (xy 89.612656 -318.132972)
			(xy 89.761237 -318.134967) (xy 89.909496 -318.144935) (xy 90.057007 -318.162846) (xy 90.203343 -318.188649)
			(xy 90.348084 -318.222269) (xy 90.490811 -318.263611) (xy 90.631114 -318.312554) (xy 90.768587 -318.368957)
			(xy 90.902834 -318.432658) (xy 91.033469 -318.503474) (xy 91.160114 -318.581199) (xy 91.282404 -318.66561)
			(xy 91.399987 -318.756463) (xy 91.512524 -318.853497) (xy 91.619691 -318.956432) (xy 91.721178 -319.064971)
			(xy 91.816692 -319.1788) (xy 91.905959 -319.297593) (xy 91.98872 -319.421005) (xy 92.064738 -319.548683)
			(xy 92.133793 -319.680256) (xy 92.195686 -319.815347) (xy 92.250239 -319.953564) (xy 92.297294 -320.094511)
			(xy 92.336716 -320.237781) (xy 92.36839 -320.38296) (xy 92.392226 -320.529629) (xy 92.408155 -320.677367)
			(xy 92.416131 -320.825747) (xy 92.41663 -320.900044) (xy 142.982451 -320.900044) (xy 142.98644 -320.751504)
			(xy 142.998397 -320.603391) (xy 143.018287 -320.456134) (xy 143.046052 -320.310158) (xy 143.081613 -320.165881)
			(xy 143.124867 -320.023722) (xy 143.175689 -319.884089) (xy 143.233933 -319.747386) (xy 143.299431 -319.614006)
			(xy 143.371994 -319.484334) (xy 143.451412 -319.358744) (xy 143.537457 -319.237597) (xy 143.629881 -319.121244)
			(xy 143.728417 -319.01002) (xy 143.832781 -318.904245) (xy 143.942673 -318.804225) (xy 144.057774 -318.710247)
			(xy 144.177754 -318.622583) (xy 144.302267 -318.541486) (xy 144.430953 -318.467189) (xy 144.563442 -318.399907)
			(xy 144.699351 -318.339833) (xy 144.838289 -318.287141) (xy 144.979855 -318.241982) (xy 145.123641 -318.204487)
			(xy 145.269232 -318.174765) (xy 145.416208 -318.1529) (xy 145.564147 -318.138956) (xy 145.71262 -318.132972)
			(xy 145.861201 -318.134967) (xy 146.00946 -318.144935) (xy 146.156971 -318.162846) (xy 146.303307 -318.188649)
			(xy 146.448048 -318.222269) (xy 146.590775 -318.263611) (xy 146.731078 -318.312554) (xy 146.868551 -318.368957)
			(xy 147.002798 -318.432658) (xy 147.133433 -318.503474) (xy 147.260078 -318.581199) (xy 147.382368 -318.66561)
			(xy 147.426741 -318.699896) (xy 160.24404 -318.699896) (xy 160.248 -318.650842) (xy 160.259777 -318.603058)
			(xy 160.279068 -318.557782) (xy 160.305371 -318.516186) (xy 160.338006 -318.479349) (xy 160.376127 -318.448224)
			(xy 160.418748 -318.423617) (xy 160.464764 -318.406165) (xy 160.512983 -318.396321) (xy 160.562158 -318.39434)
			(xy 160.611013 -318.400272) (xy 160.658284 -318.413964) (xy 160.702746 -318.435062) (xy 160.743249 -318.463018)
			(xy 160.778742 -318.49711) (xy 160.808307 -318.536454) (xy 160.831178 -318.580031) (xy 160.846762 -318.626712)
			(xy 160.854657 -318.675289) (xy 160.855152 -318.699896) (xy 162.144214 -318.699896) (xy 162.148174 -318.650842)
			(xy 162.159951 -318.603058) (xy 162.179242 -318.557782) (xy 162.205545 -318.516186) (xy 162.23818 -318.479349)
			(xy 162.276301 -318.448224) (xy 162.318922 -318.423617) (xy 162.364938 -318.406165) (xy 162.413157 -318.396321)
			(xy 162.462332 -318.39434) (xy 162.511187 -318.400272) (xy 162.558458 -318.413964) (xy 162.60292 -318.435062)
			(xy 162.643423 -318.463018) (xy 162.678916 -318.49711) (xy 162.708481 -318.536454) (xy 162.731352 -318.580031)
			(xy 162.746936 -318.626712) (xy 162.754831 -318.675289) (xy 162.755326 -318.699896) (xy 164.044134 -318.699896)
			(xy 164.048094 -318.650842) (xy 164.059871 -318.603058) (xy 164.079162 -318.557782) (xy 164.105465 -318.516186)
			(xy 164.1381 -318.479349) (xy 164.176221 -318.448224) (xy 164.218842 -318.423617) (xy 164.264858 -318.406165)
			(xy 164.313077 -318.396321) (xy 164.362252 -318.39434) (xy 164.411107 -318.400272) (xy 164.458378 -318.413964)
			(xy 164.50284 -318.435062) (xy 164.543343 -318.463018) (xy 164.578836 -318.49711) (xy 164.608401 -318.536454)
			(xy 164.631272 -318.580031) (xy 164.646856 -318.626712) (xy 164.654751 -318.675289) (xy 164.655246 -318.699896)
			(xy 165.944054 -318.699896) (xy 165.948014 -318.650842) (xy 165.959791 -318.603058) (xy 165.979082 -318.557782)
			(xy 166.005385 -318.516186) (xy 166.03802 -318.479349) (xy 166.076141 -318.448224) (xy 166.118762 -318.423617)
			(xy 166.164778 -318.406165) (xy 166.212997 -318.396321) (xy 166.262172 -318.39434) (xy 166.311027 -318.400272)
			(xy 166.358298 -318.413964) (xy 166.40276 -318.435062) (xy 166.443263 -318.463018) (xy 166.478756 -318.49711)
			(xy 166.508321 -318.536454) (xy 166.531192 -318.580031) (xy 166.546776 -318.626712) (xy 166.554671 -318.675289)
			(xy 166.555166 -318.699896) (xy 183.044096 -318.699896) (xy 183.048056 -318.650842) (xy 183.059833 -318.603058)
			(xy 183.079124 -318.557782) (xy 183.105427 -318.516186) (xy 183.138062 -318.479349) (xy 183.176183 -318.448224)
			(xy 183.218804 -318.423617) (xy 183.26482 -318.406165) (xy 183.313039 -318.396321) (xy 183.362214 -318.39434)
			(xy 183.411069 -318.400272) (xy 183.45834 -318.413964) (xy 183.502802 -318.435062) (xy 183.543305 -318.463018)
			(xy 183.578798 -318.49711) (xy 183.608363 -318.536454) (xy 183.631234 -318.580031) (xy 183.646818 -318.626712)
			(xy 183.654713 -318.675289) (xy 183.655208 -318.699896) (xy 184.94427 -318.699896) (xy 184.94823 -318.650842)
			(xy 184.960007 -318.603058) (xy 184.979298 -318.557782) (xy 185.005601 -318.516186) (xy 185.038236 -318.479349)
			(xy 185.076357 -318.448224) (xy 185.118978 -318.423617) (xy 185.164994 -318.406165) (xy 185.213213 -318.396321)
			(xy 185.262388 -318.39434) (xy 185.311243 -318.400272) (xy 185.358514 -318.413964) (xy 185.402976 -318.435062)
			(xy 185.443479 -318.463018) (xy 185.478972 -318.49711) (xy 185.508537 -318.536454) (xy 185.531408 -318.580031)
			(xy 185.546992 -318.626712) (xy 185.554887 -318.675289) (xy 185.555382 -318.699896) (xy 186.84419 -318.699896)
			(xy 186.84815 -318.650842) (xy 186.859927 -318.603058) (xy 186.879218 -318.557782) (xy 186.905521 -318.516186)
			(xy 186.938156 -318.479349) (xy 186.976277 -318.448224) (xy 187.018898 -318.423617) (xy 187.064914 -318.406165)
			(xy 187.113133 -318.396321) (xy 187.162308 -318.39434) (xy 187.211163 -318.400272) (xy 187.258434 -318.413964)
			(xy 187.302896 -318.435062) (xy 187.343399 -318.463018) (xy 187.378892 -318.49711) (xy 187.408457 -318.536454)
			(xy 187.431328 -318.580031) (xy 187.446912 -318.626712) (xy 187.454807 -318.675289) (xy 187.455302 -318.699896)
			(xy 188.74411 -318.699896) (xy 188.74807 -318.650842) (xy 188.759847 -318.603058) (xy 188.779138 -318.557782)
			(xy 188.805441 -318.516186) (xy 188.838076 -318.479349) (xy 188.876197 -318.448224) (xy 188.918818 -318.423617)
			(xy 188.964834 -318.406165) (xy 189.013053 -318.396321) (xy 189.062228 -318.39434) (xy 189.111083 -318.400272)
			(xy 189.158354 -318.413964) (xy 189.202816 -318.435062) (xy 189.243319 -318.463018) (xy 189.278812 -318.49711)
			(xy 189.308377 -318.536454) (xy 189.331248 -318.580031) (xy 189.346832 -318.626712) (xy 189.354727 -318.675289)
			(xy 189.355222 -318.699896) (xy 189.354727 -318.724503) (xy 189.346832 -318.77308) (xy 189.331248 -318.819761)
			(xy 189.308377 -318.863338) (xy 189.278812 -318.902682) (xy 189.243319 -318.936774) (xy 189.202816 -318.96473)
			(xy 189.158354 -318.985828) (xy 189.111083 -318.99952) (xy 189.062228 -319.005452) (xy 189.013053 -319.003471)
			(xy 188.964834 -318.993627) (xy 188.918818 -318.976175) (xy 188.876197 -318.951568) (xy 188.838076 -318.920443)
			(xy 188.805441 -318.883606) (xy 188.779138 -318.84201) (xy 188.759847 -318.796734) (xy 188.74807 -318.74895)
			(xy 188.74411 -318.699896) (xy 187.455302 -318.699896) (xy 187.454807 -318.724503) (xy 187.446912 -318.77308)
			(xy 187.431328 -318.819761) (xy 187.408457 -318.863338) (xy 187.378892 -318.902682) (xy 187.343399 -318.936774)
			(xy 187.302896 -318.96473) (xy 187.258434 -318.985828) (xy 187.211163 -318.99952) (xy 187.162308 -319.005452)
			(xy 187.113133 -319.003471) (xy 187.064914 -318.993627) (xy 187.018898 -318.976175) (xy 186.976277 -318.951568)
			(xy 186.938156 -318.920443) (xy 186.905521 -318.883606) (xy 186.879218 -318.84201) (xy 186.859927 -318.796734)
			(xy 186.84815 -318.74895) (xy 186.84419 -318.699896) (xy 185.555382 -318.699896) (xy 185.554887 -318.724503)
			(xy 185.546992 -318.77308) (xy 185.531408 -318.819761) (xy 185.508537 -318.863338) (xy 185.478972 -318.902682)
			(xy 185.443479 -318.936774) (xy 185.402976 -318.96473) (xy 185.358514 -318.985828) (xy 185.311243 -318.99952)
			(xy 185.262388 -319.005452) (xy 185.213213 -319.003471) (xy 185.164994 -318.993627) (xy 185.118978 -318.976175)
			(xy 185.076357 -318.951568) (xy 185.038236 -318.920443) (xy 185.005601 -318.883606) (xy 184.979298 -318.84201)
			(xy 184.960007 -318.796734) (xy 184.94823 -318.74895) (xy 184.94427 -318.699896) (xy 183.655208 -318.699896)
			(xy 183.654713 -318.724503) (xy 183.646818 -318.77308) (xy 183.631234 -318.819761) (xy 183.608363 -318.863338)
			(xy 183.578798 -318.902682) (xy 183.543305 -318.936774) (xy 183.502802 -318.96473) (xy 183.45834 -318.985828)
			(xy 183.411069 -318.99952) (xy 183.362214 -319.005452) (xy 183.313039 -319.003471) (xy 183.26482 -318.993627)
			(xy 183.218804 -318.976175) (xy 183.176183 -318.951568) (xy 183.138062 -318.920443) (xy 183.105427 -318.883606)
			(xy 183.079124 -318.84201) (xy 183.059833 -318.796734) (xy 183.048056 -318.74895) (xy 183.044096 -318.699896)
			(xy 166.555166 -318.699896) (xy 166.554671 -318.724503) (xy 166.546776 -318.77308) (xy 166.531192 -318.819761)
			(xy 166.508321 -318.863338) (xy 166.478756 -318.902682) (xy 166.443263 -318.936774) (xy 166.40276 -318.96473)
			(xy 166.358298 -318.985828) (xy 166.311027 -318.99952) (xy 166.262172 -319.005452) (xy 166.212997 -319.003471)
			(xy 166.164778 -318.993627) (xy 166.118762 -318.976175) (xy 166.076141 -318.951568) (xy 166.03802 -318.920443)
			(xy 166.005385 -318.883606) (xy 165.979082 -318.84201) (xy 165.959791 -318.796734) (xy 165.948014 -318.74895)
			(xy 165.944054 -318.699896) (xy 164.655246 -318.699896) (xy 164.654751 -318.724503) (xy 164.646856 -318.77308)
			(xy 164.631272 -318.819761) (xy 164.608401 -318.863338) (xy 164.578836 -318.902682) (xy 164.543343 -318.936774)
			(xy 164.50284 -318.96473) (xy 164.458378 -318.985828) (xy 164.411107 -318.99952) (xy 164.362252 -319.005452)
			(xy 164.313077 -319.003471) (xy 164.264858 -318.993627) (xy 164.218842 -318.976175) (xy 164.176221 -318.951568)
			(xy 164.1381 -318.920443) (xy 164.105465 -318.883606) (xy 164.079162 -318.84201) (xy 164.059871 -318.796734)
			(xy 164.048094 -318.74895) (xy 164.044134 -318.699896) (xy 162.755326 -318.699896) (xy 162.754831 -318.724503)
			(xy 162.746936 -318.77308) (xy 162.731352 -318.819761) (xy 162.708481 -318.863338) (xy 162.678916 -318.902682)
			(xy 162.643423 -318.936774) (xy 162.60292 -318.96473) (xy 162.558458 -318.985828) (xy 162.511187 -318.99952)
			(xy 162.462332 -319.005452) (xy 162.413157 -319.003471) (xy 162.364938 -318.993627) (xy 162.318922 -318.976175)
			(xy 162.276301 -318.951568) (xy 162.23818 -318.920443) (xy 162.205545 -318.883606) (xy 162.179242 -318.84201)
			(xy 162.159951 -318.796734) (xy 162.148174 -318.74895) (xy 162.144214 -318.699896) (xy 160.855152 -318.699896)
			(xy 160.854657 -318.724503) (xy 160.846762 -318.77308) (xy 160.831178 -318.819761) (xy 160.808307 -318.863338)
			(xy 160.778742 -318.902682) (xy 160.743249 -318.936774) (xy 160.702746 -318.96473) (xy 160.658284 -318.985828)
			(xy 160.611013 -318.99952) (xy 160.562158 -319.005452) (xy 160.512983 -319.003471) (xy 160.464764 -318.993627)
			(xy 160.418748 -318.976175) (xy 160.376127 -318.951568) (xy 160.338006 -318.920443) (xy 160.305371 -318.883606)
			(xy 160.279068 -318.84201) (xy 160.259777 -318.796734) (xy 160.248 -318.74895) (xy 160.24404 -318.699896)
			(xy 147.426741 -318.699896) (xy 147.499951 -318.756463) (xy 147.612488 -318.853497) (xy 147.719655 -318.956432)
			(xy 147.821142 -319.064971) (xy 147.916656 -319.1788) (xy 148.005923 -319.297593) (xy 148.088684 -319.421005)
			(xy 148.164702 -319.548683) (xy 148.233757 -319.680256) (xy 148.29565 -319.815347) (xy 148.350203 -319.953564)
			(xy 148.397258 -320.094511) (xy 148.43668 -320.237781) (xy 148.468354 -320.38296) (xy 148.49219 -320.529629)
			(xy 148.508119 -320.677367) (xy 148.516095 -320.825747) (xy 148.516594 -320.900044) (xy 202.982331 -320.900044)
			(xy 202.98632 -320.751504) (xy 202.998277 -320.603391) (xy 203.018167 -320.456134) (xy 203.045932 -320.310158)
			(xy 203.081493 -320.165881) (xy 203.124747 -320.023722) (xy 203.175569 -319.884089) (xy 203.233813 -319.747386)
			(xy 203.299311 -319.614006) (xy 203.371874 -319.484334) (xy 203.451292 -319.358744) (xy 203.537337 -319.237597)
			(xy 203.629761 -319.121244) (xy 203.728297 -319.01002) (xy 203.832661 -318.904245) (xy 203.942553 -318.804225)
			(xy 204.057654 -318.710247) (xy 204.177634 -318.622583) (xy 204.302147 -318.541486) (xy 204.430833 -318.467189)
			(xy 204.563322 -318.399907) (xy 204.699231 -318.339833) (xy 204.838169 -318.287141) (xy 204.979735 -318.241982)
			(xy 205.123521 -318.204487) (xy 205.269112 -318.174765) (xy 205.416088 -318.1529) (xy 205.564027 -318.138956)
			(xy 205.7125 -318.132972) (xy 205.861081 -318.134967) (xy 206.00934 -318.144935) (xy 206.156851 -318.162846)
			(xy 206.303187 -318.188649) (xy 206.447928 -318.222269) (xy 206.590655 -318.263611) (xy 206.730958 -318.312554)
			(xy 206.868431 -318.368957) (xy 207.002678 -318.432658) (xy 207.133313 -318.503474) (xy 207.259958 -318.581199)
			(xy 207.382248 -318.66561) (xy 207.499831 -318.756463) (xy 207.612368 -318.853497) (xy 207.719535 -318.956432)
			(xy 207.821022 -319.064971) (xy 207.916536 -319.1788) (xy 208.005803 -319.297593) (xy 208.088564 -319.421005)
			(xy 208.164582 -319.548683) (xy 208.233637 -319.680256) (xy 208.29553 -319.815347) (xy 208.350083 -319.953564)
			(xy 208.397138 -320.094511) (xy 208.43656 -320.237781) (xy 208.468234 -320.38296) (xy 208.49207 -320.529629)
			(xy 208.507999 -320.677367) (xy 208.515975 -320.825747) (xy 208.516474 -320.900044) (xy 259.082549 -320.900044)
			(xy 259.086538 -320.751504) (xy 259.098495 -320.603391) (xy 259.118385 -320.456134) (xy 259.14615 -320.310158)
			(xy 259.181711 -320.165881) (xy 259.224965 -320.023722) (xy 259.275787 -319.884089) (xy 259.334031 -319.747386)
			(xy 259.399529 -319.614006) (xy 259.472092 -319.484334) (xy 259.55151 -319.358744) (xy 259.637555 -319.237597)
			(xy 259.729979 -319.121244) (xy 259.828515 -319.01002) (xy 259.932879 -318.904245) (xy 260.042771 -318.804225)
			(xy 260.157872 -318.710247) (xy 260.277852 -318.622583) (xy 260.402365 -318.541486) (xy 260.531051 -318.467189)
			(xy 260.66354 -318.399907) (xy 260.799449 -318.339833) (xy 260.938387 -318.287141) (xy 261.079953 -318.241982)
			(xy 261.223739 -318.204487) (xy 261.36933 -318.174765) (xy 261.516306 -318.1529) (xy 261.664245 -318.138956)
			(xy 261.812718 -318.132972) (xy 261.961299 -318.134967) (xy 262.109558 -318.144935) (xy 262.257069 -318.162846)
			(xy 262.403405 -318.188649) (xy 262.548146 -318.222269) (xy 262.690873 -318.263611) (xy 262.831176 -318.312554)
			(xy 262.968649 -318.368957) (xy 263.102896 -318.432658) (xy 263.233531 -318.503474) (xy 263.360176 -318.581199)
			(xy 263.482466 -318.66561) (xy 263.526839 -318.699896) (xy 306.744128 -318.699896) (xy 306.748088 -318.650842)
			(xy 306.759865 -318.603058) (xy 306.779156 -318.557782) (xy 306.805459 -318.516186) (xy 306.838094 -318.479349)
			(xy 306.876215 -318.448224) (xy 306.918836 -318.423617) (xy 306.964852 -318.406165) (xy 307.013071 -318.396321)
			(xy 307.062246 -318.39434) (xy 307.111101 -318.400272) (xy 307.158372 -318.413964) (xy 307.202834 -318.435062)
			(xy 307.243337 -318.463018) (xy 307.27883 -318.49711) (xy 307.308395 -318.536454) (xy 307.331266 -318.580031)
			(xy 307.34685 -318.626712) (xy 307.354745 -318.675289) (xy 307.35524 -318.699896) (xy 308.644048 -318.699896)
			(xy 308.648008 -318.650842) (xy 308.659785 -318.603058) (xy 308.679076 -318.557782) (xy 308.705379 -318.516186)
			(xy 308.738014 -318.479349) (xy 308.776135 -318.448224) (xy 308.818756 -318.423617) (xy 308.864772 -318.406165)
			(xy 308.912991 -318.396321) (xy 308.962166 -318.39434) (xy 309.011021 -318.400272) (xy 309.058292 -318.413964)
			(xy 309.102754 -318.435062) (xy 309.143257 -318.463018) (xy 309.17875 -318.49711) (xy 309.208315 -318.536454)
			(xy 309.231186 -318.580031) (xy 309.24677 -318.626712) (xy 309.254665 -318.675289) (xy 309.25516 -318.699896)
			(xy 310.543968 -318.699896) (xy 310.547928 -318.650842) (xy 310.559705 -318.603058) (xy 310.578996 -318.557782)
			(xy 310.605299 -318.516186) (xy 310.637934 -318.479349) (xy 310.676055 -318.448224) (xy 310.718676 -318.423617)
			(xy 310.764692 -318.406165) (xy 310.812911 -318.396321) (xy 310.862086 -318.39434) (xy 310.910941 -318.400272)
			(xy 310.958212 -318.413964) (xy 311.002674 -318.435062) (xy 311.043177 -318.463018) (xy 311.07867 -318.49711)
			(xy 311.108235 -318.536454) (xy 311.131106 -318.580031) (xy 311.14669 -318.626712) (xy 311.154585 -318.675289)
			(xy 311.15508 -318.699896) (xy 312.443888 -318.699896) (xy 312.447848 -318.650842) (xy 312.459625 -318.603058)
			(xy 312.478916 -318.557782) (xy 312.505219 -318.516186) (xy 312.537854 -318.479349) (xy 312.575975 -318.448224)
			(xy 312.618596 -318.423617) (xy 312.664612 -318.406165) (xy 312.712831 -318.396321) (xy 312.762006 -318.39434)
			(xy 312.810861 -318.400272) (xy 312.858132 -318.413964) (xy 312.902594 -318.435062) (xy 312.943097 -318.463018)
			(xy 312.97859 -318.49711) (xy 313.008155 -318.536454) (xy 313.031026 -318.580031) (xy 313.04661 -318.626712)
			(xy 313.054505 -318.675289) (xy 313.055 -318.699896) (xy 313.054505 -318.724503) (xy 313.04661 -318.77308)
			(xy 313.031026 -318.819761) (xy 313.008155 -318.863338) (xy 312.97859 -318.902682) (xy 312.943097 -318.936774)
			(xy 312.902594 -318.96473) (xy 312.858132 -318.985828) (xy 312.810861 -318.99952) (xy 312.762006 -319.005452)
			(xy 312.712831 -319.003471) (xy 312.664612 -318.993627) (xy 312.618596 -318.976175) (xy 312.575975 -318.951568)
			(xy 312.537854 -318.920443) (xy 312.505219 -318.883606) (xy 312.478916 -318.84201) (xy 312.459625 -318.796734)
			(xy 312.447848 -318.74895) (xy 312.443888 -318.699896) (xy 311.15508 -318.699896) (xy 311.154585 -318.724503)
			(xy 311.14669 -318.77308) (xy 311.131106 -318.819761) (xy 311.108235 -318.863338) (xy 311.07867 -318.902682)
			(xy 311.043177 -318.936774) (xy 311.002674 -318.96473) (xy 310.958212 -318.985828) (xy 310.910941 -318.99952)
			(xy 310.862086 -319.005452) (xy 310.812911 -319.003471) (xy 310.764692 -318.993627) (xy 310.718676 -318.976175)
			(xy 310.676055 -318.951568) (xy 310.637934 -318.920443) (xy 310.605299 -318.883606) (xy 310.578996 -318.84201)
			(xy 310.559705 -318.796734) (xy 310.547928 -318.74895) (xy 310.543968 -318.699896) (xy 309.25516 -318.699896)
			(xy 309.254665 -318.724503) (xy 309.24677 -318.77308) (xy 309.231186 -318.819761) (xy 309.208315 -318.863338)
			(xy 309.17875 -318.902682) (xy 309.143257 -318.936774) (xy 309.102754 -318.96473) (xy 309.058292 -318.985828)
			(xy 309.011021 -318.99952) (xy 308.962166 -319.005452) (xy 308.912991 -319.003471) (xy 308.864772 -318.993627)
			(xy 308.818756 -318.976175) (xy 308.776135 -318.951568) (xy 308.738014 -318.920443) (xy 308.705379 -318.883606)
			(xy 308.679076 -318.84201) (xy 308.659785 -318.796734) (xy 308.648008 -318.74895) (xy 308.644048 -318.699896)
			(xy 307.35524 -318.699896) (xy 307.354745 -318.724503) (xy 307.34685 -318.77308) (xy 307.331266 -318.819761)
			(xy 307.308395 -318.863338) (xy 307.27883 -318.902682) (xy 307.243337 -318.936774) (xy 307.202834 -318.96473)
			(xy 307.158372 -318.985828) (xy 307.111101 -318.99952) (xy 307.062246 -319.005452) (xy 307.013071 -319.003471)
			(xy 306.964852 -318.993627) (xy 306.918836 -318.976175) (xy 306.876215 -318.951568) (xy 306.838094 -318.920443)
			(xy 306.805459 -318.883606) (xy 306.779156 -318.84201) (xy 306.759865 -318.796734) (xy 306.748088 -318.74895)
			(xy 306.744128 -318.699896) (xy 263.526839 -318.699896) (xy 263.600049 -318.756463) (xy 263.712586 -318.853497)
			(xy 263.819753 -318.956432) (xy 263.92124 -319.064971) (xy 264.016754 -319.1788) (xy 264.106021 -319.297593)
			(xy 264.188782 -319.421005) (xy 264.2648 -319.548683) (xy 264.333855 -319.680256) (xy 264.395748 -319.815347)
			(xy 264.450301 -319.953564) (xy 264.497356 -320.094511) (xy 264.536778 -320.237781) (xy 264.568452 -320.38296)
			(xy 264.592288 -320.529629) (xy 264.608217 -320.677367) (xy 264.616193 -320.825747) (xy 264.616692 -320.900044)
			(xy 319.082429 -320.900044) (xy 319.086418 -320.751504) (xy 319.098375 -320.603391) (xy 319.118265 -320.456134)
			(xy 319.14603 -320.310158) (xy 319.181591 -320.165881) (xy 319.224845 -320.023722) (xy 319.275667 -319.884089)
			(xy 319.333911 -319.747386) (xy 319.399409 -319.614006) (xy 319.471972 -319.484334) (xy 319.55139 -319.358744)
			(xy 319.637435 -319.237597) (xy 319.729859 -319.121244) (xy 319.828395 -319.01002) (xy 319.932759 -318.904245)
			(xy 320.042651 -318.804225) (xy 320.157752 -318.710247) (xy 320.277732 -318.622583) (xy 320.402245 -318.541486)
			(xy 320.530931 -318.467189) (xy 320.66342 -318.399907) (xy 320.799329 -318.339833) (xy 320.938267 -318.287141)
			(xy 321.079833 -318.241982) (xy 321.223619 -318.204487) (xy 321.36921 -318.174765) (xy 321.516186 -318.1529)
			(xy 321.664125 -318.138956) (xy 321.812598 -318.132972) (xy 321.961179 -318.134967) (xy 322.109438 -318.144935)
			(xy 322.256949 -318.162846) (xy 322.403285 -318.188649) (xy 322.548026 -318.222269) (xy 322.690753 -318.263611)
			(xy 322.831056 -318.312554) (xy 322.968529 -318.368957) (xy 323.102776 -318.432658) (xy 323.233411 -318.503474)
			(xy 323.360056 -318.581199) (xy 323.482346 -318.66561) (xy 323.599929 -318.756463) (xy 323.712466 -318.853497)
			(xy 323.819633 -318.956432) (xy 323.92112 -319.064971) (xy 324.016634 -319.1788) (xy 324.105901 -319.297593)
			(xy 324.188662 -319.421005) (xy 324.26468 -319.548683) (xy 324.333735 -319.680256) (xy 324.395628 -319.815347)
			(xy 324.450181 -319.953564) (xy 324.497236 -320.094511) (xy 324.536658 -320.237781) (xy 324.568332 -320.38296)
			(xy 324.592168 -320.529629) (xy 324.608097 -320.677367) (xy 324.616073 -320.825747) (xy 324.616572 -320.900044)
			(xy 375.182393 -320.900044) (xy 375.186382 -320.751504) (xy 375.198339 -320.603391) (xy 375.218229 -320.456134)
			(xy 375.245994 -320.310158) (xy 375.281555 -320.165881) (xy 375.324809 -320.023722) (xy 375.375631 -319.884089)
			(xy 375.433875 -319.747386) (xy 375.499373 -319.614006) (xy 375.571936 -319.484334) (xy 375.651354 -319.358744)
			(xy 375.737399 -319.237597) (xy 375.829823 -319.121244) (xy 375.928359 -319.01002) (xy 376.032723 -318.904245)
			(xy 376.142615 -318.804225) (xy 376.257716 -318.710247) (xy 376.377696 -318.622583) (xy 376.502209 -318.541486)
			(xy 376.630895 -318.467189) (xy 376.763384 -318.399907) (xy 376.899293 -318.339833) (xy 377.038231 -318.287141)
			(xy 377.179797 -318.241982) (xy 377.323583 -318.204487) (xy 377.469174 -318.174765) (xy 377.61615 -318.1529)
			(xy 377.764089 -318.138956) (xy 377.912562 -318.132972) (xy 378.061143 -318.134967) (xy 378.209402 -318.144935)
			(xy 378.356913 -318.162846) (xy 378.503249 -318.188649) (xy 378.64799 -318.222269) (xy 378.790717 -318.263611)
			(xy 378.93102 -318.312554) (xy 379.068493 -318.368957) (xy 379.20274 -318.432658) (xy 379.333375 -318.503474)
			(xy 379.46002 -318.581199) (xy 379.58231 -318.66561) (xy 379.626683 -318.699896) (xy 392.443982 -318.699896)
			(xy 392.447942 -318.650842) (xy 392.459719 -318.603058) (xy 392.47901 -318.557782) (xy 392.505313 -318.516186)
			(xy 392.537948 -318.479349) (xy 392.576069 -318.448224) (xy 392.61869 -318.423617) (xy 392.664706 -318.406165)
			(xy 392.712925 -318.396321) (xy 392.7621 -318.39434) (xy 392.810955 -318.400272) (xy 392.858226 -318.413964)
			(xy 392.902688 -318.435062) (xy 392.943191 -318.463018) (xy 392.978684 -318.49711) (xy 393.008249 -318.536454)
			(xy 393.03112 -318.580031) (xy 393.046704 -318.626712) (xy 393.054599 -318.675289) (xy 393.055094 -318.699896)
			(xy 394.344156 -318.699896) (xy 394.348116 -318.650842) (xy 394.359893 -318.603058) (xy 394.379184 -318.557782)
			(xy 394.405487 -318.516186) (xy 394.438122 -318.479349) (xy 394.476243 -318.448224) (xy 394.518864 -318.423617)
			(xy 394.56488 -318.406165) (xy 394.613099 -318.396321) (xy 394.662274 -318.39434) (xy 394.711129 -318.400272)
			(xy 394.7584 -318.413964) (xy 394.802862 -318.435062) (xy 394.843365 -318.463018) (xy 394.878858 -318.49711)
			(xy 394.908423 -318.536454) (xy 394.931294 -318.580031) (xy 394.946878 -318.626712) (xy 394.954773 -318.675289)
			(xy 394.955268 -318.699896) (xy 396.244076 -318.699896) (xy 396.248036 -318.650842) (xy 396.259813 -318.603058)
			(xy 396.279104 -318.557782) (xy 396.305407 -318.516186) (xy 396.338042 -318.479349) (xy 396.376163 -318.448224)
			(xy 396.418784 -318.423617) (xy 396.4648 -318.406165) (xy 396.513019 -318.396321) (xy 396.562194 -318.39434)
			(xy 396.611049 -318.400272) (xy 396.65832 -318.413964) (xy 396.702782 -318.435062) (xy 396.743285 -318.463018)
			(xy 396.778778 -318.49711) (xy 396.808343 -318.536454) (xy 396.831214 -318.580031) (xy 396.846798 -318.626712)
			(xy 396.854693 -318.675289) (xy 396.855188 -318.699896) (xy 398.143996 -318.699896) (xy 398.147956 -318.650842)
			(xy 398.159733 -318.603058) (xy 398.179024 -318.557782) (xy 398.205327 -318.516186) (xy 398.237962 -318.479349)
			(xy 398.276083 -318.448224) (xy 398.318704 -318.423617) (xy 398.36472 -318.406165) (xy 398.412939 -318.396321)
			(xy 398.462114 -318.39434) (xy 398.510969 -318.400272) (xy 398.55824 -318.413964) (xy 398.602702 -318.435062)
			(xy 398.643205 -318.463018) (xy 398.678698 -318.49711) (xy 398.708263 -318.536454) (xy 398.731134 -318.580031)
			(xy 398.746718 -318.626712) (xy 398.754613 -318.675289) (xy 398.755108 -318.699896) (xy 415.244038 -318.699896)
			(xy 415.247998 -318.650842) (xy 415.259775 -318.603058) (xy 415.279066 -318.557782) (xy 415.305369 -318.516186)
			(xy 415.338004 -318.479349) (xy 415.376125 -318.448224) (xy 415.418746 -318.423617) (xy 415.464762 -318.406165)
			(xy 415.512981 -318.396321) (xy 415.562156 -318.39434) (xy 415.611011 -318.400272) (xy 415.658282 -318.413964)
			(xy 415.702744 -318.435062) (xy 415.743247 -318.463018) (xy 415.77874 -318.49711) (xy 415.808305 -318.536454)
			(xy 415.831176 -318.580031) (xy 415.84676 -318.626712) (xy 415.854655 -318.675289) (xy 415.85515 -318.699896)
			(xy 417.144212 -318.699896) (xy 417.148172 -318.650842) (xy 417.159949 -318.603058) (xy 417.17924 -318.557782)
			(xy 417.205543 -318.516186) (xy 417.238178 -318.479349) (xy 417.276299 -318.448224) (xy 417.31892 -318.423617)
			(xy 417.364936 -318.406165) (xy 417.413155 -318.396321) (xy 417.46233 -318.39434) (xy 417.511185 -318.400272)
			(xy 417.558456 -318.413964) (xy 417.602918 -318.435062) (xy 417.643421 -318.463018) (xy 417.678914 -318.49711)
			(xy 417.708479 -318.536454) (xy 417.73135 -318.580031) (xy 417.746934 -318.626712) (xy 417.754829 -318.675289)
			(xy 417.755324 -318.699896) (xy 419.044132 -318.699896) (xy 419.048092 -318.650842) (xy 419.059869 -318.603058)
			(xy 419.07916 -318.557782) (xy 419.105463 -318.516186) (xy 419.138098 -318.479349) (xy 419.176219 -318.448224)
			(xy 419.21884 -318.423617) (xy 419.264856 -318.406165) (xy 419.313075 -318.396321) (xy 419.36225 -318.39434)
			(xy 419.411105 -318.400272) (xy 419.458376 -318.413964) (xy 419.502838 -318.435062) (xy 419.543341 -318.463018)
			(xy 419.578834 -318.49711) (xy 419.608399 -318.536454) (xy 419.63127 -318.580031) (xy 419.646854 -318.626712)
			(xy 419.654749 -318.675289) (xy 419.655244 -318.699896) (xy 420.944052 -318.699896) (xy 420.948012 -318.650842)
			(xy 420.959789 -318.603058) (xy 420.97908 -318.557782) (xy 421.005383 -318.516186) (xy 421.038018 -318.479349)
			(xy 421.076139 -318.448224) (xy 421.11876 -318.423617) (xy 421.164776 -318.406165) (xy 421.212995 -318.396321)
			(xy 421.26217 -318.39434) (xy 421.311025 -318.400272) (xy 421.358296 -318.413964) (xy 421.402758 -318.435062)
			(xy 421.443261 -318.463018) (xy 421.478754 -318.49711) (xy 421.508319 -318.536454) (xy 421.53119 -318.580031)
			(xy 421.546774 -318.626712) (xy 421.554669 -318.675289) (xy 421.555164 -318.699896) (xy 421.554669 -318.724503)
			(xy 421.546774 -318.77308) (xy 421.53119 -318.819761) (xy 421.508319 -318.863338) (xy 421.478754 -318.902682)
			(xy 421.443261 -318.936774) (xy 421.402758 -318.96473) (xy 421.358296 -318.985828) (xy 421.311025 -318.99952)
			(xy 421.26217 -319.005452) (xy 421.212995 -319.003471) (xy 421.164776 -318.993627) (xy 421.11876 -318.976175)
			(xy 421.076139 -318.951568) (xy 421.038018 -318.920443) (xy 421.005383 -318.883606) (xy 420.97908 -318.84201)
			(xy 420.959789 -318.796734) (xy 420.948012 -318.74895) (xy 420.944052 -318.699896) (xy 419.655244 -318.699896)
			(xy 419.654749 -318.724503) (xy 419.646854 -318.77308) (xy 419.63127 -318.819761) (xy 419.608399 -318.863338)
			(xy 419.578834 -318.902682) (xy 419.543341 -318.936774) (xy 419.502838 -318.96473) (xy 419.458376 -318.985828)
			(xy 419.411105 -318.99952) (xy 419.36225 -319.005452) (xy 419.313075 -319.003471) (xy 419.264856 -318.993627)
			(xy 419.21884 -318.976175) (xy 419.176219 -318.951568) (xy 419.138098 -318.920443) (xy 419.105463 -318.883606)
			(xy 419.07916 -318.84201) (xy 419.059869 -318.796734) (xy 419.048092 -318.74895) (xy 419.044132 -318.699896)
			(xy 417.755324 -318.699896) (xy 417.754829 -318.724503) (xy 417.746934 -318.77308) (xy 417.73135 -318.819761)
			(xy 417.708479 -318.863338) (xy 417.678914 -318.902682) (xy 417.643421 -318.936774) (xy 417.602918 -318.96473)
			(xy 417.558456 -318.985828) (xy 417.511185 -318.99952) (xy 417.46233 -319.005452) (xy 417.413155 -319.003471)
			(xy 417.364936 -318.993627) (xy 417.31892 -318.976175) (xy 417.276299 -318.951568) (xy 417.238178 -318.920443)
			(xy 417.205543 -318.883606) (xy 417.17924 -318.84201) (xy 417.159949 -318.796734) (xy 417.148172 -318.74895)
			(xy 417.144212 -318.699896) (xy 415.85515 -318.699896) (xy 415.854655 -318.724503) (xy 415.84676 -318.77308)
			(xy 415.831176 -318.819761) (xy 415.808305 -318.863338) (xy 415.77874 -318.902682) (xy 415.743247 -318.936774)
			(xy 415.702744 -318.96473) (xy 415.658282 -318.985828) (xy 415.611011 -318.99952) (xy 415.562156 -319.005452)
			(xy 415.512981 -319.003471) (xy 415.464762 -318.993627) (xy 415.418746 -318.976175) (xy 415.376125 -318.951568)
			(xy 415.338004 -318.920443) (xy 415.305369 -318.883606) (xy 415.279066 -318.84201) (xy 415.259775 -318.796734)
			(xy 415.247998 -318.74895) (xy 415.244038 -318.699896) (xy 398.755108 -318.699896) (xy 398.754613 -318.724503)
			(xy 398.746718 -318.77308) (xy 398.731134 -318.819761) (xy 398.708263 -318.863338) (xy 398.678698 -318.902682)
			(xy 398.643205 -318.936774) (xy 398.602702 -318.96473) (xy 398.55824 -318.985828) (xy 398.510969 -318.99952)
			(xy 398.462114 -319.005452) (xy 398.412939 -319.003471) (xy 398.36472 -318.993627) (xy 398.318704 -318.976175)
			(xy 398.276083 -318.951568) (xy 398.237962 -318.920443) (xy 398.205327 -318.883606) (xy 398.179024 -318.84201)
			(xy 398.159733 -318.796734) (xy 398.147956 -318.74895) (xy 398.143996 -318.699896) (xy 396.855188 -318.699896)
			(xy 396.854693 -318.724503) (xy 396.846798 -318.77308) (xy 396.831214 -318.819761) (xy 396.808343 -318.863338)
			(xy 396.778778 -318.902682) (xy 396.743285 -318.936774) (xy 396.702782 -318.96473) (xy 396.65832 -318.985828)
			(xy 396.611049 -318.99952) (xy 396.562194 -319.005452) (xy 396.513019 -319.003471) (xy 396.4648 -318.993627)
			(xy 396.418784 -318.976175) (xy 396.376163 -318.951568) (xy 396.338042 -318.920443) (xy 396.305407 -318.883606)
			(xy 396.279104 -318.84201) (xy 396.259813 -318.796734) (xy 396.248036 -318.74895) (xy 396.244076 -318.699896)
			(xy 394.955268 -318.699896) (xy 394.954773 -318.724503) (xy 394.946878 -318.77308) (xy 394.931294 -318.819761)
			(xy 394.908423 -318.863338) (xy 394.878858 -318.902682) (xy 394.843365 -318.936774) (xy 394.802862 -318.96473)
			(xy 394.7584 -318.985828) (xy 394.711129 -318.99952) (xy 394.662274 -319.005452) (xy 394.613099 -319.003471)
			(xy 394.56488 -318.993627) (xy 394.518864 -318.976175) (xy 394.476243 -318.951568) (xy 394.438122 -318.920443)
			(xy 394.405487 -318.883606) (xy 394.379184 -318.84201) (xy 394.359893 -318.796734) (xy 394.348116 -318.74895)
			(xy 394.344156 -318.699896) (xy 393.055094 -318.699896) (xy 393.054599 -318.724503) (xy 393.046704 -318.77308)
			(xy 393.03112 -318.819761) (xy 393.008249 -318.863338) (xy 392.978684 -318.902682) (xy 392.943191 -318.936774)
			(xy 392.902688 -318.96473) (xy 392.858226 -318.985828) (xy 392.810955 -318.99952) (xy 392.7621 -319.005452)
			(xy 392.712925 -319.003471) (xy 392.664706 -318.993627) (xy 392.61869 -318.976175) (xy 392.576069 -318.951568)
			(xy 392.537948 -318.920443) (xy 392.505313 -318.883606) (xy 392.47901 -318.84201) (xy 392.459719 -318.796734)
			(xy 392.447942 -318.74895) (xy 392.443982 -318.699896) (xy 379.626683 -318.699896) (xy 379.699893 -318.756463)
			(xy 379.81243 -318.853497) (xy 379.919597 -318.956432) (xy 380.021084 -319.064971) (xy 380.116598 -319.1788)
			(xy 380.205865 -319.297593) (xy 380.288626 -319.421005) (xy 380.364644 -319.548683) (xy 380.433699 -319.680256)
			(xy 380.495592 -319.815347) (xy 380.550145 -319.953564) (xy 380.5972 -320.094511) (xy 380.636622 -320.237781)
			(xy 380.668296 -320.38296) (xy 380.692132 -320.529629) (xy 380.708061 -320.677367) (xy 380.716037 -320.825747)
			(xy 380.716536 -320.900044) (xy 435.182527 -320.900044) (xy 435.186516 -320.751504) (xy 435.198473 -320.603391)
			(xy 435.218363 -320.456134) (xy 435.246128 -320.310158) (xy 435.281689 -320.165881) (xy 435.324943 -320.023722)
			(xy 435.375765 -319.884089) (xy 435.434009 -319.747386) (xy 435.499507 -319.614006) (xy 435.57207 -319.484334)
			(xy 435.651488 -319.358744) (xy 435.737533 -319.237597) (xy 435.829957 -319.121244) (xy 435.928493 -319.01002)
			(xy 436.032857 -318.904245) (xy 436.142749 -318.804225) (xy 436.25785 -318.710247) (xy 436.37783 -318.622583)
			(xy 436.502343 -318.541486) (xy 436.631029 -318.467189) (xy 436.763518 -318.399907) (xy 436.899427 -318.339833)
			(xy 437.038365 -318.287141) (xy 437.179931 -318.241982) (xy 437.323717 -318.204487) (xy 437.469308 -318.174765)
			(xy 437.616284 -318.1529) (xy 437.764223 -318.138956) (xy 437.912696 -318.132972) (xy 438.061277 -318.134967)
			(xy 438.209536 -318.144935) (xy 438.357047 -318.162846) (xy 438.503383 -318.188649) (xy 438.648124 -318.222269)
			(xy 438.790851 -318.263611) (xy 438.931154 -318.312554) (xy 439.068627 -318.368957) (xy 439.202874 -318.432658)
			(xy 439.333509 -318.503474) (xy 439.460154 -318.581199) (xy 439.582444 -318.66561) (xy 439.700027 -318.756463)
			(xy 439.812564 -318.853497) (xy 439.919731 -318.956432) (xy 440.021218 -319.064971) (xy 440.116732 -319.1788)
			(xy 440.205999 -319.297593) (xy 440.28876 -319.421005) (xy 440.364778 -319.548683) (xy 440.433833 -319.680256)
			(xy 440.495726 -319.815347) (xy 440.550279 -319.953564) (xy 440.597334 -320.094511) (xy 440.636756 -320.237781)
			(xy 440.66843 -320.38296) (xy 440.692266 -320.529629) (xy 440.708195 -320.677367) (xy 440.716171 -320.825747)
			(xy 440.71667 -320.900044) (xy 440.716171 -320.974341) (xy 440.708195 -321.122721) (xy 440.692266 -321.270459)
			(xy 440.66843 -321.417128) (xy 440.636756 -321.562307) (xy 440.597334 -321.705577) (xy 440.550279 -321.846524)
			(xy 440.495726 -321.984741) (xy 440.433833 -322.119832) (xy 440.364778 -322.251405) (xy 440.28876 -322.379083)
			(xy 440.205999 -322.502495) (xy 440.116732 -322.621288) (xy 440.021218 -322.735117) (xy 439.919731 -322.843656)
			(xy 439.812564 -322.946591) (xy 439.700027 -323.043625) (xy 439.582444 -323.134478) (xy 439.460154 -323.218889)
			(xy 439.333509 -323.296614) (xy 439.202874 -323.36743) (xy 439.068627 -323.431131) (xy 438.931154 -323.487534)
			(xy 438.790851 -323.536477) (xy 438.648124 -323.577819) (xy 438.503383 -323.611439) (xy 438.357047 -323.637242)
			(xy 438.209536 -323.655153) (xy 438.061277 -323.665121) (xy 437.912696 -323.667116) (xy 437.764223 -323.661132)
			(xy 437.616284 -323.647188) (xy 437.469308 -323.625323) (xy 437.323717 -323.595601) (xy 437.179931 -323.558106)
			(xy 437.038365 -323.512947) (xy 436.899427 -323.460255) (xy 436.763518 -323.400181) (xy 436.631029 -323.332899)
			(xy 436.502343 -323.258602) (xy 436.37783 -323.177505) (xy 436.25785 -323.089841) (xy 436.142749 -322.995863)
			(xy 436.032857 -322.895843) (xy 435.928493 -322.790068) (xy 435.829957 -322.678844) (xy 435.737533 -322.562491)
			(xy 435.651488 -322.441344) (xy 435.57207 -322.315754) (xy 435.499507 -322.186082) (xy 435.434009 -322.052702)
			(xy 435.375765 -321.915999) (xy 435.324943 -321.776366) (xy 435.281689 -321.634207) (xy 435.246128 -321.48993)
			(xy 435.218363 -321.343954) (xy 435.198473 -321.196697) (xy 435.186516 -321.048584) (xy 435.182527 -320.900044)
			(xy 380.716536 -320.900044) (xy 380.716037 -320.974341) (xy 380.708061 -321.122721) (xy 380.692132 -321.270459)
			(xy 380.668296 -321.417128) (xy 380.636622 -321.562307) (xy 380.5972 -321.705577) (xy 380.550145 -321.846524)
			(xy 380.495592 -321.984741) (xy 380.433699 -322.119832) (xy 380.364644 -322.251405) (xy 380.288626 -322.379083)
			(xy 380.205865 -322.502495) (xy 380.116598 -322.621288) (xy 380.021084 -322.735117) (xy 379.919597 -322.843656)
			(xy 379.81243 -322.946591) (xy 379.699893 -323.043625) (xy 379.58231 -323.134478) (xy 379.46002 -323.218889)
			(xy 379.333375 -323.296614) (xy 379.20274 -323.36743) (xy 379.068493 -323.431131) (xy 378.93102 -323.487534)
			(xy 378.790717 -323.536477) (xy 378.64799 -323.577819) (xy 378.503249 -323.611439) (xy 378.356913 -323.637242)
			(xy 378.209402 -323.655153) (xy 378.061143 -323.665121) (xy 377.912562 -323.667116) (xy 377.764089 -323.661132)
			(xy 377.61615 -323.647188) (xy 377.469174 -323.625323) (xy 377.323583 -323.595601) (xy 377.179797 -323.558106)
			(xy 377.038231 -323.512947) (xy 376.899293 -323.460255) (xy 376.763384 -323.400181) (xy 376.630895 -323.332899)
			(xy 376.502209 -323.258602) (xy 376.377696 -323.177505) (xy 376.257716 -323.089841) (xy 376.142615 -322.995863)
			(xy 376.032723 -322.895843) (xy 375.928359 -322.790068) (xy 375.829823 -322.678844) (xy 375.737399 -322.562491)
			(xy 375.651354 -322.441344) (xy 375.571936 -322.315754) (xy 375.499373 -322.186082) (xy 375.433875 -322.052702)
			(xy 375.375631 -321.915999) (xy 375.324809 -321.776366) (xy 375.281555 -321.634207) (xy 375.245994 -321.48993)
			(xy 375.218229 -321.343954) (xy 375.198339 -321.196697) (xy 375.186382 -321.048584) (xy 375.182393 -320.900044)
			(xy 324.616572 -320.900044) (xy 324.616073 -320.974341) (xy 324.608097 -321.122721) (xy 324.592168 -321.270459)
			(xy 324.568332 -321.417128) (xy 324.536658 -321.562307) (xy 324.497236 -321.705577) (xy 324.450181 -321.846524)
			(xy 324.395628 -321.984741) (xy 324.333735 -322.119832) (xy 324.26468 -322.251405) (xy 324.188662 -322.379083)
			(xy 324.105901 -322.502495) (xy 324.016634 -322.621288) (xy 323.92112 -322.735117) (xy 323.819633 -322.843656)
			(xy 323.712466 -322.946591) (xy 323.599929 -323.043625) (xy 323.482346 -323.134478) (xy 323.360056 -323.218889)
			(xy 323.233411 -323.296614) (xy 323.102776 -323.36743) (xy 322.968529 -323.431131) (xy 322.831056 -323.487534)
			(xy 322.690753 -323.536477) (xy 322.548026 -323.577819) (xy 322.403285 -323.611439) (xy 322.256949 -323.637242)
			(xy 322.109438 -323.655153) (xy 321.961179 -323.665121) (xy 321.812598 -323.667116) (xy 321.664125 -323.661132)
			(xy 321.516186 -323.647188) (xy 321.36921 -323.625323) (xy 321.223619 -323.595601) (xy 321.079833 -323.558106)
			(xy 320.938267 -323.512947) (xy 320.799329 -323.460255) (xy 320.66342 -323.400181) (xy 320.530931 -323.332899)
			(xy 320.402245 -323.258602) (xy 320.277732 -323.177505) (xy 320.157752 -323.089841) (xy 320.042651 -322.995863)
			(xy 319.932759 -322.895843) (xy 319.828395 -322.790068) (xy 319.729859 -322.678844) (xy 319.637435 -322.562491)
			(xy 319.55139 -322.441344) (xy 319.471972 -322.315754) (xy 319.399409 -322.186082) (xy 319.333911 -322.052702)
			(xy 319.275667 -321.915999) (xy 319.224845 -321.776366) (xy 319.181591 -321.634207) (xy 319.14603 -321.48993)
			(xy 319.118265 -321.343954) (xy 319.098375 -321.196697) (xy 319.086418 -321.048584) (xy 319.082429 -320.900044)
			(xy 264.616692 -320.900044) (xy 264.616193 -320.974341) (xy 264.608217 -321.122721) (xy 264.592288 -321.270459)
			(xy 264.568452 -321.417128) (xy 264.536778 -321.562307) (xy 264.497356 -321.705577) (xy 264.450301 -321.846524)
			(xy 264.395748 -321.984741) (xy 264.333855 -322.119832) (xy 264.2648 -322.251405) (xy 264.188782 -322.379083)
			(xy 264.106021 -322.502495) (xy 264.016754 -322.621288) (xy 263.92124 -322.735117) (xy 263.819753 -322.843656)
			(xy 263.712586 -322.946591) (xy 263.600049 -323.043625) (xy 263.482466 -323.134478) (xy 263.360176 -323.218889)
			(xy 263.233531 -323.296614) (xy 263.102896 -323.36743) (xy 262.968649 -323.431131) (xy 262.831176 -323.487534)
			(xy 262.690873 -323.536477) (xy 262.548146 -323.577819) (xy 262.403405 -323.611439) (xy 262.257069 -323.637242)
			(xy 262.109558 -323.655153) (xy 261.961299 -323.665121) (xy 261.812718 -323.667116) (xy 261.664245 -323.661132)
			(xy 261.516306 -323.647188) (xy 261.36933 -323.625323) (xy 261.223739 -323.595601) (xy 261.079953 -323.558106)
			(xy 260.938387 -323.512947) (xy 260.799449 -323.460255) (xy 260.66354 -323.400181) (xy 260.531051 -323.332899)
			(xy 260.402365 -323.258602) (xy 260.277852 -323.177505) (xy 260.157872 -323.089841) (xy 260.042771 -322.995863)
			(xy 259.932879 -322.895843) (xy 259.828515 -322.790068) (xy 259.729979 -322.678844) (xy 259.637555 -322.562491)
			(xy 259.55151 -322.441344) (xy 259.472092 -322.315754) (xy 259.399529 -322.186082) (xy 259.334031 -322.052702)
			(xy 259.275787 -321.915999) (xy 259.224965 -321.776366) (xy 259.181711 -321.634207) (xy 259.14615 -321.48993)
			(xy 259.118385 -321.343954) (xy 259.098495 -321.196697) (xy 259.086538 -321.048584) (xy 259.082549 -320.900044)
			(xy 208.516474 -320.900044) (xy 208.515975 -320.974341) (xy 208.507999 -321.122721) (xy 208.49207 -321.270459)
			(xy 208.468234 -321.417128) (xy 208.43656 -321.562307) (xy 208.397138 -321.705577) (xy 208.350083 -321.846524)
			(xy 208.29553 -321.984741) (xy 208.233637 -322.119832) (xy 208.164582 -322.251405) (xy 208.088564 -322.379083)
			(xy 208.005803 -322.502495) (xy 207.916536 -322.621288) (xy 207.821022 -322.735117) (xy 207.719535 -322.843656)
			(xy 207.612368 -322.946591) (xy 207.499831 -323.043625) (xy 207.382248 -323.134478) (xy 207.259958 -323.218889)
			(xy 207.133313 -323.296614) (xy 207.002678 -323.36743) (xy 206.868431 -323.431131) (xy 206.730958 -323.487534)
			(xy 206.590655 -323.536477) (xy 206.447928 -323.577819) (xy 206.303187 -323.611439) (xy 206.156851 -323.637242)
			(xy 206.00934 -323.655153) (xy 205.861081 -323.665121) (xy 205.7125 -323.667116) (xy 205.564027 -323.661132)
			(xy 205.416088 -323.647188) (xy 205.269112 -323.625323) (xy 205.123521 -323.595601) (xy 204.979735 -323.558106)
			(xy 204.838169 -323.512947) (xy 204.699231 -323.460255) (xy 204.563322 -323.400181) (xy 204.430833 -323.332899)
			(xy 204.302147 -323.258602) (xy 204.177634 -323.177505) (xy 204.057654 -323.089841) (xy 203.942553 -322.995863)
			(xy 203.832661 -322.895843) (xy 203.728297 -322.790068) (xy 203.629761 -322.678844) (xy 203.537337 -322.562491)
			(xy 203.451292 -322.441344) (xy 203.371874 -322.315754) (xy 203.299311 -322.186082) (xy 203.233813 -322.052702)
			(xy 203.175569 -321.915999) (xy 203.124747 -321.776366) (xy 203.081493 -321.634207) (xy 203.045932 -321.48993)
			(xy 203.018167 -321.343954) (xy 202.998277 -321.196697) (xy 202.98632 -321.048584) (xy 202.982331 -320.900044)
			(xy 148.516594 -320.900044) (xy 148.516095 -320.974341) (xy 148.508119 -321.122721) (xy 148.49219 -321.270459)
			(xy 148.468354 -321.417128) (xy 148.43668 -321.562307) (xy 148.397258 -321.705577) (xy 148.350203 -321.846524)
			(xy 148.29565 -321.984741) (xy 148.233757 -322.119832) (xy 148.164702 -322.251405) (xy 148.088684 -322.379083)
			(xy 148.005923 -322.502495) (xy 147.916656 -322.621288) (xy 147.821142 -322.735117) (xy 147.719655 -322.843656)
			(xy 147.612488 -322.946591) (xy 147.499951 -323.043625) (xy 147.382368 -323.134478) (xy 147.260078 -323.218889)
			(xy 147.133433 -323.296614) (xy 147.002798 -323.36743) (xy 146.868551 -323.431131) (xy 146.731078 -323.487534)
			(xy 146.590775 -323.536477) (xy 146.448048 -323.577819) (xy 146.303307 -323.611439) (xy 146.156971 -323.637242)
			(xy 146.00946 -323.655153) (xy 145.861201 -323.665121) (xy 145.71262 -323.667116) (xy 145.564147 -323.661132)
			(xy 145.416208 -323.647188) (xy 145.269232 -323.625323) (xy 145.123641 -323.595601) (xy 144.979855 -323.558106)
			(xy 144.838289 -323.512947) (xy 144.699351 -323.460255) (xy 144.563442 -323.400181) (xy 144.430953 -323.332899)
			(xy 144.302267 -323.258602) (xy 144.177754 -323.177505) (xy 144.057774 -323.089841) (xy 143.942673 -322.995863)
			(xy 143.832781 -322.895843) (xy 143.728417 -322.790068) (xy 143.629881 -322.678844) (xy 143.537457 -322.562491)
			(xy 143.451412 -322.441344) (xy 143.371994 -322.315754) (xy 143.299431 -322.186082) (xy 143.233933 -322.052702)
			(xy 143.175689 -321.915999) (xy 143.124867 -321.776366) (xy 143.081613 -321.634207) (xy 143.046052 -321.48993)
			(xy 143.018287 -321.343954) (xy 142.998397 -321.196697) (xy 142.98644 -321.048584) (xy 142.982451 -320.900044)
			(xy 92.41663 -320.900044) (xy 92.416131 -320.974341) (xy 92.408155 -321.122721) (xy 92.392226 -321.270459)
			(xy 92.36839 -321.417128) (xy 92.336716 -321.562307) (xy 92.297294 -321.705577) (xy 92.250239 -321.846524)
			(xy 92.195686 -321.984741) (xy 92.133793 -322.119832) (xy 92.064738 -322.251405) (xy 91.98872 -322.379083)
			(xy 91.905959 -322.502495) (xy 91.816692 -322.621288) (xy 91.721178 -322.735117) (xy 91.619691 -322.843656)
			(xy 91.512524 -322.946591) (xy 91.399987 -323.043625) (xy 91.282404 -323.134478) (xy 91.160114 -323.218889)
			(xy 91.033469 -323.296614) (xy 90.902834 -323.36743) (xy 90.768587 -323.431131) (xy 90.631114 -323.487534)
			(xy 90.490811 -323.536477) (xy 90.348084 -323.577819) (xy 90.203343 -323.611439) (xy 90.057007 -323.637242)
			(xy 89.909496 -323.655153) (xy 89.761237 -323.665121) (xy 89.612656 -323.667116) (xy 89.464183 -323.661132)
			(xy 89.316244 -323.647188) (xy 89.169268 -323.625323) (xy 89.023677 -323.595601) (xy 88.879891 -323.558106)
			(xy 88.738325 -323.512947) (xy 88.599387 -323.460255) (xy 88.463478 -323.400181) (xy 88.330989 -323.332899)
			(xy 88.202303 -323.258602) (xy 88.07779 -323.177505) (xy 87.95781 -323.089841) (xy 87.842709 -322.995863)
			(xy 87.732817 -322.895843) (xy 87.628453 -322.790068) (xy 87.529917 -322.678844) (xy 87.437493 -322.562491)
			(xy 87.351448 -322.441344) (xy 87.27203 -322.315754) (xy 87.199467 -322.186082) (xy 87.133969 -322.052702)
			(xy 87.075725 -321.915999) (xy 87.024903 -321.776366) (xy 86.981649 -321.634207) (xy 86.946088 -321.48993)
			(xy 86.918323 -321.343954) (xy 86.898433 -321.196697) (xy 86.886476 -321.048584) (xy 86.882487 -320.900044)
			(xy 32.416496 -320.900044) (xy 32.415997 -320.974341) (xy 32.408021 -321.122721) (xy 32.392092 -321.270459)
			(xy 32.368256 -321.417128) (xy 32.336582 -321.562307) (xy 32.29716 -321.705577) (xy 32.250105 -321.846524)
			(xy 32.195552 -321.984741) (xy 32.133659 -322.119832) (xy 32.064604 -322.251405) (xy 31.988586 -322.379083)
			(xy 31.905825 -322.502495) (xy 31.816558 -322.621288) (xy 31.721044 -322.735117) (xy 31.619557 -322.843656)
			(xy 31.51239 -322.946591) (xy 31.399853 -323.043625) (xy 31.28227 -323.134478) (xy 31.15998 -323.218889)
			(xy 31.033335 -323.296614) (xy 30.9027 -323.36743) (xy 30.768453 -323.431131) (xy 30.63098 -323.487534)
			(xy 30.490677 -323.536477) (xy 30.34795 -323.577819) (xy 30.203209 -323.611439) (xy 30.056873 -323.637242)
			(xy 29.909362 -323.655153) (xy 29.761103 -323.665121) (xy 29.612522 -323.667116) (xy 29.464049 -323.661132)
			(xy 29.31611 -323.647188) (xy 29.169134 -323.625323) (xy 29.023543 -323.595601) (xy 28.879757 -323.558106)
			(xy 28.738191 -323.512947) (xy 28.599253 -323.460255) (xy 28.463344 -323.400181) (xy 28.330855 -323.332899)
			(xy 28.202169 -323.258602) (xy 28.077656 -323.177505) (xy 27.957676 -323.089841) (xy 27.842575 -322.995863)
			(xy 27.732683 -322.895843) (xy 27.628319 -322.790068) (xy 27.529783 -322.678844) (xy 27.437359 -322.562491)
			(xy 27.351314 -322.441344) (xy 27.271896 -322.315754) (xy 27.199333 -322.186082) (xy 27.133835 -322.052702)
			(xy 27.075591 -321.915999) (xy 27.024769 -321.776366) (xy 26.981515 -321.634207) (xy 26.945954 -321.48993)
			(xy 26.918189 -321.343954) (xy 26.898299 -321.196697) (xy 26.886342 -321.048584) (xy 26.882353 -320.900044)
			(xy 0.508 -320.900044) (xy 0.508 -330.416662) (xy 97.355152 -330.416662) (xy 97.355152 -329.553062)
			(xy 97.355642 -329.523078) (xy 97.36347 -329.463622) (xy 97.378991 -329.405697) (xy 97.40194 -329.350293)
			(xy 97.431924 -329.298359) (xy 97.46843 -329.250783) (xy 97.510835 -329.208378) (xy 97.558411 -329.171872)
			(xy 97.610345 -329.141888) (xy 97.665749 -329.118939) (xy 97.723674 -329.103418) (xy 97.78313 -329.09559)
			(xy 97.843098 -329.09559) (xy 97.902554 -329.103418) (xy 97.960479 -329.118939) (xy 98.015883 -329.141888)
			(xy 98.067817 -329.171872) (xy 98.115393 -329.208378) (xy 98.157798 -329.250783) (xy 98.194304 -329.298359)
			(xy 98.224288 -329.350293) (xy 98.247237 -329.405697) (xy 98.262758 -329.463622) (xy 98.270586 -329.523078)
			(xy 98.271076 -329.553062) (xy 98.271076 -330.416662) (xy 98.270586 -330.446646) (xy 98.262758 -330.506102)
			(xy 98.247237 -330.564027) (xy 98.224288 -330.619431) (xy 98.194304 -330.671365) (xy 98.157798 -330.718941)
			(xy 98.115393 -330.761346) (xy 98.067817 -330.797852) (xy 98.015883 -330.827836) (xy 97.960479 -330.850785)
			(xy 97.902554 -330.866306) (xy 97.843098 -330.874134) (xy 97.78313 -330.874134) (xy 97.723674 -330.866306)
			(xy 97.665749 -330.850785) (xy 97.610345 -330.827836) (xy 97.558411 -330.797852) (xy 97.510835 -330.761346)
			(xy 97.46843 -330.718941) (xy 97.431924 -330.671365) (xy 97.40194 -330.619431) (xy 97.378991 -330.564027)
			(xy 97.36347 -330.506102) (xy 97.355642 -330.446646) (xy 97.355152 -330.416662) (xy 0.508 -330.416662)
			(xy 0.508 -331.53223) (xy 114.955828 -331.53223) (xy 114.955828 -330.66863) (xy 114.956318 -330.638646)
			(xy 114.964146 -330.57919) (xy 114.979667 -330.521265) (xy 115.002616 -330.465861) (xy 115.0326 -330.413927)
			(xy 115.069106 -330.366351) (xy 115.111511 -330.323946) (xy 115.159087 -330.28744) (xy 115.211021 -330.257456)
			(xy 115.266425 -330.234507) (xy 115.32435 -330.218986) (xy 115.383806 -330.211158) (xy 115.443774 -330.211158)
			(xy 115.50323 -330.218986) (xy 115.561155 -330.234507) (xy 115.616559 -330.257456) (xy 115.668493 -330.28744)
			(xy 115.716069 -330.323946) (xy 115.758474 -330.366351) (xy 115.79498 -330.413927) (xy 115.824964 -330.465861)
			(xy 115.847913 -330.521265) (xy 115.863434 -330.57919) (xy 115.871262 -330.638646) (xy 115.871752 -330.66863)
			(xy 115.871752 -331.53223) (xy 115.871262 -331.562214) (xy 115.863434 -331.62167) (xy 115.847913 -331.679595)
			(xy 115.824964 -331.734999) (xy 115.79498 -331.786933) (xy 115.758474 -331.834509) (xy 115.716069 -331.876914)
			(xy 115.668493 -331.91342) (xy 115.616559 -331.943404) (xy 115.561155 -331.966353) (xy 115.50323 -331.981874)
			(xy 115.443774 -331.989702) (xy 115.383806 -331.989702) (xy 115.32435 -331.981874) (xy 115.266425 -331.966353)
			(xy 115.211021 -331.943404) (xy 115.159087 -331.91342) (xy 115.111511 -331.876914) (xy 115.069106 -331.834509)
			(xy 115.0326 -331.786933) (xy 115.002616 -331.734999) (xy 114.979667 -331.679595) (xy 114.964146 -331.62167)
			(xy 114.956318 -331.562214) (xy 114.955828 -331.53223) (xy 0.508 -331.53223) (xy 0.508 -333.950056)
			(xy 93.5736 -333.950056) (xy 93.5736 -333.086456) (xy 93.57409 -333.056488) (xy 93.581913 -332.997066)
			(xy 93.597426 -332.939173) (xy 93.620362 -332.8838) (xy 93.650329 -332.831894) (xy 93.686816 -332.784344)
			(xy 93.729196 -332.741964) (xy 93.776746 -332.705477) (xy 93.828652 -332.67551) (xy 93.884025 -332.652574)
			(xy 93.941918 -332.637061) (xy 94.00134 -332.629238) (xy 94.061276 -332.629238) (xy 94.120698 -332.637061)
			(xy 94.178591 -332.652574) (xy 94.233964 -332.67551) (xy 94.28587 -332.705477) (xy 94.33342 -332.741964)
			(xy 94.3758 -332.784344) (xy 94.412287 -332.831894) (xy 94.442254 -332.8838) (xy 94.46519 -332.939173)
			(xy 94.46736 -332.947271) (xy 365.368753 -332.947271) (xy 365.368753 -332.887329) (xy 365.376578 -332.827899)
			(xy 365.392093 -332.77) (xy 365.415033 -332.71462) (xy 365.445006 -332.66271) (xy 365.481498 -332.615155)
			(xy 365.523886 -332.572772) (xy 365.571443 -332.536283) (xy 365.623356 -332.506315) (xy 365.678737 -332.48338)
			(xy 365.736639 -332.46787) (xy 365.796069 -332.460051) (xy 365.82604 -332.459584) (xy 366.68964 -332.459584)
			(xy 366.719605 -332.460093) (xy 366.779023 -332.46792) (xy 366.836911 -332.483435) (xy 366.892278 -332.506374)
			(xy 366.944178 -332.536342) (xy 366.991723 -332.572828) (xy 367.034098 -332.615207) (xy 367.07058 -332.662755)
			(xy 367.100544 -332.714658) (xy 367.123478 -332.770027) (xy 367.138988 -332.827916) (xy 367.14681 -332.887335)
			(xy 367.14681 -332.947265) (xy 367.138988 -333.006684) (xy 367.123478 -333.064573) (xy 367.100544 -333.119942)
			(xy 367.07058 -333.171845) (xy 367.034098 -333.219393) (xy 366.991723 -333.261772) (xy 366.944178 -333.298258)
			(xy 366.892278 -333.328226) (xy 366.836911 -333.351165) (xy 366.779023 -333.36668) (xy 366.719605 -333.374507)
			(xy 366.68964 -333.375) (xy 365.82604 -333.375) (xy 365.796069 -333.374549) (xy 365.736639 -333.36673)
			(xy 365.678737 -333.35122) (xy 365.623356 -333.328285) (xy 365.571443 -333.298317) (xy 365.523886 -333.261828)
			(xy 365.481498 -333.219445) (xy 365.445006 -333.17189) (xy 365.415033 -333.11998) (xy 365.392093 -333.0646)
			(xy 365.376578 -333.006701) (xy 365.368753 -332.947271) (xy 94.46736 -332.947271) (xy 94.480703 -332.997066)
			(xy 94.488526 -333.056488) (xy 94.489016 -333.086456) (xy 94.489016 -333.950056) (xy 94.488526 -333.980024)
			(xy 94.480703 -334.039446) (xy 94.46519 -334.097339) (xy 94.442254 -334.152712) (xy 94.412287 -334.204618)
			(xy 94.3758 -334.252168) (xy 94.33342 -334.294548) (xy 94.28587 -334.331035) (xy 94.233964 -334.361002)
			(xy 94.178591 -334.383938) (xy 94.120698 -334.399451) (xy 94.061276 -334.407274) (xy 94.00134 -334.407274)
			(xy 93.941918 -334.399451) (xy 93.884025 -334.383938) (xy 93.828652 -334.361002) (xy 93.776746 -334.331035)
			(xy 93.729196 -334.294548) (xy 93.686816 -334.252168) (xy 93.650329 -334.204618) (xy 93.620362 -334.152712)
			(xy 93.597426 -334.097339) (xy 93.581913 -334.039446) (xy 93.57409 -333.980024) (xy 93.5736 -333.950056)
			(xy 0.508 -333.950056) (xy 0.508 -337.266026) (xy 234.403392 -337.266026) (xy 234.403392 -336.402426)
			(xy 234.403882 -336.372458) (xy 234.411705 -336.313036) (xy 234.427218 -336.255143) (xy 234.450154 -336.19977)
			(xy 234.480121 -336.147864) (xy 234.516608 -336.100314) (xy 234.558988 -336.057934) (xy 234.606538 -336.021447)
			(xy 234.658444 -335.99148) (xy 234.713817 -335.968544) (xy 234.77171 -335.953031) (xy 234.831132 -335.945208)
			(xy 234.891068 -335.945208) (xy 234.95049 -335.953031) (xy 235.008383 -335.968544) (xy 235.063756 -335.99148)
			(xy 235.115662 -336.021447) (xy 235.163212 -336.057934) (xy 235.205592 -336.100314) (xy 235.242079 -336.147864)
			(xy 235.272046 -336.19977) (xy 235.294982 -336.255143) (xy 235.310495 -336.313036) (xy 235.318318 -336.372458)
			(xy 235.318808 -336.402426) (xy 235.318808 -337.266026) (xy 235.318318 -337.295994) (xy 235.310495 -337.355416)
			(xy 235.294982 -337.413309) (xy 235.272046 -337.468682) (xy 235.242079 -337.520588) (xy 235.205592 -337.568138)
			(xy 235.163212 -337.610518) (xy 235.115662 -337.647005) (xy 235.063756 -337.676972) (xy 235.008383 -337.699908)
			(xy 234.95049 -337.715421) (xy 234.891068 -337.723244) (xy 234.831132 -337.723244) (xy 234.77171 -337.715421)
			(xy 234.713817 -337.699908) (xy 234.658444 -337.676972) (xy 234.606538 -337.647005) (xy 234.558988 -337.610518)
			(xy 234.516608 -337.568138) (xy 234.480121 -337.520588) (xy 234.450154 -337.468682) (xy 234.427218 -337.413309)
			(xy 234.411705 -337.355416) (xy 234.403882 -337.295994) (xy 234.403392 -337.266026) (xy 0.508 -337.266026)
			(xy 0.508 -342.466769) (xy 18.951172 -342.466769) (xy 18.951172 -342.412231) (xy 18.958934 -342.358247)
			(xy 18.974299 -342.305917) (xy 18.996956 -342.256307) (xy 19.026441 -342.210426) (xy 19.062157 -342.169208)
			(xy 19.103374 -342.133493) (xy 19.149255 -342.104007) (xy 19.198865 -342.08135) (xy 19.251195 -342.065985)
			(xy 19.305179 -342.058223) (xy 19.332448 -342.057736) (xy 20.196048 -342.057736) (xy 20.223319 -342.058203)
			(xy 20.277306 -342.065965) (xy 20.329638 -342.081331) (xy 20.379252 -342.103989) (xy 20.425135 -342.133476)
			(xy 20.466355 -342.169193) (xy 20.502073 -342.210413) (xy 20.53156 -342.256297) (xy 20.554218 -342.30591)
			(xy 20.569584 -342.358242) (xy 20.577347 -342.412229) (xy 20.577347 -342.466771) (xy 20.577347 -342.466772)
			(xy 22.0601 -342.466772) (xy 22.0601 -342.412228) (xy 22.067862 -342.358241) (xy 22.083229 -342.305907)
			(xy 22.105887 -342.256293) (xy 22.135375 -342.210409) (xy 22.171094 -342.169188) (xy 22.212315 -342.133471)
			(xy 22.2582 -342.103983) (xy 22.307815 -342.081326) (xy 22.360148 -342.06596) (xy 22.414136 -342.058199)
			(xy 22.441408 -342.057736) (xy 23.305008 -342.057736) (xy 23.332277 -342.058227) (xy 23.386259 -342.06599)
			(xy 23.438588 -342.081355) (xy 23.488197 -342.104012) (xy 23.534076 -342.133498) (xy 23.575293 -342.169213)
			(xy 23.611007 -342.21043) (xy 23.640492 -342.256311) (xy 23.663147 -342.30592) (xy 23.678512 -342.358249)
			(xy 23.686274 -342.412231) (xy 23.686274 -342.466768) (xy 25.169122 -342.466768) (xy 25.169122 -342.412232)
			(xy 25.176883 -342.358251) (xy 25.192247 -342.305924) (xy 25.214901 -342.256315) (xy 25.244384 -342.210436)
			(xy 25.280096 -342.169219) (xy 25.32131 -342.133503) (xy 25.367187 -342.104016) (xy 25.416794 -342.081358)
			(xy 25.46912 -342.06599) (xy 25.5231 -342.058225) (xy 25.550368 -342.057736) (xy 26.413968 -342.057736)
			(xy 26.44124 -342.058201) (xy 26.49523 -342.06596) (xy 26.547567 -342.081323) (xy 26.597184 -342.103979)
			(xy 26.643071 -342.133465) (xy 26.684295 -342.169183) (xy 26.720015 -342.210403) (xy 26.749506 -342.256288)
			(xy 26.772166 -342.305903) (xy 26.787533 -342.358238) (xy 26.795296 -342.412228) (xy 26.795296 -342.466772)
			(xy 28.278 -342.466772) (xy 28.278 -342.412228) (xy 28.285762 -342.358238) (xy 28.30113 -342.305903)
			(xy 28.32379 -342.256288) (xy 28.35328 -342.210402) (xy 28.389001 -342.169181) (xy 28.430225 -342.133464)
			(xy 28.476112 -342.103977) (xy 28.525729 -342.08132) (xy 28.578065 -342.065957) (xy 28.632056 -342.058198)
			(xy 28.659328 -342.057736) (xy 29.522928 -342.057736) (xy 29.550196 -342.058228) (xy 29.604176 -342.065993)
			(xy 29.656502 -342.081361) (xy 29.706109 -342.104019) (xy 29.751986 -342.133505) (xy 29.7932 -342.16922)
			(xy 29.828912 -342.210437) (xy 29.858395 -342.256316) (xy 29.881049 -342.305924) (xy 29.896413 -342.358251)
			(xy 29.904174 -342.412232) (xy 29.904174 -342.466768) (xy 29.904174 -342.466769) (xy 31.387022 -342.466769)
			(xy 31.387022 -342.412231) (xy 31.394784 -342.358248) (xy 31.410149 -342.305919) (xy 31.432804 -342.25631)
			(xy 31.462289 -342.210429) (xy 31.498003 -342.169212) (xy 31.53922 -342.133496) (xy 31.585099 -342.10401)
			(xy 31.634708 -342.081353) (xy 31.687036 -342.065986) (xy 31.741019 -342.058223) (xy 31.768288 -342.057736)
			(xy 32.631888 -342.057736) (xy 32.659159 -342.058203) (xy 32.713147 -342.065963) (xy 32.765481 -342.081329)
			(xy 32.815096 -342.103985) (xy 32.86098 -342.133472) (xy 32.902202 -342.16919) (xy 32.93792 -342.21041)
			(xy 32.967409 -342.256294) (xy 32.990067 -342.305908) (xy 33.005434 -342.358241) (xy 33.013196 -342.412229)
			(xy 33.013196 -342.466771) (xy 33.013196 -342.466773) (xy 34.4959 -342.466773) (xy 34.4959 -342.412227)
			(xy 34.503663 -342.358235) (xy 34.519032 -342.305899) (xy 34.541693 -342.256282) (xy 34.571185 -342.210396)
			(xy 34.606908 -342.169174) (xy 34.648134 -342.133456) (xy 34.694024 -342.10397) (xy 34.743644 -342.081315)
			(xy 34.795982 -342.065953) (xy 34.849975 -342.058196) (xy 34.877248 -342.057736) (xy 35.740848 -342.057736)
			(xy 35.768115 -342.05823) (xy 35.822093 -342.065997) (xy 35.874417 -342.081366) (xy 35.92402 -342.104025)
			(xy 35.969895 -342.133512) (xy 36.011107 -342.169227) (xy 36.046817 -342.210443) (xy 36.076298 -342.256322)
			(xy 36.098951 -342.305928) (xy 36.114313 -342.358254) (xy 36.122074 -342.412233) (xy 36.122074 -342.466767)
			(xy 36.122073 -342.466772) (xy 37.6049 -342.466772) (xy 37.6049 -342.412228) (xy 37.612662 -342.358241)
			(xy 37.628029 -342.305907) (xy 37.650687 -342.256293) (xy 37.680175 -342.210409) (xy 37.715894 -342.169188)
			(xy 37.757115 -342.133471) (xy 37.803 -342.103983) (xy 37.852615 -342.081326) (xy 37.904948 -342.06596)
			(xy 37.958936 -342.058199) (xy 37.986208 -342.057736) (xy 38.849808 -342.057736) (xy 38.877077 -342.058227)
			(xy 38.931059 -342.06599) (xy 38.983388 -342.081355) (xy 39.032997 -342.104012) (xy 39.078876 -342.133498)
			(xy 39.120093 -342.169213) (xy 39.155807 -342.21043) (xy 39.185292 -342.256311) (xy 39.207947 -342.30592)
			(xy 39.223312 -342.358249) (xy 39.231074 -342.412231) (xy 39.231074 -342.466768) (xy 40.713922 -342.466768)
			(xy 40.713922 -342.412232) (xy 40.721683 -342.358251) (xy 40.737047 -342.305924) (xy 40.759701 -342.256315)
			(xy 40.789184 -342.210436) (xy 40.824896 -342.169219) (xy 40.86611 -342.133503) (xy 40.911987 -342.104016)
			(xy 40.961594 -342.081358) (xy 41.01392 -342.06599) (xy 41.0679 -342.058225) (xy 41.095168 -342.057736)
			(xy 41.958768 -342.057736) (xy 41.98604 -342.058201) (xy 42.04003 -342.06596) (xy 42.092367 -342.081323)
			(xy 42.141984 -342.103979) (xy 42.187871 -342.133465) (xy 42.229095 -342.169183) (xy 42.264815 -342.210403)
			(xy 42.294306 -342.256288) (xy 42.316966 -342.305903) (xy 42.332333 -342.358238) (xy 42.340096 -342.412228)
			(xy 42.340096 -342.466772) (xy 43.8228 -342.466772) (xy 43.8228 -342.412228) (xy 43.830562 -342.358238)
			(xy 43.84593 -342.305903) (xy 43.86859 -342.256288) (xy 43.89808 -342.210402) (xy 43.933801 -342.169181)
			(xy 43.975025 -342.133464) (xy 44.020912 -342.103977) (xy 44.070529 -342.08132) (xy 44.122865 -342.065957)
			(xy 44.176856 -342.058198) (xy 44.204128 -342.057736) (xy 45.067728 -342.057736) (xy 45.094996 -342.058228)
			(xy 45.148976 -342.065993) (xy 45.201302 -342.081361) (xy 45.250909 -342.104019) (xy 45.296786 -342.133505)
			(xy 45.338 -342.16922) (xy 45.373712 -342.210437) (xy 45.403195 -342.256316) (xy 45.425849 -342.305924)
			(xy 45.441213 -342.358251) (xy 45.448974 -342.412232) (xy 45.448974 -342.466768) (xy 45.448974 -342.466769)
			(xy 46.931822 -342.466769) (xy 46.931822 -342.412231) (xy 46.939584 -342.358248) (xy 46.954949 -342.305919)
			(xy 46.977604 -342.25631) (xy 47.007089 -342.210429) (xy 47.042803 -342.169212) (xy 47.08402 -342.133496)
			(xy 47.129899 -342.10401) (xy 47.179508 -342.081353) (xy 47.231836 -342.065986) (xy 47.285819 -342.058223)
			(xy 47.313088 -342.057736) (xy 48.176688 -342.057736) (xy 48.203959 -342.058203) (xy 48.257947 -342.065963)
			(xy 48.310281 -342.081329) (xy 48.359896 -342.103985) (xy 48.40578 -342.133472) (xy 48.447002 -342.16919)
			(xy 48.48272 -342.21041) (xy 48.512209 -342.256294) (xy 48.534867 -342.305908) (xy 48.550234 -342.358241)
			(xy 48.557996 -342.412229) (xy 48.557996 -342.466771) (xy 48.557996 -342.466773) (xy 50.0407 -342.466773)
			(xy 50.0407 -342.412227) (xy 50.048463 -342.358235) (xy 50.063832 -342.305899) (xy 50.086493 -342.256282)
			(xy 50.115985 -342.210396) (xy 50.151708 -342.169174) (xy 50.192934 -342.133456) (xy 50.238824 -342.10397)
			(xy 50.288444 -342.081315) (xy 50.340782 -342.065953) (xy 50.394775 -342.058196) (xy 50.422048 -342.057736)
			(xy 51.285648 -342.057736) (xy 51.312915 -342.05823) (xy 51.366893 -342.065997) (xy 51.419217 -342.081366)
			(xy 51.46882 -342.104025) (xy 51.514695 -342.133512) (xy 51.555907 -342.169227) (xy 51.591617 -342.210443)
			(xy 51.621098 -342.256322) (xy 51.643751 -342.305928) (xy 51.659113 -342.358254) (xy 51.666874 -342.412233)
			(xy 51.666874 -342.466767) (xy 51.666873 -342.466773) (xy 60.9909 -342.466773) (xy 60.9909 -342.412227)
			(xy 60.998663 -342.358236) (xy 61.014031 -342.3059) (xy 61.036692 -342.256284) (xy 61.066184 -342.210398)
			(xy 61.101906 -342.169176) (xy 61.143131 -342.133459) (xy 61.18902 -342.103972) (xy 61.238639 -342.081317)
			(xy 61.290977 -342.065954) (xy 61.344969 -342.058197) (xy 61.372242 -342.057736) (xy 62.235842 -342.057736)
			(xy 62.263109 -342.058229) (xy 62.317088 -342.065996) (xy 62.369412 -342.081365) (xy 62.419017 -342.104023)
			(xy 62.464892 -342.13351) (xy 62.506105 -342.169225) (xy 62.541815 -342.210441) (xy 62.571297 -342.25632)
			(xy 62.59395 -342.305927) (xy 62.609313 -342.358253) (xy 62.617074 -342.412233) (xy 62.617074 -342.466767)
			(xy 62.617073 -342.466771) (xy 64.099899 -342.466771) (xy 64.099899 -342.412229) (xy 64.107662 -342.358241)
			(xy 64.123028 -342.305908) (xy 64.145686 -342.256295) (xy 64.175174 -342.210411) (xy 64.210892 -342.16919)
			(xy 64.252112 -342.133473) (xy 64.297997 -342.103985) (xy 64.34761 -342.081327) (xy 64.399943 -342.065961)
			(xy 64.453931 -342.058199) (xy 64.481202 -342.057736) (xy 65.344802 -342.057736) (xy 65.372071 -342.058227)
			(xy 65.426054 -342.065988) (xy 65.478383 -342.081354) (xy 65.527993 -342.10401) (xy 65.573873 -342.133496)
			(xy 65.615091 -342.169211) (xy 65.650805 -342.210428) (xy 65.680291 -342.256309) (xy 65.702947 -342.305919)
			(xy 65.718312 -342.358248) (xy 65.726074 -342.412231) (xy 65.726074 -342.466768) (xy 67.208922 -342.466768)
			(xy 67.208922 -342.412232) (xy 67.216683 -342.358252) (xy 67.232047 -342.305925) (xy 67.2547 -342.256317)
			(xy 67.284183 -342.210438) (xy 67.319894 -342.169221) (xy 67.361107 -342.133505) (xy 67.406984 -342.104018)
			(xy 67.456589 -342.08136) (xy 67.508914 -342.065991) (xy 67.562894 -342.058225) (xy 67.590162 -342.057736)
			(xy 68.453762 -342.057736) (xy 68.481035 -342.058201) (xy 68.535025 -342.065959) (xy 68.587362 -342.081321)
			(xy 68.63698 -342.103977) (xy 68.682868 -342.133463) (xy 68.724093 -342.16918) (xy 68.759814 -342.210401)
			(xy 68.789305 -342.256287) (xy 68.811965 -342.305902) (xy 68.827333 -342.358237) (xy 68.835096 -342.412227)
			(xy 68.835096 -342.466772) (xy 70.3178 -342.466772) (xy 70.3178 -342.412228) (xy 70.325562 -342.358239)
			(xy 70.34093 -342.305904) (xy 70.363589 -342.256289) (xy 70.393079 -342.210404) (xy 70.428799 -342.169183)
			(xy 70.470022 -342.133466) (xy 70.515909 -342.103979) (xy 70.565525 -342.081322) (xy 70.61786 -342.065958)
			(xy 70.67185 -342.058198) (xy 70.699122 -342.057736) (xy 71.562722 -342.057736) (xy 71.58999 -342.058228)
			(xy 71.643971 -342.065992) (xy 71.696298 -342.081359) (xy 71.745905 -342.104017) (xy 71.791783 -342.133503)
			(xy 71.832998 -342.169218) (xy 71.86871 -342.210435) (xy 71.898194 -342.256314) (xy 71.920848 -342.305923)
			(xy 71.936213 -342.35825) (xy 71.943974 -342.412232) (xy 71.943974 -342.466768) (xy 71.943974 -342.466769)
			(xy 73.426822 -342.466769) (xy 73.426822 -342.412231) (xy 73.434584 -342.358249) (xy 73.449948 -342.305921)
			(xy 73.472603 -342.256311) (xy 73.502087 -342.210431) (xy 73.537801 -342.169214) (xy 73.579017 -342.133498)
			(xy 73.624896 -342.104012) (xy 73.674504 -342.081354) (xy 73.726831 -342.065987) (xy 73.780813 -342.058224)
			(xy 73.808082 -342.057736) (xy 74.671682 -342.057736) (xy 74.698954 -342.058202) (xy 74.752942 -342.065962)
			(xy 74.805277 -342.081327) (xy 74.854892 -342.103983) (xy 74.900778 -342.13347) (xy 74.942 -342.169188)
			(xy 74.977719 -342.210408) (xy 75.007208 -342.256292) (xy 75.029867 -342.305906) (xy 75.045234 -342.35824)
			(xy 75.052996 -342.412228) (xy 75.052996 -342.466772) (xy 75.052996 -342.466773) (xy 76.5357 -342.466773)
			(xy 76.5357 -342.412227) (xy 76.543463 -342.358236) (xy 76.558831 -342.3059) (xy 76.581492 -342.256284)
			(xy 76.610984 -342.210398) (xy 76.646706 -342.169176) (xy 76.687931 -342.133459) (xy 76.73382 -342.103972)
			(xy 76.783439 -342.081317) (xy 76.835777 -342.065954) (xy 76.889769 -342.058197) (xy 76.917042 -342.057736)
			(xy 77.780642 -342.057736) (xy 77.807909 -342.058229) (xy 77.861888 -342.065996) (xy 77.914212 -342.081365)
			(xy 77.963817 -342.104023) (xy 78.009692 -342.13351) (xy 78.050905 -342.169225) (xy 78.086615 -342.210441)
			(xy 78.116097 -342.25632) (xy 78.13875 -342.305927) (xy 78.154113 -342.358253) (xy 78.161874 -342.412233)
			(xy 78.161874 -342.466767) (xy 78.161873 -342.466771) (xy 79.644699 -342.466771) (xy 79.644699 -342.412229)
			(xy 79.652462 -342.358241) (xy 79.667828 -342.305908) (xy 79.690486 -342.256295) (xy 79.719974 -342.210411)
			(xy 79.755692 -342.16919) (xy 79.796912 -342.133473) (xy 79.842797 -342.103985) (xy 79.89241 -342.081327)
			(xy 79.944743 -342.065961) (xy 79.998731 -342.058199) (xy 80.026002 -342.057736) (xy 80.889602 -342.057736)
			(xy 80.916871 -342.058227) (xy 80.970854 -342.065988) (xy 81.023183 -342.081354) (xy 81.072793 -342.10401)
			(xy 81.118673 -342.133496) (xy 81.159891 -342.169211) (xy 81.195605 -342.210428) (xy 81.225091 -342.256309)
			(xy 81.247747 -342.305919) (xy 81.263112 -342.358248) (xy 81.270874 -342.412231) (xy 81.270874 -342.466768)
			(xy 82.753722 -342.466768) (xy 82.753722 -342.412232) (xy 82.761483 -342.358252) (xy 82.776847 -342.305925)
			(xy 82.7995 -342.256317) (xy 82.828983 -342.210438) (xy 82.864694 -342.169221) (xy 82.905907 -342.133505)
			(xy 82.951784 -342.104018) (xy 83.001389 -342.08136) (xy 83.053714 -342.065991) (xy 83.107694 -342.058225)
			(xy 83.134962 -342.057736) (xy 83.998562 -342.057736) (xy 84.025835 -342.058201) (xy 84.079825 -342.065959)
			(xy 84.132162 -342.081321) (xy 84.18178 -342.103977) (xy 84.227668 -342.133463) (xy 84.268893 -342.16918)
			(xy 84.304614 -342.210401) (xy 84.334105 -342.256287) (xy 84.356765 -342.305902) (xy 84.372133 -342.358237)
			(xy 84.379896 -342.412227) (xy 84.379896 -342.466772) (xy 85.8626 -342.466772) (xy 85.8626 -342.412228)
			(xy 85.870362 -342.358239) (xy 85.88573 -342.305904) (xy 85.908389 -342.256289) (xy 85.937879 -342.210404)
			(xy 85.973599 -342.169183) (xy 86.014822 -342.133466) (xy 86.060709 -342.103979) (xy 86.110325 -342.081322)
			(xy 86.16266 -342.065958) (xy 86.21665 -342.058198) (xy 86.243922 -342.057736) (xy 87.107522 -342.057736)
			(xy 87.13479 -342.058228) (xy 87.188771 -342.065992) (xy 87.241098 -342.081359) (xy 87.290705 -342.104017)
			(xy 87.336583 -342.133503) (xy 87.377798 -342.169218) (xy 87.41351 -342.210435) (xy 87.442994 -342.256314)
			(xy 87.465648 -342.305923) (xy 87.481013 -342.35825) (xy 87.488774 -342.412232) (xy 87.488774 -342.466768)
			(xy 87.488774 -342.466769) (xy 88.971622 -342.466769) (xy 88.971622 -342.412231) (xy 88.979384 -342.358249)
			(xy 88.994748 -342.305921) (xy 89.017403 -342.256311) (xy 89.046887 -342.210431) (xy 89.082601 -342.169214)
			(xy 89.123817 -342.133498) (xy 89.169696 -342.104012) (xy 89.219304 -342.081354) (xy 89.271631 -342.065987)
			(xy 89.325613 -342.058224) (xy 89.352882 -342.057736) (xy 90.216482 -342.057736) (xy 90.243754 -342.058202)
			(xy 90.297742 -342.065962) (xy 90.350077 -342.081327) (xy 90.399692 -342.103983) (xy 90.445578 -342.13347)
			(xy 90.4868 -342.169188) (xy 90.522519 -342.210408) (xy 90.552008 -342.256292) (xy 90.574667 -342.305906)
			(xy 90.590034 -342.35824) (xy 90.597796 -342.412228) (xy 90.597796 -342.466772) (xy 90.597796 -342.466773)
			(xy 92.0805 -342.466773) (xy 92.0805 -342.412227) (xy 92.088263 -342.358236) (xy 92.103631 -342.3059)
			(xy 92.126292 -342.256284) (xy 92.155784 -342.210398) (xy 92.191506 -342.169176) (xy 92.232731 -342.133459)
			(xy 92.27862 -342.103972) (xy 92.328239 -342.081317) (xy 92.380577 -342.065954) (xy 92.434569 -342.058197)
			(xy 92.461842 -342.057736) (xy 93.325442 -342.057736) (xy 93.352709 -342.058229) (xy 93.406688 -342.065996)
			(xy 93.459012 -342.081365) (xy 93.508617 -342.104023) (xy 93.554492 -342.13351) (xy 93.595705 -342.169225)
			(xy 93.631415 -342.210441) (xy 93.660897 -342.25632) (xy 93.68355 -342.305927) (xy 93.698913 -342.358253)
			(xy 93.706674 -342.412233) (xy 93.706674 -342.466767) (xy 93.698913 -342.520747) (xy 93.68355 -342.573073)
			(xy 93.660897 -342.62268) (xy 93.631415 -342.668559) (xy 93.60914 -342.694268) (xy 102.35157 -342.694268)
			(xy 102.35157 -342.634332) (xy 102.359393 -342.574909) (xy 102.374905 -342.517016) (xy 102.397841 -342.461642)
			(xy 102.427809 -342.409736) (xy 102.464294 -342.362185) (xy 102.506675 -342.319804) (xy 102.554224 -342.283316)
			(xy 102.60613 -342.253347) (xy 102.661502 -342.23041) (xy 102.719395 -342.214896) (xy 102.778818 -342.207071)
			(xy 102.808786 -342.20658) (xy 103.672386 -342.20658) (xy 103.702355 -342.207072) (xy 103.76178 -342.214894)
			(xy 103.819676 -342.230405) (xy 103.875051 -342.253341) (xy 103.926959 -342.283309) (xy 103.974512 -342.319796)
			(xy 104.016895 -342.362178) (xy 104.053383 -342.409729) (xy 104.083352 -342.461636) (xy 104.085479 -342.466772)
			(xy 111.4808 -342.466772) (xy 111.4808 -342.412228) (xy 111.488562 -342.358241) (xy 111.503929 -342.305907)
			(xy 111.526587 -342.256293) (xy 111.556075 -342.210409) (xy 111.591794 -342.169188) (xy 111.633015 -342.133471)
			(xy 111.6789 -342.103983) (xy 111.728515 -342.081326) (xy 111.780848 -342.06596) (xy 111.834836 -342.058199)
			(xy 111.862108 -342.057736) (xy 112.725708 -342.057736) (xy 112.752977 -342.058227) (xy 112.806959 -342.06599)
			(xy 112.859288 -342.081355) (xy 112.908897 -342.104012) (xy 112.954776 -342.133498) (xy 112.995993 -342.169213)
			(xy 113.031707 -342.21043) (xy 113.061192 -342.256311) (xy 113.083847 -342.30592) (xy 113.099212 -342.358249)
			(xy 113.106974 -342.412231) (xy 113.106974 -342.466768) (xy 114.589822 -342.466768) (xy 114.589822 -342.412232)
			(xy 114.597583 -342.358251) (xy 114.612947 -342.305924) (xy 114.635601 -342.256315) (xy 114.665084 -342.210436)
			(xy 114.700796 -342.169219) (xy 114.74201 -342.133503) (xy 114.787887 -342.104016) (xy 114.837494 -342.081358)
			(xy 114.88982 -342.06599) (xy 114.9438 -342.058225) (xy 114.971068 -342.057736) (xy 115.834668 -342.057736)
			(xy 115.86194 -342.058201) (xy 115.91593 -342.06596) (xy 115.968267 -342.081323) (xy 116.017884 -342.103979)
			(xy 116.063771 -342.133465) (xy 116.104995 -342.169183) (xy 116.140715 -342.210403) (xy 116.170206 -342.256288)
			(xy 116.192866 -342.305903) (xy 116.208233 -342.358238) (xy 116.215996 -342.412228) (xy 116.215996 -342.466772)
			(xy 117.6987 -342.466772) (xy 117.6987 -342.412228) (xy 117.706462 -342.358238) (xy 117.72183 -342.305903)
			(xy 117.74449 -342.256288) (xy 117.77398 -342.210402) (xy 117.809701 -342.169181) (xy 117.850925 -342.133464)
			(xy 117.896812 -342.103977) (xy 117.946429 -342.08132) (xy 117.998765 -342.065957) (xy 118.052756 -342.058198)
			(xy 118.080028 -342.057736) (xy 118.943628 -342.057736) (xy 118.970896 -342.058228) (xy 119.024876 -342.065993)
			(xy 119.077202 -342.081361) (xy 119.126809 -342.104019) (xy 119.172686 -342.133505) (xy 119.2139 -342.16922)
			(xy 119.249612 -342.210437) (xy 119.279095 -342.256316) (xy 119.301749 -342.305924) (xy 119.317113 -342.358251)
			(xy 119.324874 -342.412232) (xy 119.324874 -342.466768) (xy 119.324874 -342.466769) (xy 120.807722 -342.466769)
			(xy 120.807722 -342.412231) (xy 120.815484 -342.358248) (xy 120.830849 -342.305919) (xy 120.853504 -342.25631)
			(xy 120.882989 -342.210429) (xy 120.918703 -342.169212) (xy 120.95992 -342.133496) (xy 121.005799 -342.10401)
			(xy 121.055408 -342.081353) (xy 121.107736 -342.065986) (xy 121.161719 -342.058223) (xy 121.188988 -342.057736)
			(xy 122.052588 -342.057736) (xy 122.079859 -342.058203) (xy 122.133847 -342.065963) (xy 122.186181 -342.081329)
			(xy 122.235796 -342.103985) (xy 122.28168 -342.133472) (xy 122.322902 -342.16919) (xy 122.35862 -342.21041)
			(xy 122.388109 -342.256294) (xy 122.410767 -342.305908) (xy 122.426134 -342.358241) (xy 122.433896 -342.412229)
			(xy 122.433896 -342.466771) (xy 122.433896 -342.466773) (xy 123.9166 -342.466773) (xy 123.9166 -342.412227)
			(xy 123.924363 -342.358235) (xy 123.939732 -342.305899) (xy 123.962393 -342.256282) (xy 123.991885 -342.210396)
			(xy 124.027608 -342.169174) (xy 124.068834 -342.133456) (xy 124.114724 -342.10397) (xy 124.164344 -342.081315)
			(xy 124.216682 -342.065953) (xy 124.270675 -342.058196) (xy 124.297948 -342.057736) (xy 125.161548 -342.057736)
			(xy 125.188815 -342.05823) (xy 125.242793 -342.065997) (xy 125.295117 -342.081366) (xy 125.34472 -342.104025)
			(xy 125.390595 -342.133512) (xy 125.431807 -342.169227) (xy 125.467517 -342.210443) (xy 125.496998 -342.256322)
			(xy 125.519651 -342.305928) (xy 125.535013 -342.358254) (xy 125.542774 -342.412233) (xy 125.542774 -342.466767)
			(xy 125.542773 -342.466772) (xy 127.0256 -342.466772) (xy 127.0256 -342.412228) (xy 127.033362 -342.358241)
			(xy 127.048729 -342.305907) (xy 127.071387 -342.256293) (xy 127.100875 -342.210409) (xy 127.136594 -342.169188)
			(xy 127.177815 -342.133471) (xy 127.2237 -342.103983) (xy 127.273315 -342.081326) (xy 127.325648 -342.06596)
			(xy 127.379636 -342.058199) (xy 127.406908 -342.057736) (xy 128.270508 -342.057736) (xy 128.297777 -342.058227)
			(xy 128.351759 -342.06599) (xy 128.404088 -342.081355) (xy 128.453697 -342.104012) (xy 128.499576 -342.133498)
			(xy 128.540793 -342.169213) (xy 128.576507 -342.21043) (xy 128.605992 -342.256311) (xy 128.628647 -342.30592)
			(xy 128.644012 -342.358249) (xy 128.651774 -342.412231) (xy 128.651774 -342.466768) (xy 130.134622 -342.466768)
			(xy 130.134622 -342.412232) (xy 130.142383 -342.358251) (xy 130.157747 -342.305924) (xy 130.180401 -342.256315)
			(xy 130.209884 -342.210436) (xy 130.245596 -342.169219) (xy 130.28681 -342.133503) (xy 130.332687 -342.104016)
			(xy 130.382294 -342.081358) (xy 130.43462 -342.06599) (xy 130.4886 -342.058225) (xy 130.515868 -342.057736)
			(xy 131.379468 -342.057736) (xy 131.40674 -342.058201) (xy 131.46073 -342.06596) (xy 131.513067 -342.081323)
			(xy 131.562684 -342.103979) (xy 131.608571 -342.133465) (xy 131.649795 -342.169183) (xy 131.685515 -342.210403)
			(xy 131.715006 -342.256288) (xy 131.737666 -342.305903) (xy 131.753033 -342.358238) (xy 131.760796 -342.412228)
			(xy 131.760796 -342.466772) (xy 133.2435 -342.466772) (xy 133.2435 -342.412228) (xy 133.251262 -342.358238)
			(xy 133.26663 -342.305903) (xy 133.28929 -342.256288) (xy 133.31878 -342.210402) (xy 133.354501 -342.169181)
			(xy 133.395725 -342.133464) (xy 133.441612 -342.103977) (xy 133.491229 -342.08132) (xy 133.543565 -342.065957)
			(xy 133.597556 -342.058198) (xy 133.624828 -342.057736) (xy 134.488428 -342.057736) (xy 134.515696 -342.058228)
			(xy 134.569676 -342.065993) (xy 134.622002 -342.081361) (xy 134.671609 -342.104019) (xy 134.717486 -342.133505)
			(xy 134.7587 -342.16922) (xy 134.794412 -342.210437) (xy 134.823895 -342.256316) (xy 134.846549 -342.305924)
			(xy 134.861913 -342.358251) (xy 134.869674 -342.412232) (xy 134.869674 -342.466768) (xy 134.869674 -342.466769)
			(xy 136.352522 -342.466769) (xy 136.352522 -342.412231) (xy 136.360284 -342.358248) (xy 136.375649 -342.305919)
			(xy 136.398304 -342.25631) (xy 136.427789 -342.210429) (xy 136.463503 -342.169212) (xy 136.50472 -342.133496)
			(xy 136.550599 -342.10401) (xy 136.600208 -342.081353) (xy 136.652536 -342.065986) (xy 136.706519 -342.058223)
			(xy 136.733788 -342.057736) (xy 137.597388 -342.057736) (xy 137.624659 -342.058203) (xy 137.678647 -342.065963)
			(xy 137.730981 -342.081329) (xy 137.780596 -342.103985) (xy 137.82648 -342.133472) (xy 137.867702 -342.16919)
			(xy 137.90342 -342.21041) (xy 137.932909 -342.256294) (xy 137.955567 -342.305908) (xy 137.970934 -342.358241)
			(xy 137.978696 -342.412229) (xy 137.978696 -342.466771) (xy 137.978696 -342.466773) (xy 139.4614 -342.466773)
			(xy 139.4614 -342.412227) (xy 139.469163 -342.358235) (xy 139.484532 -342.305899) (xy 139.507193 -342.256282)
			(xy 139.536685 -342.210396) (xy 139.572408 -342.169174) (xy 139.613634 -342.133456) (xy 139.659524 -342.10397)
			(xy 139.709144 -342.081315) (xy 139.761482 -342.065953) (xy 139.815475 -342.058196) (xy 139.842748 -342.057736)
			(xy 140.706348 -342.057736) (xy 140.733615 -342.05823) (xy 140.787593 -342.065997) (xy 140.839917 -342.081366)
			(xy 140.88952 -342.104025) (xy 140.935395 -342.133512) (xy 140.976607 -342.169227) (xy 141.012317 -342.210443)
			(xy 141.041798 -342.256322) (xy 141.064451 -342.305928) (xy 141.079813 -342.358254) (xy 141.087574 -342.412233)
			(xy 141.087574 -342.466767) (xy 141.087573 -342.466772) (xy 142.5704 -342.466772) (xy 142.5704 -342.412228)
			(xy 142.578162 -342.358241) (xy 142.593529 -342.305907) (xy 142.616187 -342.256293) (xy 142.645675 -342.210409)
			(xy 142.681394 -342.169188) (xy 142.722615 -342.133471) (xy 142.7685 -342.103983) (xy 142.818115 -342.081326)
			(xy 142.870448 -342.06596) (xy 142.924436 -342.058199) (xy 142.951708 -342.057736) (xy 143.815308 -342.057736)
			(xy 143.842577 -342.058227) (xy 143.896559 -342.06599) (xy 143.948888 -342.081355) (xy 143.998497 -342.104012)
			(xy 144.044376 -342.133498) (xy 144.085593 -342.169213) (xy 144.121307 -342.21043) (xy 144.150792 -342.256311)
			(xy 144.173447 -342.30592) (xy 144.188812 -342.358249) (xy 144.196574 -342.412231) (xy 144.196574 -342.466768)
			(xy 164.913822 -342.466768) (xy 164.913822 -342.412232) (xy 164.921583 -342.35825) (xy 164.936947 -342.305923)
			(xy 164.959602 -342.256314) (xy 164.989085 -342.210434) (xy 165.024797 -342.169217) (xy 165.066012 -342.133502)
			(xy 165.11189 -342.104015) (xy 165.161496 -342.081357) (xy 165.213823 -342.065989) (xy 165.267804 -342.058224)
			(xy 165.295072 -342.057736) (xy 166.158672 -342.057736) (xy 166.185944 -342.058202) (xy 166.239934 -342.06596)
			(xy 166.29227 -342.081324) (xy 166.341886 -342.10398) (xy 166.387773 -342.133467) (xy 166.428996 -342.169184)
			(xy 166.464716 -342.210405) (xy 166.494207 -342.256289) (xy 166.516866 -342.305904) (xy 166.532234 -342.358239)
			(xy 166.539996 -342.412228) (xy 166.539996 -342.466772) (xy 166.539996 -342.466773) (xy 168.0227 -342.466773)
			(xy 168.0227 -342.412227) (xy 168.030463 -342.358237) (xy 168.045831 -342.305902) (xy 168.068491 -342.256286)
			(xy 168.097981 -342.210401) (xy 168.133702 -342.16918) (xy 168.174927 -342.133462) (xy 168.220815 -342.103975)
			(xy 168.270432 -342.081319) (xy 168.322769 -342.065956) (xy 168.376759 -342.058197) (xy 168.404032 -342.057736)
			(xy 169.267632 -342.057736) (xy 169.2949 -342.058229) (xy 169.34888 -342.065994) (xy 169.401205 -342.081362)
			(xy 169.450811 -342.10402) (xy 169.496688 -342.133506) (xy 169.537901 -342.169222) (xy 169.573613 -342.210438)
			(xy 169.603095 -342.256317) (xy 169.625749 -342.305925) (xy 169.641113 -342.358252) (xy 169.648874 -342.412232)
			(xy 169.648874 -342.466768) (xy 169.648874 -342.466769) (xy 171.131722 -342.466769) (xy 171.131722 -342.412231)
			(xy 171.139484 -342.358248) (xy 171.154849 -342.305918) (xy 171.177505 -342.256309) (xy 171.20699 -342.210428)
			(xy 171.242705 -342.16921) (xy 171.283921 -342.133495) (xy 171.329802 -342.104009) (xy 171.379411 -342.081352)
			(xy 171.43174 -342.065986) (xy 171.485723 -342.058223) (xy 171.512992 -342.057736) (xy 172.376592 -342.057736)
			(xy 172.403863 -342.058203) (xy 172.457851 -342.065964) (xy 172.510184 -342.08133) (xy 172.559798 -342.103987)
			(xy 172.605682 -342.133474) (xy 172.646903 -342.169191) (xy 172.682621 -342.210411) (xy 172.71211 -342.256295)
			(xy 172.734768 -342.305908) (xy 172.750134 -342.358241) (xy 172.757896 -342.412229) (xy 172.757896 -342.466767)
			(xy 174.240722 -342.466767) (xy 174.240722 -342.412233) (xy 174.248483 -342.358253) (xy 174.263846 -342.305927)
			(xy 174.286499 -342.25632) (xy 174.31598 -342.210441) (xy 174.35169 -342.169224) (xy 174.392902 -342.133509)
			(xy 174.438778 -342.104022) (xy 174.488382 -342.081363) (xy 174.540706 -342.065993) (xy 174.594685 -342.058226)
			(xy 174.621952 -342.057736) (xy 175.485552 -342.057736) (xy 175.512825 -342.0582) (xy 175.566817 -342.065957)
			(xy 175.619155 -342.081319) (xy 175.668774 -342.103974) (xy 175.714663 -342.13346) (xy 175.755889 -342.169177)
			(xy 175.791612 -342.210398) (xy 175.821103 -342.256284) (xy 175.843764 -342.3059) (xy 175.859133 -342.358236)
			(xy 175.866896 -342.412227) (xy 175.866896 -342.466772) (xy 177.3496 -342.466772) (xy 177.3496 -342.412228)
			(xy 177.357362 -342.35824) (xy 177.372729 -342.305906) (xy 177.395388 -342.256292) (xy 177.424876 -342.210407)
			(xy 177.460595 -342.169187) (xy 177.501817 -342.133469) (xy 177.547703 -342.103982) (xy 177.597317 -342.081325)
			(xy 177.649652 -342.065959) (xy 177.70364 -342.058199) (xy 177.730912 -342.057736) (xy 178.594512 -342.057736)
			(xy 178.621781 -342.058227) (xy 178.675763 -342.06599) (xy 178.728091 -342.081357) (xy 178.777699 -342.104013)
			(xy 178.823578 -342.133499) (xy 178.864794 -342.169214) (xy 178.900508 -342.210432) (xy 178.929992 -342.256312)
			(xy 178.952648 -342.305921) (xy 178.968012 -342.358249) (xy 178.975774 -342.412231) (xy 178.975774 -342.466768)
			(xy 180.458622 -342.466768) (xy 180.458622 -342.412232) (xy 180.466383 -342.35825) (xy 180.481747 -342.305923)
			(xy 180.504402 -342.256314) (xy 180.533885 -342.210434) (xy 180.569597 -342.169217) (xy 180.610812 -342.133502)
			(xy 180.65669 -342.104015) (xy 180.706296 -342.081357) (xy 180.758623 -342.065989) (xy 180.812604 -342.058224)
			(xy 180.839872 -342.057736) (xy 181.703472 -342.057736) (xy 181.730744 -342.058202) (xy 181.784734 -342.06596)
			(xy 181.83707 -342.081324) (xy 181.886686 -342.10398) (xy 181.932573 -342.133467) (xy 181.973796 -342.169184)
			(xy 182.009516 -342.210405) (xy 182.039007 -342.256289) (xy 182.061666 -342.305904) (xy 182.077034 -342.358239)
			(xy 182.084796 -342.412228) (xy 182.084796 -342.466772) (xy 182.084796 -342.466773) (xy 183.5675 -342.466773)
			(xy 183.5675 -342.412227) (xy 183.575263 -342.358237) (xy 183.590631 -342.305902) (xy 183.613291 -342.256286)
			(xy 183.642781 -342.210401) (xy 183.678502 -342.16918) (xy 183.719727 -342.133462) (xy 183.765615 -342.103975)
			(xy 183.815232 -342.081319) (xy 183.867569 -342.065956) (xy 183.921559 -342.058197) (xy 183.948832 -342.057736)
			(xy 184.812432 -342.057736) (xy 184.8397 -342.058229) (xy 184.89368 -342.065994) (xy 184.946005 -342.081362)
			(xy 184.995611 -342.10402) (xy 185.041488 -342.133506) (xy 185.082701 -342.169222) (xy 185.118413 -342.210438)
			(xy 185.147895 -342.256317) (xy 185.170549 -342.305925) (xy 185.185913 -342.358252) (xy 185.193674 -342.412232)
			(xy 185.193674 -342.466768) (xy 185.193674 -342.466769) (xy 186.676522 -342.466769) (xy 186.676522 -342.412231)
			(xy 186.684284 -342.358248) (xy 186.699649 -342.305918) (xy 186.722305 -342.256309) (xy 186.75179 -342.210428)
			(xy 186.787505 -342.16921) (xy 186.828721 -342.133495) (xy 186.874602 -342.104009) (xy 186.924211 -342.081352)
			(xy 186.97654 -342.065986) (xy 187.030523 -342.058223) (xy 187.057792 -342.057736) (xy 187.921392 -342.057736)
			(xy 187.948663 -342.058203) (xy 188.002651 -342.065964) (xy 188.054984 -342.08133) (xy 188.104598 -342.103987)
			(xy 188.150482 -342.133474) (xy 188.191703 -342.169191) (xy 188.227421 -342.210411) (xy 188.25691 -342.256295)
			(xy 188.279568 -342.305908) (xy 188.294934 -342.358241) (xy 188.302696 -342.412229) (xy 188.302696 -342.466767)
			(xy 189.785522 -342.466767) (xy 189.785522 -342.412233) (xy 189.793283 -342.358253) (xy 189.808646 -342.305927)
			(xy 189.831299 -342.25632) (xy 189.86078 -342.210441) (xy 189.89649 -342.169224) (xy 189.937702 -342.133509)
			(xy 189.983578 -342.104022) (xy 190.033182 -342.081363) (xy 190.085506 -342.065993) (xy 190.139485 -342.058226)
			(xy 190.166752 -342.057736) (xy 191.030352 -342.057736) (xy 191.057625 -342.0582) (xy 191.111617 -342.065957)
			(xy 191.163955 -342.081319) (xy 191.213574 -342.103974) (xy 191.259463 -342.13346) (xy 191.300689 -342.169177)
			(xy 191.336412 -342.210398) (xy 191.365903 -342.256284) (xy 191.388564 -342.3059) (xy 191.403933 -342.358236)
			(xy 191.411696 -342.412227) (xy 191.411696 -342.466772) (xy 192.8944 -342.466772) (xy 192.8944 -342.412228)
			(xy 192.902162 -342.35824) (xy 192.917529 -342.305906) (xy 192.940188 -342.256292) (xy 192.969676 -342.210407)
			(xy 193.005395 -342.169187) (xy 193.046617 -342.133469) (xy 193.092503 -342.103982) (xy 193.142117 -342.081325)
			(xy 193.194452 -342.065959) (xy 193.24844 -342.058199) (xy 193.275712 -342.057736) (xy 194.139312 -342.057736)
			(xy 194.166581 -342.058227) (xy 194.220563 -342.06599) (xy 194.272891 -342.081357) (xy 194.322499 -342.104013)
			(xy 194.368378 -342.133499) (xy 194.409594 -342.169214) (xy 194.445308 -342.210432) (xy 194.474792 -342.256312)
			(xy 194.497448 -342.305921) (xy 194.512812 -342.358249) (xy 194.520574 -342.412231) (xy 194.520574 -342.466768)
			(xy 196.003422 -342.466768) (xy 196.003422 -342.412232) (xy 196.011183 -342.35825) (xy 196.026547 -342.305923)
			(xy 196.049202 -342.256314) (xy 196.078685 -342.210434) (xy 196.114397 -342.169217) (xy 196.155612 -342.133502)
			(xy 196.20149 -342.104015) (xy 196.251096 -342.081357) (xy 196.303423 -342.065989) (xy 196.357404 -342.058224)
			(xy 196.384672 -342.057736) (xy 197.248272 -342.057736) (xy 197.275544 -342.058202) (xy 197.28821 -342.060022)
			(xy 255.91262 -342.060022) (xy 255.91262 -341.196422) (xy 255.91311 -341.166438) (xy 255.920938 -341.106982)
			(xy 255.936459 -341.049057) (xy 255.959408 -340.993653) (xy 255.989392 -340.941719) (xy 256.025898 -340.894143)
			(xy 256.068303 -340.851738) (xy 256.115879 -340.815232) (xy 256.167813 -340.785248) (xy 256.223217 -340.762299)
			(xy 256.281142 -340.746778) (xy 256.340598 -340.73895) (xy 256.400566 -340.73895) (xy 256.460022 -340.746778)
			(xy 256.517947 -340.762299) (xy 256.573351 -340.785248) (xy 256.625285 -340.815232) (xy 256.672861 -340.851738)
			(xy 256.715266 -340.894143) (xy 256.751772 -340.941719) (xy 256.781756 -340.993653) (xy 256.804705 -341.049057)
			(xy 256.820226 -341.106982) (xy 256.828054 -341.166438) (xy 256.828544 -341.196422) (xy 256.828544 -342.060022)
			(xy 256.828054 -342.090006) (xy 256.820226 -342.149462) (xy 256.804705 -342.207387) (xy 256.781756 -342.262791)
			(xy 256.751772 -342.314725) (xy 256.715266 -342.362301) (xy 256.672861 -342.404706) (xy 256.625285 -342.441212)
			(xy 256.581015 -342.466771) (xy 267.515799 -342.466771) (xy 267.515799 -342.412229) (xy 267.523562 -342.358241)
			(xy 267.538928 -342.305908) (xy 267.561586 -342.256295) (xy 267.591074 -342.210411) (xy 267.626792 -342.16919)
			(xy 267.668012 -342.133473) (xy 267.713897 -342.103985) (xy 267.76351 -342.081327) (xy 267.815843 -342.065961)
			(xy 267.869831 -342.058199) (xy 267.897102 -342.057736) (xy 268.760702 -342.057736) (xy 268.787971 -342.058227)
			(xy 268.841954 -342.065988) (xy 268.894283 -342.081354) (xy 268.943893 -342.10401) (xy 268.989773 -342.133496)
			(xy 269.030991 -342.169211) (xy 269.066705 -342.210428) (xy 269.096191 -342.256309) (xy 269.118847 -342.305919)
			(xy 269.134212 -342.358248) (xy 269.141974 -342.412231) (xy 269.141974 -342.466768) (xy 270.624822 -342.466768)
			(xy 270.624822 -342.412232) (xy 270.632583 -342.358252) (xy 270.647947 -342.305925) (xy 270.6706 -342.256317)
			(xy 270.700083 -342.210438) (xy 270.735794 -342.169221) (xy 270.777007 -342.133505) (xy 270.822884 -342.104018)
			(xy 270.872489 -342.08136) (xy 270.924814 -342.065991) (xy 270.978794 -342.058225) (xy 271.006062 -342.057736)
			(xy 271.869662 -342.057736) (xy 271.896935 -342.058201) (xy 271.950925 -342.065959) (xy 272.003262 -342.081321)
			(xy 272.05288 -342.103977) (xy 272.098768 -342.133463) (xy 272.139993 -342.16918) (xy 272.175714 -342.210401)
			(xy 272.205205 -342.256287) (xy 272.227865 -342.305902) (xy 272.243233 -342.358237) (xy 272.250996 -342.412227)
			(xy 272.250996 -342.466772) (xy 273.7337 -342.466772) (xy 273.7337 -342.412228) (xy 273.741462 -342.358239)
			(xy 273.75683 -342.305904) (xy 273.779489 -342.256289) (xy 273.808979 -342.210404) (xy 273.844699 -342.169183)
			(xy 273.885922 -342.133466) (xy 273.931809 -342.103979) (xy 273.981425 -342.081322) (xy 274.03376 -342.065958)
			(xy 274.08775 -342.058198) (xy 274.115022 -342.057736) (xy 274.978622 -342.057736) (xy 275.00589 -342.058228)
			(xy 275.059871 -342.065992) (xy 275.112198 -342.081359) (xy 275.161805 -342.104017) (xy 275.207683 -342.133503)
			(xy 275.248898 -342.169218) (xy 275.28461 -342.210435) (xy 275.314094 -342.256314) (xy 275.336748 -342.305923)
			(xy 275.352113 -342.35825) (xy 275.359874 -342.412232) (xy 275.359874 -342.466768) (xy 275.359874 -342.466769)
			(xy 276.842722 -342.466769) (xy 276.842722 -342.412231) (xy 276.850484 -342.358249) (xy 276.865848 -342.305921)
			(xy 276.888503 -342.256311) (xy 276.917987 -342.210431) (xy 276.953701 -342.169214) (xy 276.994917 -342.133498)
			(xy 277.040796 -342.104012) (xy 277.090404 -342.081354) (xy 277.142731 -342.065987) (xy 277.196713 -342.058224)
			(xy 277.223982 -342.057736) (xy 278.087582 -342.057736) (xy 278.114854 -342.058202) (xy 278.168842 -342.065962)
			(xy 278.221177 -342.081327) (xy 278.270792 -342.103983) (xy 278.316678 -342.13347) (xy 278.3579 -342.169188)
			(xy 278.393619 -342.210408) (xy 278.423108 -342.256292) (xy 278.445767 -342.305906) (xy 278.461134 -342.35824)
			(xy 278.468896 -342.412228) (xy 278.468896 -342.466772) (xy 278.468896 -342.466773) (xy 279.9516 -342.466773)
			(xy 279.9516 -342.412227) (xy 279.959363 -342.358236) (xy 279.974731 -342.3059) (xy 279.997392 -342.256284)
			(xy 280.026884 -342.210398) (xy 280.062606 -342.169176) (xy 280.103831 -342.133459) (xy 280.14972 -342.103972)
			(xy 280.199339 -342.081317) (xy 280.251677 -342.065954) (xy 280.305669 -342.058197) (xy 280.332942 -342.057736)
			(xy 281.196542 -342.057736) (xy 281.223809 -342.058229) (xy 281.277788 -342.065996) (xy 281.330112 -342.081365)
			(xy 281.379717 -342.104023) (xy 281.425592 -342.13351) (xy 281.466805 -342.169225) (xy 281.502515 -342.210441)
			(xy 281.531997 -342.25632) (xy 281.55465 -342.305927) (xy 281.570013 -342.358253) (xy 281.577774 -342.412233)
			(xy 281.577774 -342.466767) (xy 281.577773 -342.466771) (xy 283.060599 -342.466771) (xy 283.060599 -342.412229)
			(xy 283.068362 -342.358241) (xy 283.083728 -342.305908) (xy 283.106386 -342.256295) (xy 283.135874 -342.210411)
			(xy 283.171592 -342.16919) (xy 283.212812 -342.133473) (xy 283.258697 -342.103985) (xy 283.30831 -342.081327)
			(xy 283.360643 -342.065961) (xy 283.414631 -342.058199) (xy 283.441902 -342.057736) (xy 284.305502 -342.057736)
			(xy 284.332771 -342.058227) (xy 284.386754 -342.065988) (xy 284.439083 -342.081354) (xy 284.488693 -342.10401)
			(xy 284.534573 -342.133496) (xy 284.575791 -342.169211) (xy 284.611505 -342.210428) (xy 284.640991 -342.256309)
			(xy 284.663647 -342.305919) (xy 284.679012 -342.358248) (xy 284.686774 -342.412231) (xy 284.686774 -342.466768)
			(xy 286.169622 -342.466768) (xy 286.169622 -342.412232) (xy 286.177383 -342.358252) (xy 286.192747 -342.305925)
			(xy 286.2154 -342.256317) (xy 286.244883 -342.210438) (xy 286.280594 -342.169221) (xy 286.321807 -342.133505)
			(xy 286.367684 -342.104018) (xy 286.417289 -342.08136) (xy 286.469614 -342.065991) (xy 286.523594 -342.058225)
			(xy 286.550862 -342.057736) (xy 287.414462 -342.057736) (xy 287.441735 -342.058201) (xy 287.495725 -342.065959)
			(xy 287.548062 -342.081321) (xy 287.59768 -342.103977) (xy 287.643568 -342.133463) (xy 287.684793 -342.16918)
			(xy 287.720514 -342.210401) (xy 287.750005 -342.256287) (xy 287.772665 -342.305902) (xy 287.788033 -342.358237)
			(xy 287.795796 -342.412227) (xy 287.795796 -342.466772) (xy 289.2785 -342.466772) (xy 289.2785 -342.412228)
			(xy 289.286262 -342.358239) (xy 289.30163 -342.305904) (xy 289.324289 -342.256289) (xy 289.353779 -342.210404)
			(xy 289.389499 -342.169183) (xy 289.430722 -342.133466) (xy 289.476609 -342.103979) (xy 289.526225 -342.081322)
			(xy 289.57856 -342.065958) (xy 289.63255 -342.058198) (xy 289.659822 -342.057736) (xy 290.523422 -342.057736)
			(xy 290.55069 -342.058228) (xy 290.604671 -342.065992) (xy 290.656998 -342.081359) (xy 290.706605 -342.104017)
			(xy 290.752483 -342.133503) (xy 290.793698 -342.169218) (xy 290.82941 -342.210435) (xy 290.858894 -342.256314)
			(xy 290.881548 -342.305923) (xy 290.896913 -342.35825) (xy 290.904674 -342.412232) (xy 290.904674 -342.466768)
			(xy 290.904674 -342.466769) (xy 292.387522 -342.466769) (xy 292.387522 -342.412231) (xy 292.395284 -342.358249)
			(xy 292.410648 -342.305921) (xy 292.433303 -342.256311) (xy 292.462787 -342.210431) (xy 292.498501 -342.169214)
			(xy 292.539717 -342.133498) (xy 292.585596 -342.104012) (xy 292.635204 -342.081354) (xy 292.687531 -342.065987)
			(xy 292.741513 -342.058224) (xy 292.768782 -342.057736) (xy 293.632382 -342.057736) (xy 293.659654 -342.058202)
			(xy 293.713642 -342.065962) (xy 293.765977 -342.081327) (xy 293.815592 -342.103983) (xy 293.861478 -342.13347)
			(xy 293.9027 -342.169188) (xy 293.938419 -342.210408) (xy 293.967908 -342.256292) (xy 293.990567 -342.305906)
			(xy 294.005934 -342.35824) (xy 294.013696 -342.412228) (xy 294.013696 -342.466772) (xy 294.013696 -342.466773)
			(xy 295.4964 -342.466773) (xy 295.4964 -342.412227) (xy 295.504163 -342.358236) (xy 295.519531 -342.3059)
			(xy 295.542192 -342.256284) (xy 295.571684 -342.210398) (xy 295.607406 -342.169176) (xy 295.648631 -342.133459)
			(xy 295.69452 -342.103972) (xy 295.744139 -342.081317) (xy 295.796477 -342.065954) (xy 295.850469 -342.058197)
			(xy 295.877742 -342.057736) (xy 296.741342 -342.057736) (xy 296.768609 -342.058229) (xy 296.822588 -342.065996)
			(xy 296.874912 -342.081365) (xy 296.924517 -342.104023) (xy 296.970392 -342.13351) (xy 297.011605 -342.169225)
			(xy 297.047315 -342.210441) (xy 297.076797 -342.25632) (xy 297.09945 -342.305927) (xy 297.114813 -342.358253)
			(xy 297.122574 -342.412233) (xy 297.122574 -342.466767) (xy 297.122573 -342.466771) (xy 298.605399 -342.466771)
			(xy 298.605399 -342.412229) (xy 298.613162 -342.358241) (xy 298.628528 -342.305908) (xy 298.651186 -342.256295)
			(xy 298.680674 -342.210411) (xy 298.716392 -342.16919) (xy 298.757612 -342.133473) (xy 298.803497 -342.103985)
			(xy 298.85311 -342.081327) (xy 298.905443 -342.065961) (xy 298.959431 -342.058199) (xy 298.986702 -342.057736)
			(xy 299.850302 -342.057736) (xy 299.877571 -342.058227) (xy 299.931554 -342.065988) (xy 299.983883 -342.081354)
			(xy 300.033493 -342.10401) (xy 300.079373 -342.133496) (xy 300.120591 -342.169211) (xy 300.156305 -342.210428)
			(xy 300.185791 -342.256309) (xy 300.208447 -342.305919) (xy 300.223812 -342.358248) (xy 300.231574 -342.412231)
			(xy 300.231574 -342.466769) (xy 300.231574 -342.466771) (xy 312.1215 -342.466771) (xy 312.1215 -342.412229)
			(xy 312.129262 -342.358241) (xy 312.144628 -342.305908) (xy 312.167286 -342.256294) (xy 312.196774 -342.21041)
			(xy 312.232493 -342.16919) (xy 312.273713 -342.133472) (xy 312.319598 -342.103984) (xy 312.369212 -342.081327)
			(xy 312.421545 -342.065961) (xy 312.475533 -342.058199) (xy 312.502804 -342.057736) (xy 313.366404 -342.057736)
			(xy 313.393673 -342.058227) (xy 313.447656 -342.065989) (xy 313.499985 -342.081354) (xy 313.549594 -342.104011)
			(xy 313.595474 -342.133497) (xy 313.636691 -342.169212) (xy 313.672406 -342.210429) (xy 313.701891 -342.256309)
			(xy 313.724547 -342.305919) (xy 313.739912 -342.358248) (xy 313.747674 -342.412231) (xy 313.747674 -342.466768)
			(xy 315.230522 -342.466768) (xy 315.230522 -342.412232) (xy 315.238283 -342.358251) (xy 315.253647 -342.305924)
			(xy 315.2763 -342.256316) (xy 315.305783 -342.210437) (xy 315.341495 -342.16922) (xy 315.382708 -342.133505)
			(xy 315.428585 -342.104018) (xy 315.478191 -342.081359) (xy 315.530516 -342.065991) (xy 315.584496 -342.058225)
			(xy 315.611764 -342.057736) (xy 316.475364 -342.057736) (xy 316.502637 -342.058201) (xy 316.556627 -342.065959)
			(xy 316.608964 -342.081322) (xy 316.658581 -342.103977) (xy 316.704469 -342.133464) (xy 316.745693 -342.169181)
			(xy 316.781414 -342.210402) (xy 316.810905 -342.256287) (xy 316.833565 -342.305902) (xy 316.848933 -342.358238)
			(xy 316.856696 -342.412228) (xy 316.856696 -342.466772) (xy 318.3394 -342.466772) (xy 318.3394 -342.412228)
			(xy 318.347162 -342.358239) (xy 318.36253 -342.305904) (xy 318.385189 -342.256289) (xy 318.414679 -342.210404)
			(xy 318.4504 -342.169183) (xy 318.491623 -342.133465) (xy 318.53751 -342.103978) (xy 318.587126 -342.081322)
			(xy 318.639462 -342.065957) (xy 318.693452 -342.058198) (xy 318.720724 -342.057736) (xy 319.584324 -342.057736)
			(xy 319.611592 -342.058228) (xy 319.665573 -342.065992) (xy 319.717899 -342.08136) (xy 319.767506 -342.104017)
			(xy 319.813384 -342.133504) (xy 319.854598 -342.169219) (xy 319.890311 -342.210435) (xy 319.919794 -342.256315)
			(xy 319.942449 -342.305923) (xy 319.957813 -342.358251) (xy 319.965574 -342.412232) (xy 319.965574 -342.466768)
			(xy 319.965574 -342.466769) (xy 321.448422 -342.466769) (xy 321.448422 -342.412231) (xy 321.456184 -342.358249)
			(xy 321.471548 -342.30592) (xy 321.494203 -342.256311) (xy 321.523688 -342.21043) (xy 321.559402 -342.169213)
			(xy 321.600618 -342.133498) (xy 321.646497 -342.104011) (xy 321.696105 -342.081354) (xy 321.748433 -342.065987)
			(xy 321.802415 -342.058224) (xy 321.829684 -342.057736) (xy 322.693284 -342.057736) (xy 322.720556 -342.058202)
			(xy 322.774544 -342.065963) (xy 322.826878 -342.081327) (xy 322.876493 -342.103984) (xy 322.922379 -342.133471)
			(xy 322.9636 -342.169188) (xy 322.999319 -342.210409) (xy 323.028808 -342.256293) (xy 323.051467 -342.305907)
			(xy 323.066834 -342.35824) (xy 323.074596 -342.412228) (xy 323.074596 -342.466772) (xy 323.074596 -342.466773)
			(xy 324.5573 -342.466773) (xy 324.5573 -342.412227) (xy 324.565063 -342.358236) (xy 324.580432 -342.305899)
			(xy 324.603092 -342.256283) (xy 324.632584 -342.210397) (xy 324.668307 -342.169176) (xy 324.709532 -342.133458)
			(xy 324.755422 -342.103971) (xy 324.805041 -342.081316) (xy 324.857379 -342.065954) (xy 324.911371 -342.058196)
			(xy 324.938644 -342.057736) (xy 325.802244 -342.057736) (xy 325.829511 -342.058229) (xy 325.88349 -342.065996)
			(xy 325.935814 -342.081365) (xy 325.985418 -342.104024) (xy 326.031293 -342.133511) (xy 326.072505 -342.169226)
			(xy 326.108216 -342.210442) (xy 326.137697 -342.256321) (xy 326.16035 -342.305928) (xy 326.175713 -342.358253)
			(xy 326.183474 -342.412233) (xy 326.183474 -342.466767) (xy 326.183473 -342.466771) (xy 327.6663 -342.466771)
			(xy 327.6663 -342.412229) (xy 327.674062 -342.358241) (xy 327.689428 -342.305908) (xy 327.712086 -342.256294)
			(xy 327.741574 -342.21041) (xy 327.777293 -342.16919) (xy 327.818513 -342.133472) (xy 327.864398 -342.103984)
			(xy 327.914012 -342.081327) (xy 327.966345 -342.065961) (xy 328.020333 -342.058199) (xy 328.047604 -342.057736)
			(xy 328.911204 -342.057736) (xy 328.938473 -342.058227) (xy 328.992456 -342.065989) (xy 329.044785 -342.081354)
			(xy 329.094394 -342.104011) (xy 329.140274 -342.133497) (xy 329.181491 -342.169212) (xy 329.217206 -342.210429)
			(xy 329.246691 -342.256309) (xy 329.269347 -342.305919) (xy 329.284712 -342.358248) (xy 329.292474 -342.412231)
			(xy 329.292474 -342.466768) (xy 330.775322 -342.466768) (xy 330.775322 -342.412232) (xy 330.783083 -342.358251)
			(xy 330.798447 -342.305924) (xy 330.8211 -342.256316) (xy 330.850583 -342.210437) (xy 330.886295 -342.16922)
			(xy 330.927508 -342.133505) (xy 330.973385 -342.104018) (xy 331.022991 -342.081359) (xy 331.075316 -342.065991)
			(xy 331.129296 -342.058225) (xy 331.156564 -342.057736) (xy 332.020164 -342.057736) (xy 332.047437 -342.058201)
			(xy 332.101427 -342.065959) (xy 332.153764 -342.081322) (xy 332.203381 -342.103977) (xy 332.249269 -342.133464)
			(xy 332.290493 -342.169181) (xy 332.326214 -342.210402) (xy 332.355705 -342.256287) (xy 332.378365 -342.305902)
			(xy 332.393733 -342.358238) (xy 332.401496 -342.412228) (xy 332.401496 -342.466772) (xy 333.8842 -342.466772)
			(xy 333.8842 -342.412228) (xy 333.891962 -342.358239) (xy 333.90733 -342.305904) (xy 333.929989 -342.256289)
			(xy 333.959479 -342.210404) (xy 333.9952 -342.169183) (xy 334.036423 -342.133465) (xy 334.08231 -342.103978)
			(xy 334.131926 -342.081322) (xy 334.184262 -342.065957) (xy 334.238252 -342.058198) (xy 334.265524 -342.057736)
			(xy 335.129124 -342.057736) (xy 335.156392 -342.058228) (xy 335.210373 -342.065992) (xy 335.262699 -342.08136)
			(xy 335.312306 -342.104017) (xy 335.358184 -342.133504) (xy 335.399398 -342.169219) (xy 335.435111 -342.210435)
			(xy 335.464594 -342.256315) (xy 335.487249 -342.305923) (xy 335.502613 -342.358251) (xy 335.510374 -342.412232)
			(xy 335.510374 -342.466768) (xy 335.510374 -342.466769) (xy 336.993222 -342.466769) (xy 336.993222 -342.412231)
			(xy 337.000984 -342.358249) (xy 337.016348 -342.30592) (xy 337.039003 -342.256311) (xy 337.068488 -342.21043)
			(xy 337.104202 -342.169213) (xy 337.145418 -342.133498) (xy 337.191297 -342.104011) (xy 337.240905 -342.081354)
			(xy 337.293233 -342.065987) (xy 337.347215 -342.058224) (xy 337.374484 -342.057736) (xy 338.238084 -342.057736)
			(xy 338.265356 -342.058202) (xy 338.319344 -342.065963) (xy 338.371678 -342.081327) (xy 338.421293 -342.103984)
			(xy 338.467179 -342.133471) (xy 338.5084 -342.169188) (xy 338.544119 -342.210409) (xy 338.573608 -342.256293)
			(xy 338.596267 -342.305907) (xy 338.611634 -342.35824) (xy 338.619396 -342.412228) (xy 338.619396 -342.466772)
			(xy 338.619396 -342.466773) (xy 340.1021 -342.466773) (xy 340.1021 -342.412227) (xy 340.109863 -342.358236)
			(xy 340.125232 -342.305899) (xy 340.147892 -342.256283) (xy 340.177384 -342.210397) (xy 340.213107 -342.169176)
			(xy 340.254332 -342.133458) (xy 340.300222 -342.103971) (xy 340.349841 -342.081316) (xy 340.402179 -342.065954)
			(xy 340.456171 -342.058196) (xy 340.483444 -342.057736) (xy 341.347044 -342.057736) (xy 341.374311 -342.058229)
			(xy 341.42829 -342.065996) (xy 341.480614 -342.081365) (xy 341.530218 -342.104024) (xy 341.576093 -342.133511)
			(xy 341.617305 -342.169226) (xy 341.653016 -342.210442) (xy 341.682497 -342.256321) (xy 341.70515 -342.305928)
			(xy 341.720513 -342.358253) (xy 341.728274 -342.412233) (xy 341.728274 -342.466767) (xy 341.728273 -342.466771)
			(xy 343.2111 -342.466771) (xy 343.2111 -342.412229) (xy 343.218862 -342.358241) (xy 343.234228 -342.305908)
			(xy 343.256886 -342.256294) (xy 343.286374 -342.21041) (xy 343.322093 -342.16919) (xy 343.363313 -342.133472)
			(xy 343.409198 -342.103984) (xy 343.458812 -342.081327) (xy 343.511145 -342.065961) (xy 343.565133 -342.058199)
			(xy 343.592404 -342.057736) (xy 344.456004 -342.057736) (xy 344.483273 -342.058227) (xy 344.537256 -342.065989)
			(xy 344.589585 -342.081354) (xy 344.639194 -342.104011) (xy 344.685074 -342.133497) (xy 344.726291 -342.169212)
			(xy 344.762006 -342.210429) (xy 344.791491 -342.256309) (xy 344.814147 -342.305919) (xy 344.829512 -342.358248)
			(xy 344.837274 -342.412231) (xy 344.837274 -342.466769) (xy 370.806722 -342.466769) (xy 370.806722 -342.412231)
			(xy 370.814484 -342.358249) (xy 370.829848 -342.305921) (xy 370.852503 -342.256312) (xy 370.881987 -342.210432)
			(xy 370.9177 -342.169214) (xy 370.958916 -342.133499) (xy 371.004794 -342.104012) (xy 371.054402 -342.081355)
			(xy 371.10673 -342.065988) (xy 371.160711 -342.058224) (xy 371.18798 -342.057736) (xy 372.05158 -342.057736)
			(xy 372.078852 -342.058202) (xy 372.132841 -342.065962) (xy 372.185175 -342.081326) (xy 372.234791 -342.103983)
			(xy 372.280677 -342.13347) (xy 372.321899 -342.169187) (xy 372.357618 -342.210407) (xy 372.387108 -342.256292)
			(xy 372.409767 -342.305906) (xy 372.425134 -342.35824) (xy 372.432896 -342.412228) (xy 372.432896 -342.466772)
			(xy 372.432896 -342.466773) (xy 373.9156 -342.466773) (xy 373.9156 -342.412227) (xy 373.923363 -342.358236)
			(xy 373.938731 -342.3059) (xy 373.961392 -342.256284) (xy 373.990883 -342.210398) (xy 374.026605 -342.169177)
			(xy 374.06783 -342.133459) (xy 374.113719 -342.103973) (xy 374.163338 -342.081317) (xy 374.215676 -342.065954)
			(xy 374.269667 -342.058197) (xy 374.29694 -342.057736) (xy 375.16054 -342.057736) (xy 375.187807 -342.058229)
			(xy 375.241786 -342.065995) (xy 375.294111 -342.081364) (xy 375.343716 -342.104022) (xy 375.389591 -342.133509)
			(xy 375.430804 -342.169224) (xy 375.466515 -342.210441) (xy 375.495997 -342.256319) (xy 375.51865 -342.305927)
			(xy 375.534013 -342.358253) (xy 375.541774 -342.412233) (xy 375.541774 -342.466767) (xy 375.541774 -342.46677)
			(xy 377.024622 -342.46677) (xy 377.024622 -342.41223) (xy 377.032384 -342.358247) (xy 377.04775 -342.305917)
			(xy 377.070406 -342.256306) (xy 377.099892 -342.210425) (xy 377.135607 -342.169207) (xy 377.176825 -342.133492)
			(xy 377.222706 -342.104006) (xy 377.272317 -342.08135) (xy 377.324647 -342.065984) (xy 377.37863 -342.058222)
			(xy 377.4059 -342.057736) (xy 378.2695 -342.057736) (xy 378.296769 -342.058226) (xy 378.350753 -342.065988)
			(xy 378.403082 -342.081353) (xy 378.452692 -342.104009) (xy 378.498572 -342.133495) (xy 378.53979 -342.16921)
			(xy 378.575505 -342.210428) (xy 378.604991 -342.256308) (xy 378.627647 -342.305918) (xy 378.643012 -342.358247)
			(xy 378.650774 -342.412231) (xy 378.650774 -342.466768) (xy 380.133622 -342.466768) (xy 380.133622 -342.412232)
			(xy 380.141383 -342.358252) (xy 380.156746 -342.305925) (xy 380.1794 -342.256318) (xy 380.208882 -342.210438)
			(xy 380.244593 -342.169222) (xy 380.285806 -342.133506) (xy 380.331682 -342.104019) (xy 380.381288 -342.08136)
			(xy 380.433613 -342.065991) (xy 380.487592 -342.058225) (xy 380.51486 -342.057736) (xy 381.37846 -342.057736)
			(xy 381.405733 -342.058201) (xy 381.459724 -342.065958) (xy 381.512061 -342.081321) (xy 381.561679 -342.103976)
			(xy 381.607567 -342.133463) (xy 381.648792 -342.16918) (xy 381.684513 -342.210401) (xy 381.714005 -342.256286)
			(xy 381.736665 -342.305902) (xy 381.752033 -342.358237) (xy 381.759796 -342.412227) (xy 381.759796 -342.466772)
			(xy 383.2425 -342.466772) (xy 383.2425 -342.412228) (xy 383.250262 -342.358239) (xy 383.26563 -342.305904)
			(xy 383.288289 -342.25629) (xy 383.317778 -342.210405) (xy 383.353498 -342.169184) (xy 383.394721 -342.133466)
			(xy 383.440607 -342.103979) (xy 383.490223 -342.081323) (xy 383.542559 -342.065958) (xy 383.596548 -342.058198)
			(xy 383.62382 -342.057736) (xy 384.48742 -342.057736) (xy 384.514688 -342.058228) (xy 384.568669 -342.065992)
			(xy 384.620996 -342.081359) (xy 384.670604 -342.104016) (xy 384.716482 -342.133502) (xy 384.757697 -342.169217)
			(xy 384.79341 -342.210434) (xy 384.822894 -342.256314) (xy 384.845548 -342.305922) (xy 384.860913 -342.35825)
			(xy 384.868674 -342.412232) (xy 384.868674 -342.466768) (xy 384.868674 -342.466769) (xy 386.351522 -342.466769)
			(xy 386.351522 -342.412231) (xy 386.359284 -342.358249) (xy 386.374648 -342.305921) (xy 386.397303 -342.256312)
			(xy 386.426787 -342.210432) (xy 386.4625 -342.169214) (xy 386.503716 -342.133499) (xy 386.549594 -342.104012)
			(xy 386.599202 -342.081355) (xy 386.65153 -342.065988) (xy 386.705511 -342.058224) (xy 386.73278 -342.057736)
			(xy 387.59638 -342.057736) (xy 387.623652 -342.058202) (xy 387.677641 -342.065962) (xy 387.729975 -342.081326)
			(xy 387.779591 -342.103983) (xy 387.825477 -342.13347) (xy 387.866699 -342.169187) (xy 387.902418 -342.210407)
			(xy 387.931908 -342.256292) (xy 387.954567 -342.305906) (xy 387.969934 -342.35824) (xy 387.977696 -342.412228)
			(xy 387.977696 -342.466772) (xy 387.977696 -342.466773) (xy 389.4604 -342.466773) (xy 389.4604 -342.412227)
			(xy 389.468163 -342.358236) (xy 389.483531 -342.3059) (xy 389.506192 -342.256284) (xy 389.535683 -342.210398)
			(xy 389.571405 -342.169177) (xy 389.61263 -342.133459) (xy 389.658519 -342.103973) (xy 389.708138 -342.081317)
			(xy 389.760476 -342.065954) (xy 389.814467 -342.058197) (xy 389.84174 -342.057736) (xy 390.70534 -342.057736)
			(xy 390.732607 -342.058229) (xy 390.786586 -342.065995) (xy 390.838911 -342.081364) (xy 390.888516 -342.104022)
			(xy 390.934391 -342.133509) (xy 390.975604 -342.169224) (xy 391.011315 -342.210441) (xy 391.040797 -342.256319)
			(xy 391.06345 -342.305927) (xy 391.078813 -342.358253) (xy 391.086574 -342.412233) (xy 391.086574 -342.466767)
			(xy 391.086574 -342.46677) (xy 392.569422 -342.46677) (xy 392.569422 -342.41223) (xy 392.577184 -342.358247)
			(xy 392.59255 -342.305917) (xy 392.615206 -342.256306) (xy 392.644692 -342.210425) (xy 392.680407 -342.169207)
			(xy 392.721625 -342.133492) (xy 392.767506 -342.104006) (xy 392.817117 -342.08135) (xy 392.869447 -342.065984)
			(xy 392.92343 -342.058222) (xy 392.9507 -342.057736) (xy 393.8143 -342.057736) (xy 393.841569 -342.058226)
			(xy 393.895553 -342.065988) (xy 393.947882 -342.081353) (xy 393.997492 -342.104009) (xy 394.043372 -342.133495)
			(xy 394.08459 -342.16921) (xy 394.120305 -342.210428) (xy 394.149791 -342.256308) (xy 394.172447 -342.305918)
			(xy 394.187812 -342.358247) (xy 394.195574 -342.412231) (xy 394.195574 -342.466768) (xy 395.678422 -342.466768)
			(xy 395.678422 -342.412232) (xy 395.686183 -342.358252) (xy 395.701546 -342.305925) (xy 395.7242 -342.256318)
			(xy 395.753682 -342.210438) (xy 395.789393 -342.169222) (xy 395.830606 -342.133506) (xy 395.876482 -342.104019)
			(xy 395.926088 -342.08136) (xy 395.978413 -342.065991) (xy 396.032392 -342.058225) (xy 396.05966 -342.057736)
			(xy 396.92326 -342.057736) (xy 396.950533 -342.058201) (xy 397.004524 -342.065958) (xy 397.056861 -342.081321)
			(xy 397.106479 -342.103976) (xy 397.152367 -342.133463) (xy 397.193592 -342.16918) (xy 397.229313 -342.210401)
			(xy 397.258805 -342.256286) (xy 397.281465 -342.305902) (xy 397.296833 -342.358237) (xy 397.304596 -342.412227)
			(xy 397.304596 -342.466772) (xy 398.7873 -342.466772) (xy 398.7873 -342.412228) (xy 398.795062 -342.358239)
			(xy 398.81043 -342.305904) (xy 398.833089 -342.25629) (xy 398.862578 -342.210405) (xy 398.898298 -342.169184)
			(xy 398.939521 -342.133466) (xy 398.985407 -342.103979) (xy 399.035023 -342.081323) (xy 399.087359 -342.065958)
			(xy 399.141348 -342.058198) (xy 399.16862 -342.057736) (xy 400.03222 -342.057736) (xy 400.059488 -342.058228)
			(xy 400.113469 -342.065992) (xy 400.165796 -342.081359) (xy 400.215404 -342.104016) (xy 400.261282 -342.133502)
			(xy 400.302497 -342.169217) (xy 400.33821 -342.210434) (xy 400.367694 -342.256314) (xy 400.390348 -342.305922)
			(xy 400.405713 -342.35825) (xy 400.413474 -342.412232) (xy 400.413474 -342.466768) (xy 400.413474 -342.466769)
			(xy 401.896322 -342.466769) (xy 401.896322 -342.412231) (xy 401.904084 -342.358249) (xy 401.919448 -342.305921)
			(xy 401.942103 -342.256312) (xy 401.971587 -342.210432) (xy 402.0073 -342.169214) (xy 402.048516 -342.133499)
			(xy 402.094394 -342.104012) (xy 402.144002 -342.081355) (xy 402.19633 -342.065988) (xy 402.250311 -342.058224)
			(xy 402.27758 -342.057736) (xy 403.14118 -342.057736) (xy 403.168452 -342.058202) (xy 403.222441 -342.065962)
			(xy 403.274775 -342.081326) (xy 403.324391 -342.103983) (xy 403.370277 -342.13347) (xy 403.411499 -342.169187)
			(xy 403.447218 -342.210407) (xy 403.476708 -342.256292) (xy 403.499367 -342.305906) (xy 403.514734 -342.35824)
			(xy 403.522496 -342.412228) (xy 403.522496 -342.466769) (xy 408.913822 -342.466769) (xy 408.913822 -342.412231)
			(xy 408.921584 -342.358248) (xy 408.936949 -342.305918) (xy 408.959605 -342.256309) (xy 408.98909 -342.210428)
			(xy 409.024805 -342.16921) (xy 409.066021 -342.133495) (xy 409.111902 -342.104009) (xy 409.161511 -342.081352)
			(xy 409.21384 -342.065986) (xy 409.267823 -342.058223) (xy 409.295092 -342.057736) (xy 410.158692 -342.057736)
			(xy 410.185963 -342.058203) (xy 410.239951 -342.065964) (xy 410.292284 -342.08133) (xy 410.341898 -342.103987)
			(xy 410.387782 -342.133474) (xy 410.429003 -342.169191) (xy 410.464721 -342.210411) (xy 410.49421 -342.256295)
			(xy 410.516868 -342.305908) (xy 410.532234 -342.358241) (xy 410.539996 -342.412229) (xy 410.539996 -342.466767)
			(xy 412.022822 -342.466767) (xy 412.022822 -342.412233) (xy 412.030583 -342.358253) (xy 412.045946 -342.305927)
			(xy 412.068599 -342.25632) (xy 412.09808 -342.210441) (xy 412.13379 -342.169224) (xy 412.175002 -342.133509)
			(xy 412.220878 -342.104022) (xy 412.270482 -342.081363) (xy 412.322806 -342.065993) (xy 412.376785 -342.058226)
			(xy 412.404052 -342.057736) (xy 413.267652 -342.057736) (xy 413.294925 -342.0582) (xy 413.348917 -342.065957)
			(xy 413.401255 -342.081319) (xy 413.450874 -342.103974) (xy 413.496763 -342.13346) (xy 413.537989 -342.169177)
			(xy 413.573712 -342.210398) (xy 413.603203 -342.256284) (xy 413.625864 -342.3059) (xy 413.641233 -342.358236)
			(xy 413.648996 -342.412227) (xy 413.648996 -342.466772) (xy 415.1317 -342.466772) (xy 415.1317 -342.412228)
			(xy 415.139462 -342.35824) (xy 415.154829 -342.305906) (xy 415.177488 -342.256292) (xy 415.206976 -342.210407)
			(xy 415.242695 -342.169187) (xy 415.283917 -342.133469) (xy 415.329803 -342.103982) (xy 415.379417 -342.081325)
			(xy 415.431752 -342.065959) (xy 415.48574 -342.058199) (xy 415.513012 -342.057736) (xy 416.376612 -342.057736)
			(xy 416.403881 -342.058227) (xy 416.457863 -342.06599) (xy 416.510191 -342.081357) (xy 416.559799 -342.104013)
			(xy 416.605678 -342.133499) (xy 416.646894 -342.169214) (xy 416.682608 -342.210432) (xy 416.712092 -342.256312)
			(xy 416.734748 -342.305921) (xy 416.750112 -342.358249) (xy 416.757874 -342.412231) (xy 416.757874 -342.466768)
			(xy 418.240722 -342.466768) (xy 418.240722 -342.412232) (xy 418.248483 -342.35825) (xy 418.263847 -342.305923)
			(xy 418.286502 -342.256314) (xy 418.315985 -342.210434) (xy 418.351697 -342.169217) (xy 418.392912 -342.133502)
			(xy 418.43879 -342.104015) (xy 418.488396 -342.081357) (xy 418.540723 -342.065989) (xy 418.594704 -342.058224)
			(xy 418.621972 -342.057736) (xy 419.485572 -342.057736) (xy 419.512844 -342.058202) (xy 419.566834 -342.06596)
			(xy 419.61917 -342.081324) (xy 419.668786 -342.10398) (xy 419.714673 -342.133467) (xy 419.755896 -342.169184)
			(xy 419.791616 -342.210405) (xy 419.821107 -342.256289) (xy 419.843766 -342.305904) (xy 419.859134 -342.358239)
			(xy 419.866896 -342.412228) (xy 419.866896 -342.466772) (xy 419.866896 -342.466773) (xy 421.3496 -342.466773)
			(xy 421.3496 -342.412227) (xy 421.357363 -342.358237) (xy 421.372731 -342.305902) (xy 421.395391 -342.256286)
			(xy 421.424881 -342.210401) (xy 421.460602 -342.16918) (xy 421.501827 -342.133462) (xy 421.547715 -342.103975)
			(xy 421.597332 -342.081319) (xy 421.649669 -342.065956) (xy 421.703659 -342.058197) (xy 421.730932 -342.057736)
			(xy 422.594532 -342.057736) (xy 422.6218 -342.058229) (xy 422.67578 -342.065994) (xy 422.728105 -342.081362)
			(xy 422.777711 -342.10402) (xy 422.823588 -342.133506) (xy 422.864801 -342.169222) (xy 422.900513 -342.210438)
			(xy 422.929995 -342.256317) (xy 422.952649 -342.305925) (xy 422.968013 -342.358252) (xy 422.975774 -342.412232)
			(xy 422.975774 -342.466768) (xy 422.975774 -342.466769) (xy 424.458622 -342.466769) (xy 424.458622 -342.412231)
			(xy 424.466384 -342.358248) (xy 424.481749 -342.305918) (xy 424.504405 -342.256309) (xy 424.53389 -342.210428)
			(xy 424.569605 -342.16921) (xy 424.610821 -342.133495) (xy 424.656702 -342.104009) (xy 424.706311 -342.081352)
			(xy 424.75864 -342.065986) (xy 424.812623 -342.058223) (xy 424.839892 -342.057736) (xy 425.703492 -342.057736)
			(xy 425.730763 -342.058203) (xy 425.784751 -342.065964) (xy 425.837084 -342.08133) (xy 425.886698 -342.103987)
			(xy 425.932582 -342.133474) (xy 425.973803 -342.169191) (xy 426.009521 -342.210411) (xy 426.03901 -342.256295)
			(xy 426.061668 -342.305908) (xy 426.077034 -342.358241) (xy 426.084796 -342.412229) (xy 426.084796 -342.466767)
			(xy 427.567622 -342.466767) (xy 427.567622 -342.412233) (xy 427.575383 -342.358253) (xy 427.590746 -342.305927)
			(xy 427.613399 -342.25632) (xy 427.64288 -342.210441) (xy 427.67859 -342.169224) (xy 427.719802 -342.133509)
			(xy 427.765678 -342.104022) (xy 427.815282 -342.081363) (xy 427.867606 -342.065993) (xy 427.921585 -342.058226)
			(xy 427.948852 -342.057736) (xy 428.812452 -342.057736) (xy 428.839725 -342.0582) (xy 428.893717 -342.065957)
			(xy 428.946055 -342.081319) (xy 428.995674 -342.103974) (xy 429.041563 -342.13346) (xy 429.082789 -342.169177)
			(xy 429.118512 -342.210398) (xy 429.148003 -342.256284) (xy 429.170664 -342.3059) (xy 429.186033 -342.358236)
			(xy 429.193796 -342.412227) (xy 429.193796 -342.466772) (xy 430.6765 -342.466772) (xy 430.6765 -342.412228)
			(xy 430.684262 -342.35824) (xy 430.699629 -342.305906) (xy 430.722288 -342.256292) (xy 430.751776 -342.210407)
			(xy 430.787495 -342.169187) (xy 430.828717 -342.133469) (xy 430.874603 -342.103982) (xy 430.924217 -342.081325)
			(xy 430.976552 -342.065959) (xy 431.03054 -342.058199) (xy 431.057812 -342.057736) (xy 431.921412 -342.057736)
			(xy 431.948681 -342.058227) (xy 432.002663 -342.06599) (xy 432.054991 -342.081357) (xy 432.104599 -342.104013)
			(xy 432.150478 -342.133499) (xy 432.191694 -342.169214) (xy 432.227408 -342.210432) (xy 432.256892 -342.256312)
			(xy 432.279548 -342.305921) (xy 432.294912 -342.358249) (xy 432.302674 -342.412231) (xy 432.302674 -342.466768)
			(xy 433.785522 -342.466768) (xy 433.785522 -342.412232) (xy 433.793283 -342.35825) (xy 433.808647 -342.305923)
			(xy 433.831302 -342.256314) (xy 433.860785 -342.210434) (xy 433.896497 -342.169217) (xy 433.937712 -342.133502)
			(xy 433.98359 -342.104015) (xy 434.033196 -342.081357) (xy 434.085523 -342.065989) (xy 434.139504 -342.058224)
			(xy 434.166772 -342.057736) (xy 435.030372 -342.057736) (xy 435.057644 -342.058202) (xy 435.111634 -342.06596)
			(xy 435.16397 -342.081324) (xy 435.213586 -342.10398) (xy 435.259473 -342.133467) (xy 435.300696 -342.169184)
			(xy 435.336416 -342.210405) (xy 435.365907 -342.256289) (xy 435.388566 -342.305904) (xy 435.403934 -342.358239)
			(xy 435.411696 -342.412228) (xy 435.411696 -342.466772) (xy 435.411696 -342.466773) (xy 436.8944 -342.466773)
			(xy 436.8944 -342.412227) (xy 436.902163 -342.358237) (xy 436.917531 -342.305902) (xy 436.940191 -342.256286)
			(xy 436.969681 -342.210401) (xy 437.005402 -342.16918) (xy 437.046627 -342.133462) (xy 437.092515 -342.103975)
			(xy 437.142132 -342.081319) (xy 437.194469 -342.065956) (xy 437.248459 -342.058197) (xy 437.275732 -342.057736)
			(xy 438.139332 -342.057736) (xy 438.1666 -342.058229) (xy 438.22058 -342.065994) (xy 438.272905 -342.081362)
			(xy 438.322511 -342.10402) (xy 438.368388 -342.133506) (xy 438.409601 -342.169222) (xy 438.445313 -342.210438)
			(xy 438.474795 -342.256317) (xy 438.497449 -342.305925) (xy 438.512813 -342.358252) (xy 438.520574 -342.412232)
			(xy 438.520574 -342.466768) (xy 438.520574 -342.466769) (xy 440.003422 -342.466769) (xy 440.003422 -342.412231)
			(xy 440.011184 -342.358248) (xy 440.026549 -342.305918) (xy 440.049205 -342.256309) (xy 440.07869 -342.210428)
			(xy 440.114405 -342.16921) (xy 440.155621 -342.133495) (xy 440.201502 -342.104009) (xy 440.251111 -342.081352)
			(xy 440.30344 -342.065986) (xy 440.357423 -342.058223) (xy 440.384692 -342.057736) (xy 441.248292 -342.057736)
			(xy 441.275563 -342.058203) (xy 441.329551 -342.065964) (xy 441.381884 -342.08133) (xy 441.431498 -342.103987)
			(xy 441.477382 -342.133474) (xy 441.518603 -342.169191) (xy 441.554321 -342.210411) (xy 441.58381 -342.256295)
			(xy 441.606468 -342.305908) (xy 441.621834 -342.358241) (xy 441.629596 -342.412229) (xy 441.629596 -342.466771)
			(xy 441.621834 -342.520759) (xy 441.606468 -342.573092) (xy 441.58381 -342.622705) (xy 441.554321 -342.668589)
			(xy 441.518603 -342.709809) (xy 441.477382 -342.745526) (xy 441.431498 -342.775013) (xy 441.381884 -342.79767)
			(xy 441.329551 -342.813036) (xy 441.275563 -342.820797) (xy 441.248292 -342.82126) (xy 440.384692 -342.82126)
			(xy 440.357423 -342.820777) (xy 440.30344 -342.813014) (xy 440.251111 -342.797648) (xy 440.201502 -342.774991)
			(xy 440.155621 -342.745505) (xy 440.114405 -342.70979) (xy 440.07869 -342.668572) (xy 440.049205 -342.622691)
			(xy 440.026549 -342.573082) (xy 440.011184 -342.520752) (xy 440.003422 -342.466769) (xy 438.520574 -342.466769)
			(xy 438.512813 -342.520748) (xy 438.497449 -342.573075) (xy 438.474795 -342.622683) (xy 438.445313 -342.668562)
			(xy 438.409601 -342.709778) (xy 438.368388 -342.745494) (xy 438.322511 -342.77498) (xy 438.272905 -342.797638)
			(xy 438.22058 -342.813006) (xy 438.1666 -342.820771) (xy 438.139332 -342.82126) (xy 437.275732 -342.82126)
			(xy 437.248459 -342.820803) (xy 437.194469 -342.813044) (xy 437.142132 -342.797681) (xy 437.092515 -342.775025)
			(xy 437.046627 -342.745538) (xy 437.005402 -342.70982) (xy 436.969681 -342.668599) (xy 436.940191 -342.622714)
			(xy 436.917531 -342.573098) (xy 436.902163 -342.520763) (xy 436.8944 -342.466773) (xy 435.411696 -342.466773)
			(xy 435.403934 -342.520761) (xy 435.388566 -342.573096) (xy 435.365907 -342.622711) (xy 435.336416 -342.668595)
			(xy 435.300696 -342.709816) (xy 435.259473 -342.745533) (xy 435.213586 -342.77502) (xy 435.16397 -342.797676)
			(xy 435.111634 -342.81304) (xy 435.057644 -342.820798) (xy 435.030372 -342.82126) (xy 434.166772 -342.82126)
			(xy 434.139504 -342.820776) (xy 434.085523 -342.813011) (xy 434.033196 -342.797643) (xy 433.98359 -342.774985)
			(xy 433.937712 -342.745498) (xy 433.896497 -342.709783) (xy 433.860785 -342.668566) (xy 433.831302 -342.622686)
			(xy 433.808647 -342.573077) (xy 433.793283 -342.52075) (xy 433.785522 -342.466768) (xy 432.302674 -342.466768)
			(xy 432.302674 -342.466769) (xy 432.294912 -342.520751) (xy 432.279548 -342.573079) (xy 432.256892 -342.622688)
			(xy 432.227408 -342.668568) (xy 432.191694 -342.709786) (xy 432.150478 -342.745501) (xy 432.104599 -342.774987)
			(xy 432.054991 -342.797643) (xy 432.002663 -342.81301) (xy 431.948681 -342.820773) (xy 431.921412 -342.82126)
			(xy 431.057812 -342.82126) (xy 431.03054 -342.820801) (xy 430.976552 -342.813041) (xy 430.924217 -342.797675)
			(xy 430.874603 -342.775018) (xy 430.828717 -342.745531) (xy 430.787495 -342.709813) (xy 430.751776 -342.668593)
			(xy 430.722288 -342.622708) (xy 430.699629 -342.573094) (xy 430.684262 -342.52076) (xy 430.6765 -342.466772)
			(xy 429.193796 -342.466772) (xy 429.193796 -342.466773) (xy 429.186033 -342.520764) (xy 429.170664 -342.5731)
			(xy 429.148003 -342.622716) (xy 429.118512 -342.668602) (xy 429.082789 -342.709823) (xy 429.041563 -342.74554)
			(xy 428.995674 -342.775026) (xy 428.946055 -342.797681) (xy 428.893717 -342.813043) (xy 428.839725 -342.8208)
			(xy 428.812452 -342.82126) (xy 427.948852 -342.82126) (xy 427.921585 -342.820774) (xy 427.867606 -342.813007)
			(xy 427.815282 -342.797637) (xy 427.765678 -342.774978) (xy 427.719802 -342.745491) (xy 427.67859 -342.709776)
			(xy 427.64288 -342.668559) (xy 427.613399 -342.62268) (xy 427.590746 -342.573073) (xy 427.575383 -342.520747)
			(xy 427.567622 -342.466767) (xy 426.084796 -342.466767) (xy 426.084796 -342.466771) (xy 426.077034 -342.520759)
			(xy 426.061668 -342.573092) (xy 426.03901 -342.622705) (xy 426.009521 -342.668589) (xy 425.973803 -342.709809)
			(xy 425.932582 -342.745526) (xy 425.886698 -342.775013) (xy 425.837084 -342.79767) (xy 425.784751 -342.813036)
			(xy 425.730763 -342.820797) (xy 425.703492 -342.82126) (xy 424.839892 -342.82126) (xy 424.812623 -342.820777)
			(xy 424.75864 -342.813014) (xy 424.706311 -342.797648) (xy 424.656702 -342.774991) (xy 424.610821 -342.745505)
			(xy 424.569605 -342.70979) (xy 424.53389 -342.668572) (xy 424.504405 -342.622691) (xy 424.481749 -342.573082)
			(xy 424.466384 -342.520752) (xy 424.458622 -342.466769) (xy 422.975774 -342.466769) (xy 422.968013 -342.520748)
			(xy 422.952649 -342.573075) (xy 422.929995 -342.622683) (xy 422.900513 -342.668562) (xy 422.864801 -342.709778)
			(xy 422.823588 -342.745494) (xy 422.777711 -342.77498) (xy 422.728105 -342.797638) (xy 422.67578 -342.813006)
			(xy 422.6218 -342.820771) (xy 422.594532 -342.82126) (xy 421.730932 -342.82126) (xy 421.703659 -342.820803)
			(xy 421.649669 -342.813044) (xy 421.597332 -342.797681) (xy 421.547715 -342.775025) (xy 421.501827 -342.745538)
			(xy 421.460602 -342.70982) (xy 421.424881 -342.668599) (xy 421.395391 -342.622714) (xy 421.372731 -342.573098)
			(xy 421.357363 -342.520763) (xy 421.3496 -342.466773) (xy 419.866896 -342.466773) (xy 419.859134 -342.520761)
			(xy 419.843766 -342.573096) (xy 419.821107 -342.622711) (xy 419.791616 -342.668595) (xy 419.755896 -342.709816)
			(xy 419.714673 -342.745533) (xy 419.668786 -342.77502) (xy 419.61917 -342.797676) (xy 419.566834 -342.81304)
			(xy 419.512844 -342.820798) (xy 419.485572 -342.82126) (xy 418.621972 -342.82126) (xy 418.594704 -342.820776)
			(xy 418.540723 -342.813011) (xy 418.488396 -342.797643) (xy 418.43879 -342.774985) (xy 418.392912 -342.745498)
			(xy 418.351697 -342.709783) (xy 418.315985 -342.668566) (xy 418.286502 -342.622686) (xy 418.263847 -342.573077)
			(xy 418.248483 -342.52075) (xy 418.240722 -342.466768) (xy 416.757874 -342.466768) (xy 416.757874 -342.466769)
			(xy 416.750112 -342.520751) (xy 416.734748 -342.573079) (xy 416.712092 -342.622688) (xy 416.682608 -342.668568)
			(xy 416.646894 -342.709786) (xy 416.605678 -342.745501) (xy 416.559799 -342.774987) (xy 416.510191 -342.797643)
			(xy 416.457863 -342.81301) (xy 416.403881 -342.820773) (xy 416.376612 -342.82126) (xy 415.513012 -342.82126)
			(xy 415.48574 -342.820801) (xy 415.431752 -342.813041) (xy 415.379417 -342.797675) (xy 415.329803 -342.775018)
			(xy 415.283917 -342.745531) (xy 415.242695 -342.709813) (xy 415.206976 -342.668593) (xy 415.177488 -342.622708)
			(xy 415.154829 -342.573094) (xy 415.139462 -342.52076) (xy 415.1317 -342.466772) (xy 413.648996 -342.466772)
			(xy 413.648996 -342.466773) (xy 413.641233 -342.520764) (xy 413.625864 -342.5731) (xy 413.603203 -342.622716)
			(xy 413.573712 -342.668602) (xy 413.537989 -342.709823) (xy 413.496763 -342.74554) (xy 413.450874 -342.775026)
			(xy 413.401255 -342.797681) (xy 413.348917 -342.813043) (xy 413.294925 -342.8208) (xy 413.267652 -342.82126)
			(xy 412.404052 -342.82126) (xy 412.376785 -342.820774) (xy 412.322806 -342.813007) (xy 412.270482 -342.797637)
			(xy 412.220878 -342.774978) (xy 412.175002 -342.745491) (xy 412.13379 -342.709776) (xy 412.09808 -342.668559)
			(xy 412.068599 -342.62268) (xy 412.045946 -342.573073) (xy 412.030583 -342.520747) (xy 412.022822 -342.466767)
			(xy 410.539996 -342.466767) (xy 410.539996 -342.466771) (xy 410.532234 -342.520759) (xy 410.516868 -342.573092)
			(xy 410.49421 -342.622705) (xy 410.464721 -342.668589) (xy 410.429003 -342.709809) (xy 410.387782 -342.745526)
			(xy 410.341898 -342.775013) (xy 410.292284 -342.79767) (xy 410.239951 -342.813036) (xy 410.185963 -342.820797)
			(xy 410.158692 -342.82126) (xy 409.295092 -342.82126) (xy 409.267823 -342.820777) (xy 409.21384 -342.813014)
			(xy 409.161511 -342.797648) (xy 409.111902 -342.774991) (xy 409.066021 -342.745505) (xy 409.024805 -342.70979)
			(xy 408.98909 -342.668572) (xy 408.959605 -342.622691) (xy 408.936949 -342.573082) (xy 408.921584 -342.520752)
			(xy 408.913822 -342.466769) (xy 403.522496 -342.466769) (xy 403.522496 -342.466772) (xy 403.514734 -342.52076)
			(xy 403.499367 -342.573094) (xy 403.476708 -342.622708) (xy 403.447218 -342.668593) (xy 403.411499 -342.709813)
			(xy 403.370277 -342.74553) (xy 403.324391 -342.775017) (xy 403.274775 -342.797674) (xy 403.222441 -342.813038)
			(xy 403.168452 -342.820798) (xy 403.14118 -342.82126) (xy 402.27758 -342.82126) (xy 402.250311 -342.820776)
			(xy 402.19633 -342.813012) (xy 402.144002 -342.797645) (xy 402.094394 -342.774988) (xy 402.048516 -342.745501)
			(xy 402.0073 -342.709786) (xy 401.971587 -342.668568) (xy 401.942103 -342.622688) (xy 401.919448 -342.573079)
			(xy 401.904084 -342.520751) (xy 401.896322 -342.466769) (xy 400.413474 -342.466769) (xy 400.405713 -342.52075)
			(xy 400.390348 -342.573078) (xy 400.367694 -342.622686) (xy 400.33821 -342.668566) (xy 400.302497 -342.709783)
			(xy 400.261282 -342.745498) (xy 400.215404 -342.774984) (xy 400.165796 -342.797641) (xy 400.113469 -342.813008)
			(xy 400.059488 -342.820772) (xy 400.03222 -342.82126) (xy 399.16862 -342.82126) (xy 399.141348 -342.820802)
			(xy 399.087359 -342.813042) (xy 399.035023 -342.797677) (xy 398.985407 -342.775021) (xy 398.939521 -342.745534)
			(xy 398.898298 -342.709816) (xy 398.862578 -342.668595) (xy 398.833089 -342.62271) (xy 398.81043 -342.573096)
			(xy 398.795062 -342.520761) (xy 398.7873 -342.466772) (xy 397.304596 -342.466772) (xy 397.304596 -342.466773)
			(xy 397.296833 -342.520763) (xy 397.281465 -342.573098) (xy 397.258805 -342.622714) (xy 397.229313 -342.668599)
			(xy 397.193592 -342.70982) (xy 397.152367 -342.745537) (xy 397.106479 -342.775024) (xy 397.056861 -342.797679)
			(xy 397.004524 -342.813042) (xy 396.950533 -342.820799) (xy 396.92326 -342.82126) (xy 396.05966 -342.82126)
			(xy 396.032392 -342.820775) (xy 395.978413 -342.813009) (xy 395.926088 -342.79764) (xy 395.876482 -342.774981)
			(xy 395.830606 -342.745494) (xy 395.789393 -342.709778) (xy 395.753682 -342.668562) (xy 395.7242 -342.622682)
			(xy 395.701546 -342.573075) (xy 395.686183 -342.520748) (xy 395.678422 -342.466768) (xy 394.195574 -342.466768)
			(xy 394.195574 -342.466769) (xy 394.187812 -342.520753) (xy 394.172447 -342.573082) (xy 394.149791 -342.622692)
			(xy 394.120305 -342.668572) (xy 394.08459 -342.70979) (xy 394.043372 -342.745505) (xy 393.997492 -342.774991)
			(xy 393.947882 -342.797647) (xy 393.895553 -342.813012) (xy 393.841569 -342.820774) (xy 393.8143 -342.82126)
			(xy 392.9507 -342.82126) (xy 392.92343 -342.820778) (xy 392.869447 -342.813016) (xy 392.817117 -342.79765)
			(xy 392.767506 -342.774994) (xy 392.721625 -342.745508) (xy 392.680407 -342.709793) (xy 392.644692 -342.668575)
			(xy 392.615206 -342.622694) (xy 392.59255 -342.573083) (xy 392.577184 -342.520753) (xy 392.569422 -342.46677)
			(xy 391.086574 -342.46677) (xy 391.078813 -342.520747) (xy 391.06345 -342.573073) (xy 391.040797 -342.622681)
			(xy 391.011315 -342.668559) (xy 390.975604 -342.709776) (xy 390.934391 -342.745491) (xy 390.888516 -342.774978)
			(xy 390.838911 -342.797636) (xy 390.786586 -342.813005) (xy 390.732607 -342.820771) (xy 390.70534 -342.82126)
			(xy 389.84174 -342.82126) (xy 389.814467 -342.820803) (xy 389.760476 -342.813046) (xy 389.708138 -342.797683)
			(xy 389.658519 -342.775027) (xy 389.61263 -342.745541) (xy 389.571405 -342.709823) (xy 389.535683 -342.668602)
			(xy 389.506192 -342.622716) (xy 389.483531 -342.5731) (xy 389.468163 -342.520764) (xy 389.4604 -342.466773)
			(xy 387.977696 -342.466773) (xy 387.969934 -342.52076) (xy 387.954567 -342.573094) (xy 387.931908 -342.622708)
			(xy 387.902418 -342.668593) (xy 387.866699 -342.709813) (xy 387.825477 -342.74553) (xy 387.779591 -342.775017)
			(xy 387.729975 -342.797674) (xy 387.677641 -342.813038) (xy 387.623652 -342.820798) (xy 387.59638 -342.82126)
			(xy 386.73278 -342.82126) (xy 386.705511 -342.820776) (xy 386.65153 -342.813012) (xy 386.599202 -342.797645)
			(xy 386.549594 -342.774988) (xy 386.503716 -342.745501) (xy 386.4625 -342.709786) (xy 386.426787 -342.668568)
			(xy 386.397303 -342.622688) (xy 386.374648 -342.573079) (xy 386.359284 -342.520751) (xy 386.351522 -342.466769)
			(xy 384.868674 -342.466769) (xy 384.860913 -342.52075) (xy 384.845548 -342.573078) (xy 384.822894 -342.622686)
			(xy 384.79341 -342.668566) (xy 384.757697 -342.709783) (xy 384.716482 -342.745498) (xy 384.670604 -342.774984)
			(xy 384.620996 -342.797641) (xy 384.568669 -342.813008) (xy 384.514688 -342.820772) (xy 384.48742 -342.82126)
			(xy 383.62382 -342.82126) (xy 383.596548 -342.820802) (xy 383.542559 -342.813042) (xy 383.490223 -342.797677)
			(xy 383.440607 -342.775021) (xy 383.394721 -342.745534) (xy 383.353498 -342.709816) (xy 383.317778 -342.668595)
			(xy 383.288289 -342.62271) (xy 383.26563 -342.573096) (xy 383.250262 -342.520761) (xy 383.2425 -342.466772)
			(xy 381.759796 -342.466772) (xy 381.759796 -342.466773) (xy 381.752033 -342.520763) (xy 381.736665 -342.573098)
			(xy 381.714005 -342.622714) (xy 381.684513 -342.668599) (xy 381.648792 -342.70982) (xy 381.607567 -342.745537)
			(xy 381.561679 -342.775024) (xy 381.512061 -342.797679) (xy 381.459724 -342.813042) (xy 381.405733 -342.820799)
			(xy 381.37846 -342.82126) (xy 380.51486 -342.82126) (xy 380.487592 -342.820775) (xy 380.433613 -342.813009)
			(xy 380.381288 -342.79764) (xy 380.331682 -342.774981) (xy 380.285806 -342.745494) (xy 380.244593 -342.709778)
			(xy 380.208882 -342.668562) (xy 380.1794 -342.622682) (xy 380.156746 -342.573075) (xy 380.141383 -342.520748)
			(xy 380.133622 -342.466768) (xy 378.650774 -342.466768) (xy 378.650774 -342.466769) (xy 378.643012 -342.520753)
			(xy 378.627647 -342.573082) (xy 378.604991 -342.622692) (xy 378.575505 -342.668572) (xy 378.53979 -342.70979)
			(xy 378.498572 -342.745505) (xy 378.452692 -342.774991) (xy 378.403082 -342.797647) (xy 378.350753 -342.813012)
			(xy 378.296769 -342.820774) (xy 378.2695 -342.82126) (xy 377.4059 -342.82126) (xy 377.37863 -342.820778)
			(xy 377.324647 -342.813016) (xy 377.272317 -342.79765) (xy 377.222706 -342.774994) (xy 377.176825 -342.745508)
			(xy 377.135607 -342.709793) (xy 377.099892 -342.668575) (xy 377.070406 -342.622694) (xy 377.04775 -342.573083)
			(xy 377.032384 -342.520753) (xy 377.024622 -342.46677) (xy 375.541774 -342.46677) (xy 375.534013 -342.520747)
			(xy 375.51865 -342.573073) (xy 375.495997 -342.622681) (xy 375.466515 -342.668559) (xy 375.430804 -342.709776)
			(xy 375.389591 -342.745491) (xy 375.343716 -342.774978) (xy 375.294111 -342.797636) (xy 375.241786 -342.813005)
			(xy 375.187807 -342.820771) (xy 375.16054 -342.82126) (xy 374.29694 -342.82126) (xy 374.269667 -342.820803)
			(xy 374.215676 -342.813046) (xy 374.163338 -342.797683) (xy 374.113719 -342.775027) (xy 374.06783 -342.745541)
			(xy 374.026605 -342.709823) (xy 373.990883 -342.668602) (xy 373.961392 -342.622716) (xy 373.938731 -342.5731)
			(xy 373.923363 -342.520764) (xy 373.9156 -342.466773) (xy 372.432896 -342.466773) (xy 372.425134 -342.52076)
			(xy 372.409767 -342.573094) (xy 372.387108 -342.622708) (xy 372.357618 -342.668593) (xy 372.321899 -342.709813)
			(xy 372.280677 -342.74553) (xy 372.234791 -342.775017) (xy 372.185175 -342.797674) (xy 372.132841 -342.813038)
			(xy 372.078852 -342.820798) (xy 372.05158 -342.82126) (xy 371.18798 -342.82126) (xy 371.160711 -342.820776)
			(xy 371.10673 -342.813012) (xy 371.054402 -342.797645) (xy 371.004794 -342.774988) (xy 370.958916 -342.745501)
			(xy 370.9177 -342.709786) (xy 370.881987 -342.668568) (xy 370.852503 -342.622688) (xy 370.829848 -342.573079)
			(xy 370.814484 -342.520751) (xy 370.806722 -342.466769) (xy 344.837274 -342.466769) (xy 344.829512 -342.520752)
			(xy 344.814147 -342.573081) (xy 344.791491 -342.622691) (xy 344.762006 -342.668571) (xy 344.726291 -342.709788)
			(xy 344.685074 -342.745503) (xy 344.639194 -342.774989) (xy 344.589585 -342.797646) (xy 344.537256 -342.813011)
			(xy 344.483273 -342.820773) (xy 344.456004 -342.82126) (xy 343.592404 -342.82126) (xy 343.565133 -342.820801)
			(xy 343.511145 -342.813039) (xy 343.458812 -342.797673) (xy 343.409198 -342.775016) (xy 343.363313 -342.745528)
			(xy 343.322093 -342.70981) (xy 343.286374 -342.66859) (xy 343.256886 -342.622706) (xy 343.234228 -342.573092)
			(xy 343.218862 -342.520759) (xy 343.2111 -342.466771) (xy 341.728273 -342.466771) (xy 341.720513 -342.520747)
			(xy 341.70515 -342.573072) (xy 341.682497 -342.622679) (xy 341.653016 -342.668558) (xy 341.617305 -342.709774)
			(xy 341.576093 -342.745489) (xy 341.530218 -342.774976) (xy 341.480614 -342.797635) (xy 341.42829 -342.813004)
			(xy 341.374311 -342.820771) (xy 341.347044 -342.82126) (xy 340.483444 -342.82126) (xy 340.456171 -342.820804)
			(xy 340.402179 -342.813046) (xy 340.349841 -342.797684) (xy 340.300222 -342.775029) (xy 340.254332 -342.745542)
			(xy 340.213107 -342.709824) (xy 340.177384 -342.668603) (xy 340.147892 -342.622717) (xy 340.125232 -342.573101)
			(xy 340.109863 -342.520764) (xy 340.1021 -342.466773) (xy 338.619396 -342.466773) (xy 338.611634 -342.52076)
			(xy 338.596267 -342.573093) (xy 338.573608 -342.622707) (xy 338.544119 -342.668591) (xy 338.5084 -342.709812)
			(xy 338.467179 -342.745529) (xy 338.421293 -342.775016) (xy 338.371678 -342.797673) (xy 338.319344 -342.813037)
			(xy 338.265356 -342.820798) (xy 338.238084 -342.82126) (xy 337.374484 -342.82126) (xy 337.347215 -342.820776)
			(xy 337.293233 -342.813013) (xy 337.240905 -342.797646) (xy 337.191297 -342.774989) (xy 337.145418 -342.745502)
			(xy 337.104202 -342.709787) (xy 337.068488 -342.66857) (xy 337.039003 -342.622689) (xy 337.016348 -342.57308)
			(xy 337.000984 -342.520751) (xy 336.993222 -342.466769) (xy 335.510374 -342.466769) (xy 335.502613 -342.520749)
			(xy 335.487249 -342.573077) (xy 335.464594 -342.622685) (xy 335.435111 -342.668565) (xy 335.399398 -342.709781)
			(xy 335.358184 -342.745496) (xy 335.312306 -342.774983) (xy 335.262699 -342.79764) (xy 335.210373 -342.813008)
			(xy 335.156392 -342.820772) (xy 335.129124 -342.82126) (xy 334.265524 -342.82126) (xy 334.238252 -342.820802)
			(xy 334.184262 -342.813043) (xy 334.131926 -342.797678) (xy 334.08231 -342.775022) (xy 334.036423 -342.745535)
			(xy 333.9952 -342.709817) (xy 333.959479 -342.668596) (xy 333.929989 -342.622711) (xy 333.90733 -342.573096)
			(xy 333.891962 -342.520761) (xy 333.8842 -342.466772) (xy 332.401496 -342.466772) (xy 332.393733 -342.520762)
			(xy 332.378365 -342.573098) (xy 332.355705 -342.622713) (xy 332.326214 -342.668598) (xy 332.290493 -342.709819)
			(xy 332.249269 -342.745536) (xy 332.203381 -342.775023) (xy 332.153764 -342.797678) (xy 332.101427 -342.813041)
			(xy 332.047437 -342.820799) (xy 332.020164 -342.82126) (xy 331.156564 -342.82126) (xy 331.129296 -342.820775)
			(xy 331.075316 -342.813009) (xy 331.022991 -342.797641) (xy 330.973385 -342.774982) (xy 330.927508 -342.745495)
			(xy 330.886295 -342.70978) (xy 330.850583 -342.668563) (xy 330.8211 -342.622684) (xy 330.798447 -342.573076)
			(xy 330.783083 -342.520749) (xy 330.775322 -342.466768) (xy 329.292474 -342.466768) (xy 329.292474 -342.466769)
			(xy 329.284712 -342.520752) (xy 329.269347 -342.573081) (xy 329.246691 -342.622691) (xy 329.217206 -342.668571)
			(xy 329.181491 -342.709788) (xy 329.140274 -342.745503) (xy 329.094394 -342.774989) (xy 329.044785 -342.797646)
			(xy 328.992456 -342.813011) (xy 328.938473 -342.820773) (xy 328.911204 -342.82126) (xy 328.047604 -342.82126)
			(xy 328.020333 -342.820801) (xy 327.966345 -342.813039) (xy 327.914012 -342.797673) (xy 327.864398 -342.775016)
			(xy 327.818513 -342.745528) (xy 327.777293 -342.70981) (xy 327.741574 -342.66859) (xy 327.712086 -342.622706)
			(xy 327.689428 -342.573092) (xy 327.674062 -342.520759) (xy 327.6663 -342.466771) (xy 326.183473 -342.466771)
			(xy 326.175713 -342.520747) (xy 326.16035 -342.573072) (xy 326.137697 -342.622679) (xy 326.108216 -342.668558)
			(xy 326.072505 -342.709774) (xy 326.031293 -342.745489) (xy 325.985418 -342.774976) (xy 325.935814 -342.797635)
			(xy 325.88349 -342.813004) (xy 325.829511 -342.820771) (xy 325.802244 -342.82126) (xy 324.938644 -342.82126)
			(xy 324.911371 -342.820804) (xy 324.857379 -342.813046) (xy 324.805041 -342.797684) (xy 324.755422 -342.775029)
			(xy 324.709532 -342.745542) (xy 324.668307 -342.709824) (xy 324.632584 -342.668603) (xy 324.603092 -342.622717)
			(xy 324.580432 -342.573101) (xy 324.565063 -342.520764) (xy 324.5573 -342.466773) (xy 323.074596 -342.466773)
			(xy 323.066834 -342.52076) (xy 323.051467 -342.573093) (xy 323.028808 -342.622707) (xy 322.999319 -342.668591)
			(xy 322.9636 -342.709812) (xy 322.922379 -342.745529) (xy 322.876493 -342.775016) (xy 322.826878 -342.797673)
			(xy 322.774544 -342.813037) (xy 322.720556 -342.820798) (xy 322.693284 -342.82126) (xy 321.829684 -342.82126)
			(xy 321.802415 -342.820776) (xy 321.748433 -342.813013) (xy 321.696105 -342.797646) (xy 321.646497 -342.774989)
			(xy 321.600618 -342.745502) (xy 321.559402 -342.709787) (xy 321.523688 -342.66857) (xy 321.494203 -342.622689)
			(xy 321.471548 -342.57308) (xy 321.456184 -342.520751) (xy 321.448422 -342.466769) (xy 319.965574 -342.466769)
			(xy 319.957813 -342.520749) (xy 319.942449 -342.573077) (xy 319.919794 -342.622685) (xy 319.890311 -342.668565)
			(xy 319.854598 -342.709781) (xy 319.813384 -342.745496) (xy 319.767506 -342.774983) (xy 319.717899 -342.79764)
			(xy 319.665573 -342.813008) (xy 319.611592 -342.820772) (xy 319.584324 -342.82126) (xy 318.720724 -342.82126)
			(xy 318.693452 -342.820802) (xy 318.639462 -342.813043) (xy 318.587126 -342.797678) (xy 318.53751 -342.775022)
			(xy 318.491623 -342.745535) (xy 318.4504 -342.709817) (xy 318.414679 -342.668596) (xy 318.385189 -342.622711)
			(xy 318.36253 -342.573096) (xy 318.347162 -342.520761) (xy 318.3394 -342.466772) (xy 316.856696 -342.466772)
			(xy 316.848933 -342.520762) (xy 316.833565 -342.573098) (xy 316.810905 -342.622713) (xy 316.781414 -342.668598)
			(xy 316.745693 -342.709819) (xy 316.704469 -342.745536) (xy 316.658581 -342.775023) (xy 316.608964 -342.797678)
			(xy 316.556627 -342.813041) (xy 316.502637 -342.820799) (xy 316.475364 -342.82126) (xy 315.611764 -342.82126)
			(xy 315.584496 -342.820775) (xy 315.530516 -342.813009) (xy 315.478191 -342.797641) (xy 315.428585 -342.774982)
			(xy 315.382708 -342.745495) (xy 315.341495 -342.70978) (xy 315.305783 -342.668563) (xy 315.2763 -342.622684)
			(xy 315.253647 -342.573076) (xy 315.238283 -342.520749) (xy 315.230522 -342.466768) (xy 313.747674 -342.466768)
			(xy 313.747674 -342.466769) (xy 313.739912 -342.520752) (xy 313.724547 -342.573081) (xy 313.701891 -342.622691)
			(xy 313.672406 -342.668571) (xy 313.636691 -342.709788) (xy 313.595474 -342.745503) (xy 313.549594 -342.774989)
			(xy 313.499985 -342.797646) (xy 313.447656 -342.813011) (xy 313.393673 -342.820773) (xy 313.366404 -342.82126)
			(xy 312.502804 -342.82126) (xy 312.475533 -342.820801) (xy 312.421545 -342.813039) (xy 312.369212 -342.797673)
			(xy 312.319598 -342.775016) (xy 312.273713 -342.745528) (xy 312.232493 -342.70981) (xy 312.196774 -342.66859)
			(xy 312.167286 -342.622706) (xy 312.144628 -342.573092) (xy 312.129262 -342.520759) (xy 312.1215 -342.466771)
			(xy 300.231574 -342.466771) (xy 300.223812 -342.520752) (xy 300.208447 -342.573081) (xy 300.185791 -342.622691)
			(xy 300.156305 -342.668572) (xy 300.120591 -342.709789) (xy 300.079373 -342.745504) (xy 300.033493 -342.77499)
			(xy 299.983883 -342.797646) (xy 299.931554 -342.813012) (xy 299.877571 -342.820773) (xy 299.850302 -342.82126)
			(xy 298.986702 -342.82126) (xy 298.959431 -342.820801) (xy 298.905443 -342.813039) (xy 298.85311 -342.797673)
			(xy 298.803497 -342.775015) (xy 298.757612 -342.745527) (xy 298.716392 -342.70981) (xy 298.680674 -342.668589)
			(xy 298.651186 -342.622705) (xy 298.628528 -342.573092) (xy 298.613162 -342.520759) (xy 298.605399 -342.466771)
			(xy 297.122573 -342.466771) (xy 297.114813 -342.520747) (xy 297.09945 -342.573073) (xy 297.076797 -342.62268)
			(xy 297.047315 -342.668559) (xy 297.011605 -342.709775) (xy 296.970392 -342.74549) (xy 296.924517 -342.774977)
			(xy 296.874912 -342.797635) (xy 296.822588 -342.813004) (xy 296.768609 -342.820771) (xy 296.741342 -342.82126)
			(xy 295.877742 -342.82126) (xy 295.850469 -342.820803) (xy 295.796477 -342.813046) (xy 295.744139 -342.797683)
			(xy 295.694521 -342.775028) (xy 295.648631 -342.745541) (xy 295.607406 -342.709824) (xy 295.571684 -342.668602)
			(xy 295.542192 -342.622716) (xy 295.519531 -342.5731) (xy 295.504163 -342.520764) (xy 295.4964 -342.466773)
			(xy 294.013696 -342.466773) (xy 294.005934 -342.52076) (xy 293.990567 -342.573094) (xy 293.967908 -342.622708)
			(xy 293.938419 -342.668592) (xy 293.9027 -342.709812) (xy 293.861478 -342.74553) (xy 293.815592 -342.775017)
			(xy 293.765977 -342.797673) (xy 293.713642 -342.813038) (xy 293.659654 -342.820798) (xy 293.632382 -342.82126)
			(xy 292.768782 -342.82126) (xy 292.741513 -342.820776) (xy 292.687531 -342.813013) (xy 292.635204 -342.797646)
			(xy 292.585596 -342.774988) (xy 292.539717 -342.745502) (xy 292.498501 -342.709786) (xy 292.462787 -342.668569)
			(xy 292.433303 -342.622689) (xy 292.410648 -342.573079) (xy 292.395284 -342.520751) (xy 292.387522 -342.466769)
			(xy 290.904674 -342.466769) (xy 290.896913 -342.52075) (xy 290.881548 -342.573077) (xy 290.858894 -342.622686)
			(xy 290.82941 -342.668565) (xy 290.793698 -342.709782) (xy 290.752483 -342.745497) (xy 290.706605 -342.774983)
			(xy 290.656998 -342.797641) (xy 290.604671 -342.813008) (xy 290.55069 -342.820772) (xy 290.523422 -342.82126)
			(xy 289.659822 -342.82126) (xy 289.63255 -342.820802) (xy 289.57856 -342.813042) (xy 289.526225 -342.797678)
			(xy 289.476609 -342.775021) (xy 289.430722 -342.745534) (xy 289.389499 -342.709817) (xy 289.353779 -342.668596)
			(xy 289.324289 -342.622711) (xy 289.30163 -342.573096) (xy 289.286262 -342.520761) (xy 289.2785 -342.466772)
			(xy 287.795796 -342.466772) (xy 287.795796 -342.466773) (xy 287.788033 -342.520763) (xy 287.772665 -342.573098)
			(xy 287.750005 -342.622713) (xy 287.720514 -342.668599) (xy 287.684793 -342.70982) (xy 287.643568 -342.745537)
			(xy 287.59768 -342.775023) (xy 287.548062 -342.797679) (xy 287.495725 -342.813041) (xy 287.441735 -342.820799)
			(xy 287.414462 -342.82126) (xy 286.550862 -342.82126) (xy 286.523594 -342.820775) (xy 286.469614 -342.813009)
			(xy 286.417289 -342.79764) (xy 286.367684 -342.774982) (xy 286.321807 -342.745495) (xy 286.280594 -342.709779)
			(xy 286.244883 -342.668562) (xy 286.2154 -342.622683) (xy 286.192747 -342.573075) (xy 286.177383 -342.520748)
			(xy 286.169622 -342.466768) (xy 284.686774 -342.466768) (xy 284.686774 -342.466769) (xy 284.679012 -342.520752)
			(xy 284.663647 -342.573081) (xy 284.640991 -342.622691) (xy 284.611505 -342.668572) (xy 284.575791 -342.709789)
			(xy 284.534573 -342.745504) (xy 284.488693 -342.77499) (xy 284.439083 -342.797646) (xy 284.386754 -342.813012)
			(xy 284.332771 -342.820773) (xy 284.305502 -342.82126) (xy 283.441902 -342.82126) (xy 283.414631 -342.820801)
			(xy 283.360643 -342.813039) (xy 283.30831 -342.797673) (xy 283.258697 -342.775015) (xy 283.212812 -342.745527)
			(xy 283.171592 -342.70981) (xy 283.135874 -342.668589) (xy 283.106386 -342.622705) (xy 283.083728 -342.573092)
			(xy 283.068362 -342.520759) (xy 283.060599 -342.466771) (xy 281.577773 -342.466771) (xy 281.570013 -342.520747)
			(xy 281.55465 -342.573073) (xy 281.531997 -342.62268) (xy 281.502515 -342.668559) (xy 281.466805 -342.709775)
			(xy 281.425592 -342.74549) (xy 281.379717 -342.774977) (xy 281.330112 -342.797635) (xy 281.277788 -342.813004)
			(xy 281.223809 -342.820771) (xy 281.196542 -342.82126) (xy 280.332942 -342.82126) (xy 280.305669 -342.820803)
			(xy 280.251677 -342.813046) (xy 280.199339 -342.797683) (xy 280.149721 -342.775028) (xy 280.103831 -342.745541)
			(xy 280.062606 -342.709824) (xy 280.026884 -342.668602) (xy 279.997392 -342.622716) (xy 279.974731 -342.5731)
			(xy 279.959363 -342.520764) (xy 279.9516 -342.466773) (xy 278.468896 -342.466773) (xy 278.461134 -342.52076)
			(xy 278.445767 -342.573094) (xy 278.423108 -342.622708) (xy 278.393619 -342.668592) (xy 278.3579 -342.709812)
			(xy 278.316678 -342.74553) (xy 278.270792 -342.775017) (xy 278.221177 -342.797673) (xy 278.168842 -342.813038)
			(xy 278.114854 -342.820798) (xy 278.087582 -342.82126) (xy 277.223982 -342.82126) (xy 277.196713 -342.820776)
			(xy 277.142731 -342.813013) (xy 277.090404 -342.797646) (xy 277.040796 -342.774988) (xy 276.994917 -342.745502)
			(xy 276.953701 -342.709786) (xy 276.917987 -342.668569) (xy 276.888503 -342.622689) (xy 276.865848 -342.573079)
			(xy 276.850484 -342.520751) (xy 276.842722 -342.466769) (xy 275.359874 -342.466769) (xy 275.352113 -342.52075)
			(xy 275.336748 -342.573077) (xy 275.314094 -342.622686) (xy 275.28461 -342.668565) (xy 275.248898 -342.709782)
			(xy 275.207683 -342.745497) (xy 275.161805 -342.774983) (xy 275.112198 -342.797641) (xy 275.059871 -342.813008)
			(xy 275.00589 -342.820772) (xy 274.978622 -342.82126) (xy 274.115022 -342.82126) (xy 274.08775 -342.820802)
			(xy 274.03376 -342.813042) (xy 273.981425 -342.797678) (xy 273.931809 -342.775021) (xy 273.885922 -342.745534)
			(xy 273.844699 -342.709817) (xy 273.808979 -342.668596) (xy 273.779489 -342.622711) (xy 273.75683 -342.573096)
			(xy 273.741462 -342.520761) (xy 273.7337 -342.466772) (xy 272.250996 -342.466772) (xy 272.250996 -342.466773)
			(xy 272.243233 -342.520763) (xy 272.227865 -342.573098) (xy 272.205205 -342.622713) (xy 272.175714 -342.668599)
			(xy 272.139993 -342.70982) (xy 272.098768 -342.745537) (xy 272.05288 -342.775023) (xy 272.003262 -342.797679)
			(xy 271.950925 -342.813041) (xy 271.896935 -342.820799) (xy 271.869662 -342.82126) (xy 271.006062 -342.82126)
			(xy 270.978794 -342.820775) (xy 270.924814 -342.813009) (xy 270.872489 -342.79764) (xy 270.822884 -342.774982)
			(xy 270.777007 -342.745495) (xy 270.735794 -342.709779) (xy 270.700083 -342.668562) (xy 270.6706 -342.622683)
			(xy 270.647947 -342.573075) (xy 270.632583 -342.520748) (xy 270.624822 -342.466768) (xy 269.141974 -342.466768)
			(xy 269.141974 -342.466769) (xy 269.134212 -342.520752) (xy 269.118847 -342.573081) (xy 269.096191 -342.622691)
			(xy 269.066705 -342.668572) (xy 269.030991 -342.709789) (xy 268.989773 -342.745504) (xy 268.943893 -342.77499)
			(xy 268.894283 -342.797646) (xy 268.841954 -342.813012) (xy 268.787971 -342.820773) (xy 268.760702 -342.82126)
			(xy 267.897102 -342.82126) (xy 267.869831 -342.820801) (xy 267.815843 -342.813039) (xy 267.76351 -342.797673)
			(xy 267.713897 -342.775015) (xy 267.668012 -342.745527) (xy 267.626792 -342.70981) (xy 267.591074 -342.668589)
			(xy 267.561586 -342.622705) (xy 267.538928 -342.573092) (xy 267.523562 -342.520759) (xy 267.515799 -342.466771)
			(xy 256.581015 -342.466771) (xy 256.573351 -342.471196) (xy 256.517947 -342.494145) (xy 256.460022 -342.509666)
			(xy 256.400566 -342.517494) (xy 256.340598 -342.517494) (xy 256.281142 -342.509666) (xy 256.223217 -342.494145)
			(xy 256.167813 -342.471196) (xy 256.115879 -342.441212) (xy 256.068303 -342.404706) (xy 256.025898 -342.362301)
			(xy 255.989392 -342.314725) (xy 255.959408 -342.262791) (xy 255.936459 -342.207387) (xy 255.920938 -342.149462)
			(xy 255.91311 -342.090006) (xy 255.91262 -342.060022) (xy 197.28821 -342.060022) (xy 197.329534 -342.06596)
			(xy 197.38187 -342.081324) (xy 197.431486 -342.10398) (xy 197.477373 -342.133467) (xy 197.518596 -342.169184)
			(xy 197.554316 -342.210405) (xy 197.583807 -342.256289) (xy 197.606466 -342.305904) (xy 197.621834 -342.358239)
			(xy 197.629596 -342.412228) (xy 197.629596 -342.466772) (xy 197.621834 -342.520761) (xy 197.606466 -342.573096)
			(xy 197.583807 -342.622711) (xy 197.554316 -342.668595) (xy 197.518596 -342.709816) (xy 197.477373 -342.745533)
			(xy 197.431486 -342.77502) (xy 197.38187 -342.797676) (xy 197.329534 -342.81304) (xy 197.275544 -342.820798)
			(xy 197.248272 -342.82126) (xy 196.384672 -342.82126) (xy 196.357404 -342.820776) (xy 196.303423 -342.813011)
			(xy 196.251096 -342.797643) (xy 196.20149 -342.774985) (xy 196.155612 -342.745498) (xy 196.114397 -342.709783)
			(xy 196.078685 -342.668566) (xy 196.049202 -342.622686) (xy 196.026547 -342.573077) (xy 196.011183 -342.52075)
			(xy 196.003422 -342.466768) (xy 194.520574 -342.466768) (xy 194.520574 -342.466769) (xy 194.512812 -342.520751)
			(xy 194.497448 -342.573079) (xy 194.474792 -342.622688) (xy 194.445308 -342.668568) (xy 194.409594 -342.709786)
			(xy 194.368378 -342.745501) (xy 194.322499 -342.774987) (xy 194.272891 -342.797643) (xy 194.220563 -342.81301)
			(xy 194.166581 -342.820773) (xy 194.139312 -342.82126) (xy 193.275712 -342.82126) (xy 193.24844 -342.820801)
			(xy 193.194452 -342.813041) (xy 193.142117 -342.797675) (xy 193.092503 -342.775018) (xy 193.046617 -342.745531)
			(xy 193.005395 -342.709813) (xy 192.969676 -342.668593) (xy 192.940188 -342.622708) (xy 192.917529 -342.573094)
			(xy 192.902162 -342.52076) (xy 192.8944 -342.466772) (xy 191.411696 -342.466772) (xy 191.411696 -342.466773)
			(xy 191.403933 -342.520764) (xy 191.388564 -342.5731) (xy 191.365903 -342.622716) (xy 191.336412 -342.668602)
			(xy 191.300689 -342.709823) (xy 191.259463 -342.74554) (xy 191.213574 -342.775026) (xy 191.163955 -342.797681)
			(xy 191.111617 -342.813043) (xy 191.057625 -342.8208) (xy 191.030352 -342.82126) (xy 190.166752 -342.82126)
			(xy 190.139485 -342.820774) (xy 190.085506 -342.813007) (xy 190.033182 -342.797637) (xy 189.983578 -342.774978)
			(xy 189.937702 -342.745491) (xy 189.89649 -342.709776) (xy 189.86078 -342.668559) (xy 189.831299 -342.62268)
			(xy 189.808646 -342.573073) (xy 189.793283 -342.520747) (xy 189.785522 -342.466767) (xy 188.302696 -342.466767)
			(xy 188.302696 -342.466771) (xy 188.294934 -342.520759) (xy 188.279568 -342.573092) (xy 188.25691 -342.622705)
			(xy 188.227421 -342.668589) (xy 188.191703 -342.709809) (xy 188.150482 -342.745526) (xy 188.104598 -342.775013)
			(xy 188.054984 -342.79767) (xy 188.002651 -342.813036) (xy 187.948663 -342.820797) (xy 187.921392 -342.82126)
			(xy 187.057792 -342.82126) (xy 187.030523 -342.820777) (xy 186.97654 -342.813014) (xy 186.924211 -342.797648)
			(xy 186.874602 -342.774991) (xy 186.828721 -342.745505) (xy 186.787505 -342.70979) (xy 186.75179 -342.668572)
			(xy 186.722305 -342.622691) (xy 186.699649 -342.573082) (xy 186.684284 -342.520752) (xy 186.676522 -342.466769)
			(xy 185.193674 -342.466769) (xy 185.185913 -342.520748) (xy 185.170549 -342.573075) (xy 185.147895 -342.622683)
			(xy 185.118413 -342.668562) (xy 185.082701 -342.709778) (xy 185.041488 -342.745494) (xy 184.995611 -342.77498)
			(xy 184.946005 -342.797638) (xy 184.89368 -342.813006) (xy 184.8397 -342.820771) (xy 184.812432 -342.82126)
			(xy 183.948832 -342.82126) (xy 183.921559 -342.820803) (xy 183.867569 -342.813044) (xy 183.815232 -342.797681)
			(xy 183.765615 -342.775025) (xy 183.719727 -342.745538) (xy 183.678502 -342.70982) (xy 183.642781 -342.668599)
			(xy 183.613291 -342.622714) (xy 183.590631 -342.573098) (xy 183.575263 -342.520763) (xy 183.5675 -342.466773)
			(xy 182.084796 -342.466773) (xy 182.077034 -342.520761) (xy 182.061666 -342.573096) (xy 182.039007 -342.622711)
			(xy 182.009516 -342.668595) (xy 181.973796 -342.709816) (xy 181.932573 -342.745533) (xy 181.886686 -342.77502)
			(xy 181.83707 -342.797676) (xy 181.784734 -342.81304) (xy 181.730744 -342.820798) (xy 181.703472 -342.82126)
			(xy 180.839872 -342.82126) (xy 180.812604 -342.820776) (xy 180.758623 -342.813011) (xy 180.706296 -342.797643)
			(xy 180.65669 -342.774985) (xy 180.610812 -342.745498) (xy 180.569597 -342.709783) (xy 180.533885 -342.668566)
			(xy 180.504402 -342.622686) (xy 180.481747 -342.573077) (xy 180.466383 -342.52075) (xy 180.458622 -342.466768)
			(xy 178.975774 -342.466768) (xy 178.975774 -342.466769) (xy 178.968012 -342.520751) (xy 178.952648 -342.573079)
			(xy 178.929992 -342.622688) (xy 178.900508 -342.668568) (xy 178.864794 -342.709786) (xy 178.823578 -342.745501)
			(xy 178.777699 -342.774987) (xy 178.728091 -342.797643) (xy 178.675763 -342.81301) (xy 178.621781 -342.820773)
			(xy 178.594512 -342.82126) (xy 177.730912 -342.82126) (xy 177.70364 -342.820801) (xy 177.649652 -342.813041)
			(xy 177.597317 -342.797675) (xy 177.547703 -342.775018) (xy 177.501817 -342.745531) (xy 177.460595 -342.709813)
			(xy 177.424876 -342.668593) (xy 177.395388 -342.622708) (xy 177.372729 -342.573094) (xy 177.357362 -342.52076)
			(xy 177.3496 -342.466772) (xy 175.866896 -342.466772) (xy 175.866896 -342.466773) (xy 175.859133 -342.520764)
			(xy 175.843764 -342.5731) (xy 175.821103 -342.622716) (xy 175.791612 -342.668602) (xy 175.755889 -342.709823)
			(xy 175.714663 -342.74554) (xy 175.668774 -342.775026) (xy 175.619155 -342.797681) (xy 175.566817 -342.813043)
			(xy 175.512825 -342.8208) (xy 175.485552 -342.82126) (xy 174.621952 -342.82126) (xy 174.594685 -342.820774)
			(xy 174.540706 -342.813007) (xy 174.488382 -342.797637) (xy 174.438778 -342.774978) (xy 174.392902 -342.745491)
			(xy 174.35169 -342.709776) (xy 174.31598 -342.668559) (xy 174.286499 -342.62268) (xy 174.263846 -342.573073)
			(xy 174.248483 -342.520747) (xy 174.240722 -342.466767) (xy 172.757896 -342.466767) (xy 172.757896 -342.466771)
			(xy 172.750134 -342.520759) (xy 172.734768 -342.573092) (xy 172.71211 -342.622705) (xy 172.682621 -342.668589)
			(xy 172.646903 -342.709809) (xy 172.605682 -342.745526) (xy 172.559798 -342.775013) (xy 172.510184 -342.79767)
			(xy 172.457851 -342.813036) (xy 172.403863 -342.820797) (xy 172.376592 -342.82126) (xy 171.512992 -342.82126)
			(xy 171.485723 -342.820777) (xy 171.43174 -342.813014) (xy 171.379411 -342.797648) (xy 171.329802 -342.774991)
			(xy 171.283921 -342.745505) (xy 171.242705 -342.70979) (xy 171.20699 -342.668572) (xy 171.177505 -342.622691)
			(xy 171.154849 -342.573082) (xy 171.139484 -342.520752) (xy 171.131722 -342.466769) (xy 169.648874 -342.466769)
			(xy 169.641113 -342.520748) (xy 169.625749 -342.573075) (xy 169.603095 -342.622683) (xy 169.573613 -342.668562)
			(xy 169.537901 -342.709778) (xy 169.496688 -342.745494) (xy 169.450811 -342.77498) (xy 169.401205 -342.797638)
			(xy 169.34888 -342.813006) (xy 169.2949 -342.820771) (xy 169.267632 -342.82126) (xy 168.404032 -342.82126)
			(xy 168.376759 -342.820803) (xy 168.322769 -342.813044) (xy 168.270432 -342.797681) (xy 168.220815 -342.775025)
			(xy 168.174927 -342.745538) (xy 168.133702 -342.70982) (xy 168.097981 -342.668599) (xy 168.068491 -342.622714)
			(xy 168.045831 -342.573098) (xy 168.030463 -342.520763) (xy 168.0227 -342.466773) (xy 166.539996 -342.466773)
			(xy 166.532234 -342.520761) (xy 166.516866 -342.573096) (xy 166.494207 -342.622711) (xy 166.464716 -342.668595)
			(xy 166.428996 -342.709816) (xy 166.387773 -342.745533) (xy 166.341886 -342.77502) (xy 166.29227 -342.797676)
			(xy 166.239934 -342.81304) (xy 166.185944 -342.820798) (xy 166.158672 -342.82126) (xy 165.295072 -342.82126)
			(xy 165.267804 -342.820776) (xy 165.213823 -342.813011) (xy 165.161496 -342.797643) (xy 165.11189 -342.774985)
			(xy 165.066012 -342.745498) (xy 165.024797 -342.709783) (xy 164.989085 -342.668566) (xy 164.959602 -342.622686)
			(xy 164.936947 -342.573077) (xy 164.921583 -342.52075) (xy 164.913822 -342.466768) (xy 144.196574 -342.466768)
			(xy 144.196574 -342.466769) (xy 144.188812 -342.520751) (xy 144.173447 -342.57308) (xy 144.150792 -342.622689)
			(xy 144.121307 -342.66857) (xy 144.085593 -342.709787) (xy 144.044376 -342.745502) (xy 143.998497 -342.774988)
			(xy 143.948888 -342.797645) (xy 143.896559 -342.81301) (xy 143.842577 -342.820773) (xy 143.815308 -342.82126)
			(xy 142.951708 -342.82126) (xy 142.924436 -342.820801) (xy 142.870448 -342.81304) (xy 142.818115 -342.797674)
			(xy 142.7685 -342.775017) (xy 142.722615 -342.745529) (xy 142.681394 -342.709812) (xy 142.645675 -342.668591)
			(xy 142.616187 -342.622707) (xy 142.593529 -342.573093) (xy 142.578162 -342.520759) (xy 142.5704 -342.466772)
			(xy 141.087573 -342.466772) (xy 141.079813 -342.520746) (xy 141.064451 -342.573072) (xy 141.041798 -342.622678)
			(xy 141.012317 -342.668557) (xy 140.976607 -342.709773) (xy 140.935395 -342.745488) (xy 140.88952 -342.774975)
			(xy 140.839917 -342.797634) (xy 140.787593 -342.813003) (xy 140.733615 -342.82077) (xy 140.706348 -342.82126)
			(xy 139.842748 -342.82126) (xy 139.815475 -342.820804) (xy 139.761482 -342.813047) (xy 139.709144 -342.797685)
			(xy 139.659524 -342.77503) (xy 139.613634 -342.745544) (xy 139.572408 -342.709826) (xy 139.536685 -342.668604)
			(xy 139.507193 -342.622718) (xy 139.484532 -342.573101) (xy 139.469163 -342.520765) (xy 139.4614 -342.466773)
			(xy 137.978696 -342.466773) (xy 137.970934 -342.520759) (xy 137.955567 -342.573092) (xy 137.932909 -342.622706)
			(xy 137.90342 -342.66859) (xy 137.867702 -342.70981) (xy 137.82648 -342.745528) (xy 137.780596 -342.775015)
			(xy 137.730981 -342.797671) (xy 137.678647 -342.813037) (xy 137.624659 -342.820797) (xy 137.597388 -342.82126)
			(xy 136.733788 -342.82126) (xy 136.706519 -342.820777) (xy 136.652536 -342.813014) (xy 136.600208 -342.797647)
			(xy 136.550599 -342.77499) (xy 136.50472 -342.745504) (xy 136.463503 -342.709788) (xy 136.427789 -342.668571)
			(xy 136.398304 -342.62269) (xy 136.375649 -342.573081) (xy 136.360284 -342.520752) (xy 136.352522 -342.466769)
			(xy 134.869674 -342.466769) (xy 134.861913 -342.520749) (xy 134.846549 -342.573076) (xy 134.823895 -342.622684)
			(xy 134.794412 -342.668563) (xy 134.7587 -342.70978) (xy 134.717486 -342.745495) (xy 134.671609 -342.774981)
			(xy 134.622002 -342.797639) (xy 134.569676 -342.813007) (xy 134.515696 -342.820772) (xy 134.488428 -342.82126)
			(xy 133.624828 -342.82126) (xy 133.597556 -342.820802) (xy 133.543565 -342.813043) (xy 133.491229 -342.79768)
			(xy 133.441612 -342.775023) (xy 133.395725 -342.745536) (xy 133.354501 -342.709819) (xy 133.31878 -342.668598)
			(xy 133.28929 -342.622712) (xy 133.26663 -342.573097) (xy 133.251262 -342.520762) (xy 133.2435 -342.466772)
			(xy 131.760796 -342.466772) (xy 131.753033 -342.520762) (xy 131.737666 -342.573097) (xy 131.715006 -342.622712)
			(xy 131.685515 -342.668597) (xy 131.649795 -342.709817) (xy 131.608571 -342.745535) (xy 131.562684 -342.775021)
			(xy 131.513067 -342.797677) (xy 131.46073 -342.81304) (xy 131.40674 -342.820799) (xy 131.379468 -342.82126)
			(xy 130.515868 -342.82126) (xy 130.4886 -342.820775) (xy 130.43462 -342.81301) (xy 130.382294 -342.797642)
			(xy 130.332687 -342.774984) (xy 130.28681 -342.745497) (xy 130.245596 -342.709781) (xy 130.209884 -342.668564)
			(xy 130.180401 -342.622685) (xy 130.157747 -342.573076) (xy 130.142383 -342.520749) (xy 130.134622 -342.466768)
			(xy 128.651774 -342.466768) (xy 128.651774 -342.466769) (xy 128.644012 -342.520751) (xy 128.628647 -342.57308)
			(xy 128.605992 -342.622689) (xy 128.576507 -342.66857) (xy 128.540793 -342.709787) (xy 128.499576 -342.745502)
			(xy 128.453697 -342.774988) (xy 128.404088 -342.797645) (xy 128.351759 -342.81301) (xy 128.297777 -342.820773)
			(xy 128.270508 -342.82126) (xy 127.406908 -342.82126) (xy 127.379636 -342.820801) (xy 127.325648 -342.81304)
			(xy 127.273315 -342.797674) (xy 127.2237 -342.775017) (xy 127.177815 -342.745529) (xy 127.136594 -342.709812)
			(xy 127.100875 -342.668591) (xy 127.071387 -342.622707) (xy 127.048729 -342.573093) (xy 127.033362 -342.520759)
			(xy 127.0256 -342.466772) (xy 125.542773 -342.466772) (xy 125.535013 -342.520746) (xy 125.519651 -342.573072)
			(xy 125.496998 -342.622678) (xy 125.467517 -342.668557) (xy 125.431807 -342.709773) (xy 125.390595 -342.745488)
			(xy 125.34472 -342.774975) (xy 125.295117 -342.797634) (xy 125.242793 -342.813003) (xy 125.188815 -342.82077)
			(xy 125.161548 -342.82126) (xy 124.297948 -342.82126) (xy 124.270675 -342.820804) (xy 124.216682 -342.813047)
			(xy 124.164344 -342.797685) (xy 124.114724 -342.77503) (xy 124.068834 -342.745544) (xy 124.027608 -342.709826)
			(xy 123.991885 -342.668604) (xy 123.962393 -342.622718) (xy 123.939732 -342.573101) (xy 123.924363 -342.520765)
			(xy 123.9166 -342.466773) (xy 122.433896 -342.466773) (xy 122.426134 -342.520759) (xy 122.410767 -342.573092)
			(xy 122.388109 -342.622706) (xy 122.35862 -342.66859) (xy 122.322902 -342.70981) (xy 122.28168 -342.745528)
			(xy 122.235796 -342.775015) (xy 122.186181 -342.797671) (xy 122.133847 -342.813037) (xy 122.079859 -342.820797)
			(xy 122.052588 -342.82126) (xy 121.188988 -342.82126) (xy 121.161719 -342.820777) (xy 121.107736 -342.813014)
			(xy 121.055408 -342.797647) (xy 121.005799 -342.77499) (xy 120.95992 -342.745504) (xy 120.918703 -342.709788)
			(xy 120.882989 -342.668571) (xy 120.853504 -342.62269) (xy 120.830849 -342.573081) (xy 120.815484 -342.520752)
			(xy 120.807722 -342.466769) (xy 119.324874 -342.466769) (xy 119.317113 -342.520749) (xy 119.301749 -342.573076)
			(xy 119.279095 -342.622684) (xy 119.249612 -342.668563) (xy 119.2139 -342.70978) (xy 119.172686 -342.745495)
			(xy 119.126809 -342.774981) (xy 119.077202 -342.797639) (xy 119.024876 -342.813007) (xy 118.970896 -342.820772)
			(xy 118.943628 -342.82126) (xy 118.080028 -342.82126) (xy 118.052756 -342.820802) (xy 117.998765 -342.813043)
			(xy 117.946429 -342.79768) (xy 117.896812 -342.775023) (xy 117.850925 -342.745536) (xy 117.809701 -342.709819)
			(xy 117.77398 -342.668598) (xy 117.74449 -342.622712) (xy 117.72183 -342.573097) (xy 117.706462 -342.520762)
			(xy 117.6987 -342.466772) (xy 116.215996 -342.466772) (xy 116.208233 -342.520762) (xy 116.192866 -342.573097)
			(xy 116.170206 -342.622712) (xy 116.140715 -342.668597) (xy 116.104995 -342.709817) (xy 116.063771 -342.745535)
			(xy 116.017884 -342.775021) (xy 115.968267 -342.797677) (xy 115.91593 -342.81304) (xy 115.86194 -342.820799)
			(xy 115.834668 -342.82126) (xy 114.971068 -342.82126) (xy 114.9438 -342.820775) (xy 114.88982 -342.81301)
			(xy 114.837494 -342.797642) (xy 114.787887 -342.774984) (xy 114.74201 -342.745497) (xy 114.700796 -342.709781)
			(xy 114.665084 -342.668564) (xy 114.635601 -342.622685) (xy 114.612947 -342.573076) (xy 114.597583 -342.520749)
			(xy 114.589822 -342.466768) (xy 113.106974 -342.466768) (xy 113.106974 -342.466769) (xy 113.099212 -342.520751)
			(xy 113.083847 -342.57308) (xy 113.061192 -342.622689) (xy 113.031707 -342.66857) (xy 112.995993 -342.709787)
			(xy 112.954776 -342.745502) (xy 112.908897 -342.774988) (xy 112.859288 -342.797645) (xy 112.806959 -342.81301)
			(xy 112.752977 -342.820773) (xy 112.725708 -342.82126) (xy 111.862108 -342.82126) (xy 111.834836 -342.820801)
			(xy 111.780848 -342.81304) (xy 111.728515 -342.797674) (xy 111.6789 -342.775017) (xy 111.633015 -342.745529)
			(xy 111.591794 -342.709812) (xy 111.556075 -342.668591) (xy 111.526587 -342.622707) (xy 111.503929 -342.573093)
			(xy 111.488562 -342.520759) (xy 111.4808 -342.466772) (xy 104.085479 -342.466772) (xy 104.10629 -342.517011)
			(xy 104.121803 -342.574906) (xy 104.129627 -342.634331) (xy 104.129627 -342.694269) (xy 104.121803 -342.753694)
			(xy 104.10629 -342.811589) (xy 104.083352 -342.866964) (xy 104.053383 -342.918871) (xy 104.016895 -342.966422)
			(xy 103.974512 -343.008804) (xy 103.926959 -343.045291) (xy 103.875051 -343.075259) (xy 103.819676 -343.098195)
			(xy 103.76178 -343.113706) (xy 103.702355 -343.121528) (xy 103.672386 -343.121996) (xy 102.808786 -343.121996)
			(xy 102.778818 -343.121529) (xy 102.719395 -343.113704) (xy 102.661502 -343.09819) (xy 102.60613 -343.075253)
			(xy 102.554224 -343.045284) (xy 102.506675 -343.008796) (xy 102.464294 -342.966415) (xy 102.427809 -342.918864)
			(xy 102.397841 -342.866958) (xy 102.374905 -342.811584) (xy 102.359393 -342.753691) (xy 102.35157 -342.694268)
			(xy 93.60914 -342.694268) (xy 93.595705 -342.709775) (xy 93.554492 -342.74549) (xy 93.508617 -342.774977)
			(xy 93.459012 -342.797635) (xy 93.406688 -342.813004) (xy 93.352709 -342.820771) (xy 93.325442 -342.82126)
			(xy 92.461842 -342.82126) (xy 92.434569 -342.820803) (xy 92.380577 -342.813046) (xy 92.328239 -342.797683)
			(xy 92.278621 -342.775028) (xy 92.232731 -342.745541) (xy 92.191506 -342.709824) (xy 92.155784 -342.668602)
			(xy 92.126292 -342.622716) (xy 92.103631 -342.5731) (xy 92.088263 -342.520764) (xy 92.0805 -342.466773)
			(xy 90.597796 -342.466773) (xy 90.590034 -342.52076) (xy 90.574667 -342.573094) (xy 90.552008 -342.622708)
			(xy 90.522519 -342.668592) (xy 90.4868 -342.709812) (xy 90.445578 -342.74553) (xy 90.399692 -342.775017)
			(xy 90.350077 -342.797673) (xy 90.297742 -342.813038) (xy 90.243754 -342.820798) (xy 90.216482 -342.82126)
			(xy 89.352882 -342.82126) (xy 89.325613 -342.820776) (xy 89.271631 -342.813013) (xy 89.219304 -342.797646)
			(xy 89.169696 -342.774988) (xy 89.123817 -342.745502) (xy 89.082601 -342.709786) (xy 89.046887 -342.668569)
			(xy 89.017403 -342.622689) (xy 88.994748 -342.573079) (xy 88.979384 -342.520751) (xy 88.971622 -342.466769)
			(xy 87.488774 -342.466769) (xy 87.481013 -342.52075) (xy 87.465648 -342.573077) (xy 87.442994 -342.622686)
			(xy 87.41351 -342.668565) (xy 87.377798 -342.709782) (xy 87.336583 -342.745497) (xy 87.290705 -342.774983)
			(xy 87.241098 -342.797641) (xy 87.188771 -342.813008) (xy 87.13479 -342.820772) (xy 87.107522 -342.82126)
			(xy 86.243922 -342.82126) (xy 86.21665 -342.820802) (xy 86.16266 -342.813042) (xy 86.110325 -342.797678)
			(xy 86.060709 -342.775021) (xy 86.014822 -342.745534) (xy 85.973599 -342.709817) (xy 85.937879 -342.668596)
			(xy 85.908389 -342.622711) (xy 85.88573 -342.573096) (xy 85.870362 -342.520761) (xy 85.8626 -342.466772)
			(xy 84.379896 -342.466772) (xy 84.379896 -342.466773) (xy 84.372133 -342.520763) (xy 84.356765 -342.573098)
			(xy 84.334105 -342.622713) (xy 84.304614 -342.668599) (xy 84.268893 -342.70982) (xy 84.227668 -342.745537)
			(xy 84.18178 -342.775023) (xy 84.132162 -342.797679) (xy 84.079825 -342.813041) (xy 84.025835 -342.820799)
			(xy 83.998562 -342.82126) (xy 83.134962 -342.82126) (xy 83.107694 -342.820775) (xy 83.053714 -342.813009)
			(xy 83.001389 -342.79764) (xy 82.951784 -342.774982) (xy 82.905907 -342.745495) (xy 82.864694 -342.709779)
			(xy 82.828983 -342.668562) (xy 82.7995 -342.622683) (xy 82.776847 -342.573075) (xy 82.761483 -342.520748)
			(xy 82.753722 -342.466768) (xy 81.270874 -342.466768) (xy 81.270874 -342.466769) (xy 81.263112 -342.520752)
			(xy 81.247747 -342.573081) (xy 81.225091 -342.622691) (xy 81.195605 -342.668572) (xy 81.159891 -342.709789)
			(xy 81.118673 -342.745504) (xy 81.072793 -342.77499) (xy 81.023183 -342.797646) (xy 80.970854 -342.813012)
			(xy 80.916871 -342.820773) (xy 80.889602 -342.82126) (xy 80.026002 -342.82126) (xy 79.998731 -342.820801)
			(xy 79.944743 -342.813039) (xy 79.89241 -342.797673) (xy 79.842797 -342.775015) (xy 79.796912 -342.745527)
			(xy 79.755692 -342.70981) (xy 79.719974 -342.668589) (xy 79.690486 -342.622705) (xy 79.667828 -342.573092)
			(xy 79.652462 -342.520759) (xy 79.644699 -342.466771) (xy 78.161873 -342.466771) (xy 78.154113 -342.520747)
			(xy 78.13875 -342.573073) (xy 78.116097 -342.62268) (xy 78.086615 -342.668559) (xy 78.050905 -342.709775)
			(xy 78.009692 -342.74549) (xy 77.963817 -342.774977) (xy 77.914212 -342.797635) (xy 77.861888 -342.813004)
			(xy 77.807909 -342.820771) (xy 77.780642 -342.82126) (xy 76.917042 -342.82126) (xy 76.889769 -342.820803)
			(xy 76.835777 -342.813046) (xy 76.783439 -342.797683) (xy 76.733821 -342.775028) (xy 76.687931 -342.745541)
			(xy 76.646706 -342.709824) (xy 76.610984 -342.668602) (xy 76.581492 -342.622716) (xy 76.558831 -342.5731)
			(xy 76.543463 -342.520764) (xy 76.5357 -342.466773) (xy 75.052996 -342.466773) (xy 75.045234 -342.52076)
			(xy 75.029867 -342.573094) (xy 75.007208 -342.622708) (xy 74.977719 -342.668592) (xy 74.942 -342.709812)
			(xy 74.900778 -342.74553) (xy 74.854892 -342.775017) (xy 74.805277 -342.797673) (xy 74.752942 -342.813038)
			(xy 74.698954 -342.820798) (xy 74.671682 -342.82126) (xy 73.808082 -342.82126) (xy 73.780813 -342.820776)
			(xy 73.726831 -342.813013) (xy 73.674504 -342.797646) (xy 73.624896 -342.774988) (xy 73.579017 -342.745502)
			(xy 73.537801 -342.709786) (xy 73.502087 -342.668569) (xy 73.472603 -342.622689) (xy 73.449948 -342.573079)
			(xy 73.434584 -342.520751) (xy 73.426822 -342.466769) (xy 71.943974 -342.466769) (xy 71.936213 -342.52075)
			(xy 71.920848 -342.573077) (xy 71.898194 -342.622686) (xy 71.86871 -342.668565) (xy 71.832998 -342.709782)
			(xy 71.791783 -342.745497) (xy 71.745905 -342.774983) (xy 71.696298 -342.797641) (xy 71.643971 -342.813008)
			(xy 71.58999 -342.820772) (xy 71.562722 -342.82126) (xy 70.699122 -342.82126) (xy 70.67185 -342.820802)
			(xy 70.61786 -342.813042) (xy 70.565525 -342.797678) (xy 70.515909 -342.775021) (xy 70.470022 -342.745534)
			(xy 70.428799 -342.709817) (xy 70.393079 -342.668596) (xy 70.363589 -342.622711) (xy 70.34093 -342.573096)
			(xy 70.325562 -342.520761) (xy 70.3178 -342.466772) (xy 68.835096 -342.466772) (xy 68.835096 -342.466773)
			(xy 68.827333 -342.520763) (xy 68.811965 -342.573098) (xy 68.789305 -342.622713) (xy 68.759814 -342.668599)
			(xy 68.724093 -342.70982) (xy 68.682868 -342.745537) (xy 68.63698 -342.775023) (xy 68.587362 -342.797679)
			(xy 68.535025 -342.813041) (xy 68.481035 -342.820799) (xy 68.453762 -342.82126) (xy 67.590162 -342.82126)
			(xy 67.562894 -342.820775) (xy 67.508914 -342.813009) (xy 67.456589 -342.79764) (xy 67.406984 -342.774982)
			(xy 67.361107 -342.745495) (xy 67.319894 -342.709779) (xy 67.284183 -342.668562) (xy 67.2547 -342.622683)
			(xy 67.232047 -342.573075) (xy 67.216683 -342.520748) (xy 67.208922 -342.466768) (xy 65.726074 -342.466768)
			(xy 65.726074 -342.466769) (xy 65.718312 -342.520752) (xy 65.702947 -342.573081) (xy 65.680291 -342.622691)
			(xy 65.650805 -342.668572) (xy 65.615091 -342.709789) (xy 65.573873 -342.745504) (xy 65.527993 -342.77499)
			(xy 65.478383 -342.797646) (xy 65.426054 -342.813012) (xy 65.372071 -342.820773) (xy 65.344802 -342.82126)
			(xy 64.481202 -342.82126) (xy 64.453931 -342.820801) (xy 64.399943 -342.813039) (xy 64.34761 -342.797673)
			(xy 64.297997 -342.775015) (xy 64.252112 -342.745527) (xy 64.210892 -342.70981) (xy 64.175174 -342.668589)
			(xy 64.145686 -342.622705) (xy 64.123028 -342.573092) (xy 64.107662 -342.520759) (xy 64.099899 -342.466771)
			(xy 62.617073 -342.466771) (xy 62.609313 -342.520747) (xy 62.59395 -342.573073) (xy 62.571297 -342.62268)
			(xy 62.541815 -342.668559) (xy 62.506105 -342.709775) (xy 62.464892 -342.74549) (xy 62.419017 -342.774977)
			(xy 62.369412 -342.797635) (xy 62.317088 -342.813004) (xy 62.263109 -342.820771) (xy 62.235842 -342.82126)
			(xy 61.372242 -342.82126) (xy 61.344969 -342.820803) (xy 61.290977 -342.813046) (xy 61.238639 -342.797683)
			(xy 61.189021 -342.775028) (xy 61.143131 -342.745541) (xy 61.101906 -342.709824) (xy 61.066184 -342.668602)
			(xy 61.036692 -342.622716) (xy 61.014031 -342.5731) (xy 60.998663 -342.520764) (xy 60.9909 -342.466773)
			(xy 51.666873 -342.466773) (xy 51.659113 -342.520746) (xy 51.643751 -342.573072) (xy 51.621098 -342.622678)
			(xy 51.591617 -342.668557) (xy 51.555907 -342.709773) (xy 51.514695 -342.745488) (xy 51.46882 -342.774975)
			(xy 51.419217 -342.797634) (xy 51.366893 -342.813003) (xy 51.312915 -342.82077) (xy 51.285648 -342.82126)
			(xy 50.422048 -342.82126) (xy 50.394775 -342.820804) (xy 50.340782 -342.813047) (xy 50.288444 -342.797685)
			(xy 50.238824 -342.77503) (xy 50.192934 -342.745544) (xy 50.151708 -342.709826) (xy 50.115985 -342.668604)
			(xy 50.086493 -342.622718) (xy 50.063832 -342.573101) (xy 50.048463 -342.520765) (xy 50.0407 -342.466773)
			(xy 48.557996 -342.466773) (xy 48.550234 -342.520759) (xy 48.534867 -342.573092) (xy 48.512209 -342.622706)
			(xy 48.48272 -342.66859) (xy 48.447002 -342.70981) (xy 48.40578 -342.745528) (xy 48.359896 -342.775015)
			(xy 48.310281 -342.797671) (xy 48.257947 -342.813037) (xy 48.203959 -342.820797) (xy 48.176688 -342.82126)
			(xy 47.313088 -342.82126) (xy 47.285819 -342.820777) (xy 47.231836 -342.813014) (xy 47.179508 -342.797647)
			(xy 47.129899 -342.77499) (xy 47.08402 -342.745504) (xy 47.042803 -342.709788) (xy 47.007089 -342.668571)
			(xy 46.977604 -342.62269) (xy 46.954949 -342.573081) (xy 46.939584 -342.520752) (xy 46.931822 -342.466769)
			(xy 45.448974 -342.466769) (xy 45.441213 -342.520749) (xy 45.425849 -342.573076) (xy 45.403195 -342.622684)
			(xy 45.373712 -342.668563) (xy 45.338 -342.70978) (xy 45.296786 -342.745495) (xy 45.250909 -342.774981)
			(xy 45.201302 -342.797639) (xy 45.148976 -342.813007) (xy 45.094996 -342.820772) (xy 45.067728 -342.82126)
			(xy 44.204128 -342.82126) (xy 44.176856 -342.820802) (xy 44.122865 -342.813043) (xy 44.070529 -342.79768)
			(xy 44.020912 -342.775023) (xy 43.975025 -342.745536) (xy 43.933801 -342.709819) (xy 43.89808 -342.668598)
			(xy 43.86859 -342.622712) (xy 43.84593 -342.573097) (xy 43.830562 -342.520762) (xy 43.8228 -342.466772)
			(xy 42.340096 -342.466772) (xy 42.332333 -342.520762) (xy 42.316966 -342.573097) (xy 42.294306 -342.622712)
			(xy 42.264815 -342.668597) (xy 42.229095 -342.709817) (xy 42.187871 -342.745535) (xy 42.141984 -342.775021)
			(xy 42.092367 -342.797677) (xy 42.04003 -342.81304) (xy 41.98604 -342.820799) (xy 41.958768 -342.82126)
			(xy 41.095168 -342.82126) (xy 41.0679 -342.820775) (xy 41.01392 -342.81301) (xy 40.961594 -342.797642)
			(xy 40.911987 -342.774984) (xy 40.86611 -342.745497) (xy 40.824896 -342.709781) (xy 40.789184 -342.668564)
			(xy 40.759701 -342.622685) (xy 40.737047 -342.573076) (xy 40.721683 -342.520749) (xy 40.713922 -342.466768)
			(xy 39.231074 -342.466768) (xy 39.231074 -342.466769) (xy 39.223312 -342.520751) (xy 39.207947 -342.57308)
			(xy 39.185292 -342.622689) (xy 39.155807 -342.66857) (xy 39.120093 -342.709787) (xy 39.078876 -342.745502)
			(xy 39.032997 -342.774988) (xy 38.983388 -342.797645) (xy 38.931059 -342.81301) (xy 38.877077 -342.820773)
			(xy 38.849808 -342.82126) (xy 37.986208 -342.82126) (xy 37.958936 -342.820801) (xy 37.904948 -342.81304)
			(xy 37.852615 -342.797674) (xy 37.803 -342.775017) (xy 37.757115 -342.745529) (xy 37.715894 -342.709812)
			(xy 37.680175 -342.668591) (xy 37.650687 -342.622707) (xy 37.628029 -342.573093) (xy 37.612662 -342.520759)
			(xy 37.6049 -342.466772) (xy 36.122073 -342.466772) (xy 36.114313 -342.520746) (xy 36.098951 -342.573072)
			(xy 36.076298 -342.622678) (xy 36.046817 -342.668557) (xy 36.011107 -342.709773) (xy 35.969895 -342.745488)
			(xy 35.92402 -342.774975) (xy 35.874417 -342.797634) (xy 35.822093 -342.813003) (xy 35.768115 -342.82077)
			(xy 35.740848 -342.82126) (xy 34.877248 -342.82126) (xy 34.849975 -342.820804) (xy 34.795982 -342.813047)
			(xy 34.743644 -342.797685) (xy 34.694024 -342.77503) (xy 34.648134 -342.745544) (xy 34.606908 -342.709826)
			(xy 34.571185 -342.668604) (xy 34.541693 -342.622718) (xy 34.519032 -342.573101) (xy 34.503663 -342.520765)
			(xy 34.4959 -342.466773) (xy 33.013196 -342.466773) (xy 33.005434 -342.520759) (xy 32.990067 -342.573092)
			(xy 32.967409 -342.622706) (xy 32.93792 -342.66859) (xy 32.902202 -342.70981) (xy 32.86098 -342.745528)
			(xy 32.815096 -342.775015) (xy 32.765481 -342.797671) (xy 32.713147 -342.813037) (xy 32.659159 -342.820797)
			(xy 32.631888 -342.82126) (xy 31.768288 -342.82126) (xy 31.741019 -342.820777) (xy 31.687036 -342.813014)
			(xy 31.634708 -342.797647) (xy 31.585099 -342.77499) (xy 31.53922 -342.745504) (xy 31.498003 -342.709788)
			(xy 31.462289 -342.668571) (xy 31.432804 -342.62269) (xy 31.410149 -342.573081) (xy 31.394784 -342.520752)
			(xy 31.387022 -342.466769) (xy 29.904174 -342.466769) (xy 29.896413 -342.520749) (xy 29.881049 -342.573076)
			(xy 29.858395 -342.622684) (xy 29.828912 -342.668563) (xy 29.7932 -342.70978) (xy 29.751986 -342.745495)
			(xy 29.706109 -342.774981) (xy 29.656502 -342.797639) (xy 29.604176 -342.813007) (xy 29.550196 -342.820772)
			(xy 29.522928 -342.82126) (xy 28.659328 -342.82126) (xy 28.632056 -342.820802) (xy 28.578065 -342.813043)
			(xy 28.525729 -342.79768) (xy 28.476112 -342.775023) (xy 28.430225 -342.745536) (xy 28.389001 -342.709819)
			(xy 28.35328 -342.668598) (xy 28.32379 -342.622712) (xy 28.30113 -342.573097) (xy 28.285762 -342.520762)
			(xy 28.278 -342.466772) (xy 26.795296 -342.466772) (xy 26.787533 -342.520762) (xy 26.772166 -342.573097)
			(xy 26.749506 -342.622712) (xy 26.720015 -342.668597) (xy 26.684295 -342.709817) (xy 26.643071 -342.745535)
			(xy 26.597184 -342.775021) (xy 26.547567 -342.797677) (xy 26.49523 -342.81304) (xy 26.44124 -342.820799)
			(xy 26.413968 -342.82126) (xy 25.550368 -342.82126) (xy 25.5231 -342.820775) (xy 25.46912 -342.81301)
			(xy 25.416794 -342.797642) (xy 25.367187 -342.774984) (xy 25.32131 -342.745497) (xy 25.280096 -342.709781)
			(xy 25.244384 -342.668564) (xy 25.214901 -342.622685) (xy 25.192247 -342.573076) (xy 25.176883 -342.520749)
			(xy 25.169122 -342.466768) (xy 23.686274 -342.466768) (xy 23.686274 -342.466769) (xy 23.678512 -342.520751)
			(xy 23.663147 -342.57308) (xy 23.640492 -342.622689) (xy 23.611007 -342.66857) (xy 23.575293 -342.709787)
			(xy 23.534076 -342.745502) (xy 23.488197 -342.774988) (xy 23.438588 -342.797645) (xy 23.386259 -342.81301)
			(xy 23.332277 -342.820773) (xy 23.305008 -342.82126) (xy 22.441408 -342.82126) (xy 22.414136 -342.820801)
			(xy 22.360148 -342.81304) (xy 22.307815 -342.797674) (xy 22.2582 -342.775017) (xy 22.212315 -342.745529)
			(xy 22.171094 -342.709812) (xy 22.135375 -342.668591) (xy 22.105887 -342.622707) (xy 22.083229 -342.573093)
			(xy 22.067862 -342.520759) (xy 22.0601 -342.466772) (xy 20.577347 -342.466772) (xy 20.569584 -342.520758)
			(xy 20.554218 -342.57309) (xy 20.53156 -342.622703) (xy 20.502073 -342.668587) (xy 20.466355 -342.709807)
			(xy 20.425135 -342.745524) (xy 20.379252 -342.775011) (xy 20.329638 -342.797669) (xy 20.277306 -342.813035)
			(xy 20.223319 -342.820797) (xy 20.196048 -342.82126) (xy 19.332448 -342.82126) (xy 19.305179 -342.820777)
			(xy 19.251195 -342.813015) (xy 19.198865 -342.79765) (xy 19.149255 -342.774993) (xy 19.103374 -342.745507)
			(xy 19.062157 -342.709792) (xy 19.026441 -342.668574) (xy 18.996956 -342.622693) (xy 18.974299 -342.573083)
			(xy 18.958934 -342.520753) (xy 18.951172 -342.466769) (xy 0.508 -342.466769) (xy 0.508 -345.49242)
			(xy 18.95117 -345.49242) (xy 18.95117 -345.43788) (xy 18.958932 -345.383896) (xy 18.974298 -345.331567)
			(xy 18.996954 -345.281956) (xy 19.02644 -345.236075) (xy 19.062155 -345.194857) (xy 19.103373 -345.159141)
			(xy 19.149254 -345.129655) (xy 19.198865 -345.106998) (xy 19.251194 -345.091633) (xy 19.305178 -345.083871)
			(xy 19.332448 -345.083384) (xy 20.196048 -345.083384) (xy 20.223319 -345.083855) (xy 20.277305 -345.091617)
			(xy 20.329638 -345.106983) (xy 20.379251 -345.12964) (xy 20.425134 -345.159128) (xy 20.466354 -345.194845)
			(xy 20.502071 -345.236064) (xy 20.531559 -345.281948) (xy 20.554216 -345.33156) (xy 20.569582 -345.383893)
			(xy 20.577345 -345.437879) (xy 20.577345 -345.49242) (xy 22.06013 -345.49242) (xy 22.06013 -345.43788)
			(xy 22.067892 -345.383896) (xy 22.083258 -345.331567) (xy 22.105914 -345.281956) (xy 22.1354 -345.236075)
			(xy 22.171115 -345.194857) (xy 22.212333 -345.159141) (xy 22.258214 -345.129655) (xy 22.307825 -345.106998)
			(xy 22.360154 -345.091633) (xy 22.414138 -345.083871) (xy 22.441408 -345.083384) (xy 23.305008 -345.083384)
			(xy 23.332279 -345.083855) (xy 23.386265 -345.091617) (xy 23.438598 -345.106983) (xy 23.488211 -345.12964)
			(xy 23.534094 -345.159128) (xy 23.575314 -345.194845) (xy 23.611031 -345.236064) (xy 23.640519 -345.281948)
			(xy 23.663176 -345.33156) (xy 23.678542 -345.383893) (xy 23.686305 -345.437879) (xy 23.686305 -345.492365)
			(xy 25.16917 -345.492365) (xy 25.16917 -345.437835) (xy 25.17693 -345.383861) (xy 25.192292 -345.33154)
			(xy 25.214943 -345.281938) (xy 25.244422 -345.236064) (xy 25.28013 -345.194853) (xy 25.321339 -345.159142)
			(xy 25.36721 -345.129658) (xy 25.41681 -345.107003) (xy 25.46913 -345.091637) (xy 25.523103 -345.083872)
			(xy 25.550368 -345.083384) (xy 26.413968 -345.083384) (xy 26.441244 -345.083753) (xy 26.495241 -345.091513)
			(xy 26.547583 -345.106878) (xy 26.597207 -345.129537) (xy 26.6431 -345.159027) (xy 26.684329 -345.194749)
			(xy 26.720054 -345.235975) (xy 26.749548 -345.281865) (xy 26.772211 -345.331487) (xy 26.78758 -345.383828)
			(xy 26.795344 -345.437824) (xy 26.795344 -345.492369) (xy 28.278047 -345.492369) (xy 28.278047 -345.437831)
			(xy 28.285809 -345.383848) (xy 28.301175 -345.33152) (xy 28.323832 -345.281911) (xy 28.353319 -345.236031)
			(xy 28.389035 -345.194815) (xy 28.430253 -345.159102) (xy 28.476135 -345.129619) (xy 28.525746 -345.106965)
			(xy 28.578076 -345.091603) (xy 28.632059 -345.083845) (xy 28.659328 -345.083384) (xy 29.522928 -345.083384)
			(xy 29.550199 -345.08378) (xy 29.604186 -345.091546) (xy 29.656519 -345.106916) (xy 29.706132 -345.129576)
			(xy 29.752014 -345.159067) (xy 29.793234 -345.194786) (xy 29.82895 -345.236008) (xy 29.858437 -345.281893)
			(xy 29.881094 -345.331507) (xy 29.89646 -345.383841) (xy 29.904222 -345.437829) (xy 29.904222 -345.492366)
			(xy 31.38707 -345.492366) (xy 31.38707 -345.437834) (xy 31.394831 -345.383858) (xy 31.410194 -345.331536)
			(xy 31.432846 -345.281933) (xy 31.462327 -345.236058) (xy 31.498037 -345.194846) (xy 31.539248 -345.159135)
			(xy 31.585122 -345.129652) (xy 31.634725 -345.106998) (xy 31.687047 -345.091633) (xy 31.741022 -345.083871)
			(xy 31.768288 -345.083384) (xy 32.631888 -345.083384) (xy 32.659163 -345.083755) (xy 32.713157 -345.091516)
			(xy 32.765498 -345.106884) (xy 32.815119 -345.129543) (xy 32.861009 -345.159034) (xy 32.902236 -345.194756)
			(xy 32.937959 -345.235981) (xy 32.967451 -345.281871) (xy 32.990112 -345.331491) (xy 33.005481 -345.383831)
			(xy 33.013244 -345.437825) (xy 33.013244 -345.49237) (xy 34.495948 -345.49237) (xy 34.495948 -345.43783)
			(xy 34.50371 -345.383846) (xy 34.519077 -345.331515) (xy 34.541735 -345.281905) (xy 34.571224 -345.236024)
			(xy 34.606942 -345.194808) (xy 34.648163 -345.159095) (xy 34.694047 -345.129612) (xy 34.74366 -345.10696)
			(xy 34.795992 -345.0916) (xy 34.849978 -345.083844) (xy 34.877248 -345.083384) (xy 35.740848 -345.083384)
			(xy 35.768118 -345.083782) (xy 35.822103 -345.09155) (xy 35.874433 -345.106921) (xy 35.924044 -345.129583)
			(xy 35.969924 -345.159074) (xy 36.011141 -345.194793) (xy 36.046855 -345.236015) (xy 36.07634 -345.281899)
			(xy 36.098995 -345.331512) (xy 36.11436 -345.383844) (xy 36.122122 -345.43783) (xy 36.122122 -345.492368)
			(xy 37.604947 -345.492368) (xy 37.604947 -345.437832) (xy 37.612709 -345.383851) (xy 37.628074 -345.331524)
			(xy 37.650729 -345.281916) (xy 37.680214 -345.236038) (xy 37.715928 -345.194822) (xy 37.757144 -345.159109)
			(xy 37.803023 -345.129625) (xy 37.852631 -345.106971) (xy 37.904959 -345.091607) (xy 37.95894 -345.083847)
			(xy 37.986208 -345.083384) (xy 38.849808 -345.083384) (xy 38.87708 -345.083779) (xy 38.93107 -345.091543)
			(xy 38.983404 -345.106911) (xy 39.03302 -345.12957) (xy 39.078905 -345.15906) (xy 39.120127 -345.194779)
			(xy 39.155845 -345.236001) (xy 39.185334 -345.281888) (xy 39.207992 -345.331503) (xy 39.223359 -345.383838)
			(xy 39.231121 -345.437828) (xy 39.231121 -345.492365) (xy 40.71397 -345.492365) (xy 40.71397 -345.437835)
			(xy 40.72173 -345.383861) (xy 40.737092 -345.33154) (xy 40.759743 -345.281938) (xy 40.789222 -345.236064)
			(xy 40.82493 -345.194853) (xy 40.866139 -345.159142) (xy 40.91201 -345.129658) (xy 40.96161 -345.107003)
			(xy 41.01393 -345.091637) (xy 41.067903 -345.083872) (xy 41.095168 -345.083384) (xy 41.958768 -345.083384)
			(xy 41.986044 -345.083753) (xy 42.040041 -345.091513) (xy 42.092383 -345.106878) (xy 42.142007 -345.129537)
			(xy 42.1879 -345.159027) (xy 42.229129 -345.194749) (xy 42.264854 -345.235975) (xy 42.294348 -345.281865)
			(xy 42.317011 -345.331487) (xy 42.33238 -345.383828) (xy 42.340144 -345.437824) (xy 42.340144 -345.492369)
			(xy 43.822847 -345.492369) (xy 43.822847 -345.437831) (xy 43.830609 -345.383848) (xy 43.845975 -345.33152)
			(xy 43.868632 -345.281911) (xy 43.898119 -345.236031) (xy 43.933835 -345.194815) (xy 43.975053 -345.159102)
			(xy 44.020935 -345.129619) (xy 44.070546 -345.106965) (xy 44.122876 -345.091603) (xy 44.176859 -345.083845)
			(xy 44.204128 -345.083384) (xy 45.067728 -345.083384) (xy 45.094999 -345.08378) (xy 45.148986 -345.091546)
			(xy 45.201319 -345.106916) (xy 45.250932 -345.129576) (xy 45.296814 -345.159067) (xy 45.338034 -345.194786)
			(xy 45.37375 -345.236008) (xy 45.403237 -345.281893) (xy 45.425894 -345.331507) (xy 45.44126 -345.383841)
			(xy 45.449022 -345.437829) (xy 45.449022 -345.492366) (xy 46.93187 -345.492366) (xy 46.93187 -345.437834)
			(xy 46.939631 -345.383858) (xy 46.954994 -345.331536) (xy 46.977646 -345.281933) (xy 47.007127 -345.236058)
			(xy 47.042837 -345.194846) (xy 47.084048 -345.159135) (xy 47.129922 -345.129652) (xy 47.179525 -345.106998)
			(xy 47.231847 -345.091633) (xy 47.285822 -345.083871) (xy 47.313088 -345.083384) (xy 48.176688 -345.083384)
			(xy 48.203963 -345.083755) (xy 48.257957 -345.091516) (xy 48.310298 -345.106884) (xy 48.359919 -345.129543)
			(xy 48.405809 -345.159034) (xy 48.447036 -345.194756) (xy 48.482759 -345.235981) (xy 48.512251 -345.281871)
			(xy 48.534912 -345.331491) (xy 48.550281 -345.383831) (xy 48.558044 -345.437825) (xy 48.558044 -345.49237)
			(xy 50.040748 -345.49237) (xy 50.040748 -345.43783) (xy 50.04851 -345.383846) (xy 50.063877 -345.331515)
			(xy 50.086535 -345.281905) (xy 50.116024 -345.236024) (xy 50.151742 -345.194808) (xy 50.192963 -345.159095)
			(xy 50.238847 -345.129612) (xy 50.28846 -345.10696) (xy 50.340792 -345.0916) (xy 50.394778 -345.083844)
			(xy 50.422048 -345.083384) (xy 51.285648 -345.083384) (xy 51.312918 -345.083782) (xy 51.366903 -345.09155)
			(xy 51.419233 -345.106921) (xy 51.468844 -345.129583) (xy 51.514724 -345.159074) (xy 51.555941 -345.194793)
			(xy 51.591655 -345.236015) (xy 51.62114 -345.281899) (xy 51.643795 -345.331512) (xy 51.65916 -345.383844)
			(xy 51.666922 -345.43783) (xy 51.666922 -345.49237) (xy 60.990948 -345.49237) (xy 60.990948 -345.43783)
			(xy 60.99871 -345.383846) (xy 61.014076 -345.331517) (xy 61.036734 -345.281907) (xy 61.066222 -345.236026)
			(xy 61.10194 -345.19481) (xy 61.14316 -345.159097) (xy 61.189044 -345.129614) (xy 61.238656 -345.106962)
			(xy 61.290987 -345.091601) (xy 61.344972 -345.083845) (xy 61.372242 -345.083384) (xy 62.235842 -345.083384)
			(xy 62.263113 -345.083781) (xy 62.317098 -345.091549) (xy 62.369429 -345.10692) (xy 62.41904 -345.129581)
			(xy 62.464921 -345.159072) (xy 62.506139 -345.194791) (xy 62.541854 -345.236013) (xy 62.571339 -345.281897)
			(xy 62.593995 -345.33151) (xy 62.60936 -345.383843) (xy 62.617122 -345.437829) (xy 62.617122 -345.492368)
			(xy 64.099947 -345.492368) (xy 64.099947 -345.437832) (xy 64.107709 -345.383852) (xy 64.123073 -345.331525)
			(xy 64.145728 -345.281918) (xy 64.175212 -345.23604) (xy 64.210926 -345.194824) (xy 64.252141 -345.159111)
			(xy 64.29802 -345.129627) (xy 64.347627 -345.106972) (xy 64.399954 -345.091608) (xy 64.453934 -345.083847)
			(xy 64.481202 -345.083384) (xy 65.344802 -345.083384) (xy 65.372075 -345.083779) (xy 65.426064 -345.091542)
			(xy 65.4784 -345.106909) (xy 65.528016 -345.129568) (xy 65.573902 -345.159057) (xy 65.615124 -345.194777)
			(xy 65.650844 -345.236) (xy 65.680333 -345.281886) (xy 65.702992 -345.331502) (xy 65.718359 -345.383838)
			(xy 65.726121 -345.437827) (xy 65.726121 -345.492364) (xy 67.20897 -345.492364) (xy 67.20897 -345.437836)
			(xy 67.21673 -345.383862) (xy 67.232092 -345.331542) (xy 67.254742 -345.28194) (xy 67.284221 -345.236066)
			(xy 67.319928 -345.194855) (xy 67.361136 -345.159144) (xy 67.407007 -345.12966) (xy 67.456606 -345.107005)
			(xy 67.508925 -345.091638) (xy 67.562898 -345.083873) (xy 67.590162 -345.083384) (xy 68.453762 -345.083384)
			(xy 68.481038 -345.083753) (xy 68.535036 -345.091512) (xy 68.587379 -345.106877) (xy 68.637003 -345.129535)
			(xy 68.682897 -345.159025) (xy 68.724127 -345.194747) (xy 68.759852 -345.235973) (xy 68.789347 -345.281864)
			(xy 68.81201 -345.331485) (xy 68.82738 -345.383827) (xy 68.835144 -345.437824) (xy 68.835144 -345.492369)
			(xy 70.317847 -345.492369) (xy 70.317847 -345.437831) (xy 70.325609 -345.383849) (xy 70.340975 -345.331521)
			(xy 70.363631 -345.281912) (xy 70.393117 -345.236033) (xy 70.428833 -345.194817) (xy 70.470051 -345.159104)
			(xy 70.515932 -345.129621) (xy 70.565541 -345.106967) (xy 70.617871 -345.091605) (xy 70.671853 -345.083846)
			(xy 70.699122 -345.083384) (xy 71.562722 -345.083384) (xy 71.589994 -345.08378) (xy 71.643981 -345.091545)
			(xy 71.696315 -345.106914) (xy 71.745928 -345.129574) (xy 71.791812 -345.159064) (xy 71.833032 -345.194784)
			(xy 71.868749 -345.236006) (xy 71.898236 -345.281891) (xy 71.920893 -345.331506) (xy 71.936259 -345.38384)
			(xy 71.944022 -345.437828) (xy 71.944022 -345.492365) (xy 73.42687 -345.492365) (xy 73.42687 -345.437835)
			(xy 73.434631 -345.383859) (xy 73.449993 -345.331537) (xy 73.472645 -345.281934) (xy 73.502126 -345.23606)
			(xy 73.537835 -345.194848) (xy 73.579045 -345.159137) (xy 73.624919 -345.129654) (xy 73.674521 -345.106999)
			(xy 73.726842 -345.091634) (xy 73.780817 -345.083872) (xy 73.808082 -345.083384) (xy 74.671682 -345.083384)
			(xy 74.698957 -345.083754) (xy 74.752952 -345.091515) (xy 74.805294 -345.106882) (xy 74.854915 -345.129541)
			(xy 74.900806 -345.159032) (xy 74.942034 -345.194754) (xy 74.977757 -345.235979) (xy 75.00725 -345.281869)
			(xy 75.029912 -345.33149) (xy 75.045281 -345.38383) (xy 75.053044 -345.437825) (xy 75.053044 -345.49237)
			(xy 76.535748 -345.49237) (xy 76.535748 -345.43783) (xy 76.54351 -345.383846) (xy 76.558876 -345.331517)
			(xy 76.581534 -345.281907) (xy 76.611022 -345.236026) (xy 76.64674 -345.19481) (xy 76.68796 -345.159097)
			(xy 76.733844 -345.129614) (xy 76.783456 -345.106962) (xy 76.835787 -345.091601) (xy 76.889772 -345.083845)
			(xy 76.917042 -345.083384) (xy 77.780642 -345.083384) (xy 77.807913 -345.083781) (xy 77.861898 -345.091549)
			(xy 77.914229 -345.10692) (xy 77.96384 -345.129581) (xy 78.009721 -345.159072) (xy 78.050939 -345.194791)
			(xy 78.086654 -345.236013) (xy 78.116139 -345.281897) (xy 78.138795 -345.33151) (xy 78.15416 -345.383843)
			(xy 78.161922 -345.437829) (xy 78.161922 -345.492368) (xy 79.644747 -345.492368) (xy 79.644747 -345.437832)
			(xy 79.652509 -345.383852) (xy 79.667873 -345.331525) (xy 79.690528 -345.281918) (xy 79.720012 -345.23604)
			(xy 79.755726 -345.194824) (xy 79.796941 -345.159111) (xy 79.84282 -345.129627) (xy 79.892427 -345.106972)
			(xy 79.944754 -345.091608) (xy 79.998734 -345.083847) (xy 80.026002 -345.083384) (xy 80.889602 -345.083384)
			(xy 80.916875 -345.083779) (xy 80.970864 -345.091542) (xy 81.0232 -345.106909) (xy 81.072816 -345.129568)
			(xy 81.118702 -345.159057) (xy 81.159924 -345.194777) (xy 81.195644 -345.236) (xy 81.225133 -345.281886)
			(xy 81.247792 -345.331502) (xy 81.263159 -345.383838) (xy 81.270921 -345.437827) (xy 81.270921 -345.492364)
			(xy 82.75377 -345.492364) (xy 82.75377 -345.437836) (xy 82.76153 -345.383862) (xy 82.776892 -345.331542)
			(xy 82.799542 -345.28194) (xy 82.829021 -345.236066) (xy 82.864728 -345.194855) (xy 82.905936 -345.159144)
			(xy 82.951807 -345.12966) (xy 83.001406 -345.107005) (xy 83.053725 -345.091638) (xy 83.107698 -345.083873)
			(xy 83.134962 -345.083384) (xy 83.998562 -345.083384) (xy 84.025838 -345.083753) (xy 84.079836 -345.091512)
			(xy 84.132179 -345.106877) (xy 84.181803 -345.129535) (xy 84.227697 -345.159025) (xy 84.268927 -345.194747)
			(xy 84.304652 -345.235973) (xy 84.334147 -345.281864) (xy 84.35681 -345.331485) (xy 84.37218 -345.383827)
			(xy 84.379944 -345.437824) (xy 84.379944 -345.492369) (xy 85.862647 -345.492369) (xy 85.862647 -345.437831)
			(xy 85.870409 -345.383849) (xy 85.885775 -345.331521) (xy 85.908431 -345.281912) (xy 85.937917 -345.236033)
			(xy 85.973633 -345.194817) (xy 86.014851 -345.159104) (xy 86.060732 -345.129621) (xy 86.110341 -345.106967)
			(xy 86.162671 -345.091605) (xy 86.216653 -345.083846) (xy 86.243922 -345.083384) (xy 87.107522 -345.083384)
			(xy 87.134794 -345.08378) (xy 87.188781 -345.091545) (xy 87.241115 -345.106914) (xy 87.290728 -345.129574)
			(xy 87.336612 -345.159064) (xy 87.377832 -345.194784) (xy 87.413549 -345.236006) (xy 87.443036 -345.281891)
			(xy 87.465693 -345.331506) (xy 87.481059 -345.38384) (xy 87.488822 -345.437828) (xy 87.488822 -345.492365)
			(xy 88.97167 -345.492365) (xy 88.97167 -345.437835) (xy 88.979431 -345.383859) (xy 88.994793 -345.331537)
			(xy 89.017445 -345.281934) (xy 89.046926 -345.23606) (xy 89.082635 -345.194848) (xy 89.123845 -345.159137)
			(xy 89.169719 -345.129654) (xy 89.219321 -345.106999) (xy 89.271642 -345.091634) (xy 89.325617 -345.083872)
			(xy 89.352882 -345.083384) (xy 90.216482 -345.083384) (xy 90.243757 -345.083754) (xy 90.297752 -345.091515)
			(xy 90.350094 -345.106882) (xy 90.399715 -345.129541) (xy 90.445606 -345.159032) (xy 90.486834 -345.194754)
			(xy 90.522557 -345.235979) (xy 90.55205 -345.281869) (xy 90.574712 -345.33149) (xy 90.590081 -345.38383)
			(xy 90.597844 -345.437825) (xy 90.597844 -345.49237) (xy 92.080548 -345.49237) (xy 92.080548 -345.43783)
			(xy 92.08831 -345.383846) (xy 92.103676 -345.331517) (xy 92.126334 -345.281907) (xy 92.155822 -345.236026)
			(xy 92.19154 -345.19481) (xy 92.23276 -345.159097) (xy 92.278644 -345.129614) (xy 92.328256 -345.106962)
			(xy 92.380587 -345.091601) (xy 92.434572 -345.083845) (xy 92.461842 -345.083384) (xy 93.325442 -345.083384)
			(xy 93.352713 -345.083781) (xy 93.406698 -345.091549) (xy 93.459029 -345.10692) (xy 93.50864 -345.129581)
			(xy 93.554521 -345.159072) (xy 93.595739 -345.194791) (xy 93.631454 -345.236013) (xy 93.660939 -345.281897)
			(xy 93.683595 -345.33151) (xy 93.69896 -345.383843) (xy 93.706722 -345.437829) (xy 93.706722 -345.492368)
			(xy 111.480847 -345.492368) (xy 111.480847 -345.437832) (xy 111.488609 -345.383851) (xy 111.503974 -345.331524)
			(xy 111.526629 -345.281916) (xy 111.556114 -345.236038) (xy 111.591828 -345.194822) (xy 111.633044 -345.159109)
			(xy 111.678923 -345.129625) (xy 111.728531 -345.106971) (xy 111.780859 -345.091607) (xy 111.83484 -345.083847)
			(xy 111.862108 -345.083384) (xy 112.725708 -345.083384) (xy 112.75298 -345.083779) (xy 112.80697 -345.091543)
			(xy 112.859304 -345.106911) (xy 112.90892 -345.12957) (xy 112.954805 -345.15906) (xy 112.996027 -345.194779)
			(xy 113.031745 -345.236001) (xy 113.061234 -345.281888) (xy 113.083892 -345.331503) (xy 113.099259 -345.383838)
			(xy 113.107021 -345.437828) (xy 113.107021 -345.492365) (xy 114.58987 -345.492365) (xy 114.58987 -345.437835)
			(xy 114.59763 -345.383861) (xy 114.612992 -345.33154) (xy 114.635643 -345.281938) (xy 114.665122 -345.236064)
			(xy 114.70083 -345.194853) (xy 114.742039 -345.159142) (xy 114.78791 -345.129658) (xy 114.83751 -345.107003)
			(xy 114.88983 -345.091637) (xy 114.943803 -345.083872) (xy 114.971068 -345.083384) (xy 115.834668 -345.083384)
			(xy 115.861944 -345.083753) (xy 115.915941 -345.091513) (xy 115.968283 -345.106878) (xy 116.017907 -345.129537)
			(xy 116.0638 -345.159027) (xy 116.105029 -345.194749) (xy 116.140754 -345.235975) (xy 116.170248 -345.281865)
			(xy 116.192911 -345.331487) (xy 116.20828 -345.383828) (xy 116.216044 -345.437824) (xy 116.216044 -345.492369)
			(xy 117.698747 -345.492369) (xy 117.698747 -345.437831) (xy 117.706509 -345.383848) (xy 117.721875 -345.33152)
			(xy 117.744532 -345.281911) (xy 117.774019 -345.236031) (xy 117.809735 -345.194815) (xy 117.850953 -345.159102)
			(xy 117.896835 -345.129619) (xy 117.946446 -345.106965) (xy 117.998776 -345.091603) (xy 118.052759 -345.083845)
			(xy 118.080028 -345.083384) (xy 118.943628 -345.083384) (xy 118.970899 -345.08378) (xy 119.024886 -345.091546)
			(xy 119.077219 -345.106916) (xy 119.126832 -345.129576) (xy 119.172714 -345.159067) (xy 119.213934 -345.194786)
			(xy 119.24965 -345.236008) (xy 119.279137 -345.281893) (xy 119.301794 -345.331507) (xy 119.31716 -345.383841)
			(xy 119.324922 -345.437829) (xy 119.324922 -345.492366) (xy 120.80777 -345.492366) (xy 120.80777 -345.437834)
			(xy 120.815531 -345.383858) (xy 120.830894 -345.331536) (xy 120.853546 -345.281933) (xy 120.883027 -345.236058)
			(xy 120.918737 -345.194846) (xy 120.959948 -345.159135) (xy 121.005822 -345.129652) (xy 121.055425 -345.106998)
			(xy 121.107747 -345.091633) (xy 121.161722 -345.083871) (xy 121.188988 -345.083384) (xy 122.052588 -345.083384)
			(xy 122.079863 -345.083755) (xy 122.133857 -345.091516) (xy 122.186198 -345.106884) (xy 122.235819 -345.129543)
			(xy 122.281709 -345.159034) (xy 122.322936 -345.194756) (xy 122.358659 -345.235981) (xy 122.388151 -345.281871)
			(xy 122.410812 -345.331491) (xy 122.426181 -345.383831) (xy 122.433944 -345.437825) (xy 122.433944 -345.49237)
			(xy 123.916648 -345.49237) (xy 123.916648 -345.43783) (xy 123.92441 -345.383846) (xy 123.939777 -345.331515)
			(xy 123.962435 -345.281905) (xy 123.991924 -345.236024) (xy 124.027642 -345.194808) (xy 124.068863 -345.159095)
			(xy 124.114747 -345.129612) (xy 124.16436 -345.10696) (xy 124.216692 -345.0916) (xy 124.270678 -345.083844)
			(xy 124.297948 -345.083384) (xy 125.161548 -345.083384) (xy 125.188818 -345.083782) (xy 125.242803 -345.09155)
			(xy 125.295133 -345.106921) (xy 125.344744 -345.129583) (xy 125.390624 -345.159074) (xy 125.431841 -345.194793)
			(xy 125.467555 -345.236015) (xy 125.49704 -345.281899) (xy 125.519695 -345.331512) (xy 125.53506 -345.383844)
			(xy 125.542822 -345.43783) (xy 125.542822 -345.492368) (xy 127.025647 -345.492368) (xy 127.025647 -345.437832)
			(xy 127.033409 -345.383851) (xy 127.048774 -345.331524) (xy 127.071429 -345.281916) (xy 127.100914 -345.236038)
			(xy 127.136628 -345.194822) (xy 127.177844 -345.159109) (xy 127.223723 -345.129625) (xy 127.273331 -345.106971)
			(xy 127.325659 -345.091607) (xy 127.37964 -345.083847) (xy 127.406908 -345.083384) (xy 128.270508 -345.083384)
			(xy 128.29778 -345.083779) (xy 128.35177 -345.091543) (xy 128.404104 -345.106911) (xy 128.45372 -345.12957)
			(xy 128.499605 -345.15906) (xy 128.540827 -345.194779) (xy 128.576545 -345.236001) (xy 128.606034 -345.281888)
			(xy 128.628692 -345.331503) (xy 128.644059 -345.383838) (xy 128.651821 -345.437828) (xy 128.651821 -345.492365)
			(xy 130.13467 -345.492365) (xy 130.13467 -345.437835) (xy 130.14243 -345.383861) (xy 130.157792 -345.33154)
			(xy 130.180443 -345.281938) (xy 130.209922 -345.236064) (xy 130.24563 -345.194853) (xy 130.286839 -345.159142)
			(xy 130.33271 -345.129658) (xy 130.38231 -345.107003) (xy 130.43463 -345.091637) (xy 130.488603 -345.083872)
			(xy 130.515868 -345.083384) (xy 131.379468 -345.083384) (xy 131.406744 -345.083753) (xy 131.460741 -345.091513)
			(xy 131.513083 -345.106878) (xy 131.562707 -345.129537) (xy 131.6086 -345.159027) (xy 131.649829 -345.194749)
			(xy 131.685554 -345.235975) (xy 131.715048 -345.281865) (xy 131.737711 -345.331487) (xy 131.75308 -345.383828)
			(xy 131.760844 -345.437824) (xy 131.760844 -345.492369) (xy 133.243547 -345.492369) (xy 133.243547 -345.437831)
			(xy 133.251309 -345.383848) (xy 133.266675 -345.33152) (xy 133.289332 -345.281911) (xy 133.318819 -345.236031)
			(xy 133.354535 -345.194815) (xy 133.395753 -345.159102) (xy 133.441635 -345.129619) (xy 133.491246 -345.106965)
			(xy 133.543576 -345.091603) (xy 133.597559 -345.083845) (xy 133.624828 -345.083384) (xy 134.488428 -345.083384)
			(xy 134.515699 -345.08378) (xy 134.569686 -345.091546) (xy 134.622019 -345.106916) (xy 134.671632 -345.129576)
			(xy 134.717514 -345.159067) (xy 134.758734 -345.194786) (xy 134.79445 -345.236008) (xy 134.823937 -345.281893)
			(xy 134.846594 -345.331507) (xy 134.86196 -345.383841) (xy 134.869722 -345.437829) (xy 134.869722 -345.492366)
			(xy 136.35257 -345.492366) (xy 136.35257 -345.437834) (xy 136.360331 -345.383858) (xy 136.375694 -345.331536)
			(xy 136.398346 -345.281933) (xy 136.427827 -345.236058) (xy 136.463537 -345.194846) (xy 136.504748 -345.159135)
			(xy 136.550622 -345.129652) (xy 136.600225 -345.106998) (xy 136.652547 -345.091633) (xy 136.706522 -345.083871)
			(xy 136.733788 -345.083384) (xy 137.597388 -345.083384) (xy 137.624663 -345.083755) (xy 137.678657 -345.091516)
			(xy 137.730998 -345.106884) (xy 137.780619 -345.129543) (xy 137.826509 -345.159034) (xy 137.867736 -345.194756)
			(xy 137.903459 -345.235981) (xy 137.932951 -345.281871) (xy 137.955612 -345.331491) (xy 137.970981 -345.383831)
			(xy 137.978744 -345.437825) (xy 137.978744 -345.49237) (xy 139.461448 -345.49237) (xy 139.461448 -345.43783)
			(xy 139.46921 -345.383846) (xy 139.484577 -345.331515) (xy 139.507235 -345.281905) (xy 139.536724 -345.236024)
			(xy 139.572442 -345.194808) (xy 139.613663 -345.159095) (xy 139.659547 -345.129612) (xy 139.70916 -345.10696)
			(xy 139.761492 -345.0916) (xy 139.815478 -345.083844) (xy 139.842748 -345.083384) (xy 140.706348 -345.083384)
			(xy 140.733618 -345.083782) (xy 140.787603 -345.09155) (xy 140.839933 -345.106921) (xy 140.889544 -345.129583)
			(xy 140.935424 -345.159074) (xy 140.976641 -345.194793) (xy 141.012355 -345.236015) (xy 141.04184 -345.281899)
			(xy 141.064495 -345.331512) (xy 141.07986 -345.383844) (xy 141.087622 -345.43783) (xy 141.087622 -345.492368)
			(xy 142.570447 -345.492368) (xy 142.570447 -345.437832) (xy 142.578209 -345.383851) (xy 142.593574 -345.331524)
			(xy 142.616229 -345.281916) (xy 142.645714 -345.236038) (xy 142.681428 -345.194822) (xy 142.722644 -345.159109)
			(xy 142.768523 -345.129625) (xy 142.818131 -345.106971) (xy 142.870459 -345.091607) (xy 142.92444 -345.083847)
			(xy 142.951708 -345.083384) (xy 143.815308 -345.083384) (xy 143.84258 -345.083779) (xy 143.89657 -345.091543)
			(xy 143.948904 -345.106911) (xy 143.99852 -345.12957) (xy 144.044405 -345.15906) (xy 144.085627 -345.194779)
			(xy 144.121345 -345.236001) (xy 144.150834 -345.281888) (xy 144.173492 -345.331503) (xy 144.188859 -345.383838)
			(xy 144.196621 -345.437828) (xy 144.196621 -345.492365) (xy 164.91387 -345.492365) (xy 164.91387 -345.437835)
			(xy 164.92163 -345.383861) (xy 164.936992 -345.33154) (xy 164.959644 -345.281937) (xy 164.989123 -345.236063)
			(xy 165.024831 -345.194851) (xy 165.066041 -345.15914) (xy 165.111913 -345.129657) (xy 165.161513 -345.107002)
			(xy 165.213833 -345.091636) (xy 165.267807 -345.083872) (xy 165.295072 -345.083384) (xy 166.158672 -345.083384)
			(xy 166.185948 -345.083754) (xy 166.239944 -345.091514) (xy 166.292286 -345.106879) (xy 166.341909 -345.129538)
			(xy 166.387802 -345.159028) (xy 166.42903 -345.19475) (xy 166.464755 -345.235976) (xy 166.494249 -345.281866)
			(xy 166.516911 -345.331487) (xy 166.532281 -345.383829) (xy 166.540044 -345.437824) (xy 166.540044 -345.492369)
			(xy 168.022747 -345.492369) (xy 168.022747 -345.437831) (xy 168.03051 -345.383848) (xy 168.045876 -345.331519)
			(xy 168.068533 -345.281909) (xy 168.09802 -345.23603) (xy 168.133736 -345.194814) (xy 168.174955 -345.159101)
			(xy 168.220838 -345.129617) (xy 168.270449 -345.106964) (xy 168.322779 -345.091603) (xy 168.376763 -345.083845)
			(xy 168.404032 -345.083384) (xy 169.267632 -345.083384) (xy 169.294903 -345.083781) (xy 169.34889 -345.091547)
			(xy 169.401222 -345.106917) (xy 169.450834 -345.129578) (xy 169.496716 -345.159068) (xy 169.537935 -345.194788)
			(xy 169.573651 -345.236009) (xy 169.603138 -345.281894) (xy 169.625794 -345.331508) (xy 169.64116 -345.383842)
			(xy 169.648922 -345.437829) (xy 169.648922 -345.492366) (xy 171.13177 -345.492366) (xy 171.13177 -345.437834)
			(xy 171.139531 -345.383858) (xy 171.154894 -345.331535) (xy 171.177547 -345.281932) (xy 171.207028 -345.236057)
			(xy 171.242738 -345.194844) (xy 171.28395 -345.159133) (xy 171.329825 -345.129651) (xy 171.379428 -345.106997)
			(xy 171.43175 -345.091633) (xy 171.485726 -345.083871) (xy 171.512992 -345.083384) (xy 172.376592 -345.083384)
			(xy 172.403867 -345.083755) (xy 172.457861 -345.091517) (xy 172.510201 -345.106885) (xy 172.559821 -345.129544)
			(xy 172.605711 -345.159035) (xy 172.646937 -345.194757) (xy 172.68266 -345.235982) (xy 172.712152 -345.281872)
			(xy 172.734813 -345.331492) (xy 172.750181 -345.383831) (xy 172.757944 -345.437825) (xy 172.757944 -345.492364)
			(xy 174.24077 -345.492364) (xy 174.24077 -345.437836) (xy 174.24853 -345.383863) (xy 174.263891 -345.331544)
			(xy 174.286541 -345.281943) (xy 174.316019 -345.23607) (xy 174.351724 -345.194858) (xy 174.392931 -345.159147)
			(xy 174.438801 -345.129664) (xy 174.488399 -345.107008) (xy 174.540716 -345.09164) (xy 174.594688 -345.083874)
			(xy 174.621952 -345.083384) (xy 175.485552 -345.083384) (xy 175.512829 -345.083752) (xy 175.566827 -345.09151)
			(xy 175.619172 -345.106874) (xy 175.668797 -345.129531) (xy 175.714692 -345.159021) (xy 175.755923 -345.194743)
			(xy 175.79165 -345.235969) (xy 175.821146 -345.281861) (xy 175.843809 -345.331483) (xy 175.85918 -345.383826)
			(xy 175.866944 -345.437824) (xy 175.866944 -345.492368) (xy 177.349647 -345.492368) (xy 177.349647 -345.437832)
			(xy 177.357409 -345.38385) (xy 177.372774 -345.331523) (xy 177.39543 -345.281915) (xy 177.424915 -345.236036)
			(xy 177.460629 -345.194821) (xy 177.501846 -345.159108) (xy 177.547726 -345.129624) (xy 177.597334 -345.10697)
			(xy 177.649662 -345.091606) (xy 177.703644 -345.083847) (xy 177.730912 -345.083384) (xy 178.594512 -345.083384)
			(xy 178.621784 -345.083779) (xy 178.675773 -345.091543) (xy 178.728107 -345.106912) (xy 178.777722 -345.129571)
			(xy 178.823607 -345.159061) (xy 178.864828 -345.194781) (xy 178.900546 -345.236003) (xy 178.930035 -345.281889)
			(xy 178.952693 -345.331504) (xy 178.968059 -345.383839) (xy 178.975821 -345.437828) (xy 178.975821 -345.492365)
			(xy 180.45867 -345.492365) (xy 180.45867 -345.437835) (xy 180.46643 -345.383861) (xy 180.481792 -345.33154)
			(xy 180.504444 -345.281937) (xy 180.533923 -345.236063) (xy 180.569631 -345.194851) (xy 180.610841 -345.15914)
			(xy 180.656713 -345.129657) (xy 180.706313 -345.107002) (xy 180.758633 -345.091636) (xy 180.812607 -345.083872)
			(xy 180.839872 -345.083384) (xy 181.703472 -345.083384) (xy 181.730748 -345.083754) (xy 181.784744 -345.091514)
			(xy 181.837086 -345.106879) (xy 181.886709 -345.129538) (xy 181.932602 -345.159028) (xy 181.97383 -345.19475)
			(xy 182.009555 -345.235976) (xy 182.039049 -345.281866) (xy 182.061711 -345.331487) (xy 182.077081 -345.383829)
			(xy 182.084844 -345.437824) (xy 182.084844 -345.492369) (xy 183.567547 -345.492369) (xy 183.567547 -345.437831)
			(xy 183.57531 -345.383848) (xy 183.590676 -345.331519) (xy 183.613333 -345.281909) (xy 183.64282 -345.23603)
			(xy 183.678536 -345.194814) (xy 183.719755 -345.159101) (xy 183.765638 -345.129617) (xy 183.815249 -345.106964)
			(xy 183.867579 -345.091603) (xy 183.921563 -345.083845) (xy 183.948832 -345.083384) (xy 184.812432 -345.083384)
			(xy 184.839703 -345.083781) (xy 184.89369 -345.091547) (xy 184.946022 -345.106917) (xy 184.995634 -345.129578)
			(xy 185.041516 -345.159068) (xy 185.082735 -345.194788) (xy 185.118451 -345.236009) (xy 185.147938 -345.281894)
			(xy 185.170594 -345.331508) (xy 185.18596 -345.383842) (xy 185.193722 -345.437829) (xy 185.193722 -345.492366)
			(xy 186.67657 -345.492366) (xy 186.67657 -345.437834) (xy 186.684331 -345.383858) (xy 186.699694 -345.331535)
			(xy 186.722347 -345.281932) (xy 186.751828 -345.236057) (xy 186.787538 -345.194844) (xy 186.82875 -345.159133)
			(xy 186.874625 -345.129651) (xy 186.924228 -345.106997) (xy 186.97655 -345.091633) (xy 187.030526 -345.083871)
			(xy 187.057792 -345.083384) (xy 187.921392 -345.083384) (xy 187.948667 -345.083755) (xy 188.002661 -345.091517)
			(xy 188.055001 -345.106885) (xy 188.104621 -345.129544) (xy 188.150511 -345.159035) (xy 188.191737 -345.194757)
			(xy 188.22746 -345.235982) (xy 188.256952 -345.281872) (xy 188.279613 -345.331492) (xy 188.294981 -345.383831)
			(xy 188.302744 -345.437825) (xy 188.302744 -345.492364) (xy 189.78557 -345.492364) (xy 189.78557 -345.437836)
			(xy 189.79333 -345.383863) (xy 189.808691 -345.331544) (xy 189.831341 -345.281943) (xy 189.860819 -345.23607)
			(xy 189.896524 -345.194858) (xy 189.937731 -345.159147) (xy 189.983601 -345.129664) (xy 190.033199 -345.107008)
			(xy 190.085516 -345.09164) (xy 190.139488 -345.083874) (xy 190.166752 -345.083384) (xy 191.030352 -345.083384)
			(xy 191.057629 -345.083752) (xy 191.111627 -345.09151) (xy 191.163972 -345.106874) (xy 191.213597 -345.129531)
			(xy 191.259492 -345.159021) (xy 191.300723 -345.194743) (xy 191.33645 -345.235969) (xy 191.365946 -345.281861)
			(xy 191.388609 -345.331483) (xy 191.40398 -345.383826) (xy 191.411744 -345.437824) (xy 191.411744 -345.492368)
			(xy 192.894447 -345.492368) (xy 192.894447 -345.437832) (xy 192.902209 -345.38385) (xy 192.917574 -345.331523)
			(xy 192.94023 -345.281915) (xy 192.969715 -345.236036) (xy 193.005429 -345.194821) (xy 193.046646 -345.159108)
			(xy 193.092526 -345.129624) (xy 193.142134 -345.10697) (xy 193.194462 -345.091606) (xy 193.248444 -345.083847)
			(xy 193.275712 -345.083384) (xy 194.139312 -345.083384) (xy 194.166584 -345.083779) (xy 194.220573 -345.091543)
			(xy 194.272907 -345.106912) (xy 194.322522 -345.129571) (xy 194.368407 -345.159061) (xy 194.409628 -345.194781)
			(xy 194.445346 -345.236003) (xy 194.474835 -345.281889) (xy 194.497493 -345.331504) (xy 194.512859 -345.383839)
			(xy 194.520621 -345.437828) (xy 194.520621 -345.492365) (xy 196.00347 -345.492365) (xy 196.00347 -345.437835)
			(xy 196.01123 -345.383861) (xy 196.026592 -345.33154) (xy 196.049244 -345.281937) (xy 196.078723 -345.236063)
			(xy 196.114431 -345.194851) (xy 196.155641 -345.15914) (xy 196.201513 -345.129657) (xy 196.251113 -345.107002)
			(xy 196.303433 -345.091636) (xy 196.357407 -345.083872) (xy 196.384672 -345.083384) (xy 197.248272 -345.083384)
			(xy 197.275548 -345.083754) (xy 197.329544 -345.091514) (xy 197.381886 -345.106879) (xy 197.431509 -345.129538)
			(xy 197.477402 -345.159028) (xy 197.51863 -345.19475) (xy 197.554355 -345.235976) (xy 197.583849 -345.281866)
			(xy 197.606511 -345.331487) (xy 197.621881 -345.383829) (xy 197.629644 -345.437824) (xy 197.629644 -345.492368)
			(xy 267.515847 -345.492368) (xy 267.515847 -345.437832) (xy 267.523609 -345.383852) (xy 267.538973 -345.331525)
			(xy 267.561628 -345.281918) (xy 267.591112 -345.23604) (xy 267.626826 -345.194824) (xy 267.668041 -345.159111)
			(xy 267.71392 -345.129627) (xy 267.763527 -345.106972) (xy 267.815854 -345.091608) (xy 267.869834 -345.083847)
			(xy 267.897102 -345.083384) (xy 268.760702 -345.083384) (xy 268.787975 -345.083779) (xy 268.841964 -345.091542)
			(xy 268.8943 -345.106909) (xy 268.943916 -345.129568) (xy 268.989802 -345.159057) (xy 269.031024 -345.194777)
			(xy 269.066744 -345.236) (xy 269.096233 -345.281886) (xy 269.118892 -345.331502) (xy 269.134259 -345.383838)
			(xy 269.142021 -345.437827) (xy 269.142021 -345.492364) (xy 270.62487 -345.492364) (xy 270.62487 -345.437836)
			(xy 270.63263 -345.383862) (xy 270.647992 -345.331542) (xy 270.670642 -345.28194) (xy 270.700121 -345.236066)
			(xy 270.735828 -345.194855) (xy 270.777036 -345.159144) (xy 270.822907 -345.12966) (xy 270.872506 -345.107005)
			(xy 270.924825 -345.091638) (xy 270.978798 -345.083873) (xy 271.006062 -345.083384) (xy 271.869662 -345.083384)
			(xy 271.896938 -345.083753) (xy 271.950936 -345.091512) (xy 272.003279 -345.106877) (xy 272.052903 -345.129535)
			(xy 272.098797 -345.159025) (xy 272.140027 -345.194747) (xy 272.175752 -345.235973) (xy 272.205247 -345.281864)
			(xy 272.22791 -345.331485) (xy 272.24328 -345.383827) (xy 272.251044 -345.437824) (xy 272.251044 -345.492369)
			(xy 273.733747 -345.492369) (xy 273.733747 -345.437831) (xy 273.741509 -345.383849) (xy 273.756875 -345.331521)
			(xy 273.779531 -345.281912) (xy 273.809017 -345.236033) (xy 273.844733 -345.194817) (xy 273.885951 -345.159104)
			(xy 273.931832 -345.129621) (xy 273.981441 -345.106967) (xy 274.033771 -345.091605) (xy 274.087753 -345.083846)
			(xy 274.115022 -345.083384) (xy 274.978622 -345.083384) (xy 275.005894 -345.08378) (xy 275.059881 -345.091545)
			(xy 275.112215 -345.106914) (xy 275.161828 -345.129574) (xy 275.207712 -345.159064) (xy 275.248932 -345.194784)
			(xy 275.284649 -345.236006) (xy 275.314136 -345.281891) (xy 275.336793 -345.331506) (xy 275.352159 -345.38384)
			(xy 275.359922 -345.437828) (xy 275.359922 -345.492365) (xy 276.84277 -345.492365) (xy 276.84277 -345.437835)
			(xy 276.850531 -345.383859) (xy 276.865893 -345.331537) (xy 276.888545 -345.281934) (xy 276.918026 -345.23606)
			(xy 276.953735 -345.194848) (xy 276.994945 -345.159137) (xy 277.040819 -345.129654) (xy 277.090421 -345.106999)
			(xy 277.142742 -345.091634) (xy 277.196717 -345.083872) (xy 277.223982 -345.083384) (xy 278.087582 -345.083384)
			(xy 278.114857 -345.083754) (xy 278.168852 -345.091515) (xy 278.221194 -345.106882) (xy 278.270815 -345.129541)
			(xy 278.316706 -345.159032) (xy 278.357934 -345.194754) (xy 278.393657 -345.235979) (xy 278.42315 -345.281869)
			(xy 278.445812 -345.33149) (xy 278.461181 -345.38383) (xy 278.468944 -345.437825) (xy 278.468944 -345.49237)
			(xy 279.951648 -345.49237) (xy 279.951648 -345.43783) (xy 279.95941 -345.383846) (xy 279.974776 -345.331517)
			(xy 279.997434 -345.281907) (xy 280.026922 -345.236026) (xy 280.06264 -345.19481) (xy 280.10386 -345.159097)
			(xy 280.149744 -345.129614) (xy 280.199356 -345.106962) (xy 280.251687 -345.091601) (xy 280.305672 -345.083845)
			(xy 280.332942 -345.083384) (xy 281.196542 -345.083384) (xy 281.223813 -345.083781) (xy 281.277798 -345.091549)
			(xy 281.330129 -345.10692) (xy 281.37974 -345.129581) (xy 281.425621 -345.159072) (xy 281.466839 -345.194791)
			(xy 281.502554 -345.236013) (xy 281.532039 -345.281897) (xy 281.554695 -345.33151) (xy 281.57006 -345.383843)
			(xy 281.577822 -345.437829) (xy 281.577822 -345.492368) (xy 283.060647 -345.492368) (xy 283.060647 -345.437832)
			(xy 283.068409 -345.383852) (xy 283.083773 -345.331525) (xy 283.106428 -345.281918) (xy 283.135912 -345.23604)
			(xy 283.171626 -345.194824) (xy 283.212841 -345.159111) (xy 283.25872 -345.129627) (xy 283.308327 -345.106972)
			(xy 283.360654 -345.091608) (xy 283.414634 -345.083847) (xy 283.441902 -345.083384) (xy 284.305502 -345.083384)
			(xy 284.332775 -345.083779) (xy 284.386764 -345.091542) (xy 284.4391 -345.106909) (xy 284.488716 -345.129568)
			(xy 284.534602 -345.159057) (xy 284.575824 -345.194777) (xy 284.611544 -345.236) (xy 284.641033 -345.281886)
			(xy 284.663692 -345.331502) (xy 284.679059 -345.383838) (xy 284.686821 -345.437827) (xy 284.686821 -345.492364)
			(xy 286.16967 -345.492364) (xy 286.16967 -345.437836) (xy 286.17743 -345.383862) (xy 286.192792 -345.331542)
			(xy 286.215442 -345.28194) (xy 286.244921 -345.236066) (xy 286.280628 -345.194855) (xy 286.321836 -345.159144)
			(xy 286.367707 -345.12966) (xy 286.417306 -345.107005) (xy 286.469625 -345.091638) (xy 286.523598 -345.083873)
			(xy 286.550862 -345.083384) (xy 287.414462 -345.083384) (xy 287.441738 -345.083753) (xy 287.495736 -345.091512)
			(xy 287.548079 -345.106877) (xy 287.597703 -345.129535) (xy 287.643597 -345.159025) (xy 287.684827 -345.194747)
			(xy 287.720552 -345.235973) (xy 287.750047 -345.281864) (xy 287.77271 -345.331485) (xy 287.78808 -345.383827)
			(xy 287.795844 -345.437824) (xy 287.795844 -345.492369) (xy 289.278547 -345.492369) (xy 289.278547 -345.437831)
			(xy 289.286309 -345.383849) (xy 289.301675 -345.331521) (xy 289.324331 -345.281912) (xy 289.353817 -345.236033)
			(xy 289.389533 -345.194817) (xy 289.430751 -345.159104) (xy 289.476632 -345.129621) (xy 289.526241 -345.106967)
			(xy 289.578571 -345.091605) (xy 289.632553 -345.083846) (xy 289.659822 -345.083384) (xy 290.523422 -345.083384)
			(xy 290.550694 -345.08378) (xy 290.604681 -345.091545) (xy 290.657015 -345.106914) (xy 290.706628 -345.129574)
			(xy 290.752512 -345.159064) (xy 290.793732 -345.194784) (xy 290.829449 -345.236006) (xy 290.858936 -345.281891)
			(xy 290.881593 -345.331506) (xy 290.896959 -345.38384) (xy 290.904722 -345.437828) (xy 290.904722 -345.492365)
			(xy 292.38757 -345.492365) (xy 292.38757 -345.437835) (xy 292.395331 -345.383859) (xy 292.410693 -345.331537)
			(xy 292.433345 -345.281934) (xy 292.462826 -345.23606) (xy 292.498535 -345.194848) (xy 292.539745 -345.159137)
			(xy 292.585619 -345.129654) (xy 292.635221 -345.106999) (xy 292.687542 -345.091634) (xy 292.741517 -345.083872)
			(xy 292.768782 -345.083384) (xy 293.632382 -345.083384) (xy 293.659657 -345.083754) (xy 293.713652 -345.091515)
			(xy 293.765994 -345.106882) (xy 293.815615 -345.129541) (xy 293.861506 -345.159032) (xy 293.902734 -345.194754)
			(xy 293.938457 -345.235979) (xy 293.96795 -345.281869) (xy 293.990612 -345.33149) (xy 294.005981 -345.38383)
			(xy 294.013744 -345.437825) (xy 294.013744 -345.49237) (xy 295.496448 -345.49237) (xy 295.496448 -345.43783)
			(xy 295.50421 -345.383846) (xy 295.519576 -345.331517) (xy 295.542234 -345.281907) (xy 295.571722 -345.236026)
			(xy 295.60744 -345.19481) (xy 295.64866 -345.159097) (xy 295.694544 -345.129614) (xy 295.744156 -345.106962)
			(xy 295.796487 -345.091601) (xy 295.850472 -345.083845) (xy 295.877742 -345.083384) (xy 296.741342 -345.083384)
			(xy 296.768613 -345.083781) (xy 296.822598 -345.091549) (xy 296.874929 -345.10692) (xy 296.92454 -345.129581)
			(xy 296.970421 -345.159072) (xy 297.011639 -345.194791) (xy 297.047354 -345.236013) (xy 297.076839 -345.281897)
			(xy 297.099495 -345.33151) (xy 297.11486 -345.383843) (xy 297.122622 -345.437829) (xy 297.122622 -345.492368)
			(xy 298.605447 -345.492368) (xy 298.605447 -345.437832) (xy 298.613209 -345.383852) (xy 298.628573 -345.331525)
			(xy 298.651228 -345.281918) (xy 298.680712 -345.23604) (xy 298.716426 -345.194824) (xy 298.757641 -345.159111)
			(xy 298.80352 -345.129627) (xy 298.853127 -345.106972) (xy 298.905454 -345.091608) (xy 298.959434 -345.083847)
			(xy 298.986702 -345.083384) (xy 299.850302 -345.083384) (xy 299.877575 -345.083779) (xy 299.931564 -345.091542)
			(xy 299.9839 -345.106909) (xy 300.033516 -345.129568) (xy 300.079402 -345.159057) (xy 300.120624 -345.194777)
			(xy 300.156344 -345.236) (xy 300.185833 -345.281886) (xy 300.208492 -345.331502) (xy 300.223859 -345.383838)
			(xy 300.231621 -345.437827) (xy 300.231621 -345.492368) (xy 312.121547 -345.492368) (xy 312.121547 -345.437832)
			(xy 312.129309 -345.383851) (xy 312.144673 -345.331525) (xy 312.167328 -345.281917) (xy 312.196813 -345.236039)
			(xy 312.232526 -345.194824) (xy 312.273742 -345.159111) (xy 312.319621 -345.129627) (xy 312.369228 -345.106972)
			(xy 312.421555 -345.091608) (xy 312.475536 -345.083847) (xy 312.502804 -345.083384) (xy 313.366404 -345.083384)
			(xy 313.393676 -345.083779) (xy 313.447666 -345.091542) (xy 313.500001 -345.106909) (xy 313.549617 -345.129569)
			(xy 313.595503 -345.159058) (xy 313.636725 -345.194778) (xy 313.672444 -345.236) (xy 313.701933 -345.281886)
			(xy 313.724592 -345.331502) (xy 313.739959 -345.383838) (xy 313.747721 -345.437828) (xy 313.747721 -345.492364)
			(xy 315.23057 -345.492364) (xy 315.23057 -345.437836) (xy 315.23833 -345.383862) (xy 315.253692 -345.331541)
			(xy 315.276343 -345.281939) (xy 315.305821 -345.236066) (xy 315.341529 -345.194854) (xy 315.382737 -345.159143)
			(xy 315.428608 -345.12966) (xy 315.478207 -345.107004) (xy 315.530526 -345.091638) (xy 315.5845 -345.083873)
			(xy 315.611764 -345.083384) (xy 316.475364 -345.083384) (xy 316.50264 -345.083753) (xy 316.556637 -345.091512)
			(xy 316.608981 -345.106877) (xy 316.658604 -345.129535) (xy 316.704498 -345.159026) (xy 316.745727 -345.194747)
			(xy 316.781453 -345.235973) (xy 316.810947 -345.281864) (xy 316.83361 -345.331486) (xy 316.84898 -345.383828)
			(xy 316.856744 -345.437824) (xy 316.856744 -345.492369) (xy 318.339447 -345.492369) (xy 318.339447 -345.437831)
			(xy 318.347209 -345.383849) (xy 318.362575 -345.33152) (xy 318.385231 -345.281912) (xy 318.414718 -345.236032)
			(xy 318.450434 -345.194817) (xy 318.491652 -345.159103) (xy 318.537533 -345.12962) (xy 318.587143 -345.106966)
			(xy 318.639472 -345.091604) (xy 318.693455 -345.083846) (xy 318.720724 -345.083384) (xy 319.584324 -345.083384)
			(xy 319.611596 -345.08378) (xy 319.665583 -345.091546) (xy 319.717916 -345.106915) (xy 319.767529 -345.129575)
			(xy 319.813413 -345.159065) (xy 319.854632 -345.194785) (xy 319.890349 -345.236007) (xy 319.919836 -345.281892)
			(xy 319.942494 -345.331507) (xy 319.95786 -345.38384) (xy 319.965622 -345.437828) (xy 319.965622 -345.492365)
			(xy 321.44847 -345.492365) (xy 321.44847 -345.437835) (xy 321.456231 -345.383859) (xy 321.471593 -345.331537)
			(xy 321.494246 -345.281934) (xy 321.523726 -345.236059) (xy 321.559436 -345.194847) (xy 321.600646 -345.159136)
			(xy 321.64652 -345.129653) (xy 321.696122 -345.106999) (xy 321.748443 -345.091634) (xy 321.802419 -345.083871)
			(xy 321.829684 -345.083384) (xy 322.693284 -345.083384) (xy 322.720559 -345.083755) (xy 322.774554 -345.091516)
			(xy 322.826895 -345.106882) (xy 322.876516 -345.129542) (xy 322.922407 -345.159033) (xy 322.963634 -345.194754)
			(xy 322.999358 -345.23598) (xy 323.02885 -345.28187) (xy 323.051512 -345.33149) (xy 323.066881 -345.38383)
			(xy 323.074644 -345.437825) (xy 323.074644 -345.49237) (xy 324.557348 -345.49237) (xy 324.557348 -345.43783)
			(xy 324.56511 -345.383846) (xy 324.580476 -345.331516) (xy 324.603135 -345.281906) (xy 324.632623 -345.236026)
			(xy 324.668341 -345.194809) (xy 324.709561 -345.159096) (xy 324.755445 -345.129613) (xy 324.805057 -345.106961)
			(xy 324.857389 -345.0916) (xy 324.911374 -345.083844) (xy 324.938644 -345.083384) (xy 325.802244 -345.083384)
			(xy 325.829515 -345.083782) (xy 325.8835 -345.091549) (xy 325.93583 -345.10692) (xy 325.985441 -345.129582)
			(xy 326.031322 -345.159072) (xy 326.072539 -345.194792) (xy 326.108254 -345.236013) (xy 326.137739 -345.281898)
			(xy 326.160395 -345.331511) (xy 326.17576 -345.383843) (xy 326.183522 -345.437829) (xy 326.183522 -345.492368)
			(xy 327.666347 -345.492368) (xy 327.666347 -345.437832) (xy 327.674109 -345.383851) (xy 327.689473 -345.331525)
			(xy 327.712128 -345.281917) (xy 327.741613 -345.236039) (xy 327.777326 -345.194824) (xy 327.818542 -345.159111)
			(xy 327.864421 -345.129627) (xy 327.914028 -345.106972) (xy 327.966355 -345.091608) (xy 328.020336 -345.083847)
			(xy 328.047604 -345.083384) (xy 328.911204 -345.083384) (xy 328.938476 -345.083779) (xy 328.992466 -345.091542)
			(xy 329.044801 -345.106909) (xy 329.094417 -345.129569) (xy 329.140303 -345.159058) (xy 329.181525 -345.194778)
			(xy 329.217244 -345.236) (xy 329.246733 -345.281886) (xy 329.269392 -345.331502) (xy 329.284759 -345.383838)
			(xy 329.292521 -345.437828) (xy 329.292521 -345.492364) (xy 330.77537 -345.492364) (xy 330.77537 -345.437836)
			(xy 330.78313 -345.383862) (xy 330.798492 -345.331541) (xy 330.821143 -345.281939) (xy 330.850621 -345.236066)
			(xy 330.886329 -345.194854) (xy 330.927537 -345.159143) (xy 330.973408 -345.12966) (xy 331.023007 -345.107004)
			(xy 331.075326 -345.091638) (xy 331.1293 -345.083873) (xy 331.156564 -345.083384) (xy 332.020164 -345.083384)
			(xy 332.04744 -345.083753) (xy 332.101437 -345.091512) (xy 332.153781 -345.106877) (xy 332.203404 -345.129535)
			(xy 332.249298 -345.159026) (xy 332.290527 -345.194747) (xy 332.326253 -345.235973) (xy 332.355747 -345.281864)
			(xy 332.37841 -345.331486) (xy 332.39378 -345.383828) (xy 332.401544 -345.437824) (xy 332.401544 -345.492369)
			(xy 333.884247 -345.492369) (xy 333.884247 -345.437831) (xy 333.892009 -345.383849) (xy 333.907375 -345.33152)
			(xy 333.930031 -345.281912) (xy 333.959518 -345.236032) (xy 333.995234 -345.194817) (xy 334.036452 -345.159103)
			(xy 334.082333 -345.12962) (xy 334.131943 -345.106966) (xy 334.184272 -345.091604) (xy 334.238255 -345.083846)
			(xy 334.265524 -345.083384) (xy 335.129124 -345.083384) (xy 335.156396 -345.08378) (xy 335.210383 -345.091546)
			(xy 335.262716 -345.106915) (xy 335.312329 -345.129575) (xy 335.358213 -345.159065) (xy 335.399432 -345.194785)
			(xy 335.435149 -345.236007) (xy 335.464636 -345.281892) (xy 335.487294 -345.331507) (xy 335.50266 -345.38384)
			(xy 335.510422 -345.437828) (xy 335.510422 -345.492365) (xy 336.99327 -345.492365) (xy 336.99327 -345.437835)
			(xy 337.001031 -345.383859) (xy 337.016393 -345.331537) (xy 337.039046 -345.281934) (xy 337.068526 -345.236059)
			(xy 337.104236 -345.194847) (xy 337.145446 -345.159136) (xy 337.19132 -345.129653) (xy 337.240922 -345.106999)
			(xy 337.293243 -345.091634) (xy 337.347219 -345.083871) (xy 337.374484 -345.083384) (xy 338.238084 -345.083384)
			(xy 338.265359 -345.083755) (xy 338.319354 -345.091516) (xy 338.371695 -345.106882) (xy 338.421316 -345.129542)
			(xy 338.467207 -345.159033) (xy 338.508434 -345.194754) (xy 338.544158 -345.23598) (xy 338.57365 -345.28187)
			(xy 338.596312 -345.33149) (xy 338.611681 -345.38383) (xy 338.619444 -345.437825) (xy 338.619444 -345.49237)
			(xy 340.102148 -345.49237) (xy 340.102148 -345.43783) (xy 340.10991 -345.383846) (xy 340.125276 -345.331516)
			(xy 340.147935 -345.281906) (xy 340.177423 -345.236026) (xy 340.213141 -345.194809) (xy 340.254361 -345.159096)
			(xy 340.300245 -345.129613) (xy 340.349857 -345.106961) (xy 340.402189 -345.0916) (xy 340.456174 -345.083844)
			(xy 340.483444 -345.083384) (xy 341.347044 -345.083384) (xy 341.374315 -345.083782) (xy 341.4283 -345.091549)
			(xy 341.48063 -345.10692) (xy 341.530241 -345.129582) (xy 341.576122 -345.159072) (xy 341.617339 -345.194792)
			(xy 341.653054 -345.236013) (xy 341.682539 -345.281898) (xy 341.705195 -345.331511) (xy 341.72056 -345.383843)
			(xy 341.728322 -345.437829) (xy 341.728322 -345.492368) (xy 343.211147 -345.492368) (xy 343.211147 -345.437832)
			(xy 343.218909 -345.383851) (xy 343.234273 -345.331525) (xy 343.256928 -345.281917) (xy 343.286413 -345.236039)
			(xy 343.322126 -345.194824) (xy 343.363342 -345.159111) (xy 343.409221 -345.129627) (xy 343.458828 -345.106972)
			(xy 343.511155 -345.091608) (xy 343.565136 -345.083847) (xy 343.592404 -345.083384) (xy 344.456004 -345.083384)
			(xy 344.483276 -345.083779) (xy 344.537266 -345.091542) (xy 344.589601 -345.106909) (xy 344.639217 -345.129569)
			(xy 344.685103 -345.159058) (xy 344.726325 -345.194778) (xy 344.762044 -345.236) (xy 344.791533 -345.281886)
			(xy 344.814192 -345.331502) (xy 344.829559 -345.383838) (xy 344.837321 -345.437828) (xy 344.837321 -345.492365)
			(xy 370.80677 -345.492365) (xy 370.80677 -345.437835) (xy 370.81453 -345.383859) (xy 370.829893 -345.331538)
			(xy 370.852545 -345.281935) (xy 370.882025 -345.236061) (xy 370.917734 -345.194848) (xy 370.958945 -345.159137)
			(xy 371.004817 -345.129655) (xy 371.054419 -345.107) (xy 371.10674 -345.091635) (xy 371.160715 -345.083872)
			(xy 371.18798 -345.083384) (xy 372.05158 -345.083384) (xy 372.078855 -345.083754) (xy 372.132851 -345.091515)
			(xy 372.185192 -345.106881) (xy 372.234814 -345.129541) (xy 372.280705 -345.159031) (xy 372.321933 -345.194753)
			(xy 372.357657 -345.235978) (xy 372.38715 -345.281869) (xy 372.409812 -345.331489) (xy 372.425181 -345.38383)
			(xy 372.432944 -345.437825) (xy 372.432944 -345.49237) (xy 373.915647 -345.49237) (xy 373.915647 -345.43783)
			(xy 373.92341 -345.383847) (xy 373.938776 -345.331517) (xy 373.961434 -345.281907) (xy 373.990922 -345.236027)
			(xy 374.026639 -345.194811) (xy 374.067859 -345.159098) (xy 374.113742 -345.129615) (xy 374.163355 -345.106962)
			(xy 374.215686 -345.091601) (xy 374.26967 -345.083845) (xy 374.29694 -345.083384) (xy 375.16054 -345.083384)
			(xy 375.187811 -345.083781) (xy 375.241797 -345.091549) (xy 375.294128 -345.106919) (xy 375.343739 -345.12958)
			(xy 375.38962 -345.159071) (xy 375.430838 -345.19479) (xy 375.466553 -345.236012) (xy 375.496039 -345.281896)
			(xy 375.518695 -345.33151) (xy 375.53406 -345.383843) (xy 375.541822 -345.437829) (xy 375.541822 -345.492366)
			(xy 377.02467 -345.492366) (xy 377.02467 -345.437834) (xy 377.032431 -345.383857) (xy 377.047795 -345.331534)
			(xy 377.070448 -345.281929) (xy 377.09993 -345.236054) (xy 377.135641 -345.194841) (xy 377.176854 -345.15913)
			(xy 377.222729 -345.129648) (xy 377.272334 -345.106995) (xy 377.324657 -345.091631) (xy 377.378634 -345.08387)
			(xy 377.4059 -345.083384) (xy 378.2695 -345.083384) (xy 378.296773 -345.083779) (xy 378.350763 -345.091541)
			(xy 378.403099 -345.106908) (xy 378.452715 -345.129567) (xy 378.498601 -345.159057) (xy 378.539824 -345.194776)
			(xy 378.575543 -345.235999) (xy 378.605033 -345.281885) (xy 378.627692 -345.331501) (xy 378.643059 -345.383837)
			(xy 378.650821 -345.437827) (xy 378.650821 -345.492364) (xy 380.13367 -345.492364) (xy 380.13367 -345.437836)
			(xy 380.14143 -345.383862) (xy 380.156791 -345.331542) (xy 380.179442 -345.281941) (xy 380.208921 -345.236067)
			(xy 380.244627 -345.194855) (xy 380.285835 -345.159145) (xy 380.331705 -345.129661) (xy 380.381305 -345.107005)
			(xy 380.433623 -345.091638) (xy 380.487596 -345.083873) (xy 380.51486 -345.083384) (xy 381.37846 -345.083384)
			(xy 381.405736 -345.083753) (xy 381.459734 -345.091511) (xy 381.512078 -345.106876) (xy 381.561702 -345.129534)
			(xy 381.607596 -345.159024) (xy 381.648826 -345.194746) (xy 381.684552 -345.235972) (xy 381.714047 -345.281863)
			(xy 381.73671 -345.331485) (xy 381.75208 -345.383827) (xy 381.759844 -345.437824) (xy 381.759844 -345.492369)
			(xy 383.242547 -345.492369) (xy 383.242547 -345.437831) (xy 383.250309 -345.383849) (xy 383.265675 -345.331521)
			(xy 383.288331 -345.281913) (xy 383.317817 -345.236034) (xy 383.353532 -345.194818) (xy 383.39475 -345.159105)
			(xy 383.44063 -345.129621) (xy 383.49024 -345.106968) (xy 383.542569 -345.091605) (xy 383.596551 -345.083846)
			(xy 383.62382 -345.083384) (xy 384.48742 -345.083384) (xy 384.514692 -345.08378) (xy 384.56868 -345.091545)
			(xy 384.621013 -345.106914) (xy 384.670627 -345.129574) (xy 384.716511 -345.159064) (xy 384.757731 -345.194783)
			(xy 384.793448 -345.236005) (xy 384.822936 -345.281891) (xy 384.845593 -345.331506) (xy 384.860959 -345.38384)
			(xy 384.868722 -345.437828) (xy 384.868722 -345.492365) (xy 386.35157 -345.492365) (xy 386.35157 -345.437835)
			(xy 386.35933 -345.383859) (xy 386.374693 -345.331538) (xy 386.397345 -345.281935) (xy 386.426825 -345.236061)
			(xy 386.462534 -345.194848) (xy 386.503745 -345.159137) (xy 386.549617 -345.129655) (xy 386.599219 -345.107)
			(xy 386.65154 -345.091635) (xy 386.705515 -345.083872) (xy 386.73278 -345.083384) (xy 387.59638 -345.083384)
			(xy 387.623655 -345.083754) (xy 387.677651 -345.091515) (xy 387.729992 -345.106881) (xy 387.779614 -345.129541)
			(xy 387.825505 -345.159031) (xy 387.866733 -345.194753) (xy 387.902457 -345.235978) (xy 387.93195 -345.281869)
			(xy 387.954612 -345.331489) (xy 387.969981 -345.38383) (xy 387.977744 -345.437825) (xy 387.977744 -345.49237)
			(xy 389.460447 -345.49237) (xy 389.460447 -345.43783) (xy 389.46821 -345.383847) (xy 389.483576 -345.331517)
			(xy 389.506234 -345.281907) (xy 389.535722 -345.236027) (xy 389.571439 -345.194811) (xy 389.612659 -345.159098)
			(xy 389.658542 -345.129615) (xy 389.708155 -345.106962) (xy 389.760486 -345.091601) (xy 389.81447 -345.083845)
			(xy 389.84174 -345.083384) (xy 390.70534 -345.083384) (xy 390.732611 -345.083781) (xy 390.786597 -345.091549)
			(xy 390.838928 -345.106919) (xy 390.888539 -345.12958) (xy 390.93442 -345.159071) (xy 390.975638 -345.19479)
			(xy 391.011353 -345.236012) (xy 391.040839 -345.281896) (xy 391.063495 -345.33151) (xy 391.07886 -345.383843)
			(xy 391.086622 -345.437829) (xy 391.086622 -345.492366) (xy 392.56947 -345.492366) (xy 392.56947 -345.437834)
			(xy 392.577231 -345.383857) (xy 392.592595 -345.331534) (xy 392.615248 -345.281929) (xy 392.64473 -345.236054)
			(xy 392.680441 -345.194841) (xy 392.721654 -345.15913) (xy 392.767529 -345.129648) (xy 392.817134 -345.106995)
			(xy 392.869457 -345.091631) (xy 392.923434 -345.08387) (xy 392.9507 -345.083384) (xy 393.8143 -345.083384)
			(xy 393.841573 -345.083779) (xy 393.895563 -345.091541) (xy 393.947899 -345.106908) (xy 393.997515 -345.129567)
			(xy 394.043401 -345.159057) (xy 394.084624 -345.194776) (xy 394.120343 -345.235999) (xy 394.149833 -345.281885)
			(xy 394.172492 -345.331501) (xy 394.187859 -345.383837) (xy 394.195621 -345.437827) (xy 394.195621 -345.492364)
			(xy 395.67847 -345.492364) (xy 395.67847 -345.437836) (xy 395.68623 -345.383862) (xy 395.701591 -345.331542)
			(xy 395.724242 -345.281941) (xy 395.753721 -345.236067) (xy 395.789427 -345.194855) (xy 395.830635 -345.159145)
			(xy 395.876505 -345.129661) (xy 395.926105 -345.107005) (xy 395.978423 -345.091638) (xy 396.032396 -345.083873)
			(xy 396.05966 -345.083384) (xy 396.92326 -345.083384) (xy 396.950536 -345.083753) (xy 397.004534 -345.091511)
			(xy 397.056878 -345.106876) (xy 397.106502 -345.129534) (xy 397.152396 -345.159024) (xy 397.193626 -345.194746)
			(xy 397.229352 -345.235972) (xy 397.258847 -345.281863) (xy 397.28151 -345.331485) (xy 397.29688 -345.383827)
			(xy 397.304644 -345.437824) (xy 397.304644 -345.492369) (xy 398.787347 -345.492369) (xy 398.787347 -345.437831)
			(xy 398.795109 -345.383849) (xy 398.810475 -345.331521) (xy 398.833131 -345.281913) (xy 398.862617 -345.236034)
			(xy 398.898332 -345.194818) (xy 398.93955 -345.159105) (xy 398.98543 -345.129621) (xy 399.03504 -345.106968)
			(xy 399.087369 -345.091605) (xy 399.141351 -345.083846) (xy 399.16862 -345.083384) (xy 400.03222 -345.083384)
			(xy 400.059492 -345.08378) (xy 400.11348 -345.091545) (xy 400.165813 -345.106914) (xy 400.215427 -345.129574)
			(xy 400.261311 -345.159064) (xy 400.302531 -345.194783) (xy 400.338248 -345.236005) (xy 400.367736 -345.281891)
			(xy 400.390393 -345.331506) (xy 400.405759 -345.38384) (xy 400.413522 -345.437828) (xy 400.413522 -345.492365)
			(xy 401.89637 -345.492365) (xy 401.89637 -345.437835) (xy 401.90413 -345.383859) (xy 401.919493 -345.331538)
			(xy 401.942145 -345.281935) (xy 401.971625 -345.236061) (xy 402.007334 -345.194848) (xy 402.048545 -345.159137)
			(xy 402.094417 -345.129655) (xy 402.144019 -345.107) (xy 402.19634 -345.091635) (xy 402.250315 -345.083872)
			(xy 402.27758 -345.083384) (xy 403.14118 -345.083384) (xy 403.168455 -345.083754) (xy 403.222451 -345.091515)
			(xy 403.274792 -345.106881) (xy 403.324414 -345.129541) (xy 403.370305 -345.159031) (xy 403.411533 -345.194753)
			(xy 403.447257 -345.235978) (xy 403.47675 -345.281869) (xy 403.499412 -345.331489) (xy 403.514781 -345.38383)
			(xy 403.522544 -345.437825) (xy 403.522544 -345.492366) (xy 408.91387 -345.492366) (xy 408.91387 -345.437834)
			(xy 408.921631 -345.383858) (xy 408.936994 -345.331535) (xy 408.959647 -345.281932) (xy 408.989128 -345.236057)
			(xy 409.024838 -345.194844) (xy 409.06605 -345.159133) (xy 409.111925 -345.129651) (xy 409.161528 -345.106997)
			(xy 409.21385 -345.091633) (xy 409.267826 -345.083871) (xy 409.295092 -345.083384) (xy 410.158692 -345.083384)
			(xy 410.185967 -345.083755) (xy 410.239961 -345.091517) (xy 410.292301 -345.106885) (xy 410.341921 -345.129544)
			(xy 410.387811 -345.159035) (xy 410.429037 -345.194757) (xy 410.46476 -345.235982) (xy 410.494252 -345.281872)
			(xy 410.516913 -345.331492) (xy 410.532281 -345.383831) (xy 410.540044 -345.437825) (xy 410.540044 -345.492364)
			(xy 412.02287 -345.492364) (xy 412.02287 -345.437836) (xy 412.03063 -345.383863) (xy 412.045991 -345.331544)
			(xy 412.068641 -345.281943) (xy 412.098119 -345.23607) (xy 412.133824 -345.194858) (xy 412.175031 -345.159147)
			(xy 412.220901 -345.129664) (xy 412.270499 -345.107008) (xy 412.322816 -345.09164) (xy 412.376788 -345.083874)
			(xy 412.404052 -345.083384) (xy 413.267652 -345.083384) (xy 413.294929 -345.083752) (xy 413.348927 -345.09151)
			(xy 413.401272 -345.106874) (xy 413.450897 -345.129531) (xy 413.496792 -345.159021) (xy 413.538023 -345.194743)
			(xy 413.57375 -345.235969) (xy 413.603246 -345.281861) (xy 413.625909 -345.331483) (xy 413.64128 -345.383826)
			(xy 413.649044 -345.437824) (xy 413.649044 -345.492368) (xy 415.131747 -345.492368) (xy 415.131747 -345.437832)
			(xy 415.139509 -345.38385) (xy 415.154874 -345.331523) (xy 415.17753 -345.281915) (xy 415.207015 -345.236036)
			(xy 415.242729 -345.194821) (xy 415.283946 -345.159108) (xy 415.329826 -345.129624) (xy 415.379434 -345.10697)
			(xy 415.431762 -345.091606) (xy 415.485744 -345.083847) (xy 415.513012 -345.083384) (xy 416.376612 -345.083384)
			(xy 416.403884 -345.083779) (xy 416.457873 -345.091543) (xy 416.510207 -345.106912) (xy 416.559822 -345.129571)
			(xy 416.605707 -345.159061) (xy 416.646928 -345.194781) (xy 416.682646 -345.236003) (xy 416.712135 -345.281889)
			(xy 416.734793 -345.331504) (xy 416.750159 -345.383839) (xy 416.757921 -345.437828) (xy 416.757921 -345.492365)
			(xy 418.24077 -345.492365) (xy 418.24077 -345.437835) (xy 418.24853 -345.383861) (xy 418.263892 -345.33154)
			(xy 418.286544 -345.281937) (xy 418.316023 -345.236063) (xy 418.351731 -345.194851) (xy 418.392941 -345.15914)
			(xy 418.438813 -345.129657) (xy 418.488413 -345.107002) (xy 418.540733 -345.091636) (xy 418.594707 -345.083872)
			(xy 418.621972 -345.083384) (xy 419.485572 -345.083384) (xy 419.512848 -345.083754) (xy 419.566844 -345.091514)
			(xy 419.619186 -345.106879) (xy 419.668809 -345.129538) (xy 419.714702 -345.159028) (xy 419.75593 -345.19475)
			(xy 419.791655 -345.235976) (xy 419.821149 -345.281866) (xy 419.843811 -345.331487) (xy 419.859181 -345.383829)
			(xy 419.866944 -345.437824) (xy 419.866944 -345.492369) (xy 421.349647 -345.492369) (xy 421.349647 -345.437831)
			(xy 421.35741 -345.383848) (xy 421.372776 -345.331519) (xy 421.395433 -345.281909) (xy 421.42492 -345.23603)
			(xy 421.460636 -345.194814) (xy 421.501855 -345.159101) (xy 421.547738 -345.129617) (xy 421.597349 -345.106964)
			(xy 421.649679 -345.091603) (xy 421.703663 -345.083845) (xy 421.730932 -345.083384) (xy 422.594532 -345.083384)
			(xy 422.621803 -345.083781) (xy 422.67579 -345.091547) (xy 422.728122 -345.106917) (xy 422.777734 -345.129578)
			(xy 422.823616 -345.159068) (xy 422.864835 -345.194788) (xy 422.900551 -345.236009) (xy 422.930038 -345.281894)
			(xy 422.952694 -345.331508) (xy 422.96806 -345.383842) (xy 422.975822 -345.437829) (xy 422.975822 -345.492366)
			(xy 424.45867 -345.492366) (xy 424.45867 -345.437834) (xy 424.466431 -345.383858) (xy 424.481794 -345.331535)
			(xy 424.504447 -345.281932) (xy 424.533928 -345.236057) (xy 424.569638 -345.194844) (xy 424.61085 -345.159133)
			(xy 424.656725 -345.129651) (xy 424.706328 -345.106997) (xy 424.75865 -345.091633) (xy 424.812626 -345.083871)
			(xy 424.839892 -345.083384) (xy 425.703492 -345.083384) (xy 425.730767 -345.083755) (xy 425.784761 -345.091517)
			(xy 425.837101 -345.106885) (xy 425.886721 -345.129544) (xy 425.932611 -345.159035) (xy 425.973837 -345.194757)
			(xy 426.00956 -345.235982) (xy 426.039052 -345.281872) (xy 426.061713 -345.331492) (xy 426.077081 -345.383831)
			(xy 426.084844 -345.437825) (xy 426.084844 -345.492364) (xy 427.56767 -345.492364) (xy 427.56767 -345.437836)
			(xy 427.57543 -345.383863) (xy 427.590791 -345.331544) (xy 427.613441 -345.281943) (xy 427.642919 -345.23607)
			(xy 427.678624 -345.194858) (xy 427.719831 -345.159147) (xy 427.765701 -345.129664) (xy 427.815299 -345.107008)
			(xy 427.867616 -345.09164) (xy 427.921588 -345.083874) (xy 427.948852 -345.083384) (xy 428.812452 -345.083384)
			(xy 428.839729 -345.083752) (xy 428.893727 -345.09151) (xy 428.946072 -345.106874) (xy 428.995697 -345.129531)
			(xy 429.041592 -345.159021) (xy 429.082823 -345.194743) (xy 429.11855 -345.235969) (xy 429.148046 -345.281861)
			(xy 429.170709 -345.331483) (xy 429.18608 -345.383826) (xy 429.193844 -345.437824) (xy 429.193844 -345.492368)
			(xy 430.676547 -345.492368) (xy 430.676547 -345.437832) (xy 430.684309 -345.38385) (xy 430.699674 -345.331523)
			(xy 430.72233 -345.281915) (xy 430.751815 -345.236036) (xy 430.787529 -345.194821) (xy 430.828746 -345.159108)
			(xy 430.874626 -345.129624) (xy 430.924234 -345.10697) (xy 430.976562 -345.091606) (xy 431.030544 -345.083847)
			(xy 431.057812 -345.083384) (xy 431.921412 -345.083384) (xy 431.948684 -345.083779) (xy 432.002673 -345.091543)
			(xy 432.055007 -345.106912) (xy 432.104622 -345.129571) (xy 432.150507 -345.159061) (xy 432.191728 -345.194781)
			(xy 432.227446 -345.236003) (xy 432.256935 -345.281889) (xy 432.279593 -345.331504) (xy 432.294959 -345.383839)
			(xy 432.302721 -345.437828) (xy 432.302721 -345.492365) (xy 433.78557 -345.492365) (xy 433.78557 -345.437835)
			(xy 433.79333 -345.383861) (xy 433.808692 -345.33154) (xy 433.831344 -345.281937) (xy 433.860823 -345.236063)
			(xy 433.896531 -345.194851) (xy 433.937741 -345.15914) (xy 433.983613 -345.129657) (xy 434.033213 -345.107002)
			(xy 434.085533 -345.091636) (xy 434.139507 -345.083872) (xy 434.166772 -345.083384) (xy 435.030372 -345.083384)
			(xy 435.057648 -345.083754) (xy 435.111644 -345.091514) (xy 435.163986 -345.106879) (xy 435.213609 -345.129538)
			(xy 435.259502 -345.159028) (xy 435.30073 -345.19475) (xy 435.336455 -345.235976) (xy 435.365949 -345.281866)
			(xy 435.388611 -345.331487) (xy 435.403981 -345.383829) (xy 435.411744 -345.437824) (xy 435.411744 -345.492369)
			(xy 436.894447 -345.492369) (xy 436.894447 -345.437831) (xy 436.90221 -345.383848) (xy 436.917576 -345.331519)
			(xy 436.940233 -345.281909) (xy 436.96972 -345.23603) (xy 437.005436 -345.194814) (xy 437.046655 -345.159101)
			(xy 437.092538 -345.129617) (xy 437.142149 -345.106964) (xy 437.194479 -345.091603) (xy 437.248463 -345.083845)
			(xy 437.275732 -345.083384) (xy 438.139332 -345.083384) (xy 438.166603 -345.083781) (xy 438.22059 -345.091547)
			(xy 438.272922 -345.106917) (xy 438.322534 -345.129578) (xy 438.368416 -345.159068) (xy 438.409635 -345.194788)
			(xy 438.445351 -345.236009) (xy 438.474838 -345.281894) (xy 438.497494 -345.331508) (xy 438.51286 -345.383842)
			(xy 438.520622 -345.437829) (xy 438.520622 -345.492366) (xy 440.00347 -345.492366) (xy 440.00347 -345.437834)
			(xy 440.011231 -345.383858) (xy 440.026594 -345.331535) (xy 440.049247 -345.281932) (xy 440.078728 -345.236057)
			(xy 440.114438 -345.194844) (xy 440.15565 -345.159133) (xy 440.201525 -345.129651) (xy 440.251128 -345.106997)
			(xy 440.30345 -345.091633) (xy 440.357426 -345.083871) (xy 440.384692 -345.083384) (xy 441.248292 -345.083384)
			(xy 441.275567 -345.083755) (xy 441.329561 -345.091517) (xy 441.381901 -345.106885) (xy 441.431521 -345.129544)
			(xy 441.477411 -345.159035) (xy 441.518637 -345.194757) (xy 441.55436 -345.235982) (xy 441.583852 -345.281872)
			(xy 441.606513 -345.331492) (xy 441.621881 -345.383831) (xy 441.629644 -345.437825) (xy 441.629644 -345.492375)
			(xy 441.621881 -345.546369) (xy 441.606513 -345.598708) (xy 441.583852 -345.648328) (xy 441.55436 -345.694218)
			(xy 441.518637 -345.735443) (xy 441.477411 -345.771165) (xy 441.431521 -345.800656) (xy 441.381901 -345.823315)
			(xy 441.329561 -345.838683) (xy 441.275567 -345.846445) (xy 441.248292 -345.846908) (xy 440.384692 -345.846908)
			(xy 440.357426 -345.846329) (xy 440.30345 -345.838567) (xy 440.251128 -345.823203) (xy 440.201525 -345.800549)
			(xy 440.15565 -345.771067) (xy 440.114438 -345.735356) (xy 440.078728 -345.694143) (xy 440.049247 -345.648268)
			(xy 440.026594 -345.598665) (xy 440.011231 -345.546342) (xy 440.00347 -345.492366) (xy 438.520622 -345.492366)
			(xy 438.520622 -345.492371) (xy 438.51286 -345.546358) (xy 438.497494 -345.598692) (xy 438.474838 -345.648306)
			(xy 438.445351 -345.694191) (xy 438.409635 -345.735412) (xy 438.368416 -345.771132) (xy 438.322534 -345.800622)
			(xy 438.272922 -345.823283) (xy 438.22059 -345.838653) (xy 438.166603 -345.846419) (xy 438.139332 -345.846908)
			(xy 437.275732 -345.846908) (xy 437.248463 -345.846355) (xy 437.194479 -345.838597) (xy 437.142149 -345.823236)
			(xy 437.092538 -345.800583) (xy 437.046655 -345.771099) (xy 437.005436 -345.735386) (xy 436.96972 -345.69417)
			(xy 436.940233 -345.648291) (xy 436.917576 -345.598681) (xy 436.90221 -345.546352) (xy 436.894447 -345.492369)
			(xy 435.411744 -345.492369) (xy 435.411744 -345.492376) (xy 435.403981 -345.546371) (xy 435.388611 -345.598713)
			(xy 435.365949 -345.648334) (xy 435.336455 -345.694224) (xy 435.30073 -345.73545) (xy 435.259502 -345.771172)
			(xy 435.213609 -345.800662) (xy 435.163986 -345.823321) (xy 435.111644 -345.838686) (xy 435.057648 -345.846446)
			(xy 435.030372 -345.846908) (xy 434.166772 -345.846908) (xy 434.139507 -345.846328) (xy 434.085533 -345.838564)
			(xy 434.033213 -345.823198) (xy 433.983613 -345.800543) (xy 433.937741 -345.77106) (xy 433.896531 -345.735349)
			(xy 433.860823 -345.694137) (xy 433.831344 -345.648263) (xy 433.808692 -345.59866) (xy 433.79333 -345.546339)
			(xy 433.78557 -345.492365) (xy 432.302721 -345.492365) (xy 432.302721 -345.492372) (xy 432.294959 -345.546361)
			(xy 432.279593 -345.598696) (xy 432.256935 -345.648311) (xy 432.227446 -345.694197) (xy 432.191728 -345.735419)
			(xy 432.150507 -345.771139) (xy 432.104622 -345.800629) (xy 432.055007 -345.823288) (xy 432.002673 -345.838657)
			(xy 431.948684 -345.846421) (xy 431.921412 -345.846908) (xy 431.057812 -345.846908) (xy 431.030544 -345.846353)
			(xy 430.976562 -345.838594) (xy 430.924234 -345.82323) (xy 430.874626 -345.800576) (xy 430.828746 -345.771092)
			(xy 430.787529 -345.735379) (xy 430.751815 -345.694164) (xy 430.72233 -345.648285) (xy 430.699674 -345.598677)
			(xy 430.684309 -345.54635) (xy 430.676547 -345.492368) (xy 429.193844 -345.492368) (xy 429.193844 -345.492376)
			(xy 429.18608 -345.546374) (xy 429.170709 -345.598717) (xy 429.148046 -345.648339) (xy 429.11855 -345.694231)
			(xy 429.082823 -345.735457) (xy 429.041592 -345.771179) (xy 428.995697 -345.800669) (xy 428.946072 -345.823326)
			(xy 428.893727 -345.83869) (xy 428.839729 -345.846448) (xy 428.812452 -345.846908) (xy 427.948852 -345.846908)
			(xy 427.921588 -345.846326) (xy 427.867616 -345.83856) (xy 427.815299 -345.823192) (xy 427.765701 -345.800536)
			(xy 427.719831 -345.771053) (xy 427.678624 -345.735342) (xy 427.642919 -345.69413) (xy 427.613441 -345.648257)
			(xy 427.590791 -345.598656) (xy 427.57543 -345.546337) (xy 427.56767 -345.492364) (xy 426.084844 -345.492364)
			(xy 426.084844 -345.492375) (xy 426.077081 -345.546369) (xy 426.061713 -345.598708) (xy 426.039052 -345.648328)
			(xy 426.00956 -345.694218) (xy 425.973837 -345.735443) (xy 425.932611 -345.771165) (xy 425.886721 -345.800656)
			(xy 425.837101 -345.823315) (xy 425.784761 -345.838683) (xy 425.730767 -345.846445) (xy 425.703492 -345.846908)
			(xy 424.839892 -345.846908) (xy 424.812626 -345.846329) (xy 424.75865 -345.838567) (xy 424.706328 -345.823203)
			(xy 424.656725 -345.800549) (xy 424.61085 -345.771067) (xy 424.569638 -345.735356) (xy 424.533928 -345.694143)
			(xy 424.504447 -345.648268) (xy 424.481794 -345.598665) (xy 424.466431 -345.546342) (xy 424.45867 -345.492366)
			(xy 422.975822 -345.492366) (xy 422.975822 -345.492371) (xy 422.96806 -345.546358) (xy 422.952694 -345.598692)
			(xy 422.930038 -345.648306) (xy 422.900551 -345.694191) (xy 422.864835 -345.735412) (xy 422.823616 -345.771132)
			(xy 422.777734 -345.800622) (xy 422.728122 -345.823283) (xy 422.67579 -345.838653) (xy 422.621803 -345.846419)
			(xy 422.594532 -345.846908) (xy 421.730932 -345.846908) (xy 421.703663 -345.846355) (xy 421.649679 -345.838597)
			(xy 421.597349 -345.823236) (xy 421.547738 -345.800583) (xy 421.501855 -345.771099) (xy 421.460636 -345.735386)
			(xy 421.42492 -345.69417) (xy 421.395433 -345.648291) (xy 421.372776 -345.598681) (xy 421.35741 -345.546352)
			(xy 421.349647 -345.492369) (xy 419.866944 -345.492369) (xy 419.866944 -345.492376) (xy 419.859181 -345.546371)
			(xy 419.843811 -345.598713) (xy 419.821149 -345.648334) (xy 419.791655 -345.694224) (xy 419.75593 -345.73545)
			(xy 419.714702 -345.771172) (xy 419.668809 -345.800662) (xy 419.619186 -345.823321) (xy 419.566844 -345.838686)
			(xy 419.512848 -345.846446) (xy 419.485572 -345.846908) (xy 418.621972 -345.846908) (xy 418.594707 -345.846328)
			(xy 418.540733 -345.838564) (xy 418.488413 -345.823198) (xy 418.438813 -345.800543) (xy 418.392941 -345.77106)
			(xy 418.351731 -345.735349) (xy 418.316023 -345.694137) (xy 418.286544 -345.648263) (xy 418.263892 -345.59866)
			(xy 418.24853 -345.546339) (xy 418.24077 -345.492365) (xy 416.757921 -345.492365) (xy 416.757921 -345.492372)
			(xy 416.750159 -345.546361) (xy 416.734793 -345.598696) (xy 416.712135 -345.648311) (xy 416.682646 -345.694197)
			(xy 416.646928 -345.735419) (xy 416.605707 -345.771139) (xy 416.559822 -345.800629) (xy 416.510207 -345.823288)
			(xy 416.457873 -345.838657) (xy 416.403884 -345.846421) (xy 416.376612 -345.846908) (xy 415.513012 -345.846908)
			(xy 415.485744 -345.846353) (xy 415.431762 -345.838594) (xy 415.379434 -345.82323) (xy 415.329826 -345.800576)
			(xy 415.283946 -345.771092) (xy 415.242729 -345.735379) (xy 415.207015 -345.694164) (xy 415.17753 -345.648285)
			(xy 415.154874 -345.598677) (xy 415.139509 -345.54635) (xy 415.131747 -345.492368) (xy 413.649044 -345.492368)
			(xy 413.649044 -345.492376) (xy 413.64128 -345.546374) (xy 413.625909 -345.598717) (xy 413.603246 -345.648339)
			(xy 413.57375 -345.694231) (xy 413.538023 -345.735457) (xy 413.496792 -345.771179) (xy 413.450897 -345.800669)
			(xy 413.401272 -345.823326) (xy 413.348927 -345.83869) (xy 413.294929 -345.846448) (xy 413.267652 -345.846908)
			(xy 412.404052 -345.846908) (xy 412.376788 -345.846326) (xy 412.322816 -345.83856) (xy 412.270499 -345.823192)
			(xy 412.220901 -345.800536) (xy 412.175031 -345.771053) (xy 412.133824 -345.735342) (xy 412.098119 -345.69413)
			(xy 412.068641 -345.648257) (xy 412.045991 -345.598656) (xy 412.03063 -345.546337) (xy 412.02287 -345.492364)
			(xy 410.540044 -345.492364) (xy 410.540044 -345.492375) (xy 410.532281 -345.546369) (xy 410.516913 -345.598708)
			(xy 410.494252 -345.648328) (xy 410.46476 -345.694218) (xy 410.429037 -345.735443) (xy 410.387811 -345.771165)
			(xy 410.341921 -345.800656) (xy 410.292301 -345.823315) (xy 410.239961 -345.838683) (xy 410.185967 -345.846445)
			(xy 410.158692 -345.846908) (xy 409.295092 -345.846908) (xy 409.267826 -345.846329) (xy 409.21385 -345.838567)
			(xy 409.161528 -345.823203) (xy 409.111925 -345.800549) (xy 409.06605 -345.771067) (xy 409.024838 -345.735356)
			(xy 408.989128 -345.694143) (xy 408.959647 -345.648268) (xy 408.936994 -345.598665) (xy 408.921631 -345.546342)
			(xy 408.91387 -345.492366) (xy 403.522544 -345.492366) (xy 403.522544 -345.492375) (xy 403.514781 -345.54637)
			(xy 403.499412 -345.598711) (xy 403.47675 -345.648331) (xy 403.447257 -345.694221) (xy 403.411533 -345.735447)
			(xy 403.370305 -345.771169) (xy 403.324414 -345.800659) (xy 403.274792 -345.823319) (xy 403.222451 -345.838685)
			(xy 403.168455 -345.846446) (xy 403.14118 -345.846908) (xy 402.27758 -345.846908) (xy 402.250315 -345.846328)
			(xy 402.19634 -345.838565) (xy 402.144019 -345.8232) (xy 402.094417 -345.800545) (xy 402.048545 -345.771063)
			(xy 402.007334 -345.735352) (xy 401.971625 -345.694139) (xy 401.942145 -345.648265) (xy 401.919493 -345.598662)
			(xy 401.90413 -345.546341) (xy 401.89637 -345.492365) (xy 400.413522 -345.492365) (xy 400.413522 -345.492372)
			(xy 400.405759 -345.54636) (xy 400.390393 -345.598694) (xy 400.367736 -345.648309) (xy 400.338248 -345.694195)
			(xy 400.302531 -345.735417) (xy 400.261311 -345.771136) (xy 400.215427 -345.800626) (xy 400.165813 -345.823286)
			(xy 400.11348 -345.838655) (xy 400.059492 -345.84642) (xy 400.03222 -345.846908) (xy 399.16862 -345.846908)
			(xy 399.141351 -345.846354) (xy 399.087369 -345.838595) (xy 399.03504 -345.823232) (xy 398.98543 -345.800579)
			(xy 398.93955 -345.771095) (xy 398.898332 -345.735382) (xy 398.862617 -345.694166) (xy 398.833131 -345.648287)
			(xy 398.810475 -345.598679) (xy 398.795109 -345.546351) (xy 398.787347 -345.492369) (xy 397.304644 -345.492369)
			(xy 397.304644 -345.492376) (xy 397.29688 -345.546373) (xy 397.28151 -345.598715) (xy 397.258847 -345.648337)
			(xy 397.229352 -345.694228) (xy 397.193626 -345.735454) (xy 397.152396 -345.771176) (xy 397.106502 -345.800666)
			(xy 397.056878 -345.823324) (xy 397.004534 -345.838689) (xy 396.950536 -345.846447) (xy 396.92326 -345.846908)
			(xy 396.05966 -345.846908) (xy 396.032396 -345.846327) (xy 395.978423 -345.838562) (xy 395.926105 -345.823195)
			(xy 395.876505 -345.800539) (xy 395.830635 -345.771055) (xy 395.789427 -345.735345) (xy 395.753721 -345.694133)
			(xy 395.724242 -345.648259) (xy 395.701591 -345.598658) (xy 395.68623 -345.546338) (xy 395.67847 -345.492364)
			(xy 394.195621 -345.492364) (xy 394.195621 -345.492373) (xy 394.187859 -345.546363) (xy 394.172492 -345.598699)
			(xy 394.149833 -345.648315) (xy 394.120343 -345.694201) (xy 394.084624 -345.735424) (xy 394.043401 -345.771143)
			(xy 393.997515 -345.800633) (xy 393.947899 -345.823292) (xy 393.895563 -345.838659) (xy 393.841573 -345.846421)
			(xy 393.8143 -345.846908) (xy 392.9507 -345.846908) (xy 392.923434 -345.84633) (xy 392.869457 -345.838569)
			(xy 392.817134 -345.823205) (xy 392.767529 -345.800552) (xy 392.721654 -345.77107) (xy 392.680441 -345.735359)
			(xy 392.64473 -345.694146) (xy 392.615248 -345.648271) (xy 392.592595 -345.598666) (xy 392.577231 -345.546343)
			(xy 392.56947 -345.492366) (xy 391.086622 -345.492366) (xy 391.086622 -345.492371) (xy 391.07886 -345.546357)
			(xy 391.063495 -345.59869) (xy 391.040839 -345.648304) (xy 391.011353 -345.694188) (xy 390.975638 -345.73541)
			(xy 390.93442 -345.771129) (xy 390.888539 -345.80062) (xy 390.838928 -345.823281) (xy 390.786597 -345.838651)
			(xy 390.732611 -345.846419) (xy 390.70534 -345.846908) (xy 389.84174 -345.846908) (xy 389.81447 -345.846355)
			(xy 389.760486 -345.838599) (xy 389.708155 -345.823238) (xy 389.658542 -345.800585) (xy 389.612659 -345.771102)
			(xy 389.571439 -345.735389) (xy 389.535722 -345.694173) (xy 389.506234 -345.648293) (xy 389.483576 -345.598683)
			(xy 389.46821 -345.546353) (xy 389.460447 -345.49237) (xy 387.977744 -345.49237) (xy 387.977744 -345.492375)
			(xy 387.969981 -345.54637) (xy 387.954612 -345.598711) (xy 387.93195 -345.648331) (xy 387.902457 -345.694221)
			(xy 387.866733 -345.735447) (xy 387.825505 -345.771169) (xy 387.779614 -345.800659) (xy 387.729992 -345.823319)
			(xy 387.677651 -345.838685) (xy 387.623655 -345.846446) (xy 387.59638 -345.846908) (xy 386.73278 -345.846908)
			(xy 386.705515 -345.846328) (xy 386.65154 -345.838565) (xy 386.599219 -345.8232) (xy 386.549617 -345.800545)
			(xy 386.503745 -345.771063) (xy 386.462534 -345.735352) (xy 386.426825 -345.694139) (xy 386.397345 -345.648265)
			(xy 386.374693 -345.598662) (xy 386.35933 -345.546341) (xy 386.35157 -345.492365) (xy 384.868722 -345.492365)
			(xy 384.868722 -345.492372) (xy 384.860959 -345.54636) (xy 384.845593 -345.598694) (xy 384.822936 -345.648309)
			(xy 384.793448 -345.694195) (xy 384.757731 -345.735417) (xy 384.716511 -345.771136) (xy 384.670627 -345.800626)
			(xy 384.621013 -345.823286) (xy 384.56868 -345.838655) (xy 384.514692 -345.84642) (xy 384.48742 -345.846908)
			(xy 383.62382 -345.846908) (xy 383.596551 -345.846354) (xy 383.542569 -345.838595) (xy 383.49024 -345.823232)
			(xy 383.44063 -345.800579) (xy 383.39475 -345.771095) (xy 383.353532 -345.735382) (xy 383.317817 -345.694166)
			(xy 383.288331 -345.648287) (xy 383.265675 -345.598679) (xy 383.250309 -345.546351) (xy 383.242547 -345.492369)
			(xy 381.759844 -345.492369) (xy 381.759844 -345.492376) (xy 381.75208 -345.546373) (xy 381.73671 -345.598715)
			(xy 381.714047 -345.648337) (xy 381.684552 -345.694228) (xy 381.648826 -345.735454) (xy 381.607596 -345.771176)
			(xy 381.561702 -345.800666) (xy 381.512078 -345.823324) (xy 381.459734 -345.838689) (xy 381.405736 -345.846447)
			(xy 381.37846 -345.846908) (xy 380.51486 -345.846908) (xy 380.487596 -345.846327) (xy 380.433623 -345.838562)
			(xy 380.381305 -345.823195) (xy 380.331705 -345.800539) (xy 380.285835 -345.771055) (xy 380.244627 -345.735345)
			(xy 380.208921 -345.694133) (xy 380.179442 -345.648259) (xy 380.156791 -345.598658) (xy 380.14143 -345.546338)
			(xy 380.13367 -345.492364) (xy 378.650821 -345.492364) (xy 378.650821 -345.492373) (xy 378.643059 -345.546363)
			(xy 378.627692 -345.598699) (xy 378.605033 -345.648315) (xy 378.575543 -345.694201) (xy 378.539824 -345.735424)
			(xy 378.498601 -345.771143) (xy 378.452715 -345.800633) (xy 378.403099 -345.823292) (xy 378.350763 -345.838659)
			(xy 378.296773 -345.846421) (xy 378.2695 -345.846908) (xy 377.4059 -345.846908) (xy 377.378634 -345.84633)
			(xy 377.324657 -345.838569) (xy 377.272334 -345.823205) (xy 377.222729 -345.800552) (xy 377.176854 -345.77107)
			(xy 377.135641 -345.735359) (xy 377.09993 -345.694146) (xy 377.070448 -345.648271) (xy 377.047795 -345.598666)
			(xy 377.032431 -345.546343) (xy 377.02467 -345.492366) (xy 375.541822 -345.492366) (xy 375.541822 -345.492371)
			(xy 375.53406 -345.546357) (xy 375.518695 -345.59869) (xy 375.496039 -345.648304) (xy 375.466553 -345.694188)
			(xy 375.430838 -345.73541) (xy 375.38962 -345.771129) (xy 375.343739 -345.80062) (xy 375.294128 -345.823281)
			(xy 375.241797 -345.838651) (xy 375.187811 -345.846419) (xy 375.16054 -345.846908) (xy 374.29694 -345.846908)
			(xy 374.26967 -345.846355) (xy 374.215686 -345.838599) (xy 374.163355 -345.823238) (xy 374.113742 -345.800585)
			(xy 374.067859 -345.771102) (xy 374.026639 -345.735389) (xy 373.990922 -345.694173) (xy 373.961434 -345.648293)
			(xy 373.938776 -345.598683) (xy 373.92341 -345.546353) (xy 373.915647 -345.49237) (xy 372.432944 -345.49237)
			(xy 372.432944 -345.492375) (xy 372.425181 -345.54637) (xy 372.409812 -345.598711) (xy 372.38715 -345.648331)
			(xy 372.357657 -345.694221) (xy 372.321933 -345.735447) (xy 372.280705 -345.771169) (xy 372.234814 -345.800659)
			(xy 372.185192 -345.823319) (xy 372.132851 -345.838685) (xy 372.078855 -345.846446) (xy 372.05158 -345.846908)
			(xy 371.18798 -345.846908) (xy 371.160715 -345.846328) (xy 371.10674 -345.838565) (xy 371.054419 -345.8232)
			(xy 371.004817 -345.800545) (xy 370.958945 -345.771063) (xy 370.917734 -345.735352) (xy 370.882025 -345.694139)
			(xy 370.852545 -345.648265) (xy 370.829893 -345.598662) (xy 370.81453 -345.546341) (xy 370.80677 -345.492365)
			(xy 344.837321 -345.492365) (xy 344.837321 -345.492372) (xy 344.829559 -345.546362) (xy 344.814192 -345.598698)
			(xy 344.791533 -345.648314) (xy 344.762044 -345.6942) (xy 344.726325 -345.735422) (xy 344.685103 -345.771142)
			(xy 344.639217 -345.800631) (xy 344.589601 -345.823291) (xy 344.537266 -345.838658) (xy 344.483276 -345.846421)
			(xy 344.456004 -345.846908) (xy 343.592404 -345.846908) (xy 343.565136 -345.846353) (xy 343.511155 -345.838592)
			(xy 343.458828 -345.823228) (xy 343.409221 -345.800573) (xy 343.363342 -345.771089) (xy 343.322126 -345.735376)
			(xy 343.286413 -345.694161) (xy 343.256928 -345.648283) (xy 343.234273 -345.598675) (xy 343.218909 -345.546349)
			(xy 343.211147 -345.492368) (xy 341.728322 -345.492368) (xy 341.728322 -345.492371) (xy 341.72056 -345.546357)
			(xy 341.705195 -345.598689) (xy 341.682539 -345.648302) (xy 341.653054 -345.694187) (xy 341.617339 -345.735408)
			(xy 341.576122 -345.771128) (xy 341.530241 -345.800618) (xy 341.48063 -345.82328) (xy 341.4283 -345.838651)
			(xy 341.374315 -345.846418) (xy 341.347044 -345.846908) (xy 340.483444 -345.846908) (xy 340.456174 -345.846356)
			(xy 340.402189 -345.8386) (xy 340.349857 -345.823239) (xy 340.300245 -345.800587) (xy 340.254361 -345.771104)
			(xy 340.213141 -345.735391) (xy 340.177423 -345.694174) (xy 340.147935 -345.648294) (xy 340.125276 -345.598684)
			(xy 340.10991 -345.546354) (xy 340.102148 -345.49237) (xy 338.619444 -345.49237) (xy 338.619444 -345.492375)
			(xy 338.611681 -345.54637) (xy 338.596312 -345.59871) (xy 338.57365 -345.64833) (xy 338.544158 -345.69422)
			(xy 338.508434 -345.735446) (xy 338.467207 -345.771167) (xy 338.421316 -345.800658) (xy 338.371695 -345.823318)
			(xy 338.319354 -345.838684) (xy 338.265359 -345.846445) (xy 338.238084 -345.846908) (xy 337.374484 -345.846908)
			(xy 337.347219 -345.846329) (xy 337.293243 -345.838566) (xy 337.240922 -345.823201) (xy 337.19132 -345.800547)
			(xy 337.145446 -345.771064) (xy 337.104236 -345.735353) (xy 337.068526 -345.694141) (xy 337.039046 -345.648266)
			(xy 337.016393 -345.598663) (xy 337.001031 -345.546341) (xy 336.99327 -345.492365) (xy 335.510422 -345.492365)
			(xy 335.510422 -345.492372) (xy 335.50266 -345.54636) (xy 335.487294 -345.598693) (xy 335.464636 -345.648308)
			(xy 335.435149 -345.694193) (xy 335.399432 -345.735415) (xy 335.358213 -345.771135) (xy 335.312329 -345.800625)
			(xy 335.262716 -345.823285) (xy 335.210383 -345.838654) (xy 335.156396 -345.84642) (xy 335.129124 -345.846908)
			(xy 334.265524 -345.846908) (xy 334.238255 -345.846354) (xy 334.184272 -345.838596) (xy 334.131943 -345.823234)
			(xy 334.082333 -345.80058) (xy 334.036452 -345.771097) (xy 333.995234 -345.735383) (xy 333.959518 -345.694168)
			(xy 333.930031 -345.648288) (xy 333.907375 -345.59868) (xy 333.892009 -345.546351) (xy 333.884247 -345.492369)
			(xy 332.401544 -345.492369) (xy 332.401544 -345.492376) (xy 332.39378 -345.546372) (xy 332.37841 -345.598714)
			(xy 332.355747 -345.648336) (xy 332.326253 -345.694227) (xy 332.290527 -345.735453) (xy 332.249298 -345.771174)
			(xy 332.203404 -345.800665) (xy 332.153781 -345.823323) (xy 332.101437 -345.838688) (xy 332.04744 -345.846447)
			(xy 332.020164 -345.846908) (xy 331.156564 -345.846908) (xy 331.1293 -345.846327) (xy 331.075326 -345.838562)
			(xy 331.023007 -345.823196) (xy 330.973408 -345.80054) (xy 330.927537 -345.771057) (xy 330.886329 -345.735346)
			(xy 330.850622 -345.694134) (xy 330.821143 -345.648261) (xy 330.798492 -345.598659) (xy 330.78313 -345.546338)
			(xy 330.77537 -345.492364) (xy 329.292521 -345.492364) (xy 329.292521 -345.492372) (xy 329.284759 -345.546362)
			(xy 329.269392 -345.598698) (xy 329.246733 -345.648314) (xy 329.217244 -345.6942) (xy 329.181525 -345.735422)
			(xy 329.140303 -345.771142) (xy 329.094417 -345.800631) (xy 329.044801 -345.823291) (xy 328.992466 -345.838658)
			(xy 328.938476 -345.846421) (xy 328.911204 -345.846908) (xy 328.047604 -345.846908) (xy 328.020336 -345.846353)
			(xy 327.966355 -345.838592) (xy 327.914028 -345.823228) (xy 327.864421 -345.800573) (xy 327.818542 -345.771089)
			(xy 327.777326 -345.735376) (xy 327.741613 -345.694161) (xy 327.712128 -345.648283) (xy 327.689473 -345.598675)
			(xy 327.674109 -345.546349) (xy 327.666347 -345.492368) (xy 326.183522 -345.492368) (xy 326.183522 -345.492371)
			(xy 326.17576 -345.546357) (xy 326.160395 -345.598689) (xy 326.137739 -345.648302) (xy 326.108254 -345.694187)
			(xy 326.072539 -345.735408) (xy 326.031322 -345.771128) (xy 325.985441 -345.800618) (xy 325.93583 -345.82328)
			(xy 325.8835 -345.838651) (xy 325.829515 -345.846418) (xy 325.802244 -345.846908) (xy 324.938644 -345.846908)
			(xy 324.911374 -345.846356) (xy 324.857389 -345.8386) (xy 324.805057 -345.823239) (xy 324.755445 -345.800587)
			(xy 324.709561 -345.771104) (xy 324.668341 -345.735391) (xy 324.632623 -345.694174) (xy 324.603135 -345.648294)
			(xy 324.580476 -345.598684) (xy 324.56511 -345.546354) (xy 324.557348 -345.49237) (xy 323.074644 -345.49237)
			(xy 323.074644 -345.492375) (xy 323.066881 -345.54637) (xy 323.051512 -345.59871) (xy 323.02885 -345.64833)
			(xy 322.999358 -345.69422) (xy 322.963634 -345.735446) (xy 322.922407 -345.771167) (xy 322.876516 -345.800658)
			(xy 322.826895 -345.823318) (xy 322.774554 -345.838684) (xy 322.720559 -345.846445) (xy 322.693284 -345.846908)
			(xy 321.829684 -345.846908) (xy 321.802419 -345.846329) (xy 321.748443 -345.838566) (xy 321.696122 -345.823201)
			(xy 321.64652 -345.800547) (xy 321.600646 -345.771064) (xy 321.559436 -345.735353) (xy 321.523726 -345.694141)
			(xy 321.494246 -345.648266) (xy 321.471593 -345.598663) (xy 321.456231 -345.546341) (xy 321.44847 -345.492365)
			(xy 319.965622 -345.492365) (xy 319.965622 -345.492372) (xy 319.95786 -345.54636) (xy 319.942494 -345.598693)
			(xy 319.919836 -345.648308) (xy 319.890349 -345.694193) (xy 319.854632 -345.735415) (xy 319.813413 -345.771135)
			(xy 319.767529 -345.800625) (xy 319.717916 -345.823285) (xy 319.665583 -345.838654) (xy 319.611596 -345.84642)
			(xy 319.584324 -345.846908) (xy 318.720724 -345.846908) (xy 318.693455 -345.846354) (xy 318.639472 -345.838596)
			(xy 318.587143 -345.823234) (xy 318.537533 -345.80058) (xy 318.491652 -345.771097) (xy 318.450434 -345.735383)
			(xy 318.414718 -345.694168) (xy 318.385231 -345.648288) (xy 318.362575 -345.59868) (xy 318.347209 -345.546351)
			(xy 318.339447 -345.492369) (xy 316.856744 -345.492369) (xy 316.856744 -345.492376) (xy 316.84898 -345.546372)
			(xy 316.83361 -345.598714) (xy 316.810947 -345.648336) (xy 316.781453 -345.694227) (xy 316.745727 -345.735453)
			(xy 316.704498 -345.771174) (xy 316.658604 -345.800665) (xy 316.608981 -345.823323) (xy 316.556637 -345.838688)
			(xy 316.50264 -345.846447) (xy 316.475364 -345.846908) (xy 315.611764 -345.846908) (xy 315.5845 -345.846327)
			(xy 315.530526 -345.838562) (xy 315.478207 -345.823196) (xy 315.428608 -345.80054) (xy 315.382737 -345.771057)
			(xy 315.341529 -345.735346) (xy 315.305822 -345.694134) (xy 315.276343 -345.648261) (xy 315.253692 -345.598659)
			(xy 315.23833 -345.546338) (xy 315.23057 -345.492364) (xy 313.747721 -345.492364) (xy 313.747721 -345.492372)
			(xy 313.739959 -345.546362) (xy 313.724592 -345.598698) (xy 313.701933 -345.648314) (xy 313.672444 -345.6942)
			(xy 313.636725 -345.735422) (xy 313.595503 -345.771142) (xy 313.549617 -345.800631) (xy 313.500001 -345.823291)
			(xy 313.447666 -345.838658) (xy 313.393676 -345.846421) (xy 313.366404 -345.846908) (xy 312.502804 -345.846908)
			(xy 312.475536 -345.846353) (xy 312.421555 -345.838592) (xy 312.369228 -345.823228) (xy 312.319621 -345.800573)
			(xy 312.273742 -345.771089) (xy 312.232526 -345.735376) (xy 312.196813 -345.694161) (xy 312.167328 -345.648283)
			(xy 312.144673 -345.598675) (xy 312.129309 -345.546349) (xy 312.121547 -345.492368) (xy 300.231621 -345.492368)
			(xy 300.231621 -345.492373) (xy 300.223859 -345.546362) (xy 300.208492 -345.598698) (xy 300.185833 -345.648314)
			(xy 300.156344 -345.6942) (xy 300.120624 -345.735423) (xy 300.079402 -345.771143) (xy 300.033516 -345.800632)
			(xy 299.9839 -345.823291) (xy 299.931564 -345.838658) (xy 299.877575 -345.846421) (xy 299.850302 -345.846908)
			(xy 298.986702 -345.846908) (xy 298.959434 -345.846353) (xy 298.905454 -345.838592) (xy 298.853127 -345.823228)
			(xy 298.80352 -345.800573) (xy 298.757641 -345.771089) (xy 298.716426 -345.735376) (xy 298.680712 -345.69416)
			(xy 298.651228 -345.648282) (xy 298.628573 -345.598675) (xy 298.613209 -345.546348) (xy 298.605447 -345.492368)
			(xy 297.122622 -345.492368) (xy 297.122622 -345.492371) (xy 297.11486 -345.546357) (xy 297.099495 -345.59869)
			(xy 297.076839 -345.648303) (xy 297.047354 -345.694187) (xy 297.011639 -345.735409) (xy 296.970421 -345.771128)
			(xy 296.92454 -345.800619) (xy 296.874929 -345.82328) (xy 296.822598 -345.838651) (xy 296.768613 -345.846419)
			(xy 296.741342 -345.846908) (xy 295.877742 -345.846908) (xy 295.850472 -345.846355) (xy 295.796487 -345.838599)
			(xy 295.744156 -345.823238) (xy 295.694543 -345.800586) (xy 295.64866 -345.771103) (xy 295.60744 -345.73539)
			(xy 295.571722 -345.694174) (xy 295.542234 -345.648293) (xy 295.519576 -345.598683) (xy 295.50421 -345.546354)
			(xy 295.496448 -345.49237) (xy 294.013744 -345.49237) (xy 294.013744 -345.492375) (xy 294.005981 -345.54637)
			(xy 293.990612 -345.59871) (xy 293.96795 -345.648331) (xy 293.938457 -345.694221) (xy 293.902734 -345.735446)
			(xy 293.861506 -345.771168) (xy 293.815615 -345.800659) (xy 293.765994 -345.823318) (xy 293.713652 -345.838685)
			(xy 293.659657 -345.846446) (xy 293.632382 -345.846908) (xy 292.768782 -345.846908) (xy 292.741517 -345.846328)
			(xy 292.687542 -345.838566) (xy 292.635221 -345.823201) (xy 292.585619 -345.800546) (xy 292.539745 -345.771063)
			(xy 292.498535 -345.735352) (xy 292.462826 -345.69414) (xy 292.433345 -345.648266) (xy 292.410693 -345.598663)
			(xy 292.395331 -345.546341) (xy 292.38757 -345.492365) (xy 290.904722 -345.492365) (xy 290.904722 -345.492372)
			(xy 290.896959 -345.54636) (xy 290.881593 -345.598694) (xy 290.858936 -345.648309) (xy 290.829449 -345.694194)
			(xy 290.793732 -345.735416) (xy 290.752512 -345.771136) (xy 290.706628 -345.800626) (xy 290.657015 -345.823286)
			(xy 290.604681 -345.838655) (xy 290.550694 -345.84642) (xy 290.523422 -345.846908) (xy 289.659822 -345.846908)
			(xy 289.632553 -345.846354) (xy 289.57857 -345.838595) (xy 289.526241 -345.823233) (xy 289.476632 -345.800579)
			(xy 289.430751 -345.771096) (xy 289.389533 -345.735383) (xy 289.353817 -345.694167) (xy 289.324331 -345.648288)
			(xy 289.301675 -345.598679) (xy 289.286309 -345.546351) (xy 289.278547 -345.492369) (xy 287.795844 -345.492369)
			(xy 287.795844 -345.492376) (xy 287.78808 -345.546373) (xy 287.77271 -345.598715) (xy 287.750047 -345.648336)
			(xy 287.720552 -345.694227) (xy 287.684827 -345.735453) (xy 287.643597 -345.771175) (xy 287.597703 -345.800665)
			(xy 287.548079 -345.823323) (xy 287.495736 -345.838688) (xy 287.441738 -345.846447) (xy 287.414462 -345.846908)
			(xy 286.550862 -345.846908) (xy 286.523598 -345.846327) (xy 286.469625 -345.838562) (xy 286.417306 -345.823195)
			(xy 286.367707 -345.80054) (xy 286.321836 -345.771056) (xy 286.280628 -345.735345) (xy 286.244921 -345.694134)
			(xy 286.215442 -345.64826) (xy 286.192792 -345.598658) (xy 286.17743 -345.546338) (xy 286.16967 -345.492364)
			(xy 284.686821 -345.492364) (xy 284.686821 -345.492373) (xy 284.679059 -345.546362) (xy 284.663692 -345.598698)
			(xy 284.641033 -345.648314) (xy 284.611544 -345.6942) (xy 284.575824 -345.735423) (xy 284.534602 -345.771143)
			(xy 284.488716 -345.800632) (xy 284.4391 -345.823291) (xy 284.386764 -345.838658) (xy 284.332775 -345.846421)
			(xy 284.305502 -345.846908) (xy 283.441902 -345.846908) (xy 283.414634 -345.846353) (xy 283.360654 -345.838592)
			(xy 283.308327 -345.823228) (xy 283.25872 -345.800573) (xy 283.212841 -345.771089) (xy 283.171626 -345.735376)
			(xy 283.135912 -345.69416) (xy 283.106428 -345.648282) (xy 283.083773 -345.598675) (xy 283.068409 -345.546348)
			(xy 283.060647 -345.492368) (xy 281.577822 -345.492368) (xy 281.577822 -345.492371) (xy 281.57006 -345.546357)
			(xy 281.554695 -345.59869) (xy 281.532039 -345.648303) (xy 281.502554 -345.694187) (xy 281.466839 -345.735409)
			(xy 281.425621 -345.771128) (xy 281.37974 -345.800619) (xy 281.330129 -345.82328) (xy 281.277798 -345.838651)
			(xy 281.223813 -345.846419) (xy 281.196542 -345.846908) (xy 280.332942 -345.846908) (xy 280.305672 -345.846355)
			(xy 280.251687 -345.838599) (xy 280.199356 -345.823238) (xy 280.149743 -345.800586) (xy 280.10386 -345.771103)
			(xy 280.06264 -345.73539) (xy 280.026922 -345.694174) (xy 279.997434 -345.648293) (xy 279.974776 -345.598683)
			(xy 279.95941 -345.546354) (xy 279.951648 -345.49237) (xy 278.468944 -345.49237) (xy 278.468944 -345.492375)
			(xy 278.461181 -345.54637) (xy 278.445812 -345.59871) (xy 278.42315 -345.648331) (xy 278.393657 -345.694221)
			(xy 278.357934 -345.735446) (xy 278.316706 -345.771168) (xy 278.270815 -345.800659) (xy 278.221194 -345.823318)
			(xy 278.168852 -345.838685) (xy 278.114857 -345.846446) (xy 278.087582 -345.846908) (xy 277.223982 -345.846908)
			(xy 277.196717 -345.846328) (xy 277.142742 -345.838566) (xy 277.090421 -345.823201) (xy 277.040819 -345.800546)
			(xy 276.994945 -345.771063) (xy 276.953735 -345.735352) (xy 276.918026 -345.69414) (xy 276.888545 -345.648266)
			(xy 276.865893 -345.598663) (xy 276.850531 -345.546341) (xy 276.84277 -345.492365) (xy 275.359922 -345.492365)
			(xy 275.359922 -345.492372) (xy 275.352159 -345.54636) (xy 275.336793 -345.598694) (xy 275.314136 -345.648309)
			(xy 275.284649 -345.694194) (xy 275.248932 -345.735416) (xy 275.207712 -345.771136) (xy 275.161828 -345.800626)
			(xy 275.112215 -345.823286) (xy 275.059881 -345.838655) (xy 275.005894 -345.84642) (xy 274.978622 -345.846908)
			(xy 274.115022 -345.846908) (xy 274.087753 -345.846354) (xy 274.03377 -345.838595) (xy 273.981441 -345.823233)
			(xy 273.931832 -345.800579) (xy 273.885951 -345.771096) (xy 273.844733 -345.735383) (xy 273.809017 -345.694167)
			(xy 273.779531 -345.648288) (xy 273.756875 -345.598679) (xy 273.741509 -345.546351) (xy 273.733747 -345.492369)
			(xy 272.251044 -345.492369) (xy 272.251044 -345.492376) (xy 272.24328 -345.546373) (xy 272.22791 -345.598715)
			(xy 272.205247 -345.648336) (xy 272.175752 -345.694227) (xy 272.140027 -345.735453) (xy 272.098797 -345.771175)
			(xy 272.052903 -345.800665) (xy 272.003279 -345.823323) (xy 271.950936 -345.838688) (xy 271.896938 -345.846447)
			(xy 271.869662 -345.846908) (xy 271.006062 -345.846908) (xy 270.978798 -345.846327) (xy 270.924825 -345.838562)
			(xy 270.872506 -345.823195) (xy 270.822907 -345.80054) (xy 270.777036 -345.771056) (xy 270.735828 -345.735345)
			(xy 270.700121 -345.694134) (xy 270.670642 -345.64826) (xy 270.647992 -345.598658) (xy 270.63263 -345.546338)
			(xy 270.62487 -345.492364) (xy 269.142021 -345.492364) (xy 269.142021 -345.492373) (xy 269.134259 -345.546362)
			(xy 269.118892 -345.598698) (xy 269.096233 -345.648314) (xy 269.066744 -345.6942) (xy 269.031024 -345.735423)
			(xy 268.989802 -345.771143) (xy 268.943916 -345.800632) (xy 268.8943 -345.823291) (xy 268.841964 -345.838658)
			(xy 268.787975 -345.846421) (xy 268.760702 -345.846908) (xy 267.897102 -345.846908) (xy 267.869834 -345.846353)
			(xy 267.815854 -345.838592) (xy 267.763527 -345.823228) (xy 267.71392 -345.800573) (xy 267.668041 -345.771089)
			(xy 267.626826 -345.735376) (xy 267.591112 -345.69416) (xy 267.561628 -345.648282) (xy 267.538973 -345.598675)
			(xy 267.523609 -345.546348) (xy 267.515847 -345.492368) (xy 197.629644 -345.492368) (xy 197.629644 -345.492376)
			(xy 197.621881 -345.546371) (xy 197.606511 -345.598713) (xy 197.583849 -345.648334) (xy 197.554355 -345.694224)
			(xy 197.51863 -345.73545) (xy 197.477402 -345.771172) (xy 197.431509 -345.800662) (xy 197.381886 -345.823321)
			(xy 197.329544 -345.838686) (xy 197.275548 -345.846446) (xy 197.248272 -345.846908) (xy 196.384672 -345.846908)
			(xy 196.357407 -345.846328) (xy 196.303433 -345.838564) (xy 196.251113 -345.823198) (xy 196.201513 -345.800543)
			(xy 196.155641 -345.77106) (xy 196.114431 -345.735349) (xy 196.078723 -345.694137) (xy 196.049244 -345.648263)
			(xy 196.026592 -345.59866) (xy 196.01123 -345.546339) (xy 196.00347 -345.492365) (xy 194.520621 -345.492365)
			(xy 194.520621 -345.492372) (xy 194.512859 -345.546361) (xy 194.497493 -345.598696) (xy 194.474835 -345.648311)
			(xy 194.445346 -345.694197) (xy 194.409628 -345.735419) (xy 194.368407 -345.771139) (xy 194.322522 -345.800629)
			(xy 194.272907 -345.823288) (xy 194.220573 -345.838657) (xy 194.166584 -345.846421) (xy 194.139312 -345.846908)
			(xy 193.275712 -345.846908) (xy 193.248444 -345.846353) (xy 193.194462 -345.838594) (xy 193.142134 -345.82323)
			(xy 193.092526 -345.800576) (xy 193.046646 -345.771092) (xy 193.005429 -345.735379) (xy 192.969715 -345.694164)
			(xy 192.94023 -345.648285) (xy 192.917574 -345.598677) (xy 192.902209 -345.54635) (xy 192.894447 -345.492368)
			(xy 191.411744 -345.492368) (xy 191.411744 -345.492376) (xy 191.40398 -345.546374) (xy 191.388609 -345.598717)
			(xy 191.365946 -345.648339) (xy 191.33645 -345.694231) (xy 191.300723 -345.735457) (xy 191.259492 -345.771179)
			(xy 191.213597 -345.800669) (xy 191.163972 -345.823326) (xy 191.111627 -345.83869) (xy 191.057629 -345.846448)
			(xy 191.030352 -345.846908) (xy 190.166752 -345.846908) (xy 190.139488 -345.846326) (xy 190.085516 -345.83856)
			(xy 190.033199 -345.823192) (xy 189.983601 -345.800536) (xy 189.937731 -345.771053) (xy 189.896524 -345.735342)
			(xy 189.860819 -345.69413) (xy 189.831341 -345.648257) (xy 189.808691 -345.598656) (xy 189.79333 -345.546337)
			(xy 189.78557 -345.492364) (xy 188.302744 -345.492364) (xy 188.302744 -345.492375) (xy 188.294981 -345.546369)
			(xy 188.279613 -345.598708) (xy 188.256952 -345.648328) (xy 188.22746 -345.694218) (xy 188.191737 -345.735443)
			(xy 188.150511 -345.771165) (xy 188.104621 -345.800656) (xy 188.055001 -345.823315) (xy 188.002661 -345.838683)
			(xy 187.948667 -345.846445) (xy 187.921392 -345.846908) (xy 187.057792 -345.846908) (xy 187.030526 -345.846329)
			(xy 186.97655 -345.838567) (xy 186.924228 -345.823203) (xy 186.874625 -345.800549) (xy 186.82875 -345.771067)
			(xy 186.787538 -345.735356) (xy 186.751828 -345.694143) (xy 186.722347 -345.648268) (xy 186.699694 -345.598665)
			(xy 186.684331 -345.546342) (xy 186.67657 -345.492366) (xy 185.193722 -345.492366) (xy 185.193722 -345.492371)
			(xy 185.18596 -345.546358) (xy 185.170594 -345.598692) (xy 185.147938 -345.648306) (xy 185.118451 -345.694191)
			(xy 185.082735 -345.735412) (xy 185.041516 -345.771132) (xy 184.995634 -345.800622) (xy 184.946022 -345.823283)
			(xy 184.89369 -345.838653) (xy 184.839703 -345.846419) (xy 184.812432 -345.846908) (xy 183.948832 -345.846908)
			(xy 183.921563 -345.846355) (xy 183.867579 -345.838597) (xy 183.815249 -345.823236) (xy 183.765638 -345.800583)
			(xy 183.719755 -345.771099) (xy 183.678536 -345.735386) (xy 183.64282 -345.69417) (xy 183.613333 -345.648291)
			(xy 183.590676 -345.598681) (xy 183.57531 -345.546352) (xy 183.567547 -345.492369) (xy 182.084844 -345.492369)
			(xy 182.084844 -345.492376) (xy 182.077081 -345.546371) (xy 182.061711 -345.598713) (xy 182.039049 -345.648334)
			(xy 182.009555 -345.694224) (xy 181.97383 -345.73545) (xy 181.932602 -345.771172) (xy 181.886709 -345.800662)
			(xy 181.837086 -345.823321) (xy 181.784744 -345.838686) (xy 181.730748 -345.846446) (xy 181.703472 -345.846908)
			(xy 180.839872 -345.846908) (xy 180.812607 -345.846328) (xy 180.758633 -345.838564) (xy 180.706313 -345.823198)
			(xy 180.656713 -345.800543) (xy 180.610841 -345.77106) (xy 180.569631 -345.735349) (xy 180.533923 -345.694137)
			(xy 180.504444 -345.648263) (xy 180.481792 -345.59866) (xy 180.46643 -345.546339) (xy 180.45867 -345.492365)
			(xy 178.975821 -345.492365) (xy 178.975821 -345.492372) (xy 178.968059 -345.546361) (xy 178.952693 -345.598696)
			(xy 178.930035 -345.648311) (xy 178.900546 -345.694197) (xy 178.864828 -345.735419) (xy 178.823607 -345.771139)
			(xy 178.777722 -345.800629) (xy 178.728107 -345.823288) (xy 178.675773 -345.838657) (xy 178.621784 -345.846421)
			(xy 178.594512 -345.846908) (xy 177.730912 -345.846908) (xy 177.703644 -345.846353) (xy 177.649662 -345.838594)
			(xy 177.597334 -345.82323) (xy 177.547726 -345.800576) (xy 177.501846 -345.771092) (xy 177.460629 -345.735379)
			(xy 177.424915 -345.694164) (xy 177.39543 -345.648285) (xy 177.372774 -345.598677) (xy 177.357409 -345.54635)
			(xy 177.349647 -345.492368) (xy 175.866944 -345.492368) (xy 175.866944 -345.492376) (xy 175.85918 -345.546374)
			(xy 175.843809 -345.598717) (xy 175.821146 -345.648339) (xy 175.79165 -345.694231) (xy 175.755923 -345.735457)
			(xy 175.714692 -345.771179) (xy 175.668797 -345.800669) (xy 175.619172 -345.823326) (xy 175.566827 -345.83869)
			(xy 175.512829 -345.846448) (xy 175.485552 -345.846908) (xy 174.621952 -345.846908) (xy 174.594688 -345.846326)
			(xy 174.540716 -345.83856) (xy 174.488399 -345.823192) (xy 174.438801 -345.800536) (xy 174.392931 -345.771053)
			(xy 174.351724 -345.735342) (xy 174.316019 -345.69413) (xy 174.286541 -345.648257) (xy 174.263891 -345.598656)
			(xy 174.24853 -345.546337) (xy 174.24077 -345.492364) (xy 172.757944 -345.492364) (xy 172.757944 -345.492375)
			(xy 172.750181 -345.546369) (xy 172.734813 -345.598708) (xy 172.712152 -345.648328) (xy 172.68266 -345.694218)
			(xy 172.646937 -345.735443) (xy 172.605711 -345.771165) (xy 172.559821 -345.800656) (xy 172.510201 -345.823315)
			(xy 172.457861 -345.838683) (xy 172.403867 -345.846445) (xy 172.376592 -345.846908) (xy 171.512992 -345.846908)
			(xy 171.485726 -345.846329) (xy 171.43175 -345.838567) (xy 171.379428 -345.823203) (xy 171.329825 -345.800549)
			(xy 171.28395 -345.771067) (xy 171.242738 -345.735356) (xy 171.207028 -345.694143) (xy 171.177547 -345.648268)
			(xy 171.154894 -345.598665) (xy 171.139531 -345.546342) (xy 171.13177 -345.492366) (xy 169.648922 -345.492366)
			(xy 169.648922 -345.492371) (xy 169.64116 -345.546358) (xy 169.625794 -345.598692) (xy 169.603138 -345.648306)
			(xy 169.573651 -345.694191) (xy 169.537935 -345.735412) (xy 169.496716 -345.771132) (xy 169.450834 -345.800622)
			(xy 169.401222 -345.823283) (xy 169.34889 -345.838653) (xy 169.294903 -345.846419) (xy 169.267632 -345.846908)
			(xy 168.404032 -345.846908) (xy 168.376763 -345.846355) (xy 168.322779 -345.838597) (xy 168.270449 -345.823236)
			(xy 168.220838 -345.800583) (xy 168.174955 -345.771099) (xy 168.133736 -345.735386) (xy 168.09802 -345.69417)
			(xy 168.068533 -345.648291) (xy 168.045876 -345.598681) (xy 168.03051 -345.546352) (xy 168.022747 -345.492369)
			(xy 166.540044 -345.492369) (xy 166.540044 -345.492376) (xy 166.532281 -345.546371) (xy 166.516911 -345.598713)
			(xy 166.494249 -345.648334) (xy 166.464755 -345.694224) (xy 166.42903 -345.73545) (xy 166.387802 -345.771172)
			(xy 166.341909 -345.800662) (xy 166.292286 -345.823321) (xy 166.239944 -345.838686) (xy 166.185948 -345.846446)
			(xy 166.158672 -345.846908) (xy 165.295072 -345.846908) (xy 165.267807 -345.846328) (xy 165.213833 -345.838564)
			(xy 165.161513 -345.823198) (xy 165.111913 -345.800543) (xy 165.066041 -345.77106) (xy 165.024831 -345.735349)
			(xy 164.989123 -345.694137) (xy 164.959644 -345.648263) (xy 164.936992 -345.59866) (xy 164.92163 -345.546339)
			(xy 164.91387 -345.492365) (xy 144.196621 -345.492365) (xy 144.196621 -345.492372) (xy 144.188859 -345.546362)
			(xy 144.173492 -345.598697) (xy 144.150834 -345.648312) (xy 144.121345 -345.694199) (xy 144.085627 -345.735421)
			(xy 144.044405 -345.77114) (xy 143.99852 -345.80063) (xy 143.948904 -345.82329) (xy 143.89657 -345.838657)
			(xy 143.84258 -345.846421) (xy 143.815308 -345.846908) (xy 142.951708 -345.846908) (xy 142.92444 -345.846353)
			(xy 142.870459 -345.838593) (xy 142.818131 -345.823229) (xy 142.768523 -345.800575) (xy 142.722644 -345.771091)
			(xy 142.681428 -345.735378) (xy 142.645714 -345.694162) (xy 142.616229 -345.648284) (xy 142.593574 -345.598676)
			(xy 142.578209 -345.546349) (xy 142.570447 -345.492368) (xy 141.087622 -345.492368) (xy 141.087622 -345.49237)
			(xy 141.07986 -345.546356) (xy 141.064495 -345.598688) (xy 141.04184 -345.648301) (xy 141.012355 -345.694185)
			(xy 140.976641 -345.735407) (xy 140.935424 -345.771126) (xy 140.889543 -345.800617) (xy 140.839933 -345.823279)
			(xy 140.787603 -345.83865) (xy 140.733618 -345.846418) (xy 140.706348 -345.846908) (xy 139.842748 -345.846908)
			(xy 139.815478 -345.846356) (xy 139.761492 -345.8386) (xy 139.70916 -345.82324) (xy 139.659547 -345.800588)
			(xy 139.613663 -345.771105) (xy 139.572442 -345.735392) (xy 139.536724 -345.694176) (xy 139.507235 -345.648295)
			(xy 139.484577 -345.598685) (xy 139.46921 -345.546354) (xy 139.461448 -345.49237) (xy 137.978744 -345.49237)
			(xy 137.978744 -345.492375) (xy 137.970981 -345.546369) (xy 137.955612 -345.598709) (xy 137.932951 -345.648329)
			(xy 137.903459 -345.694219) (xy 137.867736 -345.735444) (xy 137.826509 -345.771166) (xy 137.780619 -345.800657)
			(xy 137.730998 -345.823316) (xy 137.678658 -345.838684) (xy 137.624663 -345.846445) (xy 137.597388 -345.846908)
			(xy 136.733788 -345.846908) (xy 136.706522 -345.846329) (xy 136.652547 -345.838567) (xy 136.600225 -345.823202)
			(xy 136.550622 -345.800548) (xy 136.504748 -345.771065) (xy 136.463537 -345.735354) (xy 136.427827 -345.694142)
			(xy 136.398346 -345.648267) (xy 136.375694 -345.598664) (xy 136.360331 -345.546342) (xy 136.35257 -345.492366)
			(xy 134.869722 -345.492366) (xy 134.869722 -345.492371) (xy 134.86196 -345.546359) (xy 134.846594 -345.598693)
			(xy 134.823937 -345.648307) (xy 134.79445 -345.694192) (xy 134.758734 -345.735414) (xy 134.717514 -345.771133)
			(xy 134.671632 -345.800624) (xy 134.622019 -345.823284) (xy 134.569686 -345.838654) (xy 134.515699 -345.84642)
			(xy 134.488428 -345.846908) (xy 133.624828 -345.846908) (xy 133.597559 -345.846355) (xy 133.543576 -345.838597)
			(xy 133.491246 -345.823235) (xy 133.441635 -345.800581) (xy 133.395753 -345.771098) (xy 133.354535 -345.735385)
			(xy 133.318819 -345.694169) (xy 133.289332 -345.648289) (xy 133.266675 -345.59868) (xy 133.251309 -345.546352)
			(xy 133.243547 -345.492369) (xy 131.760844 -345.492369) (xy 131.760844 -345.492376) (xy 131.75308 -345.546372)
			(xy 131.737711 -345.598713) (xy 131.715048 -345.648335) (xy 131.685554 -345.694225) (xy 131.649829 -345.735451)
			(xy 131.6086 -345.771173) (xy 131.562707 -345.800663) (xy 131.513083 -345.823322) (xy 131.460741 -345.838687)
			(xy 131.406744 -345.846447) (xy 131.379468 -345.846908) (xy 130.515868 -345.846908) (xy 130.488603 -345.846328)
			(xy 130.43463 -345.838563) (xy 130.38231 -345.823197) (xy 130.33271 -345.800542) (xy 130.286839 -345.771058)
			(xy 130.24563 -345.735347) (xy 130.209922 -345.694136) (xy 130.180443 -345.648262) (xy 130.157792 -345.59866)
			(xy 130.14243 -345.546339) (xy 130.13467 -345.492365) (xy 128.651821 -345.492365) (xy 128.651821 -345.492372)
			(xy 128.644059 -345.546362) (xy 128.628692 -345.598697) (xy 128.606034 -345.648312) (xy 128.576545 -345.694199)
			(xy 128.540827 -345.735421) (xy 128.499605 -345.77114) (xy 128.45372 -345.80063) (xy 128.404104 -345.82329)
			(xy 128.35177 -345.838657) (xy 128.29778 -345.846421) (xy 128.270508 -345.846908) (xy 127.406908 -345.846908)
			(xy 127.37964 -345.846353) (xy 127.325659 -345.838593) (xy 127.273331 -345.823229) (xy 127.223723 -345.800575)
			(xy 127.177844 -345.771091) (xy 127.136628 -345.735378) (xy 127.100914 -345.694162) (xy 127.071429 -345.648284)
			(xy 127.048774 -345.598676) (xy 127.033409 -345.546349) (xy 127.025647 -345.492368) (xy 125.542822 -345.492368)
			(xy 125.542822 -345.49237) (xy 125.53506 -345.546356) (xy 125.519695 -345.598688) (xy 125.49704 -345.648301)
			(xy 125.467555 -345.694185) (xy 125.431841 -345.735407) (xy 125.390624 -345.771126) (xy 125.344743 -345.800617)
			(xy 125.295133 -345.823279) (xy 125.242803 -345.83865) (xy 125.188818 -345.846418) (xy 125.161548 -345.846908)
			(xy 124.297948 -345.846908) (xy 124.270678 -345.846356) (xy 124.216692 -345.8386) (xy 124.16436 -345.82324)
			(xy 124.114747 -345.800588) (xy 124.068863 -345.771105) (xy 124.027642 -345.735392) (xy 123.991924 -345.694176)
			(xy 123.962435 -345.648295) (xy 123.939777 -345.598685) (xy 123.92441 -345.546354) (xy 123.916648 -345.49237)
			(xy 122.433944 -345.49237) (xy 122.433944 -345.492375) (xy 122.426181 -345.546369) (xy 122.410812 -345.598709)
			(xy 122.388151 -345.648329) (xy 122.358659 -345.694219) (xy 122.322936 -345.735444) (xy 122.281709 -345.771166)
			(xy 122.235819 -345.800657) (xy 122.186198 -345.823316) (xy 122.133858 -345.838684) (xy 122.079863 -345.846445)
			(xy 122.052588 -345.846908) (xy 121.188988 -345.846908) (xy 121.161722 -345.846329) (xy 121.107747 -345.838567)
			(xy 121.055425 -345.823202) (xy 121.005822 -345.800548) (xy 120.959948 -345.771065) (xy 120.918737 -345.735354)
			(xy 120.883027 -345.694142) (xy 120.853546 -345.648267) (xy 120.830894 -345.598664) (xy 120.815531 -345.546342)
			(xy 120.80777 -345.492366) (xy 119.324922 -345.492366) (xy 119.324922 -345.492371) (xy 119.31716 -345.546359)
			(xy 119.301794 -345.598693) (xy 119.279137 -345.648307) (xy 119.24965 -345.694192) (xy 119.213934 -345.735414)
			(xy 119.172714 -345.771133) (xy 119.126832 -345.800624) (xy 119.077219 -345.823284) (xy 119.024886 -345.838654)
			(xy 118.970899 -345.84642) (xy 118.943628 -345.846908) (xy 118.080028 -345.846908) (xy 118.052759 -345.846355)
			(xy 117.998776 -345.838597) (xy 117.946446 -345.823235) (xy 117.896835 -345.800581) (xy 117.850953 -345.771098)
			(xy 117.809735 -345.735385) (xy 117.774019 -345.694169) (xy 117.744532 -345.648289) (xy 117.721875 -345.59868)
			(xy 117.706509 -345.546352) (xy 117.698747 -345.492369) (xy 116.216044 -345.492369) (xy 116.216044 -345.492376)
			(xy 116.20828 -345.546372) (xy 116.192911 -345.598713) (xy 116.170248 -345.648335) (xy 116.140754 -345.694225)
			(xy 116.105029 -345.735451) (xy 116.0638 -345.771173) (xy 116.017907 -345.800663) (xy 115.968283 -345.823322)
			(xy 115.915941 -345.838687) (xy 115.861944 -345.846447) (xy 115.834668 -345.846908) (xy 114.971068 -345.846908)
			(xy 114.943803 -345.846328) (xy 114.88983 -345.838563) (xy 114.83751 -345.823197) (xy 114.78791 -345.800542)
			(xy 114.742039 -345.771058) (xy 114.70083 -345.735347) (xy 114.665122 -345.694136) (xy 114.635643 -345.648262)
			(xy 114.612992 -345.59866) (xy 114.59763 -345.546339) (xy 114.58987 -345.492365) (xy 113.107021 -345.492365)
			(xy 113.107021 -345.492372) (xy 113.099259 -345.546362) (xy 113.083892 -345.598697) (xy 113.061234 -345.648312)
			(xy 113.031745 -345.694199) (xy 112.996027 -345.735421) (xy 112.954805 -345.77114) (xy 112.90892 -345.80063)
			(xy 112.859304 -345.82329) (xy 112.80697 -345.838657) (xy 112.75298 -345.846421) (xy 112.725708 -345.846908)
			(xy 111.862108 -345.846908) (xy 111.83484 -345.846353) (xy 111.780859 -345.838593) (xy 111.728531 -345.823229)
			(xy 111.678923 -345.800575) (xy 111.633044 -345.771091) (xy 111.591828 -345.735378) (xy 111.556114 -345.694162)
			(xy 111.526629 -345.648284) (xy 111.503974 -345.598676) (xy 111.488609 -345.546349) (xy 111.480847 -345.492368)
			(xy 93.706722 -345.492368) (xy 93.706722 -345.492371) (xy 93.69896 -345.546357) (xy 93.683595 -345.59869)
			(xy 93.660939 -345.648303) (xy 93.631454 -345.694187) (xy 93.595739 -345.735409) (xy 93.554521 -345.771128)
			(xy 93.50864 -345.800619) (xy 93.459029 -345.82328) (xy 93.406698 -345.838651) (xy 93.352713 -345.846419)
			(xy 93.325442 -345.846908) (xy 92.461842 -345.846908) (xy 92.434572 -345.846355) (xy 92.380587 -345.838599)
			(xy 92.328256 -345.823238) (xy 92.278643 -345.800586) (xy 92.23276 -345.771103) (xy 92.19154 -345.73539)
			(xy 92.155822 -345.694174) (xy 92.126334 -345.648293) (xy 92.103676 -345.598683) (xy 92.08831 -345.546354)
			(xy 92.080548 -345.49237) (xy 90.597844 -345.49237) (xy 90.597844 -345.492375) (xy 90.590081 -345.54637)
			(xy 90.574712 -345.59871) (xy 90.55205 -345.648331) (xy 90.522557 -345.694221) (xy 90.486834 -345.735446)
			(xy 90.445606 -345.771168) (xy 90.399715 -345.800659) (xy 90.350094 -345.823318) (xy 90.297752 -345.838685)
			(xy 90.243757 -345.846446) (xy 90.216482 -345.846908) (xy 89.352882 -345.846908) (xy 89.325617 -345.846328)
			(xy 89.271642 -345.838566) (xy 89.219321 -345.823201) (xy 89.169719 -345.800546) (xy 89.123845 -345.771063)
			(xy 89.082635 -345.735352) (xy 89.046926 -345.69414) (xy 89.017445 -345.648266) (xy 88.994793 -345.598663)
			(xy 88.979431 -345.546341) (xy 88.97167 -345.492365) (xy 87.488822 -345.492365) (xy 87.488822 -345.492372)
			(xy 87.481059 -345.54636) (xy 87.465693 -345.598694) (xy 87.443036 -345.648309) (xy 87.413549 -345.694194)
			(xy 87.377832 -345.735416) (xy 87.336612 -345.771136) (xy 87.290728 -345.800626) (xy 87.241115 -345.823286)
			(xy 87.188781 -345.838655) (xy 87.134794 -345.84642) (xy 87.107522 -345.846908) (xy 86.243922 -345.846908)
			(xy 86.216653 -345.846354) (xy 86.16267 -345.838595) (xy 86.110341 -345.823233) (xy 86.060732 -345.800579)
			(xy 86.014851 -345.771096) (xy 85.973633 -345.735383) (xy 85.937917 -345.694167) (xy 85.908431 -345.648288)
			(xy 85.885775 -345.598679) (xy 85.870409 -345.546351) (xy 85.862647 -345.492369) (xy 84.379944 -345.492369)
			(xy 84.379944 -345.492376) (xy 84.37218 -345.546373) (xy 84.35681 -345.598715) (xy 84.334147 -345.648336)
			(xy 84.304652 -345.694227) (xy 84.268927 -345.735453) (xy 84.227697 -345.771175) (xy 84.181803 -345.800665)
			(xy 84.132179 -345.823323) (xy 84.079836 -345.838688) (xy 84.025838 -345.846447) (xy 83.998562 -345.846908)
			(xy 83.134962 -345.846908) (xy 83.107698 -345.846327) (xy 83.053725 -345.838562) (xy 83.001406 -345.823195)
			(xy 82.951807 -345.80054) (xy 82.905936 -345.771056) (xy 82.864728 -345.735345) (xy 82.829021 -345.694134)
			(xy 82.799542 -345.64826) (xy 82.776892 -345.598658) (xy 82.76153 -345.546338) (xy 82.75377 -345.492364)
			(xy 81.270921 -345.492364) (xy 81.270921 -345.492373) (xy 81.263159 -345.546362) (xy 81.247792 -345.598698)
			(xy 81.225133 -345.648314) (xy 81.195644 -345.6942) (xy 81.159924 -345.735423) (xy 81.118702 -345.771143)
			(xy 81.072816 -345.800632) (xy 81.0232 -345.823291) (xy 80.970864 -345.838658) (xy 80.916875 -345.846421)
			(xy 80.889602 -345.846908) (xy 80.026002 -345.846908) (xy 79.998734 -345.846353) (xy 79.944754 -345.838592)
			(xy 79.892427 -345.823228) (xy 79.84282 -345.800573) (xy 79.796941 -345.771089) (xy 79.755726 -345.735376)
			(xy 79.720012 -345.69416) (xy 79.690528 -345.648282) (xy 79.667873 -345.598675) (xy 79.652509 -345.546348)
			(xy 79.644747 -345.492368) (xy 78.161922 -345.492368) (xy 78.161922 -345.492371) (xy 78.15416 -345.546357)
			(xy 78.138795 -345.59869) (xy 78.116139 -345.648303) (xy 78.086654 -345.694187) (xy 78.050939 -345.735409)
			(xy 78.009721 -345.771128) (xy 77.96384 -345.800619) (xy 77.914229 -345.82328) (xy 77.861898 -345.838651)
			(xy 77.807913 -345.846419) (xy 77.780642 -345.846908) (xy 76.917042 -345.846908) (xy 76.889772 -345.846355)
			(xy 76.835787 -345.838599) (xy 76.783456 -345.823238) (xy 76.733843 -345.800586) (xy 76.68796 -345.771103)
			(xy 76.64674 -345.73539) (xy 76.611022 -345.694174) (xy 76.581534 -345.648293) (xy 76.558876 -345.598683)
			(xy 76.54351 -345.546354) (xy 76.535748 -345.49237) (xy 75.053044 -345.49237) (xy 75.053044 -345.492375)
			(xy 75.045281 -345.54637) (xy 75.029912 -345.59871) (xy 75.00725 -345.648331) (xy 74.977757 -345.694221)
			(xy 74.942034 -345.735446) (xy 74.900806 -345.771168) (xy 74.854915 -345.800659) (xy 74.805294 -345.823318)
			(xy 74.752952 -345.838685) (xy 74.698957 -345.846446) (xy 74.671682 -345.846908) (xy 73.808082 -345.846908)
			(xy 73.780817 -345.846328) (xy 73.726842 -345.838566) (xy 73.674521 -345.823201) (xy 73.624919 -345.800546)
			(xy 73.579045 -345.771063) (xy 73.537835 -345.735352) (xy 73.502126 -345.69414) (xy 73.472645 -345.648266)
			(xy 73.449993 -345.598663) (xy 73.434631 -345.546341) (xy 73.42687 -345.492365) (xy 71.944022 -345.492365)
			(xy 71.944022 -345.492372) (xy 71.936259 -345.54636) (xy 71.920893 -345.598694) (xy 71.898236 -345.648309)
			(xy 71.868749 -345.694194) (xy 71.833032 -345.735416) (xy 71.791812 -345.771136) (xy 71.745928 -345.800626)
			(xy 71.696315 -345.823286) (xy 71.643981 -345.838655) (xy 71.589994 -345.84642) (xy 71.562722 -345.846908)
			(xy 70.699122 -345.846908) (xy 70.671853 -345.846354) (xy 70.61787 -345.838595) (xy 70.565541 -345.823233)
			(xy 70.515932 -345.800579) (xy 70.470051 -345.771096) (xy 70.428833 -345.735383) (xy 70.393117 -345.694167)
			(xy 70.363631 -345.648288) (xy 70.340975 -345.598679) (xy 70.325609 -345.546351) (xy 70.317847 -345.492369)
			(xy 68.835144 -345.492369) (xy 68.835144 -345.492376) (xy 68.82738 -345.546373) (xy 68.81201 -345.598715)
			(xy 68.789347 -345.648336) (xy 68.759852 -345.694227) (xy 68.724127 -345.735453) (xy 68.682897 -345.771175)
			(xy 68.637003 -345.800665) (xy 68.587379 -345.823323) (xy 68.535036 -345.838688) (xy 68.481038 -345.846447)
			(xy 68.453762 -345.846908) (xy 67.590162 -345.846908) (xy 67.562898 -345.846327) (xy 67.508925 -345.838562)
			(xy 67.456606 -345.823195) (xy 67.407007 -345.80054) (xy 67.361136 -345.771056) (xy 67.319928 -345.735345)
			(xy 67.284221 -345.694134) (xy 67.254742 -345.64826) (xy 67.232092 -345.598658) (xy 67.21673 -345.546338)
			(xy 67.20897 -345.492364) (xy 65.726121 -345.492364) (xy 65.726121 -345.492373) (xy 65.718359 -345.546362)
			(xy 65.702992 -345.598698) (xy 65.680333 -345.648314) (xy 65.650844 -345.6942) (xy 65.615124 -345.735423)
			(xy 65.573902 -345.771143) (xy 65.528016 -345.800632) (xy 65.4784 -345.823291) (xy 65.426064 -345.838658)
			(xy 65.372075 -345.846421) (xy 65.344802 -345.846908) (xy 64.481202 -345.846908) (xy 64.453934 -345.846353)
			(xy 64.399954 -345.838592) (xy 64.347627 -345.823228) (xy 64.29802 -345.800573) (xy 64.252141 -345.771089)
			(xy 64.210926 -345.735376) (xy 64.175212 -345.69416) (xy 64.145728 -345.648282) (xy 64.123073 -345.598675)
			(xy 64.107709 -345.546348) (xy 64.099947 -345.492368) (xy 62.617122 -345.492368) (xy 62.617122 -345.492371)
			(xy 62.60936 -345.546357) (xy 62.593995 -345.59869) (xy 62.571339 -345.648303) (xy 62.541854 -345.694187)
			(xy 62.506139 -345.735409) (xy 62.464921 -345.771128) (xy 62.41904 -345.800619) (xy 62.369429 -345.82328)
			(xy 62.317098 -345.838651) (xy 62.263113 -345.846419) (xy 62.235842 -345.846908) (xy 61.372242 -345.846908)
			(xy 61.344972 -345.846355) (xy 61.290987 -345.838599) (xy 61.238656 -345.823238) (xy 61.189043 -345.800586)
			(xy 61.14316 -345.771103) (xy 61.10194 -345.73539) (xy 61.066222 -345.694174) (xy 61.036734 -345.648293)
			(xy 61.014076 -345.598683) (xy 60.99871 -345.546354) (xy 60.990948 -345.49237) (xy 51.666922 -345.49237)
			(xy 51.65916 -345.546356) (xy 51.643795 -345.598688) (xy 51.62114 -345.648301) (xy 51.591655 -345.694185)
			(xy 51.555941 -345.735407) (xy 51.514724 -345.771126) (xy 51.468843 -345.800617) (xy 51.419233 -345.823279)
			(xy 51.366903 -345.83865) (xy 51.312918 -345.846418) (xy 51.285648 -345.846908) (xy 50.422048 -345.846908)
			(xy 50.394778 -345.846356) (xy 50.340792 -345.8386) (xy 50.28846 -345.82324) (xy 50.238847 -345.800588)
			(xy 50.192963 -345.771105) (xy 50.151742 -345.735392) (xy 50.116024 -345.694176) (xy 50.086535 -345.648295)
			(xy 50.063877 -345.598685) (xy 50.04851 -345.546354) (xy 50.040748 -345.49237) (xy 48.558044 -345.49237)
			(xy 48.558044 -345.492375) (xy 48.550281 -345.546369) (xy 48.534912 -345.598709) (xy 48.512251 -345.648329)
			(xy 48.482759 -345.694219) (xy 48.447036 -345.735444) (xy 48.405809 -345.771166) (xy 48.359919 -345.800657)
			(xy 48.310298 -345.823316) (xy 48.257958 -345.838684) (xy 48.203963 -345.846445) (xy 48.176688 -345.846908)
			(xy 47.313088 -345.846908) (xy 47.285822 -345.846329) (xy 47.231847 -345.838567) (xy 47.179525 -345.823202)
			(xy 47.129922 -345.800548) (xy 47.084048 -345.771065) (xy 47.042837 -345.735354) (xy 47.007127 -345.694142)
			(xy 46.977646 -345.648267) (xy 46.954994 -345.598664) (xy 46.939631 -345.546342) (xy 46.93187 -345.492366)
			(xy 45.449022 -345.492366) (xy 45.449022 -345.492371) (xy 45.44126 -345.546359) (xy 45.425894 -345.598693)
			(xy 45.403237 -345.648307) (xy 45.37375 -345.694192) (xy 45.338034 -345.735414) (xy 45.296814 -345.771133)
			(xy 45.250932 -345.800624) (xy 45.201319 -345.823284) (xy 45.148986 -345.838654) (xy 45.094999 -345.84642)
			(xy 45.067728 -345.846908) (xy 44.204128 -345.846908) (xy 44.176859 -345.846355) (xy 44.122876 -345.838597)
			(xy 44.070546 -345.823235) (xy 44.020935 -345.800581) (xy 43.975053 -345.771098) (xy 43.933835 -345.735385)
			(xy 43.898119 -345.694169) (xy 43.868632 -345.648289) (xy 43.845975 -345.59868) (xy 43.830609 -345.546352)
			(xy 43.822847 -345.492369) (xy 42.340144 -345.492369) (xy 42.340144 -345.492376) (xy 42.33238 -345.546372)
			(xy 42.317011 -345.598713) (xy 42.294348 -345.648335) (xy 42.264854 -345.694225) (xy 42.229129 -345.735451)
			(xy 42.1879 -345.771173) (xy 42.142007 -345.800663) (xy 42.092383 -345.823322) (xy 42.040041 -345.838687)
			(xy 41.986044 -345.846447) (xy 41.958768 -345.846908) (xy 41.095168 -345.846908) (xy 41.067903 -345.846328)
			(xy 41.01393 -345.838563) (xy 40.96161 -345.823197) (xy 40.91201 -345.800542) (xy 40.866139 -345.771058)
			(xy 40.82493 -345.735347) (xy 40.789222 -345.694136) (xy 40.759743 -345.648262) (xy 40.737092 -345.59866)
			(xy 40.72173 -345.546339) (xy 40.71397 -345.492365) (xy 39.231121 -345.492365) (xy 39.231121 -345.492372)
			(xy 39.223359 -345.546362) (xy 39.207992 -345.598697) (xy 39.185334 -345.648312) (xy 39.155845 -345.694199)
			(xy 39.120127 -345.735421) (xy 39.078905 -345.77114) (xy 39.03302 -345.80063) (xy 38.983404 -345.82329)
			(xy 38.93107 -345.838657) (xy 38.87708 -345.846421) (xy 38.849808 -345.846908) (xy 37.986208 -345.846908)
			(xy 37.95894 -345.846353) (xy 37.904959 -345.838593) (xy 37.852631 -345.823229) (xy 37.803023 -345.800575)
			(xy 37.757144 -345.771091) (xy 37.715928 -345.735378) (xy 37.680214 -345.694162) (xy 37.650729 -345.648284)
			(xy 37.628074 -345.598676) (xy 37.612709 -345.546349) (xy 37.604947 -345.492368) (xy 36.122122 -345.492368)
			(xy 36.122122 -345.49237) (xy 36.11436 -345.546356) (xy 36.098995 -345.598688) (xy 36.07634 -345.648301)
			(xy 36.046855 -345.694185) (xy 36.011141 -345.735407) (xy 35.969924 -345.771126) (xy 35.924043 -345.800617)
			(xy 35.874433 -345.823279) (xy 35.822103 -345.83865) (xy 35.768118 -345.846418) (xy 35.740848 -345.846908)
			(xy 34.877248 -345.846908) (xy 34.849978 -345.846356) (xy 34.795992 -345.8386) (xy 34.74366 -345.82324)
			(xy 34.694047 -345.800588) (xy 34.648163 -345.771105) (xy 34.606942 -345.735392) (xy 34.571224 -345.694176)
			(xy 34.541735 -345.648295) (xy 34.519077 -345.598685) (xy 34.50371 -345.546354) (xy 34.495948 -345.49237)
			(xy 33.013244 -345.49237) (xy 33.013244 -345.492375) (xy 33.005481 -345.546369) (xy 32.990112 -345.598709)
			(xy 32.967451 -345.648329) (xy 32.937959 -345.694219) (xy 32.902236 -345.735444) (xy 32.861009 -345.771166)
			(xy 32.815119 -345.800657) (xy 32.765498 -345.823316) (xy 32.713158 -345.838684) (xy 32.659163 -345.846445)
			(xy 32.631888 -345.846908) (xy 31.768288 -345.846908) (xy 31.741022 -345.846329) (xy 31.687047 -345.838567)
			(xy 31.634725 -345.823202) (xy 31.585122 -345.800548) (xy 31.539248 -345.771065) (xy 31.498037 -345.735354)
			(xy 31.462327 -345.694142) (xy 31.432846 -345.648267) (xy 31.410194 -345.598664) (xy 31.394831 -345.546342)
			(xy 31.38707 -345.492366) (xy 29.904222 -345.492366) (xy 29.904222 -345.492371) (xy 29.89646 -345.546359)
			(xy 29.881094 -345.598693) (xy 29.858437 -345.648307) (xy 29.82895 -345.694192) (xy 29.793234 -345.735414)
			(xy 29.752014 -345.771133) (xy 29.706132 -345.800624) (xy 29.656519 -345.823284) (xy 29.604186 -345.838654)
			(xy 29.550199 -345.84642) (xy 29.522928 -345.846908) (xy 28.659328 -345.846908) (xy 28.632059 -345.846355)
			(xy 28.578076 -345.838597) (xy 28.525746 -345.823235) (xy 28.476135 -345.800581) (xy 28.430253 -345.771098)
			(xy 28.389035 -345.735385) (xy 28.353319 -345.694169) (xy 28.323832 -345.648289) (xy 28.301175 -345.59868)
			(xy 28.285809 -345.546352) (xy 28.278047 -345.492369) (xy 26.795344 -345.492369) (xy 26.795344 -345.492376)
			(xy 26.78758 -345.546372) (xy 26.772211 -345.598713) (xy 26.749548 -345.648335) (xy 26.720054 -345.694225)
			(xy 26.684329 -345.735451) (xy 26.6431 -345.771173) (xy 26.597207 -345.800663) (xy 26.547583 -345.823322)
			(xy 26.495241 -345.838687) (xy 26.441244 -345.846447) (xy 26.413968 -345.846908) (xy 25.550368 -345.846908)
			(xy 25.523103 -345.846328) (xy 25.46913 -345.838563) (xy 25.41681 -345.823197) (xy 25.36721 -345.800542)
			(xy 25.321339 -345.771058) (xy 25.28013 -345.735347) (xy 25.244422 -345.694136) (xy 25.214943 -345.648262)
			(xy 25.192292 -345.59866) (xy 25.17693 -345.546339) (xy 25.16917 -345.492365) (xy 23.686305 -345.492365)
			(xy 23.686305 -345.492421) (xy 23.678542 -345.546407) (xy 23.663176 -345.59874) (xy 23.640519 -345.648352)
			(xy 23.611031 -345.694236) (xy 23.575314 -345.735455) (xy 23.534094 -345.771172) (xy 23.488211 -345.80066)
			(xy 23.438598 -345.823317) (xy 23.386265 -345.838683) (xy 23.332279 -345.846445) (xy 23.305008 -345.846908)
			(xy 22.441408 -345.846908) (xy 22.414138 -345.846429) (xy 22.360154 -345.838667) (xy 22.307825 -345.823302)
			(xy 22.258214 -345.800645) (xy 22.212333 -345.771159) (xy 22.171115 -345.735443) (xy 22.1354 -345.694225)
			(xy 22.105914 -345.648344) (xy 22.083258 -345.598733) (xy 22.067892 -345.546404) (xy 22.06013 -345.49242)
			(xy 20.577345 -345.49242) (xy 20.577345 -345.492421) (xy 20.569582 -345.546407) (xy 20.554216 -345.59874)
			(xy 20.531559 -345.648352) (xy 20.502071 -345.694236) (xy 20.466354 -345.735455) (xy 20.425134 -345.771172)
			(xy 20.379251 -345.80066) (xy 20.329638 -345.823317) (xy 20.277305 -345.838683) (xy 20.223319 -345.846445)
			(xy 20.196048 -345.846908) (xy 19.332448 -345.846908) (xy 19.305178 -345.846429) (xy 19.251194 -345.838667)
			(xy 19.198865 -345.823302) (xy 19.149254 -345.800645) (xy 19.103373 -345.771159) (xy 19.062155 -345.735443)
			(xy 19.02644 -345.694225) (xy 18.996954 -345.648344) (xy 18.974298 -345.598733) (xy 18.958932 -345.546404)
			(xy 18.95117 -345.49242) (xy 0.508 -345.49242) (xy 0.508 -348.976496) (xy 4.708641 -348.976496) (xy 4.708641 -348.847356)
			(xy 4.716591 -348.718461) (xy 4.732461 -348.590301) (xy 4.75619 -348.46336) (xy 4.787689 -348.338121)
			(xy 4.826838 -348.215058) (xy 4.873489 -348.094639) (xy 4.927464 -347.97732) (xy 4.988559 -347.863546)
			(xy 5.056542 -347.753749) (xy 5.131156 -347.648346) (xy 5.212117 -347.547736) (xy 5.299117 -347.452301)
			(xy 5.391828 -347.362402) (xy 5.489898 -347.278381) (xy 5.592953 -347.200557) (xy 5.700604 -347.129225)
			(xy 5.812443 -347.064655) (xy 5.928044 -347.007093) (xy 6.046969 -346.956756) (xy 6.168768 -346.913836)
			(xy 6.292978 -346.878495) (xy 6.419127 -346.850868) (xy 6.546739 -346.831059) (xy 6.675328 -346.819143)
			(xy 6.804406 -346.815167) (xy 6.933484 -346.819143) (xy 7.062073 -346.831059) (xy 7.189685 -346.850868)
			(xy 7.315834 -346.878495) (xy 7.440044 -346.913836) (xy 7.451736 -346.917956) (xy 245.50903 -346.917956)
			(xy 245.50903 -346.83326) (xy 245.517081 -346.748946) (xy 245.53311 -346.66578) (xy 245.556971 -346.584513)
			(xy 245.58845 -346.505883) (xy 245.627261 -346.430602) (xy 245.673051 -346.35935) (xy 245.725407 -346.292774)
			(xy 245.783855 -346.231476) (xy 245.847865 -346.176011) (xy 245.916857 -346.126882) (xy 245.990207 -346.084533)
			(xy 246.06725 -346.049349) (xy 246.147289 -346.021647) (xy 246.229598 -346.001679) (xy 246.313433 -345.989626)
			(xy 246.398034 -345.985596) (xy 246.482635 -345.989626) (xy 246.56647 -346.001679) (xy 246.648779 -346.021647)
			(xy 246.728818 -346.049349) (xy 246.805861 -346.084533) (xy 246.879211 -346.126882) (xy 246.948203 -346.176011)
			(xy 247.012213 -346.231476) (xy 247.070661 -346.292774) (xy 247.123017 -346.35935) (xy 247.168807 -346.430602)
			(xy 247.207618 -346.505883) (xy 247.239097 -346.584513) (xy 247.262958 -346.66578) (xy 247.278987 -346.748946)
			(xy 247.287038 -346.83326) (xy 247.287542 -346.875608) (xy 247.287038 -346.917956) (xy 247.278987 -347.00227)
			(xy 247.262958 -347.085436) (xy 247.239097 -347.166703) (xy 247.207618 -347.245333) (xy 247.168807 -347.320614)
			(xy 247.123017 -347.391866) (xy 247.070661 -347.458442) (xy 247.012213 -347.51974) (xy 246.948203 -347.575205)
			(xy 246.879211 -347.624334) (xy 246.805861 -347.666683) (xy 246.728818 -347.701867) (xy 246.648779 -347.729569)
			(xy 246.56647 -347.749537) (xy 246.482635 -347.76159) (xy 246.398034 -347.765621) (xy 246.313433 -347.76159)
			(xy 246.229598 -347.749537) (xy 246.147289 -347.729569) (xy 246.06725 -347.701867) (xy 245.990207 -347.666683)
			(xy 245.916857 -347.624334) (xy 245.847865 -347.575205) (xy 245.783855 -347.51974) (xy 245.725407 -347.458442)
			(xy 245.673051 -347.391866) (xy 245.627261 -347.320614) (xy 245.58845 -347.245333) (xy 245.556971 -347.166703)
			(xy 245.53311 -347.085436) (xy 245.517081 -347.00227) (xy 245.50903 -346.917956) (xy 7.451736 -346.917956)
			(xy 7.561843 -346.956756) (xy 7.680768 -347.007093) (xy 7.796369 -347.064655) (xy 7.908208 -347.129225)
			(xy 8.015859 -347.200557) (xy 8.118914 -347.278381) (xy 8.216984 -347.362402) (xy 8.309695 -347.452301)
			(xy 8.396695 -347.547736) (xy 8.477656 -347.648346) (xy 8.55227 -347.753749) (xy 8.620253 -347.863546)
			(xy 8.681348 -347.97732) (xy 8.735323 -348.094639) (xy 8.781974 -348.215058) (xy 8.821123 -348.338121)
			(xy 8.852622 -348.46336) (xy 8.876351 -348.590301) (xy 8.879169 -348.613059) (xy 18.951174 -348.613059)
			(xy 18.951174 -348.558521) (xy 18.958936 -348.504537) (xy 18.974301 -348.452208) (xy 18.996957 -348.402598)
			(xy 19.026443 -348.356717) (xy 19.062158 -348.315499) (xy 19.103375 -348.279784) (xy 19.149256 -348.250298)
			(xy 19.198866 -348.227642) (xy 19.251195 -348.212276) (xy 19.305179 -348.204515) (xy 19.332448 -348.204028)
			(xy 20.196048 -348.204028) (xy 20.223319 -348.204491) (xy 20.277306 -348.212253) (xy 20.329639 -348.227619)
			(xy 20.379253 -348.250277) (xy 20.425136 -348.279764) (xy 20.466357 -348.315482) (xy 20.502074 -348.356702)
			(xy 20.531562 -348.402586) (xy 20.55422 -348.452199) (xy 20.569586 -348.504532) (xy 20.577349 -348.558519)
			(xy 20.577349 -348.613061) (xy 20.577347 -348.613072) (xy 22.060092 -348.613072) (xy 22.060092 -348.558528)
			(xy 22.067854 -348.504539) (xy 22.083221 -348.452204) (xy 22.10588 -348.402589) (xy 22.135369 -348.356704)
			(xy 22.171088 -348.315483) (xy 22.21231 -348.279764) (xy 22.258196 -348.250276) (xy 22.307812 -348.227618)
			(xy 22.360147 -348.212252) (xy 22.414136 -348.204491) (xy 22.441408 -348.204028) (xy 23.305008 -348.204028)
			(xy 23.332276 -348.204535) (xy 23.386258 -348.212297) (xy 23.438585 -348.227663) (xy 23.488193 -348.250319)
			(xy 23.534071 -348.279804) (xy 23.575287 -348.315519) (xy 23.611 -348.356735) (xy 23.640485 -348.402614)
			(xy 23.66314 -348.452223) (xy 23.678504 -348.50455) (xy 23.686266 -348.558532) (xy 23.686266 -348.613068)
			(xy 23.686266 -348.613069) (xy 25.169114 -348.613069) (xy 25.169114 -348.558531) (xy 25.176875 -348.504549)
			(xy 25.19224 -348.452221) (xy 25.214894 -348.402611) (xy 25.244378 -348.356731) (xy 25.28009 -348.315513)
			(xy 25.321305 -348.279797) (xy 25.367183 -348.250309) (xy 25.416791 -348.227651) (xy 25.469118 -348.212282)
			(xy 25.523099 -348.204517) (xy 25.550368 -348.204028) (xy 26.413968 -348.204028) (xy 26.44124 -348.204509)
			(xy 26.495229 -348.212268) (xy 26.547564 -348.227631) (xy 26.59718 -348.250286) (xy 26.643066 -348.279772)
			(xy 26.684289 -348.315488) (xy 26.720009 -348.356708) (xy 26.749499 -348.402592) (xy 26.772158 -348.452206)
			(xy 26.787526 -348.50454) (xy 26.795288 -348.558528) (xy 26.795288 -348.613072) (xy 26.795288 -348.613073)
			(xy 28.277992 -348.613073) (xy 28.277992 -348.558527) (xy 28.285755 -348.504536) (xy 28.301123 -348.4522)
			(xy 28.323783 -348.402584) (xy 28.353274 -348.356697) (xy 28.388995 -348.315476) (xy 28.43022 -348.279757)
			(xy 28.476108 -348.25027) (xy 28.525726 -348.227613) (xy 28.578064 -348.212249) (xy 28.632055 -348.20449)
			(xy 28.659328 -348.204028) (xy 29.522928 -348.204028) (xy 29.550195 -348.204536) (xy 29.604175 -348.212301)
			(xy 29.656499 -348.227668) (xy 29.706105 -348.250326) (xy 29.751981 -348.279811) (xy 29.793194 -348.315526)
			(xy 29.828905 -348.356742) (xy 29.858388 -348.40262) (xy 29.881041 -348.452227) (xy 29.896405 -348.504553)
			(xy 29.904166 -348.558533) (xy 29.904166 -348.613067) (xy 29.904166 -348.61307) (xy 31.387014 -348.61307)
			(xy 31.387014 -348.55853) (xy 31.394776 -348.504546) (xy 31.410141 -348.452217) (xy 31.432797 -348.402606)
			(xy 31.462283 -348.356724) (xy 31.497997 -348.315506) (xy 31.539215 -348.27979) (xy 31.585095 -348.250303)
			(xy 31.634705 -348.227645) (xy 31.687035 -348.212279) (xy 31.741018 -348.204515) (xy 31.768288 -348.204028)
			(xy 32.631888 -348.204028) (xy 32.659159 -348.204511) (xy 32.713146 -348.212271) (xy 32.765478 -348.227636)
			(xy 32.815092 -348.250292) (xy 32.860976 -348.279779) (xy 32.902196 -348.315495) (xy 32.937914 -348.356715)
			(xy 32.967402 -348.402598) (xy 32.99006 -348.45221) (xy 33.005426 -348.504543) (xy 33.013189 -348.558529)
			(xy 33.013189 -348.613071) (xy 33.013189 -348.613074) (xy 34.495892 -348.613074) (xy 34.495892 -348.558526)
			(xy 34.503655 -348.504534) (xy 34.519024 -348.452196) (xy 34.541686 -348.402578) (xy 34.571179 -348.356691)
			(xy 34.606902 -348.315468) (xy 34.648129 -348.27975) (xy 34.69402 -348.250263) (xy 34.743641 -348.227608)
			(xy 34.795981 -348.212245) (xy 34.849974 -348.204488) (xy 34.877248 -348.204028) (xy 35.740848 -348.204028)
			(xy 35.768114 -348.204538) (xy 35.822091 -348.212305) (xy 35.874414 -348.227674) (xy 35.924017 -348.250332)
			(xy 35.96989 -348.279819) (xy 36.011101 -348.315533) (xy 36.04681 -348.356748) (xy 36.076291 -348.402626)
			(xy 36.098943 -348.452231) (xy 36.114306 -348.504556) (xy 36.122066 -348.558534) (xy 36.122066 -348.613066)
			(xy 36.122065 -348.613072) (xy 37.604892 -348.613072) (xy 37.604892 -348.558528) (xy 37.612654 -348.504539)
			(xy 37.628021 -348.452204) (xy 37.65068 -348.402589) (xy 37.680169 -348.356704) (xy 37.715888 -348.315483)
			(xy 37.75711 -348.279764) (xy 37.802996 -348.250276) (xy 37.852612 -348.227618) (xy 37.904947 -348.212252)
			(xy 37.958936 -348.204491) (xy 37.986208 -348.204028) (xy 38.849808 -348.204028) (xy 38.877076 -348.204535)
			(xy 38.931058 -348.212297) (xy 38.983385 -348.227663) (xy 39.032993 -348.250319) (xy 39.078871 -348.279804)
			(xy 39.120087 -348.315519) (xy 39.1558 -348.356735) (xy 39.185285 -348.402614) (xy 39.20794 -348.452223)
			(xy 39.223304 -348.50455) (xy 39.231066 -348.558532) (xy 39.231066 -348.613068) (xy 39.231066 -348.613069)
			(xy 40.713914 -348.613069) (xy 40.713914 -348.558531) (xy 40.721675 -348.504549) (xy 40.73704 -348.452221)
			(xy 40.759694 -348.402611) (xy 40.789178 -348.356731) (xy 40.82489 -348.315513) (xy 40.866105 -348.279797)
			(xy 40.911983 -348.250309) (xy 40.961591 -348.227651) (xy 41.013918 -348.212282) (xy 41.067899 -348.204517)
			(xy 41.095168 -348.204028) (xy 41.958768 -348.204028) (xy 41.98604 -348.204509) (xy 42.040029 -348.212268)
			(xy 42.092364 -348.227631) (xy 42.14198 -348.250286) (xy 42.187866 -348.279772) (xy 42.229089 -348.315488)
			(xy 42.264809 -348.356708) (xy 42.294299 -348.402592) (xy 42.316958 -348.452206) (xy 42.332326 -348.50454)
			(xy 42.340088 -348.558528) (xy 42.340088 -348.613072) (xy 42.340088 -348.613073) (xy 43.822792 -348.613073)
			(xy 43.822792 -348.558527) (xy 43.830555 -348.504536) (xy 43.845923 -348.4522) (xy 43.868583 -348.402584)
			(xy 43.898074 -348.356697) (xy 43.933795 -348.315476) (xy 43.97502 -348.279757) (xy 44.020908 -348.25027)
			(xy 44.070526 -348.227613) (xy 44.122864 -348.212249) (xy 44.176855 -348.20449) (xy 44.204128 -348.204028)
			(xy 45.067728 -348.204028) (xy 45.094995 -348.204536) (xy 45.148975 -348.212301) (xy 45.201299 -348.227668)
			(xy 45.250905 -348.250326) (xy 45.296781 -348.279811) (xy 45.337994 -348.315526) (xy 45.373705 -348.356742)
			(xy 45.403188 -348.40262) (xy 45.425841 -348.452227) (xy 45.441205 -348.504553) (xy 45.448966 -348.558533)
			(xy 45.448966 -348.613067) (xy 45.448966 -348.61307) (xy 46.931814 -348.61307) (xy 46.931814 -348.55853)
			(xy 46.939576 -348.504546) (xy 46.954941 -348.452217) (xy 46.977597 -348.402606) (xy 47.007083 -348.356724)
			(xy 47.042797 -348.315506) (xy 47.084015 -348.27979) (xy 47.129895 -348.250303) (xy 47.179505 -348.227645)
			(xy 47.231835 -348.212279) (xy 47.285818 -348.204515) (xy 47.313088 -348.204028) (xy 48.176688 -348.204028)
			(xy 48.203959 -348.204511) (xy 48.257946 -348.212271) (xy 48.310278 -348.227636) (xy 48.359892 -348.250292)
			(xy 48.405776 -348.279779) (xy 48.446996 -348.315495) (xy 48.482714 -348.356715) (xy 48.512202 -348.402598)
			(xy 48.53486 -348.45221) (xy 48.550226 -348.504543) (xy 48.557989 -348.558529) (xy 48.557989 -348.613071)
			(xy 48.557989 -348.613074) (xy 50.040692 -348.613074) (xy 50.040692 -348.558526) (xy 50.048455 -348.504534)
			(xy 50.063824 -348.452196) (xy 50.086486 -348.402578) (xy 50.115979 -348.356691) (xy 50.151702 -348.315468)
			(xy 50.192929 -348.27975) (xy 50.23882 -348.250263) (xy 50.288441 -348.227608) (xy 50.340781 -348.212245)
			(xy 50.394774 -348.204488) (xy 50.422048 -348.204028) (xy 51.285648 -348.204028) (xy 51.312914 -348.204538)
			(xy 51.366891 -348.212305) (xy 51.419214 -348.227674) (xy 51.468817 -348.250332) (xy 51.51469 -348.279819)
			(xy 51.555901 -348.315533) (xy 51.59161 -348.356748) (xy 51.621091 -348.402626) (xy 51.643743 -348.452231)
			(xy 51.659106 -348.504556) (xy 51.666866 -348.558534) (xy 51.666866 -348.613066) (xy 51.666865 -348.613074)
			(xy 60.990892 -348.613074) (xy 60.990892 -348.558526) (xy 60.998655 -348.504534) (xy 61.014024 -348.452197)
			(xy 61.036685 -348.40258) (xy 61.066177 -348.356693) (xy 61.1019 -348.315471) (xy 61.143127 -348.279752)
			(xy 61.189017 -348.250265) (xy 61.238636 -348.227609) (xy 61.290976 -348.212246) (xy 61.344968 -348.204489)
			(xy 61.372242 -348.204028) (xy 62.235842 -348.204028) (xy 62.263109 -348.204537) (xy 62.317086 -348.212304)
			(xy 62.369409 -348.227672) (xy 62.419013 -348.25033) (xy 62.464887 -348.279816) (xy 62.506099 -348.315531)
			(xy 62.541809 -348.356746) (xy 62.57129 -348.402624) (xy 62.593943 -348.45223) (xy 62.609305 -348.504555)
			(xy 62.617066 -348.558533) (xy 62.617066 -348.613067) (xy 62.617065 -348.613072) (xy 64.099892 -348.613072)
			(xy 64.099892 -348.558528) (xy 64.107654 -348.50454) (xy 64.123021 -348.452206) (xy 64.145679 -348.402591)
			(xy 64.175168 -348.356706) (xy 64.210886 -348.315485) (xy 64.252108 -348.279766) (xy 64.297993 -348.250278)
			(xy 64.347607 -348.22762) (xy 64.399942 -348.212253) (xy 64.45393 -348.204491) (xy 64.481202 -348.204028)
			(xy 65.344802 -348.204028) (xy 65.372071 -348.204535) (xy 65.426053 -348.212296) (xy 65.47838 -348.227661)
			(xy 65.527989 -348.250317) (xy 65.573869 -348.279802) (xy 65.615085 -348.315517) (xy 65.650799 -348.356733)
			(xy 65.680284 -348.402613) (xy 65.702939 -348.452221) (xy 65.718304 -348.504549) (xy 65.726066 -348.558531)
			(xy 65.726066 -348.613068) (xy 67.208914 -348.613068) (xy 67.208914 -348.558532) (xy 67.216675 -348.50455)
			(xy 67.232039 -348.452222) (xy 67.254693 -348.402613) (xy 67.284176 -348.356733) (xy 67.319888 -348.315515)
			(xy 67.361102 -348.279799) (xy 67.40698 -348.250311) (xy 67.456586 -348.227652) (xy 67.508913 -348.212283)
			(xy 67.562894 -348.204517) (xy 67.590162 -348.204028) (xy 68.453762 -348.204028) (xy 68.481034 -348.204509)
			(xy 68.535024 -348.212266) (xy 68.58736 -348.227629) (xy 68.636976 -348.250284) (xy 68.682863 -348.27977)
			(xy 68.724087 -348.315486) (xy 68.759808 -348.356706) (xy 68.789298 -348.40259) (xy 68.811958 -348.452205)
			(xy 68.827326 -348.504539) (xy 68.835088 -348.558528) (xy 68.835088 -348.613072) (xy 68.835088 -348.613073)
			(xy 70.317792 -348.613073) (xy 70.317792 -348.558527) (xy 70.325554 -348.504537) (xy 70.340922 -348.452201)
			(xy 70.363582 -348.402585) (xy 70.393072 -348.356699) (xy 70.428793 -348.315478) (xy 70.470017 -348.279759)
			(xy 70.515905 -348.250271) (xy 70.565522 -348.227615) (xy 70.617859 -348.21225) (xy 70.671849 -348.20449)
			(xy 70.699122 -348.204028) (xy 71.562722 -348.204028) (xy 71.58999 -348.204536) (xy 71.643969 -348.2123)
			(xy 71.696295 -348.227667) (xy 71.745901 -348.250324) (xy 71.791778 -348.279809) (xy 71.832992 -348.315524)
			(xy 71.868704 -348.35674) (xy 71.898187 -348.402618) (xy 71.920841 -348.452226) (xy 71.936205 -348.504552)
			(xy 71.943966 -348.558532) (xy 71.943966 -348.613068) (xy 71.943966 -348.613069) (xy 73.426814 -348.613069)
			(xy 73.426814 -348.558531) (xy 73.434576 -348.504547) (xy 73.449941 -348.452218) (xy 73.472596 -348.402608)
			(xy 73.502081 -348.356726) (xy 73.537795 -348.315508) (xy 73.579012 -348.279792) (xy 73.624892 -348.250305)
			(xy 73.674501 -348.227647) (xy 73.72683 -348.21228) (xy 73.780813 -348.204516) (xy 73.808082 -348.204028)
			(xy 74.671682 -348.204028) (xy 74.698953 -348.20451) (xy 74.752941 -348.21227) (xy 74.805274 -348.227634)
			(xy 74.854888 -348.25029) (xy 74.900773 -348.279777) (xy 74.941994 -348.315493) (xy 74.977712 -348.356713)
			(xy 75.007201 -348.402596) (xy 75.029859 -348.452209) (xy 75.045226 -348.504542) (xy 75.052988 -348.558529)
			(xy 75.052988 -348.613071) (xy 75.052988 -348.613074) (xy 76.535692 -348.613074) (xy 76.535692 -348.558526)
			(xy 76.543455 -348.504534) (xy 76.558824 -348.452197) (xy 76.581485 -348.40258) (xy 76.610977 -348.356693)
			(xy 76.6467 -348.315471) (xy 76.687927 -348.279752) (xy 76.733817 -348.250265) (xy 76.783436 -348.227609)
			(xy 76.835776 -348.212246) (xy 76.889768 -348.204489) (xy 76.917042 -348.204028) (xy 77.780642 -348.204028)
			(xy 77.807909 -348.204537) (xy 77.861886 -348.212304) (xy 77.914209 -348.227672) (xy 77.963813 -348.25033)
			(xy 78.009687 -348.279816) (xy 78.050899 -348.315531) (xy 78.086609 -348.356746) (xy 78.11609 -348.402624)
			(xy 78.138743 -348.45223) (xy 78.154105 -348.504555) (xy 78.161866 -348.558533) (xy 78.161866 -348.613067)
			(xy 78.161865 -348.613072) (xy 79.644692 -348.613072) (xy 79.644692 -348.558528) (xy 79.652454 -348.50454)
			(xy 79.667821 -348.452206) (xy 79.690479 -348.402591) (xy 79.719968 -348.356706) (xy 79.755686 -348.315485)
			(xy 79.796908 -348.279766) (xy 79.842793 -348.250278) (xy 79.892407 -348.22762) (xy 79.944742 -348.212253)
			(xy 79.99873 -348.204491) (xy 80.026002 -348.204028) (xy 80.889602 -348.204028) (xy 80.916871 -348.204535)
			(xy 80.970853 -348.212296) (xy 81.02318 -348.227661) (xy 81.072789 -348.250317) (xy 81.118669 -348.279802)
			(xy 81.159885 -348.315517) (xy 81.195599 -348.356733) (xy 81.225084 -348.402613) (xy 81.247739 -348.452221)
			(xy 81.263104 -348.504549) (xy 81.270866 -348.558531) (xy 81.270866 -348.613068) (xy 82.753714 -348.613068)
			(xy 82.753714 -348.558532) (xy 82.761475 -348.50455) (xy 82.776839 -348.452222) (xy 82.799493 -348.402613)
			(xy 82.828976 -348.356733) (xy 82.864688 -348.315515) (xy 82.905902 -348.279799) (xy 82.95178 -348.250311)
			(xy 83.001386 -348.227652) (xy 83.053713 -348.212283) (xy 83.107694 -348.204517) (xy 83.134962 -348.204028)
			(xy 83.998562 -348.204028) (xy 84.025834 -348.204509) (xy 84.079824 -348.212266) (xy 84.13216 -348.227629)
			(xy 84.181776 -348.250284) (xy 84.227663 -348.27977) (xy 84.268887 -348.315486) (xy 84.304608 -348.356706)
			(xy 84.334098 -348.40259) (xy 84.356758 -348.452205) (xy 84.372126 -348.504539) (xy 84.379888 -348.558528)
			(xy 84.379888 -348.613072) (xy 84.379888 -348.613073) (xy 85.862592 -348.613073) (xy 85.862592 -348.558527)
			(xy 85.870354 -348.504537) (xy 85.885722 -348.452201) (xy 85.908382 -348.402585) (xy 85.937872 -348.356699)
			(xy 85.973593 -348.315478) (xy 86.014817 -348.279759) (xy 86.060705 -348.250271) (xy 86.110322 -348.227615)
			(xy 86.162659 -348.21225) (xy 86.216649 -348.20449) (xy 86.243922 -348.204028) (xy 87.107522 -348.204028)
			(xy 87.13479 -348.204536) (xy 87.188769 -348.2123) (xy 87.241095 -348.227667) (xy 87.290701 -348.250324)
			(xy 87.336578 -348.279809) (xy 87.377792 -348.315524) (xy 87.413504 -348.35674) (xy 87.442987 -348.402618)
			(xy 87.465641 -348.452226) (xy 87.481005 -348.504552) (xy 87.488766 -348.558532) (xy 87.488766 -348.613068)
			(xy 87.488766 -348.613069) (xy 88.971614 -348.613069) (xy 88.971614 -348.558531) (xy 88.979376 -348.504547)
			(xy 88.994741 -348.452218) (xy 89.017396 -348.402608) (xy 89.046881 -348.356726) (xy 89.082595 -348.315508)
			(xy 89.123812 -348.279792) (xy 89.169692 -348.250305) (xy 89.219301 -348.227647) (xy 89.27163 -348.21228)
			(xy 89.325613 -348.204516) (xy 89.352882 -348.204028) (xy 90.216482 -348.204028) (xy 90.243753 -348.20451)
			(xy 90.297741 -348.21227) (xy 90.350074 -348.227634) (xy 90.399688 -348.25029) (xy 90.445573 -348.279777)
			(xy 90.486794 -348.315493) (xy 90.522512 -348.356713) (xy 90.552001 -348.402596) (xy 90.574659 -348.452209)
			(xy 90.590026 -348.504542) (xy 90.597788 -348.558529) (xy 90.597788 -348.613071) (xy 90.597788 -348.613074)
			(xy 92.080492 -348.613074) (xy 92.080492 -348.558526) (xy 92.088255 -348.504534) (xy 92.103624 -348.452197)
			(xy 92.126285 -348.40258) (xy 92.155777 -348.356693) (xy 92.1915 -348.315471) (xy 92.232727 -348.279752)
			(xy 92.278617 -348.250265) (xy 92.328236 -348.227609) (xy 92.380576 -348.212246) (xy 92.434568 -348.204489)
			(xy 92.461842 -348.204028) (xy 93.325442 -348.204028) (xy 93.352709 -348.204537) (xy 93.406686 -348.212304)
			(xy 93.459009 -348.227672) (xy 93.508613 -348.25033) (xy 93.554487 -348.279816) (xy 93.595699 -348.315531)
			(xy 93.631409 -348.356746) (xy 93.66089 -348.402624) (xy 93.683543 -348.45223) (xy 93.698905 -348.504555)
			(xy 93.706666 -348.558533) (xy 93.706666 -348.613067) (xy 93.706665 -348.613072) (xy 111.480792 -348.613072)
			(xy 111.480792 -348.558528) (xy 111.488554 -348.504539) (xy 111.503921 -348.452204) (xy 111.52658 -348.402589)
			(xy 111.556069 -348.356704) (xy 111.591788 -348.315483) (xy 111.63301 -348.279764) (xy 111.678896 -348.250276)
			(xy 111.728512 -348.227618) (xy 111.780847 -348.212252) (xy 111.834836 -348.204491) (xy 111.862108 -348.204028)
			(xy 112.725708 -348.204028) (xy 112.752976 -348.204535) (xy 112.806958 -348.212297) (xy 112.859285 -348.227663)
			(xy 112.908893 -348.250319) (xy 112.954771 -348.279804) (xy 112.995987 -348.315519) (xy 113.0317 -348.356735)
			(xy 113.061185 -348.402614) (xy 113.08384 -348.452223) (xy 113.099204 -348.50455) (xy 113.106966 -348.558532)
			(xy 113.106966 -348.613068) (xy 113.106966 -348.613069) (xy 114.589814 -348.613069) (xy 114.589814 -348.558531)
			(xy 114.597575 -348.504549) (xy 114.61294 -348.452221) (xy 114.635594 -348.402611) (xy 114.665078 -348.356731)
			(xy 114.70079 -348.315513) (xy 114.742005 -348.279797) (xy 114.787883 -348.250309) (xy 114.837491 -348.227651)
			(xy 114.889818 -348.212282) (xy 114.943799 -348.204517) (xy 114.971068 -348.204028) (xy 115.834668 -348.204028)
			(xy 115.86194 -348.204509) (xy 115.915929 -348.212268) (xy 115.968264 -348.227631) (xy 116.01788 -348.250286)
			(xy 116.063766 -348.279772) (xy 116.104989 -348.315488) (xy 116.140709 -348.356708) (xy 116.170199 -348.402592)
			(xy 116.192858 -348.452206) (xy 116.208226 -348.50454) (xy 116.215988 -348.558528) (xy 116.215988 -348.613072)
			(xy 116.215988 -348.613073) (xy 117.698692 -348.613073) (xy 117.698692 -348.558527) (xy 117.706455 -348.504536)
			(xy 117.721823 -348.4522) (xy 117.744483 -348.402584) (xy 117.773974 -348.356697) (xy 117.809695 -348.315476)
			(xy 117.85092 -348.279757) (xy 117.896808 -348.25027) (xy 117.946426 -348.227613) (xy 117.998764 -348.212249)
			(xy 118.052755 -348.20449) (xy 118.080028 -348.204028) (xy 118.943628 -348.204028) (xy 118.970895 -348.204536)
			(xy 119.024875 -348.212301) (xy 119.077199 -348.227668) (xy 119.126805 -348.250326) (xy 119.172681 -348.279811)
			(xy 119.213894 -348.315526) (xy 119.249605 -348.356742) (xy 119.279088 -348.40262) (xy 119.301741 -348.452227)
			(xy 119.317105 -348.504553) (xy 119.324866 -348.558533) (xy 119.324866 -348.613067) (xy 119.324866 -348.61307)
			(xy 120.807714 -348.61307) (xy 120.807714 -348.55853) (xy 120.815476 -348.504546) (xy 120.830841 -348.452217)
			(xy 120.853497 -348.402606) (xy 120.882983 -348.356724) (xy 120.918697 -348.315506) (xy 120.959915 -348.27979)
			(xy 121.005795 -348.250303) (xy 121.055405 -348.227645) (xy 121.107735 -348.212279) (xy 121.161718 -348.204515)
			(xy 121.188988 -348.204028) (xy 122.052588 -348.204028) (xy 122.079859 -348.204511) (xy 122.133846 -348.212271)
			(xy 122.186178 -348.227636) (xy 122.235792 -348.250292) (xy 122.281676 -348.279779) (xy 122.322896 -348.315495)
			(xy 122.358614 -348.356715) (xy 122.388102 -348.402598) (xy 122.41076 -348.45221) (xy 122.426126 -348.504543)
			(xy 122.433889 -348.558529) (xy 122.433889 -348.613071) (xy 122.433889 -348.613074) (xy 123.916592 -348.613074)
			(xy 123.916592 -348.558526) (xy 123.924355 -348.504534) (xy 123.939724 -348.452196) (xy 123.962386 -348.402578)
			(xy 123.991879 -348.356691) (xy 124.027602 -348.315468) (xy 124.068829 -348.27975) (xy 124.11472 -348.250263)
			(xy 124.164341 -348.227608) (xy 124.216681 -348.212245) (xy 124.270674 -348.204488) (xy 124.297948 -348.204028)
			(xy 125.161548 -348.204028) (xy 125.188814 -348.204538) (xy 125.242791 -348.212305) (xy 125.295114 -348.227674)
			(xy 125.344717 -348.250332) (xy 125.39059 -348.279819) (xy 125.431801 -348.315533) (xy 125.46751 -348.356748)
			(xy 125.496991 -348.402626) (xy 125.519643 -348.452231) (xy 125.535006 -348.504556) (xy 125.542766 -348.558534)
			(xy 125.542766 -348.613066) (xy 125.542765 -348.613072) (xy 127.025592 -348.613072) (xy 127.025592 -348.558528)
			(xy 127.033354 -348.504539) (xy 127.048721 -348.452204) (xy 127.07138 -348.402589) (xy 127.100869 -348.356704)
			(xy 127.136588 -348.315483) (xy 127.17781 -348.279764) (xy 127.223696 -348.250276) (xy 127.273312 -348.227618)
			(xy 127.325647 -348.212252) (xy 127.379636 -348.204491) (xy 127.406908 -348.204028) (xy 128.270508 -348.204028)
			(xy 128.297776 -348.204535) (xy 128.351758 -348.212297) (xy 128.404085 -348.227663) (xy 128.453693 -348.250319)
			(xy 128.499571 -348.279804) (xy 128.540787 -348.315519) (xy 128.5765 -348.356735) (xy 128.605985 -348.402614)
			(xy 128.62864 -348.452223) (xy 128.644004 -348.50455) (xy 128.651766 -348.558532) (xy 128.651766 -348.613068)
			(xy 128.651766 -348.613069) (xy 130.134614 -348.613069) (xy 130.134614 -348.558531) (xy 130.142375 -348.504549)
			(xy 130.15774 -348.452221) (xy 130.180394 -348.402611) (xy 130.209878 -348.356731) (xy 130.24559 -348.315513)
			(xy 130.286805 -348.279797) (xy 130.332683 -348.250309) (xy 130.382291 -348.227651) (xy 130.434618 -348.212282)
			(xy 130.488599 -348.204517) (xy 130.515868 -348.204028) (xy 131.379468 -348.204028) (xy 131.40674 -348.204509)
			(xy 131.460729 -348.212268) (xy 131.513064 -348.227631) (xy 131.56268 -348.250286) (xy 131.608566 -348.279772)
			(xy 131.649789 -348.315488) (xy 131.685509 -348.356708) (xy 131.714999 -348.402592) (xy 131.737658 -348.452206)
			(xy 131.753026 -348.50454) (xy 131.760788 -348.558528) (xy 131.760788 -348.613072) (xy 131.760788 -348.613073)
			(xy 133.243492 -348.613073) (xy 133.243492 -348.558527) (xy 133.251255 -348.504536) (xy 133.266623 -348.4522)
			(xy 133.289283 -348.402584) (xy 133.318774 -348.356697) (xy 133.354495 -348.315476) (xy 133.39572 -348.279757)
			(xy 133.441608 -348.25027) (xy 133.491226 -348.227613) (xy 133.543564 -348.212249) (xy 133.597555 -348.20449)
			(xy 133.624828 -348.204028) (xy 134.488428 -348.204028) (xy 134.515695 -348.204536) (xy 134.569675 -348.212301)
			(xy 134.621999 -348.227668) (xy 134.671605 -348.250326) (xy 134.717481 -348.279811) (xy 134.758694 -348.315526)
			(xy 134.794405 -348.356742) (xy 134.823888 -348.40262) (xy 134.846541 -348.452227) (xy 134.861905 -348.504553)
			(xy 134.869666 -348.558533) (xy 134.869666 -348.613067) (xy 134.869666 -348.61307) (xy 136.352514 -348.61307)
			(xy 136.352514 -348.55853) (xy 136.360276 -348.504546) (xy 136.375641 -348.452217) (xy 136.398297 -348.402606)
			(xy 136.427783 -348.356724) (xy 136.463497 -348.315506) (xy 136.504715 -348.27979) (xy 136.550595 -348.250303)
			(xy 136.600205 -348.227645) (xy 136.652535 -348.212279) (xy 136.706518 -348.204515) (xy 136.733788 -348.204028)
			(xy 137.597388 -348.204028) (xy 137.624659 -348.204511) (xy 137.678646 -348.212271) (xy 137.730978 -348.227636)
			(xy 137.780592 -348.250292) (xy 137.826476 -348.279779) (xy 137.867696 -348.315495) (xy 137.903414 -348.356715)
			(xy 137.932902 -348.402598) (xy 137.95556 -348.45221) (xy 137.970926 -348.504543) (xy 137.978689 -348.558529)
			(xy 137.978689 -348.613071) (xy 137.978689 -348.613074) (xy 139.461392 -348.613074) (xy 139.461392 -348.558526)
			(xy 139.469155 -348.504534) (xy 139.484524 -348.452196) (xy 139.507186 -348.402578) (xy 139.536679 -348.356691)
			(xy 139.572402 -348.315468) (xy 139.613629 -348.27975) (xy 139.65952 -348.250263) (xy 139.709141 -348.227608)
			(xy 139.761481 -348.212245) (xy 139.815474 -348.204488) (xy 139.842748 -348.204028) (xy 140.706348 -348.204028)
			(xy 140.733614 -348.204538) (xy 140.787591 -348.212305) (xy 140.839914 -348.227674) (xy 140.889517 -348.250332)
			(xy 140.93539 -348.279819) (xy 140.976601 -348.315533) (xy 141.01231 -348.356748) (xy 141.041791 -348.402626)
			(xy 141.064443 -348.452231) (xy 141.079806 -348.504556) (xy 141.087566 -348.558534) (xy 141.087566 -348.613066)
			(xy 141.087565 -348.613072) (xy 142.570392 -348.613072) (xy 142.570392 -348.558528) (xy 142.578154 -348.504539)
			(xy 142.593521 -348.452204) (xy 142.61618 -348.402589) (xy 142.645669 -348.356704) (xy 142.681388 -348.315483)
			(xy 142.72261 -348.279764) (xy 142.768496 -348.250276) (xy 142.818112 -348.227618) (xy 142.870447 -348.212252)
			(xy 142.924436 -348.204491) (xy 142.951708 -348.204028) (xy 143.815308 -348.204028) (xy 143.842576 -348.204535)
			(xy 143.896558 -348.212297) (xy 143.948885 -348.227663) (xy 143.998493 -348.250319) (xy 144.044371 -348.279804)
			(xy 144.085587 -348.315519) (xy 144.1213 -348.356735) (xy 144.150785 -348.402614) (xy 144.17344 -348.452223)
			(xy 144.188804 -348.50455) (xy 144.196566 -348.558532) (xy 144.196566 -348.613068) (xy 144.196565 -348.613072)
			(xy 161.804792 -348.613072) (xy 161.804792 -348.558528) (xy 161.812554 -348.504538) (xy 161.827921 -348.452203)
			(xy 161.850581 -348.402588) (xy 161.88007 -348.356703) (xy 161.91579 -348.315481) (xy 161.957012 -348.279763)
			(xy 162.002899 -348.250275) (xy 162.052515 -348.227617) (xy 162.10485 -348.212252) (xy 162.15884 -348.204491)
			(xy 162.186112 -348.204028) (xy 163.049712 -348.204028) (xy 163.07698 -348.204535) (xy 163.130961 -348.212298)
			(xy 163.183288 -348.227664) (xy 163.232895 -348.25032) (xy 163.278773 -348.279806) (xy 163.319988 -348.31552)
			(xy 163.355701 -348.356736) (xy 163.385185 -348.402615) (xy 163.40784 -348.452224) (xy 163.423204 -348.504551)
			(xy 163.430966 -348.558532) (xy 163.430966 -348.613068) (xy 163.430966 -348.613069) (xy 164.913814 -348.613069)
			(xy 164.913814 -348.558531) (xy 164.921576 -348.504549) (xy 164.93694 -348.45222) (xy 164.959595 -348.40261)
			(xy 164.989079 -348.35673) (xy 165.024792 -348.315512) (xy 165.066007 -348.279795) (xy 165.111886 -348.250308)
			(xy 165.161494 -348.22765) (xy 165.213821 -348.212281) (xy 165.267803 -348.204516) (xy 165.295072 -348.204028)
			(xy 166.158672 -348.204028) (xy 166.185944 -348.20451) (xy 166.239932 -348.212268) (xy 166.292267 -348.227632)
			(xy 166.341882 -348.250287) (xy 166.387768 -348.279773) (xy 166.42899 -348.31549) (xy 166.46471 -348.356709)
			(xy 166.494199 -348.402593) (xy 166.516859 -348.452207) (xy 166.532226 -348.504541) (xy 166.539988 -348.558528)
			(xy 166.539988 -348.613072) (xy 166.539988 -348.613073) (xy 168.022692 -348.613073) (xy 168.022692 -348.558527)
			(xy 168.030455 -348.504536) (xy 168.045823 -348.452199) (xy 168.068484 -348.402583) (xy 168.097975 -348.356696)
			(xy 168.133697 -348.315474) (xy 168.174922 -348.279756) (xy 168.220811 -348.250268) (xy 168.270429 -348.227612)
			(xy 168.322767 -348.212248) (xy 168.376759 -348.204489) (xy 168.404032 -348.204028) (xy 169.267632 -348.204028)
			(xy 169.294899 -348.204537) (xy 169.348878 -348.212302) (xy 169.401202 -348.227669) (xy 169.450807 -348.250327)
			(xy 169.496683 -348.279813) (xy 169.537895 -348.315527) (xy 169.573606 -348.356743) (xy 169.603088 -348.402621)
			(xy 169.625742 -348.452228) (xy 169.641105 -348.504553) (xy 169.648866 -348.558533) (xy 169.648866 -348.613067)
			(xy 169.648866 -348.61307) (xy 171.131714 -348.61307) (xy 171.131714 -348.55853) (xy 171.139476 -348.504546)
			(xy 171.154841 -348.452216) (xy 171.177498 -348.402605) (xy 171.206984 -348.356723) (xy 171.242699 -348.315505)
			(xy 171.283917 -348.279788) (xy 171.329798 -348.250301) (xy 171.379408 -348.227644) (xy 171.431738 -348.212278)
			(xy 171.485722 -348.204515) (xy 171.512992 -348.204028) (xy 172.376592 -348.204028) (xy 172.403863 -348.204511)
			(xy 172.457849 -348.212272) (xy 172.510181 -348.227637) (xy 172.559794 -348.250294) (xy 172.605678 -348.27978)
			(xy 172.646898 -348.315497) (xy 172.682615 -348.356716) (xy 172.712103 -348.402599) (xy 172.73476 -348.452211)
			(xy 172.750126 -348.504543) (xy 172.757889 -348.558529) (xy 172.757889 -348.613068) (xy 174.240714 -348.613068)
			(xy 174.240714 -348.558532) (xy 174.248475 -348.504551) (xy 174.263838 -348.452224) (xy 174.286492 -348.402616)
			(xy 174.315974 -348.356736) (xy 174.351685 -348.315519) (xy 174.392898 -348.279803) (xy 174.438774 -348.250315)
			(xy 174.488379 -348.227655) (xy 174.540704 -348.212285) (xy 174.594684 -348.204518) (xy 174.621952 -348.204028)
			(xy 175.485552 -348.204028) (xy 175.512825 -348.204508) (xy 175.566815 -348.212265) (xy 175.619152 -348.227626)
			(xy 175.66877 -348.250281) (xy 175.714659 -348.279766) (xy 175.755883 -348.315483) (xy 175.791605 -348.356703)
			(xy 175.821096 -348.402588) (xy 175.843757 -348.452203) (xy 175.859125 -348.504538) (xy 175.866888 -348.558528)
			(xy 175.866888 -348.613072) (xy 177.349592 -348.613072) (xy 177.349592 -348.558528) (xy 177.357354 -348.504538)
			(xy 177.372721 -348.452203) (xy 177.395381 -348.402588) (xy 177.42487 -348.356703) (xy 177.46059 -348.315481)
			(xy 177.501812 -348.279763) (xy 177.547699 -348.250275) (xy 177.597315 -348.227617) (xy 177.64965 -348.212252)
			(xy 177.70364 -348.204491) (xy 177.730912 -348.204028) (xy 178.594512 -348.204028) (xy 178.62178 -348.204535)
			(xy 178.675761 -348.212298) (xy 178.728088 -348.227664) (xy 178.777695 -348.25032) (xy 178.823573 -348.279806)
			(xy 178.864788 -348.31552) (xy 178.900501 -348.356736) (xy 178.929985 -348.402615) (xy 178.95264 -348.452224)
			(xy 178.968004 -348.504551) (xy 178.975766 -348.558532) (xy 178.975766 -348.613068) (xy 178.975766 -348.613069)
			(xy 180.458614 -348.613069) (xy 180.458614 -348.558531) (xy 180.466376 -348.504549) (xy 180.48174 -348.45222)
			(xy 180.504395 -348.40261) (xy 180.533879 -348.35673) (xy 180.569592 -348.315512) (xy 180.610807 -348.279795)
			(xy 180.656686 -348.250308) (xy 180.706294 -348.22765) (xy 180.758621 -348.212281) (xy 180.812603 -348.204516)
			(xy 180.839872 -348.204028) (xy 181.703472 -348.204028) (xy 181.730744 -348.20451) (xy 181.784732 -348.212268)
			(xy 181.837067 -348.227632) (xy 181.886682 -348.250287) (xy 181.932568 -348.279773) (xy 181.97379 -348.31549)
			(xy 182.00951 -348.356709) (xy 182.038999 -348.402593) (xy 182.061659 -348.452207) (xy 182.077026 -348.504541)
			(xy 182.084788 -348.558528) (xy 182.084788 -348.613072) (xy 182.084788 -348.613073) (xy 183.567492 -348.613073)
			(xy 183.567492 -348.558527) (xy 183.575255 -348.504536) (xy 183.590623 -348.452199) (xy 183.613284 -348.402583)
			(xy 183.642775 -348.356696) (xy 183.678497 -348.315474) (xy 183.719722 -348.279756) (xy 183.765611 -348.250268)
			(xy 183.815229 -348.227612) (xy 183.867567 -348.212248) (xy 183.921559 -348.204489) (xy 183.948832 -348.204028)
			(xy 184.812432 -348.204028) (xy 184.839699 -348.204537) (xy 184.893678 -348.212302) (xy 184.946002 -348.227669)
			(xy 184.995607 -348.250327) (xy 185.041483 -348.279813) (xy 185.082695 -348.315527) (xy 185.118406 -348.356743)
			(xy 185.147888 -348.402621) (xy 185.170542 -348.452228) (xy 185.185905 -348.504553) (xy 185.193666 -348.558533)
			(xy 185.193666 -348.613067) (xy 185.193666 -348.61307) (xy 186.676514 -348.61307) (xy 186.676514 -348.55853)
			(xy 186.684276 -348.504546) (xy 186.699641 -348.452216) (xy 186.722298 -348.402605) (xy 186.751784 -348.356723)
			(xy 186.787499 -348.315505) (xy 186.828717 -348.279788) (xy 186.874598 -348.250301) (xy 186.924208 -348.227644)
			(xy 186.976538 -348.212278) (xy 187.030522 -348.204515) (xy 187.057792 -348.204028) (xy 187.921392 -348.204028)
			(xy 187.948663 -348.204511) (xy 188.002649 -348.212272) (xy 188.054981 -348.227637) (xy 188.104594 -348.250294)
			(xy 188.150478 -348.27978) (xy 188.191698 -348.315497) (xy 188.227415 -348.356716) (xy 188.256903 -348.402599)
			(xy 188.27956 -348.452211) (xy 188.294926 -348.504543) (xy 188.302689 -348.558529) (xy 188.302689 -348.613068)
			(xy 189.785514 -348.613068) (xy 189.785514 -348.558532) (xy 189.793275 -348.504551) (xy 189.808638 -348.452224)
			(xy 189.831292 -348.402616) (xy 189.860774 -348.356736) (xy 189.896485 -348.315519) (xy 189.937698 -348.279803)
			(xy 189.983574 -348.250315) (xy 190.033179 -348.227655) (xy 190.085504 -348.212285) (xy 190.139484 -348.204518)
			(xy 190.166752 -348.204028) (xy 191.030352 -348.204028) (xy 191.057625 -348.204508) (xy 191.111615 -348.212265)
			(xy 191.163952 -348.227626) (xy 191.21357 -348.250281) (xy 191.259459 -348.279766) (xy 191.300683 -348.315483)
			(xy 191.336405 -348.356703) (xy 191.365896 -348.402588) (xy 191.388557 -348.452203) (xy 191.403925 -348.504538)
			(xy 191.411688 -348.558528) (xy 191.411688 -348.613072) (xy 192.894392 -348.613072) (xy 192.894392 -348.558528)
			(xy 192.902154 -348.504538) (xy 192.917521 -348.452203) (xy 192.940181 -348.402588) (xy 192.96967 -348.356703)
			(xy 193.00539 -348.315481) (xy 193.046612 -348.279763) (xy 193.092499 -348.250275) (xy 193.142115 -348.227617)
			(xy 193.19445 -348.212252) (xy 193.24844 -348.204491) (xy 193.275712 -348.204028) (xy 194.139312 -348.204028)
			(xy 194.16658 -348.204535) (xy 194.220561 -348.212298) (xy 194.272888 -348.227664) (xy 194.322495 -348.25032)
			(xy 194.368373 -348.279806) (xy 194.409588 -348.31552) (xy 194.445301 -348.356736) (xy 194.474785 -348.402615)
			(xy 194.49744 -348.452224) (xy 194.512804 -348.504551) (xy 194.520566 -348.558532) (xy 194.520566 -348.613068)
			(xy 194.520565 -348.613072) (xy 267.515792 -348.613072) (xy 267.515792 -348.558528) (xy 267.523554 -348.50454)
			(xy 267.538921 -348.452206) (xy 267.561579 -348.402591) (xy 267.591068 -348.356706) (xy 267.626786 -348.315485)
			(xy 267.668008 -348.279766) (xy 267.713893 -348.250278) (xy 267.763507 -348.22762) (xy 267.815842 -348.212253)
			(xy 267.86983 -348.204491) (xy 267.897102 -348.204028) (xy 268.760702 -348.204028) (xy 268.787971 -348.204535)
			(xy 268.841953 -348.212296) (xy 268.89428 -348.227661) (xy 268.943889 -348.250317) (xy 268.989769 -348.279802)
			(xy 269.030985 -348.315517) (xy 269.066699 -348.356733) (xy 269.096184 -348.402613) (xy 269.118839 -348.452221)
			(xy 269.134204 -348.504549) (xy 269.141966 -348.558531) (xy 269.141966 -348.613068) (xy 270.624814 -348.613068)
			(xy 270.624814 -348.558532) (xy 270.632575 -348.50455) (xy 270.647939 -348.452222) (xy 270.670593 -348.402613)
			(xy 270.700076 -348.356733) (xy 270.735788 -348.315515) (xy 270.777002 -348.279799) (xy 270.82288 -348.250311)
			(xy 270.872486 -348.227652) (xy 270.924813 -348.212283) (xy 270.978794 -348.204517) (xy 271.006062 -348.204028)
			(xy 271.869662 -348.204028) (xy 271.896934 -348.204509) (xy 271.950924 -348.212266) (xy 272.00326 -348.227629)
			(xy 272.052876 -348.250284) (xy 272.098763 -348.27977) (xy 272.139987 -348.315486) (xy 272.175708 -348.356706)
			(xy 272.205198 -348.40259) (xy 272.227858 -348.452205) (xy 272.243226 -348.504539) (xy 272.250988 -348.558528)
			(xy 272.250988 -348.613072) (xy 272.250988 -348.613073) (xy 273.733692 -348.613073) (xy 273.733692 -348.558527)
			(xy 273.741454 -348.504537) (xy 273.756822 -348.452201) (xy 273.779482 -348.402585) (xy 273.808972 -348.356699)
			(xy 273.844693 -348.315478) (xy 273.885917 -348.279759) (xy 273.931805 -348.250271) (xy 273.981422 -348.227615)
			(xy 274.033759 -348.21225) (xy 274.087749 -348.20449) (xy 274.115022 -348.204028) (xy 274.978622 -348.204028)
			(xy 275.00589 -348.204536) (xy 275.059869 -348.2123) (xy 275.112195 -348.227667) (xy 275.161801 -348.250324)
			(xy 275.207678 -348.279809) (xy 275.248892 -348.315524) (xy 275.284604 -348.35674) (xy 275.314087 -348.402618)
			(xy 275.336741 -348.452226) (xy 275.352105 -348.504552) (xy 275.359866 -348.558532) (xy 275.359866 -348.613068)
			(xy 275.359866 -348.613069) (xy 276.842714 -348.613069) (xy 276.842714 -348.558531) (xy 276.850476 -348.504547)
			(xy 276.865841 -348.452218) (xy 276.888496 -348.402608) (xy 276.917981 -348.356726) (xy 276.953695 -348.315508)
			(xy 276.994912 -348.279792) (xy 277.040792 -348.250305) (xy 277.090401 -348.227647) (xy 277.14273 -348.21228)
			(xy 277.196713 -348.204516) (xy 277.223982 -348.204028) (xy 278.087582 -348.204028) (xy 278.114853 -348.20451)
			(xy 278.168841 -348.21227) (xy 278.221174 -348.227634) (xy 278.270788 -348.25029) (xy 278.316673 -348.279777)
			(xy 278.357894 -348.315493) (xy 278.393612 -348.356713) (xy 278.423101 -348.402596) (xy 278.445759 -348.452209)
			(xy 278.461126 -348.504542) (xy 278.468888 -348.558529) (xy 278.468888 -348.613071) (xy 278.468888 -348.613074)
			(xy 279.951592 -348.613074) (xy 279.951592 -348.558526) (xy 279.959355 -348.504534) (xy 279.974724 -348.452197)
			(xy 279.997385 -348.40258) (xy 280.026877 -348.356693) (xy 280.0626 -348.315471) (xy 280.103827 -348.279752)
			(xy 280.149717 -348.250265) (xy 280.199336 -348.227609) (xy 280.251676 -348.212246) (xy 280.305668 -348.204489)
			(xy 280.332942 -348.204028) (xy 281.196542 -348.204028) (xy 281.223809 -348.204537) (xy 281.277786 -348.212304)
			(xy 281.330109 -348.227672) (xy 281.379713 -348.25033) (xy 281.425587 -348.279816) (xy 281.466799 -348.315531)
			(xy 281.502509 -348.356746) (xy 281.53199 -348.402624) (xy 281.554643 -348.45223) (xy 281.570005 -348.504555)
			(xy 281.577766 -348.558533) (xy 281.577766 -348.613067) (xy 281.577765 -348.613072) (xy 283.060592 -348.613072)
			(xy 283.060592 -348.558528) (xy 283.068354 -348.50454) (xy 283.083721 -348.452206) (xy 283.106379 -348.402591)
			(xy 283.135868 -348.356706) (xy 283.171586 -348.315485) (xy 283.212808 -348.279766) (xy 283.258693 -348.250278)
			(xy 283.308307 -348.22762) (xy 283.360642 -348.212253) (xy 283.41463 -348.204491) (xy 283.441902 -348.204028)
			(xy 284.305502 -348.204028) (xy 284.332771 -348.204535) (xy 284.386753 -348.212296) (xy 284.43908 -348.227661)
			(xy 284.488689 -348.250317) (xy 284.534569 -348.279802) (xy 284.575785 -348.315517) (xy 284.611499 -348.356733)
			(xy 284.640984 -348.402613) (xy 284.663639 -348.452221) (xy 284.679004 -348.504549) (xy 284.686766 -348.558531)
			(xy 284.686766 -348.613068) (xy 286.169614 -348.613068) (xy 286.169614 -348.558532) (xy 286.177375 -348.50455)
			(xy 286.192739 -348.452222) (xy 286.215393 -348.402613) (xy 286.244876 -348.356733) (xy 286.280588 -348.315515)
			(xy 286.321802 -348.279799) (xy 286.36768 -348.250311) (xy 286.417286 -348.227652) (xy 286.469613 -348.212283)
			(xy 286.523594 -348.204517) (xy 286.550862 -348.204028) (xy 287.414462 -348.204028) (xy 287.441734 -348.204509)
			(xy 287.495724 -348.212266) (xy 287.54806 -348.227629) (xy 287.597676 -348.250284) (xy 287.643563 -348.27977)
			(xy 287.684787 -348.315486) (xy 287.720508 -348.356706) (xy 287.749998 -348.40259) (xy 287.772658 -348.452205)
			(xy 287.788026 -348.504539) (xy 287.795788 -348.558528) (xy 287.795788 -348.613072) (xy 287.795788 -348.613073)
			(xy 289.278492 -348.613073) (xy 289.278492 -348.558527) (xy 289.286254 -348.504537) (xy 289.301622 -348.452201)
			(xy 289.324282 -348.402585) (xy 289.353772 -348.356699) (xy 289.389493 -348.315478) (xy 289.430717 -348.279759)
			(xy 289.476605 -348.250271) (xy 289.526222 -348.227615) (xy 289.578559 -348.21225) (xy 289.632549 -348.20449)
			(xy 289.659822 -348.204028) (xy 290.523422 -348.204028) (xy 290.55069 -348.204536) (xy 290.604669 -348.2123)
			(xy 290.656995 -348.227667) (xy 290.706601 -348.250324) (xy 290.752478 -348.279809) (xy 290.793692 -348.315524)
			(xy 290.829404 -348.35674) (xy 290.858887 -348.402618) (xy 290.881541 -348.452226) (xy 290.896905 -348.504552)
			(xy 290.904666 -348.558532) (xy 290.904666 -348.613068) (xy 290.904666 -348.613069) (xy 292.387514 -348.613069)
			(xy 292.387514 -348.558531) (xy 292.395276 -348.504547) (xy 292.410641 -348.452218) (xy 292.433296 -348.402608)
			(xy 292.462781 -348.356726) (xy 292.498495 -348.315508) (xy 292.539712 -348.279792) (xy 292.585592 -348.250305)
			(xy 292.635201 -348.227647) (xy 292.68753 -348.21228) (xy 292.741513 -348.204516) (xy 292.768782 -348.204028)
			(xy 293.632382 -348.204028) (xy 293.659653 -348.20451) (xy 293.713641 -348.21227) (xy 293.765974 -348.227634)
			(xy 293.815588 -348.25029) (xy 293.861473 -348.279777) (xy 293.902694 -348.315493) (xy 293.938412 -348.356713)
			(xy 293.967901 -348.402596) (xy 293.990559 -348.452209) (xy 294.005926 -348.504542) (xy 294.013688 -348.558529)
			(xy 294.013688 -348.613071) (xy 294.013688 -348.613074) (xy 295.496392 -348.613074) (xy 295.496392 -348.558526)
			(xy 295.504155 -348.504534) (xy 295.519524 -348.452197) (xy 295.542185 -348.40258) (xy 295.571677 -348.356693)
			(xy 295.6074 -348.315471) (xy 295.648627 -348.279752) (xy 295.694517 -348.250265) (xy 295.744136 -348.227609)
			(xy 295.796476 -348.212246) (xy 295.850468 -348.204489) (xy 295.877742 -348.204028) (xy 296.741342 -348.204028)
			(xy 296.768609 -348.204537) (xy 296.822586 -348.212304) (xy 296.874909 -348.227672) (xy 296.924513 -348.25033)
			(xy 296.970387 -348.279816) (xy 297.011599 -348.315531) (xy 297.047309 -348.356746) (xy 297.07679 -348.402624)
			(xy 297.099443 -348.45223) (xy 297.114805 -348.504555) (xy 297.122566 -348.558533) (xy 297.122566 -348.613067)
			(xy 297.122565 -348.613072) (xy 298.605392 -348.613072) (xy 298.605392 -348.558528) (xy 298.613154 -348.50454)
			(xy 298.628521 -348.452206) (xy 298.651179 -348.402591) (xy 298.680668 -348.356706) (xy 298.716386 -348.315485)
			(xy 298.757608 -348.279766) (xy 298.803493 -348.250278) (xy 298.853107 -348.22762) (xy 298.905442 -348.212253)
			(xy 298.95943 -348.204491) (xy 298.986702 -348.204028) (xy 299.850302 -348.204028) (xy 299.877571 -348.204535)
			(xy 299.931553 -348.212296) (xy 299.98388 -348.227661) (xy 300.033489 -348.250317) (xy 300.079369 -348.279802)
			(xy 300.120585 -348.315517) (xy 300.156299 -348.356733) (xy 300.185784 -348.402613) (xy 300.208439 -348.452221)
			(xy 300.223804 -348.504549) (xy 300.231566 -348.558531) (xy 300.231566 -348.613069) (xy 300.231566 -348.613072)
			(xy 312.121492 -348.613072) (xy 312.121492 -348.558528) (xy 312.129254 -348.504539) (xy 312.144621 -348.452205)
			(xy 312.167279 -348.40259) (xy 312.196768 -348.356705) (xy 312.232487 -348.315484) (xy 312.273709 -348.279766)
			(xy 312.319594 -348.250277) (xy 312.369209 -348.227619) (xy 312.421543 -348.212253) (xy 312.475532 -348.204491)
			(xy 312.502804 -348.204028) (xy 313.366404 -348.204028) (xy 313.393672 -348.204535) (xy 313.447654 -348.212297)
			(xy 313.499982 -348.227662) (xy 313.54959 -348.250318) (xy 313.595469 -348.279803) (xy 313.636686 -348.315517)
			(xy 313.672399 -348.356734) (xy 313.701884 -348.402613) (xy 313.72454 -348.452222) (xy 313.739904 -348.50455)
			(xy 313.747666 -348.558532) (xy 313.747666 -348.613068) (xy 315.230514 -348.613068) (xy 315.230514 -348.558532)
			(xy 315.238275 -348.50455) (xy 315.253639 -348.452222) (xy 315.276293 -348.402613) (xy 315.305777 -348.356732)
			(xy 315.341489 -348.315514) (xy 315.382703 -348.279798) (xy 315.428581 -348.250311) (xy 315.478188 -348.227652)
			(xy 315.530514 -348.212283) (xy 315.584496 -348.204517) (xy 315.611764 -348.204028) (xy 316.475364 -348.204028)
			(xy 316.502636 -348.204509) (xy 316.556625 -348.212267) (xy 316.608961 -348.22763) (xy 316.658577 -348.250284)
			(xy 316.704464 -348.27977) (xy 316.745688 -348.315487) (xy 316.781408 -348.356707) (xy 316.810898 -348.402591)
			(xy 316.833558 -348.452205) (xy 316.848926 -348.504539) (xy 316.856688 -348.558528) (xy 316.856688 -348.613072)
			(xy 316.856688 -348.613073) (xy 318.339392 -348.613073) (xy 318.339392 -348.558527) (xy 318.347155 -348.504537)
			(xy 318.362522 -348.452201) (xy 318.385182 -348.402585) (xy 318.414673 -348.356699) (xy 318.450394 -348.315477)
			(xy 318.491618 -348.279759) (xy 318.537506 -348.250271) (xy 318.587123 -348.227614) (xy 318.63946 -348.212249)
			(xy 318.693451 -348.20449) (xy 318.720724 -348.204028) (xy 319.584324 -348.204028) (xy 319.611592 -348.204536)
			(xy 319.665571 -348.2123) (xy 319.717896 -348.227667) (xy 319.767502 -348.250324) (xy 319.813379 -348.27981)
			(xy 319.854593 -348.315524) (xy 319.890304 -348.35674) (xy 319.919787 -348.402619) (xy 319.942441 -348.452226)
			(xy 319.957805 -348.504552) (xy 319.965566 -348.558532) (xy 319.965566 -348.613068) (xy 319.965566 -348.613069)
			(xy 321.448414 -348.613069) (xy 321.448414 -348.558531) (xy 321.456176 -348.504547) (xy 321.471541 -348.452217)
			(xy 321.494196 -348.402607) (xy 321.523682 -348.356726) (xy 321.559396 -348.315507) (xy 321.600613 -348.279791)
			(xy 321.646493 -348.250304) (xy 321.696102 -348.227646) (xy 321.748431 -348.212279) (xy 321.802415 -348.204516)
			(xy 321.829684 -348.204028) (xy 322.693284 -348.204028) (xy 322.720555 -348.20451) (xy 322.774542 -348.21227)
			(xy 322.826875 -348.227635) (xy 322.876489 -348.250291) (xy 322.922374 -348.279777) (xy 322.963595 -348.315494)
			(xy 322.999313 -348.356713) (xy 323.028801 -348.402597) (xy 323.051459 -348.45221) (xy 323.066826 -348.504542)
			(xy 323.074588 -348.558529) (xy 323.074588 -348.613071) (xy 323.074588 -348.613074) (xy 324.557292 -348.613074)
			(xy 324.557292 -348.558526) (xy 324.565055 -348.504534) (xy 324.580424 -348.452197) (xy 324.603085 -348.402579)
			(xy 324.632578 -348.356692) (xy 324.668301 -348.31547) (xy 324.709527 -348.279751) (xy 324.755418 -348.250264)
			(xy 324.805038 -348.227609) (xy 324.857377 -348.212246) (xy 324.91137 -348.204489) (xy 324.938644 -348.204028)
			(xy 325.802244 -348.204028) (xy 325.829511 -348.204537) (xy 325.883488 -348.212304) (xy 325.935811 -348.227673)
			(xy 325.985414 -348.250331) (xy 326.031288 -348.279817) (xy 326.0725 -348.315531) (xy 326.108209 -348.356747)
			(xy 326.13769 -348.402624) (xy 326.160343 -348.45223) (xy 326.175705 -348.504555) (xy 326.183466 -348.558533)
			(xy 326.183466 -348.613067) (xy 326.183465 -348.613072) (xy 327.666292 -348.613072) (xy 327.666292 -348.558528)
			(xy 327.674054 -348.504539) (xy 327.689421 -348.452205) (xy 327.712079 -348.40259) (xy 327.741568 -348.356705)
			(xy 327.777287 -348.315484) (xy 327.818509 -348.279766) (xy 327.864394 -348.250277) (xy 327.914009 -348.227619)
			(xy 327.966343 -348.212253) (xy 328.020332 -348.204491) (xy 328.047604 -348.204028) (xy 328.911204 -348.204028)
			(xy 328.938472 -348.204535) (xy 328.992454 -348.212297) (xy 329.044782 -348.227662) (xy 329.09439 -348.250318)
			(xy 329.140269 -348.279803) (xy 329.181486 -348.315517) (xy 329.217199 -348.356734) (xy 329.246684 -348.402613)
			(xy 329.26934 -348.452222) (xy 329.284704 -348.50455) (xy 329.292466 -348.558532) (xy 329.292466 -348.613068)
			(xy 330.775314 -348.613068) (xy 330.775314 -348.558532) (xy 330.783075 -348.50455) (xy 330.798439 -348.452222)
			(xy 330.821093 -348.402613) (xy 330.850577 -348.356732) (xy 330.886289 -348.315514) (xy 330.927503 -348.279798)
			(xy 330.973381 -348.250311) (xy 331.022988 -348.227652) (xy 331.075314 -348.212283) (xy 331.129296 -348.204517)
			(xy 331.156564 -348.204028) (xy 332.020164 -348.204028) (xy 332.047436 -348.204509) (xy 332.101425 -348.212267)
			(xy 332.153761 -348.22763) (xy 332.203377 -348.250284) (xy 332.249264 -348.27977) (xy 332.290488 -348.315487)
			(xy 332.326208 -348.356707) (xy 332.355698 -348.402591) (xy 332.378358 -348.452205) (xy 332.393726 -348.504539)
			(xy 332.401488 -348.558528) (xy 332.401488 -348.613072) (xy 332.401488 -348.613073) (xy 333.884192 -348.613073)
			(xy 333.884192 -348.558527) (xy 333.891955 -348.504537) (xy 333.907322 -348.452201) (xy 333.929982 -348.402585)
			(xy 333.959473 -348.356699) (xy 333.995194 -348.315477) (xy 334.036418 -348.279759) (xy 334.082306 -348.250271)
			(xy 334.131923 -348.227614) (xy 334.18426 -348.212249) (xy 334.238251 -348.20449) (xy 334.265524 -348.204028)
			(xy 335.129124 -348.204028) (xy 335.156392 -348.204536) (xy 335.210371 -348.2123) (xy 335.262696 -348.227667)
			(xy 335.312302 -348.250324) (xy 335.358179 -348.27981) (xy 335.399393 -348.315524) (xy 335.435104 -348.35674)
			(xy 335.464587 -348.402619) (xy 335.487241 -348.452226) (xy 335.502605 -348.504552) (xy 335.510366 -348.558532)
			(xy 335.510366 -348.613068) (xy 335.510366 -348.613069) (xy 336.993214 -348.613069) (xy 336.993214 -348.558531)
			(xy 337.000976 -348.504547) (xy 337.016341 -348.452217) (xy 337.038996 -348.402607) (xy 337.068482 -348.356726)
			(xy 337.104196 -348.315507) (xy 337.145413 -348.279791) (xy 337.191293 -348.250304) (xy 337.240902 -348.227646)
			(xy 337.293231 -348.212279) (xy 337.347215 -348.204516) (xy 337.374484 -348.204028) (xy 338.238084 -348.204028)
			(xy 338.265355 -348.20451) (xy 338.319342 -348.21227) (xy 338.371675 -348.227635) (xy 338.421289 -348.250291)
			(xy 338.467174 -348.279777) (xy 338.508395 -348.315494) (xy 338.544113 -348.356713) (xy 338.573601 -348.402597)
			(xy 338.596259 -348.45221) (xy 338.611626 -348.504542) (xy 338.619388 -348.558529) (xy 338.619388 -348.613071)
			(xy 338.619388 -348.613074) (xy 340.102092 -348.613074) (xy 340.102092 -348.558526) (xy 340.109855 -348.504534)
			(xy 340.125224 -348.452197) (xy 340.147885 -348.402579) (xy 340.177378 -348.356692) (xy 340.213101 -348.31547)
			(xy 340.254327 -348.279751) (xy 340.300218 -348.250264) (xy 340.349838 -348.227609) (xy 340.402177 -348.212246)
			(xy 340.45617 -348.204489) (xy 340.483444 -348.204028) (xy 341.347044 -348.204028) (xy 341.374311 -348.204537)
			(xy 341.428288 -348.212304) (xy 341.480611 -348.227673) (xy 341.530214 -348.250331) (xy 341.576088 -348.279817)
			(xy 341.6173 -348.315531) (xy 341.653009 -348.356747) (xy 341.68249 -348.402624) (xy 341.705143 -348.45223)
			(xy 341.720505 -348.504555) (xy 341.728266 -348.558533) (xy 341.728266 -348.613067) (xy 341.728265 -348.613072)
			(xy 343.211092 -348.613072) (xy 343.211092 -348.558528) (xy 343.218854 -348.504539) (xy 343.234221 -348.452205)
			(xy 343.256879 -348.40259) (xy 343.286368 -348.356705) (xy 343.322087 -348.315484) (xy 343.363309 -348.279766)
			(xy 343.409194 -348.250277) (xy 343.458809 -348.227619) (xy 343.511143 -348.212253) (xy 343.565132 -348.204491)
			(xy 343.592404 -348.204028) (xy 344.456004 -348.204028) (xy 344.483272 -348.204535) (xy 344.537254 -348.212297)
			(xy 344.589582 -348.227662) (xy 344.63919 -348.250318) (xy 344.685069 -348.279803) (xy 344.726286 -348.315517)
			(xy 344.761999 -348.356734) (xy 344.791484 -348.402613) (xy 344.81414 -348.452222) (xy 344.829504 -348.50455)
			(xy 344.837266 -348.558532) (xy 344.837266 -348.613068) (xy 344.837266 -348.613069) (xy 370.806714 -348.613069)
			(xy 370.806714 -348.558531) (xy 370.814476 -348.504548) (xy 370.82984 -348.452218) (xy 370.852496 -348.402608)
			(xy 370.881981 -348.356727) (xy 370.917695 -348.315509) (xy 370.958911 -348.279793) (xy 371.004791 -348.250305)
			(xy 371.054399 -348.227647) (xy 371.106728 -348.21228) (xy 371.160711 -348.204516) (xy 371.18798 -348.204028)
			(xy 372.05158 -348.204028) (xy 372.078851 -348.20451) (xy 372.132839 -348.21227) (xy 372.185173 -348.227634)
			(xy 372.234787 -348.25029) (xy 372.280672 -348.279776) (xy 372.321893 -348.315493) (xy 372.357612 -348.356712)
			(xy 372.387101 -348.402595) (xy 372.409759 -348.452209) (xy 372.425126 -348.504542) (xy 372.432888 -348.558529)
			(xy 372.432888 -348.613071) (xy 372.432888 -348.613074) (xy 373.915592 -348.613074) (xy 373.915592 -348.558526)
			(xy 373.923355 -348.504535) (xy 373.938724 -348.452197) (xy 373.961385 -348.40258) (xy 373.990877 -348.356694)
			(xy 374.0266 -348.315471) (xy 374.067826 -348.279753) (xy 374.113715 -348.250266) (xy 374.163335 -348.22761)
			(xy 374.215674 -348.212246) (xy 374.269666 -348.204489) (xy 374.29694 -348.204028) (xy 375.16054 -348.204028)
			(xy 375.187807 -348.204537) (xy 375.241785 -348.212303) (xy 375.294108 -348.227672) (xy 375.343712 -348.25033)
			(xy 375.389587 -348.279816) (xy 375.430798 -348.31553) (xy 375.466508 -348.356746) (xy 375.49599 -348.402623)
			(xy 375.518642 -348.45223) (xy 375.534005 -348.504554) (xy 375.541766 -348.558533) (xy 375.541766 -348.613067)
			(xy 375.541766 -348.61307) (xy 377.024614 -348.61307) (xy 377.024614 -348.55853) (xy 377.032376 -348.504545)
			(xy 377.047742 -348.452214) (xy 377.070399 -348.402603) (xy 377.099886 -348.35672) (xy 377.135602 -348.315502)
			(xy 377.17682 -348.279786) (xy 377.222703 -348.250299) (xy 377.272314 -348.227642) (xy 377.324645 -348.212276)
			(xy 377.37863 -348.204514) (xy 377.4059 -348.204028) (xy 378.2695 -348.204028) (xy 378.296769 -348.204534)
			(xy 378.350751 -348.212296) (xy 378.403079 -348.227661) (xy 378.452688 -348.250316) (xy 378.498568 -348.279802)
			(xy 378.539784 -348.315516) (xy 378.575498 -348.356732) (xy 378.604984 -348.402612) (xy 378.627639 -348.452221)
			(xy 378.643004 -348.504549) (xy 378.650766 -348.558531) (xy 378.650766 -348.613068) (xy 380.133614 -348.613068)
			(xy 380.133614 -348.558532) (xy 380.141375 -348.50455) (xy 380.156739 -348.452223) (xy 380.179393 -348.402614)
			(xy 380.208876 -348.356734) (xy 380.244588 -348.315516) (xy 380.285801 -348.2798) (xy 380.331679 -348.250312)
			(xy 380.381285 -348.227653) (xy 380.433611 -348.212284) (xy 380.487592 -348.204517) (xy 380.51486 -348.204028)
			(xy 381.37846 -348.204028) (xy 381.405732 -348.204509) (xy 381.459722 -348.212266) (xy 381.512058 -348.227628)
			(xy 381.561675 -348.250283) (xy 381.607562 -348.279769) (xy 381.648786 -348.315485) (xy 381.684507 -348.356706)
			(xy 381.713998 -348.40259) (xy 381.736658 -348.452204) (xy 381.752025 -348.504539) (xy 381.759788 -348.558528)
			(xy 381.759788 -348.613072) (xy 381.759788 -348.613073) (xy 383.242492 -348.613073) (xy 383.242492 -348.558527)
			(xy 383.250254 -348.504537) (xy 383.265622 -348.452202) (xy 383.288282 -348.402586) (xy 383.317772 -348.3567)
			(xy 383.353493 -348.315478) (xy 383.394716 -348.27976) (xy 383.440603 -348.250272) (xy 383.49022 -348.227615)
			(xy 383.542557 -348.21225) (xy 383.596547 -348.20449) (xy 383.62382 -348.204028) (xy 384.48742 -348.204028)
			(xy 384.514688 -348.204536) (xy 384.568668 -348.2123) (xy 384.620994 -348.227666) (xy 384.6706 -348.250323)
			(xy 384.716477 -348.279809) (xy 384.757691 -348.315523) (xy 384.793403 -348.356739) (xy 384.822887 -348.402618)
			(xy 384.845541 -348.452225) (xy 384.860905 -348.504552) (xy 384.868666 -348.558532) (xy 384.868666 -348.613068)
			(xy 384.868666 -348.613069) (xy 386.351514 -348.613069) (xy 386.351514 -348.558531) (xy 386.359276 -348.504548)
			(xy 386.37464 -348.452218) (xy 386.397296 -348.402608) (xy 386.426781 -348.356727) (xy 386.462495 -348.315509)
			(xy 386.503711 -348.279793) (xy 386.549591 -348.250305) (xy 386.599199 -348.227647) (xy 386.651528 -348.21228)
			(xy 386.705511 -348.204516) (xy 386.73278 -348.204028) (xy 387.59638 -348.204028) (xy 387.623651 -348.20451)
			(xy 387.677639 -348.21227) (xy 387.729973 -348.227634) (xy 387.779587 -348.25029) (xy 387.825472 -348.279776)
			(xy 387.866693 -348.315493) (xy 387.902412 -348.356712) (xy 387.931901 -348.402595) (xy 387.954559 -348.452209)
			(xy 387.969926 -348.504542) (xy 387.977688 -348.558529) (xy 387.977688 -348.613071) (xy 387.977688 -348.613074)
			(xy 389.460392 -348.613074) (xy 389.460392 -348.558526) (xy 389.468155 -348.504535) (xy 389.483524 -348.452197)
			(xy 389.506185 -348.40258) (xy 389.535677 -348.356694) (xy 389.5714 -348.315471) (xy 389.612626 -348.279753)
			(xy 389.658515 -348.250266) (xy 389.708135 -348.22761) (xy 389.760474 -348.212246) (xy 389.814466 -348.204489)
			(xy 389.84174 -348.204028) (xy 390.70534 -348.204028) (xy 390.732607 -348.204537) (xy 390.786585 -348.212303)
			(xy 390.838908 -348.227672) (xy 390.888512 -348.25033) (xy 390.934387 -348.279816) (xy 390.975598 -348.31553)
			(xy 391.011308 -348.356746) (xy 391.04079 -348.402623) (xy 391.063442 -348.45223) (xy 391.078805 -348.504554)
			(xy 391.086566 -348.558533) (xy 391.086566 -348.613067) (xy 391.086566 -348.61307) (xy 392.569414 -348.61307)
			(xy 392.569414 -348.55853) (xy 392.577176 -348.504545) (xy 392.592542 -348.452214) (xy 392.615199 -348.402603)
			(xy 392.644686 -348.35672) (xy 392.680402 -348.315502) (xy 392.72162 -348.279786) (xy 392.767503 -348.250299)
			(xy 392.817114 -348.227642) (xy 392.869445 -348.212276) (xy 392.92343 -348.204514) (xy 392.9507 -348.204028)
			(xy 393.8143 -348.204028) (xy 393.841569 -348.204534) (xy 393.895551 -348.212296) (xy 393.947879 -348.227661)
			(xy 393.997488 -348.250316) (xy 394.043368 -348.279802) (xy 394.084584 -348.315516) (xy 394.120298 -348.356732)
			(xy 394.149784 -348.402612) (xy 394.172439 -348.452221) (xy 394.187804 -348.504549) (xy 394.195566 -348.558531)
			(xy 394.195566 -348.613068) (xy 395.678414 -348.613068) (xy 395.678414 -348.558532) (xy 395.686175 -348.50455)
			(xy 395.701539 -348.452223) (xy 395.724193 -348.402614) (xy 395.753676 -348.356734) (xy 395.789388 -348.315516)
			(xy 395.830601 -348.2798) (xy 395.876479 -348.250312) (xy 395.926085 -348.227653) (xy 395.978411 -348.212284)
			(xy 396.032392 -348.204517) (xy 396.05966 -348.204028) (xy 396.92326 -348.204028) (xy 396.950532 -348.204509)
			(xy 397.004522 -348.212266) (xy 397.056858 -348.227628) (xy 397.106475 -348.250283) (xy 397.152362 -348.279769)
			(xy 397.193586 -348.315485) (xy 397.229307 -348.356706) (xy 397.258798 -348.40259) (xy 397.281458 -348.452204)
			(xy 397.296825 -348.504539) (xy 397.304588 -348.558528) (xy 397.304588 -348.613072) (xy 397.304588 -348.613073)
			(xy 398.787292 -348.613073) (xy 398.787292 -348.558527) (xy 398.795054 -348.504537) (xy 398.810422 -348.452202)
			(xy 398.833082 -348.402586) (xy 398.862572 -348.3567) (xy 398.898293 -348.315478) (xy 398.939516 -348.27976)
			(xy 398.985403 -348.250272) (xy 399.03502 -348.227615) (xy 399.087357 -348.21225) (xy 399.141347 -348.20449)
			(xy 399.16862 -348.204028) (xy 400.03222 -348.204028) (xy 400.059488 -348.204536) (xy 400.113468 -348.2123)
			(xy 400.165794 -348.227666) (xy 400.2154 -348.250323) (xy 400.261277 -348.279809) (xy 400.302491 -348.315523)
			(xy 400.338203 -348.356739) (xy 400.367687 -348.402618) (xy 400.390341 -348.452225) (xy 400.405705 -348.504552)
			(xy 400.413466 -348.558532) (xy 400.413466 -348.613068) (xy 400.413466 -348.613069) (xy 401.896314 -348.613069)
			(xy 401.896314 -348.558531) (xy 401.904076 -348.504548) (xy 401.91944 -348.452218) (xy 401.942096 -348.402608)
			(xy 401.971581 -348.356727) (xy 402.007295 -348.315509) (xy 402.048511 -348.279793) (xy 402.094391 -348.250305)
			(xy 402.143999 -348.227647) (xy 402.196328 -348.21228) (xy 402.250311 -348.204516) (xy 402.27758 -348.204028)
			(xy 403.14118 -348.204028) (xy 403.168451 -348.20451) (xy 403.222439 -348.21227) (xy 403.274773 -348.227634)
			(xy 403.324387 -348.25029) (xy 403.370272 -348.279776) (xy 403.411493 -348.315493) (xy 403.447212 -348.356712)
			(xy 403.476701 -348.402595) (xy 403.499359 -348.452209) (xy 403.514726 -348.504542) (xy 403.522488 -348.558529)
			(xy 403.522488 -348.61307) (xy 408.913814 -348.61307) (xy 408.913814 -348.55853) (xy 408.921576 -348.504546)
			(xy 408.936941 -348.452216) (xy 408.959598 -348.402605) (xy 408.989084 -348.356723) (xy 409.024799 -348.315505)
			(xy 409.066017 -348.279788) (xy 409.111898 -348.250301) (xy 409.161508 -348.227644) (xy 409.213838 -348.212278)
			(xy 409.267822 -348.204515) (xy 409.295092 -348.204028) (xy 410.158692 -348.204028) (xy 410.185963 -348.204511)
			(xy 410.239949 -348.212272) (xy 410.292281 -348.227637) (xy 410.341894 -348.250294) (xy 410.387778 -348.27978)
			(xy 410.428998 -348.315497) (xy 410.464715 -348.356716) (xy 410.494203 -348.402599) (xy 410.51686 -348.452211)
			(xy 410.532226 -348.504543) (xy 410.539989 -348.558529) (xy 410.539989 -348.613068) (xy 412.022814 -348.613068)
			(xy 412.022814 -348.558532) (xy 412.030575 -348.504551) (xy 412.045938 -348.452224) (xy 412.068592 -348.402616)
			(xy 412.098074 -348.356736) (xy 412.133785 -348.315519) (xy 412.174998 -348.279803) (xy 412.220874 -348.250315)
			(xy 412.270479 -348.227655) (xy 412.322804 -348.212285) (xy 412.376784 -348.204518) (xy 412.404052 -348.204028)
			(xy 413.267652 -348.204028) (xy 413.294925 -348.204508) (xy 413.348915 -348.212265) (xy 413.401252 -348.227626)
			(xy 413.45087 -348.250281) (xy 413.496759 -348.279766) (xy 413.537983 -348.315483) (xy 413.573705 -348.356703)
			(xy 413.603196 -348.402588) (xy 413.625857 -348.452203) (xy 413.641225 -348.504538) (xy 413.648988 -348.558528)
			(xy 413.648988 -348.613072) (xy 415.131692 -348.613072) (xy 415.131692 -348.558528) (xy 415.139454 -348.504538)
			(xy 415.154821 -348.452203) (xy 415.177481 -348.402588) (xy 415.20697 -348.356703) (xy 415.24269 -348.315481)
			(xy 415.283912 -348.279763) (xy 415.329799 -348.250275) (xy 415.379415 -348.227617) (xy 415.43175 -348.212252)
			(xy 415.48574 -348.204491) (xy 415.513012 -348.204028) (xy 416.376612 -348.204028) (xy 416.40388 -348.204535)
			(xy 416.457861 -348.212298) (xy 416.510188 -348.227664) (xy 416.559795 -348.25032) (xy 416.605673 -348.279806)
			(xy 416.646888 -348.31552) (xy 416.682601 -348.356736) (xy 416.712085 -348.402615) (xy 416.73474 -348.452224)
			(xy 416.750104 -348.504551) (xy 416.757866 -348.558532) (xy 416.757866 -348.613068) (xy 416.757866 -348.613069)
			(xy 418.240714 -348.613069) (xy 418.240714 -348.558531) (xy 418.248476 -348.504549) (xy 418.26384 -348.45222)
			(xy 418.286495 -348.40261) (xy 418.315979 -348.35673) (xy 418.351692 -348.315512) (xy 418.392907 -348.279795)
			(xy 418.438786 -348.250308) (xy 418.488394 -348.22765) (xy 418.540721 -348.212281) (xy 418.594703 -348.204516)
			(xy 418.621972 -348.204028) (xy 419.485572 -348.204028) (xy 419.512844 -348.20451) (xy 419.566832 -348.212268)
			(xy 419.619167 -348.227632) (xy 419.668782 -348.250287) (xy 419.714668 -348.279773) (xy 419.75589 -348.31549)
			(xy 419.79161 -348.356709) (xy 419.821099 -348.402593) (xy 419.843759 -348.452207) (xy 419.859126 -348.504541)
			(xy 419.866888 -348.558528) (xy 419.866888 -348.613072) (xy 419.866888 -348.613073) (xy 421.349592 -348.613073)
			(xy 421.349592 -348.558527) (xy 421.357355 -348.504536) (xy 421.372723 -348.452199) (xy 421.395384 -348.402583)
			(xy 421.424875 -348.356696) (xy 421.460597 -348.315474) (xy 421.501822 -348.279756) (xy 421.547711 -348.250268)
			(xy 421.597329 -348.227612) (xy 421.649667 -348.212248) (xy 421.703659 -348.204489) (xy 421.730932 -348.204028)
			(xy 422.594532 -348.204028) (xy 422.621799 -348.204537) (xy 422.675778 -348.212302) (xy 422.728102 -348.227669)
			(xy 422.777707 -348.250327) (xy 422.823583 -348.279813) (xy 422.864795 -348.315527) (xy 422.900506 -348.356743)
			(xy 422.929988 -348.402621) (xy 422.952642 -348.452228) (xy 422.968005 -348.504553) (xy 422.975766 -348.558533)
			(xy 422.975766 -348.613067) (xy 422.975766 -348.61307) (xy 424.458614 -348.61307) (xy 424.458614 -348.55853)
			(xy 424.466376 -348.504546) (xy 424.481741 -348.452216) (xy 424.504398 -348.402605) (xy 424.533884 -348.356723)
			(xy 424.569599 -348.315505) (xy 424.610817 -348.279788) (xy 424.656698 -348.250301) (xy 424.706308 -348.227644)
			(xy 424.758638 -348.212278) (xy 424.812622 -348.204515) (xy 424.839892 -348.204028) (xy 425.703492 -348.204028)
			(xy 425.730763 -348.204511) (xy 425.784749 -348.212272) (xy 425.837081 -348.227637) (xy 425.886694 -348.250294)
			(xy 425.932578 -348.27978) (xy 425.973798 -348.315497) (xy 426.009515 -348.356716) (xy 426.039003 -348.402599)
			(xy 426.06166 -348.452211) (xy 426.077026 -348.504543) (xy 426.084789 -348.558529) (xy 426.084789 -348.613068)
			(xy 427.567614 -348.613068) (xy 427.567614 -348.558532) (xy 427.575375 -348.504551) (xy 427.590738 -348.452224)
			(xy 427.613392 -348.402616) (xy 427.642874 -348.356736) (xy 427.678585 -348.315519) (xy 427.719798 -348.279803)
			(xy 427.765674 -348.250315) (xy 427.815279 -348.227655) (xy 427.867604 -348.212285) (xy 427.921584 -348.204518)
			(xy 427.948852 -348.204028) (xy 428.812452 -348.204028) (xy 428.839725 -348.204508) (xy 428.893715 -348.212265)
			(xy 428.946052 -348.227626) (xy 428.99567 -348.250281) (xy 429.041559 -348.279766) (xy 429.082783 -348.315483)
			(xy 429.118505 -348.356703) (xy 429.147996 -348.402588) (xy 429.170657 -348.452203) (xy 429.186025 -348.504538)
			(xy 429.193788 -348.558528) (xy 429.193788 -348.613072) (xy 430.676492 -348.613072) (xy 430.676492 -348.558528)
			(xy 430.684254 -348.504538) (xy 430.699621 -348.452203) (xy 430.722281 -348.402588) (xy 430.75177 -348.356703)
			(xy 430.78749 -348.315481) (xy 430.828712 -348.279763) (xy 430.874599 -348.250275) (xy 430.924215 -348.227617)
			(xy 430.97655 -348.212252) (xy 431.03054 -348.204491) (xy 431.057812 -348.204028) (xy 431.921412 -348.204028)
			(xy 431.94868 -348.204535) (xy 432.002661 -348.212298) (xy 432.054988 -348.227664) (xy 432.104595 -348.25032)
			(xy 432.150473 -348.279806) (xy 432.191688 -348.31552) (xy 432.227401 -348.356736) (xy 432.256885 -348.402615)
			(xy 432.27954 -348.452224) (xy 432.294904 -348.504551) (xy 432.302666 -348.558532) (xy 432.302666 -348.613068)
			(xy 432.302666 -348.613069) (xy 433.785514 -348.613069) (xy 433.785514 -348.558531) (xy 433.793276 -348.504549)
			(xy 433.80864 -348.45222) (xy 433.831295 -348.40261) (xy 433.860779 -348.35673) (xy 433.896492 -348.315512)
			(xy 433.937707 -348.279795) (xy 433.983586 -348.250308) (xy 434.033194 -348.22765) (xy 434.085521 -348.212281)
			(xy 434.139503 -348.204516) (xy 434.166772 -348.204028) (xy 435.030372 -348.204028) (xy 435.057644 -348.20451)
			(xy 435.111632 -348.212268) (xy 435.163967 -348.227632) (xy 435.213582 -348.250287) (xy 435.259468 -348.279773)
			(xy 435.30069 -348.31549) (xy 435.33641 -348.356709) (xy 435.365899 -348.402593) (xy 435.388559 -348.452207)
			(xy 435.403926 -348.504541) (xy 435.411688 -348.558528) (xy 435.411688 -348.613072) (xy 435.411688 -348.613073)
			(xy 436.894392 -348.613073) (xy 436.894392 -348.558527) (xy 436.902155 -348.504536) (xy 436.917523 -348.452199)
			(xy 436.940184 -348.402583) (xy 436.969675 -348.356696) (xy 437.005397 -348.315474) (xy 437.046622 -348.279756)
			(xy 437.092511 -348.250268) (xy 437.142129 -348.227612) (xy 437.194467 -348.212248) (xy 437.248459 -348.204489)
			(xy 437.275732 -348.204028) (xy 438.139332 -348.204028) (xy 438.166599 -348.204537) (xy 438.220578 -348.212302)
			(xy 438.272902 -348.227669) (xy 438.322507 -348.250327) (xy 438.368383 -348.279813) (xy 438.409595 -348.315527)
			(xy 438.445306 -348.356743) (xy 438.474788 -348.402621) (xy 438.497442 -348.452228) (xy 438.512805 -348.504553)
			(xy 438.520566 -348.558533) (xy 438.520566 -348.613067) (xy 438.520566 -348.61307) (xy 440.003414 -348.61307)
			(xy 440.003414 -348.55853) (xy 440.011176 -348.504546) (xy 440.026541 -348.452216) (xy 440.049198 -348.402605)
			(xy 440.078684 -348.356723) (xy 440.114399 -348.315505) (xy 440.155617 -348.279788) (xy 440.201498 -348.250301)
			(xy 440.251108 -348.227644) (xy 440.303438 -348.212278) (xy 440.357422 -348.204515) (xy 440.384692 -348.204028)
			(xy 441.248292 -348.204028) (xy 441.275563 -348.204511) (xy 441.329549 -348.212272) (xy 441.381881 -348.227637)
			(xy 441.431494 -348.250294) (xy 441.477378 -348.27978) (xy 441.518598 -348.315497) (xy 441.554315 -348.356716)
			(xy 441.583803 -348.402599) (xy 441.60646 -348.452211) (xy 441.621826 -348.504543) (xy 441.629589 -348.558529)
			(xy 441.629589 -348.613071) (xy 441.621826 -348.667057) (xy 441.60646 -348.719389) (xy 441.583803 -348.769001)
			(xy 441.554315 -348.814884) (xy 441.518598 -348.856103) (xy 441.477378 -348.89182) (xy 441.431494 -348.921306)
			(xy 441.381881 -348.943963) (xy 441.329549 -348.959328) (xy 441.275563 -348.967089) (xy 441.248292 -348.967552)
			(xy 440.384692 -348.967552) (xy 440.357422 -348.967085) (xy 440.303438 -348.959322) (xy 440.251108 -348.943956)
			(xy 440.201498 -348.921299) (xy 440.155617 -348.891812) (xy 440.114399 -348.856095) (xy 440.078684 -348.814877)
			(xy 440.049198 -348.768995) (xy 440.026541 -348.719384) (xy 440.011176 -348.667054) (xy 440.003414 -348.61307)
			(xy 438.520566 -348.61307) (xy 438.512805 -348.667047) (xy 438.497442 -348.719372) (xy 438.474788 -348.768979)
			(xy 438.445306 -348.814857) (xy 438.409595 -348.856073) (xy 438.368383 -348.891787) (xy 438.322507 -348.921273)
			(xy 438.272902 -348.943931) (xy 438.220578 -348.959298) (xy 438.166599 -348.967063) (xy 438.139332 -348.967552)
			(xy 437.275732 -348.967552) (xy 437.248459 -348.967111) (xy 437.194467 -348.959352) (xy 437.142129 -348.943988)
			(xy 437.092511 -348.921332) (xy 437.046622 -348.891844) (xy 437.005397 -348.856126) (xy 436.969675 -348.814904)
			(xy 436.940184 -348.769017) (xy 436.917523 -348.719401) (xy 436.902155 -348.667064) (xy 436.894392 -348.613073)
			(xy 435.411688 -348.613073) (xy 435.403926 -348.667059) (xy 435.388559 -348.719393) (xy 435.365899 -348.769007)
			(xy 435.33641 -348.814891) (xy 435.30069 -348.85611) (xy 435.259468 -348.891827) (xy 435.213582 -348.921313)
			(xy 435.163967 -348.943968) (xy 435.111632 -348.959332) (xy 435.057644 -348.96709) (xy 435.030372 -348.967552)
			(xy 434.166772 -348.967552) (xy 434.139503 -348.967084) (xy 434.085521 -348.959319) (xy 434.033194 -348.94395)
			(xy 433.983586 -348.921292) (xy 433.937707 -348.891805) (xy 433.896492 -348.856088) (xy 433.860779 -348.81487)
			(xy 433.831295 -348.76899) (xy 433.80864 -348.71938) (xy 433.793276 -348.667051) (xy 433.785514 -348.613069)
			(xy 432.302666 -348.613069) (xy 432.294904 -348.667049) (xy 432.27954 -348.719376) (xy 432.256885 -348.768985)
			(xy 432.227401 -348.814864) (xy 432.191688 -348.85608) (xy 432.150473 -348.891794) (xy 432.104595 -348.92128)
			(xy 432.054988 -348.943936) (xy 432.002661 -348.959302) (xy 431.94868 -348.967065) (xy 431.921412 -348.967552)
			(xy 431.057812 -348.967552) (xy 431.03054 -348.967109) (xy 430.97655 -348.959348) (xy 430.924215 -348.943983)
			(xy 430.874599 -348.921325) (xy 430.828712 -348.891837) (xy 430.78749 -348.856119) (xy 430.75177 -348.814897)
			(xy 430.722281 -348.769012) (xy 430.699621 -348.719397) (xy 430.684254 -348.667062) (xy 430.676492 -348.613072)
			(xy 429.193788 -348.613072) (xy 429.186025 -348.667062) (xy 429.170657 -348.719397) (xy 429.147996 -348.769012)
			(xy 429.118505 -348.814897) (xy 429.082783 -348.856117) (xy 429.041559 -348.891834) (xy 428.99567 -348.921319)
			(xy 428.946052 -348.943974) (xy 428.893715 -348.959335) (xy 428.839725 -348.967092) (xy 428.812452 -348.967552)
			(xy 427.948852 -348.967552) (xy 427.921584 -348.967082) (xy 427.867604 -348.959315) (xy 427.815279 -348.943945)
			(xy 427.765674 -348.921285) (xy 427.719798 -348.891797) (xy 427.678585 -348.856081) (xy 427.642874 -348.814864)
			(xy 427.613392 -348.768984) (xy 427.590738 -348.719376) (xy 427.575375 -348.667049) (xy 427.567614 -348.613068)
			(xy 426.084789 -348.613068) (xy 426.084789 -348.613071) (xy 426.077026 -348.667057) (xy 426.06166 -348.719389)
			(xy 426.039003 -348.769001) (xy 426.009515 -348.814884) (xy 425.973798 -348.856103) (xy 425.932578 -348.89182)
			(xy 425.886694 -348.921306) (xy 425.837081 -348.943963) (xy 425.784749 -348.959328) (xy 425.730763 -348.967089)
			(xy 425.703492 -348.967552) (xy 424.839892 -348.967552) (xy 424.812622 -348.967085) (xy 424.758638 -348.959322)
			(xy 424.706308 -348.943956) (xy 424.656698 -348.921299) (xy 424.610817 -348.891812) (xy 424.569599 -348.856095)
			(xy 424.533884 -348.814877) (xy 424.504398 -348.768995) (xy 424.481741 -348.719384) (xy 424.466376 -348.667054)
			(xy 424.458614 -348.61307) (xy 422.975766 -348.61307) (xy 422.968005 -348.667047) (xy 422.952642 -348.719372)
			(xy 422.929988 -348.768979) (xy 422.900506 -348.814857) (xy 422.864795 -348.856073) (xy 422.823583 -348.891787)
			(xy 422.777707 -348.921273) (xy 422.728102 -348.943931) (xy 422.675778 -348.959298) (xy 422.621799 -348.967063)
			(xy 422.594532 -348.967552) (xy 421.730932 -348.967552) (xy 421.703659 -348.967111) (xy 421.649667 -348.959352)
			(xy 421.597329 -348.943988) (xy 421.547711 -348.921332) (xy 421.501822 -348.891844) (xy 421.460597 -348.856126)
			(xy 421.424875 -348.814904) (xy 421.395384 -348.769017) (xy 421.372723 -348.719401) (xy 421.357355 -348.667064)
			(xy 421.349592 -348.613073) (xy 419.866888 -348.613073) (xy 419.859126 -348.667059) (xy 419.843759 -348.719393)
			(xy 419.821099 -348.769007) (xy 419.79161 -348.814891) (xy 419.75589 -348.85611) (xy 419.714668 -348.891827)
			(xy 419.668782 -348.921313) (xy 419.619167 -348.943968) (xy 419.566832 -348.959332) (xy 419.512844 -348.96709)
			(xy 419.485572 -348.967552) (xy 418.621972 -348.967552) (xy 418.594703 -348.967084) (xy 418.540721 -348.959319)
			(xy 418.488394 -348.94395) (xy 418.438786 -348.921292) (xy 418.392907 -348.891805) (xy 418.351692 -348.856088)
			(xy 418.315979 -348.81487) (xy 418.286495 -348.76899) (xy 418.26384 -348.71938) (xy 418.248476 -348.667051)
			(xy 418.240714 -348.613069) (xy 416.757866 -348.613069) (xy 416.750104 -348.667049) (xy 416.73474 -348.719376)
			(xy 416.712085 -348.768985) (xy 416.682601 -348.814864) (xy 416.646888 -348.85608) (xy 416.605673 -348.891794)
			(xy 416.559795 -348.92128) (xy 416.510188 -348.943936) (xy 416.457861 -348.959302) (xy 416.40388 -348.967065)
			(xy 416.376612 -348.967552) (xy 415.513012 -348.967552) (xy 415.48574 -348.967109) (xy 415.43175 -348.959348)
			(xy 415.379415 -348.943983) (xy 415.329799 -348.921325) (xy 415.283912 -348.891837) (xy 415.24269 -348.856119)
			(xy 415.20697 -348.814897) (xy 415.177481 -348.769012) (xy 415.154821 -348.719397) (xy 415.139454 -348.667062)
			(xy 415.131692 -348.613072) (xy 413.648988 -348.613072) (xy 413.641225 -348.667062) (xy 413.625857 -348.719397)
			(xy 413.603196 -348.769012) (xy 413.573705 -348.814897) (xy 413.537983 -348.856117) (xy 413.496759 -348.891834)
			(xy 413.45087 -348.921319) (xy 413.401252 -348.943974) (xy 413.348915 -348.959335) (xy 413.294925 -348.967092)
			(xy 413.267652 -348.967552) (xy 412.404052 -348.967552) (xy 412.376784 -348.967082) (xy 412.322804 -348.959315)
			(xy 412.270479 -348.943945) (xy 412.220874 -348.921285) (xy 412.174998 -348.891797) (xy 412.133785 -348.856081)
			(xy 412.098074 -348.814864) (xy 412.068592 -348.768984) (xy 412.045938 -348.719376) (xy 412.030575 -348.667049)
			(xy 412.022814 -348.613068) (xy 410.539989 -348.613068) (xy 410.539989 -348.613071) (xy 410.532226 -348.667057)
			(xy 410.51686 -348.719389) (xy 410.494203 -348.769001) (xy 410.464715 -348.814884) (xy 410.428998 -348.856103)
			(xy 410.387778 -348.89182) (xy 410.341894 -348.921306) (xy 410.292281 -348.943963) (xy 410.239949 -348.959328)
			(xy 410.185963 -348.967089) (xy 410.158692 -348.967552) (xy 409.295092 -348.967552) (xy 409.267822 -348.967085)
			(xy 409.213838 -348.959322) (xy 409.161508 -348.943956) (xy 409.111898 -348.921299) (xy 409.066017 -348.891812)
			(xy 409.024799 -348.856095) (xy 408.989084 -348.814877) (xy 408.959598 -348.768995) (xy 408.936941 -348.719384)
			(xy 408.921576 -348.667054) (xy 408.913814 -348.61307) (xy 403.522488 -348.61307) (xy 403.522488 -348.613071)
			(xy 403.514726 -348.667058) (xy 403.499359 -348.719391) (xy 403.476701 -348.769005) (xy 403.447212 -348.814888)
			(xy 403.411493 -348.856107) (xy 403.370272 -348.891824) (xy 403.324387 -348.92131) (xy 403.274773 -348.943966)
			(xy 403.222439 -348.95933) (xy 403.168451 -348.96709) (xy 403.14118 -348.967552) (xy 402.27758 -348.967552)
			(xy 402.250311 -348.967084) (xy 402.196328 -348.95932) (xy 402.143999 -348.943953) (xy 402.094391 -348.921295)
			(xy 402.048511 -348.891807) (xy 402.007295 -348.856091) (xy 401.971581 -348.814873) (xy 401.942096 -348.768992)
			(xy 401.91944 -348.719382) (xy 401.904076 -348.667052) (xy 401.896314 -348.613069) (xy 400.413466 -348.613069)
			(xy 400.405705 -348.667048) (xy 400.390341 -348.719375) (xy 400.367687 -348.768982) (xy 400.338203 -348.814861)
			(xy 400.302491 -348.856077) (xy 400.261277 -348.891791) (xy 400.2154 -348.921277) (xy 400.165794 -348.943934)
			(xy 400.113468 -348.9593) (xy 400.059488 -348.967064) (xy 400.03222 -348.967552) (xy 399.16862 -348.967552)
			(xy 399.141347 -348.96711) (xy 399.087357 -348.95935) (xy 399.03502 -348.943985) (xy 398.985403 -348.921328)
			(xy 398.939516 -348.89184) (xy 398.898293 -348.856122) (xy 398.862572 -348.8149) (xy 398.833082 -348.769014)
			(xy 398.810422 -348.719398) (xy 398.795054 -348.667063) (xy 398.787292 -348.613073) (xy 397.304588 -348.613073)
			(xy 397.296825 -348.667061) (xy 397.281458 -348.719396) (xy 397.258798 -348.76901) (xy 397.229307 -348.814894)
			(xy 397.193586 -348.856115) (xy 397.152362 -348.891831) (xy 397.106475 -348.921317) (xy 397.056858 -348.943972)
			(xy 397.004522 -348.959334) (xy 396.950532 -348.967091) (xy 396.92326 -348.967552) (xy 396.05966 -348.967552)
			(xy 396.032392 -348.967083) (xy 395.978411 -348.959316) (xy 395.926085 -348.943947) (xy 395.876479 -348.921288)
			(xy 395.830601 -348.8918) (xy 395.789388 -348.856084) (xy 395.753676 -348.814866) (xy 395.724193 -348.768986)
			(xy 395.701539 -348.719377) (xy 395.686175 -348.66705) (xy 395.678414 -348.613068) (xy 394.195566 -348.613068)
			(xy 394.195566 -348.613069) (xy 394.187804 -348.667051) (xy 394.172439 -348.719379) (xy 394.149784 -348.768988)
			(xy 394.120298 -348.814868) (xy 394.084584 -348.856084) (xy 394.043368 -348.891798) (xy 393.997488 -348.921284)
			(xy 393.947879 -348.943939) (xy 393.895551 -348.959304) (xy 393.841569 -348.967066) (xy 393.8143 -348.967552)
			(xy 392.9507 -348.967552) (xy 392.92343 -348.967086) (xy 392.869445 -348.959324) (xy 392.817114 -348.943958)
			(xy 392.767503 -348.921301) (xy 392.72162 -348.891814) (xy 392.680402 -348.856098) (xy 392.644686 -348.81488)
			(xy 392.615199 -348.768997) (xy 392.592542 -348.719386) (xy 392.577176 -348.667055) (xy 392.569414 -348.61307)
			(xy 391.086566 -348.61307) (xy 391.078805 -348.667046) (xy 391.063442 -348.71937) (xy 391.04079 -348.768977)
			(xy 391.011308 -348.814854) (xy 390.975598 -348.85607) (xy 390.934387 -348.891784) (xy 390.888512 -348.92127)
			(xy 390.838908 -348.943928) (xy 390.786585 -348.959297) (xy 390.732607 -348.967063) (xy 390.70534 -348.967552)
			(xy 389.84174 -348.967552) (xy 389.814466 -348.967111) (xy 389.760474 -348.959354) (xy 389.708135 -348.94399)
			(xy 389.658515 -348.921334) (xy 389.612626 -348.891847) (xy 389.5714 -348.856129) (xy 389.535677 -348.814906)
			(xy 389.506185 -348.76902) (xy 389.483524 -348.719403) (xy 389.468155 -348.667065) (xy 389.460392 -348.613074)
			(xy 387.977688 -348.613074) (xy 387.969926 -348.667058) (xy 387.954559 -348.719391) (xy 387.931901 -348.769005)
			(xy 387.902412 -348.814888) (xy 387.866693 -348.856107) (xy 387.825472 -348.891824) (xy 387.779587 -348.92131)
			(xy 387.729973 -348.943966) (xy 387.677639 -348.95933) (xy 387.623651 -348.96709) (xy 387.59638 -348.967552)
			(xy 386.73278 -348.967552) (xy 386.705511 -348.967084) (xy 386.651528 -348.95932) (xy 386.599199 -348.943953)
			(xy 386.549591 -348.921295) (xy 386.503711 -348.891807) (xy 386.462495 -348.856091) (xy 386.426781 -348.814873)
			(xy 386.397296 -348.768992) (xy 386.37464 -348.719382) (xy 386.359276 -348.667052) (xy 386.351514 -348.613069)
			(xy 384.868666 -348.613069) (xy 384.860905 -348.667048) (xy 384.845541 -348.719375) (xy 384.822887 -348.768982)
			(xy 384.793403 -348.814861) (xy 384.757691 -348.856077) (xy 384.716477 -348.891791) (xy 384.6706 -348.921277)
			(xy 384.620994 -348.943934) (xy 384.568668 -348.9593) (xy 384.514688 -348.967064) (xy 384.48742 -348.967552)
			(xy 383.62382 -348.967552) (xy 383.596547 -348.96711) (xy 383.542557 -348.95935) (xy 383.49022 -348.943985)
			(xy 383.440603 -348.921328) (xy 383.394716 -348.89184) (xy 383.353493 -348.856122) (xy 383.317772 -348.8149)
			(xy 383.288282 -348.769014) (xy 383.265622 -348.719398) (xy 383.250254 -348.667063) (xy 383.242492 -348.613073)
			(xy 381.759788 -348.613073) (xy 381.752025 -348.667061) (xy 381.736658 -348.719396) (xy 381.713998 -348.76901)
			(xy 381.684507 -348.814894) (xy 381.648786 -348.856115) (xy 381.607562 -348.891831) (xy 381.561675 -348.921317)
			(xy 381.512058 -348.943972) (xy 381.459722 -348.959334) (xy 381.405732 -348.967091) (xy 381.37846 -348.967552)
			(xy 380.51486 -348.967552) (xy 380.487592 -348.967083) (xy 380.433611 -348.959316) (xy 380.381285 -348.943947)
			(xy 380.331679 -348.921288) (xy 380.285801 -348.8918) (xy 380.244588 -348.856084) (xy 380.208876 -348.814866)
			(xy 380.179393 -348.768986) (xy 380.156739 -348.719377) (xy 380.141375 -348.66705) (xy 380.133614 -348.613068)
			(xy 378.650766 -348.613068) (xy 378.650766 -348.613069) (xy 378.643004 -348.667051) (xy 378.627639 -348.719379)
			(xy 378.604984 -348.768988) (xy 378.575498 -348.814868) (xy 378.539784 -348.856084) (xy 378.498568 -348.891798)
			(xy 378.452688 -348.921284) (xy 378.403079 -348.943939) (xy 378.350751 -348.959304) (xy 378.296769 -348.967066)
			(xy 378.2695 -348.967552) (xy 377.4059 -348.967552) (xy 377.37863 -348.967086) (xy 377.324645 -348.959324)
			(xy 377.272314 -348.943958) (xy 377.222703 -348.921301) (xy 377.17682 -348.891814) (xy 377.135602 -348.856098)
			(xy 377.099886 -348.81488) (xy 377.070399 -348.768997) (xy 377.047742 -348.719386) (xy 377.032376 -348.667055)
			(xy 377.024614 -348.61307) (xy 375.541766 -348.61307) (xy 375.534005 -348.667046) (xy 375.518642 -348.71937)
			(xy 375.49599 -348.768977) (xy 375.466508 -348.814854) (xy 375.430798 -348.85607) (xy 375.389587 -348.891784)
			(xy 375.343712 -348.92127) (xy 375.294108 -348.943928) (xy 375.241785 -348.959297) (xy 375.187807 -348.967063)
			(xy 375.16054 -348.967552) (xy 374.29694 -348.967552) (xy 374.269666 -348.967111) (xy 374.215674 -348.959354)
			(xy 374.163335 -348.94399) (xy 374.113715 -348.921334) (xy 374.067826 -348.891847) (xy 374.0266 -348.856129)
			(xy 373.990877 -348.814906) (xy 373.961385 -348.76902) (xy 373.938724 -348.719403) (xy 373.923355 -348.667065)
			(xy 373.915592 -348.613074) (xy 372.432888 -348.613074) (xy 372.425126 -348.667058) (xy 372.409759 -348.719391)
			(xy 372.387101 -348.769005) (xy 372.357612 -348.814888) (xy 372.321893 -348.856107) (xy 372.280672 -348.891824)
			(xy 372.234787 -348.92131) (xy 372.185173 -348.943966) (xy 372.132839 -348.95933) (xy 372.078851 -348.96709)
			(xy 372.05158 -348.967552) (xy 371.18798 -348.967552) (xy 371.160711 -348.967084) (xy 371.106728 -348.95932)
			(xy 371.054399 -348.943953) (xy 371.004791 -348.921295) (xy 370.958911 -348.891807) (xy 370.917695 -348.856091)
			(xy 370.881981 -348.814873) (xy 370.852496 -348.768992) (xy 370.82984 -348.719382) (xy 370.814476 -348.667052)
			(xy 370.806714 -348.613069) (xy 344.837266 -348.613069) (xy 344.829504 -348.66705) (xy 344.81414 -348.719378)
			(xy 344.791484 -348.768987) (xy 344.761999 -348.814866) (xy 344.726286 -348.856083) (xy 344.685069 -348.891797)
			(xy 344.63919 -348.921282) (xy 344.589582 -348.943938) (xy 344.537254 -348.959303) (xy 344.483272 -348.967065)
			(xy 344.456004 -348.967552) (xy 343.592404 -348.967552) (xy 343.565132 -348.967109) (xy 343.511143 -348.959347)
			(xy 343.458809 -348.943981) (xy 343.409194 -348.921323) (xy 343.363309 -348.891834) (xy 343.322087 -348.856116)
			(xy 343.286368 -348.814895) (xy 343.256879 -348.76901) (xy 343.234221 -348.719395) (xy 343.218854 -348.667061)
			(xy 343.211092 -348.613072) (xy 341.728265 -348.613072) (xy 341.720505 -348.667045) (xy 341.705143 -348.71937)
			(xy 341.68249 -348.768976) (xy 341.653009 -348.814853) (xy 341.6173 -348.856069) (xy 341.576088 -348.891783)
			(xy 341.530214 -348.921269) (xy 341.480611 -348.943927) (xy 341.428288 -348.959296) (xy 341.374311 -348.967063)
			(xy 341.347044 -348.967552) (xy 340.483444 -348.967552) (xy 340.45617 -348.967111) (xy 340.402177 -348.959354)
			(xy 340.349838 -348.943991) (xy 340.300218 -348.921336) (xy 340.254327 -348.891849) (xy 340.213101 -348.85613)
			(xy 340.177378 -348.814908) (xy 340.147885 -348.769021) (xy 340.125224 -348.719403) (xy 340.109855 -348.667066)
			(xy 340.102092 -348.613074) (xy 338.619388 -348.613074) (xy 338.611626 -348.667058) (xy 338.596259 -348.71939)
			(xy 338.573601 -348.769003) (xy 338.544113 -348.814887) (xy 338.508395 -348.856106) (xy 338.467174 -348.891823)
			(xy 338.421289 -348.921309) (xy 338.371675 -348.943965) (xy 338.319342 -348.95933) (xy 338.265355 -348.96709)
			(xy 338.238084 -348.967552) (xy 337.374484 -348.967552) (xy 337.347215 -348.967084) (xy 337.293231 -348.959321)
			(xy 337.240902 -348.943954) (xy 337.191293 -348.921296) (xy 337.145413 -348.891809) (xy 337.104196 -348.856093)
			(xy 337.068482 -348.814874) (xy 337.038996 -348.768993) (xy 337.016341 -348.719383) (xy 337.000976 -348.667053)
			(xy 336.993214 -348.613069) (xy 335.510366 -348.613069) (xy 335.502605 -348.667048) (xy 335.487241 -348.719374)
			(xy 335.464587 -348.768981) (xy 335.435104 -348.81486) (xy 335.399393 -348.856076) (xy 335.358179 -348.89179)
			(xy 335.312302 -348.921276) (xy 335.262696 -348.943933) (xy 335.210371 -348.9593) (xy 335.156392 -348.967064)
			(xy 335.129124 -348.967552) (xy 334.265524 -348.967552) (xy 334.238251 -348.96711) (xy 334.18426 -348.959351)
			(xy 334.131923 -348.943986) (xy 334.082306 -348.921329) (xy 334.036418 -348.891841) (xy 333.995194 -348.856123)
			(xy 333.959473 -348.814901) (xy 333.929982 -348.769015) (xy 333.907322 -348.719399) (xy 333.891955 -348.667063)
			(xy 333.884192 -348.613073) (xy 332.401488 -348.613073) (xy 332.393726 -348.667061) (xy 332.378358 -348.719395)
			(xy 332.355698 -348.769009) (xy 332.326208 -348.814893) (xy 332.290488 -348.856113) (xy 332.249264 -348.89183)
			(xy 332.203377 -348.921316) (xy 332.153761 -348.94397) (xy 332.101425 -348.959333) (xy 332.047436 -348.967091)
			(xy 332.020164 -348.967552) (xy 331.156564 -348.967552) (xy 331.129296 -348.967083) (xy 331.075314 -348.959317)
			(xy 331.022988 -348.943948) (xy 330.973381 -348.921289) (xy 330.927503 -348.891802) (xy 330.886289 -348.856086)
			(xy 330.850577 -348.814868) (xy 330.821093 -348.768987) (xy 330.798439 -348.719378) (xy 330.783075 -348.66705)
			(xy 330.775314 -348.613068) (xy 329.292466 -348.613068) (xy 329.284704 -348.66705) (xy 329.26934 -348.719378)
			(xy 329.246684 -348.768987) (xy 329.217199 -348.814866) (xy 329.181486 -348.856083) (xy 329.140269 -348.891797)
			(xy 329.09439 -348.921282) (xy 329.044782 -348.943938) (xy 328.992454 -348.959303) (xy 328.938472 -348.967065)
			(xy 328.911204 -348.967552) (xy 328.047604 -348.967552) (xy 328.020332 -348.967109) (xy 327.966343 -348.959347)
			(xy 327.914009 -348.943981) (xy 327.864394 -348.921323) (xy 327.818509 -348.891834) (xy 327.777287 -348.856116)
			(xy 327.741568 -348.814895) (xy 327.712079 -348.76901) (xy 327.689421 -348.719395) (xy 327.674054 -348.667061)
			(xy 327.666292 -348.613072) (xy 326.183465 -348.613072) (xy 326.175705 -348.667045) (xy 326.160343 -348.71937)
			(xy 326.13769 -348.768976) (xy 326.108209 -348.814853) (xy 326.0725 -348.856069) (xy 326.031288 -348.891783)
			(xy 325.985414 -348.921269) (xy 325.935811 -348.943927) (xy 325.883488 -348.959296) (xy 325.829511 -348.967063)
			(xy 325.802244 -348.967552) (xy 324.938644 -348.967552) (xy 324.91137 -348.967111) (xy 324.857377 -348.959354)
			(xy 324.805038 -348.943991) (xy 324.755418 -348.921336) (xy 324.709527 -348.891849) (xy 324.668301 -348.85613)
			(xy 324.632578 -348.814908) (xy 324.603085 -348.769021) (xy 324.580424 -348.719403) (xy 324.565055 -348.667066)
			(xy 324.557292 -348.613074) (xy 323.074588 -348.613074) (xy 323.066826 -348.667058) (xy 323.051459 -348.71939)
			(xy 323.028801 -348.769003) (xy 322.999313 -348.814887) (xy 322.963595 -348.856106) (xy 322.922374 -348.891823)
			(xy 322.876489 -348.921309) (xy 322.826875 -348.943965) (xy 322.774542 -348.95933) (xy 322.720555 -348.96709)
			(xy 322.693284 -348.967552) (xy 321.829684 -348.967552) (xy 321.802415 -348.967084) (xy 321.748431 -348.959321)
			(xy 321.696102 -348.943954) (xy 321.646493 -348.921296) (xy 321.600613 -348.891809) (xy 321.559396 -348.856093)
			(xy 321.523682 -348.814874) (xy 321.494196 -348.768993) (xy 321.471541 -348.719383) (xy 321.456176 -348.667053)
			(xy 321.448414 -348.613069) (xy 319.965566 -348.613069) (xy 319.957805 -348.667048) (xy 319.942441 -348.719374)
			(xy 319.919787 -348.768981) (xy 319.890304 -348.81486) (xy 319.854593 -348.856076) (xy 319.813379 -348.89179)
			(xy 319.767502 -348.921276) (xy 319.717896 -348.943933) (xy 319.665571 -348.9593) (xy 319.611592 -348.967064)
			(xy 319.584324 -348.967552) (xy 318.720724 -348.967552) (xy 318.693451 -348.96711) (xy 318.63946 -348.959351)
			(xy 318.587123 -348.943986) (xy 318.537506 -348.921329) (xy 318.491618 -348.891841) (xy 318.450394 -348.856123)
			(xy 318.414673 -348.814901) (xy 318.385182 -348.769015) (xy 318.362522 -348.719399) (xy 318.347155 -348.667063)
			(xy 318.339392 -348.613073) (xy 316.856688 -348.613073) (xy 316.848926 -348.667061) (xy 316.833558 -348.719395)
			(xy 316.810898 -348.769009) (xy 316.781408 -348.814893) (xy 316.745688 -348.856113) (xy 316.704464 -348.89183)
			(xy 316.658577 -348.921316) (xy 316.608961 -348.94397) (xy 316.556625 -348.959333) (xy 316.502636 -348.967091)
			(xy 316.475364 -348.967552) (xy 315.611764 -348.967552) (xy 315.584496 -348.967083) (xy 315.530514 -348.959317)
			(xy 315.478188 -348.943948) (xy 315.428581 -348.921289) (xy 315.382703 -348.891802) (xy 315.341489 -348.856086)
			(xy 315.305777 -348.814868) (xy 315.276293 -348.768987) (xy 315.253639 -348.719378) (xy 315.238275 -348.66705)
			(xy 315.230514 -348.613068) (xy 313.747666 -348.613068) (xy 313.739904 -348.66705) (xy 313.72454 -348.719378)
			(xy 313.701884 -348.768987) (xy 313.672399 -348.814866) (xy 313.636686 -348.856083) (xy 313.595469 -348.891797)
			(xy 313.54959 -348.921282) (xy 313.499982 -348.943938) (xy 313.447654 -348.959303) (xy 313.393672 -348.967065)
			(xy 313.366404 -348.967552) (xy 312.502804 -348.967552) (xy 312.475532 -348.967109) (xy 312.421543 -348.959347)
			(xy 312.369209 -348.943981) (xy 312.319594 -348.921323) (xy 312.273709 -348.891834) (xy 312.232487 -348.856116)
			(xy 312.196768 -348.814895) (xy 312.167279 -348.76901) (xy 312.144621 -348.719395) (xy 312.129254 -348.667061)
			(xy 312.121492 -348.613072) (xy 300.231566 -348.613072) (xy 300.223804 -348.667051) (xy 300.208439 -348.719379)
			(xy 300.185784 -348.768987) (xy 300.156299 -348.814867) (xy 300.120585 -348.856083) (xy 300.079369 -348.891798)
			(xy 300.033489 -348.921283) (xy 299.98388 -348.943939) (xy 299.931553 -348.959304) (xy 299.877571 -348.967065)
			(xy 299.850302 -348.967552) (xy 298.986702 -348.967552) (xy 298.95943 -348.967109) (xy 298.905442 -348.959347)
			(xy 298.853107 -348.94398) (xy 298.803493 -348.921322) (xy 298.757608 -348.891834) (xy 298.716386 -348.856115)
			(xy 298.680668 -348.814894) (xy 298.651179 -348.769009) (xy 298.628521 -348.719394) (xy 298.613154 -348.66706)
			(xy 298.605392 -348.613072) (xy 297.122565 -348.613072) (xy 297.114805 -348.667045) (xy 297.099443 -348.71937)
			(xy 297.07679 -348.768976) (xy 297.047309 -348.814854) (xy 297.011599 -348.856069) (xy 296.970387 -348.891784)
			(xy 296.924513 -348.92127) (xy 296.874909 -348.943928) (xy 296.822586 -348.959296) (xy 296.768609 -348.967063)
			(xy 296.741342 -348.967552) (xy 295.877742 -348.967552) (xy 295.850468 -348.967111) (xy 295.796476 -348.959354)
			(xy 295.744136 -348.943991) (xy 295.694517 -348.921335) (xy 295.648627 -348.891848) (xy 295.6074 -348.856129)
			(xy 295.571677 -348.814907) (xy 295.542185 -348.76902) (xy 295.519524 -348.719403) (xy 295.504155 -348.667066)
			(xy 295.496392 -348.613074) (xy 294.013688 -348.613074) (xy 294.005926 -348.667058) (xy 293.990559 -348.719391)
			(xy 293.967901 -348.769004) (xy 293.938412 -348.814887) (xy 293.902694 -348.856107) (xy 293.861473 -348.891823)
			(xy 293.815588 -348.92131) (xy 293.765974 -348.943966) (xy 293.713641 -348.95933) (xy 293.659653 -348.96709)
			(xy 293.632382 -348.967552) (xy 292.768782 -348.967552) (xy 292.741513 -348.967084) (xy 292.68753 -348.95932)
			(xy 292.635201 -348.943953) (xy 292.585592 -348.921295) (xy 292.539712 -348.891808) (xy 292.498495 -348.856092)
			(xy 292.462781 -348.814874) (xy 292.433296 -348.768992) (xy 292.410641 -348.719382) (xy 292.395276 -348.667053)
			(xy 292.387514 -348.613069) (xy 290.904666 -348.613069) (xy 290.896905 -348.667048) (xy 290.881541 -348.719374)
			(xy 290.858887 -348.768982) (xy 290.829404 -348.81486) (xy 290.793692 -348.856076) (xy 290.752478 -348.891791)
			(xy 290.706601 -348.921276) (xy 290.656995 -348.943933) (xy 290.604669 -348.9593) (xy 290.55069 -348.967064)
			(xy 290.523422 -348.967552) (xy 289.659822 -348.967552) (xy 289.632549 -348.96711) (xy 289.578559 -348.95935)
			(xy 289.526222 -348.943985) (xy 289.476605 -348.921329) (xy 289.430717 -348.891841) (xy 289.389493 -348.856122)
			(xy 289.353772 -348.814901) (xy 289.324282 -348.769015) (xy 289.301622 -348.719399) (xy 289.286254 -348.667063)
			(xy 289.278492 -348.613073) (xy 287.795788 -348.613073) (xy 287.788026 -348.667061) (xy 287.772658 -348.719395)
			(xy 287.749998 -348.76901) (xy 287.720508 -348.814894) (xy 287.684787 -348.856114) (xy 287.643563 -348.89183)
			(xy 287.597676 -348.921316) (xy 287.54806 -348.943971) (xy 287.495724 -348.959334) (xy 287.441734 -348.967091)
			(xy 287.414462 -348.967552) (xy 286.550862 -348.967552) (xy 286.523594 -348.967083) (xy 286.469613 -348.959317)
			(xy 286.417286 -348.943948) (xy 286.36768 -348.921289) (xy 286.321802 -348.891801) (xy 286.280588 -348.856085)
			(xy 286.244876 -348.814867) (xy 286.215393 -348.768987) (xy 286.192739 -348.719378) (xy 286.177375 -348.66705)
			(xy 286.169614 -348.613068) (xy 284.686766 -348.613068) (xy 284.686766 -348.613069) (xy 284.679004 -348.667051)
			(xy 284.663639 -348.719379) (xy 284.640984 -348.768987) (xy 284.611499 -348.814867) (xy 284.575785 -348.856083)
			(xy 284.534569 -348.891798) (xy 284.488689 -348.921283) (xy 284.43908 -348.943939) (xy 284.386753 -348.959304)
			(xy 284.332771 -348.967065) (xy 284.305502 -348.967552) (xy 283.441902 -348.967552) (xy 283.41463 -348.967109)
			(xy 283.360642 -348.959347) (xy 283.308307 -348.94398) (xy 283.258693 -348.921322) (xy 283.212808 -348.891834)
			(xy 283.171586 -348.856115) (xy 283.135868 -348.814894) (xy 283.106379 -348.769009) (xy 283.083721 -348.719394)
			(xy 283.068354 -348.66706) (xy 283.060592 -348.613072) (xy 281.577765 -348.613072) (xy 281.570005 -348.667045)
			(xy 281.554643 -348.71937) (xy 281.53199 -348.768976) (xy 281.502509 -348.814854) (xy 281.466799 -348.856069)
			(xy 281.425587 -348.891784) (xy 281.379713 -348.92127) (xy 281.330109 -348.943928) (xy 281.277786 -348.959296)
			(xy 281.223809 -348.967063) (xy 281.196542 -348.967552) (xy 280.332942 -348.967552) (xy 280.305668 -348.967111)
			(xy 280.251676 -348.959354) (xy 280.199336 -348.943991) (xy 280.149717 -348.921335) (xy 280.103827 -348.891848)
			(xy 280.0626 -348.856129) (xy 280.026877 -348.814907) (xy 279.997385 -348.76902) (xy 279.974724 -348.719403)
			(xy 279.959355 -348.667066) (xy 279.951592 -348.613074) (xy 278.468888 -348.613074) (xy 278.461126 -348.667058)
			(xy 278.445759 -348.719391) (xy 278.423101 -348.769004) (xy 278.393612 -348.814887) (xy 278.357894 -348.856107)
			(xy 278.316673 -348.891823) (xy 278.270788 -348.92131) (xy 278.221174 -348.943966) (xy 278.168841 -348.95933)
			(xy 278.114853 -348.96709) (xy 278.087582 -348.967552) (xy 277.223982 -348.967552) (xy 277.196713 -348.967084)
			(xy 277.14273 -348.95932) (xy 277.090401 -348.943953) (xy 277.040792 -348.921295) (xy 276.994912 -348.891808)
			(xy 276.953695 -348.856092) (xy 276.917981 -348.814874) (xy 276.888496 -348.768992) (xy 276.865841 -348.719382)
			(xy 276.850476 -348.667053) (xy 276.842714 -348.613069) (xy 275.359866 -348.613069) (xy 275.352105 -348.667048)
			(xy 275.336741 -348.719374) (xy 275.314087 -348.768982) (xy 275.284604 -348.81486) (xy 275.248892 -348.856076)
			(xy 275.207678 -348.891791) (xy 275.161801 -348.921276) (xy 275.112195 -348.943933) (xy 275.059869 -348.9593)
			(xy 275.00589 -348.967064) (xy 274.978622 -348.967552) (xy 274.115022 -348.967552) (xy 274.087749 -348.96711)
			(xy 274.033759 -348.95935) (xy 273.981422 -348.943985) (xy 273.931805 -348.921329) (xy 273.885917 -348.891841)
			(xy 273.844693 -348.856122) (xy 273.808972 -348.814901) (xy 273.779482 -348.769015) (xy 273.756822 -348.719399)
			(xy 273.741454 -348.667063) (xy 273.733692 -348.613073) (xy 272.250988 -348.613073) (xy 272.243226 -348.667061)
			(xy 272.227858 -348.719395) (xy 272.205198 -348.76901) (xy 272.175708 -348.814894) (xy 272.139987 -348.856114)
			(xy 272.098763 -348.89183) (xy 272.052876 -348.921316) (xy 272.00326 -348.943971) (xy 271.950924 -348.959334)
			(xy 271.896934 -348.967091) (xy 271.869662 -348.967552) (xy 271.006062 -348.967552) (xy 270.978794 -348.967083)
			(xy 270.924813 -348.959317) (xy 270.872486 -348.943948) (xy 270.82288 -348.921289) (xy 270.777002 -348.891801)
			(xy 270.735788 -348.856085) (xy 270.700076 -348.814867) (xy 270.670593 -348.768987) (xy 270.647939 -348.719378)
			(xy 270.632575 -348.66705) (xy 270.624814 -348.613068) (xy 269.141966 -348.613068) (xy 269.141966 -348.613069)
			(xy 269.134204 -348.667051) (xy 269.118839 -348.719379) (xy 269.096184 -348.768987) (xy 269.066699 -348.814867)
			(xy 269.030985 -348.856083) (xy 268.989769 -348.891798) (xy 268.943889 -348.921283) (xy 268.89428 -348.943939)
			(xy 268.841953 -348.959304) (xy 268.787971 -348.967065) (xy 268.760702 -348.967552) (xy 267.897102 -348.967552)
			(xy 267.86983 -348.967109) (xy 267.815842 -348.959347) (xy 267.763507 -348.94398) (xy 267.713893 -348.921322)
			(xy 267.668008 -348.891834) (xy 267.626786 -348.856115) (xy 267.591068 -348.814894) (xy 267.561579 -348.769009)
			(xy 267.538921 -348.719394) (xy 267.523554 -348.66706) (xy 267.515792 -348.613072) (xy 194.520565 -348.613072)
			(xy 194.512804 -348.667049) (xy 194.49744 -348.719376) (xy 194.474785 -348.768985) (xy 194.445301 -348.814864)
			(xy 194.409588 -348.85608) (xy 194.368373 -348.891794) (xy 194.322495 -348.92128) (xy 194.272888 -348.943936)
			(xy 194.220561 -348.959302) (xy 194.16658 -348.967065) (xy 194.139312 -348.967552) (xy 193.275712 -348.967552)
			(xy 193.24844 -348.967109) (xy 193.19445 -348.959348) (xy 193.142115 -348.943983) (xy 193.092499 -348.921325)
			(xy 193.046612 -348.891837) (xy 193.00539 -348.856119) (xy 192.96967 -348.814897) (xy 192.940181 -348.769012)
			(xy 192.917521 -348.719397) (xy 192.902154 -348.667062) (xy 192.894392 -348.613072) (xy 191.411688 -348.613072)
			(xy 191.403925 -348.667062) (xy 191.388557 -348.719397) (xy 191.365896 -348.769012) (xy 191.336405 -348.814897)
			(xy 191.300683 -348.856117) (xy 191.259459 -348.891834) (xy 191.21357 -348.921319) (xy 191.163952 -348.943974)
			(xy 191.111615 -348.959335) (xy 191.057625 -348.967092) (xy 191.030352 -348.967552) (xy 190.166752 -348.967552)
			(xy 190.139484 -348.967082) (xy 190.085504 -348.959315) (xy 190.033179 -348.943945) (xy 189.983574 -348.921285)
			(xy 189.937698 -348.891797) (xy 189.896485 -348.856081) (xy 189.860774 -348.814864) (xy 189.831292 -348.768984)
			(xy 189.808638 -348.719376) (xy 189.793275 -348.667049) (xy 189.785514 -348.613068) (xy 188.302689 -348.613068)
			(xy 188.302689 -348.613071) (xy 188.294926 -348.667057) (xy 188.27956 -348.719389) (xy 188.256903 -348.769001)
			(xy 188.227415 -348.814884) (xy 188.191698 -348.856103) (xy 188.150478 -348.89182) (xy 188.104594 -348.921306)
			(xy 188.054981 -348.943963) (xy 188.002649 -348.959328) (xy 187.948663 -348.967089) (xy 187.921392 -348.967552)
			(xy 187.057792 -348.967552) (xy 187.030522 -348.967085) (xy 186.976538 -348.959322) (xy 186.924208 -348.943956)
			(xy 186.874598 -348.921299) (xy 186.828717 -348.891812) (xy 186.787499 -348.856095) (xy 186.751784 -348.814877)
			(xy 186.722298 -348.768995) (xy 186.699641 -348.719384) (xy 186.684276 -348.667054) (xy 186.676514 -348.61307)
			(xy 185.193666 -348.61307) (xy 185.185905 -348.667047) (xy 185.170542 -348.719372) (xy 185.147888 -348.768979)
			(xy 185.118406 -348.814857) (xy 185.082695 -348.856073) (xy 185.041483 -348.891787) (xy 184.995607 -348.921273)
			(xy 184.946002 -348.943931) (xy 184.893678 -348.959298) (xy 184.839699 -348.967063) (xy 184.812432 -348.967552)
			(xy 183.948832 -348.967552) (xy 183.921559 -348.967111) (xy 183.867567 -348.959352) (xy 183.815229 -348.943988)
			(xy 183.765611 -348.921332) (xy 183.719722 -348.891844) (xy 183.678497 -348.856126) (xy 183.642775 -348.814904)
			(xy 183.613284 -348.769017) (xy 183.590623 -348.719401) (xy 183.575255 -348.667064) (xy 183.567492 -348.613073)
			(xy 182.084788 -348.613073) (xy 182.077026 -348.667059) (xy 182.061659 -348.719393) (xy 182.038999 -348.769007)
			(xy 182.00951 -348.814891) (xy 181.97379 -348.85611) (xy 181.932568 -348.891827) (xy 181.886682 -348.921313)
			(xy 181.837067 -348.943968) (xy 181.784732 -348.959332) (xy 181.730744 -348.96709) (xy 181.703472 -348.967552)
			(xy 180.839872 -348.967552) (xy 180.812603 -348.967084) (xy 180.758621 -348.959319) (xy 180.706294 -348.94395)
			(xy 180.656686 -348.921292) (xy 180.610807 -348.891805) (xy 180.569592 -348.856088) (xy 180.533879 -348.81487)
			(xy 180.504395 -348.76899) (xy 180.48174 -348.71938) (xy 180.466376 -348.667051) (xy 180.458614 -348.613069)
			(xy 178.975766 -348.613069) (xy 178.968004 -348.667049) (xy 178.95264 -348.719376) (xy 178.929985 -348.768985)
			(xy 178.900501 -348.814864) (xy 178.864788 -348.85608) (xy 178.823573 -348.891794) (xy 178.777695 -348.92128)
			(xy 178.728088 -348.943936) (xy 178.675761 -348.959302) (xy 178.62178 -348.967065) (xy 178.594512 -348.967552)
			(xy 177.730912 -348.967552) (xy 177.70364 -348.967109) (xy 177.64965 -348.959348) (xy 177.597315 -348.943983)
			(xy 177.547699 -348.921325) (xy 177.501812 -348.891837) (xy 177.46059 -348.856119) (xy 177.42487 -348.814897)
			(xy 177.395381 -348.769012) (xy 177.372721 -348.719397) (xy 177.357354 -348.667062) (xy 177.349592 -348.613072)
			(xy 175.866888 -348.613072) (xy 175.859125 -348.667062) (xy 175.843757 -348.719397) (xy 175.821096 -348.769012)
			(xy 175.791605 -348.814897) (xy 175.755883 -348.856117) (xy 175.714659 -348.891834) (xy 175.66877 -348.921319)
			(xy 175.619152 -348.943974) (xy 175.566815 -348.959335) (xy 175.512825 -348.967092) (xy 175.485552 -348.967552)
			(xy 174.621952 -348.967552) (xy 174.594684 -348.967082) (xy 174.540704 -348.959315) (xy 174.488379 -348.943945)
			(xy 174.438774 -348.921285) (xy 174.392898 -348.891797) (xy 174.351685 -348.856081) (xy 174.315974 -348.814864)
			(xy 174.286492 -348.768984) (xy 174.263838 -348.719376) (xy 174.248475 -348.667049) (xy 174.240714 -348.613068)
			(xy 172.757889 -348.613068) (xy 172.757889 -348.613071) (xy 172.750126 -348.667057) (xy 172.73476 -348.719389)
			(xy 172.712103 -348.769001) (xy 172.682615 -348.814884) (xy 172.646898 -348.856103) (xy 172.605678 -348.89182)
			(xy 172.559794 -348.921306) (xy 172.510181 -348.943963) (xy 172.457849 -348.959328) (xy 172.403863 -348.967089)
			(xy 172.376592 -348.967552) (xy 171.512992 -348.967552) (xy 171.485722 -348.967085) (xy 171.431738 -348.959322)
			(xy 171.379408 -348.943956) (xy 171.329798 -348.921299) (xy 171.283917 -348.891812) (xy 171.242699 -348.856095)
			(xy 171.206984 -348.814877) (xy 171.177498 -348.768995) (xy 171.154841 -348.719384) (xy 171.139476 -348.667054)
			(xy 171.131714 -348.61307) (xy 169.648866 -348.61307) (xy 169.641105 -348.667047) (xy 169.625742 -348.719372)
			(xy 169.603088 -348.768979) (xy 169.573606 -348.814857) (xy 169.537895 -348.856073) (xy 169.496683 -348.891787)
			(xy 169.450807 -348.921273) (xy 169.401202 -348.943931) (xy 169.348878 -348.959298) (xy 169.294899 -348.967063)
			(xy 169.267632 -348.967552) (xy 168.404032 -348.967552) (xy 168.376759 -348.967111) (xy 168.322767 -348.959352)
			(xy 168.270429 -348.943988) (xy 168.220811 -348.921332) (xy 168.174922 -348.891844) (xy 168.133697 -348.856126)
			(xy 168.097975 -348.814904) (xy 168.068484 -348.769017) (xy 168.045823 -348.719401) (xy 168.030455 -348.667064)
			(xy 168.022692 -348.613073) (xy 166.539988 -348.613073) (xy 166.532226 -348.667059) (xy 166.516859 -348.719393)
			(xy 166.494199 -348.769007) (xy 166.46471 -348.814891) (xy 166.42899 -348.85611) (xy 166.387768 -348.891827)
			(xy 166.341882 -348.921313) (xy 166.292267 -348.943968) (xy 166.239932 -348.959332) (xy 166.185944 -348.96709)
			(xy 166.158672 -348.967552) (xy 165.295072 -348.967552) (xy 165.267803 -348.967084) (xy 165.213821 -348.959319)
			(xy 165.161494 -348.94395) (xy 165.111886 -348.921292) (xy 165.066007 -348.891805) (xy 165.024792 -348.856088)
			(xy 164.989079 -348.81487) (xy 164.959595 -348.76899) (xy 164.93694 -348.71938) (xy 164.921576 -348.667051)
			(xy 164.913814 -348.613069) (xy 163.430966 -348.613069) (xy 163.423204 -348.667049) (xy 163.40784 -348.719376)
			(xy 163.385185 -348.768985) (xy 163.355701 -348.814864) (xy 163.319988 -348.85608) (xy 163.278773 -348.891794)
			(xy 163.232895 -348.92128) (xy 163.183288 -348.943936) (xy 163.130961 -348.959302) (xy 163.07698 -348.967065)
			(xy 163.049712 -348.967552) (xy 162.186112 -348.967552) (xy 162.15884 -348.967109) (xy 162.10485 -348.959348)
			(xy 162.052515 -348.943983) (xy 162.002899 -348.921325) (xy 161.957012 -348.891837) (xy 161.91579 -348.856119)
			(xy 161.88007 -348.814897) (xy 161.850581 -348.769012) (xy 161.827921 -348.719397) (xy 161.812554 -348.667062)
			(xy 161.804792 -348.613072) (xy 144.196565 -348.613072) (xy 144.188804 -348.66705) (xy 144.17344 -348.719377)
			(xy 144.150785 -348.768986) (xy 144.1213 -348.814865) (xy 144.085587 -348.856081) (xy 144.044371 -348.891796)
			(xy 143.998493 -348.921281) (xy 143.948885 -348.943937) (xy 143.896558 -348.959303) (xy 143.842576 -348.967065)
			(xy 143.815308 -348.967552) (xy 142.951708 -348.967552) (xy 142.924436 -348.967109) (xy 142.870447 -348.959348)
			(xy 142.818112 -348.943982) (xy 142.768496 -348.921324) (xy 142.72261 -348.891836) (xy 142.681388 -348.856117)
			(xy 142.645669 -348.814896) (xy 142.61618 -348.769011) (xy 142.593521 -348.719396) (xy 142.578154 -348.667061)
			(xy 142.570392 -348.613072) (xy 141.087565 -348.613072) (xy 141.079806 -348.667044) (xy 141.064443 -348.719369)
			(xy 141.041791 -348.768974) (xy 141.01231 -348.814852) (xy 140.976601 -348.856067) (xy 140.93539 -348.891781)
			(xy 140.889517 -348.921268) (xy 140.839914 -348.943926) (xy 140.787591 -348.959295) (xy 140.733614 -348.967062)
			(xy 140.706348 -348.967552) (xy 139.842748 -348.967552) (xy 139.815474 -348.967112) (xy 139.761481 -348.959355)
			(xy 139.709141 -348.943992) (xy 139.65952 -348.921337) (xy 139.613629 -348.89185) (xy 139.572402 -348.856132)
			(xy 139.536679 -348.814909) (xy 139.507186 -348.769022) (xy 139.484524 -348.719404) (xy 139.469155 -348.667066)
			(xy 139.461392 -348.613074) (xy 137.978689 -348.613074) (xy 137.970926 -348.667057) (xy 137.95556 -348.71939)
			(xy 137.932902 -348.769002) (xy 137.903414 -348.814885) (xy 137.867696 -348.856105) (xy 137.826476 -348.891821)
			(xy 137.780592 -348.921308) (xy 137.730978 -348.943964) (xy 137.678646 -348.959329) (xy 137.624659 -348.967089)
			(xy 137.597388 -348.967552) (xy 136.733788 -348.967552) (xy 136.706518 -348.967085) (xy 136.652535 -348.959321)
			(xy 136.600205 -348.943955) (xy 136.550595 -348.921297) (xy 136.504715 -348.89181) (xy 136.463497 -348.856094)
			(xy 136.427783 -348.814876) (xy 136.398297 -348.768994) (xy 136.375641 -348.719383) (xy 136.360276 -348.667053)
			(xy 136.352514 -348.61307) (xy 134.869666 -348.61307) (xy 134.861905 -348.667047) (xy 134.846541 -348.719373)
			(xy 134.823888 -348.76898) (xy 134.794405 -348.814858) (xy 134.758694 -348.856074) (xy 134.717481 -348.891789)
			(xy 134.671605 -348.921274) (xy 134.621999 -348.943932) (xy 134.569675 -348.959299) (xy 134.515695 -348.967064)
			(xy 134.488428 -348.967552) (xy 133.624828 -348.967552) (xy 133.597555 -348.96711) (xy 133.543564 -348.959351)
			(xy 133.491226 -348.943987) (xy 133.441608 -348.92133) (xy 133.39572 -348.891843) (xy 133.354495 -348.856124)
			(xy 133.318774 -348.814903) (xy 133.289283 -348.769016) (xy 133.266623 -348.7194) (xy 133.251255 -348.667064)
			(xy 133.243492 -348.613073) (xy 131.760788 -348.613073) (xy 131.753026 -348.66706) (xy 131.737658 -348.719394)
			(xy 131.714999 -348.769008) (xy 131.685509 -348.814892) (xy 131.649789 -348.856112) (xy 131.608566 -348.891828)
			(xy 131.56268 -348.921314) (xy 131.513064 -348.943969) (xy 131.460729 -348.959332) (xy 131.40674 -348.967091)
			(xy 131.379468 -348.967552) (xy 130.515868 -348.967552) (xy 130.488599 -348.967083) (xy 130.434618 -348.959318)
			(xy 130.382291 -348.943949) (xy 130.332683 -348.921291) (xy 130.286805 -348.891803) (xy 130.24559 -348.856087)
			(xy 130.209878 -348.814869) (xy 130.180394 -348.768989) (xy 130.15774 -348.719379) (xy 130.142375 -348.667051)
			(xy 130.134614 -348.613069) (xy 128.651766 -348.613069) (xy 128.644004 -348.66705) (xy 128.62864 -348.719377)
			(xy 128.605985 -348.768986) (xy 128.5765 -348.814865) (xy 128.540787 -348.856081) (xy 128.499571 -348.891796)
			(xy 128.453693 -348.921281) (xy 128.404085 -348.943937) (xy 128.351758 -348.959303) (xy 128.297776 -348.967065)
			(xy 128.270508 -348.967552) (xy 127.406908 -348.967552) (xy 127.379636 -348.967109) (xy 127.325647 -348.959348)
			(xy 127.273312 -348.943982) (xy 127.223696 -348.921324) (xy 127.17781 -348.891836) (xy 127.136588 -348.856117)
			(xy 127.100869 -348.814896) (xy 127.07138 -348.769011) (xy 127.048721 -348.719396) (xy 127.033354 -348.667061)
			(xy 127.025592 -348.613072) (xy 125.542765 -348.613072) (xy 125.535006 -348.667044) (xy 125.519643 -348.719369)
			(xy 125.496991 -348.768974) (xy 125.46751 -348.814852) (xy 125.431801 -348.856067) (xy 125.39059 -348.891781)
			(xy 125.344717 -348.921268) (xy 125.295114 -348.943926) (xy 125.242791 -348.959295) (xy 125.188814 -348.967062)
			(xy 125.161548 -348.967552) (xy 124.297948 -348.967552) (xy 124.270674 -348.967112) (xy 124.216681 -348.959355)
			(xy 124.164341 -348.943992) (xy 124.11472 -348.921337) (xy 124.068829 -348.89185) (xy 124.027602 -348.856132)
			(xy 123.991879 -348.814909) (xy 123.962386 -348.769022) (xy 123.939724 -348.719404) (xy 123.924355 -348.667066)
			(xy 123.916592 -348.613074) (xy 122.433889 -348.613074) (xy 122.426126 -348.667057) (xy 122.41076 -348.71939)
			(xy 122.388102 -348.769002) (xy 122.358614 -348.814885) (xy 122.322896 -348.856105) (xy 122.281676 -348.891821)
			(xy 122.235792 -348.921308) (xy 122.186178 -348.943964) (xy 122.133846 -348.959329) (xy 122.079859 -348.967089)
			(xy 122.052588 -348.967552) (xy 121.188988 -348.967552) (xy 121.161718 -348.967085) (xy 121.107735 -348.959321)
			(xy 121.055405 -348.943955) (xy 121.005795 -348.921297) (xy 120.959915 -348.89181) (xy 120.918697 -348.856094)
			(xy 120.882983 -348.814876) (xy 120.853497 -348.768994) (xy 120.830841 -348.719383) (xy 120.815476 -348.667053)
			(xy 120.807714 -348.61307) (xy 119.324866 -348.61307) (xy 119.317105 -348.667047) (xy 119.301741 -348.719373)
			(xy 119.279088 -348.76898) (xy 119.249605 -348.814858) (xy 119.213894 -348.856074) (xy 119.172681 -348.891789)
			(xy 119.126805 -348.921274) (xy 119.077199 -348.943932) (xy 119.024875 -348.959299) (xy 118.970895 -348.967064)
			(xy 118.943628 -348.967552) (xy 118.080028 -348.967552) (xy 118.052755 -348.96711) (xy 117.998764 -348.959351)
			(xy 117.946426 -348.943987) (xy 117.896808 -348.92133) (xy 117.85092 -348.891843) (xy 117.809695 -348.856124)
			(xy 117.773974 -348.814903) (xy 117.744483 -348.769016) (xy 117.721823 -348.7194) (xy 117.706455 -348.667064)
			(xy 117.698692 -348.613073) (xy 116.215988 -348.613073) (xy 116.208226 -348.66706) (xy 116.192858 -348.719394)
			(xy 116.170199 -348.769008) (xy 116.140709 -348.814892) (xy 116.104989 -348.856112) (xy 116.063766 -348.891828)
			(xy 116.01788 -348.921314) (xy 115.968264 -348.943969) (xy 115.915929 -348.959332) (xy 115.86194 -348.967091)
			(xy 115.834668 -348.967552) (xy 114.971068 -348.967552) (xy 114.943799 -348.967083) (xy 114.889818 -348.959318)
			(xy 114.837491 -348.943949) (xy 114.787883 -348.921291) (xy 114.742005 -348.891803) (xy 114.70079 -348.856087)
			(xy 114.665078 -348.814869) (xy 114.635594 -348.768989) (xy 114.61294 -348.719379) (xy 114.597575 -348.667051)
			(xy 114.589814 -348.613069) (xy 113.106966 -348.613069) (xy 113.099204 -348.66705) (xy 113.08384 -348.719377)
			(xy 113.061185 -348.768986) (xy 113.0317 -348.814865) (xy 112.995987 -348.856081) (xy 112.954771 -348.891796)
			(xy 112.908893 -348.921281) (xy 112.859285 -348.943937) (xy 112.806958 -348.959303) (xy 112.752976 -348.967065)
			(xy 112.725708 -348.967552) (xy 111.862108 -348.967552) (xy 111.834836 -348.967109) (xy 111.780847 -348.959348)
			(xy 111.728512 -348.943982) (xy 111.678896 -348.921324) (xy 111.63301 -348.891836) (xy 111.591788 -348.856117)
			(xy 111.556069 -348.814896) (xy 111.52658 -348.769011) (xy 111.503921 -348.719396) (xy 111.488554 -348.667061)
			(xy 111.480792 -348.613072) (xy 93.706665 -348.613072) (xy 93.698905 -348.667045) (xy 93.683543 -348.71937)
			(xy 93.66089 -348.768976) (xy 93.631409 -348.814854) (xy 93.595699 -348.856069) (xy 93.554487 -348.891784)
			(xy 93.508613 -348.92127) (xy 93.459009 -348.943928) (xy 93.406686 -348.959296) (xy 93.352709 -348.967063)
			(xy 93.325442 -348.967552) (xy 92.461842 -348.967552) (xy 92.434568 -348.967111) (xy 92.380576 -348.959354)
			(xy 92.328236 -348.943991) (xy 92.278617 -348.921335) (xy 92.232727 -348.891848) (xy 92.1915 -348.856129)
			(xy 92.155777 -348.814907) (xy 92.126285 -348.76902) (xy 92.103624 -348.719403) (xy 92.088255 -348.667066)
			(xy 92.080492 -348.613074) (xy 90.597788 -348.613074) (xy 90.590026 -348.667058) (xy 90.574659 -348.719391)
			(xy 90.552001 -348.769004) (xy 90.522512 -348.814887) (xy 90.486794 -348.856107) (xy 90.445573 -348.891823)
			(xy 90.399688 -348.92131) (xy 90.350074 -348.943966) (xy 90.297741 -348.95933) (xy 90.243753 -348.96709)
			(xy 90.216482 -348.967552) (xy 89.352882 -348.967552) (xy 89.325613 -348.967084) (xy 89.27163 -348.95932)
			(xy 89.219301 -348.943953) (xy 89.169692 -348.921295) (xy 89.123812 -348.891808) (xy 89.082595 -348.856092)
			(xy 89.046881 -348.814874) (xy 89.017396 -348.768992) (xy 88.994741 -348.719382) (xy 88.979376 -348.667053)
			(xy 88.971614 -348.613069) (xy 87.488766 -348.613069) (xy 87.481005 -348.667048) (xy 87.465641 -348.719374)
			(xy 87.442987 -348.768982) (xy 87.413504 -348.81486) (xy 87.377792 -348.856076) (xy 87.336578 -348.891791)
			(xy 87.290701 -348.921276) (xy 87.241095 -348.943933) (xy 87.188769 -348.9593) (xy 87.13479 -348.967064)
			(xy 87.107522 -348.967552) (xy 86.243922 -348.967552) (xy 86.216649 -348.96711) (xy 86.162659 -348.95935)
			(xy 86.110322 -348.943985) (xy 86.060705 -348.921329) (xy 86.014817 -348.891841) (xy 85.973593 -348.856122)
			(xy 85.937872 -348.814901) (xy 85.908382 -348.769015) (xy 85.885722 -348.719399) (xy 85.870354 -348.667063)
			(xy 85.862592 -348.613073) (xy 84.379888 -348.613073) (xy 84.372126 -348.667061) (xy 84.356758 -348.719395)
			(xy 84.334098 -348.76901) (xy 84.304608 -348.814894) (xy 84.268887 -348.856114) (xy 84.227663 -348.89183)
			(xy 84.181776 -348.921316) (xy 84.13216 -348.943971) (xy 84.079824 -348.959334) (xy 84.025834 -348.967091)
			(xy 83.998562 -348.967552) (xy 83.134962 -348.967552) (xy 83.107694 -348.967083) (xy 83.053713 -348.959317)
			(xy 83.001386 -348.943948) (xy 82.95178 -348.921289) (xy 82.905902 -348.891801) (xy 82.864688 -348.856085)
			(xy 82.828976 -348.814867) (xy 82.799493 -348.768987) (xy 82.776839 -348.719378) (xy 82.761475 -348.66705)
			(xy 82.753714 -348.613068) (xy 81.270866 -348.613068) (xy 81.270866 -348.613069) (xy 81.263104 -348.667051)
			(xy 81.247739 -348.719379) (xy 81.225084 -348.768987) (xy 81.195599 -348.814867) (xy 81.159885 -348.856083)
			(xy 81.118669 -348.891798) (xy 81.072789 -348.921283) (xy 81.02318 -348.943939) (xy 80.970853 -348.959304)
			(xy 80.916871 -348.967065) (xy 80.889602 -348.967552) (xy 80.026002 -348.967552) (xy 79.99873 -348.967109)
			(xy 79.944742 -348.959347) (xy 79.892407 -348.94398) (xy 79.842793 -348.921322) (xy 79.796908 -348.891834)
			(xy 79.755686 -348.856115) (xy 79.719968 -348.814894) (xy 79.690479 -348.769009) (xy 79.667821 -348.719394)
			(xy 79.652454 -348.66706) (xy 79.644692 -348.613072) (xy 78.161865 -348.613072) (xy 78.154105 -348.667045)
			(xy 78.138743 -348.71937) (xy 78.11609 -348.768976) (xy 78.086609 -348.814854) (xy 78.050899 -348.856069)
			(xy 78.009687 -348.891784) (xy 77.963813 -348.92127) (xy 77.914209 -348.943928) (xy 77.861886 -348.959296)
			(xy 77.807909 -348.967063) (xy 77.780642 -348.967552) (xy 76.917042 -348.967552) (xy 76.889768 -348.967111)
			(xy 76.835776 -348.959354) (xy 76.783436 -348.943991) (xy 76.733817 -348.921335) (xy 76.687927 -348.891848)
			(xy 76.6467 -348.856129) (xy 76.610977 -348.814907) (xy 76.581485 -348.76902) (xy 76.558824 -348.719403)
			(xy 76.543455 -348.667066) (xy 76.535692 -348.613074) (xy 75.052988 -348.613074) (xy 75.045226 -348.667058)
			(xy 75.029859 -348.719391) (xy 75.007201 -348.769004) (xy 74.977712 -348.814887) (xy 74.941994 -348.856107)
			(xy 74.900773 -348.891823) (xy 74.854888 -348.92131) (xy 74.805274 -348.943966) (xy 74.752941 -348.95933)
			(xy 74.698953 -348.96709) (xy 74.671682 -348.967552) (xy 73.808082 -348.967552) (xy 73.780813 -348.967084)
			(xy 73.72683 -348.95932) (xy 73.674501 -348.943953) (xy 73.624892 -348.921295) (xy 73.579012 -348.891808)
			(xy 73.537795 -348.856092) (xy 73.502081 -348.814874) (xy 73.472596 -348.768992) (xy 73.449941 -348.719382)
			(xy 73.434576 -348.667053) (xy 73.426814 -348.613069) (xy 71.943966 -348.613069) (xy 71.936205 -348.667048)
			(xy 71.920841 -348.719374) (xy 71.898187 -348.768982) (xy 71.868704 -348.81486) (xy 71.832992 -348.856076)
			(xy 71.791778 -348.891791) (xy 71.745901 -348.921276) (xy 71.696295 -348.943933) (xy 71.643969 -348.9593)
			(xy 71.58999 -348.967064) (xy 71.562722 -348.967552) (xy 70.699122 -348.967552) (xy 70.671849 -348.96711)
			(xy 70.617859 -348.95935) (xy 70.565522 -348.943985) (xy 70.515905 -348.921329) (xy 70.470017 -348.891841)
			(xy 70.428793 -348.856122) (xy 70.393072 -348.814901) (xy 70.363582 -348.769015) (xy 70.340922 -348.719399)
			(xy 70.325554 -348.667063) (xy 70.317792 -348.613073) (xy 68.835088 -348.613073) (xy 68.827326 -348.667061)
			(xy 68.811958 -348.719395) (xy 68.789298 -348.76901) (xy 68.759808 -348.814894) (xy 68.724087 -348.856114)
			(xy 68.682863 -348.89183) (xy 68.636976 -348.921316) (xy 68.58736 -348.943971) (xy 68.535024 -348.959334)
			(xy 68.481034 -348.967091) (xy 68.453762 -348.967552) (xy 67.590162 -348.967552) (xy 67.562894 -348.967083)
			(xy 67.508913 -348.959317) (xy 67.456586 -348.943948) (xy 67.40698 -348.921289) (xy 67.361102 -348.891801)
			(xy 67.319888 -348.856085) (xy 67.284176 -348.814867) (xy 67.254693 -348.768987) (xy 67.232039 -348.719378)
			(xy 67.216675 -348.66705) (xy 67.208914 -348.613068) (xy 65.726066 -348.613068) (xy 65.726066 -348.613069)
			(xy 65.718304 -348.667051) (xy 65.702939 -348.719379) (xy 65.680284 -348.768987) (xy 65.650799 -348.814867)
			(xy 65.615085 -348.856083) (xy 65.573869 -348.891798) (xy 65.527989 -348.921283) (xy 65.47838 -348.943939)
			(xy 65.426053 -348.959304) (xy 65.372071 -348.967065) (xy 65.344802 -348.967552) (xy 64.481202 -348.967552)
			(xy 64.45393 -348.967109) (xy 64.399942 -348.959347) (xy 64.347607 -348.94398) (xy 64.297993 -348.921322)
			(xy 64.252108 -348.891834) (xy 64.210886 -348.856115) (xy 64.175168 -348.814894) (xy 64.145679 -348.769009)
			(xy 64.123021 -348.719394) (xy 64.107654 -348.66706) (xy 64.099892 -348.613072) (xy 62.617065 -348.613072)
			(xy 62.609305 -348.667045) (xy 62.593943 -348.71937) (xy 62.57129 -348.768976) (xy 62.541809 -348.814854)
			(xy 62.506099 -348.856069) (xy 62.464887 -348.891784) (xy 62.419013 -348.92127) (xy 62.369409 -348.943928)
			(xy 62.317086 -348.959296) (xy 62.263109 -348.967063) (xy 62.235842 -348.967552) (xy 61.372242 -348.967552)
			(xy 61.344968 -348.967111) (xy 61.290976 -348.959354) (xy 61.238636 -348.943991) (xy 61.189017 -348.921335)
			(xy 61.143127 -348.891848) (xy 61.1019 -348.856129) (xy 61.066177 -348.814907) (xy 61.036685 -348.76902)
			(xy 61.014024 -348.719403) (xy 60.998655 -348.667066) (xy 60.990892 -348.613074) (xy 51.666865 -348.613074)
			(xy 51.659106 -348.667044) (xy 51.643743 -348.719369) (xy 51.621091 -348.768974) (xy 51.59161 -348.814852)
			(xy 51.555901 -348.856067) (xy 51.51469 -348.891781) (xy 51.468817 -348.921268) (xy 51.419214 -348.943926)
			(xy 51.366891 -348.959295) (xy 51.312914 -348.967062) (xy 51.285648 -348.967552) (xy 50.422048 -348.967552)
			(xy 50.394774 -348.967112) (xy 50.340781 -348.959355) (xy 50.288441 -348.943992) (xy 50.23882 -348.921337)
			(xy 50.192929 -348.89185) (xy 50.151702 -348.856132) (xy 50.115979 -348.814909) (xy 50.086486 -348.769022)
			(xy 50.063824 -348.719404) (xy 50.048455 -348.667066) (xy 50.040692 -348.613074) (xy 48.557989 -348.613074)
			(xy 48.550226 -348.667057) (xy 48.53486 -348.71939) (xy 48.512202 -348.769002) (xy 48.482714 -348.814885)
			(xy 48.446996 -348.856105) (xy 48.405776 -348.891821) (xy 48.359892 -348.921308) (xy 48.310278 -348.943964)
			(xy 48.257946 -348.959329) (xy 48.203959 -348.967089) (xy 48.176688 -348.967552) (xy 47.313088 -348.967552)
			(xy 47.285818 -348.967085) (xy 47.231835 -348.959321) (xy 47.179505 -348.943955) (xy 47.129895 -348.921297)
			(xy 47.084015 -348.89181) (xy 47.042797 -348.856094) (xy 47.007083 -348.814876) (xy 46.977597 -348.768994)
			(xy 46.954941 -348.719383) (xy 46.939576 -348.667053) (xy 46.931814 -348.61307) (xy 45.448966 -348.61307)
			(xy 45.441205 -348.667047) (xy 45.425841 -348.719373) (xy 45.403188 -348.76898) (xy 45.373705 -348.814858)
			(xy 45.337994 -348.856074) (xy 45.296781 -348.891789) (xy 45.250905 -348.921274) (xy 45.201299 -348.943932)
			(xy 45.148975 -348.959299) (xy 45.094995 -348.967064) (xy 45.067728 -348.967552) (xy 44.204128 -348.967552)
			(xy 44.176855 -348.96711) (xy 44.122864 -348.959351) (xy 44.070526 -348.943987) (xy 44.020908 -348.92133)
			(xy 43.97502 -348.891843) (xy 43.933795 -348.856124) (xy 43.898074 -348.814903) (xy 43.868583 -348.769016)
			(xy 43.845923 -348.7194) (xy 43.830555 -348.667064) (xy 43.822792 -348.613073) (xy 42.340088 -348.613073)
			(xy 42.332326 -348.66706) (xy 42.316958 -348.719394) (xy 42.294299 -348.769008) (xy 42.264809 -348.814892)
			(xy 42.229089 -348.856112) (xy 42.187866 -348.891828) (xy 42.14198 -348.921314) (xy 42.092364 -348.943969)
			(xy 42.040029 -348.959332) (xy 41.98604 -348.967091) (xy 41.958768 -348.967552) (xy 41.095168 -348.967552)
			(xy 41.067899 -348.967083) (xy 41.013918 -348.959318) (xy 40.961591 -348.943949) (xy 40.911983 -348.921291)
			(xy 40.866105 -348.891803) (xy 40.82489 -348.856087) (xy 40.789178 -348.814869) (xy 40.759694 -348.768989)
			(xy 40.73704 -348.719379) (xy 40.721675 -348.667051) (xy 40.713914 -348.613069) (xy 39.231066 -348.613069)
			(xy 39.223304 -348.66705) (xy 39.20794 -348.719377) (xy 39.185285 -348.768986) (xy 39.1558 -348.814865)
			(xy 39.120087 -348.856081) (xy 39.078871 -348.891796) (xy 39.032993 -348.921281) (xy 38.983385 -348.943937)
			(xy 38.931058 -348.959303) (xy 38.877076 -348.967065) (xy 38.849808 -348.967552) (xy 37.986208 -348.967552)
			(xy 37.958936 -348.967109) (xy 37.904947 -348.959348) (xy 37.852612 -348.943982) (xy 37.802996 -348.921324)
			(xy 37.75711 -348.891836) (xy 37.715888 -348.856117) (xy 37.680169 -348.814896) (xy 37.65068 -348.769011)
			(xy 37.628021 -348.719396) (xy 37.612654 -348.667061) (xy 37.604892 -348.613072) (xy 36.122065 -348.613072)
			(xy 36.114306 -348.667044) (xy 36.098943 -348.719369) (xy 36.076291 -348.768974) (xy 36.04681 -348.814852)
			(xy 36.011101 -348.856067) (xy 35.96989 -348.891781) (xy 35.924017 -348.921268) (xy 35.874414 -348.943926)
			(xy 35.822091 -348.959295) (xy 35.768114 -348.967062) (xy 35.740848 -348.967552) (xy 34.877248 -348.967552)
			(xy 34.849974 -348.967112) (xy 34.795981 -348.959355) (xy 34.743641 -348.943992) (xy 34.69402 -348.921337)
			(xy 34.648129 -348.89185) (xy 34.606902 -348.856132) (xy 34.571179 -348.814909) (xy 34.541686 -348.769022)
			(xy 34.519024 -348.719404) (xy 34.503655 -348.667066) (xy 34.495892 -348.613074) (xy 33.013189 -348.613074)
			(xy 33.005426 -348.667057) (xy 32.99006 -348.71939) (xy 32.967402 -348.769002) (xy 32.937914 -348.814885)
			(xy 32.902196 -348.856105) (xy 32.860976 -348.891821) (xy 32.815092 -348.921308) (xy 32.765478 -348.943964)
			(xy 32.713146 -348.959329) (xy 32.659159 -348.967089) (xy 32.631888 -348.967552) (xy 31.768288 -348.967552)
			(xy 31.741018 -348.967085) (xy 31.687035 -348.959321) (xy 31.634705 -348.943955) (xy 31.585095 -348.921297)
			(xy 31.539215 -348.89181) (xy 31.497997 -348.856094) (xy 31.462283 -348.814876) (xy 31.432797 -348.768994)
			(xy 31.410141 -348.719383) (xy 31.394776 -348.667053) (xy 31.387014 -348.61307) (xy 29.904166 -348.61307)
			(xy 29.896405 -348.667047) (xy 29.881041 -348.719373) (xy 29.858388 -348.76898) (xy 29.828905 -348.814858)
			(xy 29.793194 -348.856074) (xy 29.751981 -348.891789) (xy 29.706105 -348.921274) (xy 29.656499 -348.943932)
			(xy 29.604175 -348.959299) (xy 29.550195 -348.967064) (xy 29.522928 -348.967552) (xy 28.659328 -348.967552)
			(xy 28.632055 -348.96711) (xy 28.578064 -348.959351) (xy 28.525726 -348.943987) (xy 28.476108 -348.92133)
			(xy 28.43022 -348.891843) (xy 28.388995 -348.856124) (xy 28.353274 -348.814903) (xy 28.323783 -348.769016)
			(xy 28.301123 -348.7194) (xy 28.285755 -348.667064) (xy 28.277992 -348.613073) (xy 26.795288 -348.613073)
			(xy 26.787526 -348.66706) (xy 26.772158 -348.719394) (xy 26.749499 -348.769008) (xy 26.720009 -348.814892)
			(xy 26.684289 -348.856112) (xy 26.643066 -348.891828) (xy 26.59718 -348.921314) (xy 26.547564 -348.943969)
			(xy 26.495229 -348.959332) (xy 26.44124 -348.967091) (xy 26.413968 -348.967552) (xy 25.550368 -348.967552)
			(xy 25.523099 -348.967083) (xy 25.469118 -348.959318) (xy 25.416791 -348.943949) (xy 25.367183 -348.921291)
			(xy 25.321305 -348.891803) (xy 25.28009 -348.856087) (xy 25.244378 -348.814869) (xy 25.214894 -348.768989)
			(xy 25.19224 -348.719379) (xy 25.176875 -348.667051) (xy 25.169114 -348.613069) (xy 23.686266 -348.613069)
			(xy 23.678504 -348.66705) (xy 23.66314 -348.719377) (xy 23.640485 -348.768986) (xy 23.611 -348.814865)
			(xy 23.575287 -348.856081) (xy 23.534071 -348.891796) (xy 23.488193 -348.921281) (xy 23.438585 -348.943937)
			(xy 23.386258 -348.959303) (xy 23.332276 -348.967065) (xy 23.305008 -348.967552) (xy 22.441408 -348.967552)
			(xy 22.414136 -348.967109) (xy 22.360147 -348.959348) (xy 22.307812 -348.943982) (xy 22.258196 -348.921324)
			(xy 22.21231 -348.891836) (xy 22.171088 -348.856117) (xy 22.135369 -348.814896) (xy 22.10588 -348.769011)
			(xy 22.083221 -348.719396) (xy 22.067854 -348.667061) (xy 22.060092 -348.613072) (xy 20.577347 -348.613072)
			(xy 20.569586 -348.667048) (xy 20.55422 -348.719381) (xy 20.531562 -348.768994) (xy 20.502074 -348.814878)
			(xy 20.466357 -348.856098) (xy 20.425136 -348.891816) (xy 20.379253 -348.921303) (xy 20.329639 -348.943961)
			(xy 20.277306 -348.959327) (xy 20.223319 -348.967089) (xy 20.196048 -348.967552) (xy 19.332448 -348.967552)
			(xy 19.305179 -348.967065) (xy 19.251195 -348.959304) (xy 19.198866 -348.943938) (xy 19.149256 -348.921282)
			(xy 19.103375 -348.891796) (xy 19.062158 -348.856081) (xy 19.026443 -348.814863) (xy 18.996957 -348.768982)
			(xy 18.974301 -348.719372) (xy 18.958936 -348.667043) (xy 18.951174 -348.613059) (xy 8.879169 -348.613059)
			(xy 8.892221 -348.718461) (xy 8.900171 -348.847356) (xy 8.900668 -348.911926) (xy 8.900171 -348.976496)
			(xy 8.892221 -349.105391) (xy 8.876351 -349.233551) (xy 8.852622 -349.360492) (xy 8.821123 -349.485731)
			(xy 8.781974 -349.608794) (xy 8.735323 -349.729213) (xy 8.681348 -349.846532) (xy 8.620253 -349.960306)
			(xy 8.55227 -350.070103) (xy 8.477656 -350.175506) (xy 8.396695 -350.276116) (xy 8.309695 -350.371551)
			(xy 8.216984 -350.46145) (xy 8.118914 -350.545471) (xy 8.015859 -350.623295) (xy 7.908208 -350.694627)
			(xy 7.796369 -350.759197) (xy 7.680768 -350.816759) (xy 7.561843 -350.867096) (xy 7.440044 -350.910016)
			(xy 7.315834 -350.945357) (xy 7.189685 -350.972984) (xy 7.062073 -350.992793) (xy 6.933484 -351.004709)
			(xy 6.804406 -351.008686) (xy 6.675328 -351.004709) (xy 6.546739 -350.992793) (xy 6.419127 -350.972984)
			(xy 6.292978 -350.945357) (xy 6.168768 -350.910016) (xy 6.046969 -350.867096) (xy 5.928044 -350.816759)
			(xy 5.812443 -350.759197) (xy 5.700604 -350.694627) (xy 5.592953 -350.623295) (xy 5.489898 -350.545471)
			(xy 5.391828 -350.46145) (xy 5.299117 -350.371551) (xy 5.212117 -350.276116) (xy 5.131156 -350.175506)
			(xy 5.056542 -350.070103) (xy 4.988559 -349.960306) (xy 4.927464 -349.846532) (xy 4.873489 -349.729213)
			(xy 4.826838 -349.608794) (xy 4.787689 -349.485731) (xy 4.75619 -349.360492) (xy 4.732461 -349.233551)
			(xy 4.716591 -349.105391) (xy 4.708641 -348.976496) (xy 0.508 -348.976496) (xy 0.508 -351.638709)
			(xy 18.951172 -351.638709) (xy 18.951172 -351.584171) (xy 18.958934 -351.530187) (xy 18.974299 -351.477857)
			(xy 18.996956 -351.428247) (xy 19.026441 -351.382366) (xy 19.062157 -351.341148) (xy 19.103374 -351.305433)
			(xy 19.149255 -351.275947) (xy 19.198865 -351.25329) (xy 19.251195 -351.237925) (xy 19.305179 -351.230163)
			(xy 19.332448 -351.229676) (xy 20.196048 -351.229676) (xy 20.223319 -351.230143) (xy 20.277306 -351.237905)
			(xy 20.329638 -351.253271) (xy 20.379252 -351.275929) (xy 20.425135 -351.305416) (xy 20.466355 -351.341133)
			(xy 20.502073 -351.382353) (xy 20.53156 -351.428237) (xy 20.554218 -351.47785) (xy 20.569584 -351.530182)
			(xy 20.577347 -351.584169) (xy 20.577347 -351.638669) (xy 22.060139 -351.638669) (xy 22.060139 -351.584131)
			(xy 22.067901 -351.530149) (xy 22.083266 -351.477821) (xy 22.105922 -351.428212) (xy 22.135407 -351.382333)
			(xy 22.171122 -351.341117) (xy 22.212339 -351.305403) (xy 22.258219 -351.275918) (xy 22.307829 -351.253263)
			(xy 22.360157 -351.237899) (xy 22.414139 -351.230139) (xy 22.441408 -351.229676) (xy 23.305008 -351.229676)
			(xy 23.33228 -351.230087) (xy 23.386268 -351.23785) (xy 23.438602 -351.253218) (xy 23.488216 -351.275877)
			(xy 23.5341 -351.305366) (xy 23.575321 -351.341085) (xy 23.611039 -351.382306) (xy 23.640527 -351.428191)
			(xy 23.663185 -351.477806) (xy 23.678551 -351.53014) (xy 23.686314 -351.584128) (xy 23.686314 -351.638665)
			(xy 25.169162 -351.638665) (xy 25.169162 -351.584135) (xy 25.176922 -351.530159) (xy 25.192284 -351.477838)
			(xy 25.214936 -351.428234) (xy 25.244416 -351.38236) (xy 25.280124 -351.341147) (xy 25.321334 -351.305435)
			(xy 25.367206 -351.275951) (xy 25.416808 -351.253296) (xy 25.469128 -351.237929) (xy 25.523103 -351.230165)
			(xy 25.550368 -351.229676) (xy 26.413968 -351.229676) (xy 26.441243 -351.230061) (xy 26.495239 -351.237821)
			(xy 26.547581 -351.253186) (xy 26.597203 -351.275844) (xy 26.643095 -351.305333) (xy 26.684323 -351.341054)
			(xy 26.720047 -351.382279) (xy 26.749541 -351.428169) (xy 26.772203 -351.477789) (xy 26.787573 -351.53013)
			(xy 26.795336 -351.584125) (xy 26.795336 -351.63867) (xy 28.278039 -351.63867) (xy 28.278039 -351.58413)
			(xy 28.285802 -351.530146) (xy 28.301168 -351.477817) (xy 28.323825 -351.428207) (xy 28.353312 -351.382326)
			(xy 28.389029 -351.341109) (xy 28.430249 -351.305396) (xy 28.476131 -351.275912) (xy 28.525743 -351.253258)
			(xy 28.578074 -351.237896) (xy 28.632058 -351.230137) (xy 28.659328 -351.229676) (xy 29.522928 -351.229676)
			(xy 29.550199 -351.230088) (xy 29.604185 -351.237854) (xy 29.656516 -351.253223) (xy 29.706128 -351.275883)
			(xy 29.75201 -351.305373) (xy 29.793228 -351.341092) (xy 29.828944 -351.382313) (xy 29.85843 -351.428197)
			(xy 29.881086 -351.47781) (xy 29.896452 -351.530143) (xy 29.904214 -351.584129) (xy 29.904214 -351.638666)
			(xy 31.387062 -351.638666) (xy 31.387062 -351.584134) (xy 31.394823 -351.530157) (xy 31.410186 -351.477833)
			(xy 31.432839 -351.428229) (xy 31.462321 -351.382353) (xy 31.498031 -351.34114) (xy 31.539243 -351.305428)
			(xy 31.585118 -351.275945) (xy 31.634722 -351.25329) (xy 31.687045 -351.237925) (xy 31.741022 -351.230163)
			(xy 31.768288 -351.229676) (xy 32.631888 -351.229676) (xy 32.659162 -351.230063) (xy 32.713156 -351.237824)
			(xy 32.765495 -351.253191) (xy 32.815115 -351.27585) (xy 32.861004 -351.30534) (xy 32.90223 -351.341061)
			(xy 32.937952 -351.382286) (xy 32.967444 -351.428175) (xy 32.990105 -351.477794) (xy 33.005473 -351.530132)
			(xy 33.013236 -351.584126) (xy 33.013236 -351.63867) (xy 34.49594 -351.63867) (xy 34.49594 -351.58413)
			(xy 34.503702 -351.530144) (xy 34.519069 -351.477812) (xy 34.541728 -351.428201) (xy 34.571217 -351.38232)
			(xy 34.606936 -351.341102) (xy 34.648158 -351.305388) (xy 34.694043 -351.275905) (xy 34.743658 -351.253253)
			(xy 34.795991 -351.237892) (xy 34.849977 -351.230136) (xy 34.877248 -351.229676) (xy 35.740848 -351.229676)
			(xy 35.768118 -351.23009) (xy 35.822102 -351.237858) (xy 35.874431 -351.253229) (xy 35.92404 -351.27589)
			(xy 35.969919 -351.30538) (xy 36.011135 -351.341099) (xy 36.046849 -351.382319) (xy 36.076333 -351.428203)
			(xy 36.098988 -351.477814) (xy 36.114352 -351.530145) (xy 36.122114 -351.58413) (xy 36.122114 -351.638669)
			(xy 37.604939 -351.638669) (xy 37.604939 -351.584131) (xy 37.612701 -351.530149) (xy 37.628066 -351.477821)
			(xy 37.650722 -351.428212) (xy 37.680207 -351.382333) (xy 37.715922 -351.341117) (xy 37.757139 -351.305403)
			(xy 37.803019 -351.275918) (xy 37.852629 -351.253263) (xy 37.904957 -351.237899) (xy 37.958939 -351.230139)
			(xy 37.986208 -351.229676) (xy 38.849808 -351.229676) (xy 38.87708 -351.230087) (xy 38.931068 -351.23785)
			(xy 38.983402 -351.253218) (xy 39.033016 -351.275877) (xy 39.0789 -351.305366) (xy 39.120121 -351.341085)
			(xy 39.155839 -351.382306) (xy 39.185327 -351.428191) (xy 39.207985 -351.477806) (xy 39.223351 -351.53014)
			(xy 39.231114 -351.584128) (xy 39.231114 -351.638665) (xy 40.713962 -351.638665) (xy 40.713962 -351.584135)
			(xy 40.721722 -351.530159) (xy 40.737084 -351.477838) (xy 40.759736 -351.428234) (xy 40.789216 -351.38236)
			(xy 40.824924 -351.341147) (xy 40.866134 -351.305435) (xy 40.912006 -351.275951) (xy 40.961608 -351.253296)
			(xy 41.013928 -351.237929) (xy 41.067903 -351.230165) (xy 41.095168 -351.229676) (xy 41.958768 -351.229676)
			(xy 41.986043 -351.230061) (xy 42.040039 -351.237821) (xy 42.092381 -351.253186) (xy 42.142003 -351.275844)
			(xy 42.187895 -351.305333) (xy 42.229123 -351.341054) (xy 42.264847 -351.382279) (xy 42.294341 -351.428169)
			(xy 42.317003 -351.477789) (xy 42.332373 -351.53013) (xy 42.340136 -351.584125) (xy 42.340136 -351.63867)
			(xy 43.822839 -351.63867) (xy 43.822839 -351.58413) (xy 43.830602 -351.530146) (xy 43.845968 -351.477817)
			(xy 43.868625 -351.428207) (xy 43.898112 -351.382326) (xy 43.933829 -351.341109) (xy 43.975049 -351.305396)
			(xy 44.020931 -351.275912) (xy 44.070543 -351.253258) (xy 44.122874 -351.237896) (xy 44.176858 -351.230137)
			(xy 44.204128 -351.229676) (xy 45.067728 -351.229676) (xy 45.094999 -351.230088) (xy 45.148985 -351.237854)
			(xy 45.201316 -351.253223) (xy 45.250928 -351.275883) (xy 45.29681 -351.305373) (xy 45.338028 -351.341092)
			(xy 45.373744 -351.382313) (xy 45.40323 -351.428197) (xy 45.425886 -351.47781) (xy 45.441252 -351.530143)
			(xy 45.449014 -351.584129) (xy 45.449014 -351.638666) (xy 46.931862 -351.638666) (xy 46.931862 -351.584134)
			(xy 46.939623 -351.530157) (xy 46.954986 -351.477833) (xy 46.977639 -351.428229) (xy 47.007121 -351.382353)
			(xy 47.042831 -351.34114) (xy 47.084043 -351.305428) (xy 47.129918 -351.275945) (xy 47.179522 -351.25329)
			(xy 47.231845 -351.237925) (xy 47.285822 -351.230163) (xy 47.313088 -351.229676) (xy 48.176688 -351.229676)
			(xy 48.203962 -351.230063) (xy 48.257956 -351.237824) (xy 48.310295 -351.253191) (xy 48.359915 -351.27585)
			(xy 48.405804 -351.30534) (xy 48.44703 -351.341061) (xy 48.482752 -351.382286) (xy 48.512244 -351.428175)
			(xy 48.534905 -351.477794) (xy 48.550273 -351.530132) (xy 48.558036 -351.584126) (xy 48.558036 -351.63867)
			(xy 50.04074 -351.63867) (xy 50.04074 -351.58413) (xy 50.048502 -351.530144) (xy 50.063869 -351.477812)
			(xy 50.086528 -351.428201) (xy 50.116017 -351.38232) (xy 50.151736 -351.341102) (xy 50.192958 -351.305388)
			(xy 50.238843 -351.275905) (xy 50.288458 -351.253253) (xy 50.340791 -351.237892) (xy 50.394777 -351.230136)
			(xy 50.422048 -351.229676) (xy 51.285648 -351.229676) (xy 51.312918 -351.23009) (xy 51.366902 -351.237858)
			(xy 51.419231 -351.253229) (xy 51.46884 -351.27589) (xy 51.514719 -351.30538) (xy 51.555935 -351.341099)
			(xy 51.591649 -351.382319) (xy 51.621133 -351.428203) (xy 51.643788 -351.477814) (xy 51.659152 -351.530145)
			(xy 51.666914 -351.58413) (xy 51.666914 -351.63867) (xy 60.99094 -351.63867) (xy 60.99094 -351.58413)
			(xy 60.998702 -351.530145) (xy 61.014069 -351.477814) (xy 61.036727 -351.428203) (xy 61.066216 -351.382322)
			(xy 61.101934 -351.341105) (xy 61.143155 -351.305391) (xy 61.18904 -351.275907) (xy 61.238653 -351.253254)
			(xy 61.290986 -351.237893) (xy 61.344972 -351.230137) (xy 61.372242 -351.229676) (xy 62.235842 -351.229676)
			(xy 62.263112 -351.230089) (xy 62.317097 -351.237857) (xy 62.369426 -351.253227) (xy 62.419036 -351.275888)
			(xy 62.464916 -351.305378) (xy 62.506133 -351.341097) (xy 62.541847 -351.382317) (xy 62.571332 -351.428201)
			(xy 62.593988 -351.477813) (xy 62.609352 -351.530145) (xy 62.617114 -351.58413) (xy 62.617114 -351.638668)
			(xy 64.099939 -351.638668) (xy 64.099939 -351.584132) (xy 64.107701 -351.53015) (xy 64.123066 -351.477822)
			(xy 64.145721 -351.428214) (xy 64.175206 -351.382335) (xy 64.21092 -351.341119) (xy 64.252136 -351.305405)
			(xy 64.298016 -351.27592) (xy 64.347624 -351.253265) (xy 64.399952 -351.2379) (xy 64.453934 -351.230139)
			(xy 64.481202 -351.229676) (xy 65.344802 -351.229676) (xy 65.372074 -351.230087) (xy 65.426063 -351.237849)
			(xy 65.478397 -351.253216) (xy 65.528012 -351.275875) (xy 65.573897 -351.305364) (xy 65.615119 -351.341083)
			(xy 65.650837 -351.382304) (xy 65.680326 -351.42819) (xy 65.702984 -351.477805) (xy 65.718351 -351.530139)
			(xy 65.726113 -351.584128) (xy 65.726113 -351.638665) (xy 67.208962 -351.638665) (xy 67.208962 -351.584135)
			(xy 67.216722 -351.53016) (xy 67.232084 -351.477839) (xy 67.254735 -351.428236) (xy 67.284215 -351.382362)
			(xy 67.319922 -351.341149) (xy 67.361131 -351.305437) (xy 67.407003 -351.275953) (xy 67.456603 -351.253297)
			(xy 67.508923 -351.23793) (xy 67.562897 -351.230165) (xy 67.590162 -351.229676) (xy 68.453762 -351.229676)
			(xy 68.481037 -351.230061) (xy 68.535034 -351.23782) (xy 68.587376 -351.253184) (xy 68.636999 -351.275842)
			(xy 68.682892 -351.305331) (xy 68.724121 -351.341052) (xy 68.759846 -351.382277) (xy 68.78934 -351.428167)
			(xy 68.812003 -351.477788) (xy 68.827372 -351.530129) (xy 68.835136 -351.584125) (xy 68.835136 -351.638669)
			(xy 70.317839 -351.638669) (xy 70.317839 -351.584131) (xy 70.325601 -351.530147) (xy 70.340967 -351.477818)
			(xy 70.363624 -351.428208) (xy 70.393111 -351.382328) (xy 70.428827 -351.341112) (xy 70.470046 -351.305398)
			(xy 70.515928 -351.275914) (xy 70.565539 -351.25326) (xy 70.617869 -351.237897) (xy 70.671853 -351.230138)
			(xy 70.699122 -351.229676) (xy 71.562722 -351.229676) (xy 71.589993 -351.230088) (xy 71.64398 -351.237853)
			(xy 71.696312 -351.253222) (xy 71.745924 -351.275881) (xy 71.791807 -351.305371) (xy 71.833026 -351.34109)
			(xy 71.868742 -351.382311) (xy 71.898229 -351.428195) (xy 71.920886 -351.477809) (xy 71.936252 -351.530142)
			(xy 71.944014 -351.584129) (xy 71.944014 -351.638666) (xy 73.426862 -351.638666) (xy 73.426862 -351.584134)
			(xy 73.434623 -351.530158) (xy 73.449986 -351.477835) (xy 73.472638 -351.428231) (xy 73.50212 -351.382355)
			(xy 73.537829 -351.341142) (xy 73.579041 -351.30543) (xy 73.624915 -351.275947) (xy 73.674518 -351.253292)
			(xy 73.72684 -351.237927) (xy 73.780816 -351.230164) (xy 73.808082 -351.229676) (xy 74.671682 -351.229676)
			(xy 74.698957 -351.230062) (xy 74.752951 -351.237823) (xy 74.805291 -351.253189) (xy 74.854911 -351.275848)
			(xy 74.900802 -351.305338) (xy 74.942028 -351.341059) (xy 74.977751 -351.382284) (xy 75.007243 -351.428173)
			(xy 75.029904 -351.477792) (xy 75.045273 -351.530132) (xy 75.053036 -351.584125) (xy 75.053036 -351.63867)
			(xy 76.53574 -351.63867) (xy 76.53574 -351.58413) (xy 76.543502 -351.530145) (xy 76.558869 -351.477814)
			(xy 76.581527 -351.428203) (xy 76.611016 -351.382322) (xy 76.646734 -351.341105) (xy 76.687955 -351.305391)
			(xy 76.73384 -351.275907) (xy 76.783453 -351.253254) (xy 76.835786 -351.237893) (xy 76.889772 -351.230137)
			(xy 76.917042 -351.229676) (xy 77.780642 -351.229676) (xy 77.807912 -351.230089) (xy 77.861897 -351.237857)
			(xy 77.914226 -351.253227) (xy 77.963836 -351.275888) (xy 78.009716 -351.305378) (xy 78.050933 -351.341097)
			(xy 78.086647 -351.382317) (xy 78.116132 -351.428201) (xy 78.138788 -351.477813) (xy 78.154152 -351.530145)
			(xy 78.161914 -351.58413) (xy 78.161914 -351.638668) (xy 79.644739 -351.638668) (xy 79.644739 -351.584132)
			(xy 79.652501 -351.53015) (xy 79.667866 -351.477822) (xy 79.690521 -351.428214) (xy 79.720006 -351.382335)
			(xy 79.75572 -351.341119) (xy 79.796936 -351.305405) (xy 79.842816 -351.27592) (xy 79.892424 -351.253265)
			(xy 79.944752 -351.2379) (xy 79.998734 -351.230139) (xy 80.026002 -351.229676) (xy 80.889602 -351.229676)
			(xy 80.916874 -351.230087) (xy 80.970863 -351.237849) (xy 81.023197 -351.253216) (xy 81.072812 -351.275875)
			(xy 81.118697 -351.305364) (xy 81.159919 -351.341083) (xy 81.195637 -351.382304) (xy 81.225126 -351.42819)
			(xy 81.247784 -351.477805) (xy 81.263151 -351.530139) (xy 81.270913 -351.584128) (xy 81.270913 -351.638665)
			(xy 82.753762 -351.638665) (xy 82.753762 -351.584135) (xy 82.761522 -351.53016) (xy 82.776884 -351.477839)
			(xy 82.799535 -351.428236) (xy 82.829015 -351.382362) (xy 82.864722 -351.341149) (xy 82.905931 -351.305437)
			(xy 82.951803 -351.275953) (xy 83.001403 -351.253297) (xy 83.053723 -351.23793) (xy 83.107697 -351.230165)
			(xy 83.134962 -351.229676) (xy 83.998562 -351.229676) (xy 84.025837 -351.230061) (xy 84.079834 -351.23782)
			(xy 84.132176 -351.253184) (xy 84.181799 -351.275842) (xy 84.227692 -351.305331) (xy 84.268921 -351.341052)
			(xy 84.304646 -351.382277) (xy 84.33414 -351.428167) (xy 84.356803 -351.477788) (xy 84.372172 -351.530129)
			(xy 84.379936 -351.584125) (xy 84.379936 -351.638669) (xy 85.862639 -351.638669) (xy 85.862639 -351.584131)
			(xy 85.870401 -351.530147) (xy 85.885767 -351.477818) (xy 85.908424 -351.428208) (xy 85.937911 -351.382328)
			(xy 85.973627 -351.341112) (xy 86.014846 -351.305398) (xy 86.060728 -351.275914) (xy 86.110339 -351.25326)
			(xy 86.162669 -351.237897) (xy 86.216653 -351.230138) (xy 86.243922 -351.229676) (xy 87.107522 -351.229676)
			(xy 87.134793 -351.230088) (xy 87.18878 -351.237853) (xy 87.241112 -351.253222) (xy 87.290724 -351.275881)
			(xy 87.336607 -351.305371) (xy 87.377826 -351.34109) (xy 87.413542 -351.382311) (xy 87.443029 -351.428195)
			(xy 87.465686 -351.477809) (xy 87.481052 -351.530142) (xy 87.488814 -351.584129) (xy 87.488814 -351.638666)
			(xy 88.971662 -351.638666) (xy 88.971662 -351.584134) (xy 88.979423 -351.530158) (xy 88.994786 -351.477835)
			(xy 89.017438 -351.428231) (xy 89.04692 -351.382355) (xy 89.082629 -351.341142) (xy 89.123841 -351.30543)
			(xy 89.169715 -351.275947) (xy 89.219318 -351.253292) (xy 89.27164 -351.237927) (xy 89.325616 -351.230164)
			(xy 89.352882 -351.229676) (xy 90.216482 -351.229676) (xy 90.243757 -351.230062) (xy 90.297751 -351.237823)
			(xy 90.350091 -351.253189) (xy 90.399711 -351.275848) (xy 90.445602 -351.305338) (xy 90.486828 -351.341059)
			(xy 90.522551 -351.382284) (xy 90.552043 -351.428173) (xy 90.574704 -351.477792) (xy 90.590073 -351.530132)
			(xy 90.597836 -351.584125) (xy 90.597836 -351.63867) (xy 92.08054 -351.63867) (xy 92.08054 -351.58413)
			(xy 92.088302 -351.530145) (xy 92.103669 -351.477814) (xy 92.126327 -351.428203) (xy 92.155816 -351.382322)
			(xy 92.191534 -351.341105) (xy 92.232755 -351.305391) (xy 92.27864 -351.275907) (xy 92.328253 -351.253254)
			(xy 92.380586 -351.237893) (xy 92.434572 -351.230137) (xy 92.461842 -351.229676) (xy 93.325442 -351.229676)
			(xy 93.352712 -351.230089) (xy 93.406697 -351.237857) (xy 93.459026 -351.253227) (xy 93.508636 -351.275888)
			(xy 93.554516 -351.305378) (xy 93.595733 -351.341097) (xy 93.631447 -351.382317) (xy 93.660932 -351.428201)
			(xy 93.683588 -351.477813) (xy 93.698952 -351.530145) (xy 93.706714 -351.58413) (xy 93.706714 -351.638669)
			(xy 111.480839 -351.638669) (xy 111.480839 -351.584131) (xy 111.488601 -351.530149) (xy 111.503966 -351.477821)
			(xy 111.526622 -351.428212) (xy 111.556107 -351.382333) (xy 111.591822 -351.341117) (xy 111.633039 -351.305403)
			(xy 111.678919 -351.275918) (xy 111.728529 -351.253263) (xy 111.780857 -351.237899) (xy 111.834839 -351.230139)
			(xy 111.862108 -351.229676) (xy 112.725708 -351.229676) (xy 112.75298 -351.230087) (xy 112.806968 -351.23785)
			(xy 112.859302 -351.253218) (xy 112.908916 -351.275877) (xy 112.9548 -351.305366) (xy 112.996021 -351.341085)
			(xy 113.031739 -351.382306) (xy 113.061227 -351.428191) (xy 113.083885 -351.477806) (xy 113.099251 -351.53014)
			(xy 113.107014 -351.584128) (xy 113.107014 -351.638665) (xy 114.589862 -351.638665) (xy 114.589862 -351.584135)
			(xy 114.597622 -351.530159) (xy 114.612984 -351.477838) (xy 114.635636 -351.428234) (xy 114.665116 -351.38236)
			(xy 114.700824 -351.341147) (xy 114.742034 -351.305435) (xy 114.787906 -351.275951) (xy 114.837508 -351.253296)
			(xy 114.889828 -351.237929) (xy 114.943803 -351.230165) (xy 114.971068 -351.229676) (xy 115.834668 -351.229676)
			(xy 115.861943 -351.230061) (xy 115.915939 -351.237821) (xy 115.968281 -351.253186) (xy 116.017903 -351.275844)
			(xy 116.063795 -351.305333) (xy 116.105023 -351.341054) (xy 116.140747 -351.382279) (xy 116.170241 -351.428169)
			(xy 116.192903 -351.477789) (xy 116.208273 -351.53013) (xy 116.216036 -351.584125) (xy 116.216036 -351.63867)
			(xy 117.698739 -351.63867) (xy 117.698739 -351.58413) (xy 117.706502 -351.530146) (xy 117.721868 -351.477817)
			(xy 117.744525 -351.428207) (xy 117.774012 -351.382326) (xy 117.809729 -351.341109) (xy 117.850949 -351.305396)
			(xy 117.896831 -351.275912) (xy 117.946443 -351.253258) (xy 117.998774 -351.237896) (xy 118.052758 -351.230137)
			(xy 118.080028 -351.229676) (xy 118.943628 -351.229676) (xy 118.970899 -351.230088) (xy 119.024885 -351.237854)
			(xy 119.077216 -351.253223) (xy 119.126828 -351.275883) (xy 119.17271 -351.305373) (xy 119.213928 -351.341092)
			(xy 119.249644 -351.382313) (xy 119.27913 -351.428197) (xy 119.301786 -351.47781) (xy 119.317152 -351.530143)
			(xy 119.324914 -351.584129) (xy 119.324914 -351.638666) (xy 120.807762 -351.638666) (xy 120.807762 -351.584134)
			(xy 120.815523 -351.530157) (xy 120.830886 -351.477833) (xy 120.853539 -351.428229) (xy 120.883021 -351.382353)
			(xy 120.918731 -351.34114) (xy 120.959943 -351.305428) (xy 121.005818 -351.275945) (xy 121.055422 -351.25329)
			(xy 121.107745 -351.237925) (xy 121.161722 -351.230163) (xy 121.188988 -351.229676) (xy 122.052588 -351.229676)
			(xy 122.079862 -351.230063) (xy 122.133856 -351.237824) (xy 122.186195 -351.253191) (xy 122.235815 -351.27585)
			(xy 122.281704 -351.30534) (xy 122.32293 -351.341061) (xy 122.358652 -351.382286) (xy 122.388144 -351.428175)
			(xy 122.410805 -351.477794) (xy 122.426173 -351.530132) (xy 122.433936 -351.584126) (xy 122.433936 -351.63867)
			(xy 123.91664 -351.63867) (xy 123.91664 -351.58413) (xy 123.924402 -351.530144) (xy 123.939769 -351.477812)
			(xy 123.962428 -351.428201) (xy 123.991917 -351.38232) (xy 124.027636 -351.341102) (xy 124.068858 -351.305388)
			(xy 124.114743 -351.275905) (xy 124.164358 -351.253253) (xy 124.216691 -351.237892) (xy 124.270677 -351.230136)
			(xy 124.297948 -351.229676) (xy 125.161548 -351.229676) (xy 125.188818 -351.23009) (xy 125.242802 -351.237858)
			(xy 125.295131 -351.253229) (xy 125.34474 -351.27589) (xy 125.390619 -351.30538) (xy 125.431835 -351.341099)
			(xy 125.467549 -351.382319) (xy 125.497033 -351.428203) (xy 125.519688 -351.477814) (xy 125.535052 -351.530145)
			(xy 125.542814 -351.58413) (xy 125.542814 -351.638669) (xy 127.025639 -351.638669) (xy 127.025639 -351.584131)
			(xy 127.033401 -351.530149) (xy 127.048766 -351.477821) (xy 127.071422 -351.428212) (xy 127.100907 -351.382333)
			(xy 127.136622 -351.341117) (xy 127.177839 -351.305403) (xy 127.223719 -351.275918) (xy 127.273329 -351.253263)
			(xy 127.325657 -351.237899) (xy 127.379639 -351.230139) (xy 127.406908 -351.229676) (xy 128.270508 -351.229676)
			(xy 128.29778 -351.230087) (xy 128.351768 -351.23785) (xy 128.404102 -351.253218) (xy 128.453716 -351.275877)
			(xy 128.4996 -351.305366) (xy 128.540821 -351.341085) (xy 128.576539 -351.382306) (xy 128.606027 -351.428191)
			(xy 128.628685 -351.477806) (xy 128.644051 -351.53014) (xy 128.651814 -351.584128) (xy 128.651814 -351.638665)
			(xy 130.134662 -351.638665) (xy 130.134662 -351.584135) (xy 130.142422 -351.530159) (xy 130.157784 -351.477838)
			(xy 130.180436 -351.428234) (xy 130.209916 -351.38236) (xy 130.245624 -351.341147) (xy 130.286834 -351.305435)
			(xy 130.332706 -351.275951) (xy 130.382308 -351.253296) (xy 130.434628 -351.237929) (xy 130.488603 -351.230165)
			(xy 130.515868 -351.229676) (xy 131.379468 -351.229676) (xy 131.406743 -351.230061) (xy 131.460739 -351.237821)
			(xy 131.513081 -351.253186) (xy 131.562703 -351.275844) (xy 131.608595 -351.305333) (xy 131.649823 -351.341054)
			(xy 131.685547 -351.382279) (xy 131.715041 -351.428169) (xy 131.737703 -351.477789) (xy 131.753073 -351.53013)
			(xy 131.760836 -351.584125) (xy 131.760836 -351.63867) (xy 133.243539 -351.63867) (xy 133.243539 -351.58413)
			(xy 133.251302 -351.530146) (xy 133.266668 -351.477817) (xy 133.289325 -351.428207) (xy 133.318812 -351.382326)
			(xy 133.354529 -351.341109) (xy 133.395749 -351.305396) (xy 133.441631 -351.275912) (xy 133.491243 -351.253258)
			(xy 133.543574 -351.237896) (xy 133.597558 -351.230137) (xy 133.624828 -351.229676) (xy 134.488428 -351.229676)
			(xy 134.515699 -351.230088) (xy 134.569685 -351.237854) (xy 134.622016 -351.253223) (xy 134.671628 -351.275883)
			(xy 134.71751 -351.305373) (xy 134.758728 -351.341092) (xy 134.794444 -351.382313) (xy 134.82393 -351.428197)
			(xy 134.846586 -351.47781) (xy 134.861952 -351.530143) (xy 134.869714 -351.584129) (xy 134.869714 -351.638666)
			(xy 136.352562 -351.638666) (xy 136.352562 -351.584134) (xy 136.360323 -351.530157) (xy 136.375686 -351.477833)
			(xy 136.398339 -351.428229) (xy 136.427821 -351.382353) (xy 136.463531 -351.34114) (xy 136.504743 -351.305428)
			(xy 136.550618 -351.275945) (xy 136.600222 -351.25329) (xy 136.652545 -351.237925) (xy 136.706522 -351.230163)
			(xy 136.733788 -351.229676) (xy 137.597388 -351.229676) (xy 137.624662 -351.230063) (xy 137.678656 -351.237824)
			(xy 137.730995 -351.253191) (xy 137.780615 -351.27585) (xy 137.826504 -351.30534) (xy 137.86773 -351.341061)
			(xy 137.903452 -351.382286) (xy 137.932944 -351.428175) (xy 137.955605 -351.477794) (xy 137.970973 -351.530132)
			(xy 137.978736 -351.584126) (xy 137.978736 -351.63867) (xy 139.46144 -351.63867) (xy 139.46144 -351.58413)
			(xy 139.469202 -351.530144) (xy 139.484569 -351.477812) (xy 139.507228 -351.428201) (xy 139.536717 -351.38232)
			(xy 139.572436 -351.341102) (xy 139.613658 -351.305388) (xy 139.659543 -351.275905) (xy 139.709158 -351.253253)
			(xy 139.761491 -351.237892) (xy 139.815477 -351.230136) (xy 139.842748 -351.229676) (xy 140.706348 -351.229676)
			(xy 140.733618 -351.23009) (xy 140.787602 -351.237858) (xy 140.839931 -351.253229) (xy 140.88954 -351.27589)
			(xy 140.935419 -351.30538) (xy 140.976635 -351.341099) (xy 141.012349 -351.382319) (xy 141.041833 -351.428203)
			(xy 141.064488 -351.477814) (xy 141.079852 -351.530145) (xy 141.087614 -351.58413) (xy 141.087614 -351.638669)
			(xy 142.570439 -351.638669) (xy 142.570439 -351.584131) (xy 142.578201 -351.530149) (xy 142.593566 -351.477821)
			(xy 142.616222 -351.428212) (xy 142.645707 -351.382333) (xy 142.681422 -351.341117) (xy 142.722639 -351.305403)
			(xy 142.768519 -351.275918) (xy 142.818129 -351.253263) (xy 142.870457 -351.237899) (xy 142.924439 -351.230139)
			(xy 142.951708 -351.229676) (xy 143.815308 -351.229676) (xy 143.84258 -351.230087) (xy 143.896568 -351.23785)
			(xy 143.948902 -351.253218) (xy 143.998516 -351.275877) (xy 144.0444 -351.305366) (xy 144.085621 -351.341085)
			(xy 144.121339 -351.382306) (xy 144.150827 -351.428191) (xy 144.173485 -351.477806) (xy 144.188851 -351.53014)
			(xy 144.196614 -351.584128) (xy 144.196614 -351.638669) (xy 161.804839 -351.638669) (xy 161.804839 -351.584131)
			(xy 161.812601 -351.530149) (xy 161.827966 -351.47782) (xy 161.850623 -351.428211) (xy 161.880108 -351.382331)
			(xy 161.915824 -351.341115) (xy 161.957041 -351.305401) (xy 162.002922 -351.275917) (xy 162.052531 -351.253262)
			(xy 162.10486 -351.237899) (xy 162.158843 -351.230139) (xy 162.186112 -351.229676) (xy 163.049712 -351.229676)
			(xy 163.076984 -351.230087) (xy 163.130971 -351.237851) (xy 163.183304 -351.253219) (xy 163.232918 -351.275878)
			(xy 163.278802 -351.305367) (xy 163.320022 -351.341086) (xy 163.35574 -351.382308) (xy 163.385228 -351.428192)
			(xy 163.407885 -351.477807) (xy 163.423251 -351.530141) (xy 163.431014 -351.584128) (xy 163.431014 -351.638665)
			(xy 164.913862 -351.638665) (xy 164.913862 -351.584135) (xy 164.921622 -351.530159) (xy 164.936985 -351.477837)
			(xy 164.959637 -351.428233) (xy 164.989117 -351.382358) (xy 165.024826 -351.341146) (xy 165.066036 -351.305434)
			(xy 165.111909 -351.27595) (xy 165.16151 -351.253295) (xy 165.213831 -351.237928) (xy 165.267807 -351.230164)
			(xy 165.295072 -351.229676) (xy 166.158672 -351.229676) (xy 166.185947 -351.230062) (xy 166.239942 -351.237821)
			(xy 166.292284 -351.253187) (xy 166.341905 -351.275845) (xy 166.387797 -351.305335) (xy 166.429024 -351.341056)
			(xy 166.464748 -351.382281) (xy 166.494242 -351.42817) (xy 166.516903 -351.47779) (xy 166.532273 -351.53013)
			(xy 166.540036 -351.584125) (xy 166.540036 -351.63867) (xy 168.022739 -351.63867) (xy 168.022739 -351.58413)
			(xy 168.030502 -351.530146) (xy 168.045868 -351.477816) (xy 168.068526 -351.428206) (xy 168.098013 -351.382325)
			(xy 168.133731 -351.341108) (xy 168.174951 -351.305394) (xy 168.220834 -351.27591) (xy 168.270446 -351.253257)
			(xy 168.322777 -351.237895) (xy 168.376762 -351.230137) (xy 168.404032 -351.229676) (xy 169.267632 -351.229676)
			(xy 169.294903 -351.230089) (xy 169.348888 -351.237855) (xy 169.401219 -351.253224) (xy 169.45083 -351.275885)
			(xy 169.496712 -351.305374) (xy 169.537929 -351.341093) (xy 169.573645 -351.382314) (xy 169.603131 -351.428198)
			(xy 169.625787 -351.477811) (xy 169.641152 -351.530143) (xy 169.648914 -351.584129) (xy 169.648914 -351.638666)
			(xy 171.131762 -351.638666) (xy 171.131762 -351.584134) (xy 171.139523 -351.530156) (xy 171.154886 -351.477832)
			(xy 171.17754 -351.428228) (xy 171.207022 -351.382352) (xy 171.242733 -351.341138) (xy 171.283945 -351.305427)
			(xy 171.329821 -351.275944) (xy 171.379425 -351.253289) (xy 171.431748 -351.237925) (xy 171.485726 -351.230163)
			(xy 171.512992 -351.229676) (xy 172.376592 -351.229676) (xy 172.403866 -351.230063) (xy 172.457859 -351.237825)
			(xy 172.510198 -351.253192) (xy 172.559817 -351.275851) (xy 172.605706 -351.305342) (xy 172.646932 -351.341063)
			(xy 172.682653 -351.382287) (xy 172.712145 -351.428176) (xy 172.734805 -351.477794) (xy 172.750173 -351.530133)
			(xy 172.757936 -351.584126) (xy 172.757936 -351.638664) (xy 174.240762 -351.638664) (xy 174.240762 -351.584136)
			(xy 174.248522 -351.530162) (xy 174.263883 -351.477841) (xy 174.286534 -351.428239) (xy 174.316012 -351.382365)
			(xy 174.351719 -351.341153) (xy 174.392926 -351.305441) (xy 174.438797 -351.275957) (xy 174.488396 -351.2533)
			(xy 174.540715 -351.237932) (xy 174.594688 -351.230166) (xy 174.621952 -351.229676) (xy 175.485552 -351.229676)
			(xy 175.512828 -351.23006) (xy 175.566825 -351.237818) (xy 175.619169 -351.253181) (xy 175.668793 -351.275838)
			(xy 175.714687 -351.305328) (xy 175.755917 -351.341049) (xy 175.791644 -351.382274) (xy 175.821139 -351.428165)
			(xy 175.843802 -351.477786) (xy 175.859172 -351.530128) (xy 175.866936 -351.584124) (xy 175.866936 -351.638669)
			(xy 177.349639 -351.638669) (xy 177.349639 -351.584131) (xy 177.357401 -351.530149) (xy 177.372766 -351.47782)
			(xy 177.395423 -351.428211) (xy 177.424908 -351.382331) (xy 177.460624 -351.341115) (xy 177.501841 -351.305401)
			(xy 177.547722 -351.275917) (xy 177.597331 -351.253262) (xy 177.64966 -351.237899) (xy 177.703643 -351.230139)
			(xy 177.730912 -351.229676) (xy 178.594512 -351.229676) (xy 178.621784 -351.230087) (xy 178.675771 -351.237851)
			(xy 178.728104 -351.253219) (xy 178.777718 -351.275878) (xy 178.823602 -351.305367) (xy 178.864822 -351.341086)
			(xy 178.90054 -351.382308) (xy 178.930028 -351.428192) (xy 178.952685 -351.477807) (xy 178.968051 -351.530141)
			(xy 178.975814 -351.584128) (xy 178.975814 -351.638665) (xy 180.458662 -351.638665) (xy 180.458662 -351.584135)
			(xy 180.466422 -351.530159) (xy 180.481785 -351.477837) (xy 180.504437 -351.428233) (xy 180.533917 -351.382358)
			(xy 180.569626 -351.341146) (xy 180.610836 -351.305434) (xy 180.656709 -351.27595) (xy 180.70631 -351.253295)
			(xy 180.758631 -351.237928) (xy 180.812607 -351.230164) (xy 180.839872 -351.229676) (xy 181.703472 -351.229676)
			(xy 181.730747 -351.230062) (xy 181.784742 -351.237821) (xy 181.837084 -351.253187) (xy 181.886705 -351.275845)
			(xy 181.932597 -351.305335) (xy 181.973824 -351.341056) (xy 182.009548 -351.382281) (xy 182.039042 -351.42817)
			(xy 182.061703 -351.47779) (xy 182.077073 -351.53013) (xy 182.084836 -351.584125) (xy 182.084836 -351.63867)
			(xy 183.567539 -351.63867) (xy 183.567539 -351.58413) (xy 183.575302 -351.530146) (xy 183.590668 -351.477816)
			(xy 183.613326 -351.428206) (xy 183.642813 -351.382325) (xy 183.678531 -351.341108) (xy 183.719751 -351.305394)
			(xy 183.765634 -351.27591) (xy 183.815246 -351.253257) (xy 183.867577 -351.237895) (xy 183.921562 -351.230137)
			(xy 183.948832 -351.229676) (xy 184.812432 -351.229676) (xy 184.839703 -351.230089) (xy 184.893688 -351.237855)
			(xy 184.946019 -351.253224) (xy 184.99563 -351.275885) (xy 185.041512 -351.305374) (xy 185.082729 -351.341093)
			(xy 185.118445 -351.382314) (xy 185.147931 -351.428198) (xy 185.170587 -351.477811) (xy 185.185952 -351.530143)
			(xy 185.193714 -351.584129) (xy 185.193714 -351.638666) (xy 186.676562 -351.638666) (xy 186.676562 -351.584134)
			(xy 186.684323 -351.530156) (xy 186.699686 -351.477832) (xy 186.72234 -351.428228) (xy 186.751822 -351.382352)
			(xy 186.787533 -351.341138) (xy 186.828745 -351.305427) (xy 186.874621 -351.275944) (xy 186.924225 -351.253289)
			(xy 186.976548 -351.237925) (xy 187.030526 -351.230163) (xy 187.057792 -351.229676) (xy 187.921392 -351.229676)
			(xy 187.948666 -351.230063) (xy 188.002659 -351.237825) (xy 188.054998 -351.253192) (xy 188.104617 -351.275851)
			(xy 188.150506 -351.305342) (xy 188.191732 -351.341063) (xy 188.227453 -351.382287) (xy 188.256945 -351.428176)
			(xy 188.279605 -351.477794) (xy 188.294973 -351.530133) (xy 188.302736 -351.584126) (xy 188.302736 -351.638664)
			(xy 189.785562 -351.638664) (xy 189.785562 -351.584136) (xy 189.793322 -351.530162) (xy 189.808683 -351.477841)
			(xy 189.831334 -351.428239) (xy 189.860812 -351.382365) (xy 189.896519 -351.341153) (xy 189.937726 -351.305441)
			(xy 189.983597 -351.275957) (xy 190.033196 -351.2533) (xy 190.085515 -351.237932) (xy 190.139488 -351.230166)
			(xy 190.166752 -351.229676) (xy 191.030352 -351.229676) (xy 191.057628 -351.23006) (xy 191.111625 -351.237818)
			(xy 191.163969 -351.253181) (xy 191.213593 -351.275838) (xy 191.259487 -351.305328) (xy 191.300717 -351.341049)
			(xy 191.336444 -351.382274) (xy 191.365939 -351.428165) (xy 191.388602 -351.477786) (xy 191.403972 -351.530128)
			(xy 191.411736 -351.584124) (xy 191.411736 -351.638669) (xy 192.894439 -351.638669) (xy 192.894439 -351.584131)
			(xy 192.902201 -351.530149) (xy 192.917566 -351.47782) (xy 192.940223 -351.428211) (xy 192.969708 -351.382331)
			(xy 193.005424 -351.341115) (xy 193.046641 -351.305401) (xy 193.092522 -351.275917) (xy 193.142131 -351.253262)
			(xy 193.19446 -351.237899) (xy 193.248443 -351.230139) (xy 193.275712 -351.229676) (xy 194.139312 -351.229676)
			(xy 194.166584 -351.230087) (xy 194.220571 -351.237851) (xy 194.272904 -351.253219) (xy 194.322518 -351.275878)
			(xy 194.368402 -351.305367) (xy 194.409622 -351.341086) (xy 194.44534 -351.382308) (xy 194.474828 -351.428192)
			(xy 194.497485 -351.477807) (xy 194.512851 -351.530141) (xy 194.520614 -351.584128) (xy 194.520614 -351.638668)
			(xy 267.515839 -351.638668) (xy 267.515839 -351.584132) (xy 267.523601 -351.53015) (xy 267.538966 -351.477822)
			(xy 267.561621 -351.428214) (xy 267.591106 -351.382335) (xy 267.62682 -351.341119) (xy 267.668036 -351.305405)
			(xy 267.713916 -351.27592) (xy 267.763524 -351.253265) (xy 267.815852 -351.2379) (xy 267.869834 -351.230139)
			(xy 267.897102 -351.229676) (xy 268.760702 -351.229676) (xy 268.787974 -351.230087) (xy 268.841963 -351.237849)
			(xy 268.894297 -351.253216) (xy 268.943912 -351.275875) (xy 268.989797 -351.305364) (xy 269.031019 -351.341083)
			(xy 269.066737 -351.382304) (xy 269.096226 -351.42819) (xy 269.118884 -351.477805) (xy 269.134251 -351.530139)
			(xy 269.142013 -351.584128) (xy 269.142013 -351.638665) (xy 270.624862 -351.638665) (xy 270.624862 -351.584135)
			(xy 270.632622 -351.53016) (xy 270.647984 -351.477839) (xy 270.670635 -351.428236) (xy 270.700115 -351.382362)
			(xy 270.735822 -351.341149) (xy 270.777031 -351.305437) (xy 270.822903 -351.275953) (xy 270.872503 -351.253297)
			(xy 270.924823 -351.23793) (xy 270.978797 -351.230165) (xy 271.006062 -351.229676) (xy 271.869662 -351.229676)
			(xy 271.896937 -351.230061) (xy 271.950934 -351.23782) (xy 272.003276 -351.253184) (xy 272.052899 -351.275842)
			(xy 272.098792 -351.305331) (xy 272.140021 -351.341052) (xy 272.175746 -351.382277) (xy 272.20524 -351.428167)
			(xy 272.227903 -351.477788) (xy 272.243272 -351.530129) (xy 272.251036 -351.584125) (xy 272.251036 -351.638669)
			(xy 273.733739 -351.638669) (xy 273.733739 -351.584131) (xy 273.741501 -351.530147) (xy 273.756867 -351.477818)
			(xy 273.779524 -351.428208) (xy 273.809011 -351.382328) (xy 273.844727 -351.341112) (xy 273.885946 -351.305398)
			(xy 273.931828 -351.275914) (xy 273.981439 -351.25326) (xy 274.033769 -351.237897) (xy 274.087753 -351.230138)
			(xy 274.115022 -351.229676) (xy 274.978622 -351.229676) (xy 275.005893 -351.230088) (xy 275.05988 -351.237853)
			(xy 275.112212 -351.253222) (xy 275.161824 -351.275881) (xy 275.207707 -351.305371) (xy 275.248926 -351.34109)
			(xy 275.284642 -351.382311) (xy 275.314129 -351.428195) (xy 275.336786 -351.477809) (xy 275.352152 -351.530142)
			(xy 275.359914 -351.584129) (xy 275.359914 -351.638666) (xy 276.842762 -351.638666) (xy 276.842762 -351.584134)
			(xy 276.850523 -351.530158) (xy 276.865886 -351.477835) (xy 276.888538 -351.428231) (xy 276.91802 -351.382355)
			(xy 276.953729 -351.341142) (xy 276.994941 -351.30543) (xy 277.040815 -351.275947) (xy 277.090418 -351.253292)
			(xy 277.14274 -351.237927) (xy 277.196716 -351.230164) (xy 277.223982 -351.229676) (xy 278.087582 -351.229676)
			(xy 278.114857 -351.230062) (xy 278.168851 -351.237823) (xy 278.221191 -351.253189) (xy 278.270811 -351.275848)
			(xy 278.316702 -351.305338) (xy 278.357928 -351.341059) (xy 278.393651 -351.382284) (xy 278.423143 -351.428173)
			(xy 278.445804 -351.477792) (xy 278.461173 -351.530132) (xy 278.468936 -351.584125) (xy 278.468936 -351.63867)
			(xy 279.95164 -351.63867) (xy 279.95164 -351.58413) (xy 279.959402 -351.530145) (xy 279.974769 -351.477814)
			(xy 279.997427 -351.428203) (xy 280.026916 -351.382322) (xy 280.062634 -351.341105) (xy 280.103855 -351.305391)
			(xy 280.14974 -351.275907) (xy 280.199353 -351.253254) (xy 280.251686 -351.237893) (xy 280.305672 -351.230137)
			(xy 280.332942 -351.229676) (xy 281.196542 -351.229676) (xy 281.223812 -351.230089) (xy 281.277797 -351.237857)
			(xy 281.330126 -351.253227) (xy 281.379736 -351.275888) (xy 281.425616 -351.305378) (xy 281.466833 -351.341097)
			(xy 281.502547 -351.382317) (xy 281.532032 -351.428201) (xy 281.554688 -351.477813) (xy 281.570052 -351.530145)
			(xy 281.577814 -351.58413) (xy 281.577814 -351.638668) (xy 283.060639 -351.638668) (xy 283.060639 -351.584132)
			(xy 283.068401 -351.53015) (xy 283.083766 -351.477822) (xy 283.106421 -351.428214) (xy 283.135906 -351.382335)
			(xy 283.17162 -351.341119) (xy 283.212836 -351.305405) (xy 283.258716 -351.27592) (xy 283.308324 -351.253265)
			(xy 283.360652 -351.2379) (xy 283.414634 -351.230139) (xy 283.441902 -351.229676) (xy 284.305502 -351.229676)
			(xy 284.332774 -351.230087) (xy 284.386763 -351.237849) (xy 284.439097 -351.253216) (xy 284.488712 -351.275875)
			(xy 284.534597 -351.305364) (xy 284.575819 -351.341083) (xy 284.611537 -351.382304) (xy 284.641026 -351.42819)
			(xy 284.663684 -351.477805) (xy 284.679051 -351.530139) (xy 284.686813 -351.584128) (xy 284.686813 -351.638665)
			(xy 286.169662 -351.638665) (xy 286.169662 -351.584135) (xy 286.177422 -351.53016) (xy 286.192784 -351.477839)
			(xy 286.215435 -351.428236) (xy 286.244915 -351.382362) (xy 286.280622 -351.341149) (xy 286.321831 -351.305437)
			(xy 286.367703 -351.275953) (xy 286.417303 -351.253297) (xy 286.469623 -351.23793) (xy 286.523597 -351.230165)
			(xy 286.550862 -351.229676) (xy 287.414462 -351.229676) (xy 287.441737 -351.230061) (xy 287.495734 -351.23782)
			(xy 287.548076 -351.253184) (xy 287.597699 -351.275842) (xy 287.643592 -351.305331) (xy 287.684821 -351.341052)
			(xy 287.720546 -351.382277) (xy 287.75004 -351.428167) (xy 287.772703 -351.477788) (xy 287.788072 -351.530129)
			(xy 287.795836 -351.584125) (xy 287.795836 -351.638669) (xy 289.278539 -351.638669) (xy 289.278539 -351.584131)
			(xy 289.286301 -351.530147) (xy 289.301667 -351.477818) (xy 289.324324 -351.428208) (xy 289.353811 -351.382328)
			(xy 289.389527 -351.341112) (xy 289.430746 -351.305398) (xy 289.476628 -351.275914) (xy 289.526239 -351.25326)
			(xy 289.578569 -351.237897) (xy 289.632553 -351.230138) (xy 289.659822 -351.229676) (xy 290.523422 -351.229676)
			(xy 290.550693 -351.230088) (xy 290.60468 -351.237853) (xy 290.657012 -351.253222) (xy 290.706624 -351.275881)
			(xy 290.752507 -351.305371) (xy 290.793726 -351.34109) (xy 290.829442 -351.382311) (xy 290.858929 -351.428195)
			(xy 290.881586 -351.477809) (xy 290.896952 -351.530142) (xy 290.904714 -351.584129) (xy 290.904714 -351.638666)
			(xy 292.387562 -351.638666) (xy 292.387562 -351.584134) (xy 292.395323 -351.530158) (xy 292.410686 -351.477835)
			(xy 292.433338 -351.428231) (xy 292.46282 -351.382355) (xy 292.498529 -351.341142) (xy 292.539741 -351.30543)
			(xy 292.585615 -351.275947) (xy 292.635218 -351.253292) (xy 292.68754 -351.237927) (xy 292.741516 -351.230164)
			(xy 292.768782 -351.229676) (xy 293.632382 -351.229676) (xy 293.659657 -351.230062) (xy 293.713651 -351.237823)
			(xy 293.765991 -351.253189) (xy 293.815611 -351.275848) (xy 293.861502 -351.305338) (xy 293.902728 -351.341059)
			(xy 293.938451 -351.382284) (xy 293.967943 -351.428173) (xy 293.990604 -351.477792) (xy 294.005973 -351.530132)
			(xy 294.013736 -351.584125) (xy 294.013736 -351.63867) (xy 295.49644 -351.63867) (xy 295.49644 -351.58413)
			(xy 295.504202 -351.530145) (xy 295.519569 -351.477814) (xy 295.542227 -351.428203) (xy 295.571716 -351.382322)
			(xy 295.607434 -351.341105) (xy 295.648655 -351.305391) (xy 295.69454 -351.275907) (xy 295.744153 -351.253254)
			(xy 295.796486 -351.237893) (xy 295.850472 -351.230137) (xy 295.877742 -351.229676) (xy 296.741342 -351.229676)
			(xy 296.768612 -351.230089) (xy 296.822597 -351.237857) (xy 296.874926 -351.253227) (xy 296.924536 -351.275888)
			(xy 296.970416 -351.305378) (xy 297.011633 -351.341097) (xy 297.047347 -351.382317) (xy 297.076832 -351.428201)
			(xy 297.099488 -351.477813) (xy 297.114852 -351.530145) (xy 297.122614 -351.58413) (xy 297.122614 -351.638668)
			(xy 298.605439 -351.638668) (xy 298.605439 -351.584132) (xy 298.613201 -351.53015) (xy 298.628566 -351.477822)
			(xy 298.651221 -351.428214) (xy 298.680706 -351.382335) (xy 298.71642 -351.341119) (xy 298.757636 -351.305405)
			(xy 298.803516 -351.27592) (xy 298.853124 -351.253265) (xy 298.905452 -351.2379) (xy 298.959434 -351.230139)
			(xy 298.986702 -351.229676) (xy 299.850302 -351.229676) (xy 299.877574 -351.230087) (xy 299.931563 -351.237849)
			(xy 299.983897 -351.253216) (xy 300.033512 -351.275875) (xy 300.079397 -351.305364) (xy 300.120619 -351.341083)
			(xy 300.156337 -351.382304) (xy 300.185826 -351.42819) (xy 300.208484 -351.477805) (xy 300.223851 -351.530139)
			(xy 300.231613 -351.584128) (xy 300.231613 -351.638668) (xy 312.121539 -351.638668) (xy 312.121539 -351.584132)
			(xy 312.129301 -351.53015) (xy 312.144666 -351.477822) (xy 312.167321 -351.428213) (xy 312.196807 -351.382334)
			(xy 312.232521 -351.341118) (xy 312.273737 -351.305404) (xy 312.319617 -351.27592) (xy 312.369226 -351.253264)
			(xy 312.421554 -351.2379) (xy 312.475536 -351.230139) (xy 312.502804 -351.229676) (xy 313.366404 -351.229676)
			(xy 313.393676 -351.230087) (xy 313.447664 -351.23785) (xy 313.499999 -351.253217) (xy 313.549613 -351.275876)
			(xy 313.595498 -351.305365) (xy 313.63672 -351.341083) (xy 313.672438 -351.382305) (xy 313.701926 -351.42819)
			(xy 313.724584 -351.477805) (xy 313.739951 -351.530139) (xy 313.747713 -351.584128) (xy 313.747713 -351.638665)
			(xy 315.230562 -351.638665) (xy 315.230562 -351.584135) (xy 315.238322 -351.53016) (xy 315.253684 -351.477838)
			(xy 315.276335 -351.428236) (xy 315.305815 -351.382361) (xy 315.341523 -351.341148) (xy 315.382732 -351.305437)
			(xy 315.428604 -351.275953) (xy 315.478205 -351.253297) (xy 315.530525 -351.23793) (xy 315.584499 -351.230165)
			(xy 315.611764 -351.229676) (xy 316.475364 -351.229676) (xy 316.502639 -351.230061) (xy 316.556636 -351.23782)
			(xy 316.608978 -351.253185) (xy 316.6586 -351.275842) (xy 316.704493 -351.305332) (xy 316.745722 -351.341053)
			(xy 316.781446 -351.382278) (xy 316.81094 -351.428168) (xy 316.833603 -351.477788) (xy 316.848972 -351.530129)
			(xy 316.856736 -351.584125) (xy 316.856736 -351.638669) (xy 318.339439 -351.638669) (xy 318.339439 -351.584131)
			(xy 318.347201 -351.530147) (xy 318.362567 -351.477818) (xy 318.385224 -351.428208) (xy 318.414711 -351.382328)
			(xy 318.450428 -351.341111) (xy 318.491647 -351.305397) (xy 318.537529 -351.275913) (xy 318.58714 -351.253259)
			(xy 318.63947 -351.237896) (xy 318.693455 -351.230138) (xy 318.720724 -351.229676) (xy 319.584324 -351.229676)
			(xy 319.611595 -351.230088) (xy 319.665581 -351.237853) (xy 319.717913 -351.253222) (xy 319.767525 -351.275882)
			(xy 319.813408 -351.305372) (xy 319.854627 -351.34109) (xy 319.890343 -351.382312) (xy 319.919829 -351.428196)
			(xy 319.942486 -351.477809) (xy 319.957852 -351.530142) (xy 319.965614 -351.584129) (xy 319.965614 -351.638666)
			(xy 321.448462 -351.638666) (xy 321.448462 -351.584134) (xy 321.456223 -351.530157) (xy 321.471586 -351.477834)
			(xy 321.494239 -351.42823) (xy 321.52372 -351.382354) (xy 321.55943 -351.341141) (xy 321.600642 -351.30543)
			(xy 321.646516 -351.275946) (xy 321.696119 -351.253291) (xy 321.748442 -351.237926) (xy 321.802418 -351.230163)
			(xy 321.829684 -351.229676) (xy 322.693284 -351.229676) (xy 322.720558 -351.230062) (xy 322.774552 -351.237824)
			(xy 322.826892 -351.25319) (xy 322.876512 -351.275849) (xy 322.922403 -351.305339) (xy 322.963629 -351.34106)
			(xy 322.999351 -351.382285) (xy 323.028843 -351.428174) (xy 323.051504 -351.477793) (xy 323.066873 -351.530132)
			(xy 323.074636 -351.584126) (xy 323.074636 -351.63867) (xy 324.55734 -351.63867) (xy 324.55734 -351.58413)
			(xy 324.565102 -351.530144) (xy 324.580469 -351.477813) (xy 324.603128 -351.428202) (xy 324.632616 -351.382321)
			(xy 324.668335 -351.341104) (xy 324.709556 -351.30539) (xy 324.755441 -351.275906) (xy 324.805055 -351.253254)
			(xy 324.857387 -351.237893) (xy 324.911374 -351.230136) (xy 324.938644 -351.229676) (xy 325.802244 -351.229676)
			(xy 325.829514 -351.23009) (xy 325.883498 -351.237857) (xy 325.935828 -351.253228) (xy 325.985437 -351.275889)
			(xy 326.031317 -351.305379) (xy 326.072534 -351.341097) (xy 326.108248 -351.382318) (xy 326.137732 -351.428201)
			(xy 326.160388 -351.477814) (xy 326.175752 -351.530145) (xy 326.183514 -351.58413) (xy 326.183514 -351.638668)
			(xy 327.666339 -351.638668) (xy 327.666339 -351.584132) (xy 327.674101 -351.53015) (xy 327.689466 -351.477822)
			(xy 327.712121 -351.428213) (xy 327.741607 -351.382334) (xy 327.777321 -351.341118) (xy 327.818537 -351.305404)
			(xy 327.864417 -351.27592) (xy 327.914026 -351.253264) (xy 327.966354 -351.2379) (xy 328.020336 -351.230139)
			(xy 328.047604 -351.229676) (xy 328.911204 -351.229676) (xy 328.938476 -351.230087) (xy 328.992464 -351.23785)
			(xy 329.044799 -351.253217) (xy 329.094413 -351.275876) (xy 329.140298 -351.305365) (xy 329.18152 -351.341083)
			(xy 329.217238 -351.382305) (xy 329.246726 -351.42819) (xy 329.269384 -351.477805) (xy 329.284751 -351.530139)
			(xy 329.292513 -351.584128) (xy 329.292513 -351.638665) (xy 330.775362 -351.638665) (xy 330.775362 -351.584135)
			(xy 330.783122 -351.53016) (xy 330.798484 -351.477838) (xy 330.821135 -351.428236) (xy 330.850615 -351.382361)
			(xy 330.886323 -351.341148) (xy 330.927532 -351.305437) (xy 330.973404 -351.275953) (xy 331.023005 -351.253297)
			(xy 331.075325 -351.23793) (xy 331.129299 -351.230165) (xy 331.156564 -351.229676) (xy 332.020164 -351.229676)
			(xy 332.047439 -351.230061) (xy 332.101436 -351.23782) (xy 332.153778 -351.253185) (xy 332.2034 -351.275842)
			(xy 332.249293 -351.305332) (xy 332.290522 -351.341053) (xy 332.326246 -351.382278) (xy 332.35574 -351.428168)
			(xy 332.378403 -351.477788) (xy 332.393772 -351.530129) (xy 332.401536 -351.584125) (xy 332.401536 -351.638669)
			(xy 333.884239 -351.638669) (xy 333.884239 -351.584131) (xy 333.892001 -351.530147) (xy 333.907367 -351.477818)
			(xy 333.930024 -351.428208) (xy 333.959511 -351.382328) (xy 333.995228 -351.341111) (xy 334.036447 -351.305397)
			(xy 334.082329 -351.275913) (xy 334.13194 -351.253259) (xy 334.18427 -351.237896) (xy 334.238255 -351.230138)
			(xy 334.265524 -351.229676) (xy 335.129124 -351.229676) (xy 335.156395 -351.230088) (xy 335.210381 -351.237853)
			(xy 335.262713 -351.253222) (xy 335.312325 -351.275882) (xy 335.358208 -351.305372) (xy 335.399427 -351.34109)
			(xy 335.435143 -351.382312) (xy 335.464629 -351.428196) (xy 335.487286 -351.477809) (xy 335.502652 -351.530142)
			(xy 335.510414 -351.584129) (xy 335.510414 -351.638666) (xy 336.993262 -351.638666) (xy 336.993262 -351.584134)
			(xy 337.001023 -351.530157) (xy 337.016386 -351.477834) (xy 337.039039 -351.42823) (xy 337.06852 -351.382354)
			(xy 337.10423 -351.341141) (xy 337.145442 -351.30543) (xy 337.191316 -351.275946) (xy 337.240919 -351.253291)
			(xy 337.293242 -351.237926) (xy 337.347218 -351.230163) (xy 337.374484 -351.229676) (xy 338.238084 -351.229676)
			(xy 338.265358 -351.230062) (xy 338.319352 -351.237824) (xy 338.371692 -351.25319) (xy 338.421312 -351.275849)
			(xy 338.467203 -351.305339) (xy 338.508429 -351.34106) (xy 338.544151 -351.382285) (xy 338.573643 -351.428174)
			(xy 338.596304 -351.477793) (xy 338.611673 -351.530132) (xy 338.619436 -351.584126) (xy 338.619436 -351.63867)
			(xy 340.10214 -351.63867) (xy 340.10214 -351.58413) (xy 340.109902 -351.530144) (xy 340.125269 -351.477813)
			(xy 340.147928 -351.428202) (xy 340.177416 -351.382321) (xy 340.213135 -351.341104) (xy 340.254356 -351.30539)
			(xy 340.300241 -351.275906) (xy 340.349855 -351.253254) (xy 340.402187 -351.237893) (xy 340.456174 -351.230136)
			(xy 340.483444 -351.229676) (xy 341.347044 -351.229676) (xy 341.374314 -351.23009) (xy 341.428298 -351.237857)
			(xy 341.480628 -351.253228) (xy 341.530237 -351.275889) (xy 341.576117 -351.305379) (xy 341.617334 -351.341097)
			(xy 341.653048 -351.382318) (xy 341.682532 -351.428201) (xy 341.705188 -351.477814) (xy 341.720552 -351.530145)
			(xy 341.728314 -351.58413) (xy 341.728314 -351.638668) (xy 343.211139 -351.638668) (xy 343.211139 -351.584132)
			(xy 343.218901 -351.53015) (xy 343.234266 -351.477822) (xy 343.256921 -351.428213) (xy 343.286407 -351.382334)
			(xy 343.322121 -351.341118) (xy 343.363337 -351.305404) (xy 343.409217 -351.27592) (xy 343.458826 -351.253264)
			(xy 343.511154 -351.2379) (xy 343.565136 -351.230139) (xy 343.592404 -351.229676) (xy 344.456004 -351.229676)
			(xy 344.483276 -351.230087) (xy 344.537264 -351.23785) (xy 344.589599 -351.253217) (xy 344.639213 -351.275876)
			(xy 344.685098 -351.305365) (xy 344.72632 -351.341083) (xy 344.762038 -351.382305) (xy 344.791526 -351.42819)
			(xy 344.814184 -351.477805) (xy 344.829551 -351.530139) (xy 344.837313 -351.584128) (xy 344.837313 -351.638666)
			(xy 370.806762 -351.638666) (xy 370.806762 -351.584134) (xy 370.814523 -351.530158) (xy 370.829885 -351.477835)
			(xy 370.852538 -351.428231) (xy 370.882019 -351.382356) (xy 370.917729 -351.341143) (xy 370.95894 -351.305431)
			(xy 371.004814 -351.275948) (xy 371.054416 -351.253292) (xy 371.106738 -351.237927) (xy 371.160714 -351.230164)
			(xy 371.18798 -351.229676) (xy 372.05158 -351.229676) (xy 372.078855 -351.230062) (xy 372.132849 -351.237823)
			(xy 372.185189 -351.253189) (xy 372.23481 -351.275848) (xy 372.280701 -351.305338) (xy 372.321927 -351.341059)
			(xy 372.35765 -351.382283) (xy 372.387143 -351.428172) (xy 372.409804 -351.477792) (xy 372.425173 -351.530131)
			(xy 372.432936 -351.584125) (xy 372.432936 -351.63867) (xy 373.91564 -351.63867) (xy 373.91564 -351.58413)
			(xy 373.923402 -351.530145) (xy 373.938769 -351.477814) (xy 373.961427 -351.428203) (xy 373.990915 -351.382322)
			(xy 374.026634 -351.341105) (xy 374.067854 -351.305391) (xy 374.113738 -351.275908) (xy 374.163352 -351.253255)
			(xy 374.215684 -351.237893) (xy 374.26967 -351.230137) (xy 374.29694 -351.229676) (xy 375.16054 -351.229676)
			(xy 375.18781 -351.230089) (xy 375.241795 -351.237856) (xy 375.294125 -351.253227) (xy 375.343735 -351.275887)
			(xy 375.389615 -351.305377) (xy 375.430832 -351.341096) (xy 375.466547 -351.382317) (xy 375.496032 -351.4282)
			(xy 375.518687 -351.477813) (xy 375.534052 -351.530144) (xy 375.541814 -351.58413) (xy 375.541814 -351.638667)
			(xy 377.024662 -351.638667) (xy 377.024662 -351.584133) (xy 377.032423 -351.530155) (xy 377.047787 -351.477831)
			(xy 377.070441 -351.428226) (xy 377.099924 -351.382349) (xy 377.135636 -351.341136) (xy 377.176849 -351.305424)
			(xy 377.222726 -351.275941) (xy 377.272331 -351.253287) (xy 377.324655 -351.237923) (xy 377.378633 -351.230162)
			(xy 377.4059 -351.229676) (xy 378.2695 -351.229676) (xy 378.296772 -351.230087) (xy 378.350761 -351.237849)
			(xy 378.403096 -351.253216) (xy 378.452711 -351.275874) (xy 378.498596 -351.305363) (xy 378.539818 -351.341082)
			(xy 378.575537 -351.382304) (xy 378.605026 -351.428189) (xy 378.627684 -351.477804) (xy 378.643051 -351.530139)
			(xy 378.650813 -351.584128) (xy 378.650813 -351.638665) (xy 380.133662 -351.638665) (xy 380.133662 -351.584135)
			(xy 380.141422 -351.53016) (xy 380.156784 -351.477839) (xy 380.179435 -351.428237) (xy 380.208914 -351.382362)
			(xy 380.244621 -351.34115) (xy 380.28583 -351.305438) (xy 380.331702 -351.275954) (xy 380.381302 -351.253298)
			(xy 380.433621 -351.237931) (xy 380.487595 -351.230165) (xy 380.51486 -351.229676) (xy 381.37846 -351.229676)
			(xy 381.405736 -351.230061) (xy 381.459732 -351.237819) (xy 381.512075 -351.253183) (xy 381.561698 -351.275841)
			(xy 381.607591 -351.30533) (xy 381.64882 -351.341051) (xy 381.684546 -351.382277) (xy 381.71404 -351.428167)
			(xy 381.736703 -351.477788) (xy 381.752072 -351.530129) (xy 381.759836 -351.584124) (xy 381.759836 -351.638669)
			(xy 383.242539 -351.638669) (xy 383.242539 -351.584131) (xy 383.250301 -351.530148) (xy 383.265667 -351.477818)
			(xy 383.288324 -351.428209) (xy 383.31781 -351.382329) (xy 383.353526 -351.341112) (xy 383.394745 -351.305398)
			(xy 383.440626 -351.275914) (xy 383.490237 -351.25326) (xy 383.542567 -351.237897) (xy 383.596551 -351.230138)
			(xy 383.62382 -351.229676) (xy 384.48742 -351.229676) (xy 384.514691 -351.230088) (xy 384.568678 -351.237853)
			(xy 384.62101 -351.253221) (xy 384.670623 -351.275881) (xy 384.716506 -351.30537) (xy 384.757725 -351.341089)
			(xy 384.793442 -351.38231) (xy 384.822929 -351.428195) (xy 384.845586 -351.477808) (xy 384.860952 -351.530142)
			(xy 384.868714 -351.584129) (xy 384.868714 -351.638666) (xy 386.351562 -351.638666) (xy 386.351562 -351.584134)
			(xy 386.359323 -351.530158) (xy 386.374685 -351.477835) (xy 386.397338 -351.428231) (xy 386.426819 -351.382356)
			(xy 386.462529 -351.341143) (xy 386.50374 -351.305431) (xy 386.549614 -351.275948) (xy 386.599216 -351.253292)
			(xy 386.651538 -351.237927) (xy 386.705514 -351.230164) (xy 386.73278 -351.229676) (xy 387.59638 -351.229676)
			(xy 387.623655 -351.230062) (xy 387.677649 -351.237823) (xy 387.729989 -351.253189) (xy 387.77961 -351.275848)
			(xy 387.825501 -351.305338) (xy 387.866727 -351.341059) (xy 387.90245 -351.382283) (xy 387.931943 -351.428172)
			(xy 387.954604 -351.477792) (xy 387.969973 -351.530131) (xy 387.977736 -351.584125) (xy 387.977736 -351.63867)
			(xy 389.46044 -351.63867) (xy 389.46044 -351.58413) (xy 389.468202 -351.530145) (xy 389.483569 -351.477814)
			(xy 389.506227 -351.428203) (xy 389.535715 -351.382322) (xy 389.571434 -351.341105) (xy 389.612654 -351.305391)
			(xy 389.658538 -351.275908) (xy 389.708152 -351.253255) (xy 389.760484 -351.237893) (xy 389.81447 -351.230137)
			(xy 389.84174 -351.229676) (xy 390.70534 -351.229676) (xy 390.73261 -351.230089) (xy 390.786595 -351.237856)
			(xy 390.838925 -351.253227) (xy 390.888535 -351.275887) (xy 390.934415 -351.305377) (xy 390.975632 -351.341096)
			(xy 391.011347 -351.382317) (xy 391.040832 -351.4282) (xy 391.063487 -351.477813) (xy 391.078852 -351.530144)
			(xy 391.086614 -351.58413) (xy 391.086614 -351.638667) (xy 392.569462 -351.638667) (xy 392.569462 -351.584133)
			(xy 392.577223 -351.530155) (xy 392.592587 -351.477831) (xy 392.615241 -351.428226) (xy 392.644724 -351.382349)
			(xy 392.680436 -351.341136) (xy 392.721649 -351.305424) (xy 392.767526 -351.275941) (xy 392.817131 -351.253287)
			(xy 392.869455 -351.237923) (xy 392.923433 -351.230162) (xy 392.9507 -351.229676) (xy 393.8143 -351.229676)
			(xy 393.841572 -351.230087) (xy 393.895561 -351.237849) (xy 393.947896 -351.253216) (xy 393.997511 -351.275874)
			(xy 394.043396 -351.305363) (xy 394.084618 -351.341082) (xy 394.120337 -351.382304) (xy 394.149826 -351.428189)
			(xy 394.172484 -351.477804) (xy 394.187851 -351.530139) (xy 394.195613 -351.584128) (xy 394.195613 -351.638665)
			(xy 395.678462 -351.638665) (xy 395.678462 -351.584135) (xy 395.686222 -351.53016) (xy 395.701584 -351.477839)
			(xy 395.724235 -351.428237) (xy 395.753714 -351.382362) (xy 395.789421 -351.34115) (xy 395.83063 -351.305438)
			(xy 395.876502 -351.275954) (xy 395.926102 -351.253298) (xy 395.978421 -351.237931) (xy 396.032395 -351.230165)
			(xy 396.05966 -351.229676) (xy 396.92326 -351.229676) (xy 396.950536 -351.230061) (xy 397.004532 -351.237819)
			(xy 397.056875 -351.253183) (xy 397.106498 -351.275841) (xy 397.152391 -351.30533) (xy 397.19362 -351.341051)
			(xy 397.229346 -351.382277) (xy 397.25884 -351.428167) (xy 397.281503 -351.477788) (xy 397.296872 -351.530129)
			(xy 397.304636 -351.584124) (xy 397.304636 -351.638669) (xy 398.787339 -351.638669) (xy 398.787339 -351.584131)
			(xy 398.795101 -351.530148) (xy 398.810467 -351.477818) (xy 398.833124 -351.428209) (xy 398.86261 -351.382329)
			(xy 398.898326 -351.341112) (xy 398.939545 -351.305398) (xy 398.985426 -351.275914) (xy 399.035037 -351.25326)
			(xy 399.087367 -351.237897) (xy 399.141351 -351.230138) (xy 399.16862 -351.229676) (xy 400.03222 -351.229676)
			(xy 400.059491 -351.230088) (xy 400.113478 -351.237853) (xy 400.16581 -351.253221) (xy 400.215423 -351.275881)
			(xy 400.261306 -351.30537) (xy 400.302525 -351.341089) (xy 400.338242 -351.38231) (xy 400.367729 -351.428195)
			(xy 400.390386 -351.477808) (xy 400.405752 -351.530142) (xy 400.413514 -351.584129) (xy 400.413514 -351.638666)
			(xy 401.896362 -351.638666) (xy 401.896362 -351.584134) (xy 401.904123 -351.530158) (xy 401.919485 -351.477835)
			(xy 401.942138 -351.428231) (xy 401.971619 -351.382356) (xy 402.007329 -351.341143) (xy 402.04854 -351.305431)
			(xy 402.094414 -351.275948) (xy 402.144016 -351.253292) (xy 402.196338 -351.237927) (xy 402.250314 -351.230164)
			(xy 402.27758 -351.229676) (xy 403.14118 -351.229676) (xy 403.168455 -351.230062) (xy 403.222449 -351.237823)
			(xy 403.274789 -351.253189) (xy 403.32441 -351.275848) (xy 403.370301 -351.305338) (xy 403.411527 -351.341059)
			(xy 403.44725 -351.382283) (xy 403.476743 -351.428172) (xy 403.499404 -351.477792) (xy 403.514773 -351.530131)
			(xy 403.522536 -351.584125) (xy 403.522536 -351.638666) (xy 408.913862 -351.638666) (xy 408.913862 -351.584134)
			(xy 408.921623 -351.530156) (xy 408.936986 -351.477832) (xy 408.95964 -351.428228) (xy 408.989122 -351.382352)
			(xy 409.024833 -351.341138) (xy 409.066045 -351.305427) (xy 409.111921 -351.275944) (xy 409.161525 -351.253289)
			(xy 409.213848 -351.237925) (xy 409.267826 -351.230163) (xy 409.295092 -351.229676) (xy 410.158692 -351.229676)
			(xy 410.185966 -351.230063) (xy 410.239959 -351.237825) (xy 410.292298 -351.253192) (xy 410.341917 -351.275851)
			(xy 410.387806 -351.305342) (xy 410.429032 -351.341063) (xy 410.464753 -351.382287) (xy 410.494245 -351.428176)
			(xy 410.516905 -351.477794) (xy 410.532273 -351.530133) (xy 410.540036 -351.584126) (xy 410.540036 -351.638664)
			(xy 412.022862 -351.638664) (xy 412.022862 -351.584136) (xy 412.030622 -351.530162) (xy 412.045983 -351.477841)
			(xy 412.068634 -351.428239) (xy 412.098112 -351.382365) (xy 412.133819 -351.341153) (xy 412.175026 -351.305441)
			(xy 412.220897 -351.275957) (xy 412.270496 -351.2533) (xy 412.322815 -351.237932) (xy 412.376788 -351.230166)
			(xy 412.404052 -351.229676) (xy 413.267652 -351.229676) (xy 413.294928 -351.23006) (xy 413.348925 -351.237818)
			(xy 413.401269 -351.253181) (xy 413.450893 -351.275838) (xy 413.496787 -351.305328) (xy 413.538017 -351.341049)
			(xy 413.573744 -351.382274) (xy 413.603239 -351.428165) (xy 413.625902 -351.477786) (xy 413.641272 -351.530128)
			(xy 413.649036 -351.584124) (xy 413.649036 -351.638669) (xy 415.131739 -351.638669) (xy 415.131739 -351.584131)
			(xy 415.139501 -351.530149) (xy 415.154866 -351.47782) (xy 415.177523 -351.428211) (xy 415.207008 -351.382331)
			(xy 415.242724 -351.341115) (xy 415.283941 -351.305401) (xy 415.329822 -351.275917) (xy 415.379431 -351.253262)
			(xy 415.43176 -351.237899) (xy 415.485743 -351.230139) (xy 415.513012 -351.229676) (xy 416.376612 -351.229676)
			(xy 416.403884 -351.230087) (xy 416.457871 -351.237851) (xy 416.510204 -351.253219) (xy 416.559818 -351.275878)
			(xy 416.605702 -351.305367) (xy 416.646922 -351.341086) (xy 416.68264 -351.382308) (xy 416.712128 -351.428192)
			(xy 416.734785 -351.477807) (xy 416.750151 -351.530141) (xy 416.757914 -351.584128) (xy 416.757914 -351.638665)
			(xy 418.240762 -351.638665) (xy 418.240762 -351.584135) (xy 418.248522 -351.530159) (xy 418.263885 -351.477837)
			(xy 418.286537 -351.428233) (xy 418.316017 -351.382358) (xy 418.351726 -351.341146) (xy 418.392936 -351.305434)
			(xy 418.438809 -351.27595) (xy 418.48841 -351.253295) (xy 418.540731 -351.237928) (xy 418.594707 -351.230164)
			(xy 418.621972 -351.229676) (xy 419.485572 -351.229676) (xy 419.512847 -351.230062) (xy 419.566842 -351.237821)
			(xy 419.619184 -351.253187) (xy 419.668805 -351.275845) (xy 419.714697 -351.305335) (xy 419.755924 -351.341056)
			(xy 419.791648 -351.382281) (xy 419.821142 -351.42817) (xy 419.843803 -351.47779) (xy 419.859173 -351.53013)
			(xy 419.866936 -351.584125) (xy 419.866936 -351.63867) (xy 421.349639 -351.63867) (xy 421.349639 -351.58413)
			(xy 421.357402 -351.530146) (xy 421.372768 -351.477816) (xy 421.395426 -351.428206) (xy 421.424913 -351.382325)
			(xy 421.460631 -351.341108) (xy 421.501851 -351.305394) (xy 421.547734 -351.27591) (xy 421.597346 -351.253257)
			(xy 421.649677 -351.237895) (xy 421.703662 -351.230137) (xy 421.730932 -351.229676) (xy 422.594532 -351.229676)
			(xy 422.621803 -351.230089) (xy 422.675788 -351.237855) (xy 422.728119 -351.253224) (xy 422.77773 -351.275885)
			(xy 422.823612 -351.305374) (xy 422.864829 -351.341093) (xy 422.900545 -351.382314) (xy 422.930031 -351.428198)
			(xy 422.952687 -351.477811) (xy 422.968052 -351.530143) (xy 422.975814 -351.584129) (xy 422.975814 -351.638666)
			(xy 424.458662 -351.638666) (xy 424.458662 -351.584134) (xy 424.466423 -351.530156) (xy 424.481786 -351.477832)
			(xy 424.50444 -351.428228) (xy 424.533922 -351.382352) (xy 424.569633 -351.341138) (xy 424.610845 -351.305427)
			(xy 424.656721 -351.275944) (xy 424.706325 -351.253289) (xy 424.758648 -351.237925) (xy 424.812626 -351.230163)
			(xy 424.839892 -351.229676) (xy 425.703492 -351.229676) (xy 425.730766 -351.230063) (xy 425.784759 -351.237825)
			(xy 425.837098 -351.253192) (xy 425.886717 -351.275851) (xy 425.932606 -351.305342) (xy 425.973832 -351.341063)
			(xy 426.009553 -351.382287) (xy 426.039045 -351.428176) (xy 426.061705 -351.477794) (xy 426.077073 -351.530133)
			(xy 426.084836 -351.584126) (xy 426.084836 -351.638664) (xy 427.567662 -351.638664) (xy 427.567662 -351.584136)
			(xy 427.575422 -351.530162) (xy 427.590783 -351.477841) (xy 427.613434 -351.428239) (xy 427.642912 -351.382365)
			(xy 427.678619 -351.341153) (xy 427.719826 -351.305441) (xy 427.765697 -351.275957) (xy 427.815296 -351.2533)
			(xy 427.867615 -351.237932) (xy 427.921588 -351.230166) (xy 427.948852 -351.229676) (xy 428.812452 -351.229676)
			(xy 428.839728 -351.23006) (xy 428.893725 -351.237818) (xy 428.946069 -351.253181) (xy 428.995693 -351.275838)
			(xy 429.041587 -351.305328) (xy 429.082817 -351.341049) (xy 429.118544 -351.382274) (xy 429.148039 -351.428165)
			(xy 429.170702 -351.477786) (xy 429.186072 -351.530128) (xy 429.193836 -351.584124) (xy 429.193836 -351.638669)
			(xy 430.676539 -351.638669) (xy 430.676539 -351.584131) (xy 430.684301 -351.530149) (xy 430.699666 -351.47782)
			(xy 430.722323 -351.428211) (xy 430.751808 -351.382331) (xy 430.787524 -351.341115) (xy 430.828741 -351.305401)
			(xy 430.874622 -351.275917) (xy 430.924231 -351.253262) (xy 430.97656 -351.237899) (xy 431.030543 -351.230139)
			(xy 431.057812 -351.229676) (xy 431.921412 -351.229676) (xy 431.948684 -351.230087) (xy 432.002671 -351.237851)
			(xy 432.055004 -351.253219) (xy 432.104618 -351.275878) (xy 432.150502 -351.305367) (xy 432.191722 -351.341086)
			(xy 432.22744 -351.382308) (xy 432.256928 -351.428192) (xy 432.279585 -351.477807) (xy 432.294951 -351.530141)
			(xy 432.302714 -351.584128) (xy 432.302714 -351.638665) (xy 433.785562 -351.638665) (xy 433.785562 -351.584135)
			(xy 433.793322 -351.530159) (xy 433.808685 -351.477837) (xy 433.831337 -351.428233) (xy 433.860817 -351.382358)
			(xy 433.896526 -351.341146) (xy 433.937736 -351.305434) (xy 433.983609 -351.27595) (xy 434.03321 -351.253295)
			(xy 434.085531 -351.237928) (xy 434.139507 -351.230164) (xy 434.166772 -351.229676) (xy 435.030372 -351.229676)
			(xy 435.057647 -351.230062) (xy 435.111642 -351.237821) (xy 435.163984 -351.253187) (xy 435.213605 -351.275845)
			(xy 435.259497 -351.305335) (xy 435.300724 -351.341056) (xy 435.336448 -351.382281) (xy 435.365942 -351.42817)
			(xy 435.388603 -351.47779) (xy 435.403973 -351.53013) (xy 435.411736 -351.584125) (xy 435.411736 -351.63867)
			(xy 436.894439 -351.63867) (xy 436.894439 -351.58413) (xy 436.902202 -351.530146) (xy 436.917568 -351.477816)
			(xy 436.940226 -351.428206) (xy 436.969713 -351.382325) (xy 437.005431 -351.341108) (xy 437.046651 -351.305394)
			(xy 437.092534 -351.27591) (xy 437.142146 -351.253257) (xy 437.194477 -351.237895) (xy 437.248462 -351.230137)
			(xy 437.275732 -351.229676) (xy 438.139332 -351.229676) (xy 438.166603 -351.230089) (xy 438.220588 -351.237855)
			(xy 438.272919 -351.253224) (xy 438.32253 -351.275885) (xy 438.368412 -351.305374) (xy 438.409629 -351.341093)
			(xy 438.445345 -351.382314) (xy 438.474831 -351.428198) (xy 438.497487 -351.477811) (xy 438.512852 -351.530143)
			(xy 438.520614 -351.584129) (xy 438.520614 -351.638666) (xy 440.003462 -351.638666) (xy 440.003462 -351.584134)
			(xy 440.011223 -351.530156) (xy 440.026586 -351.477832) (xy 440.04924 -351.428228) (xy 440.078722 -351.382352)
			(xy 440.114433 -351.341138) (xy 440.155645 -351.305427) (xy 440.201521 -351.275944) (xy 440.251125 -351.253289)
			(xy 440.303448 -351.237925) (xy 440.357426 -351.230163) (xy 440.384692 -351.229676) (xy 441.248292 -351.229676)
			(xy 441.275566 -351.230063) (xy 441.329559 -351.237825) (xy 441.381898 -351.253192) (xy 441.431517 -351.275851)
			(xy 441.477406 -351.305342) (xy 441.518632 -351.341063) (xy 441.554353 -351.382287) (xy 441.583845 -351.428176)
			(xy 441.606505 -351.477794) (xy 441.621873 -351.530133) (xy 441.629636 -351.584126) (xy 441.629636 -351.638674)
			(xy 441.621873 -351.692667) (xy 441.606505 -351.745006) (xy 441.583845 -351.794624) (xy 441.554353 -351.840513)
			(xy 441.518632 -351.881737) (xy 441.477406 -351.917458) (xy 441.431517 -351.946949) (xy 441.381898 -351.969608)
			(xy 441.329559 -351.984975) (xy 441.275566 -351.992737) (xy 441.248292 -351.9932) (xy 440.384692 -351.9932)
			(xy 440.357426 -351.992637) (xy 440.303448 -351.984875) (xy 440.251125 -351.969511) (xy 440.201521 -351.946856)
			(xy 440.155645 -351.917373) (xy 440.114433 -351.881662) (xy 440.078722 -351.840448) (xy 440.04924 -351.794572)
			(xy 440.026586 -351.744968) (xy 440.011223 -351.692644) (xy 440.003462 -351.638666) (xy 438.520614 -351.638666)
			(xy 438.520614 -351.638671) (xy 438.512852 -351.692657) (xy 438.497487 -351.744989) (xy 438.474831 -351.794602)
			(xy 438.445345 -351.840486) (xy 438.409629 -351.881707) (xy 438.368412 -351.917426) (xy 438.32253 -351.946915)
			(xy 438.272919 -351.969576) (xy 438.220588 -351.984945) (xy 438.166603 -351.992711) (xy 438.139332 -351.9932)
			(xy 437.275732 -351.9932) (xy 437.248462 -351.992663) (xy 437.194477 -351.984905) (xy 437.142146 -351.969543)
			(xy 437.092534 -351.94689) (xy 437.046651 -351.917406) (xy 437.005431 -351.881692) (xy 436.969713 -351.840475)
			(xy 436.940226 -351.794594) (xy 436.917568 -351.744984) (xy 436.902202 -351.692654) (xy 436.894439 -351.63867)
			(xy 435.411736 -351.63867) (xy 435.411736 -351.638675) (xy 435.403973 -351.69267) (xy 435.388603 -351.74501)
			(xy 435.365942 -351.79463) (xy 435.336448 -351.840519) (xy 435.300724 -351.881744) (xy 435.259497 -351.917465)
			(xy 435.213605 -351.946955) (xy 435.163984 -351.969613) (xy 435.111642 -351.984979) (xy 435.057647 -351.992738)
			(xy 435.030372 -351.9932) (xy 434.166772 -351.9932) (xy 434.139507 -351.992636) (xy 434.085531 -351.984872)
			(xy 434.03321 -351.969505) (xy 433.983609 -351.94685) (xy 433.937736 -351.917366) (xy 433.896526 -351.881654)
			(xy 433.860817 -351.840442) (xy 433.831337 -351.794567) (xy 433.808685 -351.744963) (xy 433.793322 -351.692641)
			(xy 433.785562 -351.638665) (xy 432.302714 -351.638665) (xy 432.302714 -351.638672) (xy 432.294951 -351.692659)
			(xy 432.279585 -351.744993) (xy 432.256928 -351.794608) (xy 432.22744 -351.840492) (xy 432.191722 -351.881714)
			(xy 432.150502 -351.917433) (xy 432.104618 -351.946922) (xy 432.055004 -351.969581) (xy 432.002671 -351.984949)
			(xy 431.948684 -351.992713) (xy 431.921412 -351.9932) (xy 431.057812 -351.9932) (xy 431.030543 -351.992661)
			(xy 430.97656 -351.984901) (xy 430.924231 -351.969538) (xy 430.874622 -351.946883) (xy 430.828741 -351.917399)
			(xy 430.787524 -351.881685) (xy 430.751808 -351.840469) (xy 430.722323 -351.794589) (xy 430.699666 -351.74498)
			(xy 430.684301 -351.692651) (xy 430.676539 -351.638669) (xy 429.193836 -351.638669) (xy 429.193836 -351.638676)
			(xy 429.186072 -351.692672) (xy 429.170702 -351.745014) (xy 429.148039 -351.794635) (xy 429.118544 -351.840526)
			(xy 429.082817 -351.881751) (xy 429.041587 -351.917472) (xy 428.995693 -351.946962) (xy 428.946069 -351.969619)
			(xy 428.893725 -351.984982) (xy 428.839728 -351.99274) (xy 428.812452 -351.9932) (xy 427.948852 -351.9932)
			(xy 427.921588 -351.992634) (xy 427.867615 -351.984868) (xy 427.815296 -351.9695) (xy 427.765697 -351.946843)
			(xy 427.719826 -351.917359) (xy 427.678619 -351.881647) (xy 427.642912 -351.840435) (xy 427.613434 -351.794561)
			(xy 427.590783 -351.744959) (xy 427.575422 -351.692639) (xy 427.567662 -351.638664) (xy 426.084836 -351.638664)
			(xy 426.084836 -351.638674) (xy 426.077073 -351.692667) (xy 426.061705 -351.745006) (xy 426.039045 -351.794624)
			(xy 426.009553 -351.840513) (xy 425.973832 -351.881737) (xy 425.932606 -351.917458) (xy 425.886717 -351.946949)
			(xy 425.837098 -351.969608) (xy 425.784759 -351.984975) (xy 425.730766 -351.992737) (xy 425.703492 -351.9932)
			(xy 424.839892 -351.9932) (xy 424.812626 -351.992637) (xy 424.758648 -351.984875) (xy 424.706325 -351.969511)
			(xy 424.656721 -351.946856) (xy 424.610845 -351.917373) (xy 424.569633 -351.881662) (xy 424.533922 -351.840448)
			(xy 424.50444 -351.794572) (xy 424.481786 -351.744968) (xy 424.466423 -351.692644) (xy 424.458662 -351.638666)
			(xy 422.975814 -351.638666) (xy 422.975814 -351.638671) (xy 422.968052 -351.692657) (xy 422.952687 -351.744989)
			(xy 422.930031 -351.794602) (xy 422.900545 -351.840486) (xy 422.864829 -351.881707) (xy 422.823612 -351.917426)
			(xy 422.77773 -351.946915) (xy 422.728119 -351.969576) (xy 422.675788 -351.984945) (xy 422.621803 -351.992711)
			(xy 422.594532 -351.9932) (xy 421.730932 -351.9932) (xy 421.703662 -351.992663) (xy 421.649677 -351.984905)
			(xy 421.597346 -351.969543) (xy 421.547734 -351.94689) (xy 421.501851 -351.917406) (xy 421.460631 -351.881692)
			(xy 421.424913 -351.840475) (xy 421.395426 -351.794594) (xy 421.372768 -351.744984) (xy 421.357402 -351.692654)
			(xy 421.349639 -351.63867) (xy 419.866936 -351.63867) (xy 419.866936 -351.638675) (xy 419.859173 -351.69267)
			(xy 419.843803 -351.74501) (xy 419.821142 -351.79463) (xy 419.791648 -351.840519) (xy 419.755924 -351.881744)
			(xy 419.714697 -351.917465) (xy 419.668805 -351.946955) (xy 419.619184 -351.969613) (xy 419.566842 -351.984979)
			(xy 419.512847 -351.992738) (xy 419.485572 -351.9932) (xy 418.621972 -351.9932) (xy 418.594707 -351.992636)
			(xy 418.540731 -351.984872) (xy 418.48841 -351.969505) (xy 418.438809 -351.94685) (xy 418.392936 -351.917366)
			(xy 418.351726 -351.881654) (xy 418.316017 -351.840442) (xy 418.286537 -351.794567) (xy 418.263885 -351.744963)
			(xy 418.248522 -351.692641) (xy 418.240762 -351.638665) (xy 416.757914 -351.638665) (xy 416.757914 -351.638672)
			(xy 416.750151 -351.692659) (xy 416.734785 -351.744993) (xy 416.712128 -351.794608) (xy 416.68264 -351.840492)
			(xy 416.646922 -351.881714) (xy 416.605702 -351.917433) (xy 416.559818 -351.946922) (xy 416.510204 -351.969581)
			(xy 416.457871 -351.984949) (xy 416.403884 -351.992713) (xy 416.376612 -351.9932) (xy 415.513012 -351.9932)
			(xy 415.485743 -351.992661) (xy 415.43176 -351.984901) (xy 415.379431 -351.969538) (xy 415.329822 -351.946883)
			(xy 415.283941 -351.917399) (xy 415.242724 -351.881685) (xy 415.207008 -351.840469) (xy 415.177523 -351.794589)
			(xy 415.154866 -351.74498) (xy 415.139501 -351.692651) (xy 415.131739 -351.638669) (xy 413.649036 -351.638669)
			(xy 413.649036 -351.638676) (xy 413.641272 -351.692672) (xy 413.625902 -351.745014) (xy 413.603239 -351.794635)
			(xy 413.573744 -351.840526) (xy 413.538017 -351.881751) (xy 413.496787 -351.917472) (xy 413.450893 -351.946962)
			(xy 413.401269 -351.969619) (xy 413.348925 -351.984982) (xy 413.294928 -351.99274) (xy 413.267652 -351.9932)
			(xy 412.404052 -351.9932) (xy 412.376788 -351.992634) (xy 412.322815 -351.984868) (xy 412.270496 -351.9695)
			(xy 412.220897 -351.946843) (xy 412.175026 -351.917359) (xy 412.133819 -351.881647) (xy 412.098112 -351.840435)
			(xy 412.068634 -351.794561) (xy 412.045983 -351.744959) (xy 412.030622 -351.692639) (xy 412.022862 -351.638664)
			(xy 410.540036 -351.638664) (xy 410.540036 -351.638674) (xy 410.532273 -351.692667) (xy 410.516905 -351.745006)
			(xy 410.494245 -351.794624) (xy 410.464753 -351.840513) (xy 410.429032 -351.881737) (xy 410.387806 -351.917458)
			(xy 410.341917 -351.946949) (xy 410.292298 -351.969608) (xy 410.239959 -351.984975) (xy 410.185966 -351.992737)
			(xy 410.158692 -351.9932) (xy 409.295092 -351.9932) (xy 409.267826 -351.992637) (xy 409.213848 -351.984875)
			(xy 409.161525 -351.969511) (xy 409.111921 -351.946856) (xy 409.066045 -351.917373) (xy 409.024833 -351.881662)
			(xy 408.989122 -351.840448) (xy 408.95964 -351.794572) (xy 408.936986 -351.744968) (xy 408.921623 -351.692644)
			(xy 408.913862 -351.638666) (xy 403.522536 -351.638666) (xy 403.522536 -351.638675) (xy 403.514773 -351.692669)
			(xy 403.499404 -351.745008) (xy 403.476743 -351.794628) (xy 403.44725 -351.840517) (xy 403.411527 -351.881741)
			(xy 403.370301 -351.917462) (xy 403.32441 -351.946952) (xy 403.274789 -351.969611) (xy 403.222449 -351.984977)
			(xy 403.168455 -351.992738) (xy 403.14118 -351.9932) (xy 402.27758 -351.9932) (xy 402.250314 -351.992636)
			(xy 402.196338 -351.984873) (xy 402.144016 -351.969508) (xy 402.094414 -351.946852) (xy 402.04854 -351.917369)
			(xy 402.007329 -351.881657) (xy 401.971619 -351.840444) (xy 401.942138 -351.794569) (xy 401.919485 -351.744965)
			(xy 401.904123 -351.692642) (xy 401.896362 -351.638666) (xy 400.413514 -351.638666) (xy 400.413514 -351.638671)
			(xy 400.405752 -351.692658) (xy 400.390386 -351.744992) (xy 400.367729 -351.794605) (xy 400.338242 -351.84049)
			(xy 400.302525 -351.881711) (xy 400.261306 -351.91743) (xy 400.215423 -351.946919) (xy 400.16581 -351.969579)
			(xy 400.113478 -351.984947) (xy 400.059491 -351.992712) (xy 400.03222 -351.9932) (xy 399.16862 -351.9932)
			(xy 399.141351 -351.992662) (xy 399.087367 -351.984903) (xy 399.035037 -351.96954) (xy 398.985426 -351.946886)
			(xy 398.939545 -351.917402) (xy 398.898326 -351.881688) (xy 398.86261 -351.840471) (xy 398.833124 -351.794591)
			(xy 398.810467 -351.744982) (xy 398.795101 -351.692652) (xy 398.787339 -351.638669) (xy 397.304636 -351.638669)
			(xy 397.304636 -351.638676) (xy 397.296872 -351.692671) (xy 397.281503 -351.745012) (xy 397.25884 -351.794633)
			(xy 397.229346 -351.840523) (xy 397.19362 -351.881749) (xy 397.152391 -351.91747) (xy 397.106498 -351.946959)
			(xy 397.056875 -351.969617) (xy 397.004532 -351.984981) (xy 396.950536 -351.992739) (xy 396.92326 -351.9932)
			(xy 396.05966 -351.9932) (xy 396.032395 -351.992635) (xy 395.978421 -351.984869) (xy 395.926102 -351.969502)
			(xy 395.876502 -351.946846) (xy 395.83063 -351.917362) (xy 395.789421 -351.88165) (xy 395.753714 -351.840438)
			(xy 395.724235 -351.794563) (xy 395.701584 -351.744961) (xy 395.686222 -351.69264) (xy 395.678462 -351.638665)
			(xy 394.195613 -351.638665) (xy 394.195613 -351.638672) (xy 394.187851 -351.692661) (xy 394.172484 -351.744996)
			(xy 394.149826 -351.794611) (xy 394.120337 -351.840496) (xy 394.084618 -351.881718) (xy 394.043396 -351.917437)
			(xy 393.997511 -351.946926) (xy 393.947896 -351.969584) (xy 393.895561 -351.984951) (xy 393.841572 -351.992713)
			(xy 393.8143 -351.9932) (xy 392.9507 -351.9932) (xy 392.923433 -351.992638) (xy 392.869455 -351.984877)
			(xy 392.817131 -351.969513) (xy 392.767526 -351.946859) (xy 392.721649 -351.917376) (xy 392.680436 -351.881664)
			(xy 392.644724 -351.840451) (xy 392.615241 -351.794574) (xy 392.592587 -351.744969) (xy 392.577223 -351.692645)
			(xy 392.569462 -351.638667) (xy 391.086614 -351.638667) (xy 391.086614 -351.63867) (xy 391.078852 -351.692656)
			(xy 391.063487 -351.744987) (xy 391.040832 -351.7946) (xy 391.011347 -351.840483) (xy 390.975632 -351.881704)
			(xy 390.934415 -351.917423) (xy 390.888535 -351.946913) (xy 390.838925 -351.969573) (xy 390.786595 -351.984944)
			(xy 390.73261 -351.992711) (xy 390.70534 -351.9932) (xy 389.84174 -351.9932) (xy 389.81447 -351.992663)
			(xy 389.760484 -351.984907) (xy 389.708152 -351.969545) (xy 389.658538 -351.946892) (xy 389.612654 -351.917409)
			(xy 389.571434 -351.881695) (xy 389.535715 -351.840478) (xy 389.506227 -351.794597) (xy 389.483569 -351.744986)
			(xy 389.468202 -351.692655) (xy 389.46044 -351.63867) (xy 387.977736 -351.63867) (xy 387.977736 -351.638675)
			(xy 387.969973 -351.692669) (xy 387.954604 -351.745008) (xy 387.931943 -351.794628) (xy 387.90245 -351.840517)
			(xy 387.866727 -351.881741) (xy 387.825501 -351.917462) (xy 387.77961 -351.946952) (xy 387.729989 -351.969611)
			(xy 387.677649 -351.984977) (xy 387.623655 -351.992738) (xy 387.59638 -351.9932) (xy 386.73278 -351.9932)
			(xy 386.705514 -351.992636) (xy 386.651538 -351.984873) (xy 386.599216 -351.969508) (xy 386.549614 -351.946852)
			(xy 386.50374 -351.917369) (xy 386.462529 -351.881657) (xy 386.426819 -351.840444) (xy 386.397338 -351.794569)
			(xy 386.374685 -351.744965) (xy 386.359323 -351.692642) (xy 386.351562 -351.638666) (xy 384.868714 -351.638666)
			(xy 384.868714 -351.638671) (xy 384.860952 -351.692658) (xy 384.845586 -351.744992) (xy 384.822929 -351.794605)
			(xy 384.793442 -351.84049) (xy 384.757725 -351.881711) (xy 384.716506 -351.91743) (xy 384.670623 -351.946919)
			(xy 384.62101 -351.969579) (xy 384.568678 -351.984947) (xy 384.514691 -351.992712) (xy 384.48742 -351.9932)
			(xy 383.62382 -351.9932) (xy 383.596551 -351.992662) (xy 383.542567 -351.984903) (xy 383.490237 -351.96954)
			(xy 383.440626 -351.946886) (xy 383.394745 -351.917402) (xy 383.353526 -351.881688) (xy 383.31781 -351.840471)
			(xy 383.288324 -351.794591) (xy 383.265667 -351.744982) (xy 383.250301 -351.692652) (xy 383.242539 -351.638669)
			(xy 381.759836 -351.638669) (xy 381.759836 -351.638676) (xy 381.752072 -351.692671) (xy 381.736703 -351.745012)
			(xy 381.71404 -351.794633) (xy 381.684546 -351.840523) (xy 381.64882 -351.881749) (xy 381.607591 -351.91747)
			(xy 381.561698 -351.946959) (xy 381.512075 -351.969617) (xy 381.459732 -351.984981) (xy 381.405736 -351.992739)
			(xy 381.37846 -351.9932) (xy 380.51486 -351.9932) (xy 380.487595 -351.992635) (xy 380.433621 -351.984869)
			(xy 380.381302 -351.969502) (xy 380.331702 -351.946846) (xy 380.28583 -351.917362) (xy 380.244621 -351.88165)
			(xy 380.208914 -351.840438) (xy 380.179435 -351.794563) (xy 380.156784 -351.744961) (xy 380.141422 -351.69264)
			(xy 380.133662 -351.638665) (xy 378.650813 -351.638665) (xy 378.650813 -351.638672) (xy 378.643051 -351.692661)
			(xy 378.627684 -351.744996) (xy 378.605026 -351.794611) (xy 378.575537 -351.840496) (xy 378.539818 -351.881718)
			(xy 378.498596 -351.917437) (xy 378.452711 -351.946926) (xy 378.403096 -351.969584) (xy 378.350761 -351.984951)
			(xy 378.296772 -351.992713) (xy 378.2695 -351.9932) (xy 377.4059 -351.9932) (xy 377.378633 -351.992638)
			(xy 377.324655 -351.984877) (xy 377.272331 -351.969513) (xy 377.222726 -351.946859) (xy 377.176849 -351.917376)
			(xy 377.135636 -351.881664) (xy 377.099924 -351.840451) (xy 377.070441 -351.794574) (xy 377.047787 -351.744969)
			(xy 377.032423 -351.692645) (xy 377.024662 -351.638667) (xy 375.541814 -351.638667) (xy 375.541814 -351.63867)
			(xy 375.534052 -351.692656) (xy 375.518687 -351.744987) (xy 375.496032 -351.7946) (xy 375.466547 -351.840483)
			(xy 375.430832 -351.881704) (xy 375.389615 -351.917423) (xy 375.343735 -351.946913) (xy 375.294125 -351.969573)
			(xy 375.241795 -351.984944) (xy 375.18781 -351.992711) (xy 375.16054 -351.9932) (xy 374.29694 -351.9932)
			(xy 374.26967 -351.992663) (xy 374.215684 -351.984907) (xy 374.163352 -351.969545) (xy 374.113738 -351.946892)
			(xy 374.067854 -351.917409) (xy 374.026634 -351.881695) (xy 373.990915 -351.840478) (xy 373.961427 -351.794597)
			(xy 373.938769 -351.744986) (xy 373.923402 -351.692655) (xy 373.91564 -351.63867) (xy 372.432936 -351.63867)
			(xy 372.432936 -351.638675) (xy 372.425173 -351.692669) (xy 372.409804 -351.745008) (xy 372.387143 -351.794628)
			(xy 372.35765 -351.840517) (xy 372.321927 -351.881741) (xy 372.280701 -351.917462) (xy 372.23481 -351.946952)
			(xy 372.185189 -351.969611) (xy 372.132849 -351.984977) (xy 372.078855 -351.992738) (xy 372.05158 -351.9932)
			(xy 371.18798 -351.9932) (xy 371.160714 -351.992636) (xy 371.106738 -351.984873) (xy 371.054416 -351.969508)
			(xy 371.004814 -351.946852) (xy 370.95894 -351.917369) (xy 370.917729 -351.881657) (xy 370.882019 -351.840444)
			(xy 370.852538 -351.794569) (xy 370.829885 -351.744965) (xy 370.814523 -351.692642) (xy 370.806762 -351.638666)
			(xy 344.837313 -351.638666) (xy 344.837313 -351.638672) (xy 344.829551 -351.692661) (xy 344.814184 -351.744995)
			(xy 344.791526 -351.79461) (xy 344.762038 -351.840495) (xy 344.726319 -351.881717) (xy 344.685098 -351.917435)
			(xy 344.639213 -351.946924) (xy 344.589599 -351.969583) (xy 344.537264 -351.98495) (xy 344.483276 -351.992713)
			(xy 344.456004 -351.9932) (xy 343.592404 -351.9932) (xy 343.565136 -351.992661) (xy 343.511154 -351.9849)
			(xy 343.458826 -351.969536) (xy 343.409217 -351.94688) (xy 343.363337 -351.917396) (xy 343.322121 -351.881682)
			(xy 343.286407 -351.840466) (xy 343.256921 -351.794587) (xy 343.234266 -351.744978) (xy 343.218901 -351.69265)
			(xy 343.211139 -351.638668) (xy 341.728314 -351.638668) (xy 341.728314 -351.63867) (xy 341.720552 -351.692655)
			(xy 341.705188 -351.744986) (xy 341.682532 -351.794599) (xy 341.653048 -351.840482) (xy 341.617334 -351.881703)
			(xy 341.576117 -351.917421) (xy 341.530237 -351.946911) (xy 341.480628 -351.969572) (xy 341.428298 -351.984943)
			(xy 341.374314 -351.99271) (xy 341.347044 -351.9932) (xy 340.483444 -351.9932) (xy 340.456174 -351.992664)
			(xy 340.402187 -351.984907) (xy 340.349855 -351.969546) (xy 340.300241 -351.946894) (xy 340.254356 -351.91741)
			(xy 340.213135 -351.881696) (xy 340.177416 -351.840479) (xy 340.147928 -351.794598) (xy 340.125269 -351.744987)
			(xy 340.109902 -351.692656) (xy 340.10214 -351.63867) (xy 338.619436 -351.63867) (xy 338.619436 -351.638674)
			(xy 338.611673 -351.692668) (xy 338.596304 -351.745007) (xy 338.573643 -351.794626) (xy 338.544151 -351.840515)
			(xy 338.508429 -351.88174) (xy 338.467203 -351.917461) (xy 338.421312 -351.946951) (xy 338.371692 -351.96961)
			(xy 338.319352 -351.984976) (xy 338.265358 -351.992738) (xy 338.238084 -351.9932) (xy 337.374484 -351.9932)
			(xy 337.347218 -351.992637) (xy 337.293242 -351.984874) (xy 337.240919 -351.969509) (xy 337.191316 -351.946854)
			(xy 337.145442 -351.91737) (xy 337.10423 -351.881659) (xy 337.06852 -351.840446) (xy 337.039039 -351.79457)
			(xy 337.016386 -351.744966) (xy 337.001023 -351.692643) (xy 336.993262 -351.638666) (xy 335.510414 -351.638666)
			(xy 335.510414 -351.638671) (xy 335.502652 -351.692658) (xy 335.487286 -351.744991) (xy 335.464629 -351.794604)
			(xy 335.435143 -351.840488) (xy 335.399427 -351.88171) (xy 335.358208 -351.917428) (xy 335.312325 -351.946918)
			(xy 335.262713 -351.969578) (xy 335.210381 -351.984947) (xy 335.156395 -351.992712) (xy 335.129124 -351.9932)
			(xy 334.265524 -351.9932) (xy 334.238255 -351.992662) (xy 334.18427 -351.984904) (xy 334.13194 -351.969541)
			(xy 334.082329 -351.946887) (xy 334.036447 -351.917403) (xy 333.995228 -351.881689) (xy 333.959511 -351.840472)
			(xy 333.930024 -351.794592) (xy 333.907367 -351.744982) (xy 333.892001 -351.692653) (xy 333.884239 -351.638669)
			(xy 332.401536 -351.638669) (xy 332.401536 -351.638675) (xy 332.393772 -351.692671) (xy 332.378403 -351.745011)
			(xy 332.35574 -351.794632) (xy 332.326246 -351.840522) (xy 332.290522 -351.881747) (xy 332.249293 -351.917468)
			(xy 332.2034 -351.946958) (xy 332.153778 -351.969615) (xy 332.101436 -351.98498) (xy 332.047439 -351.992739)
			(xy 332.020164 -351.9932) (xy 331.156564 -351.9932) (xy 331.129299 -351.992635) (xy 331.075325 -351.98487)
			(xy 331.023005 -351.969503) (xy 330.973404 -351.946847) (xy 330.927532 -351.917363) (xy 330.886323 -351.881652)
			(xy 330.850615 -351.840439) (xy 330.821136 -351.794564) (xy 330.798484 -351.744962) (xy 330.783122 -351.69264)
			(xy 330.775362 -351.638665) (xy 329.292513 -351.638665) (xy 329.292513 -351.638672) (xy 329.284751 -351.692661)
			(xy 329.269384 -351.744995) (xy 329.246726 -351.79461) (xy 329.217238 -351.840495) (xy 329.181519 -351.881717)
			(xy 329.140298 -351.917435) (xy 329.094413 -351.946924) (xy 329.044799 -351.969583) (xy 328.992464 -351.98495)
			(xy 328.938476 -351.992713) (xy 328.911204 -351.9932) (xy 328.047604 -351.9932) (xy 328.020336 -351.992661)
			(xy 327.966354 -351.9849) (xy 327.914026 -351.969536) (xy 327.864417 -351.94688) (xy 327.818537 -351.917396)
			(xy 327.777321 -351.881682) (xy 327.741607 -351.840466) (xy 327.712121 -351.794587) (xy 327.689466 -351.744978)
			(xy 327.674101 -351.69265) (xy 327.666339 -351.638668) (xy 326.183514 -351.638668) (xy 326.183514 -351.63867)
			(xy 326.175752 -351.692655) (xy 326.160388 -351.744986) (xy 326.137732 -351.794599) (xy 326.108248 -351.840482)
			(xy 326.072534 -351.881703) (xy 326.031317 -351.917421) (xy 325.985437 -351.946911) (xy 325.935828 -351.969572)
			(xy 325.883498 -351.984943) (xy 325.829514 -351.99271) (xy 325.802244 -351.9932) (xy 324.938644 -351.9932)
			(xy 324.911374 -351.992664) (xy 324.857387 -351.984907) (xy 324.805055 -351.969546) (xy 324.755441 -351.946894)
			(xy 324.709556 -351.91741) (xy 324.668335 -351.881696) (xy 324.632616 -351.840479) (xy 324.603128 -351.794598)
			(xy 324.580469 -351.744987) (xy 324.565102 -351.692656) (xy 324.55734 -351.63867) (xy 323.074636 -351.63867)
			(xy 323.074636 -351.638674) (xy 323.066873 -351.692668) (xy 323.051504 -351.745007) (xy 323.028843 -351.794626)
			(xy 322.999351 -351.840515) (xy 322.963629 -351.88174) (xy 322.922403 -351.917461) (xy 322.876512 -351.946951)
			(xy 322.826892 -351.96961) (xy 322.774552 -351.984976) (xy 322.720558 -351.992738) (xy 322.693284 -351.9932)
			(xy 321.829684 -351.9932) (xy 321.802418 -351.992637) (xy 321.748442 -351.984874) (xy 321.696119 -351.969509)
			(xy 321.646516 -351.946854) (xy 321.600642 -351.91737) (xy 321.55943 -351.881659) (xy 321.52372 -351.840446)
			(xy 321.494239 -351.79457) (xy 321.471586 -351.744966) (xy 321.456223 -351.692643) (xy 321.448462 -351.638666)
			(xy 319.965614 -351.638666) (xy 319.965614 -351.638671) (xy 319.957852 -351.692658) (xy 319.942486 -351.744991)
			(xy 319.919829 -351.794604) (xy 319.890343 -351.840488) (xy 319.854627 -351.88171) (xy 319.813408 -351.917428)
			(xy 319.767525 -351.946918) (xy 319.717913 -351.969578) (xy 319.665581 -351.984947) (xy 319.611595 -351.992712)
			(xy 319.584324 -351.9932) (xy 318.720724 -351.9932) (xy 318.693455 -351.992662) (xy 318.63947 -351.984904)
			(xy 318.58714 -351.969541) (xy 318.537529 -351.946887) (xy 318.491647 -351.917403) (xy 318.450428 -351.881689)
			(xy 318.414711 -351.840472) (xy 318.385224 -351.794592) (xy 318.362567 -351.744982) (xy 318.347201 -351.692653)
			(xy 318.339439 -351.638669) (xy 316.856736 -351.638669) (xy 316.856736 -351.638675) (xy 316.848972 -351.692671)
			(xy 316.833603 -351.745011) (xy 316.81094 -351.794632) (xy 316.781446 -351.840522) (xy 316.745722 -351.881747)
			(xy 316.704493 -351.917468) (xy 316.6586 -351.946958) (xy 316.608978 -351.969615) (xy 316.556636 -351.98498)
			(xy 316.502639 -351.992739) (xy 316.475364 -351.9932) (xy 315.611764 -351.9932) (xy 315.584499 -351.992635)
			(xy 315.530525 -351.98487) (xy 315.478205 -351.969503) (xy 315.428604 -351.946847) (xy 315.382732 -351.917363)
			(xy 315.341523 -351.881652) (xy 315.305815 -351.840439) (xy 315.276336 -351.794564) (xy 315.253684 -351.744962)
			(xy 315.238322 -351.69264) (xy 315.230562 -351.638665) (xy 313.747713 -351.638665) (xy 313.747713 -351.638672)
			(xy 313.739951 -351.692661) (xy 313.724584 -351.744995) (xy 313.701926 -351.79461) (xy 313.672438 -351.840495)
			(xy 313.636719 -351.881717) (xy 313.595498 -351.917435) (xy 313.549613 -351.946924) (xy 313.499999 -351.969583)
			(xy 313.447664 -351.98495) (xy 313.393676 -351.992713) (xy 313.366404 -351.9932) (xy 312.502804 -351.9932)
			(xy 312.475536 -351.992661) (xy 312.421554 -351.9849) (xy 312.369226 -351.969536) (xy 312.319617 -351.94688)
			(xy 312.273737 -351.917396) (xy 312.232521 -351.881682) (xy 312.196807 -351.840466) (xy 312.167321 -351.794587)
			(xy 312.144666 -351.744978) (xy 312.129301 -351.69265) (xy 312.121539 -351.638668) (xy 300.231613 -351.638668)
			(xy 300.231613 -351.638672) (xy 300.223851 -351.692661) (xy 300.208484 -351.744995) (xy 300.185826 -351.79461)
			(xy 300.156337 -351.840496) (xy 300.120619 -351.881717) (xy 300.079397 -351.917436) (xy 300.033512 -351.946925)
			(xy 299.983897 -351.969584) (xy 299.931563 -351.984951) (xy 299.877574 -351.992713) (xy 299.850302 -351.9932)
			(xy 298.986702 -351.9932) (xy 298.959434 -351.992661) (xy 298.905452 -351.9849) (xy 298.853124 -351.969535)
			(xy 298.803516 -351.94688) (xy 298.757636 -351.917395) (xy 298.71642 -351.881681) (xy 298.680706 -351.840465)
			(xy 298.651221 -351.794586) (xy 298.628566 -351.744978) (xy 298.613201 -351.69265) (xy 298.605439 -351.638668)
			(xy 297.122614 -351.638668) (xy 297.122614 -351.63867) (xy 297.114852 -351.692655) (xy 297.099488 -351.744987)
			(xy 297.076832 -351.794599) (xy 297.047347 -351.840483) (xy 297.011633 -351.881703) (xy 296.970416 -351.917422)
			(xy 296.924536 -351.946912) (xy 296.874926 -351.969573) (xy 296.822597 -351.984943) (xy 296.768612 -351.992711)
			(xy 296.741342 -351.9932) (xy 295.877742 -351.9932) (xy 295.850472 -351.992663) (xy 295.796486 -351.984907)
			(xy 295.744153 -351.969546) (xy 295.69454 -351.946893) (xy 295.648655 -351.917409) (xy 295.607434 -351.881695)
			(xy 295.571716 -351.840478) (xy 295.542227 -351.794597) (xy 295.519569 -351.744986) (xy 295.504202 -351.692655)
			(xy 295.49644 -351.63867) (xy 294.013736 -351.63867) (xy 294.013736 -351.638675) (xy 294.005973 -351.692668)
			(xy 293.990604 -351.745008) (xy 293.967943 -351.794627) (xy 293.938451 -351.840516) (xy 293.902728 -351.881741)
			(xy 293.861502 -351.917462) (xy 293.815611 -351.946952) (xy 293.765991 -351.969611) (xy 293.713651 -351.984977)
			(xy 293.659657 -351.992738) (xy 293.632382 -351.9932) (xy 292.768782 -351.9932) (xy 292.741516 -351.992636)
			(xy 292.68754 -351.984873) (xy 292.635218 -351.969508) (xy 292.585615 -351.946853) (xy 292.539741 -351.91737)
			(xy 292.498529 -351.881658) (xy 292.46282 -351.840445) (xy 292.433338 -351.794569) (xy 292.410686 -351.744965)
			(xy 292.395323 -351.692642) (xy 292.387562 -351.638666) (xy 290.904714 -351.638666) (xy 290.904714 -351.638671)
			(xy 290.896952 -351.692658) (xy 290.881586 -351.744991) (xy 290.858929 -351.794605) (xy 290.829442 -351.840489)
			(xy 290.793726 -351.88171) (xy 290.752507 -351.917429) (xy 290.706624 -351.946919) (xy 290.657012 -351.969578)
			(xy 290.60468 -351.984947) (xy 290.550693 -351.992712) (xy 290.523422 -351.9932) (xy 289.659822 -351.9932)
			(xy 289.632553 -351.992662) (xy 289.578569 -351.984903) (xy 289.526239 -351.96954) (xy 289.476628 -351.946886)
			(xy 289.430746 -351.917402) (xy 289.389527 -351.881688) (xy 289.353811 -351.840472) (xy 289.324324 -351.794592)
			(xy 289.301667 -351.744982) (xy 289.286301 -351.692653) (xy 289.278539 -351.638669) (xy 287.795836 -351.638669)
			(xy 287.795836 -351.638675) (xy 287.788072 -351.692671) (xy 287.772703 -351.745012) (xy 287.75004 -351.794633)
			(xy 287.720546 -351.840523) (xy 287.684821 -351.881748) (xy 287.643592 -351.917469) (xy 287.597699 -351.946958)
			(xy 287.548076 -351.969616) (xy 287.495734 -351.98498) (xy 287.441737 -351.992739) (xy 287.414462 -351.9932)
			(xy 286.550862 -351.9932) (xy 286.523597 -351.992635) (xy 286.469623 -351.98487) (xy 286.417303 -351.969503)
			(xy 286.367703 -351.946847) (xy 286.321831 -351.917363) (xy 286.280622 -351.881651) (xy 286.244915 -351.840438)
			(xy 286.215435 -351.794564) (xy 286.192784 -351.744961) (xy 286.177422 -351.69264) (xy 286.169662 -351.638665)
			(xy 284.686813 -351.638665) (xy 284.686813 -351.638672) (xy 284.679051 -351.692661) (xy 284.663684 -351.744995)
			(xy 284.641026 -351.79461) (xy 284.611537 -351.840496) (xy 284.575819 -351.881717) (xy 284.534597 -351.917436)
			(xy 284.488712 -351.946925) (xy 284.439097 -351.969584) (xy 284.386763 -351.984951) (xy 284.332774 -351.992713)
			(xy 284.305502 -351.9932) (xy 283.441902 -351.9932) (xy 283.414634 -351.992661) (xy 283.360652 -351.9849)
			(xy 283.308324 -351.969535) (xy 283.258716 -351.94688) (xy 283.212836 -351.917395) (xy 283.17162 -351.881681)
			(xy 283.135906 -351.840465) (xy 283.106421 -351.794586) (xy 283.083766 -351.744978) (xy 283.068401 -351.69265)
			(xy 283.060639 -351.638668) (xy 281.577814 -351.638668) (xy 281.577814 -351.63867) (xy 281.570052 -351.692655)
			(xy 281.554688 -351.744987) (xy 281.532032 -351.794599) (xy 281.502547 -351.840483) (xy 281.466833 -351.881703)
			(xy 281.425616 -351.917422) (xy 281.379736 -351.946912) (xy 281.330126 -351.969573) (xy 281.277797 -351.984943)
			(xy 281.223812 -351.992711) (xy 281.196542 -351.9932) (xy 280.332942 -351.9932) (xy 280.305672 -351.992663)
			(xy 280.251686 -351.984907) (xy 280.199353 -351.969546) (xy 280.14974 -351.946893) (xy 280.103855 -351.917409)
			(xy 280.062634 -351.881695) (xy 280.026916 -351.840478) (xy 279.997427 -351.794597) (xy 279.974769 -351.744986)
			(xy 279.959402 -351.692655) (xy 279.95164 -351.63867) (xy 278.468936 -351.63867) (xy 278.468936 -351.638675)
			(xy 278.461173 -351.692668) (xy 278.445804 -351.745008) (xy 278.423143 -351.794627) (xy 278.393651 -351.840516)
			(xy 278.357928 -351.881741) (xy 278.316702 -351.917462) (xy 278.270811 -351.946952) (xy 278.221191 -351.969611)
			(xy 278.168851 -351.984977) (xy 278.114857 -351.992738) (xy 278.087582 -351.9932) (xy 277.223982 -351.9932)
			(xy 277.196716 -351.992636) (xy 277.14274 -351.984873) (xy 277.090418 -351.969508) (xy 277.040815 -351.946853)
			(xy 276.994941 -351.91737) (xy 276.953729 -351.881658) (xy 276.91802 -351.840445) (xy 276.888538 -351.794569)
			(xy 276.865886 -351.744965) (xy 276.850523 -351.692642) (xy 276.842762 -351.638666) (xy 275.359914 -351.638666)
			(xy 275.359914 -351.638671) (xy 275.352152 -351.692658) (xy 275.336786 -351.744991) (xy 275.314129 -351.794605)
			(xy 275.284642 -351.840489) (xy 275.248926 -351.88171) (xy 275.207707 -351.917429) (xy 275.161824 -351.946919)
			(xy 275.112212 -351.969578) (xy 275.05988 -351.984947) (xy 275.005893 -351.992712) (xy 274.978622 -351.9932)
			(xy 274.115022 -351.9932) (xy 274.087753 -351.992662) (xy 274.033769 -351.984903) (xy 273.981439 -351.96954)
			(xy 273.931828 -351.946886) (xy 273.885946 -351.917402) (xy 273.844727 -351.881688) (xy 273.809011 -351.840472)
			(xy 273.779524 -351.794592) (xy 273.756867 -351.744982) (xy 273.741501 -351.692653) (xy 273.733739 -351.638669)
			(xy 272.251036 -351.638669) (xy 272.251036 -351.638675) (xy 272.243272 -351.692671) (xy 272.227903 -351.745012)
			(xy 272.20524 -351.794633) (xy 272.175746 -351.840523) (xy 272.140021 -351.881748) (xy 272.098792 -351.917469)
			(xy 272.052899 -351.946958) (xy 272.003276 -351.969616) (xy 271.950934 -351.98498) (xy 271.896937 -351.992739)
			(xy 271.869662 -351.9932) (xy 271.006062 -351.9932) (xy 270.978797 -351.992635) (xy 270.924823 -351.98487)
			(xy 270.872503 -351.969503) (xy 270.822903 -351.946847) (xy 270.777031 -351.917363) (xy 270.735822 -351.881651)
			(xy 270.700115 -351.840438) (xy 270.670635 -351.794564) (xy 270.647984 -351.744961) (xy 270.632622 -351.69264)
			(xy 270.624862 -351.638665) (xy 269.142013 -351.638665) (xy 269.142013 -351.638672) (xy 269.134251 -351.692661)
			(xy 269.118884 -351.744995) (xy 269.096226 -351.79461) (xy 269.066737 -351.840496) (xy 269.031019 -351.881717)
			(xy 268.989797 -351.917436) (xy 268.943912 -351.946925) (xy 268.894297 -351.969584) (xy 268.841963 -351.984951)
			(xy 268.787974 -351.992713) (xy 268.760702 -351.9932) (xy 267.897102 -351.9932) (xy 267.869834 -351.992661)
			(xy 267.815852 -351.9849) (xy 267.763524 -351.969535) (xy 267.713916 -351.94688) (xy 267.668036 -351.917395)
			(xy 267.62682 -351.881681) (xy 267.591106 -351.840465) (xy 267.561621 -351.794586) (xy 267.538966 -351.744978)
			(xy 267.523601 -351.69265) (xy 267.515839 -351.638668) (xy 194.520614 -351.638668) (xy 194.520614 -351.638672)
			(xy 194.512851 -351.692659) (xy 194.497485 -351.744993) (xy 194.474828 -351.794608) (xy 194.44534 -351.840492)
			(xy 194.409622 -351.881714) (xy 194.368402 -351.917433) (xy 194.322518 -351.946922) (xy 194.272904 -351.969581)
			(xy 194.220571 -351.984949) (xy 194.166584 -351.992713) (xy 194.139312 -351.9932) (xy 193.275712 -351.9932)
			(xy 193.248443 -351.992661) (xy 193.19446 -351.984901) (xy 193.142131 -351.969538) (xy 193.092522 -351.946883)
			(xy 193.046641 -351.917399) (xy 193.005424 -351.881685) (xy 192.969708 -351.840469) (xy 192.940223 -351.794589)
			(xy 192.917566 -351.74498) (xy 192.902201 -351.692651) (xy 192.894439 -351.638669) (xy 191.411736 -351.638669)
			(xy 191.411736 -351.638676) (xy 191.403972 -351.692672) (xy 191.388602 -351.745014) (xy 191.365939 -351.794635)
			(xy 191.336444 -351.840526) (xy 191.300717 -351.881751) (xy 191.259487 -351.917472) (xy 191.213593 -351.946962)
			(xy 191.163969 -351.969619) (xy 191.111625 -351.984982) (xy 191.057628 -351.99274) (xy 191.030352 -351.9932)
			(xy 190.166752 -351.9932) (xy 190.139488 -351.992634) (xy 190.085515 -351.984868) (xy 190.033196 -351.9695)
			(xy 189.983597 -351.946843) (xy 189.937726 -351.917359) (xy 189.896519 -351.881647) (xy 189.860812 -351.840435)
			(xy 189.831334 -351.794561) (xy 189.808683 -351.744959) (xy 189.793322 -351.692639) (xy 189.785562 -351.638664)
			(xy 188.302736 -351.638664) (xy 188.302736 -351.638674) (xy 188.294973 -351.692667) (xy 188.279605 -351.745006)
			(xy 188.256945 -351.794624) (xy 188.227453 -351.840513) (xy 188.191732 -351.881737) (xy 188.150506 -351.917458)
			(xy 188.104617 -351.946949) (xy 188.054998 -351.969608) (xy 188.002659 -351.984975) (xy 187.948666 -351.992737)
			(xy 187.921392 -351.9932) (xy 187.057792 -351.9932) (xy 187.030526 -351.992637) (xy 186.976548 -351.984875)
			(xy 186.924225 -351.969511) (xy 186.874621 -351.946856) (xy 186.828745 -351.917373) (xy 186.787533 -351.881662)
			(xy 186.751822 -351.840448) (xy 186.72234 -351.794572) (xy 186.699686 -351.744968) (xy 186.684323 -351.692644)
			(xy 186.676562 -351.638666) (xy 185.193714 -351.638666) (xy 185.193714 -351.638671) (xy 185.185952 -351.692657)
			(xy 185.170587 -351.744989) (xy 185.147931 -351.794602) (xy 185.118445 -351.840486) (xy 185.082729 -351.881707)
			(xy 185.041512 -351.917426) (xy 184.99563 -351.946915) (xy 184.946019 -351.969576) (xy 184.893688 -351.984945)
			(xy 184.839703 -351.992711) (xy 184.812432 -351.9932) (xy 183.948832 -351.9932) (xy 183.921562 -351.992663)
			(xy 183.867577 -351.984905) (xy 183.815246 -351.969543) (xy 183.765634 -351.94689) (xy 183.719751 -351.917406)
			(xy 183.678531 -351.881692) (xy 183.642813 -351.840475) (xy 183.613326 -351.794594) (xy 183.590668 -351.744984)
			(xy 183.575302 -351.692654) (xy 183.567539 -351.63867) (xy 182.084836 -351.63867) (xy 182.084836 -351.638675)
			(xy 182.077073 -351.69267) (xy 182.061703 -351.74501) (xy 182.039042 -351.79463) (xy 182.009548 -351.840519)
			(xy 181.973824 -351.881744) (xy 181.932597 -351.917465) (xy 181.886705 -351.946955) (xy 181.837084 -351.969613)
			(xy 181.784742 -351.984979) (xy 181.730747 -351.992738) (xy 181.703472 -351.9932) (xy 180.839872 -351.9932)
			(xy 180.812607 -351.992636) (xy 180.758631 -351.984872) (xy 180.70631 -351.969505) (xy 180.656709 -351.94685)
			(xy 180.610836 -351.917366) (xy 180.569626 -351.881654) (xy 180.533917 -351.840442) (xy 180.504437 -351.794567)
			(xy 180.481785 -351.744963) (xy 180.466422 -351.692641) (xy 180.458662 -351.638665) (xy 178.975814 -351.638665)
			(xy 178.975814 -351.638672) (xy 178.968051 -351.692659) (xy 178.952685 -351.744993) (xy 178.930028 -351.794608)
			(xy 178.90054 -351.840492) (xy 178.864822 -351.881714) (xy 178.823602 -351.917433) (xy 178.777718 -351.946922)
			(xy 178.728104 -351.969581) (xy 178.675771 -351.984949) (xy 178.621784 -351.992713) (xy 178.594512 -351.9932)
			(xy 177.730912 -351.9932) (xy 177.703643 -351.992661) (xy 177.64966 -351.984901) (xy 177.597331 -351.969538)
			(xy 177.547722 -351.946883) (xy 177.501841 -351.917399) (xy 177.460624 -351.881685) (xy 177.424908 -351.840469)
			(xy 177.395423 -351.794589) (xy 177.372766 -351.74498) (xy 177.357401 -351.692651) (xy 177.349639 -351.638669)
			(xy 175.866936 -351.638669) (xy 175.866936 -351.638676) (xy 175.859172 -351.692672) (xy 175.843802 -351.745014)
			(xy 175.821139 -351.794635) (xy 175.791644 -351.840526) (xy 175.755917 -351.881751) (xy 175.714687 -351.917472)
			(xy 175.668793 -351.946962) (xy 175.619169 -351.969619) (xy 175.566825 -351.984982) (xy 175.512828 -351.99274)
			(xy 175.485552 -351.9932) (xy 174.621952 -351.9932) (xy 174.594688 -351.992634) (xy 174.540715 -351.984868)
			(xy 174.488396 -351.9695) (xy 174.438797 -351.946843) (xy 174.392926 -351.917359) (xy 174.351719 -351.881647)
			(xy 174.316012 -351.840435) (xy 174.286534 -351.794561) (xy 174.263883 -351.744959) (xy 174.248522 -351.692639)
			(xy 174.240762 -351.638664) (xy 172.757936 -351.638664) (xy 172.757936 -351.638674) (xy 172.750173 -351.692667)
			(xy 172.734805 -351.745006) (xy 172.712145 -351.794624) (xy 172.682653 -351.840513) (xy 172.646932 -351.881737)
			(xy 172.605706 -351.917458) (xy 172.559817 -351.946949) (xy 172.510198 -351.969608) (xy 172.457859 -351.984975)
			(xy 172.403866 -351.992737) (xy 172.376592 -351.9932) (xy 171.512992 -351.9932) (xy 171.485726 -351.992637)
			(xy 171.431748 -351.984875) (xy 171.379425 -351.969511) (xy 171.329821 -351.946856) (xy 171.283945 -351.917373)
			(xy 171.242733 -351.881662) (xy 171.207022 -351.840448) (xy 171.17754 -351.794572) (xy 171.154886 -351.744968)
			(xy 171.139523 -351.692644) (xy 171.131762 -351.638666) (xy 169.648914 -351.638666) (xy 169.648914 -351.638671)
			(xy 169.641152 -351.692657) (xy 169.625787 -351.744989) (xy 169.603131 -351.794602) (xy 169.573645 -351.840486)
			(xy 169.537929 -351.881707) (xy 169.496712 -351.917426) (xy 169.45083 -351.946915) (xy 169.401219 -351.969576)
			(xy 169.348888 -351.984945) (xy 169.294903 -351.992711) (xy 169.267632 -351.9932) (xy 168.404032 -351.9932)
			(xy 168.376762 -351.992663) (xy 168.322777 -351.984905) (xy 168.270446 -351.969543) (xy 168.220834 -351.94689)
			(xy 168.174951 -351.917406) (xy 168.133731 -351.881692) (xy 168.098013 -351.840475) (xy 168.068526 -351.794594)
			(xy 168.045868 -351.744984) (xy 168.030502 -351.692654) (xy 168.022739 -351.63867) (xy 166.540036 -351.63867)
			(xy 166.540036 -351.638675) (xy 166.532273 -351.69267) (xy 166.516903 -351.74501) (xy 166.494242 -351.79463)
			(xy 166.464748 -351.840519) (xy 166.429024 -351.881744) (xy 166.387797 -351.917465) (xy 166.341905 -351.946955)
			(xy 166.292284 -351.969613) (xy 166.239942 -351.984979) (xy 166.185947 -351.992738) (xy 166.158672 -351.9932)
			(xy 165.295072 -351.9932) (xy 165.267807 -351.992636) (xy 165.213831 -351.984872) (xy 165.16151 -351.969505)
			(xy 165.111909 -351.94685) (xy 165.066036 -351.917366) (xy 165.024826 -351.881654) (xy 164.989117 -351.840442)
			(xy 164.959637 -351.794567) (xy 164.936985 -351.744963) (xy 164.921622 -351.692641) (xy 164.913862 -351.638665)
			(xy 163.431014 -351.638665) (xy 163.431014 -351.638672) (xy 163.423251 -351.692659) (xy 163.407885 -351.744993)
			(xy 163.385228 -351.794608) (xy 163.35574 -351.840492) (xy 163.320022 -351.881714) (xy 163.278802 -351.917433)
			(xy 163.232918 -351.946922) (xy 163.183304 -351.969581) (xy 163.130971 -351.984949) (xy 163.076984 -351.992713)
			(xy 163.049712 -351.9932) (xy 162.186112 -351.9932) (xy 162.158843 -351.992661) (xy 162.10486 -351.984901)
			(xy 162.052531 -351.969538) (xy 162.002922 -351.946883) (xy 161.957041 -351.917399) (xy 161.915824 -351.881685)
			(xy 161.880108 -351.840469) (xy 161.850623 -351.794589) (xy 161.827966 -351.74498) (xy 161.812601 -351.692651)
			(xy 161.804839 -351.638669) (xy 144.196614 -351.638669) (xy 144.196614 -351.638672) (xy 144.188851 -351.69266)
			(xy 144.173485 -351.744994) (xy 144.150827 -351.794609) (xy 144.121339 -351.840494) (xy 144.085621 -351.881715)
			(xy 144.0444 -351.917434) (xy 143.998516 -351.946923) (xy 143.948902 -351.969582) (xy 143.896568 -351.98495)
			(xy 143.84258 -351.992713) (xy 143.815308 -351.9932) (xy 142.951708 -351.9932) (xy 142.924439 -351.992661)
			(xy 142.870457 -351.984901) (xy 142.818129 -351.969537) (xy 142.768519 -351.946882) (xy 142.722639 -351.917397)
			(xy 142.681422 -351.881683) (xy 142.645707 -351.840467) (xy 142.616222 -351.794588) (xy 142.593566 -351.744979)
			(xy 142.578201 -351.692651) (xy 142.570439 -351.638669) (xy 141.087614 -351.638669) (xy 141.087614 -351.63867)
			(xy 141.079852 -351.692655) (xy 141.064488 -351.744986) (xy 141.041833 -351.794597) (xy 141.012349 -351.840481)
			(xy 140.976635 -351.881701) (xy 140.935419 -351.91742) (xy 140.88954 -351.94691) (xy 140.839931 -351.969571)
			(xy 140.787602 -351.984942) (xy 140.733618 -351.99271) (xy 140.706348 -351.9932) (xy 139.842748 -351.9932)
			(xy 139.815477 -351.992664) (xy 139.761491 -351.984908) (xy 139.709158 -351.969547) (xy 139.659543 -351.946895)
			(xy 139.613658 -351.917411) (xy 139.572436 -351.881698) (xy 139.536717 -351.84048) (xy 139.507228 -351.794599)
			(xy 139.484569 -351.744987) (xy 139.469202 -351.692656) (xy 139.46144 -351.63867) (xy 137.978736 -351.63867)
			(xy 137.978736 -351.638674) (xy 137.970973 -351.692668) (xy 137.955605 -351.745006) (xy 137.932944 -351.794625)
			(xy 137.903452 -351.840514) (xy 137.86773 -351.881739) (xy 137.826504 -351.91746) (xy 137.780615 -351.94695)
			(xy 137.730995 -351.969609) (xy 137.678656 -351.984976) (xy 137.624662 -351.992737) (xy 137.597388 -351.9932)
			(xy 136.733788 -351.9932) (xy 136.706522 -351.992637) (xy 136.652545 -351.984875) (xy 136.600222 -351.96951)
			(xy 136.550618 -351.946855) (xy 136.504744 -351.917372) (xy 136.463531 -351.88166) (xy 136.427821 -351.840447)
			(xy 136.398339 -351.794571) (xy 136.375686 -351.744967) (xy 136.360323 -351.692643) (xy 136.352562 -351.638666)
			(xy 134.869714 -351.638666) (xy 134.869714 -351.638671) (xy 134.861952 -351.692657) (xy 134.846586 -351.74499)
			(xy 134.82393 -351.794603) (xy 134.794444 -351.840487) (xy 134.758728 -351.881708) (xy 134.71751 -351.917427)
			(xy 134.671628 -351.946917) (xy 134.622016 -351.969577) (xy 134.569685 -351.984946) (xy 134.515699 -351.992712)
			(xy 134.488428 -351.9932) (xy 133.624828 -351.9932) (xy 133.597558 -351.992663) (xy 133.543574 -351.984904)
			(xy 133.491243 -351.969542) (xy 133.441631 -351.946888) (xy 133.395749 -351.917404) (xy 133.354529 -351.881691)
			(xy 133.318812 -351.840474) (xy 133.289325 -351.794593) (xy 133.266668 -351.744983) (xy 133.251302 -351.692654)
			(xy 133.243539 -351.63867) (xy 131.760836 -351.63867) (xy 131.760836 -351.638675) (xy 131.753073 -351.69267)
			(xy 131.737703 -351.745011) (xy 131.715041 -351.794631) (xy 131.685547 -351.840521) (xy 131.649823 -351.881746)
			(xy 131.608595 -351.917467) (xy 131.562703 -351.946956) (xy 131.513081 -351.969614) (xy 131.460739 -351.984979)
			(xy 131.406743 -351.992739) (xy 131.379468 -351.9932) (xy 130.515868 -351.9932) (xy 130.488603 -351.992635)
			(xy 130.434628 -351.984871) (xy 130.382308 -351.969504) (xy 130.332706 -351.946849) (xy 130.286834 -351.917365)
			(xy 130.245624 -351.881653) (xy 130.209916 -351.84044) (xy 130.180436 -351.794566) (xy 130.157784 -351.744962)
			(xy 130.142422 -351.692641) (xy 130.134662 -351.638665) (xy 128.651814 -351.638665) (xy 128.651814 -351.638672)
			(xy 128.644051 -351.69266) (xy 128.628685 -351.744994) (xy 128.606027 -351.794609) (xy 128.576539 -351.840494)
			(xy 128.540821 -351.881715) (xy 128.4996 -351.917434) (xy 128.453716 -351.946923) (xy 128.404102 -351.969582)
			(xy 128.351768 -351.98495) (xy 128.29778 -351.992713) (xy 128.270508 -351.9932) (xy 127.406908 -351.9932)
			(xy 127.379639 -351.992661) (xy 127.325657 -351.984901) (xy 127.273329 -351.969537) (xy 127.223719 -351.946882)
			(xy 127.177839 -351.917397) (xy 127.136622 -351.881683) (xy 127.100907 -351.840467) (xy 127.071422 -351.794588)
			(xy 127.048766 -351.744979) (xy 127.033401 -351.692651) (xy 127.025639 -351.638669) (xy 125.542814 -351.638669)
			(xy 125.542814 -351.63867) (xy 125.535052 -351.692655) (xy 125.519688 -351.744986) (xy 125.497033 -351.794597)
			(xy 125.467549 -351.840481) (xy 125.431835 -351.881701) (xy 125.390619 -351.91742) (xy 125.34474 -351.94691)
			(xy 125.295131 -351.969571) (xy 125.242802 -351.984942) (xy 125.188818 -351.99271) (xy 125.161548 -351.9932)
			(xy 124.297948 -351.9932) (xy 124.270677 -351.992664) (xy 124.216691 -351.984908) (xy 124.164358 -351.969547)
			(xy 124.114743 -351.946895) (xy 124.068858 -351.917411) (xy 124.027636 -351.881698) (xy 123.991917 -351.84048)
			(xy 123.962428 -351.794599) (xy 123.939769 -351.744987) (xy 123.924402 -351.692656) (xy 123.91664 -351.63867)
			(xy 122.433936 -351.63867) (xy 122.433936 -351.638674) (xy 122.426173 -351.692668) (xy 122.410805 -351.745006)
			(xy 122.388144 -351.794625) (xy 122.358652 -351.840514) (xy 122.32293 -351.881739) (xy 122.281704 -351.91746)
			(xy 122.235815 -351.94695) (xy 122.186195 -351.969609) (xy 122.133856 -351.984976) (xy 122.079862 -351.992737)
			(xy 122.052588 -351.9932) (xy 121.188988 -351.9932) (xy 121.161722 -351.992637) (xy 121.107745 -351.984875)
			(xy 121.055422 -351.96951) (xy 121.005818 -351.946855) (xy 120.959944 -351.917372) (xy 120.918731 -351.88166)
			(xy 120.883021 -351.840447) (xy 120.853539 -351.794571) (xy 120.830886 -351.744967) (xy 120.815523 -351.692643)
			(xy 120.807762 -351.638666) (xy 119.324914 -351.638666) (xy 119.324914 -351.638671) (xy 119.317152 -351.692657)
			(xy 119.301786 -351.74499) (xy 119.27913 -351.794603) (xy 119.249644 -351.840487) (xy 119.213928 -351.881708)
			(xy 119.17271 -351.917427) (xy 119.126828 -351.946917) (xy 119.077216 -351.969577) (xy 119.024885 -351.984946)
			(xy 118.970899 -351.992712) (xy 118.943628 -351.9932) (xy 118.080028 -351.9932) (xy 118.052758 -351.992663)
			(xy 117.998774 -351.984904) (xy 117.946443 -351.969542) (xy 117.896831 -351.946888) (xy 117.850949 -351.917404)
			(xy 117.809729 -351.881691) (xy 117.774012 -351.840474) (xy 117.744525 -351.794593) (xy 117.721868 -351.744983)
			(xy 117.706502 -351.692654) (xy 117.698739 -351.63867) (xy 116.216036 -351.63867) (xy 116.216036 -351.638675)
			(xy 116.208273 -351.69267) (xy 116.192903 -351.745011) (xy 116.170241 -351.794631) (xy 116.140747 -351.840521)
			(xy 116.105023 -351.881746) (xy 116.063795 -351.917467) (xy 116.017903 -351.946956) (xy 115.968281 -351.969614)
			(xy 115.915939 -351.984979) (xy 115.861943 -351.992739) (xy 115.834668 -351.9932) (xy 114.971068 -351.9932)
			(xy 114.943803 -351.992635) (xy 114.889828 -351.984871) (xy 114.837508 -351.969504) (xy 114.787906 -351.946849)
			(xy 114.742034 -351.917365) (xy 114.700824 -351.881653) (xy 114.665116 -351.84044) (xy 114.635636 -351.794566)
			(xy 114.612984 -351.744962) (xy 114.597622 -351.692641) (xy 114.589862 -351.638665) (xy 113.107014 -351.638665)
			(xy 113.107014 -351.638672) (xy 113.099251 -351.69266) (xy 113.083885 -351.744994) (xy 113.061227 -351.794609)
			(xy 113.031739 -351.840494) (xy 112.996021 -351.881715) (xy 112.9548 -351.917434) (xy 112.908916 -351.946923)
			(xy 112.859302 -351.969582) (xy 112.806968 -351.98495) (xy 112.75298 -351.992713) (xy 112.725708 -351.9932)
			(xy 111.862108 -351.9932) (xy 111.834839 -351.992661) (xy 111.780857 -351.984901) (xy 111.728529 -351.969537)
			(xy 111.678919 -351.946882) (xy 111.633039 -351.917397) (xy 111.591822 -351.881683) (xy 111.556107 -351.840467)
			(xy 111.526622 -351.794588) (xy 111.503966 -351.744979) (xy 111.488601 -351.692651) (xy 111.480839 -351.638669)
			(xy 93.706714 -351.638669) (xy 93.706714 -351.63867) (xy 93.698952 -351.692655) (xy 93.683588 -351.744987)
			(xy 93.660932 -351.794599) (xy 93.631447 -351.840483) (xy 93.595733 -351.881703) (xy 93.554516 -351.917422)
			(xy 93.508636 -351.946912) (xy 93.459026 -351.969573) (xy 93.406697 -351.984943) (xy 93.352712 -351.992711)
			(xy 93.325442 -351.9932) (xy 92.461842 -351.9932) (xy 92.434572 -351.992663) (xy 92.380586 -351.984907)
			(xy 92.328253 -351.969546) (xy 92.27864 -351.946893) (xy 92.232755 -351.917409) (xy 92.191534 -351.881695)
			(xy 92.155816 -351.840478) (xy 92.126327 -351.794597) (xy 92.103669 -351.744986) (xy 92.088302 -351.692655)
			(xy 92.08054 -351.63867) (xy 90.597836 -351.63867) (xy 90.597836 -351.638675) (xy 90.590073 -351.692668)
			(xy 90.574704 -351.745008) (xy 90.552043 -351.794627) (xy 90.522551 -351.840516) (xy 90.486828 -351.881741)
			(xy 90.445602 -351.917462) (xy 90.399711 -351.946952) (xy 90.350091 -351.969611) (xy 90.297751 -351.984977)
			(xy 90.243757 -351.992738) (xy 90.216482 -351.9932) (xy 89.352882 -351.9932) (xy 89.325616 -351.992636)
			(xy 89.27164 -351.984873) (xy 89.219318 -351.969508) (xy 89.169715 -351.946853) (xy 89.123841 -351.91737)
			(xy 89.082629 -351.881658) (xy 89.04692 -351.840445) (xy 89.017438 -351.794569) (xy 88.994786 -351.744965)
			(xy 88.979423 -351.692642) (xy 88.971662 -351.638666) (xy 87.488814 -351.638666) (xy 87.488814 -351.638671)
			(xy 87.481052 -351.692658) (xy 87.465686 -351.744991) (xy 87.443029 -351.794605) (xy 87.413542 -351.840489)
			(xy 87.377826 -351.88171) (xy 87.336607 -351.917429) (xy 87.290724 -351.946919) (xy 87.241112 -351.969578)
			(xy 87.18878 -351.984947) (xy 87.134793 -351.992712) (xy 87.107522 -351.9932) (xy 86.243922 -351.9932)
			(xy 86.216653 -351.992662) (xy 86.162669 -351.984903) (xy 86.110339 -351.96954) (xy 86.060728 -351.946886)
			(xy 86.014846 -351.917402) (xy 85.973627 -351.881688) (xy 85.937911 -351.840472) (xy 85.908424 -351.794592)
			(xy 85.885767 -351.744982) (xy 85.870401 -351.692653) (xy 85.862639 -351.638669) (xy 84.379936 -351.638669)
			(xy 84.379936 -351.638675) (xy 84.372172 -351.692671) (xy 84.356803 -351.745012) (xy 84.33414 -351.794633)
			(xy 84.304646 -351.840523) (xy 84.268921 -351.881748) (xy 84.227692 -351.917469) (xy 84.181799 -351.946958)
			(xy 84.132176 -351.969616) (xy 84.079834 -351.98498) (xy 84.025837 -351.992739) (xy 83.998562 -351.9932)
			(xy 83.134962 -351.9932) (xy 83.107697 -351.992635) (xy 83.053723 -351.98487) (xy 83.001403 -351.969503)
			(xy 82.951803 -351.946847) (xy 82.905931 -351.917363) (xy 82.864722 -351.881651) (xy 82.829015 -351.840438)
			(xy 82.799535 -351.794564) (xy 82.776884 -351.744961) (xy 82.761522 -351.69264) (xy 82.753762 -351.638665)
			(xy 81.270913 -351.638665) (xy 81.270913 -351.638672) (xy 81.263151 -351.692661) (xy 81.247784 -351.744995)
			(xy 81.225126 -351.79461) (xy 81.195637 -351.840496) (xy 81.159919 -351.881717) (xy 81.118697 -351.917436)
			(xy 81.072812 -351.946925) (xy 81.023197 -351.969584) (xy 80.970863 -351.984951) (xy 80.916874 -351.992713)
			(xy 80.889602 -351.9932) (xy 80.026002 -351.9932) (xy 79.998734 -351.992661) (xy 79.944752 -351.9849)
			(xy 79.892424 -351.969535) (xy 79.842816 -351.94688) (xy 79.796936 -351.917395) (xy 79.75572 -351.881681)
			(xy 79.720006 -351.840465) (xy 79.690521 -351.794586) (xy 79.667866 -351.744978) (xy 79.652501 -351.69265)
			(xy 79.644739 -351.638668) (xy 78.161914 -351.638668) (xy 78.161914 -351.63867) (xy 78.154152 -351.692655)
			(xy 78.138788 -351.744987) (xy 78.116132 -351.794599) (xy 78.086647 -351.840483) (xy 78.050933 -351.881703)
			(xy 78.009716 -351.917422) (xy 77.963836 -351.946912) (xy 77.914226 -351.969573) (xy 77.861897 -351.984943)
			(xy 77.807912 -351.992711) (xy 77.780642 -351.9932) (xy 76.917042 -351.9932) (xy 76.889772 -351.992663)
			(xy 76.835786 -351.984907) (xy 76.783453 -351.969546) (xy 76.73384 -351.946893) (xy 76.687955 -351.917409)
			(xy 76.646734 -351.881695) (xy 76.611016 -351.840478) (xy 76.581527 -351.794597) (xy 76.558869 -351.744986)
			(xy 76.543502 -351.692655) (xy 76.53574 -351.63867) (xy 75.053036 -351.63867) (xy 75.053036 -351.638675)
			(xy 75.045273 -351.692668) (xy 75.029904 -351.745008) (xy 75.007243 -351.794627) (xy 74.977751 -351.840516)
			(xy 74.942028 -351.881741) (xy 74.900802 -351.917462) (xy 74.854911 -351.946952) (xy 74.805291 -351.969611)
			(xy 74.752951 -351.984977) (xy 74.698957 -351.992738) (xy 74.671682 -351.9932) (xy 73.808082 -351.9932)
			(xy 73.780816 -351.992636) (xy 73.72684 -351.984873) (xy 73.674518 -351.969508) (xy 73.624915 -351.946853)
			(xy 73.579041 -351.91737) (xy 73.537829 -351.881658) (xy 73.50212 -351.840445) (xy 73.472638 -351.794569)
			(xy 73.449986 -351.744965) (xy 73.434623 -351.692642) (xy 73.426862 -351.638666) (xy 71.944014 -351.638666)
			(xy 71.944014 -351.638671) (xy 71.936252 -351.692658) (xy 71.920886 -351.744991) (xy 71.898229 -351.794605)
			(xy 71.868742 -351.840489) (xy 71.833026 -351.88171) (xy 71.791807 -351.917429) (xy 71.745924 -351.946919)
			(xy 71.696312 -351.969578) (xy 71.64398 -351.984947) (xy 71.589993 -351.992712) (xy 71.562722 -351.9932)
			(xy 70.699122 -351.9932) (xy 70.671853 -351.992662) (xy 70.617869 -351.984903) (xy 70.565539 -351.96954)
			(xy 70.515928 -351.946886) (xy 70.470046 -351.917402) (xy 70.428827 -351.881688) (xy 70.393111 -351.840472)
			(xy 70.363624 -351.794592) (xy 70.340967 -351.744982) (xy 70.325601 -351.692653) (xy 70.317839 -351.638669)
			(xy 68.835136 -351.638669) (xy 68.835136 -351.638675) (xy 68.827372 -351.692671) (xy 68.812003 -351.745012)
			(xy 68.78934 -351.794633) (xy 68.759846 -351.840523) (xy 68.724121 -351.881748) (xy 68.682892 -351.917469)
			(xy 68.636999 -351.946958) (xy 68.587376 -351.969616) (xy 68.535034 -351.98498) (xy 68.481037 -351.992739)
			(xy 68.453762 -351.9932) (xy 67.590162 -351.9932) (xy 67.562897 -351.992635) (xy 67.508923 -351.98487)
			(xy 67.456603 -351.969503) (xy 67.407003 -351.946847) (xy 67.361131 -351.917363) (xy 67.319922 -351.881651)
			(xy 67.284215 -351.840438) (xy 67.254735 -351.794564) (xy 67.232084 -351.744961) (xy 67.216722 -351.69264)
			(xy 67.208962 -351.638665) (xy 65.726113 -351.638665) (xy 65.726113 -351.638672) (xy 65.718351 -351.692661)
			(xy 65.702984 -351.744995) (xy 65.680326 -351.79461) (xy 65.650837 -351.840496) (xy 65.615119 -351.881717)
			(xy 65.573897 -351.917436) (xy 65.528012 -351.946925) (xy 65.478397 -351.969584) (xy 65.426063 -351.984951)
			(xy 65.372074 -351.992713) (xy 65.344802 -351.9932) (xy 64.481202 -351.9932) (xy 64.453934 -351.992661)
			(xy 64.399952 -351.9849) (xy 64.347624 -351.969535) (xy 64.298016 -351.94688) (xy 64.252136 -351.917395)
			(xy 64.21092 -351.881681) (xy 64.175206 -351.840465) (xy 64.145721 -351.794586) (xy 64.123066 -351.744978)
			(xy 64.107701 -351.69265) (xy 64.099939 -351.638668) (xy 62.617114 -351.638668) (xy 62.617114 -351.63867)
			(xy 62.609352 -351.692655) (xy 62.593988 -351.744987) (xy 62.571332 -351.794599) (xy 62.541847 -351.840483)
			(xy 62.506133 -351.881703) (xy 62.464916 -351.917422) (xy 62.419036 -351.946912) (xy 62.369426 -351.969573)
			(xy 62.317097 -351.984943) (xy 62.263112 -351.992711) (xy 62.235842 -351.9932) (xy 61.372242 -351.9932)
			(xy 61.344972 -351.992663) (xy 61.290986 -351.984907) (xy 61.238653 -351.969546) (xy 61.18904 -351.946893)
			(xy 61.143155 -351.917409) (xy 61.101934 -351.881695) (xy 61.066216 -351.840478) (xy 61.036727 -351.794597)
			(xy 61.014069 -351.744986) (xy 60.998702 -351.692655) (xy 60.99094 -351.63867) (xy 51.666914 -351.63867)
			(xy 51.659152 -351.692655) (xy 51.643788 -351.744986) (xy 51.621133 -351.794597) (xy 51.591649 -351.840481)
			(xy 51.555935 -351.881701) (xy 51.514719 -351.91742) (xy 51.46884 -351.94691) (xy 51.419231 -351.969571)
			(xy 51.366902 -351.984942) (xy 51.312918 -351.99271) (xy 51.285648 -351.9932) (xy 50.422048 -351.9932)
			(xy 50.394777 -351.992664) (xy 50.340791 -351.984908) (xy 50.288458 -351.969547) (xy 50.238843 -351.946895)
			(xy 50.192958 -351.917411) (xy 50.151736 -351.881698) (xy 50.116017 -351.84048) (xy 50.086528 -351.794599)
			(xy 50.063869 -351.744987) (xy 50.048502 -351.692656) (xy 50.04074 -351.63867) (xy 48.558036 -351.63867)
			(xy 48.558036 -351.638674) (xy 48.550273 -351.692668) (xy 48.534905 -351.745006) (xy 48.512244 -351.794625)
			(xy 48.482752 -351.840514) (xy 48.44703 -351.881739) (xy 48.405804 -351.91746) (xy 48.359915 -351.94695)
			(xy 48.310295 -351.969609) (xy 48.257956 -351.984976) (xy 48.203962 -351.992737) (xy 48.176688 -351.9932)
			(xy 47.313088 -351.9932) (xy 47.285822 -351.992637) (xy 47.231845 -351.984875) (xy 47.179522 -351.96951)
			(xy 47.129918 -351.946855) (xy 47.084044 -351.917372) (xy 47.042831 -351.88166) (xy 47.007121 -351.840447)
			(xy 46.977639 -351.794571) (xy 46.954986 -351.744967) (xy 46.939623 -351.692643) (xy 46.931862 -351.638666)
			(xy 45.449014 -351.638666) (xy 45.449014 -351.638671) (xy 45.441252 -351.692657) (xy 45.425886 -351.74499)
			(xy 45.40323 -351.794603) (xy 45.373744 -351.840487) (xy 45.338028 -351.881708) (xy 45.29681 -351.917427)
			(xy 45.250928 -351.946917) (xy 45.201316 -351.969577) (xy 45.148985 -351.984946) (xy 45.094999 -351.992712)
			(xy 45.067728 -351.9932) (xy 44.204128 -351.9932) (xy 44.176858 -351.992663) (xy 44.122874 -351.984904)
			(xy 44.070543 -351.969542) (xy 44.020931 -351.946888) (xy 43.975049 -351.917404) (xy 43.933829 -351.881691)
			(xy 43.898112 -351.840474) (xy 43.868625 -351.794593) (xy 43.845968 -351.744983) (xy 43.830602 -351.692654)
			(xy 43.822839 -351.63867) (xy 42.340136 -351.63867) (xy 42.340136 -351.638675) (xy 42.332373 -351.69267)
			(xy 42.317003 -351.745011) (xy 42.294341 -351.794631) (xy 42.264847 -351.840521) (xy 42.229123 -351.881746)
			(xy 42.187895 -351.917467) (xy 42.142003 -351.946956) (xy 42.092381 -351.969614) (xy 42.040039 -351.984979)
			(xy 41.986043 -351.992739) (xy 41.958768 -351.9932) (xy 41.095168 -351.9932) (xy 41.067903 -351.992635)
			(xy 41.013928 -351.984871) (xy 40.961608 -351.969504) (xy 40.912006 -351.946849) (xy 40.866134 -351.917365)
			(xy 40.824924 -351.881653) (xy 40.789216 -351.84044) (xy 40.759736 -351.794566) (xy 40.737084 -351.744962)
			(xy 40.721722 -351.692641) (xy 40.713962 -351.638665) (xy 39.231114 -351.638665) (xy 39.231114 -351.638672)
			(xy 39.223351 -351.69266) (xy 39.207985 -351.744994) (xy 39.185327 -351.794609) (xy 39.155839 -351.840494)
			(xy 39.120121 -351.881715) (xy 39.0789 -351.917434) (xy 39.033016 -351.946923) (xy 38.983402 -351.969582)
			(xy 38.931068 -351.98495) (xy 38.87708 -351.992713) (xy 38.849808 -351.9932) (xy 37.986208 -351.9932)
			(xy 37.958939 -351.992661) (xy 37.904957 -351.984901) (xy 37.852629 -351.969537) (xy 37.803019 -351.946882)
			(xy 37.757139 -351.917397) (xy 37.715922 -351.881683) (xy 37.680207 -351.840467) (xy 37.650722 -351.794588)
			(xy 37.628066 -351.744979) (xy 37.612701 -351.692651) (xy 37.604939 -351.638669) (xy 36.122114 -351.638669)
			(xy 36.122114 -351.63867) (xy 36.114352 -351.692655) (xy 36.098988 -351.744986) (xy 36.076333 -351.794597)
			(xy 36.046849 -351.840481) (xy 36.011135 -351.881701) (xy 35.969919 -351.91742) (xy 35.92404 -351.94691)
			(xy 35.874431 -351.969571) (xy 35.822102 -351.984942) (xy 35.768118 -351.99271) (xy 35.740848 -351.9932)
			(xy 34.877248 -351.9932) (xy 34.849977 -351.992664) (xy 34.795991 -351.984908) (xy 34.743658 -351.969547)
			(xy 34.694043 -351.946895) (xy 34.648158 -351.917411) (xy 34.606936 -351.881698) (xy 34.571217 -351.84048)
			(xy 34.541728 -351.794599) (xy 34.519069 -351.744987) (xy 34.503702 -351.692656) (xy 34.49594 -351.63867)
			(xy 33.013236 -351.63867) (xy 33.013236 -351.638674) (xy 33.005473 -351.692668) (xy 32.990105 -351.745006)
			(xy 32.967444 -351.794625) (xy 32.937952 -351.840514) (xy 32.90223 -351.881739) (xy 32.861004 -351.91746)
			(xy 32.815115 -351.94695) (xy 32.765495 -351.969609) (xy 32.713156 -351.984976) (xy 32.659162 -351.992737)
			(xy 32.631888 -351.9932) (xy 31.768288 -351.9932) (xy 31.741022 -351.992637) (xy 31.687045 -351.984875)
			(xy 31.634722 -351.96951) (xy 31.585118 -351.946855) (xy 31.539244 -351.917372) (xy 31.498031 -351.88166)
			(xy 31.462321 -351.840447) (xy 31.432839 -351.794571) (xy 31.410186 -351.744967) (xy 31.394823 -351.692643)
			(xy 31.387062 -351.638666) (xy 29.904214 -351.638666) (xy 29.904214 -351.638671) (xy 29.896452 -351.692657)
			(xy 29.881086 -351.74499) (xy 29.85843 -351.794603) (xy 29.828944 -351.840487) (xy 29.793228 -351.881708)
			(xy 29.75201 -351.917427) (xy 29.706128 -351.946917) (xy 29.656516 -351.969577) (xy 29.604185 -351.984946)
			(xy 29.550199 -351.992712) (xy 29.522928 -351.9932) (xy 28.659328 -351.9932) (xy 28.632058 -351.992663)
			(xy 28.578074 -351.984904) (xy 28.525743 -351.969542) (xy 28.476131 -351.946888) (xy 28.430249 -351.917404)
			(xy 28.389029 -351.881691) (xy 28.353312 -351.840474) (xy 28.323825 -351.794593) (xy 28.301168 -351.744983)
			(xy 28.285802 -351.692654) (xy 28.278039 -351.63867) (xy 26.795336 -351.63867) (xy 26.795336 -351.638675)
			(xy 26.787573 -351.69267) (xy 26.772203 -351.745011) (xy 26.749541 -351.794631) (xy 26.720047 -351.840521)
			(xy 26.684323 -351.881746) (xy 26.643095 -351.917467) (xy 26.597203 -351.946956) (xy 26.547581 -351.969614)
			(xy 26.495239 -351.984979) (xy 26.441243 -351.992739) (xy 26.413968 -351.9932) (xy 25.550368 -351.9932)
			(xy 25.523103 -351.992635) (xy 25.469128 -351.984871) (xy 25.416808 -351.969504) (xy 25.367206 -351.946849)
			(xy 25.321334 -351.917365) (xy 25.280124 -351.881653) (xy 25.244416 -351.84044) (xy 25.214936 -351.794566)
			(xy 25.192284 -351.744962) (xy 25.176922 -351.692641) (xy 25.169162 -351.638665) (xy 23.686314 -351.638665)
			(xy 23.686314 -351.638672) (xy 23.678551 -351.69266) (xy 23.663185 -351.744994) (xy 23.640527 -351.794609)
			(xy 23.611039 -351.840494) (xy 23.575321 -351.881715) (xy 23.5341 -351.917434) (xy 23.488216 -351.946923)
			(xy 23.438602 -351.969582) (xy 23.386268 -351.98495) (xy 23.33228 -351.992713) (xy 23.305008 -351.9932)
			(xy 22.441408 -351.9932) (xy 22.414139 -351.992661) (xy 22.360157 -351.984901) (xy 22.307829 -351.969537)
			(xy 22.258219 -351.946882) (xy 22.212339 -351.917397) (xy 22.171122 -351.881683) (xy 22.135407 -351.840467)
			(xy 22.105922 -351.794588) (xy 22.083266 -351.744979) (xy 22.067901 -351.692651) (xy 22.060139 -351.638669)
			(xy 20.577347 -351.638669) (xy 20.577347 -351.638711) (xy 20.569584 -351.692698) (xy 20.554218 -351.74503)
			(xy 20.53156 -351.794643) (xy 20.502073 -351.840527) (xy 20.466355 -351.881747) (xy 20.425135 -351.917464)
			(xy 20.379252 -351.946951) (xy 20.329638 -351.969609) (xy 20.277306 -351.984975) (xy 20.223319 -351.992737)
			(xy 20.196048 -351.9932) (xy 19.332448 -351.9932) (xy 19.305179 -351.992717) (xy 19.251195 -351.984955)
			(xy 19.198865 -351.96959) (xy 19.149255 -351.946933) (xy 19.103374 -351.917447) (xy 19.062157 -351.881732)
			(xy 19.026441 -351.840514) (xy 18.996956 -351.794633) (xy 18.974299 -351.745023) (xy 18.958934 -351.692693)
			(xy 18.951172 -351.638709) (xy 0.508 -351.638709) (xy 0.508 -354.759373) (xy 22.060084 -354.759373)
			(xy 22.060084 -354.704827) (xy 22.067846 -354.650837) (xy 22.083214 -354.598501) (xy 22.105873 -354.548885)
			(xy 22.135363 -354.502999) (xy 22.171083 -354.461777) (xy 22.212306 -354.426058) (xy 22.258192 -354.396569)
			(xy 22.307809 -354.373911) (xy 22.360145 -354.358545) (xy 22.414135 -354.350783) (xy 22.441408 -354.35032)
			(xy 23.305008 -354.35032) (xy 23.332276 -354.350843) (xy 23.386256 -354.358605) (xy 23.438582 -354.37397)
			(xy 23.488189 -354.396626) (xy 23.534067 -354.426111) (xy 23.575281 -354.461824) (xy 23.610994 -354.50304)
			(xy 23.640478 -354.548918) (xy 23.663132 -354.598525) (xy 23.678497 -354.650852) (xy 23.686258 -354.704832)
			(xy 23.686258 -354.759368) (xy 23.686258 -354.759369) (xy 25.169106 -354.759369) (xy 25.169106 -354.704831)
			(xy 25.176868 -354.650847) (xy 25.192232 -354.598518) (xy 25.214887 -354.548908) (xy 25.244371 -354.503026)
			(xy 25.280085 -354.461807) (xy 25.3213 -354.42609) (xy 25.36718 -354.396602) (xy 25.416788 -354.373943)
			(xy 25.469116 -354.358574) (xy 25.523099 -354.350809) (xy 25.550368 -354.35032) (xy 26.413968 -354.35032)
			(xy 26.441239 -354.350817) (xy 26.495227 -354.358575) (xy 26.547561 -354.373938) (xy 26.597176 -354.396593)
			(xy 26.643061 -354.426078) (xy 26.684283 -354.461794) (xy 26.720003 -354.503013) (xy 26.749492 -354.548896)
			(xy 26.772151 -354.598509) (xy 26.787518 -354.650842) (xy 26.79528 -354.704829) (xy 26.79528 -354.759371)
			(xy 26.79528 -354.759374) (xy 28.277984 -354.759374) (xy 28.277984 -354.704826) (xy 28.285747 -354.650835)
			(xy 28.301115 -354.598497) (xy 28.323776 -354.54888) (xy 28.353268 -354.502993) (xy 28.38899 -354.46177)
			(xy 28.430215 -354.426051) (xy 28.476104 -354.396562) (xy 28.525723 -354.373905) (xy 28.578062 -354.358541)
			(xy 28.632054 -354.350782) (xy 28.659328 -354.35032) (xy 29.522928 -354.35032) (xy 29.550195 -354.350844)
			(xy 29.604173 -354.358609) (xy 29.656497 -354.373976) (xy 29.706101 -354.396633) (xy 29.751976 -354.426118)
			(xy 29.793188 -354.461831) (xy 29.828899 -354.503046) (xy 29.858381 -354.548924) (xy 29.881034 -354.59853)
			(xy 29.896397 -354.650855) (xy 29.904158 -354.704833) (xy 29.904158 -354.759367) (xy 29.904158 -354.75937)
			(xy 31.387006 -354.75937) (xy 31.387006 -354.70483) (xy 31.394768 -354.650845) (xy 31.410134 -354.598514)
			(xy 31.43279 -354.548902) (xy 31.462276 -354.50302) (xy 31.497992 -354.4618) (xy 31.53921 -354.426083)
			(xy 31.585091 -354.396596) (xy 31.634703 -354.373938) (xy 31.687033 -354.358571) (xy 31.741018 -354.350807)
			(xy 31.768288 -354.35032) (xy 32.631888 -354.35032) (xy 32.659158 -354.350819) (xy 32.713144 -354.358579)
			(xy 32.765476 -354.373944) (xy 32.815088 -354.396599) (xy 32.860971 -354.426085) (xy 32.902191 -354.461801)
			(xy 32.937908 -354.503019) (xy 32.967395 -354.548902) (xy 32.990052 -354.598513) (xy 33.005418 -354.650844)
			(xy 33.013181 -354.70483) (xy 33.013181 -354.75937) (xy 33.01318 -354.759374) (xy 34.495884 -354.759374)
			(xy 34.495884 -354.704826) (xy 34.503647 -354.650832) (xy 34.519017 -354.598493) (xy 34.541679 -354.548874)
			(xy 34.571172 -354.502986) (xy 34.606897 -354.461763) (xy 34.648125 -354.426044) (xy 34.694016 -354.396556)
			(xy 34.743638 -354.3739) (xy 34.795979 -354.358537) (xy 34.849973 -354.35078) (xy 34.877248 -354.35032)
			(xy 35.740848 -354.35032) (xy 35.768114 -354.350846) (xy 35.82209 -354.358613) (xy 35.874411 -354.373981)
			(xy 35.924013 -354.396639) (xy 35.969886 -354.426125) (xy 36.011095 -354.461839) (xy 36.046804 -354.503053)
			(xy 36.076284 -354.548929) (xy 36.098936 -354.598534) (xy 36.114298 -354.650857) (xy 36.122058 -354.704834)
			(xy 36.122058 -354.759366) (xy 36.122057 -354.759373) (xy 37.604884 -354.759373) (xy 37.604884 -354.704827)
			(xy 37.612646 -354.650837) (xy 37.628014 -354.598501) (xy 37.650673 -354.548885) (xy 37.680163 -354.502999)
			(xy 37.715883 -354.461777) (xy 37.757106 -354.426058) (xy 37.802992 -354.396569) (xy 37.852609 -354.373911)
			(xy 37.904945 -354.358545) (xy 37.958935 -354.350783) (xy 37.986208 -354.35032) (xy 38.849808 -354.35032)
			(xy 38.877076 -354.350843) (xy 38.931056 -354.358605) (xy 38.983382 -354.37397) (xy 39.032989 -354.396626)
			(xy 39.078867 -354.426111) (xy 39.120081 -354.461824) (xy 39.155794 -354.50304) (xy 39.185278 -354.548918)
			(xy 39.207932 -354.598525) (xy 39.223297 -354.650852) (xy 39.231058 -354.704832) (xy 39.231058 -354.759368)
			(xy 39.231058 -354.759369) (xy 40.713906 -354.759369) (xy 40.713906 -354.704831) (xy 40.721668 -354.650847)
			(xy 40.737032 -354.598518) (xy 40.759687 -354.548908) (xy 40.789171 -354.503026) (xy 40.824885 -354.461807)
			(xy 40.8661 -354.42609) (xy 40.91198 -354.396602) (xy 40.961588 -354.373943) (xy 41.013916 -354.358574)
			(xy 41.067899 -354.350809) (xy 41.095168 -354.35032) (xy 41.958768 -354.35032) (xy 41.986039 -354.350817)
			(xy 42.040027 -354.358575) (xy 42.092361 -354.373938) (xy 42.141976 -354.396593) (xy 42.187861 -354.426078)
			(xy 42.229083 -354.461794) (xy 42.264803 -354.503013) (xy 42.294292 -354.548896) (xy 42.316951 -354.598509)
			(xy 42.332318 -354.650842) (xy 42.34008 -354.704829) (xy 42.34008 -354.759371) (xy 42.34008 -354.759374)
			(xy 43.822784 -354.759374) (xy 43.822784 -354.704826) (xy 43.830547 -354.650835) (xy 43.845915 -354.598497)
			(xy 43.868576 -354.54888) (xy 43.898068 -354.502993) (xy 43.93379 -354.46177) (xy 43.975015 -354.426051)
			(xy 44.020904 -354.396562) (xy 44.070523 -354.373905) (xy 44.122862 -354.358541) (xy 44.176854 -354.350782)
			(xy 44.204128 -354.35032) (xy 45.067728 -354.35032) (xy 45.094995 -354.350844) (xy 45.148973 -354.358609)
			(xy 45.201297 -354.373976) (xy 45.250901 -354.396633) (xy 45.296776 -354.426118) (xy 45.337988 -354.461831)
			(xy 45.373699 -354.503046) (xy 45.403181 -354.548924) (xy 45.425834 -354.59853) (xy 45.441197 -354.650855)
			(xy 45.448958 -354.704833) (xy 45.448958 -354.759367) (xy 45.448958 -354.75937) (xy 46.931806 -354.75937)
			(xy 46.931806 -354.70483) (xy 46.939568 -354.650845) (xy 46.954934 -354.598514) (xy 46.97759 -354.548902)
			(xy 47.007076 -354.50302) (xy 47.042792 -354.4618) (xy 47.08401 -354.426083) (xy 47.129891 -354.396596)
			(xy 47.179503 -354.373938) (xy 47.231833 -354.358571) (xy 47.285818 -354.350807) (xy 47.313088 -354.35032)
			(xy 48.176688 -354.35032) (xy 48.203958 -354.350819) (xy 48.257944 -354.358579) (xy 48.310276 -354.373944)
			(xy 48.359888 -354.396599) (xy 48.405771 -354.426085) (xy 48.446991 -354.461801) (xy 48.482708 -354.503019)
			(xy 48.512195 -354.548902) (xy 48.534852 -354.598513) (xy 48.550218 -354.650844) (xy 48.557981 -354.70483)
			(xy 48.557981 -354.75937) (xy 48.55798 -354.759374) (xy 50.040684 -354.759374) (xy 50.040684 -354.704826)
			(xy 50.048447 -354.650832) (xy 50.063817 -354.598493) (xy 50.086479 -354.548874) (xy 50.115972 -354.502986)
			(xy 50.151697 -354.461763) (xy 50.192925 -354.426044) (xy 50.238816 -354.396556) (xy 50.288438 -354.3739)
			(xy 50.340779 -354.358537) (xy 50.394773 -354.35078) (xy 50.422048 -354.35032) (xy 51.285648 -354.35032)
			(xy 51.312914 -354.350846) (xy 51.36689 -354.358613) (xy 51.419211 -354.373981) (xy 51.468813 -354.396639)
			(xy 51.514686 -354.426125) (xy 51.555895 -354.461839) (xy 51.591604 -354.503053) (xy 51.621084 -354.548929)
			(xy 51.643736 -354.598534) (xy 51.659098 -354.650857) (xy 51.666858 -354.704834) (xy 51.666858 -354.759366)
			(xy 51.666857 -354.759372) (xy 64.099884 -354.759372) (xy 64.099884 -354.704828) (xy 64.107646 -354.650838)
			(xy 64.123013 -354.598503) (xy 64.145672 -354.548887) (xy 64.175161 -354.503001) (xy 64.210881 -354.461779)
			(xy 64.252103 -354.42606) (xy 64.297989 -354.396571) (xy 64.347605 -354.373912) (xy 64.39994 -354.358546)
			(xy 64.45393 -354.350783) (xy 64.481202 -354.35032) (xy 65.344802 -354.35032) (xy 65.37207 -354.350843)
			(xy 65.426051 -354.358604) (xy 65.478378 -354.373969) (xy 65.527985 -354.396624) (xy 65.573864 -354.426109)
			(xy 65.615079 -354.461822) (xy 65.650793 -354.503038) (xy 65.680277 -354.548917) (xy 65.702932 -354.598524)
			(xy 65.718296 -354.650851) (xy 65.726058 -354.704832) (xy 65.726058 -354.759368) (xy 65.726058 -354.759369)
			(xy 67.208906 -354.759369) (xy 67.208906 -354.704831) (xy 67.216667 -354.650848) (xy 67.232032 -354.598519)
			(xy 67.254686 -354.548909) (xy 67.28417 -354.503028) (xy 67.319883 -354.46181) (xy 67.361098 -354.426093)
			(xy 67.406976 -354.396604) (xy 67.456584 -354.373945) (xy 67.508911 -354.358575) (xy 67.562893 -354.350809)
			(xy 67.590162 -354.35032) (xy 68.453762 -354.35032) (xy 68.481033 -354.350817) (xy 68.535022 -354.358574)
			(xy 68.587357 -354.373936) (xy 68.636972 -354.396591) (xy 68.682859 -354.426076) (xy 68.724081 -354.461792)
			(xy 68.759801 -354.503011) (xy 68.789291 -354.548894) (xy 68.81195 -354.598508) (xy 68.827318 -354.650841)
			(xy 68.83508 -354.704829) (xy 68.83508 -354.759371) (xy 68.83508 -354.759373) (xy 70.317784 -354.759373)
			(xy 70.317784 -354.704827) (xy 70.325547 -354.650835) (xy 70.340915 -354.598498) (xy 70.363575 -354.548882)
			(xy 70.393066 -354.502995) (xy 70.428788 -354.461772) (xy 70.470012 -354.426053) (xy 70.515901 -354.396564)
			(xy 70.565519 -354.373907) (xy 70.617857 -354.358542) (xy 70.671849 -354.350782) (xy 70.699122 -354.35032)
			(xy 71.562722 -354.35032) (xy 71.589989 -354.350844) (xy 71.643968 -354.358608) (xy 71.696292 -354.373974)
			(xy 71.745897 -354.396631) (xy 71.791773 -354.426116) (xy 71.832986 -354.461829) (xy 71.868697 -354.503044)
			(xy 71.89818 -354.548922) (xy 71.920833 -354.598528) (xy 71.936197 -354.650854) (xy 71.943958 -354.704833)
			(xy 71.943958 -354.759367) (xy 71.943958 -354.75937) (xy 73.426806 -354.75937) (xy 73.426806 -354.70483)
			(xy 73.434568 -354.650846) (xy 73.449933 -354.598515) (xy 73.472589 -354.548904) (xy 73.502075 -354.503022)
			(xy 73.53779 -354.461802) (xy 73.579007 -354.426085) (xy 73.624888 -354.396598) (xy 73.674498 -354.373939)
			(xy 73.726828 -354.358572) (xy 73.780812 -354.350808) (xy 73.808082 -354.35032) (xy 74.671682 -354.35032)
			(xy 74.698953 -354.350818) (xy 74.752939 -354.358578) (xy 74.805271 -354.373942) (xy 74.854884 -354.396597)
			(xy 74.900768 -354.426083) (xy 74.941988 -354.461799) (xy 74.977706 -354.503018) (xy 75.007194 -354.5489)
			(xy 75.029852 -354.598512) (xy 75.045218 -354.650844) (xy 75.052981 -354.704829) (xy 75.052981 -354.759371)
			(xy 75.052981 -354.759374) (xy 76.535684 -354.759374) (xy 76.535684 -354.704826) (xy 76.543447 -354.650833)
			(xy 76.558816 -354.598494) (xy 76.581478 -354.548876) (xy 76.610971 -354.502988) (xy 76.646695 -354.461765)
			(xy 76.687922 -354.426046) (xy 76.733813 -354.396558) (xy 76.783434 -354.373902) (xy 76.835774 -354.358538)
			(xy 76.889768 -354.350781) (xy 76.917042 -354.35032) (xy 77.780642 -354.35032) (xy 77.807908 -354.350845)
			(xy 77.861885 -354.358611) (xy 77.914207 -354.37398) (xy 77.963809 -354.396637) (xy 78.009683 -354.426123)
			(xy 78.050893 -354.461836) (xy 78.086602 -354.503051) (xy 78.116083 -354.548928) (xy 78.138735 -354.598533)
			(xy 78.154098 -354.650856) (xy 78.161858 -354.704834) (xy 78.161858 -354.759366) (xy 78.161857 -354.759372)
			(xy 79.644684 -354.759372) (xy 79.644684 -354.704828) (xy 79.652446 -354.650838) (xy 79.667813 -354.598503)
			(xy 79.690472 -354.548887) (xy 79.719961 -354.503001) (xy 79.755681 -354.461779) (xy 79.796903 -354.42606)
			(xy 79.842789 -354.396571) (xy 79.892405 -354.373912) (xy 79.94474 -354.358546) (xy 79.99873 -354.350783)
			(xy 80.026002 -354.35032) (xy 80.889602 -354.35032) (xy 80.91687 -354.350843) (xy 80.970851 -354.358604)
			(xy 81.023178 -354.373969) (xy 81.072785 -354.396624) (xy 81.118664 -354.426109) (xy 81.159879 -354.461822)
			(xy 81.195593 -354.503038) (xy 81.225077 -354.548917) (xy 81.247732 -354.598524) (xy 81.263096 -354.650851)
			(xy 81.270858 -354.704832) (xy 81.270858 -354.759368) (xy 81.270858 -354.759369) (xy 82.753706 -354.759369)
			(xy 82.753706 -354.704831) (xy 82.761467 -354.650848) (xy 82.776832 -354.598519) (xy 82.799486 -354.548909)
			(xy 82.82897 -354.503028) (xy 82.864683 -354.46181) (xy 82.905898 -354.426093) (xy 82.951776 -354.396604)
			(xy 83.001384 -354.373945) (xy 83.053711 -354.358575) (xy 83.107693 -354.350809) (xy 83.134962 -354.35032)
			(xy 83.998562 -354.35032) (xy 84.025833 -354.350817) (xy 84.079822 -354.358574) (xy 84.132157 -354.373936)
			(xy 84.181772 -354.396591) (xy 84.227659 -354.426076) (xy 84.268881 -354.461792) (xy 84.304601 -354.503011)
			(xy 84.334091 -354.548894) (xy 84.35675 -354.598508) (xy 84.372118 -354.650841) (xy 84.37988 -354.704829)
			(xy 84.37988 -354.759371) (xy 84.37988 -354.759373) (xy 85.862584 -354.759373) (xy 85.862584 -354.704827)
			(xy 85.870347 -354.650835) (xy 85.885715 -354.598498) (xy 85.908375 -354.548882) (xy 85.937866 -354.502995)
			(xy 85.973588 -354.461772) (xy 86.014812 -354.426053) (xy 86.060701 -354.396564) (xy 86.110319 -354.373907)
			(xy 86.162657 -354.358542) (xy 86.216649 -354.350782) (xy 86.243922 -354.35032) (xy 87.107522 -354.35032)
			(xy 87.134789 -354.350844) (xy 87.188768 -354.358608) (xy 87.241092 -354.373974) (xy 87.290697 -354.396631)
			(xy 87.336573 -354.426116) (xy 87.377786 -354.461829) (xy 87.413497 -354.503044) (xy 87.44298 -354.548922)
			(xy 87.465633 -354.598528) (xy 87.480997 -354.650854) (xy 87.488758 -354.704833) (xy 87.488758 -354.759367)
			(xy 87.488758 -354.75937) (xy 88.971606 -354.75937) (xy 88.971606 -354.70483) (xy 88.979368 -354.650846)
			(xy 88.994733 -354.598515) (xy 89.017389 -354.548904) (xy 89.046875 -354.503022) (xy 89.08259 -354.461802)
			(xy 89.123807 -354.426085) (xy 89.169688 -354.396598) (xy 89.219298 -354.373939) (xy 89.271628 -354.358572)
			(xy 89.325612 -354.350808) (xy 89.352882 -354.35032) (xy 90.216482 -354.35032) (xy 90.243753 -354.350818)
			(xy 90.297739 -354.358578) (xy 90.350071 -354.373942) (xy 90.399684 -354.396597) (xy 90.445568 -354.426083)
			(xy 90.486788 -354.461799) (xy 90.522506 -354.503018) (xy 90.551994 -354.5489) (xy 90.574652 -354.598512)
			(xy 90.590018 -354.650844) (xy 90.597781 -354.704829) (xy 90.597781 -354.759371) (xy 90.597781 -354.759374)
			(xy 92.080484 -354.759374) (xy 92.080484 -354.704826) (xy 92.088247 -354.650833) (xy 92.103616 -354.598494)
			(xy 92.126278 -354.548876) (xy 92.155771 -354.502988) (xy 92.191495 -354.461765) (xy 92.232722 -354.426046)
			(xy 92.278613 -354.396558) (xy 92.328234 -354.373902) (xy 92.380574 -354.358538) (xy 92.434568 -354.350781)
			(xy 92.461842 -354.35032) (xy 93.325442 -354.35032) (xy 93.352708 -354.350845) (xy 93.406685 -354.358611)
			(xy 93.459007 -354.37398) (xy 93.508609 -354.396637) (xy 93.554483 -354.426123) (xy 93.595693 -354.461836)
			(xy 93.631402 -354.503051) (xy 93.660883 -354.548928) (xy 93.683535 -354.598533) (xy 93.698898 -354.650856)
			(xy 93.706658 -354.704834) (xy 93.706658 -354.759366) (xy 93.706658 -354.759369) (xy 114.589806 -354.759369)
			(xy 114.589806 -354.704831) (xy 114.597568 -354.650847) (xy 114.612932 -354.598518) (xy 114.635587 -354.548908)
			(xy 114.665071 -354.503026) (xy 114.700785 -354.461807) (xy 114.742 -354.42609) (xy 114.78788 -354.396602)
			(xy 114.837488 -354.373943) (xy 114.889816 -354.358574) (xy 114.943799 -354.350809) (xy 114.971068 -354.35032)
			(xy 115.834668 -354.35032) (xy 115.861939 -354.350817) (xy 115.915927 -354.358575) (xy 115.968261 -354.373938)
			(xy 116.017876 -354.396593) (xy 116.063761 -354.426078) (xy 116.104983 -354.461794) (xy 116.140703 -354.503013)
			(xy 116.170192 -354.548896) (xy 116.192851 -354.598509) (xy 116.208218 -354.650842) (xy 116.21598 -354.704829)
			(xy 116.21598 -354.759371) (xy 116.21598 -354.759374) (xy 117.698684 -354.759374) (xy 117.698684 -354.704826)
			(xy 117.706447 -354.650835) (xy 117.721815 -354.598497) (xy 117.744476 -354.54888) (xy 117.773968 -354.502993)
			(xy 117.80969 -354.46177) (xy 117.850915 -354.426051) (xy 117.896804 -354.396562) (xy 117.946423 -354.373905)
			(xy 117.998762 -354.358541) (xy 118.052754 -354.350782) (xy 118.080028 -354.35032) (xy 118.943628 -354.35032)
			(xy 118.970895 -354.350844) (xy 119.024873 -354.358609) (xy 119.077197 -354.373976) (xy 119.126801 -354.396633)
			(xy 119.172676 -354.426118) (xy 119.213888 -354.461831) (xy 119.249599 -354.503046) (xy 119.279081 -354.548924)
			(xy 119.301734 -354.59853) (xy 119.317097 -354.650855) (xy 119.324858 -354.704833) (xy 119.324858 -354.759367)
			(xy 119.324858 -354.75937) (xy 120.807706 -354.75937) (xy 120.807706 -354.70483) (xy 120.815468 -354.650845)
			(xy 120.830834 -354.598514) (xy 120.85349 -354.548902) (xy 120.882976 -354.50302) (xy 120.918692 -354.4618)
			(xy 120.95991 -354.426083) (xy 121.005791 -354.396596) (xy 121.055403 -354.373938) (xy 121.107733 -354.358571)
			(xy 121.161718 -354.350807) (xy 121.188988 -354.35032) (xy 122.052588 -354.35032) (xy 122.079858 -354.350819)
			(xy 122.133844 -354.358579) (xy 122.186176 -354.373944) (xy 122.235788 -354.396599) (xy 122.281671 -354.426085)
			(xy 122.322891 -354.461801) (xy 122.358608 -354.503019) (xy 122.388095 -354.548902) (xy 122.410752 -354.598513)
			(xy 122.426118 -354.650844) (xy 122.433881 -354.70483) (xy 122.433881 -354.75937) (xy 122.43388 -354.759374)
			(xy 123.916584 -354.759374) (xy 123.916584 -354.704826) (xy 123.924347 -354.650832) (xy 123.939717 -354.598493)
			(xy 123.962379 -354.548874) (xy 123.991872 -354.502986) (xy 124.027597 -354.461763) (xy 124.068825 -354.426044)
			(xy 124.114716 -354.396556) (xy 124.164338 -354.3739) (xy 124.216679 -354.358537) (xy 124.270673 -354.35078)
			(xy 124.297948 -354.35032) (xy 125.161548 -354.35032) (xy 125.188814 -354.350846) (xy 125.24279 -354.358613)
			(xy 125.295111 -354.373981) (xy 125.344713 -354.396639) (xy 125.390586 -354.426125) (xy 125.431795 -354.461839)
			(xy 125.467504 -354.503053) (xy 125.496984 -354.548929) (xy 125.519636 -354.598534) (xy 125.534998 -354.650857)
			(xy 125.542758 -354.704834) (xy 125.542758 -354.759366) (xy 125.542757 -354.759373) (xy 127.025584 -354.759373)
			(xy 127.025584 -354.704827) (xy 127.033346 -354.650837) (xy 127.048714 -354.598501) (xy 127.071373 -354.548885)
			(xy 127.100863 -354.502999) (xy 127.136583 -354.461777) (xy 127.177806 -354.426058) (xy 127.223692 -354.396569)
			(xy 127.273309 -354.373911) (xy 127.325645 -354.358545) (xy 127.379635 -354.350783) (xy 127.406908 -354.35032)
			(xy 128.270508 -354.35032) (xy 128.297776 -354.350843) (xy 128.351756 -354.358605) (xy 128.404082 -354.37397)
			(xy 128.453689 -354.396626) (xy 128.499567 -354.426111) (xy 128.540781 -354.461824) (xy 128.576494 -354.50304)
			(xy 128.605978 -354.548918) (xy 128.628632 -354.598525) (xy 128.643997 -354.650852) (xy 128.651758 -354.704832)
			(xy 128.651758 -354.759368) (xy 128.651758 -354.759369) (xy 130.134606 -354.759369) (xy 130.134606 -354.704831)
			(xy 130.142368 -354.650847) (xy 130.157732 -354.598518) (xy 130.180387 -354.548908) (xy 130.209871 -354.503026)
			(xy 130.245585 -354.461807) (xy 130.2868 -354.42609) (xy 130.33268 -354.396602) (xy 130.382288 -354.373943)
			(xy 130.434616 -354.358574) (xy 130.488599 -354.350809) (xy 130.515868 -354.35032) (xy 131.379468 -354.35032)
			(xy 131.406739 -354.350817) (xy 131.460727 -354.358575) (xy 131.513061 -354.373938) (xy 131.562676 -354.396593)
			(xy 131.608561 -354.426078) (xy 131.649783 -354.461794) (xy 131.685503 -354.503013) (xy 131.714992 -354.548896)
			(xy 131.737651 -354.598509) (xy 131.753018 -354.650842) (xy 131.76078 -354.704829) (xy 131.76078 -354.759371)
			(xy 131.76078 -354.759374) (xy 133.243484 -354.759374) (xy 133.243484 -354.704826) (xy 133.251247 -354.650835)
			(xy 133.266615 -354.598497) (xy 133.289276 -354.54888) (xy 133.318768 -354.502993) (xy 133.35449 -354.46177)
			(xy 133.395715 -354.426051) (xy 133.441604 -354.396562) (xy 133.491223 -354.373905) (xy 133.543562 -354.358541)
			(xy 133.597554 -354.350782) (xy 133.624828 -354.35032) (xy 134.488428 -354.35032) (xy 134.515695 -354.350844)
			(xy 134.569673 -354.358609) (xy 134.621997 -354.373976) (xy 134.671601 -354.396633) (xy 134.717476 -354.426118)
			(xy 134.758688 -354.461831) (xy 134.794399 -354.503046) (xy 134.823881 -354.548924) (xy 134.846534 -354.59853)
			(xy 134.861897 -354.650855) (xy 134.869658 -354.704833) (xy 134.869658 -354.759367) (xy 134.869658 -354.75937)
			(xy 136.352506 -354.75937) (xy 136.352506 -354.70483) (xy 136.360268 -354.650845) (xy 136.375634 -354.598514)
			(xy 136.39829 -354.548902) (xy 136.427776 -354.50302) (xy 136.463492 -354.4618) (xy 136.50471 -354.426083)
			(xy 136.550591 -354.396596) (xy 136.600203 -354.373938) (xy 136.652533 -354.358571) (xy 136.706518 -354.350807)
			(xy 136.733788 -354.35032) (xy 137.597388 -354.35032) (xy 137.624658 -354.350819) (xy 137.678644 -354.358579)
			(xy 137.730976 -354.373944) (xy 137.780588 -354.396599) (xy 137.826471 -354.426085) (xy 137.867691 -354.461801)
			(xy 137.903408 -354.503019) (xy 137.932895 -354.548902) (xy 137.955552 -354.598513) (xy 137.970918 -354.650844)
			(xy 137.978681 -354.70483) (xy 137.978681 -354.75937) (xy 137.97868 -354.759374) (xy 139.461384 -354.759374)
			(xy 139.461384 -354.704826) (xy 139.469147 -354.650832) (xy 139.484517 -354.598493) (xy 139.507179 -354.548874)
			(xy 139.536672 -354.502986) (xy 139.572397 -354.461763) (xy 139.613625 -354.426044) (xy 139.659516 -354.396556)
			(xy 139.709138 -354.3739) (xy 139.761479 -354.358537) (xy 139.815473 -354.35078) (xy 139.842748 -354.35032)
			(xy 140.706348 -354.35032) (xy 140.733614 -354.350846) (xy 140.78759 -354.358613) (xy 140.839911 -354.373981)
			(xy 140.889513 -354.396639) (xy 140.935386 -354.426125) (xy 140.976595 -354.461839) (xy 141.012304 -354.503053)
			(xy 141.041784 -354.548929) (xy 141.064436 -354.598534) (xy 141.079798 -354.650857) (xy 141.087558 -354.704834)
			(xy 141.087558 -354.759366) (xy 141.087557 -354.759373) (xy 142.570384 -354.759373) (xy 142.570384 -354.704827)
			(xy 142.578146 -354.650837) (xy 142.593514 -354.598501) (xy 142.616173 -354.548885) (xy 142.645663 -354.502999)
			(xy 142.681383 -354.461777) (xy 142.722606 -354.426058) (xy 142.768492 -354.396569) (xy 142.818109 -354.373911)
			(xy 142.870445 -354.358545) (xy 142.924435 -354.350783) (xy 142.951708 -354.35032) (xy 143.815308 -354.35032)
			(xy 143.842576 -354.350843) (xy 143.896556 -354.358605) (xy 143.948882 -354.37397) (xy 143.998489 -354.396626)
			(xy 144.044367 -354.426111) (xy 144.085581 -354.461824) (xy 144.121294 -354.50304) (xy 144.150778 -354.548918)
			(xy 144.173432 -354.598525) (xy 144.188797 -354.650852) (xy 144.196558 -354.704832) (xy 144.196558 -354.759368)
			(xy 158.695906 -354.759368) (xy 158.695906 -354.704832) (xy 158.703667 -354.65085) (xy 158.719031 -354.598521)
			(xy 158.741685 -354.548912) (xy 158.771167 -354.503031) (xy 158.806879 -354.461813) (xy 158.848093 -354.426096)
			(xy 158.89397 -354.396608) (xy 158.943576 -354.373948) (xy 158.995903 -354.358577) (xy 159.049884 -354.35081)
			(xy 159.077152 -354.35032) (xy 159.940752 -354.35032) (xy 159.968024 -354.350816) (xy 160.022013 -354.358572)
			(xy 160.074349 -354.373934) (xy 160.123966 -354.396588) (xy 160.169854 -354.426072) (xy 160.211078 -354.461788)
			(xy 160.246799 -354.503008) (xy 160.276289 -354.548891) (xy 160.298949 -354.598506) (xy 160.314317 -354.65084)
			(xy 160.32208 -354.704828) (xy 160.32208 -354.759372) (xy 160.32208 -354.759373) (xy 161.804784 -354.759373)
			(xy 161.804784 -354.704827) (xy 161.812546 -354.650837) (xy 161.827914 -354.598501) (xy 161.850573 -354.548884)
			(xy 161.880064 -354.502998) (xy 161.915784 -354.461776) (xy 161.957008 -354.426056) (xy 162.002895 -354.396568)
			(xy 162.052512 -354.37391) (xy 162.104848 -354.358544) (xy 162.158839 -354.350783) (xy 162.186112 -354.35032)
			(xy 163.049712 -354.35032) (xy 163.07698 -354.350843) (xy 163.130959 -354.358606) (xy 163.183285 -354.373972)
			(xy 163.232891 -354.396627) (xy 163.278768 -354.426112) (xy 163.319983 -354.461826) (xy 163.355695 -354.503041)
			(xy 163.385178 -354.548919) (xy 163.407833 -354.598526) (xy 163.423197 -354.650852) (xy 163.430958 -354.704832)
			(xy 163.430958 -354.759368) (xy 163.430958 -354.759369) (xy 164.913806 -354.759369) (xy 164.913806 -354.704831)
			(xy 164.921568 -354.650847) (xy 164.936932 -354.598517) (xy 164.959588 -354.548907) (xy 164.989072 -354.503025)
			(xy 165.024786 -354.461806) (xy 165.066002 -354.426089) (xy 165.111882 -354.396601) (xy 165.161491 -354.373942)
			(xy 165.21382 -354.358574) (xy 165.267803 -354.350808) (xy 165.295072 -354.35032) (xy 166.158672 -354.35032)
			(xy 166.185943 -354.350818) (xy 166.23993 -354.358576) (xy 166.292264 -354.373939) (xy 166.341878 -354.396594)
			(xy 166.387763 -354.42608) (xy 166.428985 -354.461795) (xy 166.464704 -354.503014) (xy 166.494192 -354.548897)
			(xy 166.516851 -354.59851) (xy 166.532218 -354.650842) (xy 166.53998 -354.704829) (xy 166.53998 -354.759371)
			(xy 166.53998 -354.759374) (xy 168.022684 -354.759374) (xy 168.022684 -354.704826) (xy 168.030447 -354.650834)
			(xy 168.045816 -354.598496) (xy 168.068477 -354.548879) (xy 168.097969 -354.502991) (xy 168.133691 -354.461768)
			(xy 168.174917 -354.426049) (xy 168.220807 -354.396561) (xy 168.270426 -354.373904) (xy 168.322765 -354.35854)
			(xy 168.376758 -354.350781) (xy 168.404032 -354.35032) (xy 169.267632 -354.35032) (xy 169.294899 -354.350845)
			(xy 169.348876 -354.35861) (xy 169.401199 -354.373977) (xy 169.450803 -354.396634) (xy 169.496678 -354.426119)
			(xy 169.53789 -354.461833) (xy 169.5736 -354.503048) (xy 169.603081 -354.548925) (xy 169.625734 -354.598531)
			(xy 169.641097 -354.650855) (xy 169.648858 -354.704833) (xy 169.648858 -354.759367) (xy 169.648858 -354.75937)
			(xy 171.131706 -354.75937) (xy 171.131706 -354.70483) (xy 171.139468 -354.650844) (xy 171.154834 -354.598513)
			(xy 171.177491 -354.548901) (xy 171.206977 -354.503018) (xy 171.242693 -354.461799) (xy 171.283912 -354.426082)
			(xy 171.329794 -354.396594) (xy 171.379405 -354.373937) (xy 171.431736 -354.35857) (xy 171.485722 -354.350807)
			(xy 171.512992 -354.35032) (xy 172.376592 -354.35032) (xy 172.403862 -354.350819) (xy 172.457847 -354.35858)
			(xy 172.510178 -354.373945) (xy 172.55979 -354.396601) (xy 172.605673 -354.426087) (xy 172.646892 -354.461802)
			(xy 172.682609 -354.503021) (xy 172.712096 -354.548903) (xy 172.734753 -354.598514) (xy 172.750119 -354.650845)
			(xy 172.757881 -354.70483) (xy 172.757881 -354.759368) (xy 174.240706 -354.759368) (xy 174.240706 -354.704832)
			(xy 174.248467 -354.65085) (xy 174.263831 -354.598521) (xy 174.286485 -354.548912) (xy 174.315967 -354.503031)
			(xy 174.351679 -354.461813) (xy 174.392893 -354.426096) (xy 174.43877 -354.396608) (xy 174.488376 -354.373948)
			(xy 174.540703 -354.358577) (xy 174.594684 -354.35081) (xy 174.621952 -354.35032) (xy 175.485552 -354.35032)
			(xy 175.512824 -354.350816) (xy 175.566813 -354.358572) (xy 175.619149 -354.373934) (xy 175.668766 -354.396588)
			(xy 175.714654 -354.426072) (xy 175.755878 -354.461788) (xy 175.791599 -354.503008) (xy 175.821089 -354.548891)
			(xy 175.843749 -354.598506) (xy 175.859117 -354.65084) (xy 175.86688 -354.704828) (xy 175.86688 -354.759372)
			(xy 175.86688 -354.759373) (xy 177.349584 -354.759373) (xy 177.349584 -354.704827) (xy 177.357346 -354.650837)
			(xy 177.372714 -354.598501) (xy 177.395373 -354.548884) (xy 177.424864 -354.502998) (xy 177.460584 -354.461776)
			(xy 177.501808 -354.426056) (xy 177.547695 -354.396568) (xy 177.597312 -354.37391) (xy 177.649648 -354.358544)
			(xy 177.703639 -354.350783) (xy 177.730912 -354.35032) (xy 178.594512 -354.35032) (xy 178.62178 -354.350843)
			(xy 178.675759 -354.358606) (xy 178.728085 -354.373972) (xy 178.777691 -354.396627) (xy 178.823568 -354.426112)
			(xy 178.864783 -354.461826) (xy 178.900495 -354.503041) (xy 178.929978 -354.548919) (xy 178.952633 -354.598526)
			(xy 178.967997 -354.650852) (xy 178.975758 -354.704832) (xy 178.975758 -354.759368) (xy 178.975758 -354.759369)
			(xy 180.458606 -354.759369) (xy 180.458606 -354.704831) (xy 180.466368 -354.650847) (xy 180.481732 -354.598517)
			(xy 180.504388 -354.548907) (xy 180.533872 -354.503025) (xy 180.569586 -354.461806) (xy 180.610802 -354.426089)
			(xy 180.656682 -354.396601) (xy 180.706291 -354.373942) (xy 180.75862 -354.358574) (xy 180.812603 -354.350808)
			(xy 180.839872 -354.35032) (xy 181.703472 -354.35032) (xy 181.730743 -354.350818) (xy 181.78473 -354.358576)
			(xy 181.837064 -354.373939) (xy 181.886678 -354.396594) (xy 181.932563 -354.42608) (xy 181.973785 -354.461795)
			(xy 182.009504 -354.503014) (xy 182.038992 -354.548897) (xy 182.061651 -354.59851) (xy 182.077018 -354.650842)
			(xy 182.08478 -354.704829) (xy 182.08478 -354.735472) (xy 183.567508 -354.735472) (xy 183.567508 -354.680928)
			(xy 183.57527 -354.626939) (xy 183.590638 -354.574605) (xy 183.613298 -354.52499) (xy 183.642788 -354.479106)
			(xy 183.678508 -354.437885) (xy 183.719731 -354.402169) (xy 183.765618 -354.372682) (xy 183.815235 -354.350027)
			(xy 183.86757 -354.334664) (xy 183.92156 -354.326905) (xy 183.948832 -354.326444) (xy 184.812432 -354.326444)
			(xy 184.8397 -354.326921) (xy 184.893681 -354.334686) (xy 184.946008 -354.350054) (xy 184.995615 -354.372713)
			(xy 185.041492 -354.4022) (xy 185.082707 -354.437916) (xy 185.118419 -354.479133) (xy 185.147903 -354.525013)
			(xy 185.170557 -354.574622) (xy 185.185921 -354.62695) (xy 185.193682 -354.680932) (xy 185.193682 -354.735468)
			(xy 185.193682 -354.735469) (xy 186.67653 -354.735469) (xy 186.67653 -354.680931) (xy 186.684292 -354.626949)
			(xy 186.699656 -354.574621) (xy 186.722312 -354.525012) (xy 186.751796 -354.479133) (xy 186.78751 -354.437916)
			(xy 186.828726 -354.402201) (xy 186.874605 -354.372716) (xy 186.924214 -354.350059) (xy 186.976542 -354.334693)
			(xy 187.030523 -354.326931) (xy 187.057792 -354.326444) (xy 187.921392 -354.326444) (xy 187.948664 -354.326895)
			(xy 188.002652 -354.334656) (xy 188.054987 -354.350022) (xy 188.104602 -354.37268) (xy 188.150487 -354.402167)
			(xy 188.191709 -354.437885) (xy 188.227428 -354.479106) (xy 188.256917 -354.524991) (xy 188.279575 -354.574606)
			(xy 188.294942 -354.62694) (xy 188.302704 -354.680928) (xy 188.302704 -354.735472) (xy 188.299268 -354.759369)
			(xy 270.624806 -354.759369) (xy 270.624806 -354.704831) (xy 270.632567 -354.650848) (xy 270.647932 -354.598519)
			(xy 270.670586 -354.548909) (xy 270.70007 -354.503028) (xy 270.735783 -354.46181) (xy 270.776998 -354.426093)
			(xy 270.822876 -354.396604) (xy 270.872484 -354.373945) (xy 270.924811 -354.358575) (xy 270.978793 -354.350809)
			(xy 271.006062 -354.35032) (xy 271.869662 -354.35032) (xy 271.896933 -354.350817) (xy 271.950922 -354.358574)
			(xy 272.003257 -354.373936) (xy 272.052872 -354.396591) (xy 272.098759 -354.426076) (xy 272.139981 -354.461792)
			(xy 272.175701 -354.503011) (xy 272.205191 -354.548894) (xy 272.22785 -354.598508) (xy 272.243218 -354.650841)
			(xy 272.25098 -354.704829) (xy 272.25098 -354.759371) (xy 272.25098 -354.759373) (xy 273.733684 -354.759373)
			(xy 273.733684 -354.704827) (xy 273.741447 -354.650835) (xy 273.756815 -354.598498) (xy 273.779475 -354.548882)
			(xy 273.808966 -354.502995) (xy 273.844688 -354.461772) (xy 273.885912 -354.426053) (xy 273.931801 -354.396564)
			(xy 273.981419 -354.373907) (xy 274.033757 -354.358542) (xy 274.087749 -354.350782) (xy 274.115022 -354.35032)
			(xy 274.978622 -354.35032) (xy 275.005889 -354.350844) (xy 275.059868 -354.358608) (xy 275.112192 -354.373974)
			(xy 275.161797 -354.396631) (xy 275.207673 -354.426116) (xy 275.248886 -354.461829) (xy 275.284597 -354.503044)
			(xy 275.31408 -354.548922) (xy 275.336733 -354.598528) (xy 275.352097 -354.650854) (xy 275.359858 -354.704833)
			(xy 275.359858 -354.759367) (xy 275.359858 -354.75937) (xy 276.842706 -354.75937) (xy 276.842706 -354.70483)
			(xy 276.850468 -354.650846) (xy 276.865833 -354.598515) (xy 276.888489 -354.548904) (xy 276.917975 -354.503022)
			(xy 276.95369 -354.461802) (xy 276.994907 -354.426085) (xy 277.040788 -354.396598) (xy 277.090398 -354.373939)
			(xy 277.142728 -354.358572) (xy 277.196712 -354.350808) (xy 277.223982 -354.35032) (xy 278.087582 -354.35032)
			(xy 278.114853 -354.350818) (xy 278.168839 -354.358578) (xy 278.221171 -354.373942) (xy 278.270784 -354.396597)
			(xy 278.316668 -354.426083) (xy 278.357888 -354.461799) (xy 278.393606 -354.503018) (xy 278.423094 -354.5489)
			(xy 278.445752 -354.598512) (xy 278.461118 -354.650844) (xy 278.468881 -354.704829) (xy 278.468881 -354.759371)
			(xy 278.468881 -354.759374) (xy 279.951584 -354.759374) (xy 279.951584 -354.704826) (xy 279.959347 -354.650833)
			(xy 279.974716 -354.598494) (xy 279.997378 -354.548876) (xy 280.026871 -354.502988) (xy 280.062595 -354.461765)
			(xy 280.103822 -354.426046) (xy 280.149713 -354.396558) (xy 280.199334 -354.373902) (xy 280.251674 -354.358538)
			(xy 280.305668 -354.350781) (xy 280.332942 -354.35032) (xy 281.196542 -354.35032) (xy 281.223808 -354.350845)
			(xy 281.277785 -354.358611) (xy 281.330107 -354.37398) (xy 281.379709 -354.396637) (xy 281.425583 -354.426123)
			(xy 281.466793 -354.461836) (xy 281.502502 -354.503051) (xy 281.531983 -354.548928) (xy 281.554635 -354.598533)
			(xy 281.569998 -354.650856) (xy 281.577758 -354.704834) (xy 281.577758 -354.759366) (xy 281.577757 -354.759372)
			(xy 283.060584 -354.759372) (xy 283.060584 -354.704828) (xy 283.068346 -354.650838) (xy 283.083713 -354.598503)
			(xy 283.106372 -354.548887) (xy 283.135861 -354.503001) (xy 283.171581 -354.461779) (xy 283.212803 -354.42606)
			(xy 283.258689 -354.396571) (xy 283.308305 -354.373912) (xy 283.36064 -354.358546) (xy 283.41463 -354.350783)
			(xy 283.441902 -354.35032) (xy 284.305502 -354.35032) (xy 284.33277 -354.350843) (xy 284.386751 -354.358604)
			(xy 284.439078 -354.373969) (xy 284.488685 -354.396624) (xy 284.534564 -354.426109) (xy 284.575779 -354.461822)
			(xy 284.611493 -354.503038) (xy 284.640977 -354.548917) (xy 284.663632 -354.598524) (xy 284.678996 -354.650851)
			(xy 284.686758 -354.704832) (xy 284.686758 -354.759368) (xy 284.686758 -354.759369) (xy 286.169606 -354.759369)
			(xy 286.169606 -354.704831) (xy 286.177367 -354.650848) (xy 286.192732 -354.598519) (xy 286.215386 -354.548909)
			(xy 286.24487 -354.503028) (xy 286.280583 -354.46181) (xy 286.321798 -354.426093) (xy 286.367676 -354.396604)
			(xy 286.417284 -354.373945) (xy 286.469611 -354.358575) (xy 286.523593 -354.350809) (xy 286.550862 -354.35032)
			(xy 287.414462 -354.35032) (xy 287.441733 -354.350817) (xy 287.495722 -354.358574) (xy 287.548057 -354.373936)
			(xy 287.597672 -354.396591) (xy 287.643559 -354.426076) (xy 287.684781 -354.461792) (xy 287.720501 -354.503011)
			(xy 287.749991 -354.548894) (xy 287.77265 -354.598508) (xy 287.788018 -354.650841) (xy 287.79578 -354.704829)
			(xy 287.79578 -354.759371) (xy 287.79578 -354.759373) (xy 289.278484 -354.759373) (xy 289.278484 -354.704827)
			(xy 289.286247 -354.650835) (xy 289.301615 -354.598498) (xy 289.324275 -354.548882) (xy 289.353766 -354.502995)
			(xy 289.389488 -354.461772) (xy 289.430712 -354.426053) (xy 289.476601 -354.396564) (xy 289.526219 -354.373907)
			(xy 289.578557 -354.358542) (xy 289.632549 -354.350782) (xy 289.659822 -354.35032) (xy 290.523422 -354.35032)
			(xy 290.550689 -354.350844) (xy 290.604668 -354.358608) (xy 290.656992 -354.373974) (xy 290.706597 -354.396631)
			(xy 290.752473 -354.426116) (xy 290.793686 -354.461829) (xy 290.829397 -354.503044) (xy 290.85888 -354.548922)
			(xy 290.881533 -354.598528) (xy 290.896897 -354.650854) (xy 290.904658 -354.704833) (xy 290.904658 -354.759367)
			(xy 290.904658 -354.75937) (xy 292.387506 -354.75937) (xy 292.387506 -354.70483) (xy 292.395268 -354.650846)
			(xy 292.410633 -354.598515) (xy 292.433289 -354.548904) (xy 292.462775 -354.503022) (xy 292.49849 -354.461802)
			(xy 292.539707 -354.426085) (xy 292.585588 -354.396598) (xy 292.635198 -354.373939) (xy 292.687528 -354.358572)
			(xy 292.741512 -354.350808) (xy 292.768782 -354.35032) (xy 293.632382 -354.35032) (xy 293.659653 -354.350818)
			(xy 293.713639 -354.358578) (xy 293.765971 -354.373942) (xy 293.815584 -354.396597) (xy 293.861468 -354.426083)
			(xy 293.902688 -354.461799) (xy 293.938406 -354.503018) (xy 293.967894 -354.5489) (xy 293.990552 -354.598512)
			(xy 294.005918 -354.650844) (xy 294.013681 -354.704829) (xy 294.013681 -354.759371) (xy 294.013681 -354.759374)
			(xy 295.496384 -354.759374) (xy 295.496384 -354.704826) (xy 295.504147 -354.650833) (xy 295.519516 -354.598494)
			(xy 295.542178 -354.548876) (xy 295.571671 -354.502988) (xy 295.607395 -354.461765) (xy 295.648622 -354.426046)
			(xy 295.694513 -354.396558) (xy 295.744134 -354.373902) (xy 295.796474 -354.358538) (xy 295.850468 -354.350781)
			(xy 295.877742 -354.35032) (xy 296.741342 -354.35032) (xy 296.768608 -354.350845) (xy 296.822585 -354.358611)
			(xy 296.874907 -354.37398) (xy 296.924509 -354.396637) (xy 296.970383 -354.426123) (xy 297.011593 -354.461836)
			(xy 297.047302 -354.503051) (xy 297.076783 -354.548928) (xy 297.099435 -354.598533) (xy 297.114798 -354.650856)
			(xy 297.122558 -354.704834) (xy 297.122558 -354.759366) (xy 297.122557 -354.759372) (xy 298.605384 -354.759372)
			(xy 298.605384 -354.704828) (xy 298.613146 -354.650838) (xy 298.628513 -354.598503) (xy 298.651172 -354.548887)
			(xy 298.680661 -354.503001) (xy 298.716381 -354.461779) (xy 298.757603 -354.42606) (xy 298.803489 -354.396571)
			(xy 298.853105 -354.373912) (xy 298.90544 -354.358546) (xy 298.95943 -354.350783) (xy 298.986702 -354.35032)
			(xy 299.850302 -354.35032) (xy 299.87757 -354.350843) (xy 299.931551 -354.358604) (xy 299.983878 -354.373969)
			(xy 300.033485 -354.396624) (xy 300.079364 -354.426109) (xy 300.120579 -354.461822) (xy 300.156293 -354.503038)
			(xy 300.185777 -354.548917) (xy 300.208432 -354.598524) (xy 300.223796 -354.650851) (xy 300.231558 -354.704832)
			(xy 300.231558 -354.759368) (xy 300.231558 -354.759369) (xy 315.230506 -354.759369) (xy 315.230506 -354.704831)
			(xy 315.238267 -354.650848) (xy 315.253632 -354.598519) (xy 315.276286 -354.548909) (xy 315.30577 -354.503027)
			(xy 315.341483 -354.461809) (xy 315.382699 -354.426092) (xy 315.428577 -354.396604) (xy 315.478185 -354.373944)
			(xy 315.530513 -354.358575) (xy 315.584495 -354.350809) (xy 315.611764 -354.35032) (xy 316.475364 -354.35032)
			(xy 316.502635 -354.350817) (xy 316.556624 -354.358575) (xy 316.608958 -354.373937) (xy 316.658574 -354.396591)
			(xy 316.70446 -354.426077) (xy 316.745682 -354.461793) (xy 316.781402 -354.503012) (xy 316.810891 -354.548895)
			(xy 316.83355 -354.598508) (xy 316.848918 -354.650841) (xy 316.85668 -354.704829) (xy 316.85668 -354.759371)
			(xy 316.85668 -354.759373) (xy 318.339384 -354.759373) (xy 318.339384 -354.704827) (xy 318.347147 -354.650835)
			(xy 318.362515 -354.598498) (xy 318.385175 -354.548881) (xy 318.414667 -354.502994) (xy 318.450388 -354.461771)
			(xy 318.491613 -354.426052) (xy 318.537502 -354.396564) (xy 318.587121 -354.373907) (xy 318.639459 -354.358542)
			(xy 318.693451 -354.350782) (xy 318.720724 -354.35032) (xy 319.584324 -354.35032) (xy 319.611591 -354.350844)
			(xy 319.665569 -354.358608) (xy 319.717894 -354.373975) (xy 319.767498 -354.396631) (xy 319.813374 -354.426116)
			(xy 319.854587 -354.46183) (xy 319.890298 -354.503045) (xy 319.91978 -354.548923) (xy 319.942434 -354.598529)
			(xy 319.957797 -354.650854) (xy 319.965558 -354.704833) (xy 319.965558 -354.759367) (xy 319.965558 -354.75937)
			(xy 321.448406 -354.75937) (xy 321.448406 -354.70483) (xy 321.456168 -354.650845) (xy 321.471533 -354.598515)
			(xy 321.494189 -354.548903) (xy 321.523675 -354.503021) (xy 321.55939 -354.461802) (xy 321.600608 -354.426085)
			(xy 321.646489 -354.396597) (xy 321.6961 -354.373939) (xy 321.74843 -354.358571) (xy 321.802414 -354.350808)
			(xy 321.829684 -354.35032) (xy 322.693284 -354.35032) (xy 322.720554 -354.350818) (xy 322.774541 -354.358578)
			(xy 322.826873 -354.373942) (xy 322.876485 -354.396598) (xy 322.922369 -354.426084) (xy 322.963589 -354.4618)
			(xy 322.999307 -354.503018) (xy 323.028794 -354.5489) (xy 323.051452 -354.598512) (xy 323.066818 -354.650844)
			(xy 323.074581 -354.70483) (xy 323.074581 -354.75937) (xy 323.07458 -354.759374) (xy 324.557284 -354.759374)
			(xy 324.557284 -354.704826) (xy 324.565047 -354.650832) (xy 324.580417 -354.598494) (xy 324.603078 -354.548875)
			(xy 324.632571 -354.502987) (xy 324.668295 -354.461764) (xy 324.709523 -354.426045) (xy 324.755414 -354.396557)
			(xy 324.805035 -354.373901) (xy 324.857375 -354.358538) (xy 324.91137 -354.350781) (xy 324.938644 -354.35032)
			(xy 325.802244 -354.35032) (xy 325.82951 -354.350845) (xy 325.883486 -354.358612) (xy 325.935808 -354.37398)
			(xy 325.98541 -354.396638) (xy 326.031284 -354.426124) (xy 326.072494 -354.461837) (xy 326.108203 -354.503052)
			(xy 326.137683 -354.548928) (xy 326.160335 -354.598533) (xy 326.175698 -354.650857) (xy 326.183458 -354.704834)
			(xy 326.183458 -354.759366) (xy 326.183457 -354.759372) (xy 327.666284 -354.759372) (xy 327.666284 -354.704828)
			(xy 327.674046 -354.650838) (xy 327.689413 -354.598502) (xy 327.712072 -354.548887) (xy 327.741562 -354.503001)
			(xy 327.777281 -354.461778) (xy 327.818504 -354.426059) (xy 327.86439 -354.39657) (xy 327.914006 -354.373912)
			(xy 327.966342 -354.358545) (xy 328.020332 -354.350783) (xy 328.047604 -354.35032) (xy 328.911204 -354.35032)
			(xy 328.938472 -354.350843) (xy 328.992453 -354.358604) (xy 329.044779 -354.373969) (xy 329.094386 -354.396625)
			(xy 329.140265 -354.426109) (xy 329.18148 -354.461823) (xy 329.217193 -354.503039) (xy 329.246677 -354.548917)
			(xy 329.269332 -354.598525) (xy 329.284696 -354.650851) (xy 329.292458 -354.704832) (xy 329.292458 -354.759368)
			(xy 329.292458 -354.759369) (xy 330.775306 -354.759369) (xy 330.775306 -354.704831) (xy 330.783067 -354.650848)
			(xy 330.798432 -354.598519) (xy 330.821086 -354.548909) (xy 330.85057 -354.503027) (xy 330.886283 -354.461809)
			(xy 330.927499 -354.426092) (xy 330.973377 -354.396604) (xy 331.022985 -354.373944) (xy 331.075313 -354.358575)
			(xy 331.129295 -354.350809) (xy 331.156564 -354.35032) (xy 332.020164 -354.35032) (xy 332.047435 -354.350817)
			(xy 332.101424 -354.358575) (xy 332.153758 -354.373937) (xy 332.203374 -354.396591) (xy 332.24926 -354.426077)
			(xy 332.290482 -354.461793) (xy 332.326202 -354.503012) (xy 332.355691 -354.548895) (xy 332.37835 -354.598508)
			(xy 332.393718 -354.650841) (xy 332.40148 -354.704829) (xy 332.40148 -354.759371) (xy 332.40148 -354.759373)
			(xy 333.884184 -354.759373) (xy 333.884184 -354.704827) (xy 333.891947 -354.650835) (xy 333.907315 -354.598498)
			(xy 333.929975 -354.548881) (xy 333.959467 -354.502994) (xy 333.995188 -354.461771) (xy 334.036413 -354.426052)
			(xy 334.082302 -354.396564) (xy 334.131921 -354.373907) (xy 334.184259 -354.358542) (xy 334.238251 -354.350782)
			(xy 334.265524 -354.35032) (xy 335.129124 -354.35032) (xy 335.156391 -354.350844) (xy 335.210369 -354.358608)
			(xy 335.262694 -354.373975) (xy 335.312298 -354.396631) (xy 335.358174 -354.426116) (xy 335.399387 -354.46183)
			(xy 335.435098 -354.503045) (xy 335.46458 -354.548923) (xy 335.487234 -354.598529) (xy 335.502597 -354.650854)
			(xy 335.510358 -354.704833) (xy 335.510358 -354.759367) (xy 335.510358 -354.75937) (xy 336.993206 -354.75937)
			(xy 336.993206 -354.70483) (xy 337.000968 -354.650845) (xy 337.016333 -354.598515) (xy 337.038989 -354.548903)
			(xy 337.068475 -354.503021) (xy 337.10419 -354.461802) (xy 337.145408 -354.426085) (xy 337.191289 -354.396597)
			(xy 337.2409 -354.373939) (xy 337.29323 -354.358571) (xy 337.347214 -354.350808) (xy 337.374484 -354.35032)
			(xy 338.238084 -354.35032) (xy 338.265354 -354.350818) (xy 338.319341 -354.358578) (xy 338.371673 -354.373942)
			(xy 338.421285 -354.396598) (xy 338.467169 -354.426084) (xy 338.508389 -354.4618) (xy 338.544107 -354.503018)
			(xy 338.573594 -354.5489) (xy 338.596252 -354.598512) (xy 338.611618 -354.650844) (xy 338.619381 -354.70483)
			(xy 338.619381 -354.75937) (xy 338.61938 -354.759374) (xy 340.102084 -354.759374) (xy 340.102084 -354.704826)
			(xy 340.109847 -354.650832) (xy 340.125217 -354.598494) (xy 340.147878 -354.548875) (xy 340.177371 -354.502987)
			(xy 340.213095 -354.461764) (xy 340.254323 -354.426045) (xy 340.300214 -354.396557) (xy 340.349835 -354.373901)
			(xy 340.402175 -354.358538) (xy 340.45617 -354.350781) (xy 340.483444 -354.35032) (xy 341.347044 -354.35032)
			(xy 341.37431 -354.350845) (xy 341.428286 -354.358612) (xy 341.480608 -354.37398) (xy 341.53021 -354.396638)
			(xy 341.576084 -354.426124) (xy 341.617294 -354.461837) (xy 341.653003 -354.503052) (xy 341.682483 -354.548928)
			(xy 341.705135 -354.598533) (xy 341.720498 -354.650857) (xy 341.728258 -354.704834) (xy 341.728258 -354.759366)
			(xy 341.728257 -354.759372) (xy 343.211084 -354.759372) (xy 343.211084 -354.704828) (xy 343.218846 -354.650838)
			(xy 343.234213 -354.598502) (xy 343.256872 -354.548887) (xy 343.286362 -354.503001) (xy 343.322081 -354.461778)
			(xy 343.363304 -354.426059) (xy 343.40919 -354.39657) (xy 343.458806 -354.373912) (xy 343.511142 -354.358545)
			(xy 343.565132 -354.350783) (xy 343.592404 -354.35032) (xy 344.456004 -354.35032) (xy 344.483272 -354.350843)
			(xy 344.537253 -354.358604) (xy 344.589579 -354.373969) (xy 344.639186 -354.396625) (xy 344.685065 -354.426109)
			(xy 344.72628 -354.461823) (xy 344.761993 -354.503039) (xy 344.791477 -354.548917) (xy 344.814132 -354.598525)
			(xy 344.829496 -354.650851) (xy 344.837258 -354.704832) (xy 344.837258 -354.759368) (xy 344.837257 -354.759374)
			(xy 373.915584 -354.759374) (xy 373.915584 -354.704826) (xy 373.923347 -354.650833) (xy 373.938716 -354.598495)
			(xy 373.961378 -354.548876) (xy 373.990871 -354.502989) (xy 374.026594 -354.461766) (xy 374.067821 -354.426047)
			(xy 374.113712 -354.396559) (xy 374.163332 -354.373902) (xy 374.215672 -354.358539) (xy 374.269666 -354.350781)
			(xy 374.29694 -354.35032) (xy 375.16054 -354.35032) (xy 375.187806 -354.350845) (xy 375.241783 -354.358611)
			(xy 375.294105 -354.373979) (xy 375.343708 -354.396637) (xy 375.389582 -354.426122) (xy 375.430793 -354.461836)
			(xy 375.466502 -354.50305) (xy 375.495983 -354.548927) (xy 375.518635 -354.598532) (xy 375.533997 -354.650856)
			(xy 375.541758 -354.704834) (xy 375.541758 -354.759366) (xy 375.541757 -354.759371) (xy 377.024606 -354.759371)
			(xy 377.024606 -354.704829) (xy 377.032369 -354.650843) (xy 377.047735 -354.598511) (xy 377.070392 -354.548899)
			(xy 377.099879 -354.503016) (xy 377.135596 -354.461796) (xy 377.176816 -354.426079) (xy 377.222699 -354.396592)
			(xy 377.272311 -354.373935) (xy 377.324643 -354.358569) (xy 377.378629 -354.350806) (xy 377.4059 -354.35032)
			(xy 378.2695 -354.35032) (xy 378.296768 -354.350842) (xy 378.350749 -354.358604) (xy 378.403076 -354.373968)
			(xy 378.452684 -354.396623) (xy 378.498563 -354.426108) (xy 378.539778 -354.461822) (xy 378.575492 -354.503037)
			(xy 378.604977 -354.548916) (xy 378.627632 -354.598524) (xy 378.642996 -354.650851) (xy 378.650758 -354.704832)
			(xy 378.650758 -354.759368) (xy 378.650758 -354.759369) (xy 380.133606 -354.759369) (xy 380.133606 -354.704831)
			(xy 380.141367 -354.650849) (xy 380.156731 -354.59852) (xy 380.179386 -354.54891) (xy 380.208869 -354.503029)
			(xy 380.244582 -354.46181) (xy 380.285797 -354.426093) (xy 380.331675 -354.396605) (xy 380.381282 -354.373945)
			(xy 380.433609 -354.358576) (xy 380.487591 -354.350809) (xy 380.51486 -354.35032) (xy 381.37846 -354.35032)
			(xy 381.405732 -354.350817) (xy 381.45972 -354.358574) (xy 381.512055 -354.373936) (xy 381.561671 -354.39659)
			(xy 381.607558 -354.426075) (xy 381.648781 -354.461791) (xy 381.684501 -354.50301) (xy 381.713991 -354.548894)
			(xy 381.73665 -354.598507) (xy 381.752018 -354.650841) (xy 381.75978 -354.704828) (xy 381.75978 -354.759372)
			(xy 381.75978 -354.759373) (xy 383.242484 -354.759373) (xy 383.242484 -354.704827) (xy 383.250247 -354.650836)
			(xy 383.265615 -354.598499) (xy 383.288275 -354.548882) (xy 383.317766 -354.502995) (xy 383.353487 -354.461773)
			(xy 383.394711 -354.426054) (xy 383.4406 -354.396565) (xy 383.490218 -354.373908) (xy 383.542555 -354.358542)
			(xy 383.596547 -354.350782) (xy 383.62382 -354.35032) (xy 384.48742 -354.35032) (xy 384.514687 -354.350844)
			(xy 384.568666 -354.358607) (xy 384.620991 -354.373974) (xy 384.670596 -354.39663) (xy 384.716472 -354.426115)
			(xy 384.757686 -354.461829) (xy 384.793397 -354.503044) (xy 384.82288 -354.548922) (xy 384.845533 -354.598528)
			(xy 384.860897 -354.650854) (xy 384.868658 -354.704833) (xy 384.868658 -354.759367) (xy 384.868658 -354.75937)
			(xy 386.351506 -354.75937) (xy 386.351506 -354.70483) (xy 386.359268 -354.650846) (xy 386.374633 -354.598515)
			(xy 386.397289 -354.548904) (xy 386.426774 -354.503022) (xy 386.462489 -354.461803) (xy 386.503706 -354.426086)
			(xy 386.549587 -354.396598) (xy 386.599197 -354.37394) (xy 386.651526 -354.358572) (xy 386.70551 -354.350808)
			(xy 386.73278 -354.35032) (xy 387.59638 -354.35032) (xy 387.623651 -354.350818) (xy 387.677637 -354.358578)
			(xy 387.72997 -354.373941) (xy 387.779583 -354.396597) (xy 387.825467 -354.426082) (xy 387.866688 -354.461798)
			(xy 387.902406 -354.503017) (xy 387.931894 -354.548899) (xy 387.954552 -354.598511) (xy 387.969918 -354.650843)
			(xy 387.97768 -354.704829) (xy 387.97768 -354.759371) (xy 387.97768 -354.759374) (xy 389.460384 -354.759374)
			(xy 389.460384 -354.704826) (xy 389.468147 -354.650833) (xy 389.483516 -354.598495) (xy 389.506178 -354.548876)
			(xy 389.535671 -354.502989) (xy 389.571394 -354.461766) (xy 389.612621 -354.426047) (xy 389.658512 -354.396559)
			(xy 389.708132 -354.373902) (xy 389.760472 -354.358539) (xy 389.814466 -354.350781) (xy 389.84174 -354.35032)
			(xy 390.70534 -354.35032) (xy 390.732606 -354.350845) (xy 390.786583 -354.358611) (xy 390.838905 -354.373979)
			(xy 390.888508 -354.396637) (xy 390.934382 -354.426122) (xy 390.975593 -354.461836) (xy 391.011302 -354.50305)
			(xy 391.040783 -354.548927) (xy 391.063435 -354.598532) (xy 391.078797 -354.650856) (xy 391.086558 -354.704834)
			(xy 391.086558 -354.759366) (xy 391.086557 -354.759371) (xy 392.569406 -354.759371) (xy 392.569406 -354.704829)
			(xy 392.577169 -354.650843) (xy 392.592535 -354.598511) (xy 392.615192 -354.548899) (xy 392.644679 -354.503016)
			(xy 392.680396 -354.461796) (xy 392.721616 -354.426079) (xy 392.767499 -354.396592) (xy 392.817111 -354.373935)
			(xy 392.869443 -354.358569) (xy 392.923429 -354.350806) (xy 392.9507 -354.35032) (xy 393.8143 -354.35032)
			(xy 393.841568 -354.350842) (xy 393.895549 -354.358604) (xy 393.947876 -354.373968) (xy 393.997484 -354.396623)
			(xy 394.043363 -354.426108) (xy 394.084578 -354.461822) (xy 394.120292 -354.503037) (xy 394.149777 -354.548916)
			(xy 394.172432 -354.598524) (xy 394.187796 -354.650851) (xy 394.195558 -354.704832) (xy 394.195558 -354.759368)
			(xy 394.195558 -354.759369) (xy 395.678406 -354.759369) (xy 395.678406 -354.704831) (xy 395.686167 -354.650849)
			(xy 395.701531 -354.59852) (xy 395.724186 -354.54891) (xy 395.753669 -354.503029) (xy 395.789382 -354.46181)
			(xy 395.830597 -354.426093) (xy 395.876475 -354.396605) (xy 395.926082 -354.373945) (xy 395.978409 -354.358576)
			(xy 396.032391 -354.350809) (xy 396.05966 -354.35032) (xy 396.92326 -354.35032) (xy 396.950532 -354.350817)
			(xy 397.00452 -354.358574) (xy 397.056855 -354.373936) (xy 397.106471 -354.39659) (xy 397.152358 -354.426075)
			(xy 397.193581 -354.461791) (xy 397.229301 -354.50301) (xy 397.258791 -354.548894) (xy 397.28145 -354.598507)
			(xy 397.296818 -354.650841) (xy 397.30458 -354.704828) (xy 397.30458 -354.759372) (xy 397.30458 -354.759373)
			(xy 398.787284 -354.759373) (xy 398.787284 -354.704827) (xy 398.795047 -354.650836) (xy 398.810415 -354.598499)
			(xy 398.833075 -354.548882) (xy 398.862566 -354.502995) (xy 398.898287 -354.461773) (xy 398.939511 -354.426054)
			(xy 398.9854 -354.396565) (xy 399.035018 -354.373908) (xy 399.087355 -354.358542) (xy 399.141347 -354.350782)
			(xy 399.16862 -354.35032) (xy 400.03222 -354.35032) (xy 400.059487 -354.350844) (xy 400.113466 -354.358607)
			(xy 400.165791 -354.373974) (xy 400.215396 -354.39663) (xy 400.261272 -354.426115) (xy 400.302486 -354.461829)
			(xy 400.338197 -354.503044) (xy 400.36768 -354.548922) (xy 400.390333 -354.598528) (xy 400.405697 -354.650854)
			(xy 400.413458 -354.704833) (xy 400.413458 -354.759367) (xy 400.413458 -354.75937) (xy 401.896306 -354.75937)
			(xy 401.896306 -354.70483) (xy 401.904068 -354.650846) (xy 401.919433 -354.598515) (xy 401.942089 -354.548904)
			(xy 401.971574 -354.503022) (xy 402.007289 -354.461803) (xy 402.048506 -354.426086) (xy 402.094387 -354.396598)
			(xy 402.143997 -354.37394) (xy 402.196326 -354.358572) (xy 402.25031 -354.350808) (xy 402.27758 -354.35032)
			(xy 403.14118 -354.35032) (xy 403.168451 -354.350818) (xy 403.222437 -354.358578) (xy 403.27477 -354.373941)
			(xy 403.324383 -354.396597) (xy 403.370267 -354.426082) (xy 403.411488 -354.461798) (xy 403.447206 -354.503017)
			(xy 403.476694 -354.548899) (xy 403.499352 -354.598511) (xy 403.514718 -354.650843) (xy 403.52248 -354.704829)
			(xy 403.52248 -354.759368) (xy 412.022806 -354.759368) (xy 412.022806 -354.704832) (xy 412.030567 -354.65085)
			(xy 412.045931 -354.598521) (xy 412.068585 -354.548912) (xy 412.098067 -354.503031) (xy 412.133779 -354.461813)
			(xy 412.174993 -354.426096) (xy 412.22087 -354.396608) (xy 412.270476 -354.373948) (xy 412.322803 -354.358577)
			(xy 412.376784 -354.35081) (xy 412.404052 -354.35032) (xy 413.267652 -354.35032) (xy 413.294924 -354.350816)
			(xy 413.348913 -354.358572) (xy 413.401249 -354.373934) (xy 413.450866 -354.396588) (xy 413.496754 -354.426072)
			(xy 413.537978 -354.461788) (xy 413.573699 -354.503008) (xy 413.603189 -354.548891) (xy 413.625849 -354.598506)
			(xy 413.641217 -354.65084) (xy 413.64898 -354.704828) (xy 413.64898 -354.759372) (xy 413.64898 -354.759373)
			(xy 415.131684 -354.759373) (xy 415.131684 -354.704827) (xy 415.139446 -354.650837) (xy 415.154814 -354.598501)
			(xy 415.177473 -354.548884) (xy 415.206964 -354.502998) (xy 415.242684 -354.461776) (xy 415.283908 -354.426056)
			(xy 415.329795 -354.396568) (xy 415.379412 -354.37391) (xy 415.431748 -354.358544) (xy 415.485739 -354.350783)
			(xy 415.513012 -354.35032) (xy 416.376612 -354.35032) (xy 416.40388 -354.350843) (xy 416.457859 -354.358606)
			(xy 416.510185 -354.373972) (xy 416.559791 -354.396627) (xy 416.605668 -354.426112) (xy 416.646883 -354.461826)
			(xy 416.682595 -354.503041) (xy 416.712078 -354.548919) (xy 416.734733 -354.598526) (xy 416.750097 -354.650852)
			(xy 416.757858 -354.704832) (xy 416.757858 -354.759368) (xy 416.757858 -354.759369) (xy 418.240706 -354.759369)
			(xy 418.240706 -354.704831) (xy 418.248468 -354.650847) (xy 418.263832 -354.598517) (xy 418.286488 -354.548907)
			(xy 418.315972 -354.503025) (xy 418.351686 -354.461806) (xy 418.392902 -354.426089) (xy 418.438782 -354.396601)
			(xy 418.488391 -354.373942) (xy 418.54072 -354.358574) (xy 418.594703 -354.350808) (xy 418.621972 -354.35032)
			(xy 419.485572 -354.35032) (xy 419.512843 -354.350818) (xy 419.56683 -354.358576) (xy 419.619164 -354.373939)
			(xy 419.668778 -354.396594) (xy 419.714663 -354.42608) (xy 419.755885 -354.461795) (xy 419.791604 -354.503014)
			(xy 419.821092 -354.548897) (xy 419.843751 -354.59851) (xy 419.859118 -354.650842) (xy 419.86688 -354.704829)
			(xy 419.86688 -354.759371) (xy 419.86688 -354.759374) (xy 421.349584 -354.759374) (xy 421.349584 -354.704826)
			(xy 421.357347 -354.650834) (xy 421.372716 -354.598496) (xy 421.395377 -354.548879) (xy 421.424869 -354.502991)
			(xy 421.460591 -354.461768) (xy 421.501817 -354.426049) (xy 421.547707 -354.396561) (xy 421.597326 -354.373904)
			(xy 421.649665 -354.35854) (xy 421.703658 -354.350781) (xy 421.730932 -354.35032) (xy 422.594532 -354.35032)
			(xy 422.621799 -354.350845) (xy 422.675776 -354.35861) (xy 422.728099 -354.373977) (xy 422.777703 -354.396634)
			(xy 422.823578 -354.426119) (xy 422.86479 -354.461833) (xy 422.9005 -354.503048) (xy 422.929981 -354.548925)
			(xy 422.952634 -354.598531) (xy 422.967997 -354.650855) (xy 422.975758 -354.704833) (xy 422.975758 -354.759367)
			(xy 422.975758 -354.75937) (xy 424.458606 -354.75937) (xy 424.458606 -354.70483) (xy 424.466368 -354.650844)
			(xy 424.481734 -354.598513) (xy 424.504391 -354.548901) (xy 424.533877 -354.503018) (xy 424.569593 -354.461799)
			(xy 424.610812 -354.426082) (xy 424.656694 -354.396594) (xy 424.706305 -354.373937) (xy 424.758636 -354.35857)
			(xy 424.812622 -354.350807) (xy 424.839892 -354.35032) (xy 425.703492 -354.35032) (xy 425.730762 -354.350819)
			(xy 425.784747 -354.35858) (xy 425.837078 -354.373945) (xy 425.88669 -354.396601) (xy 425.932573 -354.426087)
			(xy 425.973792 -354.461802) (xy 426.009509 -354.503021) (xy 426.038996 -354.548903) (xy 426.061653 -354.598514)
			(xy 426.077019 -354.650845) (xy 426.084781 -354.70483) (xy 426.084781 -354.759368) (xy 427.567606 -354.759368)
			(xy 427.567606 -354.704832) (xy 427.575367 -354.65085) (xy 427.590731 -354.598521) (xy 427.613385 -354.548912)
			(xy 427.642867 -354.503031) (xy 427.678579 -354.461813) (xy 427.719793 -354.426096) (xy 427.76567 -354.396608)
			(xy 427.815276 -354.373948) (xy 427.867603 -354.358577) (xy 427.921584 -354.35081) (xy 427.948852 -354.35032)
			(xy 428.812452 -354.35032) (xy 428.839724 -354.350816) (xy 428.893713 -354.358572) (xy 428.946049 -354.373934)
			(xy 428.995666 -354.396588) (xy 429.041554 -354.426072) (xy 429.082778 -354.461788) (xy 429.118499 -354.503008)
			(xy 429.147989 -354.548891) (xy 429.170649 -354.598506) (xy 429.186017 -354.65084) (xy 429.19378 -354.704828)
			(xy 429.19378 -354.759372) (xy 429.19378 -354.759373) (xy 430.676484 -354.759373) (xy 430.676484 -354.704827)
			(xy 430.684246 -354.650837) (xy 430.699614 -354.598501) (xy 430.722273 -354.548884) (xy 430.751764 -354.502998)
			(xy 430.787484 -354.461776) (xy 430.828708 -354.426056) (xy 430.874595 -354.396568) (xy 430.924212 -354.37391)
			(xy 430.976548 -354.358544) (xy 431.030539 -354.350783) (xy 431.057812 -354.35032) (xy 431.921412 -354.35032)
			(xy 431.94868 -354.350843) (xy 432.002659 -354.358606) (xy 432.054985 -354.373972) (xy 432.104591 -354.396627)
			(xy 432.150468 -354.426112) (xy 432.191683 -354.461826) (xy 432.227395 -354.503041) (xy 432.256878 -354.548919)
			(xy 432.279533 -354.598526) (xy 432.294897 -354.650852) (xy 432.302658 -354.704832) (xy 432.302658 -354.759368)
			(xy 432.302658 -354.759369) (xy 433.785506 -354.759369) (xy 433.785506 -354.704831) (xy 433.793268 -354.650847)
			(xy 433.808632 -354.598517) (xy 433.831288 -354.548907) (xy 433.860772 -354.503025) (xy 433.896486 -354.461806)
			(xy 433.937702 -354.426089) (xy 433.983582 -354.396601) (xy 434.033191 -354.373942) (xy 434.08552 -354.358574)
			(xy 434.139503 -354.350808) (xy 434.166772 -354.35032) (xy 435.030372 -354.35032) (xy 435.057643 -354.350818)
			(xy 435.11163 -354.358576) (xy 435.163964 -354.373939) (xy 435.213578 -354.396594) (xy 435.259463 -354.42608)
			(xy 435.300685 -354.461795) (xy 435.336404 -354.503014) (xy 435.365892 -354.548897) (xy 435.388551 -354.59851)
			(xy 435.403918 -354.650842) (xy 435.41168 -354.704829) (xy 435.41168 -354.759371) (xy 435.41168 -354.759374)
			(xy 436.894384 -354.759374) (xy 436.894384 -354.704826) (xy 436.902147 -354.650834) (xy 436.917516 -354.598496)
			(xy 436.940177 -354.548879) (xy 436.969669 -354.502991) (xy 437.005391 -354.461768) (xy 437.046617 -354.426049)
			(xy 437.092507 -354.396561) (xy 437.142126 -354.373904) (xy 437.194465 -354.35854) (xy 437.248458 -354.350781)
			(xy 437.275732 -354.35032) (xy 438.139332 -354.35032) (xy 438.166599 -354.350845) (xy 438.220576 -354.35861)
			(xy 438.272899 -354.373977) (xy 438.322503 -354.396634) (xy 438.368378 -354.426119) (xy 438.40959 -354.461833)
			(xy 438.4453 -354.503048) (xy 438.474781 -354.548925) (xy 438.497434 -354.598531) (xy 438.512797 -354.650855)
			(xy 438.520558 -354.704833) (xy 438.520558 -354.759367) (xy 438.520558 -354.75937) (xy 440.003406 -354.75937)
			(xy 440.003406 -354.70483) (xy 440.011168 -354.650844) (xy 440.026534 -354.598513) (xy 440.049191 -354.548901)
			(xy 440.078677 -354.503018) (xy 440.114393 -354.461799) (xy 440.155612 -354.426082) (xy 440.201494 -354.396594)
			(xy 440.251105 -354.373937) (xy 440.303436 -354.35857) (xy 440.357422 -354.350807) (xy 440.384692 -354.35032)
			(xy 441.248292 -354.35032) (xy 441.275562 -354.350819) (xy 441.329547 -354.35858) (xy 441.381878 -354.373945)
			(xy 441.43149 -354.396601) (xy 441.477373 -354.426087) (xy 441.518592 -354.461802) (xy 441.554309 -354.503021)
			(xy 441.583796 -354.548903) (xy 441.606453 -354.598514) (xy 441.621819 -354.650845) (xy 441.629581 -354.70483)
			(xy 441.629581 -354.75937) (xy 441.621819 -354.813355) (xy 441.606453 -354.865686) (xy 441.583796 -354.915297)
			(xy 441.554309 -354.961179) (xy 441.518592 -355.002398) (xy 441.477373 -355.038113) (xy 441.43149 -355.067599)
			(xy 441.381878 -355.090255) (xy 441.329547 -355.10562) (xy 441.275562 -355.113381) (xy 441.248292 -355.113844)
			(xy 440.384692 -355.113844) (xy 440.357422 -355.113393) (xy 440.303436 -355.10563) (xy 440.251105 -355.090263)
			(xy 440.201494 -355.067606) (xy 440.155612 -355.038118) (xy 440.114393 -355.002401) (xy 440.078677 -354.961182)
			(xy 440.049191 -354.915299) (xy 440.026534 -354.865687) (xy 440.011168 -354.813356) (xy 440.003406 -354.75937)
			(xy 438.520558 -354.75937) (xy 438.512797 -354.813345) (xy 438.497434 -354.865669) (xy 438.474781 -354.915275)
			(xy 438.4453 -354.961152) (xy 438.40959 -355.002367) (xy 438.368378 -355.038081) (xy 438.322503 -355.067566)
			(xy 438.272899 -355.090223) (xy 438.220576 -355.10559) (xy 438.166599 -355.113355) (xy 438.139332 -355.113844)
			(xy 437.275732 -355.113844) (xy 437.248458 -355.113419) (xy 437.194465 -355.10566) (xy 437.142126 -355.090296)
			(xy 437.092507 -355.067639) (xy 437.046617 -355.038151) (xy 437.005391 -355.002432) (xy 436.969669 -354.961209)
			(xy 436.940177 -354.915321) (xy 436.917516 -354.865704) (xy 436.902147 -354.813366) (xy 436.894384 -354.759374)
			(xy 435.41168 -354.759374) (xy 435.403918 -354.813358) (xy 435.388551 -354.86569) (xy 435.365892 -354.915303)
			(xy 435.336404 -354.961186) (xy 435.300685 -355.002405) (xy 435.259463 -355.03812) (xy 435.213578 -355.067606)
			(xy 435.163964 -355.090261) (xy 435.11163 -355.105624) (xy 435.057643 -355.113382) (xy 435.030372 -355.113844)
			(xy 434.166772 -355.113844) (xy 434.139503 -355.113392) (xy 434.08552 -355.105626) (xy 434.033191 -355.090258)
			(xy 433.983582 -355.067599) (xy 433.937702 -355.038111) (xy 433.896486 -355.002394) (xy 433.860772 -354.961175)
			(xy 433.831288 -354.915293) (xy 433.808632 -354.865683) (xy 433.793268 -354.813353) (xy 433.785506 -354.759369)
			(xy 432.302658 -354.759369) (xy 432.294897 -354.813348) (xy 432.279533 -354.865674) (xy 432.256878 -354.915281)
			(xy 432.227395 -354.961159) (xy 432.191683 -355.002374) (xy 432.150468 -355.038088) (xy 432.104591 -355.067573)
			(xy 432.054985 -355.090228) (xy 432.002659 -355.105594) (xy 431.94868 -355.113357) (xy 431.921412 -355.113844)
			(xy 431.057812 -355.113844) (xy 431.030539 -355.113417) (xy 430.976548 -355.105656) (xy 430.924212 -355.09029)
			(xy 430.874595 -355.067632) (xy 430.828708 -355.038144) (xy 430.787484 -355.002424) (xy 430.751764 -354.961202)
			(xy 430.722273 -354.915316) (xy 430.699614 -354.865699) (xy 430.684246 -354.813363) (xy 430.676484 -354.759373)
			(xy 429.19378 -354.759373) (xy 429.186017 -354.81336) (xy 429.170649 -354.865694) (xy 429.147989 -354.915309)
			(xy 429.118499 -354.961192) (xy 429.082778 -355.002412) (xy 429.041554 -355.038128) (xy 428.995666 -355.067612)
			(xy 428.946049 -355.090266) (xy 428.893713 -355.105628) (xy 428.839724 -355.113384) (xy 428.812452 -355.113844)
			(xy 427.948852 -355.113844) (xy 427.921584 -355.11339) (xy 427.867603 -355.105623) (xy 427.815276 -355.090252)
			(xy 427.76567 -355.067592) (xy 427.719793 -355.038104) (xy 427.678579 -355.002387) (xy 427.642867 -354.961169)
			(xy 427.613385 -354.915288) (xy 427.590731 -354.865679) (xy 427.575367 -354.81335) (xy 427.567606 -354.759368)
			(xy 426.084781 -354.759368) (xy 426.084781 -354.75937) (xy 426.077019 -354.813355) (xy 426.061653 -354.865686)
			(xy 426.038996 -354.915297) (xy 426.009509 -354.961179) (xy 425.973792 -355.002398) (xy 425.932573 -355.038113)
			(xy 425.88669 -355.067599) (xy 425.837078 -355.090255) (xy 425.784747 -355.10562) (xy 425.730762 -355.113381)
			(xy 425.703492 -355.113844) (xy 424.839892 -355.113844) (xy 424.812622 -355.113393) (xy 424.758636 -355.10563)
			(xy 424.706305 -355.090263) (xy 424.656694 -355.067606) (xy 424.610812 -355.038118) (xy 424.569593 -355.002401)
			(xy 424.533877 -354.961182) (xy 424.504391 -354.915299) (xy 424.481734 -354.865687) (xy 424.466368 -354.813356)
			(xy 424.458606 -354.75937) (xy 422.975758 -354.75937) (xy 422.967997 -354.813345) (xy 422.952634 -354.865669)
			(xy 422.929981 -354.915275) (xy 422.9005 -354.961152) (xy 422.86479 -355.002367) (xy 422.823578 -355.038081)
			(xy 422.777703 -355.067566) (xy 422.728099 -355.090223) (xy 422.675776 -355.10559) (xy 422.621799 -355.113355)
			(xy 422.594532 -355.113844) (xy 421.730932 -355.113844) (xy 421.703658 -355.113419) (xy 421.649665 -355.10566)
			(xy 421.597326 -355.090296) (xy 421.547707 -355.067639) (xy 421.501817 -355.038151) (xy 421.460591 -355.002432)
			(xy 421.424869 -354.961209) (xy 421.395377 -354.915321) (xy 421.372716 -354.865704) (xy 421.357347 -354.813366)
			(xy 421.349584 -354.759374) (xy 419.86688 -354.759374) (xy 419.859118 -354.813358) (xy 419.843751 -354.86569)
			(xy 419.821092 -354.915303) (xy 419.791604 -354.961186) (xy 419.755885 -355.002405) (xy 419.714663 -355.03812)
			(xy 419.668778 -355.067606) (xy 419.619164 -355.090261) (xy 419.56683 -355.105624) (xy 419.512843 -355.113382)
			(xy 419.485572 -355.113844) (xy 418.621972 -355.113844) (xy 418.594703 -355.113392) (xy 418.54072 -355.105626)
			(xy 418.488391 -355.090258) (xy 418.438782 -355.067599) (xy 418.392902 -355.038111) (xy 418.351686 -355.002394)
			(xy 418.315972 -354.961175) (xy 418.286488 -354.915293) (xy 418.263832 -354.865683) (xy 418.248468 -354.813353)
			(xy 418.240706 -354.759369) (xy 416.757858 -354.759369) (xy 416.750097 -354.813348) (xy 416.734733 -354.865674)
			(xy 416.712078 -354.915281) (xy 416.682595 -354.961159) (xy 416.646883 -355.002374) (xy 416.605668 -355.038088)
			(xy 416.559791 -355.067573) (xy 416.510185 -355.090228) (xy 416.457859 -355.105594) (xy 416.40388 -355.113357)
			(xy 416.376612 -355.113844) (xy 415.513012 -355.113844) (xy 415.485739 -355.113417) (xy 415.431748 -355.105656)
			(xy 415.379412 -355.09029) (xy 415.329795 -355.067632) (xy 415.283908 -355.038144) (xy 415.242684 -355.002424)
			(xy 415.206964 -354.961202) (xy 415.177473 -354.915316) (xy 415.154814 -354.865699) (xy 415.139446 -354.813363)
			(xy 415.131684 -354.759373) (xy 413.64898 -354.759373) (xy 413.641217 -354.81336) (xy 413.625849 -354.865694)
			(xy 413.603189 -354.915309) (xy 413.573699 -354.961192) (xy 413.537978 -355.002412) (xy 413.496754 -355.038128)
			(xy 413.450866 -355.067612) (xy 413.401249 -355.090266) (xy 413.348913 -355.105628) (xy 413.294924 -355.113384)
			(xy 413.267652 -355.113844) (xy 412.404052 -355.113844) (xy 412.376784 -355.11339) (xy 412.322803 -355.105623)
			(xy 412.270476 -355.090252) (xy 412.22087 -355.067592) (xy 412.174993 -355.038104) (xy 412.133779 -355.002387)
			(xy 412.098067 -354.961169) (xy 412.068585 -354.915288) (xy 412.045931 -354.865679) (xy 412.030567 -354.81335)
			(xy 412.022806 -354.759368) (xy 403.52248 -354.759368) (xy 403.52248 -354.759371) (xy 403.514718 -354.813357)
			(xy 403.499352 -354.865689) (xy 403.476694 -354.915301) (xy 403.447206 -354.961183) (xy 403.411488 -355.002402)
			(xy 403.370267 -355.038118) (xy 403.324383 -355.067603) (xy 403.27477 -355.090259) (xy 403.222437 -355.105622)
			(xy 403.168451 -355.113382) (xy 403.14118 -355.113844) (xy 402.27758 -355.113844) (xy 402.25031 -355.113392)
			(xy 402.196326 -355.105628) (xy 402.143997 -355.09026) (xy 402.094387 -355.067602) (xy 402.048506 -355.038114)
			(xy 402.007289 -355.002397) (xy 401.971574 -354.961178) (xy 401.942089 -354.915296) (xy 401.919433 -354.865685)
			(xy 401.904068 -354.813354) (xy 401.896306 -354.75937) (xy 400.413458 -354.75937) (xy 400.405697 -354.813346)
			(xy 400.390333 -354.865672) (xy 400.36768 -354.915278) (xy 400.338197 -354.961156) (xy 400.302486 -355.002371)
			(xy 400.261272 -355.038085) (xy 400.215396 -355.06757) (xy 400.165791 -355.090226) (xy 400.113466 -355.105593)
			(xy 400.059487 -355.113356) (xy 400.03222 -355.113844) (xy 399.16862 -355.113844) (xy 399.141347 -355.113418)
			(xy 399.087355 -355.105658) (xy 399.035018 -355.090292) (xy 398.9854 -355.067635) (xy 398.939511 -355.038146)
			(xy 398.898287 -355.002427) (xy 398.862566 -354.961205) (xy 398.833075 -354.915318) (xy 398.810415 -354.865701)
			(xy 398.795047 -354.813364) (xy 398.787284 -354.759373) (xy 397.30458 -354.759373) (xy 397.296818 -354.813359)
			(xy 397.28145 -354.865693) (xy 397.258791 -354.915306) (xy 397.229301 -354.96119) (xy 397.193581 -355.002409)
			(xy 397.152358 -355.038125) (xy 397.106471 -355.06761) (xy 397.056855 -355.090264) (xy 397.00452 -355.105626)
			(xy 396.950532 -355.113383) (xy 396.92326 -355.113844) (xy 396.05966 -355.113844) (xy 396.032391 -355.113391)
			(xy 395.978409 -355.105624) (xy 395.926082 -355.090255) (xy 395.876475 -355.067595) (xy 395.830597 -355.038107)
			(xy 395.789382 -355.00239) (xy 395.753669 -354.961171) (xy 395.724186 -354.91529) (xy 395.701531 -354.86568)
			(xy 395.686167 -354.813351) (xy 395.678406 -354.759369) (xy 394.195558 -354.759369) (xy 394.187796 -354.813349)
			(xy 394.172432 -354.865676) (xy 394.149777 -354.915284) (xy 394.120292 -354.961163) (xy 394.084578 -355.002378)
			(xy 394.043363 -355.038092) (xy 393.997484 -355.067577) (xy 393.947876 -355.090232) (xy 393.895549 -355.105596)
			(xy 393.841568 -355.113358) (xy 393.8143 -355.113844) (xy 392.9507 -355.113844) (xy 392.923429 -355.113394)
			(xy 392.869443 -355.105631) (xy 392.817111 -355.090265) (xy 392.767499 -355.067608) (xy 392.721616 -355.038121)
			(xy 392.680396 -355.002404) (xy 392.644679 -354.961184) (xy 392.615192 -354.915301) (xy 392.592535 -354.865689)
			(xy 392.577169 -354.813357) (xy 392.569406 -354.759371) (xy 391.086557 -354.759371) (xy 391.078797 -354.813344)
			(xy 391.063435 -354.865668) (xy 391.040783 -354.915273) (xy 391.011302 -354.96115) (xy 390.975593 -355.002364)
			(xy 390.934382 -355.038078) (xy 390.888508 -355.067563) (xy 390.838905 -355.090221) (xy 390.786583 -355.105589)
			(xy 390.732606 -355.113355) (xy 390.70534 -355.113844) (xy 389.84174 -355.113844) (xy 389.814466 -355.113419)
			(xy 389.760472 -355.105661) (xy 389.708132 -355.090298) (xy 389.658512 -355.067641) (xy 389.612621 -355.038153)
			(xy 389.571394 -355.002434) (xy 389.535671 -354.961211) (xy 389.506178 -354.915324) (xy 389.483516 -354.865705)
			(xy 389.468147 -354.813367) (xy 389.460384 -354.759374) (xy 387.97768 -354.759374) (xy 387.969918 -354.813357)
			(xy 387.954552 -354.865689) (xy 387.931894 -354.915301) (xy 387.902406 -354.961183) (xy 387.866688 -355.002402)
			(xy 387.825467 -355.038118) (xy 387.779583 -355.067603) (xy 387.72997 -355.090259) (xy 387.677637 -355.105622)
			(xy 387.623651 -355.113382) (xy 387.59638 -355.113844) (xy 386.73278 -355.113844) (xy 386.70551 -355.113392)
			(xy 386.651526 -355.105628) (xy 386.599197 -355.09026) (xy 386.549587 -355.067602) (xy 386.503706 -355.038114)
			(xy 386.462489 -355.002397) (xy 386.426774 -354.961178) (xy 386.397289 -354.915296) (xy 386.374633 -354.865685)
			(xy 386.359268 -354.813354) (xy 386.351506 -354.75937) (xy 384.868658 -354.75937) (xy 384.860897 -354.813346)
			(xy 384.845533 -354.865672) (xy 384.82288 -354.915278) (xy 384.793397 -354.961156) (xy 384.757686 -355.002371)
			(xy 384.716472 -355.038085) (xy 384.670596 -355.06757) (xy 384.620991 -355.090226) (xy 384.568666 -355.105593)
			(xy 384.514687 -355.113356) (xy 384.48742 -355.113844) (xy 383.62382 -355.113844) (xy 383.596547 -355.113418)
			(xy 383.542555 -355.105658) (xy 383.490218 -355.090292) (xy 383.4406 -355.067635) (xy 383.394711 -355.038146)
			(xy 383.353487 -355.002427) (xy 383.317766 -354.961205) (xy 383.288275 -354.915318) (xy 383.265615 -354.865701)
			(xy 383.250247 -354.813364) (xy 383.242484 -354.759373) (xy 381.75978 -354.759373) (xy 381.752018 -354.813359)
			(xy 381.73665 -354.865693) (xy 381.713991 -354.915306) (xy 381.684501 -354.96119) (xy 381.648781 -355.002409)
			(xy 381.607558 -355.038125) (xy 381.561671 -355.06761) (xy 381.512055 -355.090264) (xy 381.45972 -355.105626)
			(xy 381.405732 -355.113383) (xy 381.37846 -355.113844) (xy 380.51486 -355.113844) (xy 380.487591 -355.113391)
			(xy 380.433609 -355.105624) (xy 380.381282 -355.090255) (xy 380.331675 -355.067595) (xy 380.285797 -355.038107)
			(xy 380.244582 -355.00239) (xy 380.208869 -354.961171) (xy 380.179386 -354.91529) (xy 380.156731 -354.86568)
			(xy 380.141367 -354.813351) (xy 380.133606 -354.759369) (xy 378.650758 -354.759369) (xy 378.642996 -354.813349)
			(xy 378.627632 -354.865676) (xy 378.604977 -354.915284) (xy 378.575492 -354.961163) (xy 378.539778 -355.002378)
			(xy 378.498563 -355.038092) (xy 378.452684 -355.067577) (xy 378.403076 -355.090232) (xy 378.350749 -355.105596)
			(xy 378.296768 -355.113358) (xy 378.2695 -355.113844) (xy 377.4059 -355.113844) (xy 377.378629 -355.113394)
			(xy 377.324643 -355.105631) (xy 377.272311 -355.090265) (xy 377.222699 -355.067608) (xy 377.176816 -355.038121)
			(xy 377.135596 -355.002404) (xy 377.099879 -354.961184) (xy 377.070392 -354.915301) (xy 377.047735 -354.865689)
			(xy 377.032369 -354.813357) (xy 377.024606 -354.759371) (xy 375.541757 -354.759371) (xy 375.533997 -354.813344)
			(xy 375.518635 -354.865668) (xy 375.495983 -354.915273) (xy 375.466502 -354.96115) (xy 375.430793 -355.002364)
			(xy 375.389582 -355.038078) (xy 375.343708 -355.067563) (xy 375.294105 -355.090221) (xy 375.241783 -355.105589)
			(xy 375.187806 -355.113355) (xy 375.16054 -355.113844) (xy 374.29694 -355.113844) (xy 374.269666 -355.113419)
			(xy 374.215672 -355.105661) (xy 374.163332 -355.090298) (xy 374.113712 -355.067641) (xy 374.067821 -355.038153)
			(xy 374.026594 -355.002434) (xy 373.990871 -354.961211) (xy 373.961378 -354.915324) (xy 373.938716 -354.865705)
			(xy 373.923347 -354.813367) (xy 373.915584 -354.759374) (xy 344.837257 -354.759374) (xy 344.829496 -354.813349)
			(xy 344.814132 -354.865675) (xy 344.791477 -354.915283) (xy 344.761993 -354.961161) (xy 344.72628 -355.002377)
			(xy 344.685065 -355.038091) (xy 344.639186 -355.067575) (xy 344.589579 -355.090231) (xy 344.537253 -355.105596)
			(xy 344.483272 -355.113357) (xy 344.456004 -355.113844) (xy 343.592404 -355.113844) (xy 343.565132 -355.113417)
			(xy 343.511142 -355.105655) (xy 343.458806 -355.090288) (xy 343.40919 -355.06763) (xy 343.363304 -355.038141)
			(xy 343.322081 -355.002422) (xy 343.286362 -354.961199) (xy 343.256872 -354.915313) (xy 343.234213 -354.865698)
			(xy 343.218846 -354.813362) (xy 343.211084 -354.759372) (xy 341.728257 -354.759372) (xy 341.720498 -354.813343)
			(xy 341.705135 -354.865667) (xy 341.682483 -354.915272) (xy 341.653003 -354.961148) (xy 341.617294 -355.002363)
			(xy 341.576084 -355.038076) (xy 341.53021 -355.067562) (xy 341.480608 -355.09022) (xy 341.428286 -355.105588)
			(xy 341.37431 -355.113355) (xy 341.347044 -355.113844) (xy 340.483444 -355.113844) (xy 340.45617 -355.113419)
			(xy 340.402175 -355.105662) (xy 340.349835 -355.090299) (xy 340.300214 -355.067643) (xy 340.254323 -355.038155)
			(xy 340.213095 -355.002436) (xy 340.177371 -354.961213) (xy 340.147878 -354.915325) (xy 340.125217 -354.865706)
			(xy 340.109847 -354.813368) (xy 340.102084 -354.759374) (xy 338.61938 -354.759374) (xy 338.611618 -354.813356)
			(xy 338.596252 -354.865688) (xy 338.573594 -354.9153) (xy 338.544107 -354.961182) (xy 338.508389 -355.0024)
			(xy 338.467169 -355.038116) (xy 338.421285 -355.067602) (xy 338.371673 -355.090258) (xy 338.319341 -355.105622)
			(xy 338.265354 -355.113382) (xy 338.238084 -355.113844) (xy 337.374484 -355.113844) (xy 337.347214 -355.113392)
			(xy 337.29323 -355.105629) (xy 337.2409 -355.090261) (xy 337.191289 -355.067603) (xy 337.145408 -355.038115)
			(xy 337.10419 -355.002398) (xy 337.068475 -354.961179) (xy 337.038989 -354.915297) (xy 337.016333 -354.865685)
			(xy 337.000968 -354.813355) (xy 336.993206 -354.75937) (xy 335.510358 -354.75937) (xy 335.502597 -354.813346)
			(xy 335.487234 -354.865671) (xy 335.46458 -354.915277) (xy 335.435098 -354.961155) (xy 335.399387 -355.00237)
			(xy 335.358174 -355.038084) (xy 335.312298 -355.067569) (xy 335.262694 -355.090225) (xy 335.210369 -355.105592)
			(xy 335.156391 -355.113356) (xy 335.129124 -355.113844) (xy 334.265524 -355.113844) (xy 334.238251 -355.113418)
			(xy 334.184259 -355.105658) (xy 334.131921 -355.090293) (xy 334.082302 -355.067636) (xy 334.036413 -355.038148)
			(xy 333.995188 -355.002429) (xy 333.959467 -354.961206) (xy 333.929975 -354.915319) (xy 333.907315 -354.865702)
			(xy 333.891947 -354.813365) (xy 333.884184 -354.759373) (xy 332.40148 -354.759373) (xy 332.393718 -354.813359)
			(xy 332.37835 -354.865692) (xy 332.355691 -354.915305) (xy 332.326202 -354.961188) (xy 332.290482 -355.002407)
			(xy 332.24926 -355.038123) (xy 332.203374 -355.067609) (xy 332.153758 -355.090263) (xy 332.101424 -355.105625)
			(xy 332.047435 -355.113383) (xy 332.020164 -355.113844) (xy 331.156564 -355.113844) (xy 331.129295 -355.113391)
			(xy 331.075313 -355.105625) (xy 331.022985 -355.090256) (xy 330.973377 -355.067596) (xy 330.927499 -355.038108)
			(xy 330.886283 -355.002391) (xy 330.85057 -354.961173) (xy 330.821086 -354.915291) (xy 330.798432 -354.865681)
			(xy 330.783067 -354.813352) (xy 330.775306 -354.759369) (xy 329.292458 -354.759369) (xy 329.284696 -354.813349)
			(xy 329.269332 -354.865675) (xy 329.246677 -354.915283) (xy 329.217193 -354.961161) (xy 329.18148 -355.002377)
			(xy 329.140265 -355.038091) (xy 329.094386 -355.067575) (xy 329.044779 -355.090231) (xy 328.992453 -355.105596)
			(xy 328.938472 -355.113357) (xy 328.911204 -355.113844) (xy 328.047604 -355.113844) (xy 328.020332 -355.113417)
			(xy 327.966342 -355.105655) (xy 327.914006 -355.090288) (xy 327.86439 -355.06763) (xy 327.818504 -355.038141)
			(xy 327.777281 -355.002422) (xy 327.741562 -354.961199) (xy 327.712072 -354.915313) (xy 327.689413 -354.865698)
			(xy 327.674046 -354.813362) (xy 327.666284 -354.759372) (xy 326.183457 -354.759372) (xy 326.175698 -354.813343)
			(xy 326.160335 -354.865667) (xy 326.137683 -354.915272) (xy 326.108203 -354.961148) (xy 326.072494 -355.002363)
			(xy 326.031284 -355.038076) (xy 325.98541 -355.067562) (xy 325.935808 -355.09022) (xy 325.883486 -355.105588)
			(xy 325.82951 -355.113355) (xy 325.802244 -355.113844) (xy 324.938644 -355.113844) (xy 324.91137 -355.113419)
			(xy 324.857375 -355.105662) (xy 324.805035 -355.090299) (xy 324.755414 -355.067643) (xy 324.709523 -355.038155)
			(xy 324.668295 -355.002436) (xy 324.632571 -354.961213) (xy 324.603078 -354.915325) (xy 324.580417 -354.865706)
			(xy 324.565047 -354.813368) (xy 324.557284 -354.759374) (xy 323.07458 -354.759374) (xy 323.066818 -354.813356)
			(xy 323.051452 -354.865688) (xy 323.028794 -354.9153) (xy 322.999307 -354.961182) (xy 322.963589 -355.0024)
			(xy 322.922369 -355.038116) (xy 322.876485 -355.067602) (xy 322.826873 -355.090258) (xy 322.774541 -355.105622)
			(xy 322.720554 -355.113382) (xy 322.693284 -355.113844) (xy 321.829684 -355.113844) (xy 321.802414 -355.113392)
			(xy 321.74843 -355.105629) (xy 321.6961 -355.090261) (xy 321.646489 -355.067603) (xy 321.600608 -355.038115)
			(xy 321.55939 -355.002398) (xy 321.523675 -354.961179) (xy 321.494189 -354.915297) (xy 321.471533 -354.865685)
			(xy 321.456168 -354.813355) (xy 321.448406 -354.75937) (xy 319.965558 -354.75937) (xy 319.957797 -354.813346)
			(xy 319.942434 -354.865671) (xy 319.91978 -354.915277) (xy 319.890298 -354.961155) (xy 319.854587 -355.00237)
			(xy 319.813374 -355.038084) (xy 319.767498 -355.067569) (xy 319.717894 -355.090225) (xy 319.665569 -355.105592)
			(xy 319.611591 -355.113356) (xy 319.584324 -355.113844) (xy 318.720724 -355.113844) (xy 318.693451 -355.113418)
			(xy 318.639459 -355.105658) (xy 318.587121 -355.090293) (xy 318.537502 -355.067636) (xy 318.491613 -355.038148)
			(xy 318.450388 -355.002429) (xy 318.414667 -354.961206) (xy 318.385175 -354.915319) (xy 318.362515 -354.865702)
			(xy 318.347147 -354.813365) (xy 318.339384 -354.759373) (xy 316.85668 -354.759373) (xy 316.848918 -354.813359)
			(xy 316.83355 -354.865692) (xy 316.810891 -354.915305) (xy 316.781402 -354.961188) (xy 316.745682 -355.002407)
			(xy 316.70446 -355.038123) (xy 316.658574 -355.067609) (xy 316.608958 -355.090263) (xy 316.556624 -355.105625)
			(xy 316.502635 -355.113383) (xy 316.475364 -355.113844) (xy 315.611764 -355.113844) (xy 315.584495 -355.113391)
			(xy 315.530513 -355.105625) (xy 315.478185 -355.090256) (xy 315.428577 -355.067596) (xy 315.382699 -355.038108)
			(xy 315.341483 -355.002391) (xy 315.30577 -354.961173) (xy 315.276286 -354.915291) (xy 315.253632 -354.865681)
			(xy 315.238267 -354.813352) (xy 315.230506 -354.759369) (xy 300.231558 -354.759369) (xy 300.223796 -354.813349)
			(xy 300.208432 -354.865676) (xy 300.185777 -354.915283) (xy 300.156293 -354.961162) (xy 300.120579 -355.002378)
			(xy 300.079364 -355.038091) (xy 300.033485 -355.067576) (xy 299.983878 -355.090231) (xy 299.931551 -355.105596)
			(xy 299.87757 -355.113357) (xy 299.850302 -355.113844) (xy 298.986702 -355.113844) (xy 298.95943 -355.113417)
			(xy 298.90544 -355.105654) (xy 298.853105 -355.090288) (xy 298.803489 -355.067629) (xy 298.757603 -355.03814)
			(xy 298.716381 -355.002421) (xy 298.680661 -354.961199) (xy 298.651172 -354.915313) (xy 298.628513 -354.865697)
			(xy 298.613146 -354.813362) (xy 298.605384 -354.759372) (xy 297.122557 -354.759372) (xy 297.114798 -354.813344)
			(xy 297.099435 -354.865667) (xy 297.076783 -354.915272) (xy 297.047302 -354.961149) (xy 297.011593 -355.002364)
			(xy 296.970383 -355.038077) (xy 296.924509 -355.067563) (xy 296.874907 -355.09022) (xy 296.822585 -355.105589)
			(xy 296.768608 -355.113355) (xy 296.741342 -355.113844) (xy 295.877742 -355.113844) (xy 295.850468 -355.113419)
			(xy 295.796474 -355.105662) (xy 295.744134 -355.090298) (xy 295.694513 -355.067642) (xy 295.648622 -355.038154)
			(xy 295.607395 -355.002435) (xy 295.571671 -354.961212) (xy 295.542178 -354.915324) (xy 295.519516 -354.865706)
			(xy 295.504147 -354.813367) (xy 295.496384 -354.759374) (xy 294.013681 -354.759374) (xy 294.005918 -354.813356)
			(xy 293.990552 -354.865688) (xy 293.967894 -354.9153) (xy 293.938406 -354.961182) (xy 293.902688 -355.002401)
			(xy 293.861468 -355.038117) (xy 293.815584 -355.067603) (xy 293.765971 -355.090258) (xy 293.713639 -355.105622)
			(xy 293.659653 -355.113382) (xy 293.632382 -355.113844) (xy 292.768782 -355.113844) (xy 292.741512 -355.113392)
			(xy 292.687528 -355.105628) (xy 292.635198 -355.090261) (xy 292.585588 -355.067602) (xy 292.539707 -355.038115)
			(xy 292.49849 -355.002398) (xy 292.462775 -354.961178) (xy 292.433289 -354.915296) (xy 292.410633 -354.865685)
			(xy 292.395268 -354.813354) (xy 292.387506 -354.75937) (xy 290.904658 -354.75937) (xy 290.896897 -354.813346)
			(xy 290.881533 -354.865672) (xy 290.85888 -354.915278) (xy 290.829397 -354.961156) (xy 290.793686 -355.002371)
			(xy 290.752473 -355.038084) (xy 290.706597 -355.067569) (xy 290.656992 -355.090226) (xy 290.604668 -355.105592)
			(xy 290.550689 -355.113356) (xy 290.523422 -355.113844) (xy 289.659822 -355.113844) (xy 289.632549 -355.113418)
			(xy 289.578557 -355.105658) (xy 289.526219 -355.090293) (xy 289.476601 -355.067636) (xy 289.430712 -355.038147)
			(xy 289.389488 -355.002428) (xy 289.353766 -354.961205) (xy 289.324275 -354.915318) (xy 289.301615 -354.865702)
			(xy 289.286247 -354.813365) (xy 289.278484 -354.759373) (xy 287.79578 -354.759373) (xy 287.788018 -354.813359)
			(xy 287.77265 -354.865692) (xy 287.749991 -354.915306) (xy 287.720501 -354.961189) (xy 287.684781 -355.002408)
			(xy 287.643559 -355.038124) (xy 287.597672 -355.067609) (xy 287.548057 -355.090264) (xy 287.495722 -355.105626)
			(xy 287.441733 -355.113383) (xy 287.414462 -355.113844) (xy 286.550862 -355.113844) (xy 286.523593 -355.113391)
			(xy 286.469611 -355.105625) (xy 286.417284 -355.090255) (xy 286.367676 -355.067596) (xy 286.321798 -355.038107)
			(xy 286.280583 -355.00239) (xy 286.24487 -354.961172) (xy 286.215386 -354.915291) (xy 286.192732 -354.865681)
			(xy 286.177367 -354.813352) (xy 286.169606 -354.759369) (xy 284.686758 -354.759369) (xy 284.678996 -354.813349)
			(xy 284.663632 -354.865676) (xy 284.640977 -354.915283) (xy 284.611493 -354.961162) (xy 284.575779 -355.002378)
			(xy 284.534564 -355.038091) (xy 284.488685 -355.067576) (xy 284.439078 -355.090231) (xy 284.386751 -355.105596)
			(xy 284.33277 -355.113357) (xy 284.305502 -355.113844) (xy 283.441902 -355.113844) (xy 283.41463 -355.113417)
			(xy 283.36064 -355.105654) (xy 283.308305 -355.090288) (xy 283.258689 -355.067629) (xy 283.212803 -355.03814)
			(xy 283.171581 -355.002421) (xy 283.135861 -354.961199) (xy 283.106372 -354.915313) (xy 283.083713 -354.865697)
			(xy 283.068346 -354.813362) (xy 283.060584 -354.759372) (xy 281.577757 -354.759372) (xy 281.569998 -354.813344)
			(xy 281.554635 -354.865667) (xy 281.531983 -354.915272) (xy 281.502502 -354.961149) (xy 281.466793 -355.002364)
			(xy 281.425583 -355.038077) (xy 281.379709 -355.067563) (xy 281.330107 -355.09022) (xy 281.277785 -355.105589)
			(xy 281.223808 -355.113355) (xy 281.196542 -355.113844) (xy 280.332942 -355.113844) (xy 280.305668 -355.113419)
			(xy 280.251674 -355.105662) (xy 280.199334 -355.090298) (xy 280.149713 -355.067642) (xy 280.103822 -355.038154)
			(xy 280.062595 -355.002435) (xy 280.026871 -354.961212) (xy 279.997378 -354.915324) (xy 279.974716 -354.865706)
			(xy 279.959347 -354.813367) (xy 279.951584 -354.759374) (xy 278.468881 -354.759374) (xy 278.461118 -354.813356)
			(xy 278.445752 -354.865688) (xy 278.423094 -354.9153) (xy 278.393606 -354.961182) (xy 278.357888 -355.002401)
			(xy 278.316668 -355.038117) (xy 278.270784 -355.067603) (xy 278.221171 -355.090258) (xy 278.168839 -355.105622)
			(xy 278.114853 -355.113382) (xy 278.087582 -355.113844) (xy 277.223982 -355.113844) (xy 277.196712 -355.113392)
			(xy 277.142728 -355.105628) (xy 277.090398 -355.090261) (xy 277.040788 -355.067602) (xy 276.994907 -355.038115)
			(xy 276.95369 -355.002398) (xy 276.917975 -354.961178) (xy 276.888489 -354.915296) (xy 276.865833 -354.865685)
			(xy 276.850468 -354.813354) (xy 276.842706 -354.75937) (xy 275.359858 -354.75937) (xy 275.352097 -354.813346)
			(xy 275.336733 -354.865672) (xy 275.31408 -354.915278) (xy 275.284597 -354.961156) (xy 275.248886 -355.002371)
			(xy 275.207673 -355.038084) (xy 275.161797 -355.067569) (xy 275.112192 -355.090226) (xy 275.059868 -355.105592)
			(xy 275.005889 -355.113356) (xy 274.978622 -355.113844) (xy 274.115022 -355.113844) (xy 274.087749 -355.113418)
			(xy 274.033757 -355.105658) (xy 273.981419 -355.090293) (xy 273.931801 -355.067636) (xy 273.885912 -355.038147)
			(xy 273.844688 -355.002428) (xy 273.808966 -354.961205) (xy 273.779475 -354.915318) (xy 273.756815 -354.865702)
			(xy 273.741447 -354.813365) (xy 273.733684 -354.759373) (xy 272.25098 -354.759373) (xy 272.243218 -354.813359)
			(xy 272.22785 -354.865692) (xy 272.205191 -354.915306) (xy 272.175701 -354.961189) (xy 272.139981 -355.002408)
			(xy 272.098759 -355.038124) (xy 272.052872 -355.067609) (xy 272.003257 -355.090264) (xy 271.950922 -355.105626)
			(xy 271.896933 -355.113383) (xy 271.869662 -355.113844) (xy 271.006062 -355.113844) (xy 270.978793 -355.113391)
			(xy 270.924811 -355.105625) (xy 270.872484 -355.090255) (xy 270.822876 -355.067596) (xy 270.776998 -355.038107)
			(xy 270.735783 -355.00239) (xy 270.70007 -354.961172) (xy 270.670586 -354.915291) (xy 270.647932 -354.865681)
			(xy 270.632567 -354.813352) (xy 270.624806 -354.759369) (xy 188.299268 -354.759369) (xy 188.294942 -354.78946)
			(xy 188.279575 -354.841794) (xy 188.256917 -354.891409) (xy 188.227428 -354.937294) (xy 188.191709 -354.978515)
			(xy 188.150487 -355.014233) (xy 188.104602 -355.04372) (xy 188.054987 -355.066378) (xy 188.002652 -355.081744)
			(xy 187.948664 -355.089505) (xy 187.921392 -355.089968) (xy 187.057792 -355.089968) (xy 187.030523 -355.089469)
			(xy 186.976542 -355.081707) (xy 186.924214 -355.066341) (xy 186.874605 -355.043684) (xy 186.828726 -355.014199)
			(xy 186.78751 -354.978484) (xy 186.751796 -354.937267) (xy 186.722312 -354.891388) (xy 186.699656 -354.841779)
			(xy 186.684292 -354.789451) (xy 186.67653 -354.735469) (xy 185.193682 -354.735469) (xy 185.185921 -354.78945)
			(xy 185.170557 -354.841778) (xy 185.147903 -354.891387) (xy 185.118419 -354.937267) (xy 185.082707 -354.978484)
			(xy 185.041492 -355.0142) (xy 184.995615 -355.043687) (xy 184.946008 -355.066346) (xy 184.893681 -355.081714)
			(xy 184.8397 -355.089479) (xy 184.812432 -355.089968) (xy 183.948832 -355.089968) (xy 183.92156 -355.089495)
			(xy 183.86757 -355.081736) (xy 183.815235 -355.066373) (xy 183.765618 -355.043718) (xy 183.719731 -355.014231)
			(xy 183.678508 -354.978515) (xy 183.642788 -354.937294) (xy 183.613298 -354.89141) (xy 183.590638 -354.841795)
			(xy 183.57527 -354.789461) (xy 183.567508 -354.735472) (xy 182.08478 -354.735472) (xy 182.08478 -354.759371)
			(xy 182.077018 -354.813358) (xy 182.061651 -354.86569) (xy 182.038992 -354.915303) (xy 182.009504 -354.961186)
			(xy 181.973785 -355.002405) (xy 181.932563 -355.03812) (xy 181.886678 -355.067606) (xy 181.837064 -355.090261)
			(xy 181.78473 -355.105624) (xy 181.730743 -355.113382) (xy 181.703472 -355.113844) (xy 180.839872 -355.113844)
			(xy 180.812603 -355.113392) (xy 180.75862 -355.105626) (xy 180.706291 -355.090258) (xy 180.656682 -355.067599)
			(xy 180.610802 -355.038111) (xy 180.569586 -355.002394) (xy 180.533872 -354.961175) (xy 180.504388 -354.915293)
			(xy 180.481732 -354.865683) (xy 180.466368 -354.813353) (xy 180.458606 -354.759369) (xy 178.975758 -354.759369)
			(xy 178.967997 -354.813348) (xy 178.952633 -354.865674) (xy 178.929978 -354.915281) (xy 178.900495 -354.961159)
			(xy 178.864783 -355.002374) (xy 178.823568 -355.038088) (xy 178.777691 -355.067573) (xy 178.728085 -355.090228)
			(xy 178.675759 -355.105594) (xy 178.62178 -355.113357) (xy 178.594512 -355.113844) (xy 177.730912 -355.113844)
			(xy 177.703639 -355.113417) (xy 177.649648 -355.105656) (xy 177.597312 -355.09029) (xy 177.547695 -355.067632)
			(xy 177.501808 -355.038144) (xy 177.460584 -355.002424) (xy 177.424864 -354.961202) (xy 177.395373 -354.915316)
			(xy 177.372714 -354.865699) (xy 177.357346 -354.813363) (xy 177.349584 -354.759373) (xy 175.86688 -354.759373)
			(xy 175.859117 -354.81336) (xy 175.843749 -354.865694) (xy 175.821089 -354.915309) (xy 175.791599 -354.961192)
			(xy 175.755878 -355.002412) (xy 175.714654 -355.038128) (xy 175.668766 -355.067612) (xy 175.619149 -355.090266)
			(xy 175.566813 -355.105628) (xy 175.512824 -355.113384) (xy 175.485552 -355.113844) (xy 174.621952 -355.113844)
			(xy 174.594684 -355.11339) (xy 174.540703 -355.105623) (xy 174.488376 -355.090252) (xy 174.43877 -355.067592)
			(xy 174.392893 -355.038104) (xy 174.351679 -355.002387) (xy 174.315967 -354.961169) (xy 174.286485 -354.915288)
			(xy 174.263831 -354.865679) (xy 174.248467 -354.81335) (xy 174.240706 -354.759368) (xy 172.757881 -354.759368)
			(xy 172.757881 -354.75937) (xy 172.750119 -354.813355) (xy 172.734753 -354.865686) (xy 172.712096 -354.915297)
			(xy 172.682609 -354.961179) (xy 172.646892 -355.002398) (xy 172.605673 -355.038113) (xy 172.55979 -355.067599)
			(xy 172.510178 -355.090255) (xy 172.457847 -355.10562) (xy 172.403862 -355.113381) (xy 172.376592 -355.113844)
			(xy 171.512992 -355.113844) (xy 171.485722 -355.113393) (xy 171.431736 -355.10563) (xy 171.379405 -355.090263)
			(xy 171.329794 -355.067606) (xy 171.283912 -355.038118) (xy 171.242693 -355.002401) (xy 171.206977 -354.961182)
			(xy 171.177491 -354.915299) (xy 171.154834 -354.865687) (xy 171.139468 -354.813356) (xy 171.131706 -354.75937)
			(xy 169.648858 -354.75937) (xy 169.641097 -354.813345) (xy 169.625734 -354.865669) (xy 169.603081 -354.915275)
			(xy 169.5736 -354.961152) (xy 169.53789 -355.002367) (xy 169.496678 -355.038081) (xy 169.450803 -355.067566)
			(xy 169.401199 -355.090223) (xy 169.348876 -355.10559) (xy 169.294899 -355.113355) (xy 169.267632 -355.113844)
			(xy 168.404032 -355.113844) (xy 168.376758 -355.113419) (xy 168.322765 -355.10566) (xy 168.270426 -355.090296)
			(xy 168.220807 -355.067639) (xy 168.174917 -355.038151) (xy 168.133691 -355.002432) (xy 168.097969 -354.961209)
			(xy 168.068477 -354.915321) (xy 168.045816 -354.865704) (xy 168.030447 -354.813366) (xy 168.022684 -354.759374)
			(xy 166.53998 -354.759374) (xy 166.532218 -354.813358) (xy 166.516851 -354.86569) (xy 166.494192 -354.915303)
			(xy 166.464704 -354.961186) (xy 166.428985 -355.002405) (xy 166.387763 -355.03812) (xy 166.341878 -355.067606)
			(xy 166.292264 -355.090261) (xy 166.23993 -355.105624) (xy 166.185943 -355.113382) (xy 166.158672 -355.113844)
			(xy 165.295072 -355.113844) (xy 165.267803 -355.113392) (xy 165.21382 -355.105626) (xy 165.161491 -355.090258)
			(xy 165.111882 -355.067599) (xy 165.066002 -355.038111) (xy 165.024786 -355.002394) (xy 164.989072 -354.961175)
			(xy 164.959588 -354.915293) (xy 164.936932 -354.865683) (xy 164.921568 -354.813353) (xy 164.913806 -354.759369)
			(xy 163.430958 -354.759369) (xy 163.423197 -354.813348) (xy 163.407833 -354.865674) (xy 163.385178 -354.915281)
			(xy 163.355695 -354.961159) (xy 163.319983 -355.002374) (xy 163.278768 -355.038088) (xy 163.232891 -355.067573)
			(xy 163.183285 -355.090228) (xy 163.130959 -355.105594) (xy 163.07698 -355.113357) (xy 163.049712 -355.113844)
			(xy 162.186112 -355.113844) (xy 162.158839 -355.113417) (xy 162.104848 -355.105656) (xy 162.052512 -355.09029)
			(xy 162.002895 -355.067632) (xy 161.957008 -355.038144) (xy 161.915784 -355.002424) (xy 161.880064 -354.961202)
			(xy 161.850573 -354.915316) (xy 161.827914 -354.865699) (xy 161.812546 -354.813363) (xy 161.804784 -354.759373)
			(xy 160.32208 -354.759373) (xy 160.314317 -354.81336) (xy 160.298949 -354.865694) (xy 160.276289 -354.915309)
			(xy 160.246799 -354.961192) (xy 160.211078 -355.002412) (xy 160.169854 -355.038128) (xy 160.123966 -355.067612)
			(xy 160.074349 -355.090266) (xy 160.022013 -355.105628) (xy 159.968024 -355.113384) (xy 159.940752 -355.113844)
			(xy 159.077152 -355.113844) (xy 159.049884 -355.11339) (xy 158.995903 -355.105623) (xy 158.943576 -355.090252)
			(xy 158.89397 -355.067592) (xy 158.848093 -355.038104) (xy 158.806879 -355.002387) (xy 158.771167 -354.961169)
			(xy 158.741685 -354.915288) (xy 158.719031 -354.865679) (xy 158.703667 -354.81335) (xy 158.695906 -354.759368)
			(xy 144.196558 -354.759368) (xy 144.188797 -354.813348) (xy 144.173432 -354.865675) (xy 144.150778 -354.915282)
			(xy 144.121294 -354.96116) (xy 144.085581 -355.002376) (xy 144.044367 -355.038089) (xy 143.998489 -355.067574)
			(xy 143.948882 -355.09023) (xy 143.896556 -355.105595) (xy 143.842576 -355.113357) (xy 143.815308 -355.113844)
			(xy 142.951708 -355.113844) (xy 142.924435 -355.113417) (xy 142.870445 -355.105655) (xy 142.818109 -355.090289)
			(xy 142.768492 -355.067631) (xy 142.722606 -355.038142) (xy 142.681383 -355.002423) (xy 142.645663 -354.961201)
			(xy 142.616173 -354.915315) (xy 142.593514 -354.865699) (xy 142.578146 -354.813363) (xy 142.570384 -354.759373)
			(xy 141.087557 -354.759373) (xy 141.079798 -354.813343) (xy 141.064436 -354.865666) (xy 141.041784 -354.915271)
			(xy 141.012304 -354.961147) (xy 140.976595 -355.002361) (xy 140.935386 -355.038075) (xy 140.889513 -355.067561)
			(xy 140.839911 -355.090219) (xy 140.78759 -355.105587) (xy 140.733614 -355.113354) (xy 140.706348 -355.113844)
			(xy 139.842748 -355.113844) (xy 139.815473 -355.11342) (xy 139.761479 -355.105663) (xy 139.709138 -355.0903)
			(xy 139.659516 -355.067644) (xy 139.613625 -355.038156) (xy 139.572397 -355.002437) (xy 139.536672 -354.961214)
			(xy 139.507179 -354.915326) (xy 139.484517 -354.865707) (xy 139.469147 -354.813368) (xy 139.461384 -354.759374)
			(xy 137.97868 -354.759374) (xy 137.970918 -354.813356) (xy 137.955552 -354.865687) (xy 137.932895 -354.915298)
			(xy 137.903408 -354.961181) (xy 137.867691 -355.002399) (xy 137.826471 -355.038115) (xy 137.780588 -355.067601)
			(xy 137.730976 -355.090256) (xy 137.678644 -355.105621) (xy 137.624658 -355.113381) (xy 137.597388 -355.113844)
			(xy 136.733788 -355.113844) (xy 136.706518 -355.113393) (xy 136.652533 -355.105629) (xy 136.600203 -355.090262)
			(xy 136.550591 -355.067604) (xy 136.50471 -355.038117) (xy 136.463492 -355.0024) (xy 136.427776 -354.96118)
			(xy 136.39829 -354.915298) (xy 136.375634 -354.865686) (xy 136.360268 -354.813355) (xy 136.352506 -354.75937)
			(xy 134.869658 -354.75937) (xy 134.861897 -354.813345) (xy 134.846534 -354.86567) (xy 134.823881 -354.915276)
			(xy 134.794399 -354.961154) (xy 134.758688 -355.002369) (xy 134.717476 -355.038082) (xy 134.671601 -355.067567)
			(xy 134.621997 -355.090224) (xy 134.569673 -355.105591) (xy 134.515695 -355.113356) (xy 134.488428 -355.113844)
			(xy 133.624828 -355.113844) (xy 133.597554 -355.113418) (xy 133.543562 -355.105659) (xy 133.491223 -355.090295)
			(xy 133.441604 -355.067638) (xy 133.395715 -355.038149) (xy 133.35449 -355.00243) (xy 133.318768 -354.961207)
			(xy 133.289276 -354.91532) (xy 133.266615 -354.865703) (xy 133.251247 -354.813365) (xy 133.243484 -354.759374)
			(xy 131.76078 -354.759374) (xy 131.753018 -354.813358) (xy 131.737651 -354.865691) (xy 131.714992 -354.915304)
			(xy 131.685503 -354.961187) (xy 131.649783 -355.002406) (xy 131.608561 -355.038122) (xy 131.562676 -355.067607)
			(xy 131.513061 -355.090262) (xy 131.460727 -355.105625) (xy 131.406739 -355.113383) (xy 131.379468 -355.113844)
			(xy 130.515868 -355.113844) (xy 130.488599 -355.113391) (xy 130.434616 -355.105626) (xy 130.382288 -355.090257)
			(xy 130.33268 -355.067598) (xy 130.2868 -355.03811) (xy 130.245585 -355.002393) (xy 130.209871 -354.961174)
			(xy 130.180387 -354.915292) (xy 130.157732 -354.865682) (xy 130.142368 -354.813353) (xy 130.134606 -354.759369)
			(xy 128.651758 -354.759369) (xy 128.643997 -354.813348) (xy 128.628632 -354.865675) (xy 128.605978 -354.915282)
			(xy 128.576494 -354.96116) (xy 128.540781 -355.002376) (xy 128.499567 -355.038089) (xy 128.453689 -355.067574)
			(xy 128.404082 -355.09023) (xy 128.351756 -355.105595) (xy 128.297776 -355.113357) (xy 128.270508 -355.113844)
			(xy 127.406908 -355.113844) (xy 127.379635 -355.113417) (xy 127.325645 -355.105655) (xy 127.273309 -355.090289)
			(xy 127.223692 -355.067631) (xy 127.177806 -355.038142) (xy 127.136583 -355.002423) (xy 127.100863 -354.961201)
			(xy 127.071373 -354.915315) (xy 127.048714 -354.865699) (xy 127.033346 -354.813363) (xy 127.025584 -354.759373)
			(xy 125.542757 -354.759373) (xy 125.534998 -354.813343) (xy 125.519636 -354.865666) (xy 125.496984 -354.915271)
			(xy 125.467504 -354.961147) (xy 125.431795 -355.002361) (xy 125.390586 -355.038075) (xy 125.344713 -355.067561)
			(xy 125.295111 -355.090219) (xy 125.24279 -355.105587) (xy 125.188814 -355.113354) (xy 125.161548 -355.113844)
			(xy 124.297948 -355.113844) (xy 124.270673 -355.11342) (xy 124.216679 -355.105663) (xy 124.164338 -355.0903)
			(xy 124.114716 -355.067644) (xy 124.068825 -355.038156) (xy 124.027597 -355.002437) (xy 123.991872 -354.961214)
			(xy 123.962379 -354.915326) (xy 123.939717 -354.865707) (xy 123.924347 -354.813368) (xy 123.916584 -354.759374)
			(xy 122.43388 -354.759374) (xy 122.426118 -354.813356) (xy 122.410752 -354.865687) (xy 122.388095 -354.915298)
			(xy 122.358608 -354.961181) (xy 122.322891 -355.002399) (xy 122.281671 -355.038115) (xy 122.235788 -355.067601)
			(xy 122.186176 -355.090256) (xy 122.133844 -355.105621) (xy 122.079858 -355.113381) (xy 122.052588 -355.113844)
			(xy 121.188988 -355.113844) (xy 121.161718 -355.113393) (xy 121.107733 -355.105629) (xy 121.055403 -355.090262)
			(xy 121.005791 -355.067604) (xy 120.95991 -355.038117) (xy 120.918692 -355.0024) (xy 120.882976 -354.96118)
			(xy 120.85349 -354.915298) (xy 120.830834 -354.865686) (xy 120.815468 -354.813355) (xy 120.807706 -354.75937)
			(xy 119.324858 -354.75937) (xy 119.317097 -354.813345) (xy 119.301734 -354.86567) (xy 119.279081 -354.915276)
			(xy 119.249599 -354.961154) (xy 119.213888 -355.002369) (xy 119.172676 -355.038082) (xy 119.126801 -355.067567)
			(xy 119.077197 -355.090224) (xy 119.024873 -355.105591) (xy 118.970895 -355.113356) (xy 118.943628 -355.113844)
			(xy 118.080028 -355.113844) (xy 118.052754 -355.113418) (xy 117.998762 -355.105659) (xy 117.946423 -355.090295)
			(xy 117.896804 -355.067638) (xy 117.850915 -355.038149) (xy 117.80969 -355.00243) (xy 117.773968 -354.961207)
			(xy 117.744476 -354.91532) (xy 117.721815 -354.865703) (xy 117.706447 -354.813365) (xy 117.698684 -354.759374)
			(xy 116.21598 -354.759374) (xy 116.208218 -354.813358) (xy 116.192851 -354.865691) (xy 116.170192 -354.915304)
			(xy 116.140703 -354.961187) (xy 116.104983 -355.002406) (xy 116.063761 -355.038122) (xy 116.017876 -355.067607)
			(xy 115.968261 -355.090262) (xy 115.915927 -355.105625) (xy 115.861939 -355.113383) (xy 115.834668 -355.113844)
			(xy 114.971068 -355.113844) (xy 114.943799 -355.113391) (xy 114.889816 -355.105626) (xy 114.837488 -355.090257)
			(xy 114.78788 -355.067598) (xy 114.742 -355.03811) (xy 114.700785 -355.002393) (xy 114.665071 -354.961174)
			(xy 114.635587 -354.915292) (xy 114.612932 -354.865682) (xy 114.597568 -354.813353) (xy 114.589806 -354.759369)
			(xy 93.706658 -354.759369) (xy 93.698898 -354.813344) (xy 93.683535 -354.865667) (xy 93.660883 -354.915272)
			(xy 93.631402 -354.961149) (xy 93.595693 -355.002364) (xy 93.554483 -355.038077) (xy 93.508609 -355.067563)
			(xy 93.459007 -355.09022) (xy 93.406685 -355.105589) (xy 93.352708 -355.113355) (xy 93.325442 -355.113844)
			(xy 92.461842 -355.113844) (xy 92.434568 -355.113419) (xy 92.380574 -355.105662) (xy 92.328234 -355.090298)
			(xy 92.278613 -355.067642) (xy 92.232722 -355.038154) (xy 92.191495 -355.002435) (xy 92.155771 -354.961212)
			(xy 92.126278 -354.915324) (xy 92.103616 -354.865706) (xy 92.088247 -354.813367) (xy 92.080484 -354.759374)
			(xy 90.597781 -354.759374) (xy 90.590018 -354.813356) (xy 90.574652 -354.865688) (xy 90.551994 -354.9153)
			(xy 90.522506 -354.961182) (xy 90.486788 -355.002401) (xy 90.445568 -355.038117) (xy 90.399684 -355.067603)
			(xy 90.350071 -355.090258) (xy 90.297739 -355.105622) (xy 90.243753 -355.113382) (xy 90.216482 -355.113844)
			(xy 89.352882 -355.113844) (xy 89.325612 -355.113392) (xy 89.271628 -355.105628) (xy 89.219298 -355.090261)
			(xy 89.169688 -355.067602) (xy 89.123807 -355.038115) (xy 89.08259 -355.002398) (xy 89.046875 -354.961178)
			(xy 89.017389 -354.915296) (xy 88.994733 -354.865685) (xy 88.979368 -354.813354) (xy 88.971606 -354.75937)
			(xy 87.488758 -354.75937) (xy 87.480997 -354.813346) (xy 87.465633 -354.865672) (xy 87.44298 -354.915278)
			(xy 87.413497 -354.961156) (xy 87.377786 -355.002371) (xy 87.336573 -355.038084) (xy 87.290697 -355.067569)
			(xy 87.241092 -355.090226) (xy 87.188768 -355.105592) (xy 87.134789 -355.113356) (xy 87.107522 -355.113844)
			(xy 86.243922 -355.113844) (xy 86.216649 -355.113418) (xy 86.162657 -355.105658) (xy 86.110319 -355.090293)
			(xy 86.060701 -355.067636) (xy 86.014812 -355.038147) (xy 85.973588 -355.002428) (xy 85.937866 -354.961205)
			(xy 85.908375 -354.915318) (xy 85.885715 -354.865702) (xy 85.870347 -354.813365) (xy 85.862584 -354.759373)
			(xy 84.37988 -354.759373) (xy 84.372118 -354.813359) (xy 84.35675 -354.865692) (xy 84.334091 -354.915306)
			(xy 84.304601 -354.961189) (xy 84.268881 -355.002408) (xy 84.227659 -355.038124) (xy 84.181772 -355.067609)
			(xy 84.132157 -355.090264) (xy 84.079822 -355.105626) (xy 84.025833 -355.113383) (xy 83.998562 -355.113844)
			(xy 83.134962 -355.113844) (xy 83.107693 -355.113391) (xy 83.053711 -355.105625) (xy 83.001384 -355.090255)
			(xy 82.951776 -355.067596) (xy 82.905898 -355.038107) (xy 82.864683 -355.00239) (xy 82.82897 -354.961172)
			(xy 82.799486 -354.915291) (xy 82.776832 -354.865681) (xy 82.761467 -354.813352) (xy 82.753706 -354.759369)
			(xy 81.270858 -354.759369) (xy 81.263096 -354.813349) (xy 81.247732 -354.865676) (xy 81.225077 -354.915283)
			(xy 81.195593 -354.961162) (xy 81.159879 -355.002378) (xy 81.118664 -355.038091) (xy 81.072785 -355.067576)
			(xy 81.023178 -355.090231) (xy 80.970851 -355.105596) (xy 80.91687 -355.113357) (xy 80.889602 -355.113844)
			(xy 80.026002 -355.113844) (xy 79.99873 -355.113417) (xy 79.94474 -355.105654) (xy 79.892405 -355.090288)
			(xy 79.842789 -355.067629) (xy 79.796903 -355.03814) (xy 79.755681 -355.002421) (xy 79.719961 -354.961199)
			(xy 79.690472 -354.915313) (xy 79.667813 -354.865697) (xy 79.652446 -354.813362) (xy 79.644684 -354.759372)
			(xy 78.161857 -354.759372) (xy 78.154098 -354.813344) (xy 78.138735 -354.865667) (xy 78.116083 -354.915272)
			(xy 78.086602 -354.961149) (xy 78.050893 -355.002364) (xy 78.009683 -355.038077) (xy 77.963809 -355.067563)
			(xy 77.914207 -355.09022) (xy 77.861885 -355.105589) (xy 77.807908 -355.113355) (xy 77.780642 -355.113844)
			(xy 76.917042 -355.113844) (xy 76.889768 -355.113419) (xy 76.835774 -355.105662) (xy 76.783434 -355.090298)
			(xy 76.733813 -355.067642) (xy 76.687922 -355.038154) (xy 76.646695 -355.002435) (xy 76.610971 -354.961212)
			(xy 76.581478 -354.915324) (xy 76.558816 -354.865706) (xy 76.543447 -354.813367) (xy 76.535684 -354.759374)
			(xy 75.052981 -354.759374) (xy 75.045218 -354.813356) (xy 75.029852 -354.865688) (xy 75.007194 -354.9153)
			(xy 74.977706 -354.961182) (xy 74.941988 -355.002401) (xy 74.900768 -355.038117) (xy 74.854884 -355.067603)
			(xy 74.805271 -355.090258) (xy 74.752939 -355.105622) (xy 74.698953 -355.113382) (xy 74.671682 -355.113844)
			(xy 73.808082 -355.113844) (xy 73.780812 -355.113392) (xy 73.726828 -355.105628) (xy 73.674498 -355.090261)
			(xy 73.624888 -355.067602) (xy 73.579007 -355.038115) (xy 73.53779 -355.002398) (xy 73.502075 -354.961178)
			(xy 73.472589 -354.915296) (xy 73.449933 -354.865685) (xy 73.434568 -354.813354) (xy 73.426806 -354.75937)
			(xy 71.943958 -354.75937) (xy 71.936197 -354.813346) (xy 71.920833 -354.865672) (xy 71.89818 -354.915278)
			(xy 71.868697 -354.961156) (xy 71.832986 -355.002371) (xy 71.791773 -355.038084) (xy 71.745897 -355.067569)
			(xy 71.696292 -355.090226) (xy 71.643968 -355.105592) (xy 71.589989 -355.113356) (xy 71.562722 -355.113844)
			(xy 70.699122 -355.113844) (xy 70.671849 -355.113418) (xy 70.617857 -355.105658) (xy 70.565519 -355.090293)
			(xy 70.515901 -355.067636) (xy 70.470012 -355.038147) (xy 70.428788 -355.002428) (xy 70.393066 -354.961205)
			(xy 70.363575 -354.915318) (xy 70.340915 -354.865702) (xy 70.325547 -354.813365) (xy 70.317784 -354.759373)
			(xy 68.83508 -354.759373) (xy 68.827318 -354.813359) (xy 68.81195 -354.865692) (xy 68.789291 -354.915306)
			(xy 68.759801 -354.961189) (xy 68.724081 -355.002408) (xy 68.682859 -355.038124) (xy 68.636972 -355.067609)
			(xy 68.587357 -355.090264) (xy 68.535022 -355.105626) (xy 68.481033 -355.113383) (xy 68.453762 -355.113844)
			(xy 67.590162 -355.113844) (xy 67.562893 -355.113391) (xy 67.508911 -355.105625) (xy 67.456584 -355.090255)
			(xy 67.406976 -355.067596) (xy 67.361098 -355.038107) (xy 67.319883 -355.00239) (xy 67.28417 -354.961172)
			(xy 67.254686 -354.915291) (xy 67.232032 -354.865681) (xy 67.216667 -354.813352) (xy 67.208906 -354.759369)
			(xy 65.726058 -354.759369) (xy 65.718296 -354.813349) (xy 65.702932 -354.865676) (xy 65.680277 -354.915283)
			(xy 65.650793 -354.961162) (xy 65.615079 -355.002378) (xy 65.573864 -355.038091) (xy 65.527985 -355.067576)
			(xy 65.478378 -355.090231) (xy 65.426051 -355.105596) (xy 65.37207 -355.113357) (xy 65.344802 -355.113844)
			(xy 64.481202 -355.113844) (xy 64.45393 -355.113417) (xy 64.39994 -355.105654) (xy 64.347605 -355.090288)
			(xy 64.297989 -355.067629) (xy 64.252103 -355.03814) (xy 64.210881 -355.002421) (xy 64.175161 -354.961199)
			(xy 64.145672 -354.915313) (xy 64.123013 -354.865697) (xy 64.107646 -354.813362) (xy 64.099884 -354.759372)
			(xy 51.666857 -354.759372) (xy 51.659098 -354.813343) (xy 51.643736 -354.865666) (xy 51.621084 -354.915271)
			(xy 51.591604 -354.961147) (xy 51.555895 -355.002361) (xy 51.514686 -355.038075) (xy 51.468813 -355.067561)
			(xy 51.419211 -355.090219) (xy 51.36689 -355.105587) (xy 51.312914 -355.113354) (xy 51.285648 -355.113844)
			(xy 50.422048 -355.113844) (xy 50.394773 -355.11342) (xy 50.340779 -355.105663) (xy 50.288438 -355.0903)
			(xy 50.238816 -355.067644) (xy 50.192925 -355.038156) (xy 50.151697 -355.002437) (xy 50.115972 -354.961214)
			(xy 50.086479 -354.915326) (xy 50.063817 -354.865707) (xy 50.048447 -354.813368) (xy 50.040684 -354.759374)
			(xy 48.55798 -354.759374) (xy 48.550218 -354.813356) (xy 48.534852 -354.865687) (xy 48.512195 -354.915298)
			(xy 48.482708 -354.961181) (xy 48.446991 -355.002399) (xy 48.405771 -355.038115) (xy 48.359888 -355.067601)
			(xy 48.310276 -355.090256) (xy 48.257944 -355.105621) (xy 48.203958 -355.113381) (xy 48.176688 -355.113844)
			(xy 47.313088 -355.113844) (xy 47.285818 -355.113393) (xy 47.231833 -355.105629) (xy 47.179503 -355.090262)
			(xy 47.129891 -355.067604) (xy 47.08401 -355.038117) (xy 47.042792 -355.0024) (xy 47.007076 -354.96118)
			(xy 46.97759 -354.915298) (xy 46.954934 -354.865686) (xy 46.939568 -354.813355) (xy 46.931806 -354.75937)
			(xy 45.448958 -354.75937) (xy 45.441197 -354.813345) (xy 45.425834 -354.86567) (xy 45.403181 -354.915276)
			(xy 45.373699 -354.961154) (xy 45.337988 -355.002369) (xy 45.296776 -355.038082) (xy 45.250901 -355.067567)
			(xy 45.201297 -355.090224) (xy 45.148973 -355.105591) (xy 45.094995 -355.113356) (xy 45.067728 -355.113844)
			(xy 44.204128 -355.113844) (xy 44.176854 -355.113418) (xy 44.122862 -355.105659) (xy 44.070523 -355.090295)
			(xy 44.020904 -355.067638) (xy 43.975015 -355.038149) (xy 43.93379 -355.00243) (xy 43.898068 -354.961207)
			(xy 43.868576 -354.91532) (xy 43.845915 -354.865703) (xy 43.830547 -354.813365) (xy 43.822784 -354.759374)
			(xy 42.34008 -354.759374) (xy 42.332318 -354.813358) (xy 42.316951 -354.865691) (xy 42.294292 -354.915304)
			(xy 42.264803 -354.961187) (xy 42.229083 -355.002406) (xy 42.187861 -355.038122) (xy 42.141976 -355.067607)
			(xy 42.092361 -355.090262) (xy 42.040027 -355.105625) (xy 41.986039 -355.113383) (xy 41.958768 -355.113844)
			(xy 41.095168 -355.113844) (xy 41.067899 -355.113391) (xy 41.013916 -355.105626) (xy 40.961588 -355.090257)
			(xy 40.91198 -355.067598) (xy 40.8661 -355.03811) (xy 40.824885 -355.002393) (xy 40.789171 -354.961174)
			(xy 40.759687 -354.915292) (xy 40.737032 -354.865682) (xy 40.721668 -354.813353) (xy 40.713906 -354.759369)
			(xy 39.231058 -354.759369) (xy 39.223297 -354.813348) (xy 39.207932 -354.865675) (xy 39.185278 -354.915282)
			(xy 39.155794 -354.96116) (xy 39.120081 -355.002376) (xy 39.078867 -355.038089) (xy 39.032989 -355.067574)
			(xy 38.983382 -355.09023) (xy 38.931056 -355.105595) (xy 38.877076 -355.113357) (xy 38.849808 -355.113844)
			(xy 37.986208 -355.113844) (xy 37.958935 -355.113417) (xy 37.904945 -355.105655) (xy 37.852609 -355.090289)
			(xy 37.802992 -355.067631) (xy 37.757106 -355.038142) (xy 37.715883 -355.002423) (xy 37.680163 -354.961201)
			(xy 37.650673 -354.915315) (xy 37.628014 -354.865699) (xy 37.612646 -354.813363) (xy 37.604884 -354.759373)
			(xy 36.122057 -354.759373) (xy 36.114298 -354.813343) (xy 36.098936 -354.865666) (xy 36.076284 -354.915271)
			(xy 36.046804 -354.961147) (xy 36.011095 -355.002361) (xy 35.969886 -355.038075) (xy 35.924013 -355.067561)
			(xy 35.874411 -355.090219) (xy 35.82209 -355.105587) (xy 35.768114 -355.113354) (xy 35.740848 -355.113844)
			(xy 34.877248 -355.113844) (xy 34.849973 -355.11342) (xy 34.795979 -355.105663) (xy 34.743638 -355.0903)
			(xy 34.694016 -355.067644) (xy 34.648125 -355.038156) (xy 34.606897 -355.002437) (xy 34.571172 -354.961214)
			(xy 34.541679 -354.915326) (xy 34.519017 -354.865707) (xy 34.503647 -354.813368) (xy 34.495884 -354.759374)
			(xy 33.01318 -354.759374) (xy 33.005418 -354.813356) (xy 32.990052 -354.865687) (xy 32.967395 -354.915298)
			(xy 32.937908 -354.961181) (xy 32.902191 -355.002399) (xy 32.860971 -355.038115) (xy 32.815088 -355.067601)
			(xy 32.765476 -355.090256) (xy 32.713144 -355.105621) (xy 32.659158 -355.113381) (xy 32.631888 -355.113844)
			(xy 31.768288 -355.113844) (xy 31.741018 -355.113393) (xy 31.687033 -355.105629) (xy 31.634703 -355.090262)
			(xy 31.585091 -355.067604) (xy 31.53921 -355.038117) (xy 31.497992 -355.0024) (xy 31.462276 -354.96118)
			(xy 31.43279 -354.915298) (xy 31.410134 -354.865686) (xy 31.394768 -354.813355) (xy 31.387006 -354.75937)
			(xy 29.904158 -354.75937) (xy 29.896397 -354.813345) (xy 29.881034 -354.86567) (xy 29.858381 -354.915276)
			(xy 29.828899 -354.961154) (xy 29.793188 -355.002369) (xy 29.751976 -355.038082) (xy 29.706101 -355.067567)
			(xy 29.656497 -355.090224) (xy 29.604173 -355.105591) (xy 29.550195 -355.113356) (xy 29.522928 -355.113844)
			(xy 28.659328 -355.113844) (xy 28.632054 -355.113418) (xy 28.578062 -355.105659) (xy 28.525723 -355.090295)
			(xy 28.476104 -355.067638) (xy 28.430215 -355.038149) (xy 28.38899 -355.00243) (xy 28.353268 -354.961207)
			(xy 28.323776 -354.91532) (xy 28.301115 -354.865703) (xy 28.285747 -354.813365) (xy 28.277984 -354.759374)
			(xy 26.79528 -354.759374) (xy 26.787518 -354.813358) (xy 26.772151 -354.865691) (xy 26.749492 -354.915304)
			(xy 26.720003 -354.961187) (xy 26.684283 -355.002406) (xy 26.643061 -355.038122) (xy 26.597176 -355.067607)
			(xy 26.547561 -355.090262) (xy 26.495227 -355.105625) (xy 26.441239 -355.113383) (xy 26.413968 -355.113844)
			(xy 25.550368 -355.113844) (xy 25.523099 -355.113391) (xy 25.469116 -355.105626) (xy 25.416788 -355.090257)
			(xy 25.36718 -355.067598) (xy 25.3213 -355.03811) (xy 25.280085 -355.002393) (xy 25.244371 -354.961174)
			(xy 25.214887 -354.915292) (xy 25.192232 -354.865682) (xy 25.176868 -354.813353) (xy 25.169106 -354.759369)
			(xy 23.686258 -354.759369) (xy 23.678497 -354.813348) (xy 23.663132 -354.865675) (xy 23.640478 -354.915282)
			(xy 23.610994 -354.96116) (xy 23.575281 -355.002376) (xy 23.534067 -355.038089) (xy 23.488189 -355.067574)
			(xy 23.438582 -355.09023) (xy 23.386256 -355.105595) (xy 23.332276 -355.113357) (xy 23.305008 -355.113844)
			(xy 22.441408 -355.113844) (xy 22.414135 -355.113417) (xy 22.360145 -355.105655) (xy 22.307809 -355.090289)
			(xy 22.258192 -355.067631) (xy 22.212306 -355.038142) (xy 22.171083 -355.002423) (xy 22.135363 -354.961201)
			(xy 22.105873 -354.915315) (xy 22.083214 -354.865699) (xy 22.067846 -354.813363) (xy 22.060084 -354.759373)
			(xy 0.508 -354.759373) (xy 0.508 -357.784969) (xy 22.060131 -357.784969) (xy 22.060131 -357.730431)
			(xy 22.067893 -357.676447) (xy 22.083259 -357.624118) (xy 22.105915 -357.574508) (xy 22.135401 -357.528628)
			(xy 22.171117 -357.487411) (xy 22.212334 -357.451696) (xy 22.258215 -357.422211) (xy 22.307826 -357.399556)
			(xy 22.360155 -357.384191) (xy 22.414139 -357.376431) (xy 22.441408 -357.375968) (xy 23.305008 -357.375968)
			(xy 23.332279 -357.376395) (xy 23.386266 -357.384158) (xy 23.438599 -357.399525) (xy 23.488212 -357.422184)
			(xy 23.534095 -357.451672) (xy 23.575315 -357.48739) (xy 23.611032 -357.528611) (xy 23.64052 -357.574495)
			(xy 23.663177 -357.624109) (xy 23.678543 -357.676442) (xy 23.686306 -357.730429) (xy 23.686306 -357.784966)
			(xy 25.169154 -357.784966) (xy 25.169154 -357.730434) (xy 25.176914 -357.676458) (xy 25.192277 -357.624135)
			(xy 25.214929 -357.574531) (xy 25.24441 -357.528655) (xy 25.280119 -357.487441) (xy 25.321329 -357.451729)
			(xy 25.367203 -357.422244) (xy 25.416805 -357.399588) (xy 25.469126 -357.384221) (xy 25.523102 -357.376457)
			(xy 25.550368 -357.375968) (xy 26.413968 -357.375968) (xy 26.441243 -357.376369) (xy 26.495237 -357.384128)
			(xy 26.547578 -357.399493) (xy 26.597199 -357.422151) (xy 26.64309 -357.45164) (xy 26.684317 -357.48736)
			(xy 26.720041 -357.528584) (xy 26.749534 -357.574473) (xy 26.772196 -357.624092) (xy 26.787565 -357.676431)
			(xy 26.795328 -357.730425) (xy 26.795328 -357.78497) (xy 28.278031 -357.78497) (xy 28.278032 -357.73043)
			(xy 28.285794 -357.676445) (xy 28.30116 -357.624114) (xy 28.323818 -357.574503) (xy 28.353306 -357.528621)
			(xy 28.389024 -357.487404) (xy 28.430244 -357.451689) (xy 28.476127 -357.422205) (xy 28.52574 -357.39955)
			(xy 28.578072 -357.384188) (xy 28.632058 -357.37643) (xy 28.659328 -357.375968) (xy 29.522928 -357.375968)
			(xy 29.550198 -357.376396) (xy 29.604183 -357.384162) (xy 29.656513 -357.399531) (xy 29.706124 -357.42219)
			(xy 29.752005 -357.451679) (xy 29.793222 -357.487397) (xy 29.828937 -357.528618) (xy 29.858423 -357.574501)
			(xy 29.881079 -357.624113) (xy 29.896444 -357.676444) (xy 29.904206 -357.73043) (xy 29.904206 -357.784967)
			(xy 31.387054 -357.784967) (xy 31.387054 -357.730433) (xy 31.394815 -357.676455) (xy 31.410179 -357.624131)
			(xy 31.432832 -357.574525) (xy 31.462315 -357.528648) (xy 31.498026 -357.487434) (xy 31.539239 -357.451722)
			(xy 31.585115 -357.422238) (xy 31.634719 -357.399583) (xy 31.687043 -357.384218) (xy 31.741021 -357.376455)
			(xy 31.768288 -357.375968) (xy 32.631888 -357.375968) (xy 32.659162 -357.376371) (xy 32.713154 -357.384132)
			(xy 32.765492 -357.399499) (xy 32.815111 -357.422157) (xy 32.861 -357.451647) (xy 32.902224 -357.487367)
			(xy 32.937946 -357.528591) (xy 32.967437 -357.574479) (xy 32.990097 -357.624096) (xy 33.005465 -357.676434)
			(xy 33.013228 -357.730426) (xy 33.013228 -357.784971) (xy 34.495932 -357.784971) (xy 34.495932 -357.730429)
			(xy 34.503694 -357.676442) (xy 34.519062 -357.62411) (xy 34.541721 -357.574497) (xy 34.571211 -357.528615)
			(xy 34.606931 -357.487397) (xy 34.648153 -357.451682) (xy 34.694039 -357.422198) (xy 34.743655 -357.399545)
			(xy 34.795989 -357.384184) (xy 34.849977 -357.376428) (xy 34.877248 -357.375968) (xy 35.740848 -357.375968)
			(xy 35.768117 -357.376398) (xy 35.8221 -357.384166) (xy 35.874428 -357.399536) (xy 35.924036 -357.422197)
			(xy 35.969914 -357.451687) (xy 36.011129 -357.487405) (xy 36.046842 -357.528624) (xy 36.076326 -357.574506)
			(xy 36.09898 -357.624117) (xy 36.114345 -357.676447) (xy 36.122106 -357.730431) (xy 36.122106 -357.784969)
			(xy 37.604931 -357.784969) (xy 37.604931 -357.730431) (xy 37.612693 -357.676447) (xy 37.628059 -357.624118)
			(xy 37.650715 -357.574508) (xy 37.680201 -357.528628) (xy 37.715917 -357.487411) (xy 37.757134 -357.451696)
			(xy 37.803015 -357.422211) (xy 37.852626 -357.399556) (xy 37.904955 -357.384191) (xy 37.958939 -357.376431)
			(xy 37.986208 -357.375968) (xy 38.849808 -357.375968) (xy 38.877079 -357.376395) (xy 38.931066 -357.384158)
			(xy 38.983399 -357.399525) (xy 39.033012 -357.422184) (xy 39.078895 -357.451672) (xy 39.120115 -357.48739)
			(xy 39.155832 -357.528611) (xy 39.18532 -357.574495) (xy 39.207977 -357.624109) (xy 39.223343 -357.676442)
			(xy 39.231106 -357.730429) (xy 39.231106 -357.784966) (xy 40.713954 -357.784966) (xy 40.713954 -357.730434)
			(xy 40.721714 -357.676458) (xy 40.737077 -357.624135) (xy 40.759729 -357.574531) (xy 40.78921 -357.528655)
			(xy 40.824919 -357.487441) (xy 40.866129 -357.451729) (xy 40.912003 -357.422244) (xy 40.961605 -357.399588)
			(xy 41.013926 -357.384221) (xy 41.067902 -357.376457) (xy 41.095168 -357.375968) (xy 41.958768 -357.375968)
			(xy 41.986043 -357.376369) (xy 42.040037 -357.384128) (xy 42.092378 -357.399493) (xy 42.141999 -357.422151)
			(xy 42.18789 -357.45164) (xy 42.229117 -357.48736) (xy 42.264841 -357.528584) (xy 42.294334 -357.574473)
			(xy 42.316996 -357.624092) (xy 42.332365 -357.676431) (xy 42.340128 -357.730425) (xy 42.340128 -357.78497)
			(xy 43.822831 -357.78497) (xy 43.822832 -357.73043) (xy 43.830594 -357.676445) (xy 43.84596 -357.624114)
			(xy 43.868618 -357.574503) (xy 43.898106 -357.528621) (xy 43.933824 -357.487404) (xy 43.975044 -357.451689)
			(xy 44.020927 -357.422205) (xy 44.07054 -357.39955) (xy 44.122872 -357.384188) (xy 44.176858 -357.37643)
			(xy 44.204128 -357.375968) (xy 45.067728 -357.375968) (xy 45.094998 -357.376396) (xy 45.148983 -357.384162)
			(xy 45.201313 -357.399531) (xy 45.250924 -357.42219) (xy 45.296805 -357.451679) (xy 45.338022 -357.487397)
			(xy 45.373737 -357.528618) (xy 45.403223 -357.574501) (xy 45.425879 -357.624113) (xy 45.441244 -357.676444)
			(xy 45.449006 -357.73043) (xy 45.449006 -357.784967) (xy 46.931854 -357.784967) (xy 46.931854 -357.730433)
			(xy 46.939615 -357.676455) (xy 46.954979 -357.624131) (xy 46.977632 -357.574525) (xy 47.007115 -357.528648)
			(xy 47.042826 -357.487434) (xy 47.084039 -357.451722) (xy 47.129915 -357.422238) (xy 47.179519 -357.399583)
			(xy 47.231843 -357.384218) (xy 47.285821 -357.376455) (xy 47.313088 -357.375968) (xy 48.176688 -357.375968)
			(xy 48.203962 -357.376371) (xy 48.257954 -357.384132) (xy 48.310292 -357.399499) (xy 48.359911 -357.422157)
			(xy 48.4058 -357.451647) (xy 48.447024 -357.487367) (xy 48.482746 -357.528591) (xy 48.512237 -357.574479)
			(xy 48.534897 -357.624096) (xy 48.550265 -357.676434) (xy 48.558028 -357.730426) (xy 48.558028 -357.784971)
			(xy 50.040732 -357.784971) (xy 50.040732 -357.730429) (xy 50.048494 -357.676442) (xy 50.063862 -357.62411)
			(xy 50.086521 -357.574497) (xy 50.116011 -357.528615) (xy 50.151731 -357.487397) (xy 50.192953 -357.451682)
			(xy 50.238839 -357.422198) (xy 50.288455 -357.399545) (xy 50.340789 -357.384184) (xy 50.394777 -357.376428)
			(xy 50.422048 -357.375968) (xy 51.285648 -357.375968) (xy 51.312917 -357.376398) (xy 51.3669 -357.384166)
			(xy 51.419228 -357.399536) (xy 51.468836 -357.422197) (xy 51.514714 -357.451687) (xy 51.555929 -357.487405)
			(xy 51.591642 -357.528624) (xy 51.621126 -357.574506) (xy 51.64378 -357.624117) (xy 51.659145 -357.676447)
			(xy 51.666906 -357.730431) (xy 51.666906 -357.784969) (xy 64.099931 -357.784969) (xy 64.099931 -357.730431)
			(xy 64.107693 -357.676448) (xy 64.123058 -357.62412) (xy 64.145714 -357.57451) (xy 64.1752 -357.52863)
			(xy 64.210914 -357.487413) (xy 64.252132 -357.451698) (xy 64.298012 -357.422213) (xy 64.347621 -357.399557)
			(xy 64.39995 -357.384193) (xy 64.453933 -357.376431) (xy 64.481202 -357.375968) (xy 65.344802 -357.375968)
			(xy 65.372073 -357.376395) (xy 65.426061 -357.384157) (xy 65.478394 -357.399524) (xy 65.528008 -357.422182)
			(xy 65.573893 -357.45167) (xy 65.615113 -357.487388) (xy 65.650831 -357.528609) (xy 65.680319 -357.574493)
			(xy 65.702977 -357.624107) (xy 65.718343 -357.676441) (xy 65.726106 -357.730429) (xy 65.726106 -357.784966)
			(xy 67.208954 -357.784966) (xy 67.208954 -357.730435) (xy 67.216714 -357.676458) (xy 67.232077 -357.624136)
			(xy 67.254728 -357.574532) (xy 67.284208 -357.528657) (xy 67.319917 -357.487443) (xy 67.361126 -357.451731)
			(xy 67.406999 -357.422246) (xy 67.4566 -357.39959) (xy 67.508921 -357.384222) (xy 67.562897 -357.376457)
			(xy 67.590162 -357.375968) (xy 68.453762 -357.375968) (xy 68.481037 -357.376369) (xy 68.535032 -357.384127)
			(xy 68.587373 -357.399491) (xy 68.636995 -357.422149) (xy 68.682887 -357.451638) (xy 68.724115 -357.487358)
			(xy 68.75984 -357.528582) (xy 68.789333 -357.574471) (xy 68.811995 -357.624091) (xy 68.827365 -357.676431)
			(xy 68.835128 -357.730425) (xy 68.835128 -357.78497) (xy 70.317831 -357.78497) (xy 70.317831 -357.73043)
			(xy 70.325594 -357.676446) (xy 70.34096 -357.624115) (xy 70.363617 -357.574505) (xy 70.393105 -357.528623)
			(xy 70.428822 -357.487406) (xy 70.470041 -357.451691) (xy 70.515924 -357.422207) (xy 70.565536 -357.399552)
			(xy 70.617867 -357.384189) (xy 70.671852 -357.37643) (xy 70.699122 -357.375968) (xy 71.562722 -357.375968)
			(xy 71.589992 -357.376396) (xy 71.643978 -357.384161) (xy 71.696309 -357.399529) (xy 71.74592 -357.422189)
			(xy 71.791802 -357.451677) (xy 71.83302 -357.487395) (xy 71.868736 -357.528616) (xy 71.898222 -357.574499)
			(xy 71.920878 -357.624112) (xy 71.936244 -357.676444) (xy 71.944006 -357.730429) (xy 71.944006 -357.784966)
			(xy 73.426854 -357.784966) (xy 73.426854 -357.730434) (xy 73.434615 -357.676456) (xy 73.449978 -357.624132)
			(xy 73.472631 -357.574527) (xy 73.502113 -357.52865) (xy 73.537824 -357.487436) (xy 73.579036 -357.451724)
			(xy 73.624911 -357.42224) (xy 73.674515 -357.399584) (xy 73.726838 -357.384219) (xy 73.780816 -357.376456)
			(xy 73.808082 -357.375968) (xy 74.671682 -357.375968) (xy 74.698956 -357.37637) (xy 74.752949 -357.384131)
			(xy 74.805288 -357.399497) (xy 74.854907 -357.422155) (xy 74.900797 -357.451645) (xy 74.942022 -357.487365)
			(xy 74.977744 -357.528589) (xy 75.007236 -357.574477) (xy 75.029897 -357.624095) (xy 75.045265 -357.676433)
			(xy 75.053028 -357.730426) (xy 75.053028 -357.784971) (xy 76.535732 -357.784971) (xy 76.535732 -357.730429)
			(xy 76.543494 -357.676443) (xy 76.558861 -357.624111) (xy 76.58152 -357.574499) (xy 76.611009 -357.528617)
			(xy 76.646729 -357.487399) (xy 76.687951 -357.451684) (xy 76.733836 -357.4222) (xy 76.78345 -357.399547)
			(xy 76.835784 -357.384185) (xy 76.889771 -357.376429) (xy 76.917042 -357.375968) (xy 77.780642 -357.375968)
			(xy 77.807912 -357.376397) (xy 77.861895 -357.384165) (xy 77.914223 -357.399535) (xy 77.963832 -357.422195)
			(xy 78.009711 -357.451684) (xy 78.050927 -357.487402) (xy 78.086641 -357.528622) (xy 78.116125 -357.574505)
			(xy 78.13878 -357.624116) (xy 78.154144 -357.676446) (xy 78.161906 -357.73043) (xy 78.161906 -357.784969)
			(xy 79.644731 -357.784969) (xy 79.644731 -357.730431) (xy 79.652493 -357.676448) (xy 79.667858 -357.62412)
			(xy 79.690514 -357.57451) (xy 79.72 -357.52863) (xy 79.755714 -357.487413) (xy 79.796932 -357.451698)
			(xy 79.842812 -357.422213) (xy 79.892421 -357.399557) (xy 79.94475 -357.384193) (xy 79.998733 -357.376431)
			(xy 80.026002 -357.375968) (xy 80.889602 -357.375968) (xy 80.916873 -357.376395) (xy 80.970861 -357.384157)
			(xy 81.023194 -357.399524) (xy 81.072808 -357.422182) (xy 81.118693 -357.45167) (xy 81.159913 -357.487388)
			(xy 81.195631 -357.528609) (xy 81.225119 -357.574493) (xy 81.247777 -357.624107) (xy 81.263143 -357.676441)
			(xy 81.270906 -357.730429) (xy 81.270906 -357.784966) (xy 82.753754 -357.784966) (xy 82.753754 -357.730435)
			(xy 82.761514 -357.676458) (xy 82.776877 -357.624136) (xy 82.799528 -357.574532) (xy 82.829008 -357.528657)
			(xy 82.864717 -357.487443) (xy 82.905926 -357.451731) (xy 82.951799 -357.422246) (xy 83.0014 -357.39959)
			(xy 83.053721 -357.384222) (xy 83.107697 -357.376457) (xy 83.134962 -357.375968) (xy 83.998562 -357.375968)
			(xy 84.025837 -357.376369) (xy 84.079832 -357.384127) (xy 84.132173 -357.399491) (xy 84.181795 -357.422149)
			(xy 84.227687 -357.451638) (xy 84.268915 -357.487358) (xy 84.30464 -357.528582) (xy 84.334133 -357.574471)
			(xy 84.356795 -357.624091) (xy 84.372165 -357.676431) (xy 84.379928 -357.730425) (xy 84.379928 -357.78497)
			(xy 85.862631 -357.78497) (xy 85.862631 -357.73043) (xy 85.870394 -357.676446) (xy 85.88576 -357.624115)
			(xy 85.908417 -357.574505) (xy 85.937905 -357.528623) (xy 85.973622 -357.487406) (xy 86.014841 -357.451691)
			(xy 86.060724 -357.422207) (xy 86.110336 -357.399552) (xy 86.162667 -357.384189) (xy 86.216652 -357.37643)
			(xy 86.243922 -357.375968) (xy 87.107522 -357.375968) (xy 87.134792 -357.376396) (xy 87.188778 -357.384161)
			(xy 87.241109 -357.399529) (xy 87.29072 -357.422189) (xy 87.336602 -357.451677) (xy 87.37782 -357.487395)
			(xy 87.413536 -357.528616) (xy 87.443022 -357.574499) (xy 87.465678 -357.624112) (xy 87.481044 -357.676444)
			(xy 87.488806 -357.730429) (xy 87.488806 -357.784966) (xy 88.971654 -357.784966) (xy 88.971654 -357.730434)
			(xy 88.979415 -357.676456) (xy 88.994778 -357.624132) (xy 89.017431 -357.574527) (xy 89.046913 -357.52865)
			(xy 89.082624 -357.487436) (xy 89.123836 -357.451724) (xy 89.169711 -357.42224) (xy 89.219315 -357.399584)
			(xy 89.271638 -357.384219) (xy 89.325616 -357.376456) (xy 89.352882 -357.375968) (xy 90.216482 -357.375968)
			(xy 90.243756 -357.37637) (xy 90.297749 -357.384131) (xy 90.350088 -357.399497) (xy 90.399707 -357.422155)
			(xy 90.445597 -357.451645) (xy 90.486822 -357.487365) (xy 90.522544 -357.528589) (xy 90.552036 -357.574477)
			(xy 90.574697 -357.624095) (xy 90.590065 -357.676433) (xy 90.597828 -357.730426) (xy 90.597828 -357.784971)
			(xy 92.080532 -357.784971) (xy 92.080532 -357.730429) (xy 92.088294 -357.676443) (xy 92.103661 -357.624111)
			(xy 92.12632 -357.574499) (xy 92.155809 -357.528617) (xy 92.191529 -357.487399) (xy 92.232751 -357.451684)
			(xy 92.278636 -357.4222) (xy 92.32825 -357.399547) (xy 92.380584 -357.384185) (xy 92.434571 -357.376429)
			(xy 92.461842 -357.375968) (xy 93.325442 -357.375968) (xy 93.352712 -357.376397) (xy 93.406695 -357.384165)
			(xy 93.459023 -357.399535) (xy 93.508632 -357.422195) (xy 93.554511 -357.451684) (xy 93.595727 -357.487402)
			(xy 93.631441 -357.528622) (xy 93.660925 -357.574505) (xy 93.68358 -357.624116) (xy 93.698944 -357.676446)
			(xy 93.706706 -357.73043) (xy 93.706706 -357.784966) (xy 114.589854 -357.784966) (xy 114.589854 -357.730434)
			(xy 114.597614 -357.676458) (xy 114.612977 -357.624135) (xy 114.635629 -357.574531) (xy 114.66511 -357.528655)
			(xy 114.700819 -357.487441) (xy 114.742029 -357.451729) (xy 114.787903 -357.422244) (xy 114.837505 -357.399588)
			(xy 114.889826 -357.384221) (xy 114.943802 -357.376457) (xy 114.971068 -357.375968) (xy 115.834668 -357.375968)
			(xy 115.861943 -357.376369) (xy 115.915937 -357.384128) (xy 115.968278 -357.399493) (xy 116.017899 -357.422151)
			(xy 116.06379 -357.45164) (xy 116.105017 -357.48736) (xy 116.140741 -357.528584) (xy 116.170234 -357.574473)
			(xy 116.192896 -357.624092) (xy 116.208265 -357.676431) (xy 116.216028 -357.730425) (xy 116.216028 -357.78497)
			(xy 117.698731 -357.78497) (xy 117.698732 -357.73043) (xy 117.706494 -357.676445) (xy 117.72186 -357.624114)
			(xy 117.744518 -357.574503) (xy 117.774006 -357.528621) (xy 117.809724 -357.487404) (xy 117.850944 -357.451689)
			(xy 117.896827 -357.422205) (xy 117.94644 -357.39955) (xy 117.998772 -357.384188) (xy 118.052758 -357.37643)
			(xy 118.080028 -357.375968) (xy 118.943628 -357.375968) (xy 118.970898 -357.376396) (xy 119.024883 -357.384162)
			(xy 119.077213 -357.399531) (xy 119.126824 -357.42219) (xy 119.172705 -357.451679) (xy 119.213922 -357.487397)
			(xy 119.249637 -357.528618) (xy 119.279123 -357.574501) (xy 119.301779 -357.624113) (xy 119.317144 -357.676444)
			(xy 119.324906 -357.73043) (xy 119.324906 -357.784967) (xy 120.807754 -357.784967) (xy 120.807754 -357.730433)
			(xy 120.815515 -357.676455) (xy 120.830879 -357.624131) (xy 120.853532 -357.574525) (xy 120.883015 -357.528648)
			(xy 120.918726 -357.487434) (xy 120.959939 -357.451722) (xy 121.005815 -357.422238) (xy 121.055419 -357.399583)
			(xy 121.107743 -357.384218) (xy 121.161721 -357.376455) (xy 121.188988 -357.375968) (xy 122.052588 -357.375968)
			(xy 122.079862 -357.376371) (xy 122.133854 -357.384132) (xy 122.186192 -357.399499) (xy 122.235811 -357.422157)
			(xy 122.2817 -357.451647) (xy 122.322924 -357.487367) (xy 122.358646 -357.528591) (xy 122.388137 -357.574479)
			(xy 122.410797 -357.624096) (xy 122.426165 -357.676434) (xy 122.433928 -357.730426) (xy 122.433928 -357.784971)
			(xy 123.916632 -357.784971) (xy 123.916632 -357.730429) (xy 123.924394 -357.676442) (xy 123.939762 -357.62411)
			(xy 123.962421 -357.574497) (xy 123.991911 -357.528615) (xy 124.027631 -357.487397) (xy 124.068853 -357.451682)
			(xy 124.114739 -357.422198) (xy 124.164355 -357.399545) (xy 124.216689 -357.384184) (xy 124.270677 -357.376428)
			(xy 124.297948 -357.375968) (xy 125.161548 -357.375968) (xy 125.188817 -357.376398) (xy 125.2428 -357.384166)
			(xy 125.295128 -357.399536) (xy 125.344736 -357.422197) (xy 125.390614 -357.451687) (xy 125.431829 -357.487405)
			(xy 125.467542 -357.528624) (xy 125.497026 -357.574506) (xy 125.51968 -357.624117) (xy 125.535045 -357.676447)
			(xy 125.542806 -357.730431) (xy 125.542806 -357.784969) (xy 127.025631 -357.784969) (xy 127.025631 -357.730431)
			(xy 127.033393 -357.676447) (xy 127.048759 -357.624118) (xy 127.071415 -357.574508) (xy 127.100901 -357.528628)
			(xy 127.136617 -357.487411) (xy 127.177834 -357.451696) (xy 127.223715 -357.422211) (xy 127.273326 -357.399556)
			(xy 127.325655 -357.384191) (xy 127.379639 -357.376431) (xy 127.406908 -357.375968) (xy 128.270508 -357.375968)
			(xy 128.297779 -357.376395) (xy 128.351766 -357.384158) (xy 128.404099 -357.399525) (xy 128.453712 -357.422184)
			(xy 128.499595 -357.451672) (xy 128.540815 -357.48739) (xy 128.576532 -357.528611) (xy 128.60602 -357.574495)
			(xy 128.628677 -357.624109) (xy 128.644043 -357.676442) (xy 128.651806 -357.730429) (xy 128.651806 -357.784966)
			(xy 130.134654 -357.784966) (xy 130.134654 -357.730434) (xy 130.142414 -357.676458) (xy 130.157777 -357.624135)
			(xy 130.180429 -357.574531) (xy 130.20991 -357.528655) (xy 130.245619 -357.487441) (xy 130.286829 -357.451729)
			(xy 130.332703 -357.422244) (xy 130.382305 -357.399588) (xy 130.434626 -357.384221) (xy 130.488602 -357.376457)
			(xy 130.515868 -357.375968) (xy 131.379468 -357.375968) (xy 131.406743 -357.376369) (xy 131.460737 -357.384128)
			(xy 131.513078 -357.399493) (xy 131.562699 -357.422151) (xy 131.60859 -357.45164) (xy 131.649817 -357.48736)
			(xy 131.685541 -357.528584) (xy 131.715034 -357.574473) (xy 131.737696 -357.624092) (xy 131.753065 -357.676431)
			(xy 131.760828 -357.730425) (xy 131.760828 -357.78497) (xy 133.243531 -357.78497) (xy 133.243532 -357.73043)
			(xy 133.251294 -357.676445) (xy 133.26666 -357.624114) (xy 133.289318 -357.574503) (xy 133.318806 -357.528621)
			(xy 133.354524 -357.487404) (xy 133.395744 -357.451689) (xy 133.441627 -357.422205) (xy 133.49124 -357.39955)
			(xy 133.543572 -357.384188) (xy 133.597558 -357.37643) (xy 133.624828 -357.375968) (xy 134.488428 -357.375968)
			(xy 134.515698 -357.376396) (xy 134.569683 -357.384162) (xy 134.622013 -357.399531) (xy 134.671624 -357.42219)
			(xy 134.717505 -357.451679) (xy 134.758722 -357.487397) (xy 134.794437 -357.528618) (xy 134.823923 -357.574501)
			(xy 134.846579 -357.624113) (xy 134.861944 -357.676444) (xy 134.869706 -357.73043) (xy 134.869706 -357.784967)
			(xy 136.352554 -357.784967) (xy 136.352554 -357.730433) (xy 136.360315 -357.676455) (xy 136.375679 -357.624131)
			(xy 136.398332 -357.574525) (xy 136.427815 -357.528648) (xy 136.463526 -357.487434) (xy 136.504739 -357.451722)
			(xy 136.550615 -357.422238) (xy 136.600219 -357.399583) (xy 136.652543 -357.384218) (xy 136.706521 -357.376455)
			(xy 136.733788 -357.375968) (xy 137.597388 -357.375968) (xy 137.624662 -357.376371) (xy 137.678654 -357.384132)
			(xy 137.730992 -357.399499) (xy 137.780611 -357.422157) (xy 137.8265 -357.451647) (xy 137.867724 -357.487367)
			(xy 137.903446 -357.528591) (xy 137.932937 -357.574479) (xy 137.955597 -357.624096) (xy 137.970965 -357.676434)
			(xy 137.978728 -357.730426) (xy 137.978728 -357.784971) (xy 139.461432 -357.784971) (xy 139.461432 -357.730429)
			(xy 139.469194 -357.676442) (xy 139.484562 -357.62411) (xy 139.507221 -357.574497) (xy 139.536711 -357.528615)
			(xy 139.572431 -357.487397) (xy 139.613653 -357.451682) (xy 139.659539 -357.422198) (xy 139.709155 -357.399545)
			(xy 139.761489 -357.384184) (xy 139.815477 -357.376428) (xy 139.842748 -357.375968) (xy 140.706348 -357.375968)
			(xy 140.733617 -357.376398) (xy 140.7876 -357.384166) (xy 140.839928 -357.399536) (xy 140.889536 -357.422197)
			(xy 140.935414 -357.451687) (xy 140.976629 -357.487405) (xy 141.012342 -357.528624) (xy 141.041826 -357.574506)
			(xy 141.06448 -357.624117) (xy 141.079845 -357.676447) (xy 141.087606 -357.730431) (xy 141.087606 -357.784969)
			(xy 142.570431 -357.784969) (xy 142.570431 -357.730431) (xy 142.578193 -357.676447) (xy 142.593559 -357.624118)
			(xy 142.616215 -357.574508) (xy 142.645701 -357.528628) (xy 142.681417 -357.487411) (xy 142.722634 -357.451696)
			(xy 142.768515 -357.422211) (xy 142.818126 -357.399556) (xy 142.870455 -357.384191) (xy 142.924439 -357.376431)
			(xy 142.951708 -357.375968) (xy 143.815308 -357.375968) (xy 143.842579 -357.376395) (xy 143.896566 -357.384158)
			(xy 143.948899 -357.399525) (xy 143.998512 -357.422184) (xy 144.044395 -357.451672) (xy 144.085615 -357.48739)
			(xy 144.121332 -357.528611) (xy 144.15082 -357.574495) (xy 144.173477 -357.624109) (xy 144.188843 -357.676442)
			(xy 144.196606 -357.730429) (xy 144.196606 -357.784965) (xy 158.695954 -357.784965) (xy 158.695954 -357.730435)
			(xy 158.703714 -357.67646) (xy 158.719076 -357.624138) (xy 158.741727 -357.574535) (xy 158.771206 -357.52866)
			(xy 158.806913 -357.487447) (xy 158.848122 -357.451735) (xy 158.893993 -357.42225) (xy 158.943593 -357.399593)
			(xy 158.995913 -357.384224) (xy 159.049887 -357.376458) (xy 159.077152 -357.375968) (xy 159.940752 -357.375968)
			(xy 159.968027 -357.376368) (xy 160.022024 -357.384125) (xy 160.074366 -357.399489) (xy 160.123989 -357.422145)
			(xy 160.169883 -357.451634) (xy 160.211112 -357.487354) (xy 160.246837 -357.528579) (xy 160.276332 -357.574468)
			(xy 160.298994 -357.624089) (xy 160.314364 -357.676429) (xy 160.322128 -357.730425) (xy 160.322128 -357.784969)
			(xy 161.804831 -357.784969) (xy 161.804831 -357.730431) (xy 161.812593 -357.676447) (xy 161.827959 -357.624117)
			(xy 161.850616 -357.574507) (xy 161.880102 -357.528627) (xy 161.915818 -357.487409) (xy 161.957036 -357.451695)
			(xy 162.002918 -357.42221) (xy 162.052529 -357.399555) (xy 162.104859 -357.384191) (xy 162.158843 -357.376431)
			(xy 162.186112 -357.375968) (xy 163.049712 -357.375968) (xy 163.076983 -357.376395) (xy 163.130969 -357.384159)
			(xy 163.183302 -357.399527) (xy 163.232914 -357.422185) (xy 163.278797 -357.451674) (xy 163.320017 -357.487392)
			(xy 163.355733 -357.528612) (xy 163.385221 -357.574496) (xy 163.407878 -357.62411) (xy 163.423244 -357.676442)
			(xy 163.431006 -357.730429) (xy 163.431006 -357.784966) (xy 164.913854 -357.784966) (xy 164.913854 -357.730434)
			(xy 164.921615 -357.676457) (xy 164.936977 -357.624134) (xy 164.95963 -357.57453) (xy 164.989111 -357.528654)
			(xy 165.02482 -357.48744) (xy 165.066031 -357.451727) (xy 165.111905 -357.422243) (xy 165.161508 -357.399587)
			(xy 165.21383 -357.384221) (xy 165.267806 -357.376456) (xy 165.295072 -357.375968) (xy 166.158672 -357.375968)
			(xy 166.185946 -357.37637) (xy 166.239941 -357.384129) (xy 166.292281 -357.399494) (xy 166.341901 -357.422152)
			(xy 166.387792 -357.451641) (xy 166.429019 -357.487361) (xy 166.464742 -357.528585) (xy 166.494235 -357.574474)
			(xy 166.516896 -357.624093) (xy 166.532265 -357.676432) (xy 166.540028 -357.730426) (xy 166.540028 -357.78497)
			(xy 168.022732 -357.78497) (xy 168.022732 -357.73043) (xy 168.030494 -357.676444) (xy 168.045861 -357.624113)
			(xy 168.068519 -357.574502) (xy 168.098007 -357.52862) (xy 168.133725 -357.487402) (xy 168.174946 -357.451688)
			(xy 168.22083 -357.422203) (xy 168.270443 -357.399549) (xy 168.322776 -357.384187) (xy 168.376762 -357.376429)
			(xy 168.404032 -357.375968) (xy 169.267632 -357.375968) (xy 169.294902 -357.376397) (xy 169.348886 -357.384163)
			(xy 169.401216 -357.399532) (xy 169.450826 -357.422192) (xy 169.496707 -357.451681) (xy 169.537924 -357.487399)
			(xy 169.573638 -357.528619) (xy 169.603124 -357.574502) (xy 169.625779 -357.624114) (xy 169.641144 -357.676445)
			(xy 169.648906 -357.73043) (xy 169.648906 -357.784967) (xy 171.131754 -357.784967) (xy 171.131754 -357.730433)
			(xy 171.139515 -357.676454) (xy 171.154879 -357.62413) (xy 171.177533 -357.574524) (xy 171.207016 -357.528647)
			(xy 171.242727 -357.487433) (xy 171.283941 -357.45172) (xy 171.329817 -357.422237) (xy 171.379422 -357.399582)
			(xy 171.431747 -357.384217) (xy 171.485725 -357.376455) (xy 171.512992 -357.375968) (xy 172.376592 -357.375968)
			(xy 172.403866 -357.376371) (xy 172.457857 -357.384133) (xy 172.510195 -357.3995) (xy 172.559813 -357.422159)
			(xy 172.605702 -357.451648) (xy 172.646926 -357.487368) (xy 172.682647 -357.528592) (xy 172.712138 -357.57448)
			(xy 172.734798 -357.624097) (xy 172.750165 -357.676435) (xy 172.757928 -357.730426) (xy 172.757928 -357.784965)
			(xy 174.240754 -357.784965) (xy 174.240754 -357.730435) (xy 174.248514 -357.67646) (xy 174.263876 -357.624138)
			(xy 174.286527 -357.574535) (xy 174.316006 -357.52866) (xy 174.351713 -357.487447) (xy 174.392922 -357.451735)
			(xy 174.438793 -357.42225) (xy 174.488393 -357.399593) (xy 174.540713 -357.384224) (xy 174.594687 -357.376458)
			(xy 174.621952 -357.375968) (xy 175.485552 -357.375968) (xy 175.512827 -357.376368) (xy 175.566824 -357.384125)
			(xy 175.619166 -357.399489) (xy 175.668789 -357.422145) (xy 175.714683 -357.451634) (xy 175.755912 -357.487354)
			(xy 175.791637 -357.528579) (xy 175.821132 -357.574468) (xy 175.843794 -357.624089) (xy 175.859164 -357.676429)
			(xy 175.866928 -357.730425) (xy 175.866928 -357.784969) (xy 177.349631 -357.784969) (xy 177.349631 -357.730431)
			(xy 177.357393 -357.676447) (xy 177.372759 -357.624117) (xy 177.395416 -357.574507) (xy 177.424902 -357.528627)
			(xy 177.460618 -357.487409) (xy 177.501836 -357.451695) (xy 177.547718 -357.42221) (xy 177.597329 -357.399555)
			(xy 177.649659 -357.384191) (xy 177.703643 -357.376431) (xy 177.730912 -357.375968) (xy 178.594512 -357.375968)
			(xy 178.621783 -357.376395) (xy 178.675769 -357.384159) (xy 178.728102 -357.399527) (xy 178.777714 -357.422185)
			(xy 178.823597 -357.451674) (xy 178.864817 -357.487392) (xy 178.900533 -357.528612) (xy 178.930021 -357.574496)
			(xy 178.952678 -357.62411) (xy 178.968044 -357.676442) (xy 178.975806 -357.730429) (xy 178.975806 -357.784966)
			(xy 180.458654 -357.784966) (xy 180.458654 -357.730434) (xy 180.466415 -357.676457) (xy 180.481777 -357.624134)
			(xy 180.50443 -357.57453) (xy 180.533911 -357.528654) (xy 180.56962 -357.48744) (xy 180.610831 -357.451727)
			(xy 180.656705 -357.422243) (xy 180.706308 -357.399587) (xy 180.75863 -357.384221) (xy 180.812606 -357.376456)
			(xy 180.839872 -357.375968) (xy 181.703472 -357.375968) (xy 181.730746 -357.37637) (xy 181.784741 -357.384129)
			(xy 181.837081 -357.399494) (xy 181.886701 -357.422152) (xy 181.932592 -357.451641) (xy 181.973819 -357.487361)
			(xy 182.009542 -357.528585) (xy 182.039035 -357.574474) (xy 182.061696 -357.624093) (xy 182.077065 -357.676432)
			(xy 182.084828 -357.730426) (xy 182.084828 -357.761176) (xy 183.567456 -357.761176) (xy 183.567456 -357.706624)
			(xy 183.57522 -357.652628) (xy 183.590589 -357.600287) (xy 183.613252 -357.550665) (xy 183.642746 -357.504775)
			(xy 183.678471 -357.463549) (xy 183.7197 -357.427827) (xy 183.765593 -357.398337) (xy 183.815217 -357.375678)
			(xy 183.867559 -357.360313) (xy 183.921556 -357.352553) (xy 183.948832 -357.352092) (xy 184.812432 -357.352092)
			(xy 184.839697 -357.352672) (xy 184.89367 -357.360437) (xy 184.94599 -357.375803) (xy 184.99559 -357.398458)
			(xy 185.041461 -357.427942) (xy 185.08267 -357.463653) (xy 185.118378 -357.504864) (xy 185.147857 -357.550738)
			(xy 185.170508 -357.60034) (xy 185.18587 -357.652661) (xy 185.19363 -357.706635) (xy 185.19363 -357.761165)
			(xy 185.193629 -357.761172) (xy 186.676479 -357.761172) (xy 186.676479 -357.706628) (xy 186.684241 -357.652638)
			(xy 186.699608 -357.600303) (xy 186.722266 -357.550688) (xy 186.751755 -357.504801) (xy 186.787473 -357.463579)
			(xy 186.828695 -357.42786) (xy 186.87458 -357.39837) (xy 186.924196 -357.37571) (xy 186.97653 -357.360343)
			(xy 187.03052 -357.352579) (xy 187.057792 -357.352092) (xy 187.921392 -357.352092) (xy 187.94866 -357.352647)
			(xy 188.002641 -357.360407) (xy 188.054969 -357.375771) (xy 188.104577 -357.398425) (xy 188.150456 -357.427909)
			(xy 188.191672 -357.463622) (xy 188.227386 -357.504838) (xy 188.256871 -357.550716) (xy 188.279526 -357.600324)
			(xy 188.294891 -357.652651) (xy 188.302653 -357.706632) (xy 188.302653 -357.761168) (xy 188.294891 -357.815149)
			(xy 188.279526 -357.867476) (xy 188.256871 -357.917084) (xy 188.227386 -357.962962) (xy 188.223925 -357.966956)
			(xy 245.50903 -357.966956) (xy 245.50903 -357.88226) (xy 245.517081 -357.797946) (xy 245.53311 -357.71478)
			(xy 245.556971 -357.633513) (xy 245.58845 -357.554883) (xy 245.627261 -357.479602) (xy 245.673051 -357.40835)
			(xy 245.725407 -357.341774) (xy 245.783855 -357.280476) (xy 245.847865 -357.225011) (xy 245.916857 -357.175882)
			(xy 245.990207 -357.133533) (xy 246.06725 -357.098349) (xy 246.147289 -357.070647) (xy 246.229598 -357.050679)
			(xy 246.313433 -357.038626) (xy 246.398034 -357.034596) (xy 246.482635 -357.038626) (xy 246.56647 -357.050679)
			(xy 246.648779 -357.070647) (xy 246.728818 -357.098349) (xy 246.805861 -357.133533) (xy 246.879211 -357.175882)
			(xy 246.948203 -357.225011) (xy 247.012213 -357.280476) (xy 247.070661 -357.341774) (xy 247.123017 -357.40835)
			(xy 247.168807 -357.479602) (xy 247.207618 -357.554883) (xy 247.239097 -357.633513) (xy 247.262958 -357.71478)
			(xy 247.276485 -357.784966) (xy 270.624854 -357.784966) (xy 270.624854 -357.730435) (xy 270.632614 -357.676458)
			(xy 270.647977 -357.624136) (xy 270.670628 -357.574532) (xy 270.700108 -357.528657) (xy 270.735817 -357.487443)
			(xy 270.777026 -357.451731) (xy 270.822899 -357.422246) (xy 270.8725 -357.39959) (xy 270.924821 -357.384222)
			(xy 270.978797 -357.376457) (xy 271.006062 -357.375968) (xy 271.869662 -357.375968) (xy 271.896937 -357.376369)
			(xy 271.950932 -357.384127) (xy 272.003273 -357.399491) (xy 272.052895 -357.422149) (xy 272.098787 -357.451638)
			(xy 272.140015 -357.487358) (xy 272.17574 -357.528582) (xy 272.205233 -357.574471) (xy 272.227895 -357.624091)
			(xy 272.243265 -357.676431) (xy 272.251028 -357.730425) (xy 272.251028 -357.78497) (xy 273.733731 -357.78497)
			(xy 273.733731 -357.73043) (xy 273.741494 -357.676446) (xy 273.75686 -357.624115) (xy 273.779517 -357.574505)
			(xy 273.809005 -357.528623) (xy 273.844722 -357.487406) (xy 273.885941 -357.451691) (xy 273.931824 -357.422207)
			(xy 273.981436 -357.399552) (xy 274.033767 -357.384189) (xy 274.087752 -357.37643) (xy 274.115022 -357.375968)
			(xy 274.978622 -357.375968) (xy 275.005892 -357.376396) (xy 275.059878 -357.384161) (xy 275.112209 -357.399529)
			(xy 275.16182 -357.422189) (xy 275.207702 -357.451677) (xy 275.24892 -357.487395) (xy 275.284636 -357.528616)
			(xy 275.314122 -357.574499) (xy 275.336778 -357.624112) (xy 275.352144 -357.676444) (xy 275.359906 -357.730429)
			(xy 275.359906 -357.784966) (xy 276.842754 -357.784966) (xy 276.842754 -357.730434) (xy 276.850515 -357.676456)
			(xy 276.865878 -357.624132) (xy 276.888531 -357.574527) (xy 276.918013 -357.52865) (xy 276.953724 -357.487436)
			(xy 276.994936 -357.451724) (xy 277.040811 -357.42224) (xy 277.090415 -357.399584) (xy 277.142738 -357.384219)
			(xy 277.196716 -357.376456) (xy 277.223982 -357.375968) (xy 278.087582 -357.375968) (xy 278.114856 -357.37637)
			(xy 278.168849 -357.384131) (xy 278.221188 -357.399497) (xy 278.270807 -357.422155) (xy 278.316697 -357.451645)
			(xy 278.357922 -357.487365) (xy 278.393644 -357.528589) (xy 278.423136 -357.574477) (xy 278.445797 -357.624095)
			(xy 278.461165 -357.676433) (xy 278.468928 -357.730426) (xy 278.468928 -357.784971) (xy 279.951632 -357.784971)
			(xy 279.951632 -357.730429) (xy 279.959394 -357.676443) (xy 279.974761 -357.624111) (xy 279.99742 -357.574499)
			(xy 280.026909 -357.528617) (xy 280.062629 -357.487399) (xy 280.103851 -357.451684) (xy 280.149736 -357.4222)
			(xy 280.19935 -357.399547) (xy 280.251684 -357.384185) (xy 280.305671 -357.376429) (xy 280.332942 -357.375968)
			(xy 281.196542 -357.375968) (xy 281.223812 -357.376397) (xy 281.277795 -357.384165) (xy 281.330123 -357.399535)
			(xy 281.379732 -357.422195) (xy 281.425611 -357.451684) (xy 281.466827 -357.487402) (xy 281.502541 -357.528622)
			(xy 281.532025 -357.574505) (xy 281.55468 -357.624116) (xy 281.570044 -357.676446) (xy 281.577806 -357.73043)
			(xy 281.577806 -357.784969) (xy 283.060631 -357.784969) (xy 283.060631 -357.730431) (xy 283.068393 -357.676448)
			(xy 283.083758 -357.62412) (xy 283.106414 -357.57451) (xy 283.1359 -357.52863) (xy 283.171614 -357.487413)
			(xy 283.212832 -357.451698) (xy 283.258712 -357.422213) (xy 283.308321 -357.399557) (xy 283.36065 -357.384193)
			(xy 283.414633 -357.376431) (xy 283.441902 -357.375968) (xy 284.305502 -357.375968) (xy 284.332773 -357.376395)
			(xy 284.386761 -357.384157) (xy 284.439094 -357.399524) (xy 284.488708 -357.422182) (xy 284.534593 -357.45167)
			(xy 284.575813 -357.487388) (xy 284.611531 -357.528609) (xy 284.641019 -357.574493) (xy 284.663677 -357.624107)
			(xy 284.679043 -357.676441) (xy 284.686806 -357.730429) (xy 284.686806 -357.784966) (xy 286.169654 -357.784966)
			(xy 286.169654 -357.730435) (xy 286.177414 -357.676458) (xy 286.192777 -357.624136) (xy 286.215428 -357.574532)
			(xy 286.244908 -357.528657) (xy 286.280617 -357.487443) (xy 286.321826 -357.451731) (xy 286.367699 -357.422246)
			(xy 286.4173 -357.39959) (xy 286.469621 -357.384222) (xy 286.523597 -357.376457) (xy 286.550862 -357.375968)
			(xy 287.414462 -357.375968) (xy 287.441737 -357.376369) (xy 287.495732 -357.384127) (xy 287.548073 -357.399491)
			(xy 287.597695 -357.422149) (xy 287.643587 -357.451638) (xy 287.684815 -357.487358) (xy 287.72054 -357.528582)
			(xy 287.750033 -357.574471) (xy 287.772695 -357.624091) (xy 287.788065 -357.676431) (xy 287.795828 -357.730425)
			(xy 287.795828 -357.78497) (xy 289.278531 -357.78497) (xy 289.278531 -357.73043) (xy 289.286294 -357.676446)
			(xy 289.30166 -357.624115) (xy 289.324317 -357.574505) (xy 289.353805 -357.528623) (xy 289.389522 -357.487406)
			(xy 289.430741 -357.451691) (xy 289.476624 -357.422207) (xy 289.526236 -357.399552) (xy 289.578567 -357.384189)
			(xy 289.632552 -357.37643) (xy 289.659822 -357.375968) (xy 290.523422 -357.375968) (xy 290.550692 -357.376396)
			(xy 290.604678 -357.384161) (xy 290.657009 -357.399529) (xy 290.70662 -357.422189) (xy 290.752502 -357.451677)
			(xy 290.79372 -357.487395) (xy 290.829436 -357.528616) (xy 290.858922 -357.574499) (xy 290.881578 -357.624112)
			(xy 290.896944 -357.676444) (xy 290.904706 -357.730429) (xy 290.904706 -357.784966) (xy 292.387554 -357.784966)
			(xy 292.387554 -357.730434) (xy 292.395315 -357.676456) (xy 292.410678 -357.624132) (xy 292.433331 -357.574527)
			(xy 292.462813 -357.52865) (xy 292.498524 -357.487436) (xy 292.539736 -357.451724) (xy 292.585611 -357.42224)
			(xy 292.635215 -357.399584) (xy 292.687538 -357.384219) (xy 292.741516 -357.376456) (xy 292.768782 -357.375968)
			(xy 293.632382 -357.375968) (xy 293.659656 -357.37637) (xy 293.713649 -357.384131) (xy 293.765988 -357.399497)
			(xy 293.815607 -357.422155) (xy 293.861497 -357.451645) (xy 293.902722 -357.487365) (xy 293.938444 -357.528589)
			(xy 293.967936 -357.574477) (xy 293.990597 -357.624095) (xy 294.005965 -357.676433) (xy 294.013728 -357.730426)
			(xy 294.013728 -357.784971) (xy 295.496432 -357.784971) (xy 295.496432 -357.730429) (xy 295.504194 -357.676443)
			(xy 295.519561 -357.624111) (xy 295.54222 -357.574499) (xy 295.571709 -357.528617) (xy 295.607429 -357.487399)
			(xy 295.648651 -357.451684) (xy 295.694536 -357.4222) (xy 295.74415 -357.399547) (xy 295.796484 -357.384185)
			(xy 295.850471 -357.376429) (xy 295.877742 -357.375968) (xy 296.741342 -357.375968) (xy 296.768612 -357.376397)
			(xy 296.822595 -357.384165) (xy 296.874923 -357.399535) (xy 296.924532 -357.422195) (xy 296.970411 -357.451684)
			(xy 297.011627 -357.487402) (xy 297.047341 -357.528622) (xy 297.076825 -357.574505) (xy 297.09948 -357.624116)
			(xy 297.114844 -357.676446) (xy 297.122606 -357.73043) (xy 297.122606 -357.784969) (xy 298.605431 -357.784969)
			(xy 298.605431 -357.730431) (xy 298.613193 -357.676448) (xy 298.628558 -357.62412) (xy 298.651214 -357.57451)
			(xy 298.6807 -357.52863) (xy 298.716414 -357.487413) (xy 298.757632 -357.451698) (xy 298.803512 -357.422213)
			(xy 298.853121 -357.399557) (xy 298.90545 -357.384193) (xy 298.959433 -357.376431) (xy 298.986702 -357.375968)
			(xy 299.850302 -357.375968) (xy 299.877573 -357.376395) (xy 299.931561 -357.384157) (xy 299.983894 -357.399524)
			(xy 300.033508 -357.422182) (xy 300.079393 -357.45167) (xy 300.120613 -357.487388) (xy 300.156331 -357.528609)
			(xy 300.185819 -357.574493) (xy 300.208477 -357.624107) (xy 300.223843 -357.676441) (xy 300.231606 -357.730429)
			(xy 300.231606 -357.784966) (xy 315.230554 -357.784966) (xy 315.230554 -357.730434) (xy 315.238314 -357.676458)
			(xy 315.253677 -357.624136) (xy 315.276328 -357.574532) (xy 315.305809 -357.528656) (xy 315.341517 -357.487443)
			(xy 315.382727 -357.45173) (xy 315.4286 -357.422246) (xy 315.478202 -357.399589) (xy 315.530523 -357.384222)
			(xy 315.584498 -357.376457) (xy 315.611764 -357.375968) (xy 316.475364 -357.375968) (xy 316.502639 -357.376369)
			(xy 316.556634 -357.384128) (xy 316.608975 -357.399492) (xy 316.658597 -357.422149) (xy 316.704488 -357.451638)
			(xy 316.745716 -357.487359) (xy 316.78144 -357.528583) (xy 316.810933 -357.574472) (xy 316.833595 -357.624091)
			(xy 316.848965 -357.676431) (xy 316.856728 -357.730425) (xy 316.856728 -357.78497) (xy 318.339431 -357.78497)
			(xy 318.339431 -357.73043) (xy 318.347194 -357.676445) (xy 318.36256 -357.624115) (xy 318.385217 -357.574504)
			(xy 318.414705 -357.528623) (xy 318.450422 -357.487405) (xy 318.491642 -357.451691) (xy 318.537525 -357.422206)
			(xy 318.587137 -357.399552) (xy 318.639469 -357.384189) (xy 318.693454 -357.37643) (xy 318.720724 -357.375968)
			(xy 319.584324 -357.375968) (xy 319.611594 -357.376396) (xy 319.66558 -357.384161) (xy 319.71791 -357.39953)
			(xy 319.767521 -357.422189) (xy 319.813403 -357.451678) (xy 319.854621 -357.487396) (xy 319.890336 -357.528616)
			(xy 319.919822 -357.5745) (xy 319.942479 -357.624112) (xy 319.957844 -357.676444) (xy 319.965606 -357.73043)
			(xy 319.965606 -357.784967) (xy 321.448454 -357.784967) (xy 321.448454 -357.730434) (xy 321.456215 -357.676456)
			(xy 321.471578 -357.624131) (xy 321.494232 -357.574526) (xy 321.523714 -357.52865) (xy 321.559424 -357.487436)
			(xy 321.600637 -357.451723) (xy 321.646512 -357.422239) (xy 321.696116 -357.399584) (xy 321.74844 -357.384218)
			(xy 321.802418 -357.376455) (xy 321.829684 -357.375968) (xy 322.693284 -357.375968) (xy 322.720558 -357.37637)
			(xy 322.774551 -357.384131) (xy 322.826889 -357.399497) (xy 322.876508 -357.422156) (xy 322.922398 -357.451645)
			(xy 322.963623 -357.487366) (xy 322.999345 -357.528589) (xy 323.028836 -357.574477) (xy 323.051497 -357.624096)
			(xy 323.066865 -357.676434) (xy 323.074628 -357.730426) (xy 323.074628 -357.784971) (xy 324.557332 -357.784971)
			(xy 324.557332 -357.730429) (xy 324.565094 -357.676443) (xy 324.580461 -357.624111) (xy 324.603121 -357.574498)
			(xy 324.63261 -357.528616) (xy 324.668329 -357.487398) (xy 324.709551 -357.451684) (xy 324.755437 -357.422199)
			(xy 324.805052 -357.399546) (xy 324.857386 -357.384185) (xy 324.911373 -357.376428) (xy 324.938644 -357.375968)
			(xy 325.802244 -357.375968) (xy 325.829513 -357.376398) (xy 325.883497 -357.384165) (xy 325.935825 -357.399535)
			(xy 325.985433 -357.422196) (xy 326.031312 -357.451685) (xy 326.072528 -357.487403) (xy 326.108241 -357.528623)
			(xy 326.137725 -357.574505) (xy 326.16038 -357.624116) (xy 326.175744 -357.676447) (xy 326.183506 -357.73043)
			(xy 326.183506 -357.784969) (xy 327.666331 -357.784969) (xy 327.666331 -357.730431) (xy 327.674093 -357.676448)
			(xy 327.689458 -357.624119) (xy 327.712114 -357.57451) (xy 327.7416 -357.528629) (xy 327.777315 -357.487412)
			(xy 327.818533 -357.451698) (xy 327.864413 -357.422212) (xy 327.914023 -357.399557) (xy 327.966352 -357.384192)
			(xy 328.020335 -357.376431) (xy 328.047604 -357.375968) (xy 328.911204 -357.375968) (xy 328.938475 -357.376395)
			(xy 328.992463 -357.384158) (xy 329.044796 -357.399524) (xy 329.094409 -357.422183) (xy 329.140293 -357.451671)
			(xy 329.181514 -357.487389) (xy 329.217231 -357.52861) (xy 329.246719 -357.574494) (xy 329.269377 -357.624108)
			(xy 329.284743 -357.676441) (xy 329.292506 -357.730429) (xy 329.292506 -357.784966) (xy 330.775354 -357.784966)
			(xy 330.775354 -357.730434) (xy 330.783114 -357.676458) (xy 330.798477 -357.624136) (xy 330.821128 -357.574532)
			(xy 330.850609 -357.528656) (xy 330.886317 -357.487443) (xy 330.927527 -357.45173) (xy 330.9734 -357.422246)
			(xy 331.023002 -357.399589) (xy 331.075323 -357.384222) (xy 331.129298 -357.376457) (xy 331.156564 -357.375968)
			(xy 332.020164 -357.375968) (xy 332.047439 -357.376369) (xy 332.101434 -357.384128) (xy 332.153775 -357.399492)
			(xy 332.203397 -357.422149) (xy 332.249288 -357.451638) (xy 332.290516 -357.487359) (xy 332.32624 -357.528583)
			(xy 332.355733 -357.574472) (xy 332.378395 -357.624091) (xy 332.393765 -357.676431) (xy 332.401528 -357.730425)
			(xy 332.401528 -357.78497) (xy 333.884231 -357.78497) (xy 333.884231 -357.73043) (xy 333.891994 -357.676445)
			(xy 333.90736 -357.624115) (xy 333.930017 -357.574504) (xy 333.959505 -357.528623) (xy 333.995222 -357.487405)
			(xy 334.036442 -357.451691) (xy 334.082325 -357.422206) (xy 334.131937 -357.399552) (xy 334.184269 -357.384189)
			(xy 334.238254 -357.37643) (xy 334.265524 -357.375968) (xy 335.129124 -357.375968) (xy 335.156394 -357.376396)
			(xy 335.21038 -357.384161) (xy 335.26271 -357.39953) (xy 335.312321 -357.422189) (xy 335.358203 -357.451678)
			(xy 335.399421 -357.487396) (xy 335.435136 -357.528616) (xy 335.464622 -357.5745) (xy 335.487279 -357.624112)
			(xy 335.502644 -357.676444) (xy 335.510406 -357.73043) (xy 335.510406 -357.784967) (xy 336.993254 -357.784967)
			(xy 336.993254 -357.730434) (xy 337.001015 -357.676456) (xy 337.016378 -357.624131) (xy 337.039032 -357.574526)
			(xy 337.068514 -357.52865) (xy 337.104224 -357.487436) (xy 337.145437 -357.451723) (xy 337.191312 -357.422239)
			(xy 337.240916 -357.399584) (xy 337.29324 -357.384218) (xy 337.347218 -357.376455) (xy 337.374484 -357.375968)
			(xy 338.238084 -357.375968) (xy 338.265358 -357.37637) (xy 338.319351 -357.384131) (xy 338.371689 -357.399497)
			(xy 338.421308 -357.422156) (xy 338.467198 -357.451645) (xy 338.508423 -357.487366) (xy 338.544145 -357.528589)
			(xy 338.573636 -357.574477) (xy 338.596297 -357.624096) (xy 338.611665 -357.676434) (xy 338.619428 -357.730426)
			(xy 338.619428 -357.784971) (xy 340.102132 -357.784971) (xy 340.102132 -357.730429) (xy 340.109894 -357.676443)
			(xy 340.125261 -357.624111) (xy 340.147921 -357.574498) (xy 340.17741 -357.528616) (xy 340.213129 -357.487398)
			(xy 340.254351 -357.451684) (xy 340.300237 -357.422199) (xy 340.349852 -357.399546) (xy 340.402186 -357.384185)
			(xy 340.456173 -357.376428) (xy 340.483444 -357.375968) (xy 341.347044 -357.375968) (xy 341.374313 -357.376398)
			(xy 341.428297 -357.384165) (xy 341.480625 -357.399535) (xy 341.530233 -357.422196) (xy 341.576112 -357.451685)
			(xy 341.617328 -357.487403) (xy 341.653041 -357.528623) (xy 341.682525 -357.574505) (xy 341.70518 -357.624116)
			(xy 341.720544 -357.676447) (xy 341.728306 -357.73043) (xy 341.728306 -357.784969) (xy 343.211131 -357.784969)
			(xy 343.211131 -357.730431) (xy 343.218893 -357.676448) (xy 343.234258 -357.624119) (xy 343.256914 -357.57451)
			(xy 343.2864 -357.528629) (xy 343.322115 -357.487412) (xy 343.363333 -357.451698) (xy 343.409213 -357.422212)
			(xy 343.458823 -357.399557) (xy 343.511152 -357.384192) (xy 343.565135 -357.376431) (xy 343.592404 -357.375968)
			(xy 344.456004 -357.375968) (xy 344.483275 -357.376395) (xy 344.537263 -357.384158) (xy 344.589596 -357.399524)
			(xy 344.639209 -357.422183) (xy 344.685093 -357.451671) (xy 344.726314 -357.487389) (xy 344.762031 -357.52861)
			(xy 344.791519 -357.574494) (xy 344.814177 -357.624108) (xy 344.829543 -357.676441) (xy 344.837306 -357.730429)
			(xy 344.837306 -357.784971) (xy 373.915632 -357.784971) (xy 373.915632 -357.730429) (xy 373.923394 -357.676443)
			(xy 373.938761 -357.624111) (xy 373.96142 -357.574499) (xy 373.990909 -357.528617) (xy 374.026628 -357.4874)
			(xy 374.06785 -357.451685) (xy 374.113735 -357.422201) (xy 374.163349 -357.399547) (xy 374.215682 -357.384186)
			(xy 374.269669 -357.376429) (xy 374.29694 -357.375968) (xy 375.16054 -357.375968) (xy 375.18781 -357.376397)
			(xy 375.241793 -357.384164) (xy 375.294122 -357.399534) (xy 375.343731 -357.422194) (xy 375.389611 -357.451684)
			(xy 375.430827 -357.487402) (xy 375.46654 -357.528622) (xy 375.496025 -357.574504) (xy 375.51868 -357.624116)
			(xy 375.534044 -357.676446) (xy 375.541806 -357.73043) (xy 375.541806 -357.784967) (xy 377.024654 -357.784967)
			(xy 377.024654 -357.730433) (xy 377.032415 -357.676453) (xy 377.04778 -357.624128) (xy 377.070434 -357.574522)
			(xy 377.099918 -357.528644) (xy 377.13563 -357.48743) (xy 377.176844 -357.451718) (xy 377.222722 -357.422234)
			(xy 377.272328 -357.39958) (xy 377.324653 -357.384215) (xy 377.378633 -357.376454) (xy 377.4059 -357.375968)
			(xy 378.2695 -357.375968) (xy 378.296772 -357.376395) (xy 378.350759 -357.384157) (xy 378.403093 -357.399523)
			(xy 378.452707 -357.422181) (xy 378.498592 -357.451669) (xy 378.539812 -357.487388) (xy 378.575531 -357.528608)
			(xy 378.605019 -357.574493) (xy 378.627677 -357.624107) (xy 378.643043 -357.676441) (xy 378.650805 -357.730428)
			(xy 378.650805 -357.784965) (xy 380.133654 -357.784965) (xy 380.133654 -357.730435) (xy 380.141414 -357.676459)
			(xy 380.156776 -357.624137) (xy 380.179428 -357.574533) (xy 380.208908 -357.528658) (xy 380.244616 -357.487444)
			(xy 380.285825 -357.451732) (xy 380.331698 -357.422247) (xy 380.381299 -357.39959) (xy 380.43362 -357.384223)
			(xy 380.487595 -357.376457) (xy 380.51486 -357.375968) (xy 381.37846 -357.375968) (xy 381.405735 -357.376369)
			(xy 381.45973 -357.384127) (xy 381.512072 -357.399491) (xy 381.561694 -357.422148) (xy 381.607586 -357.451637)
			(xy 381.648815 -357.487357) (xy 381.684539 -357.528582) (xy 381.714033 -357.574471) (xy 381.736695 -357.62409)
			(xy 381.752065 -357.67643) (xy 381.759828 -357.730425) (xy 381.759828 -357.78497) (xy 383.242531 -357.78497)
			(xy 383.242531 -357.73043) (xy 383.250294 -357.676446) (xy 383.26566 -357.624116) (xy 383.288317 -357.574505)
			(xy 383.317804 -357.528624) (xy 383.353521 -357.487407) (xy 383.39474 -357.451692) (xy 383.440623 -357.422207)
			(xy 383.490234 -357.399553) (xy 383.542565 -357.384189) (xy 383.59655 -357.37643) (xy 383.62382 -357.375968)
			(xy 384.48742 -357.375968) (xy 384.514691 -357.376396) (xy 384.568676 -357.38416) (xy 384.621007 -357.399529)
			(xy 384.670619 -357.422188) (xy 384.716501 -357.451677) (xy 384.75772 -357.487395) (xy 384.793435 -357.528615)
			(xy 384.822922 -357.574499) (xy 384.845578 -357.624111) (xy 384.860944 -357.676443) (xy 384.868706 -357.730429)
			(xy 384.868706 -357.784966) (xy 386.351554 -357.784966) (xy 386.351554 -357.730434) (xy 386.359315 -357.676456)
			(xy 386.374678 -357.624132) (xy 386.397331 -357.574527) (xy 386.426813 -357.528651) (xy 386.462523 -357.487437)
			(xy 386.503735 -357.451725) (xy 386.54961 -357.422241) (xy 386.599213 -357.399585) (xy 386.651537 -357.384219)
			(xy 386.705514 -357.376456) (xy 386.73278 -357.375968) (xy 387.59638 -357.375968) (xy 387.623654 -357.37637)
			(xy 387.677647 -357.384131) (xy 387.729987 -357.399496) (xy 387.779606 -357.422155) (xy 387.825496 -357.451644)
			(xy 387.866722 -357.487364) (xy 387.902444 -357.528588) (xy 387.931936 -357.574476) (xy 387.954597 -357.624095)
			(xy 387.969965 -357.676433) (xy 387.977728 -357.730426) (xy 387.977728 -357.784971) (xy 389.460432 -357.784971)
			(xy 389.460432 -357.730429) (xy 389.468194 -357.676443) (xy 389.483561 -357.624111) (xy 389.50622 -357.574499)
			(xy 389.535709 -357.528617) (xy 389.571428 -357.4874) (xy 389.61265 -357.451685) (xy 389.658535 -357.422201)
			(xy 389.708149 -357.399547) (xy 389.760482 -357.384186) (xy 389.814469 -357.376429) (xy 389.84174 -357.375968)
			(xy 390.70534 -357.375968) (xy 390.73261 -357.376397) (xy 390.786593 -357.384164) (xy 390.838922 -357.399534)
			(xy 390.888531 -357.422194) (xy 390.934411 -357.451684) (xy 390.975627 -357.487402) (xy 391.01134 -357.528622)
			(xy 391.040825 -357.574504) (xy 391.06348 -357.624116) (xy 391.078844 -357.676446) (xy 391.086606 -357.73043)
			(xy 391.086606 -357.784967) (xy 392.569454 -357.784967) (xy 392.569454 -357.730433) (xy 392.577215 -357.676453)
			(xy 392.59258 -357.624128) (xy 392.615234 -357.574522) (xy 392.644718 -357.528644) (xy 392.68043 -357.48743)
			(xy 392.721644 -357.451718) (xy 392.767522 -357.422234) (xy 392.817128 -357.39958) (xy 392.869453 -357.384215)
			(xy 392.923433 -357.376454) (xy 392.9507 -357.375968) (xy 393.8143 -357.375968) (xy 393.841572 -357.376395)
			(xy 393.895559 -357.384157) (xy 393.947893 -357.399523) (xy 393.997507 -357.422181) (xy 394.043392 -357.451669)
			(xy 394.084612 -357.487388) (xy 394.120331 -357.528608) (xy 394.149819 -357.574493) (xy 394.172477 -357.624107)
			(xy 394.187843 -357.676441) (xy 394.195605 -357.730428) (xy 394.195605 -357.784965) (xy 395.678454 -357.784965)
			(xy 395.678454 -357.730435) (xy 395.686214 -357.676459) (xy 395.701576 -357.624137) (xy 395.724228 -357.574533)
			(xy 395.753708 -357.528658) (xy 395.789416 -357.487444) (xy 395.830625 -357.451732) (xy 395.876498 -357.422247)
			(xy 395.926099 -357.39959) (xy 395.97842 -357.384223) (xy 396.032395 -357.376457) (xy 396.05966 -357.375968)
			(xy 396.92326 -357.375968) (xy 396.950535 -357.376369) (xy 397.00453 -357.384127) (xy 397.056872 -357.399491)
			(xy 397.106494 -357.422148) (xy 397.152386 -357.451637) (xy 397.193615 -357.487357) (xy 397.229339 -357.528582)
			(xy 397.258833 -357.574471) (xy 397.281495 -357.62409) (xy 397.296865 -357.67643) (xy 397.304628 -357.730425)
			(xy 397.304628 -357.78497) (xy 398.787331 -357.78497) (xy 398.787331 -357.73043) (xy 398.795094 -357.676446)
			(xy 398.81046 -357.624116) (xy 398.833117 -357.574505) (xy 398.862604 -357.528624) (xy 398.898321 -357.487407)
			(xy 398.93954 -357.451692) (xy 398.985423 -357.422207) (xy 399.035034 -357.399553) (xy 399.087365 -357.384189)
			(xy 399.14135 -357.37643) (xy 399.16862 -357.375968) (xy 400.03222 -357.375968) (xy 400.059491 -357.376396)
			(xy 400.113476 -357.38416) (xy 400.165807 -357.399529) (xy 400.215419 -357.422188) (xy 400.261301 -357.451677)
			(xy 400.30252 -357.487395) (xy 400.338235 -357.528615) (xy 400.367722 -357.574499) (xy 400.390378 -357.624111)
			(xy 400.405744 -357.676443) (xy 400.413506 -357.730429) (xy 400.413506 -357.784966) (xy 401.896354 -357.784966)
			(xy 401.896354 -357.730434) (xy 401.904115 -357.676456) (xy 401.919478 -357.624132) (xy 401.942131 -357.574527)
			(xy 401.971613 -357.528651) (xy 402.007323 -357.487437) (xy 402.048535 -357.451725) (xy 402.09441 -357.422241)
			(xy 402.144013 -357.399585) (xy 402.196337 -357.384219) (xy 402.250314 -357.376456) (xy 402.27758 -357.375968)
			(xy 403.14118 -357.375968) (xy 403.168454 -357.37637) (xy 403.222447 -357.384131) (xy 403.274787 -357.399496)
			(xy 403.324406 -357.422155) (xy 403.370296 -357.451644) (xy 403.411522 -357.487364) (xy 403.447244 -357.528588)
			(xy 403.476736 -357.574476) (xy 403.499397 -357.624095) (xy 403.514765 -357.676433) (xy 403.522528 -357.730426)
			(xy 403.522528 -357.784965) (xy 412.022854 -357.784965) (xy 412.022854 -357.730435) (xy 412.030614 -357.67646)
			(xy 412.045976 -357.624138) (xy 412.068627 -357.574535) (xy 412.098106 -357.52866) (xy 412.133813 -357.487447)
			(xy 412.175022 -357.451735) (xy 412.220893 -357.42225) (xy 412.270493 -357.399593) (xy 412.322813 -357.384224)
			(xy 412.376787 -357.376458) (xy 412.404052 -357.375968) (xy 413.267652 -357.375968) (xy 413.294927 -357.376368)
			(xy 413.348924 -357.384125) (xy 413.401266 -357.399489) (xy 413.450889 -357.422145) (xy 413.496783 -357.451634)
			(xy 413.538012 -357.487354) (xy 413.573737 -357.528579) (xy 413.603232 -357.574468) (xy 413.625894 -357.624089)
			(xy 413.641264 -357.676429) (xy 413.649028 -357.730425) (xy 413.649028 -357.784969) (xy 415.131731 -357.784969)
			(xy 415.131731 -357.730431) (xy 415.139493 -357.676447) (xy 415.154859 -357.624117) (xy 415.177516 -357.574507)
			(xy 415.207002 -357.528627) (xy 415.242718 -357.487409) (xy 415.283936 -357.451695) (xy 415.329818 -357.42221)
			(xy 415.379429 -357.399555) (xy 415.431759 -357.384191) (xy 415.485743 -357.376431) (xy 415.513012 -357.375968)
			(xy 416.376612 -357.375968) (xy 416.403883 -357.376395) (xy 416.457869 -357.384159) (xy 416.510202 -357.399527)
			(xy 416.559814 -357.422185) (xy 416.605697 -357.451674) (xy 416.646917 -357.487392) (xy 416.682633 -357.528612)
			(xy 416.712121 -357.574496) (xy 416.734778 -357.62411) (xy 416.750144 -357.676442) (xy 416.757906 -357.730429)
			(xy 416.757906 -357.784966) (xy 418.240754 -357.784966) (xy 418.240754 -357.730434) (xy 418.248515 -357.676457)
			(xy 418.263877 -357.624134) (xy 418.28653 -357.57453) (xy 418.316011 -357.528654) (xy 418.35172 -357.48744)
			(xy 418.392931 -357.451727) (xy 418.438805 -357.422243) (xy 418.488408 -357.399587) (xy 418.54073 -357.384221)
			(xy 418.594706 -357.376456) (xy 418.621972 -357.375968) (xy 419.485572 -357.375968) (xy 419.512846 -357.37637)
			(xy 419.566841 -357.384129) (xy 419.619181 -357.399494) (xy 419.668801 -357.422152) (xy 419.714692 -357.451641)
			(xy 419.755919 -357.487361) (xy 419.791642 -357.528585) (xy 419.821135 -357.574474) (xy 419.843796 -357.624093)
			(xy 419.859165 -357.676432) (xy 419.866928 -357.730426) (xy 419.866928 -357.78497) (xy 421.349632 -357.78497)
			(xy 421.349632 -357.73043) (xy 421.357394 -357.676444) (xy 421.372761 -357.624113) (xy 421.395419 -357.574502)
			(xy 421.424907 -357.52862) (xy 421.460625 -357.487402) (xy 421.501846 -357.451688) (xy 421.54773 -357.422203)
			(xy 421.597343 -357.399549) (xy 421.649676 -357.384187) (xy 421.703662 -357.376429) (xy 421.730932 -357.375968)
			(xy 422.594532 -357.375968) (xy 422.621802 -357.376397) (xy 422.675786 -357.384163) (xy 422.728116 -357.399532)
			(xy 422.777726 -357.422192) (xy 422.823607 -357.451681) (xy 422.864824 -357.487399) (xy 422.900538 -357.528619)
			(xy 422.930024 -357.574502) (xy 422.952679 -357.624114) (xy 422.968044 -357.676445) (xy 422.975806 -357.73043)
			(xy 422.975806 -357.784967) (xy 424.458654 -357.784967) (xy 424.458654 -357.730433) (xy 424.466415 -357.676454)
			(xy 424.481779 -357.62413) (xy 424.504433 -357.574524) (xy 424.533916 -357.528647) (xy 424.569627 -357.487433)
			(xy 424.610841 -357.45172) (xy 424.656717 -357.422237) (xy 424.706322 -357.399582) (xy 424.758647 -357.384217)
			(xy 424.812625 -357.376455) (xy 424.839892 -357.375968) (xy 425.703492 -357.375968) (xy 425.730766 -357.376371)
			(xy 425.784757 -357.384133) (xy 425.837095 -357.3995) (xy 425.886713 -357.422159) (xy 425.932602 -357.451648)
			(xy 425.973826 -357.487368) (xy 426.009547 -357.528592) (xy 426.039038 -357.57448) (xy 426.061698 -357.624097)
			(xy 426.077065 -357.676435) (xy 426.084828 -357.730426) (xy 426.084828 -357.784965) (xy 427.567654 -357.784965)
			(xy 427.567654 -357.730435) (xy 427.575414 -357.67646) (xy 427.590776 -357.624138) (xy 427.613427 -357.574535)
			(xy 427.642906 -357.52866) (xy 427.678613 -357.487447) (xy 427.719822 -357.451735) (xy 427.765693 -357.42225)
			(xy 427.815293 -357.399593) (xy 427.867613 -357.384224) (xy 427.921587 -357.376458) (xy 427.948852 -357.375968)
			(xy 428.812452 -357.375968) (xy 428.839727 -357.376368) (xy 428.893724 -357.384125) (xy 428.946066 -357.399489)
			(xy 428.995689 -357.422145) (xy 429.041583 -357.451634) (xy 429.082812 -357.487354) (xy 429.118537 -357.528579)
			(xy 429.148032 -357.574468) (xy 429.170694 -357.624089) (xy 429.186064 -357.676429) (xy 429.193828 -357.730425)
			(xy 429.193828 -357.784969) (xy 430.676531 -357.784969) (xy 430.676531 -357.730431) (xy 430.684293 -357.676447)
			(xy 430.699659 -357.624117) (xy 430.722316 -357.574507) (xy 430.751802 -357.528627) (xy 430.787518 -357.487409)
			(xy 430.828736 -357.451695) (xy 430.874618 -357.42221) (xy 430.924229 -357.399555) (xy 430.976559 -357.384191)
			(xy 431.030543 -357.376431) (xy 431.057812 -357.375968) (xy 431.921412 -357.375968) (xy 431.948683 -357.376395)
			(xy 432.002669 -357.384159) (xy 432.055002 -357.399527) (xy 432.104614 -357.422185) (xy 432.150497 -357.451674)
			(xy 432.191717 -357.487392) (xy 432.227433 -357.528612) (xy 432.256921 -357.574496) (xy 432.279578 -357.62411)
			(xy 432.294944 -357.676442) (xy 432.302706 -357.730429) (xy 432.302706 -357.784966) (xy 433.785554 -357.784966)
			(xy 433.785554 -357.730434) (xy 433.793315 -357.676457) (xy 433.808677 -357.624134) (xy 433.83133 -357.57453)
			(xy 433.860811 -357.528654) (xy 433.89652 -357.48744) (xy 433.937731 -357.451727) (xy 433.983605 -357.422243)
			(xy 434.033208 -357.399587) (xy 434.08553 -357.384221) (xy 434.139506 -357.376456) (xy 434.166772 -357.375968)
			(xy 435.030372 -357.375968) (xy 435.057646 -357.37637) (xy 435.111641 -357.384129) (xy 435.163981 -357.399494)
			(xy 435.213601 -357.422152) (xy 435.259492 -357.451641) (xy 435.300719 -357.487361) (xy 435.336442 -357.528585)
			(xy 435.365935 -357.574474) (xy 435.388596 -357.624093) (xy 435.403965 -357.676432) (xy 435.411728 -357.730426)
			(xy 435.411728 -357.78497) (xy 436.894432 -357.78497) (xy 436.894432 -357.73043) (xy 436.902194 -357.676444)
			(xy 436.917561 -357.624113) (xy 436.940219 -357.574502) (xy 436.969707 -357.52862) (xy 437.005425 -357.487402)
			(xy 437.046646 -357.451688) (xy 437.09253 -357.422203) (xy 437.142143 -357.399549) (xy 437.194476 -357.384187)
			(xy 437.248462 -357.376429) (xy 437.275732 -357.375968) (xy 438.139332 -357.375968) (xy 438.166602 -357.376397)
			(xy 438.220586 -357.384163) (xy 438.272916 -357.399532) (xy 438.322526 -357.422192) (xy 438.368407 -357.451681)
			(xy 438.409624 -357.487399) (xy 438.445338 -357.528619) (xy 438.474824 -357.574502) (xy 438.497479 -357.624114)
			(xy 438.512844 -357.676445) (xy 438.520606 -357.73043) (xy 438.520606 -357.784967) (xy 440.003454 -357.784967)
			(xy 440.003454 -357.730433) (xy 440.011215 -357.676454) (xy 440.026579 -357.62413) (xy 440.049233 -357.574524)
			(xy 440.078716 -357.528647) (xy 440.114427 -357.487433) (xy 440.155641 -357.45172) (xy 440.201517 -357.422237)
			(xy 440.251122 -357.399582) (xy 440.303447 -357.384217) (xy 440.357425 -357.376455) (xy 440.384692 -357.375968)
			(xy 441.248292 -357.375968) (xy 441.275566 -357.376371) (xy 441.329557 -357.384133) (xy 441.381895 -357.3995)
			(xy 441.431513 -357.422159) (xy 441.477402 -357.451648) (xy 441.518626 -357.487368) (xy 441.554347 -357.528592)
			(xy 441.583838 -357.57448) (xy 441.606498 -357.624097) (xy 441.621865 -357.676435) (xy 441.629628 -357.730426)
			(xy 441.629628 -357.784974) (xy 441.621865 -357.838965) (xy 441.606498 -357.891303) (xy 441.583838 -357.94092)
			(xy 441.554347 -357.986808) (xy 441.518626 -358.028032) (xy 441.477402 -358.063752) (xy 441.431513 -358.093241)
			(xy 441.381895 -358.1159) (xy 441.329557 -358.131267) (xy 441.275566 -358.139029) (xy 441.248292 -358.139492)
			(xy 440.384692 -358.139492) (xy 440.357425 -358.138945) (xy 440.303447 -358.131183) (xy 440.251122 -358.115818)
			(xy 440.201517 -358.093163) (xy 440.155641 -358.06368) (xy 440.114427 -358.027967) (xy 440.078716 -357.986753)
			(xy 440.049233 -357.940876) (xy 440.026579 -357.89127) (xy 440.011215 -357.838946) (xy 440.003454 -357.784967)
			(xy 438.520606 -357.784967) (xy 438.520606 -357.78497) (xy 438.512844 -357.838955) (xy 438.497479 -357.891286)
			(xy 438.474824 -357.940898) (xy 438.445338 -357.986781) (xy 438.409624 -358.028001) (xy 438.368407 -358.063719)
			(xy 438.322526 -358.093208) (xy 438.272916 -358.115868) (xy 438.220586 -358.131237) (xy 438.166602 -358.139003)
			(xy 438.139332 -358.139492) (xy 437.275732 -358.139492) (xy 437.248462 -358.138971) (xy 437.194476 -358.131213)
			(xy 437.142143 -358.115851) (xy 437.09253 -358.093197) (xy 437.046646 -358.063712) (xy 437.005425 -358.027998)
			(xy 436.969707 -357.98678) (xy 436.940219 -357.940898) (xy 436.917561 -357.891287) (xy 436.902194 -357.838956)
			(xy 436.894432 -357.78497) (xy 435.411728 -357.78497) (xy 435.411728 -357.784974) (xy 435.403965 -357.838968)
			(xy 435.388596 -357.891307) (xy 435.365935 -357.940926) (xy 435.336442 -357.986815) (xy 435.300719 -358.028039)
			(xy 435.259492 -358.063759) (xy 435.213601 -358.093248) (xy 435.163981 -358.115906) (xy 435.111641 -358.131271)
			(xy 435.057646 -358.13903) (xy 435.030372 -358.139492) (xy 434.166772 -358.139492) (xy 434.139506 -358.138944)
			(xy 434.08553 -358.131179) (xy 434.033208 -358.115813) (xy 433.983605 -358.093157) (xy 433.937731 -358.063673)
			(xy 433.89652 -358.02796) (xy 433.860811 -357.986746) (xy 433.83133 -357.94087) (xy 433.808677 -357.891266)
			(xy 433.793315 -357.838943) (xy 433.785554 -357.784966) (xy 432.302706 -357.784966) (xy 432.302706 -357.784971)
			(xy 432.294944 -357.838958) (xy 432.279578 -357.89129) (xy 432.256921 -357.940904) (xy 432.227433 -357.986788)
			(xy 432.191717 -358.028008) (xy 432.150497 -358.063726) (xy 432.104614 -358.093215) (xy 432.055002 -358.115873)
			(xy 432.002669 -358.131241) (xy 431.948683 -358.139005) (xy 431.921412 -358.139492) (xy 431.057812 -358.139492)
			(xy 431.030543 -358.138969) (xy 430.976559 -358.131209) (xy 430.924229 -358.115845) (xy 430.874618 -358.09319)
			(xy 430.828736 -358.063705) (xy 430.787518 -358.027991) (xy 430.751802 -357.986773) (xy 430.722316 -357.940893)
			(xy 430.699659 -357.891283) (xy 430.684293 -357.838953) (xy 430.676531 -357.784969) (xy 429.193828 -357.784969)
			(xy 429.193828 -357.784975) (xy 429.186064 -357.838971) (xy 429.170694 -357.891311) (xy 429.148032 -357.940932)
			(xy 429.118537 -357.986821) (xy 429.082812 -358.028046) (xy 429.041583 -358.063766) (xy 428.995689 -358.093255)
			(xy 428.946066 -358.115911) (xy 428.893724 -358.131275) (xy 428.839727 -358.139032) (xy 428.812452 -358.139492)
			(xy 427.948852 -358.139492) (xy 427.921587 -358.138942) (xy 427.867613 -358.131176) (xy 427.815293 -358.115807)
			(xy 427.765693 -358.09315) (xy 427.719822 -358.063665) (xy 427.678613 -358.027953) (xy 427.642906 -357.98674)
			(xy 427.613427 -357.940865) (xy 427.590776 -357.891262) (xy 427.575414 -357.83894) (xy 427.567654 -357.784965)
			(xy 426.084828 -357.784965) (xy 426.084828 -357.784974) (xy 426.077065 -357.838965) (xy 426.061698 -357.891303)
			(xy 426.039038 -357.94092) (xy 426.009547 -357.986808) (xy 425.973826 -358.028032) (xy 425.932602 -358.063752)
			(xy 425.886713 -358.093241) (xy 425.837095 -358.1159) (xy 425.784757 -358.131267) (xy 425.730766 -358.139029)
			(xy 425.703492 -358.139492) (xy 424.839892 -358.139492) (xy 424.812625 -358.138945) (xy 424.758647 -358.131183)
			(xy 424.706322 -358.115818) (xy 424.656717 -358.093163) (xy 424.610841 -358.06368) (xy 424.569627 -358.027967)
			(xy 424.533916 -357.986753) (xy 424.504433 -357.940876) (xy 424.481779 -357.89127) (xy 424.466415 -357.838946)
			(xy 424.458654 -357.784967) (xy 422.975806 -357.784967) (xy 422.975806 -357.78497) (xy 422.968044 -357.838955)
			(xy 422.952679 -357.891286) (xy 422.930024 -357.940898) (xy 422.900538 -357.986781) (xy 422.864824 -358.028001)
			(xy 422.823607 -358.063719) (xy 422.777726 -358.093208) (xy 422.728116 -358.115868) (xy 422.675786 -358.131237)
			(xy 422.621802 -358.139003) (xy 422.594532 -358.139492) (xy 421.730932 -358.139492) (xy 421.703662 -358.138971)
			(xy 421.649676 -358.131213) (xy 421.597343 -358.115851) (xy 421.54773 -358.093197) (xy 421.501846 -358.063712)
			(xy 421.460625 -358.027998) (xy 421.424907 -357.98678) (xy 421.395419 -357.940898) (xy 421.372761 -357.891287)
			(xy 421.357394 -357.838956) (xy 421.349632 -357.78497) (xy 419.866928 -357.78497) (xy 419.866928 -357.784974)
			(xy 419.859165 -357.838968) (xy 419.843796 -357.891307) (xy 419.821135 -357.940926) (xy 419.791642 -357.986815)
			(xy 419.755919 -358.028039) (xy 419.714692 -358.063759) (xy 419.668801 -358.093248) (xy 419.619181 -358.115906)
			(xy 419.566841 -358.131271) (xy 419.512846 -358.13903) (xy 419.485572 -358.139492) (xy 418.621972 -358.139492)
			(xy 418.594706 -358.138944) (xy 418.54073 -358.131179) (xy 418.488408 -358.115813) (xy 418.438805 -358.093157)
			(xy 418.392931 -358.063673) (xy 418.35172 -358.02796) (xy 418.316011 -357.986746) (xy 418.28653 -357.94087)
			(xy 418.263877 -357.891266) (xy 418.248515 -357.838943) (xy 418.240754 -357.784966) (xy 416.757906 -357.784966)
			(xy 416.757906 -357.784971) (xy 416.750144 -357.838958) (xy 416.734778 -357.89129) (xy 416.712121 -357.940904)
			(xy 416.682633 -357.986788) (xy 416.646917 -358.028008) (xy 416.605697 -358.063726) (xy 416.559814 -358.093215)
			(xy 416.510202 -358.115873) (xy 416.457869 -358.131241) (xy 416.403883 -358.139005) (xy 416.376612 -358.139492)
			(xy 415.513012 -358.139492) (xy 415.485743 -358.138969) (xy 415.431759 -358.131209) (xy 415.379429 -358.115845)
			(xy 415.329818 -358.09319) (xy 415.283936 -358.063705) (xy 415.242718 -358.027991) (xy 415.207002 -357.986773)
			(xy 415.177516 -357.940893) (xy 415.154859 -357.891283) (xy 415.139493 -357.838953) (xy 415.131731 -357.784969)
			(xy 413.649028 -357.784969) (xy 413.649028 -357.784975) (xy 413.641264 -357.838971) (xy 413.625894 -357.891311)
			(xy 413.603232 -357.940932) (xy 413.573737 -357.986821) (xy 413.538012 -358.028046) (xy 413.496783 -358.063766)
			(xy 413.450889 -358.093255) (xy 413.401266 -358.115911) (xy 413.348924 -358.131275) (xy 413.294927 -358.139032)
			(xy 413.267652 -358.139492) (xy 412.404052 -358.139492) (xy 412.376787 -358.138942) (xy 412.322813 -358.131176)
			(xy 412.270493 -358.115807) (xy 412.220893 -358.09315) (xy 412.175022 -358.063665) (xy 412.133813 -358.027953)
			(xy 412.098106 -357.98674) (xy 412.068627 -357.940865) (xy 412.045976 -357.891262) (xy 412.030614 -357.83894)
			(xy 412.022854 -357.784965) (xy 403.522528 -357.784965) (xy 403.522528 -357.784974) (xy 403.514765 -357.838967)
			(xy 403.499397 -357.891305) (xy 403.476736 -357.940924) (xy 403.447244 -357.986812) (xy 403.411522 -358.028036)
			(xy 403.370296 -358.063756) (xy 403.324406 -358.093245) (xy 403.274787 -358.115904) (xy 403.222447 -358.131269)
			(xy 403.168454 -358.13903) (xy 403.14118 -358.139492) (xy 402.27758 -358.139492) (xy 402.250314 -358.138944)
			(xy 402.196337 -358.131181) (xy 402.144013 -358.115815) (xy 402.09441 -358.093159) (xy 402.048535 -358.063675)
			(xy 402.007323 -358.027963) (xy 401.971613 -357.986749) (xy 401.942131 -357.940873) (xy 401.919478 -357.891268)
			(xy 401.904115 -357.838944) (xy 401.896354 -357.784966) (xy 400.413506 -357.784966) (xy 400.413506 -357.784971)
			(xy 400.405744 -357.838957) (xy 400.390378 -357.891289) (xy 400.367722 -357.940901) (xy 400.338235 -357.986785)
			(xy 400.30252 -358.028005) (xy 400.261301 -358.063723) (xy 400.215419 -358.093212) (xy 400.165807 -358.115871)
			(xy 400.113476 -358.13124) (xy 400.059491 -358.139004) (xy 400.03222 -358.139492) (xy 399.16862 -358.139492)
			(xy 399.14135 -358.13897) (xy 399.087365 -358.131211) (xy 399.035034 -358.115847) (xy 398.985423 -358.093193)
			(xy 398.93954 -358.063708) (xy 398.898321 -358.027993) (xy 398.862604 -357.986776) (xy 398.833117 -357.940895)
			(xy 398.81046 -357.891284) (xy 398.795094 -357.838954) (xy 398.787331 -357.78497) (xy 397.304628 -357.78497)
			(xy 397.304628 -357.784975) (xy 397.296865 -357.83897) (xy 397.281495 -357.89131) (xy 397.258833 -357.940929)
			(xy 397.229339 -357.986818) (xy 397.193615 -358.028043) (xy 397.152386 -358.063763) (xy 397.106494 -358.093252)
			(xy 397.056872 -358.115909) (xy 397.00453 -358.131273) (xy 396.950535 -358.139031) (xy 396.92326 -358.139492)
			(xy 396.05966 -358.139492) (xy 396.032395 -358.138943) (xy 395.97842 -358.131177) (xy 395.926099 -358.11581)
			(xy 395.876498 -358.093153) (xy 395.830625 -358.063668) (xy 395.789416 -358.027956) (xy 395.753708 -357.986742)
			(xy 395.724228 -357.940867) (xy 395.701576 -357.891263) (xy 395.686214 -357.838941) (xy 395.678454 -357.784965)
			(xy 394.195605 -357.784965) (xy 394.195605 -357.784972) (xy 394.187843 -357.838959) (xy 394.172477 -357.891293)
			(xy 394.149819 -357.940907) (xy 394.120331 -357.986792) (xy 394.084612 -358.028012) (xy 394.043392 -358.063731)
			(xy 393.997507 -358.093219) (xy 393.947893 -358.115877) (xy 393.895559 -358.131243) (xy 393.841572 -358.139005)
			(xy 393.8143 -358.139492) (xy 392.9507 -358.139492) (xy 392.923433 -358.138946) (xy 392.869453 -358.131185)
			(xy 392.817128 -358.11582) (xy 392.767522 -358.093166) (xy 392.721644 -358.063682) (xy 392.68043 -358.02797)
			(xy 392.644718 -357.986756) (xy 392.615234 -357.940878) (xy 392.59258 -357.891272) (xy 392.577215 -357.838947)
			(xy 392.569454 -357.784967) (xy 391.086606 -357.784967) (xy 391.086606 -357.78497) (xy 391.078844 -357.838954)
			(xy 391.06348 -357.891284) (xy 391.040825 -357.940896) (xy 391.01134 -357.986778) (xy 390.975627 -358.027998)
			(xy 390.934411 -358.063716) (xy 390.888531 -358.093206) (xy 390.838922 -358.115866) (xy 390.786593 -358.131236)
			(xy 390.73261 -358.139003) (xy 390.70534 -358.139492) (xy 389.84174 -358.139492) (xy 389.814469 -358.138971)
			(xy 389.760482 -358.131214) (xy 389.708149 -358.115853) (xy 389.658535 -358.093199) (xy 389.61265 -358.063715)
			(xy 389.571428 -358.028) (xy 389.535709 -357.986783) (xy 389.50622 -357.940901) (xy 389.483561 -357.891289)
			(xy 389.468194 -357.838957) (xy 389.460432 -357.784971) (xy 387.977728 -357.784971) (xy 387.977728 -357.784974)
			(xy 387.969965 -357.838967) (xy 387.954597 -357.891305) (xy 387.931936 -357.940924) (xy 387.902444 -357.986812)
			(xy 387.866722 -358.028036) (xy 387.825496 -358.063756) (xy 387.779606 -358.093245) (xy 387.729987 -358.115904)
			(xy 387.677647 -358.131269) (xy 387.623654 -358.13903) (xy 387.59638 -358.139492) (xy 386.73278 -358.139492)
			(xy 386.705514 -358.138944) (xy 386.651537 -358.131181) (xy 386.599213 -358.115815) (xy 386.54961 -358.093159)
			(xy 386.503735 -358.063675) (xy 386.462523 -358.027963) (xy 386.426813 -357.986749) (xy 386.397331 -357.940873)
			(xy 386.374678 -357.891268) (xy 386.359315 -357.838944) (xy 386.351554 -357.784966) (xy 384.868706 -357.784966)
			(xy 384.868706 -357.784971) (xy 384.860944 -357.838957) (xy 384.845578 -357.891289) (xy 384.822922 -357.940901)
			(xy 384.793435 -357.986785) (xy 384.75772 -358.028005) (xy 384.716501 -358.063723) (xy 384.670619 -358.093212)
			(xy 384.621007 -358.115871) (xy 384.568676 -358.13124) (xy 384.514691 -358.139004) (xy 384.48742 -358.139492)
			(xy 383.62382 -358.139492) (xy 383.59655 -358.13897) (xy 383.542565 -358.131211) (xy 383.490234 -358.115847)
			(xy 383.440623 -358.093193) (xy 383.39474 -358.063708) (xy 383.353521 -358.027993) (xy 383.317804 -357.986776)
			(xy 383.288317 -357.940895) (xy 383.26566 -357.891284) (xy 383.250294 -357.838954) (xy 383.242531 -357.78497)
			(xy 381.759828 -357.78497) (xy 381.759828 -357.784975) (xy 381.752065 -357.83897) (xy 381.736695 -357.89131)
			(xy 381.714033 -357.940929) (xy 381.684539 -357.986818) (xy 381.648815 -358.028043) (xy 381.607586 -358.063763)
			(xy 381.561694 -358.093252) (xy 381.512072 -358.115909) (xy 381.45973 -358.131273) (xy 381.405735 -358.139031)
			(xy 381.37846 -358.139492) (xy 380.51486 -358.139492) (xy 380.487595 -358.138943) (xy 380.43362 -358.131177)
			(xy 380.381299 -358.11581) (xy 380.331698 -358.093153) (xy 380.285825 -358.063668) (xy 380.244616 -358.027956)
			(xy 380.208908 -357.986742) (xy 380.179428 -357.940867) (xy 380.156776 -357.891263) (xy 380.141414 -357.838941)
			(xy 380.133654 -357.784965) (xy 378.650805 -357.784965) (xy 378.650805 -357.784972) (xy 378.643043 -357.838959)
			(xy 378.627677 -357.891293) (xy 378.605019 -357.940907) (xy 378.575531 -357.986792) (xy 378.539812 -358.028012)
			(xy 378.498592 -358.063731) (xy 378.452707 -358.093219) (xy 378.403093 -358.115877) (xy 378.350759 -358.131243)
			(xy 378.296772 -358.139005) (xy 378.2695 -358.139492) (xy 377.4059 -358.139492) (xy 377.378633 -358.138946)
			(xy 377.324653 -358.131185) (xy 377.272328 -358.11582) (xy 377.222722 -358.093166) (xy 377.176844 -358.063682)
			(xy 377.13563 -358.02797) (xy 377.099918 -357.986756) (xy 377.070434 -357.940878) (xy 377.04778 -357.891272)
			(xy 377.032415 -357.838947) (xy 377.024654 -357.784967) (xy 375.541806 -357.784967) (xy 375.541806 -357.78497)
			(xy 375.534044 -357.838954) (xy 375.51868 -357.891284) (xy 375.496025 -357.940896) (xy 375.46654 -357.986778)
			(xy 375.430827 -358.027998) (xy 375.389611 -358.063716) (xy 375.343731 -358.093206) (xy 375.294122 -358.115866)
			(xy 375.241793 -358.131236) (xy 375.18781 -358.139003) (xy 375.16054 -358.139492) (xy 374.29694 -358.139492)
			(xy 374.269669 -358.138971) (xy 374.215682 -358.131214) (xy 374.163349 -358.115853) (xy 374.113735 -358.093199)
			(xy 374.06785 -358.063715) (xy 374.026628 -358.028) (xy 373.990909 -357.986783) (xy 373.96142 -357.940901)
			(xy 373.938761 -357.891289) (xy 373.923394 -357.838957) (xy 373.915632 -357.784971) (xy 344.837306 -357.784971)
			(xy 344.829543 -357.838959) (xy 344.814177 -357.891292) (xy 344.791519 -357.940906) (xy 344.762031 -357.98679)
			(xy 344.726314 -358.028011) (xy 344.685093 -358.063729) (xy 344.639209 -358.093217) (xy 344.589596 -358.115876)
			(xy 344.537263 -358.131242) (xy 344.483275 -358.139005) (xy 344.456004 -358.139492) (xy 343.592404 -358.139492)
			(xy 343.565135 -358.138969) (xy 343.511152 -358.131208) (xy 343.458823 -358.115843) (xy 343.409213 -358.093188)
			(xy 343.363333 -358.063702) (xy 343.322115 -358.027988) (xy 343.2864 -357.986771) (xy 343.256914 -357.94089)
			(xy 343.234258 -357.891281) (xy 343.218893 -357.838952) (xy 343.211131 -357.784969) (xy 341.728306 -357.784969)
			(xy 341.728306 -357.78497) (xy 341.720544 -357.838953) (xy 341.70518 -357.891284) (xy 341.682525 -357.940895)
			(xy 341.653041 -357.986777) (xy 341.617328 -358.027997) (xy 341.576112 -358.063715) (xy 341.530233 -358.093204)
			(xy 341.480625 -358.115865) (xy 341.428297 -358.131235) (xy 341.374313 -358.139002) (xy 341.347044 -358.139492)
			(xy 340.483444 -358.139492) (xy 340.456173 -358.138972) (xy 340.402186 -358.131215) (xy 340.349852 -358.115854)
			(xy 340.300237 -358.093201) (xy 340.254351 -358.063716) (xy 340.213129 -358.028002) (xy 340.17741 -357.986784)
			(xy 340.147921 -357.940902) (xy 340.125261 -357.891289) (xy 340.109894 -357.838957) (xy 340.102132 -357.784971)
			(xy 338.619428 -357.784971) (xy 338.619428 -357.784974) (xy 338.611665 -357.838966) (xy 338.596297 -357.891304)
			(xy 338.573636 -357.940923) (xy 338.544145 -357.986811) (xy 338.508423 -358.028034) (xy 338.467198 -358.063755)
			(xy 338.421308 -358.093244) (xy 338.371689 -358.115903) (xy 338.319351 -358.131269) (xy 338.265358 -358.13903)
			(xy 338.238084 -358.139492) (xy 337.374484 -358.139492) (xy 337.347218 -358.138945) (xy 337.29324 -358.131182)
			(xy 337.240916 -358.115816) (xy 337.191312 -358.093161) (xy 337.145437 -358.063677) (xy 337.104224 -358.027964)
			(xy 337.068514 -357.98675) (xy 337.039032 -357.940874) (xy 337.016378 -357.891269) (xy 337.001015 -357.838944)
			(xy 336.993254 -357.784967) (xy 335.510406 -357.784967) (xy 335.510406 -357.78497) (xy 335.502644 -357.838956)
			(xy 335.487279 -357.891288) (xy 335.464622 -357.9409) (xy 335.435136 -357.986784) (xy 335.399421 -358.028004)
			(xy 335.358203 -358.063722) (xy 335.312321 -358.093211) (xy 335.26271 -358.11587) (xy 335.21038 -358.131239)
			(xy 335.156394 -358.139004) (xy 335.129124 -358.139492) (xy 334.265524 -358.139492) (xy 334.238254 -358.13897)
			(xy 334.184269 -358.131211) (xy 334.131937 -358.115848) (xy 334.082325 -358.093194) (xy 334.036442 -358.063709)
			(xy 333.995222 -358.027995) (xy 333.959505 -357.986777) (xy 333.930017 -357.940896) (xy 333.90736 -357.891285)
			(xy 333.891994 -357.838955) (xy 333.884231 -357.78497) (xy 332.401528 -357.78497) (xy 332.401528 -357.784975)
			(xy 332.393765 -357.838969) (xy 332.378395 -357.891309) (xy 332.355733 -357.940928) (xy 332.32624 -357.986817)
			(xy 332.290516 -358.028041) (xy 332.249288 -358.063762) (xy 332.203397 -358.093251) (xy 332.153775 -358.115908)
			(xy 332.101434 -358.131272) (xy 332.047439 -358.139031) (xy 332.020164 -358.139492) (xy 331.156564 -358.139492)
			(xy 331.129298 -358.138943) (xy 331.075323 -358.131178) (xy 331.023002 -358.115811) (xy 330.9734 -358.093154)
			(xy 330.927527 -358.06367) (xy 330.886317 -358.027957) (xy 330.850609 -357.986744) (xy 330.821128 -357.940868)
			(xy 330.798477 -357.891264) (xy 330.783114 -357.838942) (xy 330.775354 -357.784966) (xy 329.292506 -357.784966)
			(xy 329.292506 -357.784971) (xy 329.284743 -357.838959) (xy 329.269377 -357.891292) (xy 329.246719 -357.940906)
			(xy 329.217231 -357.98679) (xy 329.181514 -358.028011) (xy 329.140293 -358.063729) (xy 329.094409 -358.093217)
			(xy 329.044796 -358.115876) (xy 328.992463 -358.131242) (xy 328.938475 -358.139005) (xy 328.911204 -358.139492)
			(xy 328.047604 -358.139492) (xy 328.020335 -358.138969) (xy 327.966352 -358.131208) (xy 327.914023 -358.115843)
			(xy 327.864413 -358.093188) (xy 327.818533 -358.063702) (xy 327.777315 -358.027988) (xy 327.7416 -357.986771)
			(xy 327.712114 -357.94089) (xy 327.689458 -357.891281) (xy 327.674093 -357.838952) (xy 327.666331 -357.784969)
			(xy 326.183506 -357.784969) (xy 326.183506 -357.78497) (xy 326.175744 -357.838953) (xy 326.16038 -357.891284)
			(xy 326.137725 -357.940895) (xy 326.108241 -357.986777) (xy 326.072528 -358.027997) (xy 326.031312 -358.063715)
			(xy 325.985433 -358.093204) (xy 325.935825 -358.115865) (xy 325.883497 -358.131235) (xy 325.829513 -358.139002)
			(xy 325.802244 -358.139492) (xy 324.938644 -358.139492) (xy 324.911373 -358.138972) (xy 324.857386 -358.131215)
			(xy 324.805052 -358.115854) (xy 324.755437 -358.093201) (xy 324.709551 -358.063716) (xy 324.668329 -358.028002)
			(xy 324.63261 -357.986784) (xy 324.603121 -357.940902) (xy 324.580461 -357.891289) (xy 324.565094 -357.838957)
			(xy 324.557332 -357.784971) (xy 323.074628 -357.784971) (xy 323.074628 -357.784974) (xy 323.066865 -357.838966)
			(xy 323.051497 -357.891304) (xy 323.028836 -357.940923) (xy 322.999345 -357.986811) (xy 322.963623 -358.028034)
			(xy 322.922398 -358.063755) (xy 322.876508 -358.093244) (xy 322.826889 -358.115903) (xy 322.774551 -358.131269)
			(xy 322.720558 -358.13903) (xy 322.693284 -358.139492) (xy 321.829684 -358.139492) (xy 321.802418 -358.138945)
			(xy 321.74844 -358.131182) (xy 321.696116 -358.115816) (xy 321.646512 -358.093161) (xy 321.600637 -358.063677)
			(xy 321.559424 -358.027964) (xy 321.523714 -357.98675) (xy 321.494232 -357.940874) (xy 321.471578 -357.891269)
			(xy 321.456215 -357.838944) (xy 321.448454 -357.784967) (xy 319.965606 -357.784967) (xy 319.965606 -357.78497)
			(xy 319.957844 -357.838956) (xy 319.942479 -357.891288) (xy 319.919822 -357.9409) (xy 319.890336 -357.986784)
			(xy 319.854621 -358.028004) (xy 319.813403 -358.063722) (xy 319.767521 -358.093211) (xy 319.71791 -358.11587)
			(xy 319.66558 -358.131239) (xy 319.611594 -358.139004) (xy 319.584324 -358.139492) (xy 318.720724 -358.139492)
			(xy 318.693454 -358.13897) (xy 318.639469 -358.131211) (xy 318.587137 -358.115848) (xy 318.537525 -358.093194)
			(xy 318.491642 -358.063709) (xy 318.450422 -358.027995) (xy 318.414705 -357.986777) (xy 318.385217 -357.940896)
			(xy 318.36256 -357.891285) (xy 318.347194 -357.838955) (xy 318.339431 -357.78497) (xy 316.856728 -357.78497)
			(xy 316.856728 -357.784975) (xy 316.848965 -357.838969) (xy 316.833595 -357.891309) (xy 316.810933 -357.940928)
			(xy 316.78144 -357.986817) (xy 316.745716 -358.028041) (xy 316.704488 -358.063762) (xy 316.658597 -358.093251)
			(xy 316.608975 -358.115908) (xy 316.556634 -358.131272) (xy 316.502639 -358.139031) (xy 316.475364 -358.139492)
			(xy 315.611764 -358.139492) (xy 315.584498 -358.138943) (xy 315.530523 -358.131178) (xy 315.478202 -358.115811)
			(xy 315.4286 -358.093154) (xy 315.382727 -358.06367) (xy 315.341517 -358.027957) (xy 315.305809 -357.986744)
			(xy 315.276328 -357.940868) (xy 315.253677 -357.891264) (xy 315.238314 -357.838942) (xy 315.230554 -357.784966)
			(xy 300.231606 -357.784966) (xy 300.231606 -357.784971) (xy 300.223843 -357.838959) (xy 300.208477 -357.891293)
			(xy 300.185819 -357.940907) (xy 300.156331 -357.986791) (xy 300.120613 -358.028012) (xy 300.079393 -358.06373)
			(xy 300.033508 -358.093218) (xy 299.983894 -358.115876) (xy 299.931561 -358.131243) (xy 299.877573 -358.139005)
			(xy 299.850302 -358.139492) (xy 298.986702 -358.139492) (xy 298.959433 -358.138969) (xy 298.90545 -358.131207)
			(xy 298.853121 -358.115843) (xy 298.803512 -358.093187) (xy 298.757632 -358.063702) (xy 298.716414 -358.027987)
			(xy 298.6807 -357.98677) (xy 298.651214 -357.94089) (xy 298.628558 -357.89128) (xy 298.613193 -357.838952)
			(xy 298.605431 -357.784969) (xy 297.122606 -357.784969) (xy 297.122606 -357.78497) (xy 297.114844 -357.838954)
			(xy 297.09948 -357.891284) (xy 297.076825 -357.940895) (xy 297.047341 -357.986778) (xy 297.011627 -358.027998)
			(xy 296.970411 -358.063716) (xy 296.924532 -358.093205) (xy 296.874923 -358.115865) (xy 296.822595 -358.131235)
			(xy 296.768612 -358.139003) (xy 296.741342 -358.139492) (xy 295.877742 -358.139492) (xy 295.850471 -358.138971)
			(xy 295.796484 -358.131215) (xy 295.74415 -358.115853) (xy 295.694536 -358.0932) (xy 295.64865 -358.063716)
			(xy 295.607429 -358.028001) (xy 295.571709 -357.986783) (xy 295.54222 -357.940901) (xy 295.519561 -357.891289)
			(xy 295.504194 -357.838957) (xy 295.496432 -357.784971) (xy 294.013728 -357.784971) (xy 294.013728 -357.784974)
			(xy 294.005965 -357.838967) (xy 293.990597 -357.891305) (xy 293.967936 -357.940923) (xy 293.938444 -357.986811)
			(xy 293.902722 -358.028035) (xy 293.861497 -358.063755) (xy 293.815607 -358.093245) (xy 293.765988 -358.115903)
			(xy 293.713649 -358.131269) (xy 293.659656 -358.13903) (xy 293.632382 -358.139492) (xy 292.768782 -358.139492)
			(xy 292.741516 -358.138944) (xy 292.687538 -358.131181) (xy 292.635215 -358.115816) (xy 292.585611 -358.09316)
			(xy 292.539736 -358.063676) (xy 292.498524 -358.027964) (xy 292.462813 -357.98675) (xy 292.433331 -357.940873)
			(xy 292.410678 -357.891268) (xy 292.395315 -357.838944) (xy 292.387554 -357.784966) (xy 290.904706 -357.784966)
			(xy 290.904706 -357.784971) (xy 290.896944 -357.838956) (xy 290.881578 -357.891288) (xy 290.858922 -357.940901)
			(xy 290.829436 -357.986784) (xy 290.79372 -358.028005) (xy 290.752502 -358.063723) (xy 290.70662 -358.093211)
			(xy 290.657009 -358.115871) (xy 290.604678 -358.131239) (xy 290.550692 -358.139004) (xy 290.523422 -358.139492)
			(xy 289.659822 -358.139492) (xy 289.632552 -358.13897) (xy 289.578567 -358.131211) (xy 289.526236 -358.115848)
			(xy 289.476624 -358.093193) (xy 289.430741 -358.063709) (xy 289.389522 -358.027994) (xy 289.353805 -357.986777)
			(xy 289.324317 -357.940895) (xy 289.30166 -357.891285) (xy 289.286294 -357.838954) (xy 289.278531 -357.78497)
			(xy 287.795828 -357.78497) (xy 287.795828 -357.784975) (xy 287.788065 -357.838969) (xy 287.772695 -357.891309)
			(xy 287.750033 -357.940929) (xy 287.72054 -357.986818) (xy 287.684815 -358.028042) (xy 287.643587 -358.063762)
			(xy 287.597695 -358.093251) (xy 287.548073 -358.115908) (xy 287.495732 -358.131273) (xy 287.441737 -358.139031)
			(xy 287.414462 -358.139492) (xy 286.550862 -358.139492) (xy 286.523597 -358.138943) (xy 286.469621 -358.131178)
			(xy 286.4173 -358.11581) (xy 286.367699 -358.093154) (xy 286.321826 -358.063669) (xy 286.280617 -358.027957)
			(xy 286.244908 -357.986743) (xy 286.215428 -357.940868) (xy 286.192777 -357.891264) (xy 286.177414 -357.838942)
			(xy 286.169654 -357.784966) (xy 284.686806 -357.784966) (xy 284.686806 -357.784971) (xy 284.679043 -357.838959)
			(xy 284.663677 -357.891293) (xy 284.641019 -357.940907) (xy 284.611531 -357.986791) (xy 284.575813 -358.028012)
			(xy 284.534593 -358.06373) (xy 284.488708 -358.093218) (xy 284.439094 -358.115876) (xy 284.386761 -358.131243)
			(xy 284.332773 -358.139005) (xy 284.305502 -358.139492) (xy 283.441902 -358.139492) (xy 283.414633 -358.138969)
			(xy 283.36065 -358.131207) (xy 283.308321 -358.115843) (xy 283.258712 -358.093187) (xy 283.212832 -358.063702)
			(xy 283.171614 -358.027987) (xy 283.1359 -357.98677) (xy 283.106414 -357.94089) (xy 283.083758 -357.89128)
			(xy 283.068393 -357.838952) (xy 283.060631 -357.784969) (xy 281.577806 -357.784969) (xy 281.577806 -357.78497)
			(xy 281.570044 -357.838954) (xy 281.55468 -357.891284) (xy 281.532025 -357.940895) (xy 281.502541 -357.986778)
			(xy 281.466827 -358.027998) (xy 281.425611 -358.063716) (xy 281.379732 -358.093205) (xy 281.330123 -358.115865)
			(xy 281.277795 -358.131235) (xy 281.223812 -358.139003) (xy 281.196542 -358.139492) (xy 280.332942 -358.139492)
			(xy 280.305671 -358.138971) (xy 280.251684 -358.131215) (xy 280.19935 -358.115853) (xy 280.149736 -358.0932)
			(xy 280.10385 -358.063716) (xy 280.062629 -358.028001) (xy 280.026909 -357.986783) (xy 279.99742 -357.940901)
			(xy 279.974761 -357.891289) (xy 279.959394 -357.838957) (xy 279.951632 -357.784971) (xy 278.468928 -357.784971)
			(xy 278.468928 -357.784974) (xy 278.461165 -357.838967) (xy 278.445797 -357.891305) (xy 278.423136 -357.940923)
			(xy 278.393644 -357.986811) (xy 278.357922 -358.028035) (xy 278.316697 -358.063755) (xy 278.270807 -358.093245)
			(xy 278.221188 -358.115903) (xy 278.168849 -358.131269) (xy 278.114856 -358.13903) (xy 278.087582 -358.139492)
			(xy 277.223982 -358.139492) (xy 277.196716 -358.138944) (xy 277.142738 -358.131181) (xy 277.090415 -358.115816)
			(xy 277.040811 -358.09316) (xy 276.994936 -358.063676) (xy 276.953724 -358.027964) (xy 276.918013 -357.98675)
			(xy 276.888531 -357.940873) (xy 276.865878 -357.891268) (xy 276.850515 -357.838944) (xy 276.842754 -357.784966)
			(xy 275.359906 -357.784966) (xy 275.359906 -357.784971) (xy 275.352144 -357.838956) (xy 275.336778 -357.891288)
			(xy 275.314122 -357.940901) (xy 275.284636 -357.986784) (xy 275.24892 -358.028005) (xy 275.207702 -358.063723)
			(xy 275.16182 -358.093211) (xy 275.112209 -358.115871) (xy 275.059878 -358.131239) (xy 275.005892 -358.139004)
			(xy 274.978622 -358.139492) (xy 274.115022 -358.139492) (xy 274.087752 -358.13897) (xy 274.033767 -358.131211)
			(xy 273.981436 -358.115848) (xy 273.931824 -358.093193) (xy 273.885941 -358.063709) (xy 273.844722 -358.027994)
			(xy 273.809005 -357.986777) (xy 273.779517 -357.940895) (xy 273.75686 -357.891285) (xy 273.741494 -357.838954)
			(xy 273.733731 -357.78497) (xy 272.251028 -357.78497) (xy 272.251028 -357.784975) (xy 272.243265 -357.838969)
			(xy 272.227895 -357.891309) (xy 272.205233 -357.940929) (xy 272.17574 -357.986818) (xy 272.140015 -358.028042)
			(xy 272.098787 -358.063762) (xy 272.052895 -358.093251) (xy 272.003273 -358.115908) (xy 271.950932 -358.131273)
			(xy 271.896937 -358.139031) (xy 271.869662 -358.139492) (xy 271.006062 -358.139492) (xy 270.978797 -358.138943)
			(xy 270.924821 -358.131178) (xy 270.8725 -358.11581) (xy 270.822899 -358.093154) (xy 270.777026 -358.063669)
			(xy 270.735817 -358.027957) (xy 270.700108 -357.986743) (xy 270.670628 -357.940868) (xy 270.647977 -357.891264)
			(xy 270.632614 -357.838942) (xy 270.624854 -357.784966) (xy 247.276485 -357.784966) (xy 247.278987 -357.797946)
			(xy 247.287038 -357.88226) (xy 247.287542 -357.924608) (xy 247.287038 -357.966956) (xy 247.278987 -358.05127)
			(xy 247.262958 -358.134436) (xy 247.239097 -358.215703) (xy 247.207618 -358.294333) (xy 247.168807 -358.369614)
			(xy 247.123017 -358.440866) (xy 247.070661 -358.507442) (xy 247.012213 -358.56874) (xy 246.948203 -358.624205)
			(xy 246.879211 -358.673334) (xy 246.805861 -358.715683) (xy 246.728818 -358.750867) (xy 246.648779 -358.778569)
			(xy 246.56647 -358.798537) (xy 246.482635 -358.81059) (xy 246.398034 -358.814621) (xy 246.313433 -358.81059)
			(xy 246.229598 -358.798537) (xy 246.147289 -358.778569) (xy 246.06725 -358.750867) (xy 245.990207 -358.715683)
			(xy 245.916857 -358.673334) (xy 245.847865 -358.624205) (xy 245.783855 -358.56874) (xy 245.725407 -358.507442)
			(xy 245.673051 -358.440866) (xy 245.627261 -358.369614) (xy 245.58845 -358.294333) (xy 245.556971 -358.215703)
			(xy 245.53311 -358.134436) (xy 245.517081 -358.05127) (xy 245.50903 -357.966956) (xy 188.223925 -357.966956)
			(xy 188.191672 -358.004178) (xy 188.150456 -358.039891) (xy 188.104577 -358.069375) (xy 188.054969 -358.092029)
			(xy 188.002641 -358.107393) (xy 187.94866 -358.115153) (xy 187.921392 -358.115616) (xy 187.057792 -358.115616)
			(xy 187.03052 -358.115221) (xy 186.97653 -358.107457) (xy 186.924196 -358.092089) (xy 186.87458 -358.06943)
			(xy 186.828695 -358.03994) (xy 186.787473 -358.004221) (xy 186.751755 -357.962999) (xy 186.722266 -357.917112)
			(xy 186.699608 -357.867497) (xy 186.684241 -357.815162) (xy 186.676479 -357.761172) (xy 185.193629 -357.761172)
			(xy 185.18587 -357.815139) (xy 185.170508 -357.86746) (xy 185.147857 -357.917062) (xy 185.118378 -357.962936)
			(xy 185.08267 -358.004147) (xy 185.041461 -358.039858) (xy 184.99559 -358.069342) (xy 184.94599 -358.091997)
			(xy 184.89367 -358.107363) (xy 184.839697 -358.115128) (xy 184.812432 -358.115616) (xy 183.948832 -358.115616)
			(xy 183.921556 -358.115247) (xy 183.867559 -358.107487) (xy 183.815217 -358.092122) (xy 183.765593 -358.069463)
			(xy 183.7197 -358.039973) (xy 183.678471 -358.004251) (xy 183.642746 -357.963025) (xy 183.613252 -357.917135)
			(xy 183.590589 -357.867513) (xy 183.57522 -357.815172) (xy 183.567456 -357.761176) (xy 182.084828 -357.761176)
			(xy 182.084828 -357.784974) (xy 182.077065 -357.838968) (xy 182.061696 -357.891307) (xy 182.039035 -357.940926)
			(xy 182.009542 -357.986815) (xy 181.973819 -358.028039) (xy 181.932592 -358.063759) (xy 181.886701 -358.093248)
			(xy 181.837081 -358.115906) (xy 181.784741 -358.131271) (xy 181.730746 -358.13903) (xy 181.703472 -358.139492)
			(xy 180.839872 -358.139492) (xy 180.812606 -358.138944) (xy 180.75863 -358.131179) (xy 180.706308 -358.115813)
			(xy 180.656705 -358.093157) (xy 180.610831 -358.063673) (xy 180.56962 -358.02796) (xy 180.533911 -357.986746)
			(xy 180.50443 -357.94087) (xy 180.481777 -357.891266) (xy 180.466415 -357.838943) (xy 180.458654 -357.784966)
			(xy 178.975806 -357.784966) (xy 178.975806 -357.784971) (xy 178.968044 -357.838958) (xy 178.952678 -357.89129)
			(xy 178.930021 -357.940904) (xy 178.900533 -357.986788) (xy 178.864817 -358.028008) (xy 178.823597 -358.063726)
			(xy 178.777714 -358.093215) (xy 178.728102 -358.115873) (xy 178.675769 -358.131241) (xy 178.621783 -358.139005)
			(xy 178.594512 -358.139492) (xy 177.730912 -358.139492) (xy 177.703643 -358.138969) (xy 177.649659 -358.131209)
			(xy 177.597329 -358.115845) (xy 177.547718 -358.09319) (xy 177.501836 -358.063705) (xy 177.460618 -358.027991)
			(xy 177.424902 -357.986773) (xy 177.395416 -357.940893) (xy 177.372759 -357.891283) (xy 177.357393 -357.838953)
			(xy 177.349631 -357.784969) (xy 175.866928 -357.784969) (xy 175.866928 -357.784975) (xy 175.859164 -357.838971)
			(xy 175.843794 -357.891311) (xy 175.821132 -357.940932) (xy 175.791637 -357.986821) (xy 175.755912 -358.028046)
			(xy 175.714683 -358.063766) (xy 175.668789 -358.093255) (xy 175.619166 -358.115911) (xy 175.566824 -358.131275)
			(xy 175.512827 -358.139032) (xy 175.485552 -358.139492) (xy 174.621952 -358.139492) (xy 174.594687 -358.138942)
			(xy 174.540713 -358.131176) (xy 174.488393 -358.115807) (xy 174.438793 -358.09315) (xy 174.392922 -358.063665)
			(xy 174.351713 -358.027953) (xy 174.316006 -357.98674) (xy 174.286527 -357.940865) (xy 174.263876 -357.891262)
			(xy 174.248514 -357.83894) (xy 174.240754 -357.784965) (xy 172.757928 -357.784965) (xy 172.757928 -357.784974)
			(xy 172.750165 -357.838965) (xy 172.734798 -357.891303) (xy 172.712138 -357.94092) (xy 172.682647 -357.986808)
			(xy 172.646926 -358.028032) (xy 172.605702 -358.063752) (xy 172.559813 -358.093241) (xy 172.510195 -358.1159)
			(xy 172.457857 -358.131267) (xy 172.403866 -358.139029) (xy 172.376592 -358.139492) (xy 171.512992 -358.139492)
			(xy 171.485725 -358.138945) (xy 171.431747 -358.131183) (xy 171.379422 -358.115818) (xy 171.329817 -358.093163)
			(xy 171.283941 -358.06368) (xy 171.242727 -358.027967) (xy 171.207016 -357.986753) (xy 171.177533 -357.940876)
			(xy 171.154879 -357.89127) (xy 171.139515 -357.838946) (xy 171.131754 -357.784967) (xy 169.648906 -357.784967)
			(xy 169.648906 -357.78497) (xy 169.641144 -357.838955) (xy 169.625779 -357.891286) (xy 169.603124 -357.940898)
			(xy 169.573638 -357.986781) (xy 169.537924 -358.028001) (xy 169.496707 -358.063719) (xy 169.450826 -358.093208)
			(xy 169.401216 -358.115868) (xy 169.348886 -358.131237) (xy 169.294902 -358.139003) (xy 169.267632 -358.139492)
			(xy 168.404032 -358.139492) (xy 168.376762 -358.138971) (xy 168.322776 -358.131213) (xy 168.270443 -358.115851)
			(xy 168.22083 -358.093197) (xy 168.174946 -358.063712) (xy 168.133725 -358.027998) (xy 168.098007 -357.98678)
			(xy 168.068519 -357.940898) (xy 168.045861 -357.891287) (xy 168.030494 -357.838956) (xy 168.022732 -357.78497)
			(xy 166.540028 -357.78497) (xy 166.540028 -357.784974) (xy 166.532265 -357.838968) (xy 166.516896 -357.891307)
			(xy 166.494235 -357.940926) (xy 166.464742 -357.986815) (xy 166.429019 -358.028039) (xy 166.387792 -358.063759)
			(xy 166.341901 -358.093248) (xy 166.292281 -358.115906) (xy 166.239941 -358.131271) (xy 166.185946 -358.13903)
			(xy 166.158672 -358.139492) (xy 165.295072 -358.139492) (xy 165.267806 -358.138944) (xy 165.21383 -358.131179)
			(xy 165.161508 -358.115813) (xy 165.111905 -358.093157) (xy 165.066031 -358.063673) (xy 165.02482 -358.02796)
			(xy 164.989111 -357.986746) (xy 164.95963 -357.94087) (xy 164.936977 -357.891266) (xy 164.921615 -357.838943)
			(xy 164.913854 -357.784966) (xy 163.431006 -357.784966) (xy 163.431006 -357.784971) (xy 163.423244 -357.838958)
			(xy 163.407878 -357.89129) (xy 163.385221 -357.940904) (xy 163.355733 -357.986788) (xy 163.320017 -358.028008)
			(xy 163.278797 -358.063726) (xy 163.232914 -358.093215) (xy 163.183302 -358.115873) (xy 163.130969 -358.131241)
			(xy 163.076983 -358.139005) (xy 163.049712 -358.139492) (xy 162.186112 -358.139492) (xy 162.158843 -358.138969)
			(xy 162.104859 -358.131209) (xy 162.052529 -358.115845) (xy 162.002918 -358.09319) (xy 161.957036 -358.063705)
			(xy 161.915818 -358.027991) (xy 161.880102 -357.986773) (xy 161.850616 -357.940893) (xy 161.827959 -357.891283)
			(xy 161.812593 -357.838953) (xy 161.804831 -357.784969) (xy 160.322128 -357.784969) (xy 160.322128 -357.784975)
			(xy 160.314364 -357.838971) (xy 160.298994 -357.891311) (xy 160.276332 -357.940932) (xy 160.246837 -357.986821)
			(xy 160.211112 -358.028046) (xy 160.169883 -358.063766) (xy 160.123989 -358.093255) (xy 160.074366 -358.115911)
			(xy 160.022024 -358.131275) (xy 159.968027 -358.139032) (xy 159.940752 -358.139492) (xy 159.077152 -358.139492)
			(xy 159.049887 -358.138942) (xy 158.995913 -358.131176) (xy 158.943593 -358.115807) (xy 158.893993 -358.09315)
			(xy 158.848122 -358.063665) (xy 158.806913 -358.027953) (xy 158.771206 -357.98674) (xy 158.741727 -357.940865)
			(xy 158.719076 -357.891262) (xy 158.703714 -357.83894) (xy 158.695954 -357.784965) (xy 144.196606 -357.784965)
			(xy 144.196606 -357.784971) (xy 144.188843 -357.838958) (xy 144.173477 -357.891291) (xy 144.15082 -357.940905)
			(xy 144.121332 -357.986789) (xy 144.085615 -358.02801) (xy 144.044395 -358.063728) (xy 143.998512 -358.093216)
			(xy 143.948899 -358.115875) (xy 143.896566 -358.131242) (xy 143.842579 -358.139005) (xy 143.815308 -358.139492)
			(xy 142.951708 -358.139492) (xy 142.924439 -358.138969) (xy 142.870455 -358.131209) (xy 142.818126 -358.115844)
			(xy 142.768515 -358.093189) (xy 142.722634 -358.063704) (xy 142.681417 -358.027989) (xy 142.645701 -357.986772)
			(xy 142.616215 -357.940892) (xy 142.593559 -357.891282) (xy 142.578193 -357.838953) (xy 142.570431 -357.784969)
			(xy 141.087606 -357.784969) (xy 141.079845 -357.838953) (xy 141.06448 -357.891283) (xy 141.041826 -357.940894)
			(xy 141.012342 -357.986776) (xy 140.976629 -358.027995) (xy 140.935414 -358.063713) (xy 140.889536 -358.093203)
			(xy 140.839928 -358.115864) (xy 140.7876 -358.131234) (xy 140.733617 -358.139002) (xy 140.706348 -358.139492)
			(xy 139.842748 -358.139492) (xy 139.815477 -358.138972) (xy 139.761489 -358.131216) (xy 139.709155 -358.115855)
			(xy 139.659539 -358.093202) (xy 139.613653 -358.063718) (xy 139.572431 -358.028003) (xy 139.536711 -357.986785)
			(xy 139.507221 -357.940903) (xy 139.484562 -357.89129) (xy 139.469194 -357.838958) (xy 139.461432 -357.784971)
			(xy 137.978728 -357.784971) (xy 137.978728 -357.784974) (xy 137.970965 -357.838966) (xy 137.955597 -357.891304)
			(xy 137.932937 -357.940921) (xy 137.903446 -357.986809) (xy 137.867724 -358.028033) (xy 137.8265 -358.063753)
			(xy 137.780611 -358.093243) (xy 137.730992 -358.115901) (xy 137.678654 -358.131268) (xy 137.624662 -358.139029)
			(xy 137.597388 -358.139492) (xy 136.733788 -358.139492) (xy 136.706521 -358.138945) (xy 136.652543 -358.131182)
			(xy 136.600219 -358.115817) (xy 136.550615 -358.093162) (xy 136.504739 -358.063678) (xy 136.463526 -358.027966)
			(xy 136.427815 -357.986752) (xy 136.398332 -357.940875) (xy 136.375679 -357.891269) (xy 136.360315 -357.838945)
			(xy 136.352554 -357.784967) (xy 134.869706 -357.784967) (xy 134.869706 -357.78497) (xy 134.861944 -357.838956)
			(xy 134.846579 -357.891287) (xy 134.823923 -357.940899) (xy 134.794437 -357.986782) (xy 134.758722 -358.028003)
			(xy 134.717505 -358.063721) (xy 134.671624 -358.09321) (xy 134.622013 -358.115869) (xy 134.569683 -358.131238)
			(xy 134.515698 -358.139004) (xy 134.488428 -358.139492) (xy 133.624828 -358.139492) (xy 133.597558 -358.13897)
			(xy 133.543572 -358.131212) (xy 133.49124 -358.11585) (xy 133.441627 -358.093195) (xy 133.395744 -358.063711)
			(xy 133.354524 -358.027996) (xy 133.318806 -357.986779) (xy 133.289318 -357.940897) (xy 133.26666 -357.891286)
			(xy 133.251294 -357.838955) (xy 133.243531 -357.78497) (xy 131.760828 -357.78497) (xy 131.760828 -357.784975)
			(xy 131.753065 -357.838969) (xy 131.737696 -357.891308) (xy 131.715034 -357.940927) (xy 131.685541 -357.986816)
			(xy 131.649817 -358.02804) (xy 131.60859 -358.06376) (xy 131.562699 -358.093249) (xy 131.513078 -358.115907)
			(xy 131.460737 -358.131272) (xy 131.406743 -358.139031) (xy 131.379468 -358.139492) (xy 130.515868 -358.139492)
			(xy 130.488602 -358.138943) (xy 130.434626 -358.131179) (xy 130.382305 -358.115812) (xy 130.332703 -358.093156)
			(xy 130.286829 -358.063671) (xy 130.245619 -358.027959) (xy 130.20991 -357.986745) (xy 130.180429 -357.940869)
			(xy 130.157777 -357.891265) (xy 130.142414 -357.838942) (xy 130.134654 -357.784966) (xy 128.651806 -357.784966)
			(xy 128.651806 -357.784971) (xy 128.644043 -357.838958) (xy 128.628677 -357.891291) (xy 128.60602 -357.940905)
			(xy 128.576532 -357.986789) (xy 128.540815 -358.02801) (xy 128.499595 -358.063728) (xy 128.453712 -358.093216)
			(xy 128.404099 -358.115875) (xy 128.351766 -358.131242) (xy 128.297779 -358.139005) (xy 128.270508 -358.139492)
			(xy 127.406908 -358.139492) (xy 127.379639 -358.138969) (xy 127.325655 -358.131209) (xy 127.273326 -358.115844)
			(xy 127.223715 -358.093189) (xy 127.177834 -358.063704) (xy 127.136617 -358.027989) (xy 127.100901 -357.986772)
			(xy 127.071415 -357.940892) (xy 127.048759 -357.891282) (xy 127.033393 -357.838953) (xy 127.025631 -357.784969)
			(xy 125.542806 -357.784969) (xy 125.535045 -357.838953) (xy 125.51968 -357.891283) (xy 125.497026 -357.940894)
			(xy 125.467542 -357.986776) (xy 125.431829 -358.027995) (xy 125.390614 -358.063713) (xy 125.344736 -358.093203)
			(xy 125.295128 -358.115864) (xy 125.2428 -358.131234) (xy 125.188817 -358.139002) (xy 125.161548 -358.139492)
			(xy 124.297948 -358.139492) (xy 124.270677 -358.138972) (xy 124.216689 -358.131216) (xy 124.164355 -358.115855)
			(xy 124.114739 -358.093202) (xy 124.068853 -358.063718) (xy 124.027631 -358.028003) (xy 123.991911 -357.986785)
			(xy 123.962421 -357.940903) (xy 123.939762 -357.89129) (xy 123.924394 -357.838958) (xy 123.916632 -357.784971)
			(xy 122.433928 -357.784971) (xy 122.433928 -357.784974) (xy 122.426165 -357.838966) (xy 122.410797 -357.891304)
			(xy 122.388137 -357.940921) (xy 122.358646 -357.986809) (xy 122.322924 -358.028033) (xy 122.2817 -358.063753)
			(xy 122.235811 -358.093243) (xy 122.186192 -358.115901) (xy 122.133854 -358.131268) (xy 122.079862 -358.139029)
			(xy 122.052588 -358.139492) (xy 121.188988 -358.139492) (xy 121.161721 -358.138945) (xy 121.107743 -358.131182)
			(xy 121.055419 -358.115817) (xy 121.005815 -358.093162) (xy 120.959939 -358.063678) (xy 120.918726 -358.027966)
			(xy 120.883015 -357.986752) (xy 120.853532 -357.940875) (xy 120.830879 -357.891269) (xy 120.815515 -357.838945)
			(xy 120.807754 -357.784967) (xy 119.324906 -357.784967) (xy 119.324906 -357.78497) (xy 119.317144 -357.838956)
			(xy 119.301779 -357.891287) (xy 119.279123 -357.940899) (xy 119.249637 -357.986782) (xy 119.213922 -358.028003)
			(xy 119.172705 -358.063721) (xy 119.126824 -358.09321) (xy 119.077213 -358.115869) (xy 119.024883 -358.131238)
			(xy 118.970898 -358.139004) (xy 118.943628 -358.139492) (xy 118.080028 -358.139492) (xy 118.052758 -358.13897)
			(xy 117.998772 -358.131212) (xy 117.94644 -358.11585) (xy 117.896827 -358.093195) (xy 117.850944 -358.063711)
			(xy 117.809724 -358.027996) (xy 117.774006 -357.986779) (xy 117.744518 -357.940897) (xy 117.72186 -357.891286)
			(xy 117.706494 -357.838955) (xy 117.698731 -357.78497) (xy 116.216028 -357.78497) (xy 116.216028 -357.784975)
			(xy 116.208265 -357.838969) (xy 116.192896 -357.891308) (xy 116.170234 -357.940927) (xy 116.140741 -357.986816)
			(xy 116.105017 -358.02804) (xy 116.06379 -358.06376) (xy 116.017899 -358.093249) (xy 115.968278 -358.115907)
			(xy 115.915937 -358.131272) (xy 115.861943 -358.139031) (xy 115.834668 -358.139492) (xy 114.971068 -358.139492)
			(xy 114.943802 -358.138943) (xy 114.889826 -358.131179) (xy 114.837505 -358.115812) (xy 114.787903 -358.093156)
			(xy 114.742029 -358.063671) (xy 114.700819 -358.027959) (xy 114.66511 -357.986745) (xy 114.635629 -357.940869)
			(xy 114.612977 -357.891265) (xy 114.597614 -357.838942) (xy 114.589854 -357.784966) (xy 93.706706 -357.784966)
			(xy 93.706706 -357.78497) (xy 93.698944 -357.838954) (xy 93.68358 -357.891284) (xy 93.660925 -357.940895)
			(xy 93.631441 -357.986778) (xy 93.595727 -358.027998) (xy 93.554511 -358.063716) (xy 93.508632 -358.093205)
			(xy 93.459023 -358.115865) (xy 93.406695 -358.131235) (xy 93.352712 -358.139003) (xy 93.325442 -358.139492)
			(xy 92.461842 -358.139492) (xy 92.434571 -358.138971) (xy 92.380584 -358.131215) (xy 92.32825 -358.115853)
			(xy 92.278636 -358.0932) (xy 92.23275 -358.063716) (xy 92.191529 -358.028001) (xy 92.155809 -357.986783)
			(xy 92.12632 -357.940901) (xy 92.103661 -357.891289) (xy 92.088294 -357.838957) (xy 92.080532 -357.784971)
			(xy 90.597828 -357.784971) (xy 90.597828 -357.784974) (xy 90.590065 -357.838967) (xy 90.574697 -357.891305)
			(xy 90.552036 -357.940923) (xy 90.522544 -357.986811) (xy 90.486822 -358.028035) (xy 90.445597 -358.063755)
			(xy 90.399707 -358.093245) (xy 90.350088 -358.115903) (xy 90.297749 -358.131269) (xy 90.243756 -358.13903)
			(xy 90.216482 -358.139492) (xy 89.352882 -358.139492) (xy 89.325616 -358.138944) (xy 89.271638 -358.131181)
			(xy 89.219315 -358.115816) (xy 89.169711 -358.09316) (xy 89.123836 -358.063676) (xy 89.082624 -358.027964)
			(xy 89.046913 -357.98675) (xy 89.017431 -357.940873) (xy 88.994778 -357.891268) (xy 88.979415 -357.838944)
			(xy 88.971654 -357.784966) (xy 87.488806 -357.784966) (xy 87.488806 -357.784971) (xy 87.481044 -357.838956)
			(xy 87.465678 -357.891288) (xy 87.443022 -357.940901) (xy 87.413536 -357.986784) (xy 87.37782 -358.028005)
			(xy 87.336602 -358.063723) (xy 87.29072 -358.093211) (xy 87.241109 -358.115871) (xy 87.188778 -358.131239)
			(xy 87.134792 -358.139004) (xy 87.107522 -358.139492) (xy 86.243922 -358.139492) (xy 86.216652 -358.13897)
			(xy 86.162667 -358.131211) (xy 86.110336 -358.115848) (xy 86.060724 -358.093193) (xy 86.014841 -358.063709)
			(xy 85.973622 -358.027994) (xy 85.937905 -357.986777) (xy 85.908417 -357.940895) (xy 85.88576 -357.891285)
			(xy 85.870394 -357.838954) (xy 85.862631 -357.78497) (xy 84.379928 -357.78497) (xy 84.379928 -357.784975)
			(xy 84.372165 -357.838969) (xy 84.356795 -357.891309) (xy 84.334133 -357.940929) (xy 84.30464 -357.986818)
			(xy 84.268915 -358.028042) (xy 84.227687 -358.063762) (xy 84.181795 -358.093251) (xy 84.132173 -358.115908)
			(xy 84.079832 -358.131273) (xy 84.025837 -358.139031) (xy 83.998562 -358.139492) (xy 83.134962 -358.139492)
			(xy 83.107697 -358.138943) (xy 83.053721 -358.131178) (xy 83.0014 -358.11581) (xy 82.951799 -358.093154)
			(xy 82.905926 -358.063669) (xy 82.864717 -358.027957) (xy 82.829008 -357.986743) (xy 82.799528 -357.940868)
			(xy 82.776877 -357.891264) (xy 82.761514 -357.838942) (xy 82.753754 -357.784966) (xy 81.270906 -357.784966)
			(xy 81.270906 -357.784971) (xy 81.263143 -357.838959) (xy 81.247777 -357.891293) (xy 81.225119 -357.940907)
			(xy 81.195631 -357.986791) (xy 81.159913 -358.028012) (xy 81.118693 -358.06373) (xy 81.072808 -358.093218)
			(xy 81.023194 -358.115876) (xy 80.970861 -358.131243) (xy 80.916873 -358.139005) (xy 80.889602 -358.139492)
			(xy 80.026002 -358.139492) (xy 79.998733 -358.138969) (xy 79.94475 -358.131207) (xy 79.892421 -358.115843)
			(xy 79.842812 -358.093187) (xy 79.796932 -358.063702) (xy 79.755714 -358.027987) (xy 79.72 -357.98677)
			(xy 79.690514 -357.94089) (xy 79.667858 -357.89128) (xy 79.652493 -357.838952) (xy 79.644731 -357.784969)
			(xy 78.161906 -357.784969) (xy 78.161906 -357.78497) (xy 78.154144 -357.838954) (xy 78.13878 -357.891284)
			(xy 78.116125 -357.940895) (xy 78.086641 -357.986778) (xy 78.050927 -358.027998) (xy 78.009711 -358.063716)
			(xy 77.963832 -358.093205) (xy 77.914223 -358.115865) (xy 77.861895 -358.131235) (xy 77.807912 -358.139003)
			(xy 77.780642 -358.139492) (xy 76.917042 -358.139492) (xy 76.889771 -358.138971) (xy 76.835784 -358.131215)
			(xy 76.78345 -358.115853) (xy 76.733836 -358.0932) (xy 76.68795 -358.063716) (xy 76.646729 -358.028001)
			(xy 76.611009 -357.986783) (xy 76.58152 -357.940901) (xy 76.558861 -357.891289) (xy 76.543494 -357.838957)
			(xy 76.535732 -357.784971) (xy 75.053028 -357.784971) (xy 75.053028 -357.784974) (xy 75.045265 -357.838967)
			(xy 75.029897 -357.891305) (xy 75.007236 -357.940923) (xy 74.977744 -357.986811) (xy 74.942022 -358.028035)
			(xy 74.900797 -358.063755) (xy 74.854907 -358.093245) (xy 74.805288 -358.115903) (xy 74.752949 -358.131269)
			(xy 74.698956 -358.13903) (xy 74.671682 -358.139492) (xy 73.808082 -358.139492) (xy 73.780816 -358.138944)
			(xy 73.726838 -358.131181) (xy 73.674515 -358.115816) (xy 73.624911 -358.09316) (xy 73.579036 -358.063676)
			(xy 73.537824 -358.027964) (xy 73.502113 -357.98675) (xy 73.472631 -357.940873) (xy 73.449978 -357.891268)
			(xy 73.434615 -357.838944) (xy 73.426854 -357.784966) (xy 71.944006 -357.784966) (xy 71.944006 -357.784971)
			(xy 71.936244 -357.838956) (xy 71.920878 -357.891288) (xy 71.898222 -357.940901) (xy 71.868736 -357.986784)
			(xy 71.83302 -358.028005) (xy 71.791802 -358.063723) (xy 71.74592 -358.093211) (xy 71.696309 -358.115871)
			(xy 71.643978 -358.131239) (xy 71.589992 -358.139004) (xy 71.562722 -358.139492) (xy 70.699122 -358.139492)
			(xy 70.671852 -358.13897) (xy 70.617867 -358.131211) (xy 70.565536 -358.115848) (xy 70.515924 -358.093193)
			(xy 70.470041 -358.063709) (xy 70.428822 -358.027994) (xy 70.393105 -357.986777) (xy 70.363617 -357.940895)
			(xy 70.34096 -357.891285) (xy 70.325594 -357.838954) (xy 70.317831 -357.78497) (xy 68.835128 -357.78497)
			(xy 68.835128 -357.784975) (xy 68.827365 -357.838969) (xy 68.811995 -357.891309) (xy 68.789333 -357.940929)
			(xy 68.75984 -357.986818) (xy 68.724115 -358.028042) (xy 68.682887 -358.063762) (xy 68.636995 -358.093251)
			(xy 68.587373 -358.115908) (xy 68.535032 -358.131273) (xy 68.481037 -358.139031) (xy 68.453762 -358.139492)
			(xy 67.590162 -358.139492) (xy 67.562897 -358.138943) (xy 67.508921 -358.131178) (xy 67.4566 -358.11581)
			(xy 67.406999 -358.093154) (xy 67.361126 -358.063669) (xy 67.319917 -358.027957) (xy 67.284208 -357.986743)
			(xy 67.254728 -357.940868) (xy 67.232077 -357.891264) (xy 67.216714 -357.838942) (xy 67.208954 -357.784966)
			(xy 65.726106 -357.784966) (xy 65.726106 -357.784971) (xy 65.718343 -357.838959) (xy 65.702977 -357.891293)
			(xy 65.680319 -357.940907) (xy 65.650831 -357.986791) (xy 65.615113 -358.028012) (xy 65.573893 -358.06373)
			(xy 65.528008 -358.093218) (xy 65.478394 -358.115876) (xy 65.426061 -358.131243) (xy 65.372073 -358.139005)
			(xy 65.344802 -358.139492) (xy 64.481202 -358.139492) (xy 64.453933 -358.138969) (xy 64.39995 -358.131207)
			(xy 64.347621 -358.115843) (xy 64.298012 -358.093187) (xy 64.252132 -358.063702) (xy 64.210914 -358.027987)
			(xy 64.1752 -357.98677) (xy 64.145714 -357.94089) (xy 64.123058 -357.89128) (xy 64.107693 -357.838952)
			(xy 64.099931 -357.784969) (xy 51.666906 -357.784969) (xy 51.659145 -357.838953) (xy 51.64378 -357.891283)
			(xy 51.621126 -357.940894) (xy 51.591642 -357.986776) (xy 51.555929 -358.027995) (xy 51.514714 -358.063713)
			(xy 51.468836 -358.093203) (xy 51.419228 -358.115864) (xy 51.3669 -358.131234) (xy 51.312917 -358.139002)
			(xy 51.285648 -358.139492) (xy 50.422048 -358.139492) (xy 50.394777 -358.138972) (xy 50.340789 -358.131216)
			(xy 50.288455 -358.115855) (xy 50.238839 -358.093202) (xy 50.192953 -358.063718) (xy 50.151731 -358.028003)
			(xy 50.116011 -357.986785) (xy 50.086521 -357.940903) (xy 50.063862 -357.89129) (xy 50.048494 -357.838958)
			(xy 50.040732 -357.784971) (xy 48.558028 -357.784971) (xy 48.558028 -357.784974) (xy 48.550265 -357.838966)
			(xy 48.534897 -357.891304) (xy 48.512237 -357.940921) (xy 48.482746 -357.986809) (xy 48.447024 -358.028033)
			(xy 48.4058 -358.063753) (xy 48.359911 -358.093243) (xy 48.310292 -358.115901) (xy 48.257954 -358.131268)
			(xy 48.203962 -358.139029) (xy 48.176688 -358.139492) (xy 47.313088 -358.139492) (xy 47.285821 -358.138945)
			(xy 47.231843 -358.131182) (xy 47.179519 -358.115817) (xy 47.129915 -358.093162) (xy 47.084039 -358.063678)
			(xy 47.042826 -358.027966) (xy 47.007115 -357.986752) (xy 46.977632 -357.940875) (xy 46.954979 -357.891269)
			(xy 46.939615 -357.838945) (xy 46.931854 -357.784967) (xy 45.449006 -357.784967) (xy 45.449006 -357.78497)
			(xy 45.441244 -357.838956) (xy 45.425879 -357.891287) (xy 45.403223 -357.940899) (xy 45.373737 -357.986782)
			(xy 45.338022 -358.028003) (xy 45.296805 -358.063721) (xy 45.250924 -358.09321) (xy 45.201313 -358.115869)
			(xy 45.148983 -358.131238) (xy 45.094998 -358.139004) (xy 45.067728 -358.139492) (xy 44.204128 -358.139492)
			(xy 44.176858 -358.13897) (xy 44.122872 -358.131212) (xy 44.07054 -358.11585) (xy 44.020927 -358.093195)
			(xy 43.975044 -358.063711) (xy 43.933824 -358.027996) (xy 43.898106 -357.986779) (xy 43.868618 -357.940897)
			(xy 43.84596 -357.891286) (xy 43.830594 -357.838955) (xy 43.822831 -357.78497) (xy 42.340128 -357.78497)
			(xy 42.340128 -357.784975) (xy 42.332365 -357.838969) (xy 42.316996 -357.891308) (xy 42.294334 -357.940927)
			(xy 42.264841 -357.986816) (xy 42.229117 -358.02804) (xy 42.18789 -358.06376) (xy 42.141999 -358.093249)
			(xy 42.092378 -358.115907) (xy 42.040037 -358.131272) (xy 41.986043 -358.139031) (xy 41.958768 -358.139492)
			(xy 41.095168 -358.139492) (xy 41.067902 -358.138943) (xy 41.013926 -358.131179) (xy 40.961605 -358.115812)
			(xy 40.912003 -358.093156) (xy 40.866129 -358.063671) (xy 40.824919 -358.027959) (xy 40.78921 -357.986745)
			(xy 40.759729 -357.940869) (xy 40.737077 -357.891265) (xy 40.721714 -357.838942) (xy 40.713954 -357.784966)
			(xy 39.231106 -357.784966) (xy 39.231106 -357.784971) (xy 39.223343 -357.838958) (xy 39.207977 -357.891291)
			(xy 39.18532 -357.940905) (xy 39.155832 -357.986789) (xy 39.120115 -358.02801) (xy 39.078895 -358.063728)
			(xy 39.033012 -358.093216) (xy 38.983399 -358.115875) (xy 38.931066 -358.131242) (xy 38.877079 -358.139005)
			(xy 38.849808 -358.139492) (xy 37.986208 -358.139492) (xy 37.958939 -358.138969) (xy 37.904955 -358.131209)
			(xy 37.852626 -358.115844) (xy 37.803015 -358.093189) (xy 37.757134 -358.063704) (xy 37.715917 -358.027989)
			(xy 37.680201 -357.986772) (xy 37.650715 -357.940892) (xy 37.628059 -357.891282) (xy 37.612693 -357.838953)
			(xy 37.604931 -357.784969) (xy 36.122106 -357.784969) (xy 36.114345 -357.838953) (xy 36.09898 -357.891283)
			(xy 36.076326 -357.940894) (xy 36.046842 -357.986776) (xy 36.011129 -358.027995) (xy 35.969914 -358.063713)
			(xy 35.924036 -358.093203) (xy 35.874428 -358.115864) (xy 35.8221 -358.131234) (xy 35.768117 -358.139002)
			(xy 35.740848 -358.139492) (xy 34.877248 -358.139492) (xy 34.849977 -358.138972) (xy 34.795989 -358.131216)
			(xy 34.743655 -358.115855) (xy 34.694039 -358.093202) (xy 34.648153 -358.063718) (xy 34.606931 -358.028003)
			(xy 34.571211 -357.986785) (xy 34.541721 -357.940903) (xy 34.519062 -357.89129) (xy 34.503694 -357.838958)
			(xy 34.495932 -357.784971) (xy 33.013228 -357.784971) (xy 33.013228 -357.784974) (xy 33.005465 -357.838966)
			(xy 32.990097 -357.891304) (xy 32.967437 -357.940921) (xy 32.937946 -357.986809) (xy 32.902224 -358.028033)
			(xy 32.861 -358.063753) (xy 32.815111 -358.093243) (xy 32.765492 -358.115901) (xy 32.713154 -358.131268)
			(xy 32.659162 -358.139029) (xy 32.631888 -358.139492) (xy 31.768288 -358.139492) (xy 31.741021 -358.138945)
			(xy 31.687043 -358.131182) (xy 31.634719 -358.115817) (xy 31.585115 -358.093162) (xy 31.539239 -358.063678)
			(xy 31.498026 -358.027966) (xy 31.462315 -357.986752) (xy 31.432832 -357.940875) (xy 31.410179 -357.891269)
			(xy 31.394815 -357.838945) (xy 31.387054 -357.784967) (xy 29.904206 -357.784967) (xy 29.904206 -357.78497)
			(xy 29.896444 -357.838956) (xy 29.881079 -357.891287) (xy 29.858423 -357.940899) (xy 29.828937 -357.986782)
			(xy 29.793222 -358.028003) (xy 29.752005 -358.063721) (xy 29.706124 -358.09321) (xy 29.656513 -358.115869)
			(xy 29.604183 -358.131238) (xy 29.550198 -358.139004) (xy 29.522928 -358.139492) (xy 28.659328 -358.139492)
			(xy 28.632058 -358.13897) (xy 28.578072 -358.131212) (xy 28.52574 -358.11585) (xy 28.476127 -358.093195)
			(xy 28.430244 -358.063711) (xy 28.389024 -358.027996) (xy 28.353306 -357.986779) (xy 28.323818 -357.940897)
			(xy 28.30116 -357.891286) (xy 28.285794 -357.838955) (xy 28.278031 -357.78497) (xy 26.795328 -357.78497)
			(xy 26.795328 -357.784975) (xy 26.787565 -357.838969) (xy 26.772196 -357.891308) (xy 26.749534 -357.940927)
			(xy 26.720041 -357.986816) (xy 26.684317 -358.02804) (xy 26.64309 -358.06376) (xy 26.597199 -358.093249)
			(xy 26.547578 -358.115907) (xy 26.495237 -358.131272) (xy 26.441243 -358.139031) (xy 26.413968 -358.139492)
			(xy 25.550368 -358.139492) (xy 25.523102 -358.138943) (xy 25.469126 -358.131179) (xy 25.416805 -358.115812)
			(xy 25.367203 -358.093156) (xy 25.321329 -358.063671) (xy 25.280119 -358.027959) (xy 25.24441 -357.986745)
			(xy 25.214929 -357.940869) (xy 25.192277 -357.891265) (xy 25.176914 -357.838942) (xy 25.169154 -357.784966)
			(xy 23.686306 -357.784966) (xy 23.686306 -357.784971) (xy 23.678543 -357.838958) (xy 23.663177 -357.891291)
			(xy 23.64052 -357.940905) (xy 23.611032 -357.986789) (xy 23.575315 -358.02801) (xy 23.534095 -358.063728)
			(xy 23.488212 -358.093216) (xy 23.438599 -358.115875) (xy 23.386266 -358.131242) (xy 23.332279 -358.139005)
			(xy 23.305008 -358.139492) (xy 22.441408 -358.139492) (xy 22.414139 -358.138969) (xy 22.360155 -358.131209)
			(xy 22.307826 -358.115844) (xy 22.258215 -358.093189) (xy 22.212334 -358.063704) (xy 22.171117 -358.027989)
			(xy 22.135401 -357.986772) (xy 22.105915 -357.940892) (xy 22.083259 -357.891282) (xy 22.067893 -357.838953)
			(xy 22.060131 -357.784969) (xy 0.508 -357.784969) (xy 0.508 -360.017783) (xy 101.774757 -360.017783)
			(xy 101.774757 -359.957817) (xy 101.782584 -359.898365) (xy 101.798104 -359.840443) (xy 101.821052 -359.785042)
			(xy 101.851035 -359.733111) (xy 101.88754 -359.685538) (xy 101.929942 -359.643136) (xy 101.977516 -359.606632)
			(xy 102.029448 -359.57665) (xy 102.084849 -359.553703) (xy 102.142771 -359.538183) (xy 102.202223 -359.530357)
			(xy 102.232206 -359.529888) (xy 103.095806 -359.529888) (xy 103.125793 -359.530279) (xy 103.185255 -359.538108)
			(xy 103.243186 -359.553631) (xy 103.298595 -359.576583) (xy 103.350534 -359.60657) (xy 103.398115 -359.643081)
			(xy 103.440523 -359.68549) (xy 103.477033 -359.733071) (xy 103.50702 -359.785011) (xy 103.529971 -359.84042)
			(xy 103.545494 -359.898351) (xy 103.553322 -359.957813) (xy 103.553322 -360.017787) (xy 103.545494 -360.077249)
			(xy 103.529971 -360.13518) (xy 103.50702 -360.190589) (xy 103.477033 -360.242529) (xy 103.440523 -360.29011)
			(xy 103.398115 -360.332519) (xy 103.350534 -360.36903) (xy 103.298595 -360.399017) (xy 103.243186 -360.421969)
			(xy 103.185255 -360.437492) (xy 103.125793 -360.445321) (xy 103.095806 -360.445812) (xy 102.232206 -360.445812)
			(xy 102.202223 -360.445243) (xy 102.142771 -360.437417) (xy 102.084849 -360.421897) (xy 102.029448 -360.39895)
			(xy 101.977516 -360.368968) (xy 101.929942 -360.332464) (xy 101.88754 -360.290062) (xy 101.851035 -360.242489)
			(xy 101.821052 -360.190558) (xy 101.798104 -360.135157) (xy 101.782584 -360.077235) (xy 101.774757 -360.017783)
			(xy 0.508 -360.017783) (xy 0.508 -363.334808) (xy 54.890416 -363.334808) (xy 54.890416 -362.471208)
			(xy 54.890906 -362.441224) (xy 54.898734 -362.381768) (xy 54.914255 -362.323843) (xy 54.937204 -362.268439)
			(xy 54.967188 -362.216505) (xy 55.003694 -362.168929) (xy 55.046099 -362.126524) (xy 55.093675 -362.090018)
			(xy 55.145609 -362.060034) (xy 55.201013 -362.037085) (xy 55.258938 -362.021564) (xy 55.318394 -362.013736)
			(xy 55.378362 -362.013736) (xy 55.437818 -362.021564) (xy 55.495743 -362.037085) (xy 55.551147 -362.060034)
			(xy 55.603081 -362.090018) (xy 55.650657 -362.126524) (xy 55.693062 -362.168929) (xy 55.729568 -362.216505)
			(xy 55.759552 -362.268439) (xy 55.782501 -362.323843) (xy 55.798022 -362.381768) (xy 55.80585 -362.441224)
			(xy 55.80634 -362.471208) (xy 55.80634 -363.334808) (xy 55.80585 -363.364792) (xy 55.798022 -363.424248)
			(xy 55.782501 -363.482173) (xy 55.759552 -363.537577) (xy 55.729568 -363.589511) (xy 55.693062 -363.637087)
			(xy 55.650657 -363.679492) (xy 55.603081 -363.715998) (xy 55.551147 -363.745982) (xy 55.495743 -363.768931)
			(xy 55.437818 -363.784452) (xy 55.378362 -363.79228) (xy 55.318394 -363.79228) (xy 55.258938 -363.784452)
			(xy 55.201013 -363.768931) (xy 55.145609 -363.745982) (xy 55.093675 -363.715998) (xy 55.046099 -363.679492)
			(xy 55.003694 -363.637087) (xy 54.967188 -363.589511) (xy 54.937204 -363.537577) (xy 54.914255 -363.482173)
			(xy 54.898734 -363.424248) (xy 54.890906 -363.364792) (xy 54.890416 -363.334808) (xy 0.508 -363.334808)
			(xy 0.508 -365.797384) (xy 54.438294 -365.797384) (xy 54.438294 -365.737416) (xy 54.446121 -365.67796)
			(xy 54.461641 -365.620034) (xy 54.484589 -365.564629) (xy 54.514571 -365.512694) (xy 54.551076 -365.465115)
			(xy 54.593478 -365.422709) (xy 54.641052 -365.386199) (xy 54.692984 -365.356211) (xy 54.748387 -365.333257)
			(xy 54.806311 -365.317731) (xy 54.865766 -365.309897) (xy 54.89575 -365.309404) (xy 55.75935 -365.309404)
			(xy 55.789336 -365.309938) (xy 55.848794 -365.31776) (xy 55.906723 -365.333276) (xy 55.962131 -365.356222)
			(xy 56.01407 -365.386203) (xy 56.06165 -365.422708) (xy 56.104059 -365.465112) (xy 56.140569 -365.512689)
			(xy 56.170556 -365.564624) (xy 56.193508 -365.620029) (xy 56.20903 -365.677957) (xy 56.216859 -365.737414)
			(xy 56.216859 -365.797386) (xy 56.20903 -365.856843) (xy 56.193508 -365.914771) (xy 56.170556 -365.970176)
			(xy 56.140569 -366.022112) (xy 56.104059 -366.069688) (xy 56.06165 -366.112092) (xy 56.01407 -366.148597)
			(xy 55.962131 -366.178578) (xy 55.906723 -366.201524) (xy 55.848794 -366.21704) (xy 55.789336 -366.224862)
			(xy 55.75935 -366.225328) (xy 54.89575 -366.225328) (xy 54.865766 -366.224903) (xy 54.806311 -366.217069)
			(xy 54.748386 -366.201543) (xy 54.692984 -366.178589) (xy 54.641052 -366.148601) (xy 54.593478 -366.112091)
			(xy 54.551076 -366.069685) (xy 54.514571 -366.022106) (xy 54.484589 -365.970171) (xy 54.461641 -365.914766)
			(xy 54.446121 -365.85684) (xy 54.438294 -365.797384) (xy 0.508 -365.797384) (xy 0.508 -368.516662)
			(xy 53.966364 -368.516662) (xy 53.966364 -367.653062) (xy 53.96685 -367.625793) (xy 53.974612 -367.571809)
			(xy 53.989977 -367.519479) (xy 54.012634 -367.469869) (xy 54.04212 -367.423988) (xy 54.077835 -367.382771)
			(xy 54.119052 -367.347056) (xy 54.164933 -367.31757) (xy 54.214543 -367.294913) (xy 54.266873 -367.279548)
			(xy 54.320857 -367.271786) (xy 54.375395 -367.271786) (xy 54.429379 -367.279548) (xy 54.481709 -367.294913)
			(xy 54.531319 -367.31757) (xy 54.5772 -367.347056) (xy 54.618417 -367.382771) (xy 54.654132 -367.423988)
			(xy 54.683618 -367.469869) (xy 54.706275 -367.519479) (xy 54.72164 -367.571809) (xy 54.729402 -367.625793)
			(xy 54.729888 -367.653062) (xy 54.729888 -368.516662) (xy 57.339484 -368.516662) (xy 57.339484 -367.653062)
			(xy 57.33997 -367.625793) (xy 57.347732 -367.571809) (xy 57.363097 -367.519479) (xy 57.385754 -367.469869)
			(xy 57.41524 -367.423988) (xy 57.450955 -367.382771) (xy 57.492172 -367.347056) (xy 57.538053 -367.31757)
			(xy 57.587663 -367.294913) (xy 57.639993 -367.279548) (xy 57.693977 -367.271786) (xy 57.748515 -367.271786)
			(xy 57.802499 -367.279548) (xy 57.854829 -367.294913) (xy 57.904439 -367.31757) (xy 57.95032 -367.347056)
			(xy 57.991537 -367.382771) (xy 58.027252 -367.423988) (xy 58.056738 -367.469869) (xy 58.079395 -367.519479)
			(xy 58.09476 -367.571809) (xy 58.102522 -367.625793) (xy 58.103008 -367.653062) (xy 58.103008 -368.516662)
			(xy 58.102522 -368.543931) (xy 58.09476 -368.597915) (xy 58.079395 -368.650245) (xy 58.056738 -368.699855)
			(xy 58.027252 -368.745736) (xy 57.991537 -368.786953) (xy 57.95032 -368.822668) (xy 57.904439 -368.852154)
			(xy 57.854829 -368.874811) (xy 57.802499 -368.890176) (xy 57.748515 -368.897938) (xy 57.693977 -368.897938)
			(xy 57.639993 -368.890176) (xy 57.587663 -368.874811) (xy 57.538053 -368.852154) (xy 57.492172 -368.822668)
			(xy 57.450955 -368.786953) (xy 57.41524 -368.745736) (xy 57.385754 -368.699855) (xy 57.363097 -368.650245)
			(xy 57.347732 -368.597915) (xy 57.33997 -368.543931) (xy 57.339484 -368.516662) (xy 54.729888 -368.516662)
			(xy 54.729402 -368.543931) (xy 54.72164 -368.597915) (xy 54.706275 -368.650245) (xy 54.683618 -368.699855)
			(xy 54.654132 -368.745736) (xy 54.618417 -368.786953) (xy 54.5772 -368.822668) (xy 54.531319 -368.852154)
			(xy 54.481709 -368.874811) (xy 54.429379 -368.890176) (xy 54.375395 -368.897938) (xy 54.320857 -368.897938)
			(xy 54.266873 -368.890176) (xy 54.214543 -368.874811) (xy 54.164933 -368.852154) (xy 54.119052 -368.822668)
			(xy 54.077835 -368.786953) (xy 54.04212 -368.745736) (xy 54.012634 -368.699855) (xy 53.989977 -368.650245)
			(xy 53.974612 -368.597915) (xy 53.96685 -368.543931) (xy 53.966364 -368.516662) (xy 0.508 -368.516662)
			(xy 0.508 -370.523703) (xy 27.348898 -370.523703) (xy 27.348899 -370.456279) (xy 27.356975 -370.38934)
			(xy 27.373012 -370.323851) (xy 27.396776 -370.260753) (xy 27.427927 -370.200957) (xy 27.466016 -370.145322)
			(xy 27.48788 -370.119656) (xy 27.493675 -370.11251) (xy 27.500191 -370.09532) (xy 27.50058 -370.086128)
			(xy 27.50058 -369.928902) (xy 27.501029 -369.918771) (xy 27.508764 -369.900042) (xy 27.523062 -369.885684)
			(xy 27.541759 -369.877872) (xy 27.551888 -369.87734) (xy 28.268168 -369.87734) (xy 28.278293 -369.877743)
			(xy 28.297004 -369.885488) (xy 28.311321 -369.899809) (xy 28.31906 -369.918522) (xy 28.319476 -369.928648)
			(xy 28.319476 -370.086128) (xy 28.319878 -370.095316) (xy 28.326398 -370.1125) (xy 28.332176 -370.119656)
			(xy 28.354029 -370.145331) (xy 28.39212 -370.200963) (xy 28.423272 -370.260758) (xy 28.447038 -370.323854)
			(xy 28.463075 -370.389342) (xy 28.471152 -370.456279) (xy 28.471153 -370.523644) (xy 31.749193 -370.523644)
			(xy 31.749194 -370.456338) (xy 31.75724 -370.389514) (xy 31.773215 -370.324131) (xy 31.79689 -370.261126)
			(xy 31.827927 -370.201402) (xy 31.865879 -370.145816) (xy 31.887668 -370.120164) (xy 31.893471 -370.113023)
			(xy 31.89998 -370.095829) (xy 31.900368 -370.086636) (xy 31.900368 -369.928902) (xy 31.900766 -369.918727)
			(xy 31.908556 -369.899926) (xy 31.92295 -369.88554) (xy 31.941755 -369.877761) (xy 31.95193 -369.87734)
			(xy 32.66821 -369.87734) (xy 32.678369 -369.877825) (xy 32.697138 -369.885603) (xy 32.711503 -369.899972)
			(xy 32.719277 -369.918743) (xy 32.719772 -369.928902) (xy 32.719772 -370.086636) (xy 32.720171 -370.095824)
			(xy 32.726693 -370.113008) (xy 32.732472 -370.120164) (xy 32.754248 -370.145826) (xy 32.792196 -370.201411)
			(xy 32.823229 -370.261134) (xy 32.846902 -370.324137) (xy 32.862876 -370.389518) (xy 32.870921 -370.456339)
			(xy 32.870922 -370.523643) (xy 32.870915 -370.523703) (xy 36.148986 -370.523703) (xy 36.148987 -370.456279)
			(xy 36.157063 -370.389341) (xy 36.173099 -370.323851) (xy 36.196863 -370.260754) (xy 36.228013 -370.200957)
			(xy 36.266101 -370.145322) (xy 36.287964 -370.119656) (xy 36.29377 -370.112518) (xy 36.300277 -370.095322)
			(xy 36.300664 -370.086128) (xy 36.300664 -369.928902) (xy 36.301129 -369.918772) (xy 36.308861 -369.900047)
			(xy 36.323154 -369.88569) (xy 36.341845 -369.877875) (xy 36.351972 -369.87734) (xy 37.068252 -369.87734)
			(xy 37.078408 -369.877762) (xy 37.097167 -369.885549) (xy 37.111494 -369.899947) (xy 37.119188 -369.918744)
			(xy 37.11956 -369.928902) (xy 37.11956 -370.086128) (xy 37.119966 -370.095315) (xy 37.126483 -370.112499)
			(xy 37.13226 -370.119656) (xy 37.154114 -370.14533) (xy 37.192205 -370.200963) (xy 37.223359 -370.260757)
			(xy 37.247125 -370.323853) (xy 37.263163 -370.389341) (xy 37.27124 -370.456279) (xy 37.271241 -370.523703)
			(xy 37.271241 -370.523704) (xy 40.548752 -370.523704) (xy 40.548753 -370.456278) (xy 40.556831 -370.389338)
			(xy 40.572869 -370.323848) (xy 40.596637 -370.26075) (xy 40.627792 -370.200954) (xy 40.665885 -370.14532)
			(xy 40.687752 -370.119656) (xy 40.693556 -370.112516) (xy 40.700065 -370.095321) (xy 40.700452 -370.086128)
			(xy 40.700452 -369.928902) (xy 40.700929 -369.918774) (xy 40.708658 -369.900051) (xy 40.722947 -369.885694)
			(xy 40.741634 -369.877877) (xy 40.75176 -369.87734) (xy 41.46804 -369.87734) (xy 41.478202 -369.87769)
			(xy 41.496963 -369.885506) (xy 41.511286 -369.899925) (xy 41.518977 -369.918738) (xy 41.519348 -369.928902)
			(xy 41.519348 -370.086128) (xy 41.519756 -370.095315) (xy 41.526273 -370.112499) (xy 41.532048 -370.119656)
			(xy 41.553902 -370.14533) (xy 41.591994 -370.200962) (xy 41.623149 -370.260757) (xy 41.646916 -370.323852)
			(xy 41.662954 -370.389341) (xy 41.671031 -370.456279) (xy 41.671032 -370.523644) (xy 44.949071 -370.523644)
			(xy 44.949073 -370.456338) (xy 44.957118 -370.389515) (xy 44.973092 -370.324132) (xy 44.996766 -370.261127)
			(xy 45.027801 -370.201403) (xy 45.065751 -370.145816) (xy 45.08754 -370.120164) (xy 45.093339 -370.113021)
			(xy 45.099851 -370.095829) (xy 45.10024 -370.086636) (xy 45.10024 -369.928902) (xy 45.100665 -369.91873)
			(xy 45.10845 -369.899935) (xy 45.122835 -369.88555) (xy 45.14163 -369.877765) (xy 45.151802 -369.87734)
			(xy 45.868082 -369.87734) (xy 45.878253 -369.877778) (xy 45.897047 -369.885558) (xy 45.911433 -369.899939)
			(xy 45.919218 -369.918731) (xy 45.919644 -369.928902) (xy 45.919644 -370.086636) (xy 45.92005 -370.095823)
			(xy 45.926568 -370.113007) (xy 45.932344 -370.120164) (xy 45.95412 -370.145826) (xy 45.992071 -370.20141)
			(xy 46.023105 -370.261132) (xy 46.046779 -370.324136) (xy 46.062754 -370.389517) (xy 46.070799 -370.456339)
			(xy 46.0708 -370.523643) (xy 46.062757 -370.590465) (xy 46.046785 -370.655847) (xy 46.023113 -370.718851)
			(xy 45.99208 -370.778574) (xy 45.954131 -370.83416) (xy 45.932344 -370.859812) (xy 45.926553 -370.866961)
			(xy 45.920036 -370.884149) (xy 45.919644 -370.89334) (xy 45.919644 -371.386862) (xy 45.920085 -371.396046)
			(xy 45.926578 -371.41323) (xy 45.932344 -371.42039) (xy 45.954146 -371.44603) (xy 45.992096 -371.501618)
			(xy 46.023129 -371.561343) (xy 46.046568 -371.623726) (xy 47.14919 -371.623726) (xy 47.149193 -371.556417)
			(xy 47.157242 -371.489591) (xy 47.17322 -371.424206) (xy 47.1969 -371.3612) (xy 47.22794 -371.301475)
			(xy 47.265897 -371.24589) (xy 47.287688 -371.220238) (xy 47.293492 -371.213098) (xy 47.300003 -371.195904)
			(xy 47.300388 -371.18671) (xy 47.300388 -371.028722) (xy 47.300783 -371.018546) (xy 47.30857 -370.999742)
			(xy 47.322966 -370.985355) (xy 47.341773 -370.977578) (xy 47.35195 -370.97716) (xy 48.06823 -370.97716)
			(xy 48.078392 -370.977609) (xy 48.097167 -370.985398) (xy 48.111532 -370.999777) (xy 48.119301 -371.018559)
			(xy 48.119792 -371.028722) (xy 48.119792 -371.18671) (xy 48.120199 -371.195898) (xy 48.126715 -371.213082)
			(xy 48.132492 -371.220238) (xy 48.154241 -371.245921) (xy 48.192189 -371.301504) (xy 48.196948 -371.310662)
			(xy 53.966364 -371.310662) (xy 53.966364 -370.447062) (xy 53.96685 -370.419793) (xy 53.974612 -370.365809)
			(xy 53.989977 -370.313479) (xy 54.012634 -370.263869) (xy 54.04212 -370.217988) (xy 54.077835 -370.176771)
			(xy 54.119052 -370.141056) (xy 54.164933 -370.11157) (xy 54.214543 -370.088913) (xy 54.266873 -370.073548)
			(xy 54.320857 -370.065786) (xy 54.375395 -370.065786) (xy 54.429379 -370.073548) (xy 54.481709 -370.088913)
			(xy 54.531319 -370.11157) (xy 54.5772 -370.141056) (xy 54.618417 -370.176771) (xy 54.654132 -370.217988)
			(xy 54.683618 -370.263869) (xy 54.706275 -370.313479) (xy 54.72164 -370.365809) (xy 54.729402 -370.419793)
			(xy 54.729888 -370.447062) (xy 54.729888 -371.310662) (xy 57.339484 -371.310662) (xy 57.339484 -370.447062)
			(xy 57.33997 -370.419793) (xy 57.347732 -370.365809) (xy 57.363097 -370.313479) (xy 57.385754 -370.263869)
			(xy 57.41524 -370.217988) (xy 57.450955 -370.176771) (xy 57.492172 -370.141056) (xy 57.538053 -370.11157)
			(xy 57.587663 -370.088913) (xy 57.639993 -370.073548) (xy 57.693977 -370.065786) (xy 57.748515 -370.065786)
			(xy 57.802499 -370.073548) (xy 57.854829 -370.088913) (xy 57.904439 -370.11157) (xy 57.95032 -370.141056)
			(xy 57.991537 -370.176771) (xy 58.027252 -370.217988) (xy 58.056738 -370.263869) (xy 58.079395 -370.313479)
			(xy 58.09476 -370.365809) (xy 58.102522 -370.419793) (xy 58.103008 -370.447062) (xy 58.103008 -370.523703)
			(xy 71.348807 -370.523703) (xy 71.348808 -370.456279) (xy 71.356885 -370.38934) (xy 71.372921 -370.32385)
			(xy 71.396686 -370.260753) (xy 71.427838 -370.200956) (xy 71.465928 -370.145321) (xy 71.487792 -370.119656)
			(xy 71.493589 -370.112511) (xy 71.500104 -370.09532) (xy 71.500492 -370.086128) (xy 71.500492 -369.928902)
			(xy 71.501027 -369.918781) (xy 71.508745 -369.900069) (xy 71.523016 -369.885715) (xy 71.541682 -369.877887)
			(xy 71.5518 -369.87734) (xy 72.26808 -369.87734) (xy 72.278238 -369.877739) (xy 72.296998 -369.885535)
			(xy 72.311323 -369.89994) (xy 72.319016 -369.918742) (xy 72.319388 -369.928902) (xy 72.319388 -370.086128)
			(xy 72.319787 -370.095316) (xy 72.326309 -370.1125) (xy 72.332088 -370.119656) (xy 72.353941 -370.145331)
			(xy 72.39203 -370.200964) (xy 72.423182 -370.260758) (xy 72.446948 -370.323854) (xy 72.462984 -370.389342)
			(xy 72.471061 -370.45628) (xy 72.471063 -370.523644) (xy 75.749102 -370.523644) (xy 75.749103 -370.456338)
			(xy 75.757149 -370.389513) (xy 75.773125 -370.32413) (xy 75.796801 -370.261125) (xy 75.827837 -370.201401)
			(xy 75.86579 -370.145816) (xy 75.88758 -370.120164) (xy 75.893372 -370.113015) (xy 75.89989 -370.095828)
			(xy 75.90028 -370.086636) (xy 75.90028 -369.928902) (xy 75.900666 -369.918725) (xy 75.908459 -369.899923)
			(xy 75.922856 -369.885536) (xy 75.941665 -369.877759) (xy 75.951842 -369.87734) (xy 76.668122 -369.87734)
			(xy 76.678281 -369.877815) (xy 76.697052 -369.885597) (xy 76.711416 -369.899969) (xy 76.71919 -369.918742)
			(xy 76.719684 -369.928902) (xy 76.719684 -370.086636) (xy 76.72008 -370.095825) (xy 76.726604 -370.113009)
			(xy 76.732384 -370.120164) (xy 76.754159 -370.145826) (xy 76.792107 -370.201412) (xy 76.82314 -370.261134)
			(xy 76.846812 -370.324137) (xy 76.862785 -370.389518) (xy 76.87083 -370.456339) (xy 76.870831 -370.523643)
			(xy 76.870824 -370.523703) (xy 80.148895 -370.523703) (xy 80.148896 -370.456279) (xy 80.156972 -370.38934)
			(xy 80.173008 -370.323851) (xy 80.196773 -370.260754) (xy 80.227924 -370.200957) (xy 80.266012 -370.145322)
			(xy 80.287876 -370.119656) (xy 80.293671 -370.112509) (xy 80.300187 -370.09532) (xy 80.300576 -370.086128)
			(xy 80.300576 -369.928902) (xy 80.301029 -369.918771) (xy 80.308763 -369.900043) (xy 80.32306 -369.885685)
			(xy 80.341755 -369.877873) (xy 80.351884 -369.87734) (xy 81.068164 -369.87734) (xy 81.078289 -369.877747)
			(xy 81.096999 -369.88549) (xy 81.111316 -369.899811) (xy 81.119056 -369.918523) (xy 81.119472 -369.928648)
			(xy 81.119472 -370.086128) (xy 81.119875 -370.095316) (xy 81.126394 -370.1125) (xy 81.132172 -370.119656)
			(xy 81.154025 -370.14533) (xy 81.192116 -370.200963) (xy 81.223269 -370.260758) (xy 81.247035 -370.323853)
			(xy 81.263072 -370.389342) (xy 81.271149 -370.456279) (xy 81.27115 -370.523703) (xy 84.548686 -370.523703)
			(xy 84.548687 -370.456279) (xy 84.556763 -370.389341) (xy 84.572799 -370.323851) (xy 84.596563 -370.260754)
			(xy 84.627713 -370.200957) (xy 84.665801 -370.145322) (xy 84.687664 -370.119656) (xy 84.69347 -370.112518)
			(xy 84.699977 -370.095322) (xy 84.700364 -370.086128) (xy 84.700364 -369.928902) (xy 84.700829 -369.918772)
			(xy 84.708561 -369.900047) (xy 84.722854 -369.88569) (xy 84.741545 -369.877875) (xy 84.751672 -369.87734)
			(xy 85.467952 -369.87734) (xy 85.478076 -369.877756) (xy 85.496787 -369.885496) (xy 85.511104 -369.899813)
			(xy 85.518844 -369.918524) (xy 85.51926 -369.928648) (xy 85.51926 -370.086128) (xy 85.519666 -370.095315)
			(xy 85.526183 -370.112499) (xy 85.53196 -370.119656) (xy 85.553814 -370.14533) (xy 85.591905 -370.200963)
			(xy 85.623059 -370.260757) (xy 85.646825 -370.323853) (xy 85.662863 -370.389341) (xy 85.67094 -370.456279)
			(xy 85.670941 -370.523644) (xy 115.349244 -370.523644) (xy 115.349245 -370.456338) (xy 115.35729 -370.389516)
			(xy 115.373263 -370.324133) (xy 115.396936 -370.261128) (xy 115.427969 -370.201404) (xy 115.465917 -370.145817)
			(xy 115.487704 -370.120164) (xy 115.493499 -370.113018) (xy 115.500014 -370.095828) (xy 115.500404 -370.086636)
			(xy 115.500404 -369.928902) (xy 115.500934 -369.918749) (xy 115.508702 -369.899986) (xy 115.523056 -369.885622)
			(xy 115.541813 -369.877841) (xy 115.551966 -369.87734) (xy 116.268246 -369.87734) (xy 116.278407 -369.877796)
			(xy 116.297177 -369.885586) (xy 116.311541 -369.899963) (xy 116.319314 -369.918741) (xy 116.319808 -369.928902)
			(xy 116.319808 -370.086636) (xy 116.320199 -370.095825) (xy 116.326726 -370.11301) (xy 116.332508 -370.120164)
			(xy 116.354286 -370.145825) (xy 116.392238 -370.201409) (xy 116.423275 -370.261131) (xy 116.446951 -370.324134)
			(xy 116.462926 -370.389516) (xy 116.470972 -370.456338) (xy 116.470973 -370.523644) (xy 116.470966 -370.523703)
			(xy 119.749013 -370.523703) (xy 119.749014 -370.456279) (xy 119.757091 -370.38934) (xy 119.773128 -370.32385)
			(xy 119.796893 -370.260752) (xy 119.828045 -370.200956) (xy 119.866135 -370.145321) (xy 119.888 -370.119656)
			(xy 119.893798 -370.112512) (xy 119.900312 -370.09532) (xy 119.9007 -370.086128) (xy 119.9007 -369.928902)
			(xy 119.901227 -369.91878) (xy 119.908947 -369.900067) (xy 119.92322 -369.885712) (xy 119.941889 -369.877886)
			(xy 119.952008 -369.87734) (xy 120.668288 -369.87734) (xy 120.678446 -369.877732) (xy 120.697206 -369.885531)
			(xy 120.711531 -369.899938) (xy 120.719224 -369.918741) (xy 120.719596 -369.928902) (xy 120.719596 -370.086128)
			(xy 120.719993 -370.095317) (xy 120.726516 -370.112501) (xy 120.732296 -370.119656) (xy 120.754148 -370.145331)
			(xy 120.792238 -370.200964) (xy 120.823389 -370.260759) (xy 120.847154 -370.323854) (xy 120.863191 -370.389342)
			(xy 120.871267 -370.45628) (xy 120.871269 -370.523644) (xy 124.149308 -370.523644) (xy 124.149309 -370.456338)
			(xy 124.157355 -370.389513) (xy 124.173331 -370.32413) (xy 124.197007 -370.261125) (xy 124.228045 -370.201401)
			(xy 124.265998 -370.145816) (xy 124.287788 -370.120164) (xy 124.293581 -370.113016) (xy 124.300098 -370.095828)
			(xy 124.300488 -370.086636) (xy 124.300488 -369.928902) (xy 124.300867 -369.918724) (xy 124.30866 -369.89992)
			(xy 124.32306 -369.885533) (xy 124.341872 -369.877757) (xy 124.35205 -369.87734) (xy 125.06833 -369.87734)
			(xy 125.07849 -369.877809) (xy 125.09726 -369.885593) (xy 125.111625 -369.899967) (xy 125.119398 -369.918742)
			(xy 125.119892 -369.928902) (xy 125.119892 -370.086636) (xy 125.120286 -370.095825) (xy 125.126811 -370.113009)
			(xy 125.132592 -370.120164) (xy 125.154367 -370.145826) (xy 125.192314 -370.201412) (xy 125.223346 -370.261134)
			(xy 125.247018 -370.324138) (xy 125.262991 -370.389518) (xy 125.271036 -370.456339) (xy 125.271037 -370.523643)
			(xy 125.271037 -370.523644) (xy 128.549099 -370.523644) (xy 128.5491 -370.456338) (xy 128.557146 -370.389514)
			(xy 128.573121 -370.32413) (xy 128.596797 -370.261125) (xy 128.627834 -370.201402) (xy 128.665787 -370.145816)
			(xy 128.687576 -370.120164) (xy 128.693368 -370.113015) (xy 128.699886 -370.095828) (xy 128.700276 -370.086636)
			(xy 128.700276 -369.928902) (xy 128.700666 -369.918726) (xy 128.708458 -369.899924) (xy 128.722854 -369.885538)
			(xy 128.741661 -369.877759) (xy 128.751838 -369.87734) (xy 129.468118 -369.87734) (xy 129.478277 -369.877818)
			(xy 129.497047 -369.885599) (xy 129.511412 -369.89997) (xy 129.519185 -369.918743) (xy 129.51968 -369.928902)
			(xy 129.51968 -370.086636) (xy 129.520077 -370.095824) (xy 129.5266 -370.113008) (xy 129.53238 -370.120164)
			(xy 129.554155 -370.145826) (xy 129.592103 -370.201412) (xy 129.623136 -370.261134) (xy 129.646809 -370.324137)
			(xy 129.662782 -370.389518) (xy 129.670827 -370.456339) (xy 129.670828 -370.523643) (xy 129.670828 -370.523644)
			(xy 159.349153 -370.523644) (xy 159.349154 -370.456338) (xy 159.357199 -370.389515) (xy 159.373173 -370.324133)
			(xy 159.396846 -370.261128) (xy 159.427879 -370.201404) (xy 159.465828 -370.145816) (xy 159.487616 -370.120164)
			(xy 159.493412 -370.113019) (xy 159.499927 -370.095828) (xy 159.500316 -370.086636) (xy 159.500316 -369.928902)
			(xy 159.500835 -369.918747) (xy 159.508604 -369.899982) (xy 159.522962 -369.885618) (xy 159.541723 -369.877839)
			(xy 159.551878 -369.87734) (xy 160.268158 -369.87734) (xy 160.278327 -369.877798) (xy 160.297121 -369.88557)
			(xy 160.311508 -369.899945) (xy 160.319294 -369.918733) (xy 160.31972 -369.928902) (xy 160.31972 -370.086636)
			(xy 160.320109 -370.095826) (xy 160.326637 -370.11301) (xy 160.33242 -370.120164) (xy 160.354197 -370.145825)
			(xy 160.392149 -370.20141) (xy 160.423185 -370.261131) (xy 160.44686 -370.324135) (xy 160.462835 -370.389516)
			(xy 160.470881 -370.456339) (xy 160.470882 -370.523643) (xy 160.470875 -370.523703) (xy 163.748922 -370.523703)
			(xy 163.748923 -370.456279) (xy 163.757 -370.389339) (xy 163.773037 -370.323849) (xy 163.796803 -370.260752)
			(xy 163.827956 -370.200955) (xy 163.866047 -370.145321) (xy 163.887912 -370.119656) (xy 163.893711 -370.112513)
			(xy 163.900224 -370.095321) (xy 163.900612 -370.086128) (xy 163.900612 -369.928902) (xy 163.901127 -369.918779)
			(xy 163.908849 -369.900063) (xy 163.923126 -369.885708) (xy 163.9418 -369.877884) (xy 163.95192 -369.87734)
			(xy 164.6682 -369.87734) (xy 164.678359 -369.877722) (xy 164.697119 -369.885526) (xy 164.711444 -369.899935)
			(xy 164.719136 -369.918741) (xy 164.719508 -369.928902) (xy 164.719508 -370.086128) (xy 164.719903 -370.095317)
			(xy 164.726427 -370.112501) (xy 164.732208 -370.119656) (xy 164.75406 -370.145331) (xy 164.792148 -370.200964)
			(xy 164.823299 -370.260759) (xy 164.847064 -370.323855) (xy 164.8631 -370.389343) (xy 164.871176 -370.45628)
			(xy 164.871178 -370.523644) (xy 168.149241 -370.523644) (xy 168.149242 -370.456338) (xy 168.157287 -370.389516)
			(xy 168.17326 -370.324133) (xy 168.196933 -370.261128) (xy 168.227965 -370.201404) (xy 168.265913 -370.145817)
			(xy 168.2877 -370.120164) (xy 168.293494 -370.113017) (xy 168.30001 -370.095828) (xy 168.3004 -370.086636)
			(xy 168.3004 -369.928902) (xy 168.300934 -369.918749) (xy 168.308701 -369.899987) (xy 168.323054 -369.885623)
			(xy 168.341809 -369.877842) (xy 168.351962 -369.87734) (xy 169.068242 -369.87734) (xy 169.078403 -369.877799)
			(xy 169.097173 -369.885588) (xy 169.111537 -369.899964) (xy 169.11931 -369.918741) (xy 169.119804 -369.928902)
			(xy 169.119804 -370.086636) (xy 169.120196 -370.095825) (xy 169.126722 -370.113009) (xy 169.132504 -370.120164)
			(xy 169.154279 -370.145826) (xy 169.192225 -370.201412) (xy 169.223256 -370.261135) (xy 169.246928 -370.324138)
			(xy 169.2629 -370.389519) (xy 169.270945 -370.456339) (xy 169.270946 -370.523643) (xy 169.270946 -370.523644)
			(xy 172.549008 -370.523644) (xy 172.549009 -370.456338) (xy 172.557055 -370.389513) (xy 172.573031 -370.32413)
			(xy 172.596707 -370.261125) (xy 172.627745 -370.201401) (xy 172.665698 -370.145816) (xy 172.687488 -370.120164)
			(xy 172.693281 -370.113016) (xy 172.699798 -370.095828) (xy 172.700188 -370.086636) (xy 172.700188 -369.928902)
			(xy 172.700567 -369.918724) (xy 172.70836 -369.89992) (xy 172.72276 -369.885533) (xy 172.741572 -369.877757)
			(xy 172.75175 -369.87734) (xy 173.46803 -369.87734) (xy 173.47819 -369.877809) (xy 173.49696 -369.885593)
			(xy 173.511325 -369.899967) (xy 173.519098 -369.918742) (xy 173.519592 -369.928902) (xy 173.519592 -370.086636)
			(xy 173.519986 -370.095825) (xy 173.526511 -370.113009) (xy 173.532292 -370.120164) (xy 173.554067 -370.145826)
			(xy 173.592014 -370.201412) (xy 173.623046 -370.261134) (xy 173.646718 -370.324138) (xy 173.662691 -370.389518)
			(xy 173.670736 -370.456339) (xy 173.670737 -370.523643) (xy 173.662694 -370.590464) (xy 173.646724 -370.655845)
			(xy 173.623054 -370.718849) (xy 173.592023 -370.778573) (xy 173.554078 -370.834159) (xy 173.532292 -370.859812)
			(xy 173.526507 -370.866965) (xy 173.519986 -370.88415) (xy 173.519592 -370.89334) (xy 173.519592 -370.901722)
			(xy 204.470508 -370.901722) (xy 204.470508 -367.316004) (xy 204.470934 -367.305935) (xy 204.478654 -367.287337)
			(xy 204.485494 -367.279936) (xy 204.682344 -367.083086) (xy 204.689733 -367.076232) (xy 204.708341 -367.068521)
			(xy 204.718412 -367.0681) (xy 208.051146 -367.0681) (xy 208.061216 -367.068527) (xy 208.079815 -367.076244)
			(xy 208.087214 -367.083086) (xy 208.263998 -367.25987) (xy 208.270817 -367.267287) (xy 208.278549 -367.285873)
			(xy 208.278984 -367.295938) (xy 208.278984 -370.103908) (xy 208.279552 -370.116248) (xy 208.288818 -370.13912)
			(xy 208.297018 -370.148358) (xy 208.297526 -370.148866) (xy 208.34985 -370.20119) (xy 208.35903 -370.209654)
			(xy 208.382078 -370.219214) (xy 208.394554 -370.219732) (xy 208.738724 -370.219732) (xy 208.748796 -370.220137)
			(xy 208.767394 -370.227871) (xy 208.774792 -370.234718) (xy 209.51444 -370.974366) (xy 209.523615 -370.982837)
			(xy 209.546667 -370.99239) (xy 209.559144 -370.992908) (xy 210.018376 -370.992908) (xy 210.028444 -370.993344)
			(xy 210.047042 -371.001057) (xy 210.054444 -371.007894) (xy 210.21421 -371.16766) (xy 210.221026 -371.175079)
			(xy 210.228759 -371.193664) (xy 210.229196 -371.203728) (xy 210.229196 -371.61724) (xy 210.229798 -371.629697)
			(xy 210.239356 -371.652707) (xy 210.247738 -371.661944) (xy 210.379056 -371.793262) (xy 210.379564 -371.79377)
			(xy 210.388781 -371.802003) (xy 210.411665 -371.811276) (xy 210.424014 -371.811804) (xy 216.605104 -371.811804)
			(xy 216.617445 -371.811237) (xy 216.640316 -371.801971) (xy 216.649554 -371.79377) (xy 216.650062 -371.793262)
			(xy 217.67927 -370.764054) (xy 217.679778 -370.763546) (xy 217.688008 -370.754327) (xy 217.697282 -370.731444)
			(xy 217.697812 -370.719096) (xy 217.697812 -367.36528) (xy 217.698224 -367.355209) (xy 217.705954 -367.336611)
			(xy 217.712798 -367.329212) (xy 217.96883 -367.073434) (xy 217.97623 -367.066593) (xy 217.994829 -367.058873)
			(xy 218.004898 -367.058448) (xy 221.295214 -367.058448) (xy 221.305259 -367.058823) (xy 221.323856 -367.066407)
			(xy 221.331282 -367.07318) (xy 221.508066 -367.249964) (xy 221.514878 -367.257386) (xy 221.522615 -367.275968)
			(xy 221.523052 -367.286032) (xy 221.523052 -370.745258) (xy 221.523577 -370.757603) (xy 221.532871 -370.780476)
			(xy 221.541086 -370.789708) (xy 221.541594 -370.790216) (xy 221.701614 -370.950236) (xy 221.708464 -370.957628)
			(xy 221.716177 -370.976233) (xy 221.7166 -370.986304) (xy 221.7166 -373.574564) (xy 221.71724 -373.587017)
			(xy 221.726771 -373.610028) (xy 221.735142 -373.619268) (xy 223.603312 -375.487438) (xy 223.6125 -375.495892)
			(xy 223.635542 -375.505456) (xy 223.648016 -375.50598) (xy 225.569526 -375.50598) (xy 225.581983 -375.505377)
			(xy 225.604994 -375.49582) (xy 225.61423 -375.487438) (xy 226.890326 -374.211342) (xy 226.890834 -374.210834)
			(xy 226.899064 -374.201614) (xy 226.90834 -374.178732) (xy 226.908868 -374.166384) (xy 226.908868 -372.704106)
			(xy 226.909279 -372.694035) (xy 226.917008 -372.675436) (xy 226.923854 -372.668038) (xy 228.193346 -371.3988)
			(xy 228.201796 -371.389609) (xy 228.211362 -371.366569) (xy 228.211888 -371.354096) (xy 228.211888 -370.983256)
			(xy 228.212267 -370.973181) (xy 228.220018 -370.954582) (xy 228.226874 -370.947188) (xy 228.380798 -370.793264)
			(xy 228.389257 -370.78408) (xy 228.398819 -370.761035) (xy 228.39934 -370.74856) (xy 228.39934 -367.292382)
			(xy 228.399715 -367.282337) (xy 228.4073 -367.263741) (xy 228.414072 -367.256314) (xy 228.600508 -367.069878)
			(xy 228.607909 -367.063039) (xy 228.626508 -367.055319) (xy 228.636576 -367.054892) (xy 231.959912 -367.054892)
			(xy 231.969985 -367.055287) (xy 231.988584 -367.063026) (xy 231.99598 -367.069878) (xy 232.182416 -367.256314)
			(xy 232.1891 -367.263803) (xy 232.196697 -367.282356) (xy 232.197148 -367.292382) (xy 232.197148 -370.755164)
			(xy 232.197775 -370.767618) (xy 232.207314 -370.79063) (xy 232.21569 -370.799868) (xy 232.35031 -370.934234)
			(xy 232.357159 -370.941627) (xy 232.364873 -370.960232) (xy 232.365296 -370.970302) (xy 232.365296 -371.212364)
			(xy 232.365833 -371.224708) (xy 232.37512 -371.247579) (xy 232.38333 -371.256814) (xy 232.383838 -371.257322)
			(xy 233.100118 -371.973602) (xy 233.106954 -371.981005) (xy 233.114675 -371.999602) (xy 233.115104 -372.00967)
			(xy 233.115104 -375.498868) (xy 233.115741 -375.511321) (xy 233.125274 -375.534332) (xy 233.133646 -375.543572)
			(xy 233.841798 -376.251724) (xy 235.85424 -376.251724) (xy 235.85424 -368.653314) (xy 235.854662 -368.643244)
			(xy 235.862384 -368.624646) (xy 235.869226 -368.617246) (xy 236.22889 -368.257582) (xy 236.236297 -368.250752)
			(xy 236.254891 -368.243027) (xy 236.264958 -368.242596) (xy 242.047014 -368.242596) (xy 242.057087 -368.242989)
			(xy 242.075686 -368.25073) (xy 242.083082 -368.257582) (xy 242.35029 -368.52479) (xy 242.357117 -368.532201)
			(xy 242.364845 -368.550792) (xy 242.365276 -368.560858) (xy 242.365276 -376.144028) (xy 242.364736 -376.155236)
			(xy 242.355238 -376.175537) (xy 242.346988 -376.183144) (xy 242.273836 -376.244104) (xy 242.269772 -376.247914)
			(xy 241.986816 -376.53087) (xy 241.986562 -376.531124) (xy 241.978942 -376.540522) (xy 241.91849 -376.631454)
			(xy 241.910997 -376.641545) (xy 241.888878 -376.653411) (xy 241.876326 -376.65406) (xy 236.25683 -376.65406)
			(xy 236.246761 -376.653629) (xy 236.228163 -376.645913) (xy 236.220762 -376.639074) (xy 235.869226 -376.287792)
			(xy 235.862394 -376.280386) (xy 235.854669 -376.261791) (xy 235.85424 -376.251724) (xy 233.841798 -376.251724)
			(xy 234.964478 -377.374404) (xy 242.49126 -377.374404) (xy 242.49126 -368.547142) (xy 242.491691 -368.537073)
			(xy 242.499406 -368.518474) (xy 242.506246 -368.511074) (xy 242.759738 -368.257582) (xy 242.767129 -368.25073)
			(xy 242.785735 -368.243018) (xy 242.795806 -368.242596) (xy 265.583924 -368.242596) (xy 265.593998 -368.242984)
			(xy 265.612597 -368.250728) (xy 265.619992 -368.257582) (xy 266.105894 -368.743484) (xy 266.112719 -368.750896)
			(xy 266.120448 -368.769486) (xy 266.12088 -368.779552) (xy 266.12088 -370.523704) (xy 286.928752 -370.523704)
			(xy 286.928753 -370.456278) (xy 286.936831 -370.389338) (xy 286.952869 -370.323848) (xy 286.976637 -370.26075)
			(xy 287.007792 -370.200954) (xy 287.045885 -370.14532) (xy 287.067752 -370.119656) (xy 287.073556 -370.112516)
			(xy 287.080065 -370.095321) (xy 287.080452 -370.086128) (xy 287.080452 -369.928902) (xy 287.080929 -369.918774)
			(xy 287.088658 -369.900051) (xy 287.102947 -369.885694) (xy 287.121634 -369.877877) (xy 287.13176 -369.87734)
			(xy 287.84804 -369.87734) (xy 287.85817 -369.877684) (xy 287.876882 -369.885453) (xy 287.891196 -369.899792)
			(xy 287.898933 -369.918517) (xy 287.899348 -369.928648) (xy 287.899348 -370.086128) (xy 287.899756 -370.095315)
			(xy 287.906273 -370.112499) (xy 287.912048 -370.119656) (xy 287.933902 -370.14533) (xy 287.971994 -370.200962)
			(xy 288.003149 -370.260757) (xy 288.026916 -370.323852) (xy 288.042954 -370.389341) (xy 288.051031 -370.456279)
			(xy 288.051032 -370.523644) (xy 291.329071 -370.523644) (xy 291.329073 -370.456338) (xy 291.337118 -370.389515)
			(xy 291.353092 -370.324132) (xy 291.376766 -370.261127) (xy 291.407801 -370.201403) (xy 291.445751 -370.145816)
			(xy 291.46754 -370.120164) (xy 291.473339 -370.113021) (xy 291.479851 -370.095829) (xy 291.48024 -370.086636)
			(xy 291.48024 -369.928902) (xy 291.480665 -369.91873) (xy 291.48845 -369.899935) (xy 291.502835 -369.88555)
			(xy 291.52163 -369.877765) (xy 291.531802 -369.87734) (xy 292.248082 -369.87734) (xy 292.258253 -369.877778)
			(xy 292.277047 -369.885558) (xy 292.291433 -369.899939) (xy 292.299218 -369.918731) (xy 292.299644 -369.928902)
			(xy 292.299644 -370.086636) (xy 292.30005 -370.095823) (xy 292.306568 -370.113007) (xy 292.312344 -370.120164)
			(xy 292.33412 -370.145826) (xy 292.372071 -370.20141) (xy 292.403105 -370.261132) (xy 292.426779 -370.324136)
			(xy 292.442754 -370.389517) (xy 292.450799 -370.456339) (xy 292.4508 -370.523643) (xy 292.450793 -370.523704)
			(xy 295.72884 -370.523704) (xy 295.728841 -370.456278) (xy 295.736918 -370.389339) (xy 295.752956 -370.323848)
			(xy 295.776723 -370.260751) (xy 295.807878 -370.200955) (xy 295.84597 -370.145321) (xy 295.867836 -370.119656)
			(xy 295.873638 -370.112515) (xy 295.880149 -370.095321) (xy 295.880536 -370.086128) (xy 295.880536 -369.928902)
			(xy 295.881028 -369.918776) (xy 295.888755 -369.900056) (xy 295.903039 -369.885699) (xy 295.92172 -369.877879)
			(xy 295.931844 -369.87734) (xy 296.648124 -369.87734) (xy 296.658285 -369.877703) (xy 296.677045 -369.885514)
			(xy 296.691369 -369.899929) (xy 296.699061 -369.918739) (xy 296.699432 -369.928902) (xy 296.699432 -370.086128)
			(xy 296.699844 -370.095315) (xy 296.706358 -370.112498) (xy 296.712132 -370.119656) (xy 296.733983 -370.145332)
			(xy 296.77207 -370.200965) (xy 296.803219 -370.26076) (xy 296.826983 -370.323856) (xy 296.843018 -370.389343)
			(xy 296.851095 -370.45628) (xy 296.851096 -370.523702) (xy 296.851096 -370.523704) (xy 300.128631 -370.523704)
			(xy 300.128632 -370.456278) (xy 300.136709 -370.389339) (xy 300.152747 -370.323849) (xy 300.176513 -370.260751)
			(xy 300.207667 -370.200955) (xy 300.245758 -370.145321) (xy 300.267624 -370.119656) (xy 300.273425 -370.112514)
			(xy 300.279936 -370.095321) (xy 300.280324 -370.086128) (xy 300.280324 -369.928902) (xy 300.280828 -369.918777)
			(xy 300.288552 -369.900059) (xy 300.302833 -369.885704) (xy 300.32151 -369.877882) (xy 300.331632 -369.87734)
			(xy 301.047912 -369.87734) (xy 301.058072 -369.877712) (xy 301.076832 -369.885519) (xy 301.091157 -369.899932)
			(xy 301.098849 -369.91874) (xy 301.09922 -369.928902) (xy 301.09922 -370.086128) (xy 301.099612 -370.095317)
			(xy 301.106138 -370.112502) (xy 301.11192 -370.119656) (xy 301.133771 -370.145331) (xy 301.171859 -370.200965)
			(xy 301.203009 -370.26076) (xy 301.226773 -370.323855) (xy 301.242809 -370.389343) (xy 301.250886 -370.45628)
			(xy 301.250887 -370.523644) (xy 330.92919 -370.523644) (xy 330.929191 -370.456338) (xy 330.937237 -370.389514)
			(xy 330.953212 -370.324131) (xy 330.976887 -370.261126) (xy 331.007923 -370.201402) (xy 331.045875 -370.145816)
			(xy 331.067664 -370.120164) (xy 331.073466 -370.113023) (xy 331.079976 -370.095829) (xy 331.080364 -370.086636)
			(xy 331.080364 -369.928902) (xy 331.080766 -369.918727) (xy 331.088555 -369.899928) (xy 331.102948 -369.885542)
			(xy 331.121751 -369.877761) (xy 331.131926 -369.87734) (xy 331.848206 -369.87734) (xy 331.858364 -369.877829)
			(xy 331.877134 -369.885605) (xy 331.891499 -369.899973) (xy 331.899273 -369.918744) (xy 331.899768 -369.928902)
			(xy 331.899768 -370.086636) (xy 331.900168 -370.095824) (xy 331.90669 -370.113008) (xy 331.912468 -370.120164)
			(xy 331.934244 -370.145826) (xy 331.972193 -370.201411) (xy 332.003226 -370.261133) (xy 332.026899 -370.324137)
			(xy 332.042873 -370.389518) (xy 332.050918 -370.456339) (xy 332.050919 -370.523643) (xy 332.050912 -370.523703)
			(xy 335.328983 -370.523703) (xy 335.328984 -370.456279) (xy 335.33706 -370.389341) (xy 335.353096 -370.323852)
			(xy 335.376859 -370.260754) (xy 335.408009 -370.200957) (xy 335.446097 -370.145322) (xy 335.46796 -370.119656)
			(xy 335.473765 -370.112517) (xy 335.480273 -370.095322) (xy 335.48066 -370.086128) (xy 335.48066 -369.928902)
			(xy 335.481129 -369.918773) (xy 335.48886 -369.900048) (xy 335.503152 -369.885691) (xy 335.521841 -369.877875)
			(xy 335.531968 -369.87734) (xy 336.248248 -369.87734) (xy 336.25841 -369.877683) (xy 336.277171 -369.885502)
			(xy 336.291494 -369.899923) (xy 336.299185 -369.918737) (xy 336.299556 -369.928902) (xy 336.299556 -370.086128)
			(xy 336.299963 -370.095315) (xy 336.30648 -370.112499) (xy 336.312256 -370.119656) (xy 336.33411 -370.14533)
			(xy 336.372202 -370.200962) (xy 336.403355 -370.260757) (xy 336.427122 -370.323853) (xy 336.44316 -370.389341)
			(xy 336.451237 -370.456279) (xy 336.451238 -370.523644) (xy 339.729277 -370.523644) (xy 339.729279 -370.456338)
			(xy 339.737324 -370.389514) (xy 339.753299 -370.324131) (xy 339.776973 -370.261126) (xy 339.808008 -370.201402)
			(xy 339.845959 -370.145816) (xy 339.867748 -370.120164) (xy 339.873548 -370.113022) (xy 339.880059 -370.095829)
			(xy 339.880448 -370.086636) (xy 339.880448 -369.928902) (xy 339.880866 -369.918729) (xy 339.888652 -369.899933)
			(xy 339.903039 -369.885547) (xy 339.921837 -369.877764) (xy 339.93201 -369.87734) (xy 340.64829 -369.87734)
			(xy 340.658461 -369.877772) (xy 340.677256 -369.885554) (xy 340.691641 -369.899937) (xy 340.699426 -369.918731)
			(xy 340.699852 -369.928902) (xy 340.699852 -370.086636) (xy 340.700256 -370.095824) (xy 340.706775 -370.113007)
			(xy 340.712552 -370.120164) (xy 340.734328 -370.145826) (xy 340.772278 -370.201411) (xy 340.803312 -370.261133)
			(xy 340.826986 -370.324136) (xy 340.84296 -370.389517) (xy 340.851005 -370.456339) (xy 340.851006 -370.523643)
			(xy 340.851006 -370.523644) (xy 344.129068 -370.523644) (xy 344.129069 -370.456338) (xy 344.137115 -370.389515)
			(xy 344.153089 -370.324132) (xy 344.176763 -370.261127) (xy 344.207797 -370.201403) (xy 344.245748 -370.145816)
			(xy 344.267536 -370.120164) (xy 344.273335 -370.113021) (xy 344.279847 -370.095829) (xy 344.280236 -370.086636)
			(xy 344.280236 -369.928902) (xy 344.280735 -369.918745) (xy 344.288508 -369.899976) (xy 344.302873 -369.885611)
			(xy 344.321641 -369.877836) (xy 344.331798 -369.87734) (xy 345.048078 -369.87734) (xy 345.058248 -369.877782)
			(xy 345.077043 -369.88556) (xy 345.091429 -369.89994) (xy 345.099214 -369.918732) (xy 345.09964 -369.928902)
			(xy 345.09964 -370.086636) (xy 345.100046 -370.095823) (xy 345.106564 -370.113007) (xy 345.11234 -370.120164)
			(xy 345.134116 -370.145826) (xy 345.172067 -370.20141) (xy 345.203102 -370.261132) (xy 345.226776 -370.324136)
			(xy 345.242751 -370.389517) (xy 345.250796 -370.456339) (xy 345.250797 -370.523643) (xy 345.250797 -370.523644)
			(xy 374.929099 -370.523644) (xy 374.9291 -370.456338) (xy 374.937146 -370.389514) (xy 374.953121 -370.32413)
			(xy 374.976797 -370.261125) (xy 375.007834 -370.201402) (xy 375.045787 -370.145816) (xy 375.067576 -370.120164)
			(xy 375.073368 -370.113015) (xy 375.079886 -370.095828) (xy 375.080276 -370.086636) (xy 375.080276 -369.928902)
			(xy 375.080666 -369.918726) (xy 375.088458 -369.899924) (xy 375.102854 -369.885538) (xy 375.121661 -369.877759)
			(xy 375.131838 -369.87734) (xy 375.848118 -369.87734) (xy 375.858277 -369.877818) (xy 375.877047 -369.885599)
			(xy 375.891412 -369.89997) (xy 375.899185 -369.918743) (xy 375.89968 -369.928902) (xy 375.89968 -370.086636)
			(xy 375.900077 -370.095824) (xy 375.9066 -370.113008) (xy 375.91238 -370.120164) (xy 375.934155 -370.145826)
			(xy 375.972103 -370.201412) (xy 376.003136 -370.261134) (xy 376.026809 -370.324137) (xy 376.042782 -370.389518)
			(xy 376.050827 -370.456339) (xy 376.050828 -370.523643) (xy 376.050821 -370.523703) (xy 379.328892 -370.523703)
			(xy 379.328893 -370.456279) (xy 379.336969 -370.38934) (xy 379.353005 -370.323851) (xy 379.376769 -370.260754)
			(xy 379.40792 -370.200957) (xy 379.446008 -370.145322) (xy 379.467872 -370.119656) (xy 379.473678 -370.112518)
			(xy 379.480185 -370.095322) (xy 379.480572 -370.086128) (xy 379.480572 -369.928902) (xy 379.481029 -369.918772)
			(xy 379.488762 -369.900044) (xy 379.503058 -369.885687) (xy 379.521752 -369.877873) (xy 379.53188 -369.87734)
			(xy 380.24816 -369.87734) (xy 380.258316 -369.877755) (xy 380.277076 -369.885545) (xy 380.291402 -369.899945)
			(xy 380.299096 -369.918743) (xy 380.299468 -369.928902) (xy 380.299468 -370.086128) (xy 380.299872 -370.095316)
			(xy 380.306391 -370.1125) (xy 380.312168 -370.119656) (xy 380.334021 -370.14533) (xy 380.372112 -370.200963)
			(xy 380.403265 -370.260758) (xy 380.427032 -370.323853) (xy 380.443069 -370.389342) (xy 380.451146 -370.456279)
			(xy 380.451147 -370.523644) (xy 383.729187 -370.523644) (xy 383.729188 -370.456338) (xy 383.737234 -370.389514)
			(xy 383.753209 -370.324131) (xy 383.776884 -370.261126) (xy 383.807919 -370.201402) (xy 383.845871 -370.145816)
			(xy 383.86766 -370.120164) (xy 383.873462 -370.113023) (xy 383.879972 -370.095829) (xy 383.88036 -370.086636)
			(xy 383.88036 -369.928902) (xy 383.880766 -369.918728) (xy 383.888554 -369.899929) (xy 383.902946 -369.885543)
			(xy 383.921748 -369.877762) (xy 383.931922 -369.87734) (xy 384.648202 -369.87734) (xy 384.65836 -369.877832)
			(xy 384.67713 -369.885607) (xy 384.691495 -369.899974) (xy 384.699269 -369.918744) (xy 384.699764 -369.928902)
			(xy 384.699764 -370.086636) (xy 384.700165 -370.095824) (xy 384.706686 -370.113008) (xy 384.712464 -370.120164)
			(xy 384.73424 -370.145826) (xy 384.772189 -370.201411) (xy 384.803222 -370.261133) (xy 384.826895 -370.324137)
			(xy 384.842869 -370.389518) (xy 384.850914 -370.456339) (xy 384.850915 -370.523643) (xy 384.850915 -370.523644)
			(xy 388.128977 -370.523644) (xy 388.128979 -370.456338) (xy 388.137024 -370.389514) (xy 388.152999 -370.324131)
			(xy 388.176673 -370.261126) (xy 388.207708 -370.201402) (xy 388.245659 -370.145816) (xy 388.267448 -370.120164)
			(xy 388.273248 -370.113022) (xy 388.279759 -370.095829) (xy 388.280148 -370.086636) (xy 388.280148 -369.928902)
			(xy 388.280566 -369.918729) (xy 388.288352 -369.899933) (xy 388.302739 -369.885547) (xy 388.321537 -369.877764)
			(xy 388.33171 -369.87734) (xy 389.04799 -369.87734) (xy 389.058161 -369.877772) (xy 389.076956 -369.885554)
			(xy 389.091341 -369.899937) (xy 389.099126 -369.918731) (xy 389.099552 -369.928902) (xy 389.099552 -370.086636)
			(xy 389.099956 -370.095824) (xy 389.106475 -370.113007) (xy 389.112252 -370.120164) (xy 389.134028 -370.145826)
			(xy 389.171978 -370.201411) (xy 389.203012 -370.261133) (xy 389.226686 -370.324136) (xy 389.24266 -370.389517)
			(xy 389.250705 -370.456339) (xy 389.250706 -370.523643) (xy 389.250706 -370.523644) (xy 418.929008 -370.523644)
			(xy 418.929009 -370.456338) (xy 418.937055 -370.389513) (xy 418.953031 -370.32413) (xy 418.976707 -370.261125)
			(xy 419.007745 -370.201401) (xy 419.045698 -370.145816) (xy 419.067488 -370.120164) (xy 419.073281 -370.113016)
			(xy 419.079798 -370.095828) (xy 419.080188 -370.086636) (xy 419.080188 -369.928902) (xy 419.080567 -369.918724)
			(xy 419.08836 -369.89992) (xy 419.10276 -369.885533) (xy 419.121572 -369.877757) (xy 419.13175 -369.87734)
			(xy 419.84803 -369.87734) (xy 419.85819 -369.877809) (xy 419.87696 -369.885593) (xy 419.891325 -369.899967)
			(xy 419.899098 -369.918742) (xy 419.899592 -369.928902) (xy 419.899592 -370.086636) (xy 419.899986 -370.095825)
			(xy 419.906511 -370.113009) (xy 419.912292 -370.120164) (xy 419.934067 -370.145826) (xy 419.972014 -370.201412)
			(xy 420.003046 -370.261134) (xy 420.026718 -370.324138) (xy 420.042691 -370.389518) (xy 420.050736 -370.456339)
			(xy 420.050737 -370.523643) (xy 420.05073 -370.523703) (xy 423.328801 -370.523703) (xy 423.328802 -370.456279)
			(xy 423.336878 -370.38934) (xy 423.352915 -370.323851) (xy 423.37668 -370.260753) (xy 423.407831 -370.200957)
			(xy 423.44592 -370.145322) (xy 423.467784 -370.119656) (xy 423.47358 -370.11251) (xy 423.480095 -370.09532)
			(xy 423.480484 -370.086128) (xy 423.480484 -369.928902) (xy 423.48093 -369.91877) (xy 423.488665 -369.900041)
			(xy 423.502964 -369.885683) (xy 423.521662 -369.877871) (xy 423.531792 -369.87734) (xy 424.248072 -369.87734)
			(xy 424.258198 -369.87774) (xy 424.276908 -369.885486) (xy 424.291225 -369.899808) (xy 424.298964 -369.918522)
			(xy 424.29938 -369.928648) (xy 424.29938 -370.086128) (xy 424.299781 -370.095316) (xy 424.306302 -370.1125)
			(xy 424.31208 -370.119656) (xy 424.333933 -370.145331) (xy 424.372023 -370.200963) (xy 424.403176 -370.260758)
			(xy 424.426941 -370.323854) (xy 424.442978 -370.389342) (xy 424.451055 -370.456279) (xy 424.451056 -370.523644)
			(xy 427.729096 -370.523644) (xy 427.729097 -370.456338) (xy 427.737143 -370.389514) (xy 427.753118 -370.32413)
			(xy 427.776794 -370.261125) (xy 427.80783 -370.201402) (xy 427.845783 -370.145816) (xy 427.867572 -370.120164)
			(xy 427.873375 -370.113024) (xy 427.879884 -370.095829) (xy 427.880272 -370.086636) (xy 427.880272 -369.928902)
			(xy 427.880666 -369.918726) (xy 427.888457 -369.899925) (xy 427.902852 -369.885539) (xy 427.921658 -369.87776)
			(xy 427.931834 -369.87734) (xy 428.648114 -369.87734) (xy 428.658273 -369.877822) (xy 428.677043 -369.885602)
			(xy 428.691407 -369.899971) (xy 428.699181 -369.918743) (xy 428.699676 -369.928902) (xy 428.699676 -370.086636)
			(xy 428.700074 -370.095824) (xy 428.706597 -370.113008) (xy 428.712376 -370.120164) (xy 428.734152 -370.145826)
			(xy 428.7721 -370.201411) (xy 428.803133 -370.261134) (xy 428.826806 -370.324137) (xy 428.842779 -370.389518)
			(xy 428.850824 -370.456339) (xy 428.850825 -370.523643) (xy 428.850825 -370.523644) (xy 432.128887 -370.523644)
			(xy 432.128888 -370.456338) (xy 432.136934 -370.389514) (xy 432.152909 -370.324131) (xy 432.176584 -370.261126)
			(xy 432.207619 -370.201402) (xy 432.245571 -370.145816) (xy 432.26736 -370.120164) (xy 432.273162 -370.113023)
			(xy 432.279672 -370.095829) (xy 432.28006 -370.086636) (xy 432.28006 -369.928902) (xy 432.280466 -369.918728)
			(xy 432.288254 -369.899929) (xy 432.302646 -369.885543) (xy 432.321448 -369.877762) (xy 432.331622 -369.87734)
			(xy 433.047902 -369.87734) (xy 433.05806 -369.877832) (xy 433.07683 -369.885607) (xy 433.091195 -369.899974)
			(xy 433.098969 -369.918744) (xy 433.099464 -369.928902) (xy 433.099464 -370.086636) (xy 433.099865 -370.095824)
			(xy 433.106386 -370.113008) (xy 433.112164 -370.120164) (xy 433.13394 -370.145826) (xy 433.171889 -370.201411)
			(xy 433.202922 -370.261133) (xy 433.226595 -370.324137) (xy 433.242569 -370.389518) (xy 433.250614 -370.456339)
			(xy 433.250615 -370.523643) (xy 433.242572 -370.590465) (xy 433.226601 -370.655846) (xy 433.20293 -370.71885)
			(xy 433.171898 -370.778573) (xy 433.133951 -370.83416) (xy 433.112164 -370.859812) (xy 433.106375 -370.866963)
			(xy 433.099857 -370.884149) (xy 433.099464 -370.89334) (xy 433.099464 -371.386862) (xy 433.099901 -371.396046)
			(xy 433.106397 -371.41323) (xy 433.112164 -371.42039) (xy 433.133966 -371.446031) (xy 433.171914 -371.501619)
			(xy 433.202946 -371.561344) (xy 433.226383 -371.623725) (xy 434.329029 -371.623725) (xy 434.329032 -371.556418)
			(xy 434.33708 -371.489593) (xy 434.353056 -371.424209) (xy 434.376732 -371.361203) (xy 434.407768 -371.301478)
			(xy 434.445719 -371.245891) (xy 434.467508 -371.220238) (xy 434.473314 -371.2131) (xy 434.479823 -371.195904)
			(xy 434.480208 -371.18671) (xy 434.480208 -371.028722) (xy 434.48075 -371.018569) (xy 434.488512 -370.999806)
			(xy 434.502863 -370.985441) (xy 434.521618 -370.977661) (xy 434.53177 -370.97716) (xy 435.24805 -370.97716)
			(xy 435.258221 -370.977605) (xy 435.277019 -370.985378) (xy 435.291406 -370.999758) (xy 435.299189 -371.018551)
			(xy 435.299612 -371.028722) (xy 435.299612 -371.18671) (xy 435.300015 -371.195898) (xy 435.306533 -371.213082)
			(xy 435.312312 -371.220238) (xy 435.334064 -371.24592) (xy 435.372017 -371.301501) (xy 435.403055 -371.36122)
			(xy 435.426732 -371.424221) (xy 435.442709 -371.4896) (xy 435.450757 -371.55642) (xy 435.45076 -371.623723)
			(xy 435.442719 -371.690544) (xy 435.426749 -371.755924) (xy 435.403078 -371.818928) (xy 435.372046 -371.87865)
			(xy 435.334099 -371.934235) (xy 435.312312 -371.959886) (xy 435.306498 -371.967019) (xy 435.299993 -371.984219)
			(xy 435.299612 -371.993414) (xy 435.299612 -372.486682) (xy 435.300028 -372.495869) (xy 435.306537 -372.513053)
			(xy 435.312312 -372.52021) (xy 435.334135 -372.545834) (xy 435.372086 -372.601423) (xy 435.40312 -372.66115)
			(xy 435.426793 -372.724159) (xy 435.442765 -372.789545) (xy 435.450807 -372.856371) (xy 435.450804 -372.92368)
			(xy 435.442756 -372.990506) (xy 435.426778 -373.05589) (xy 435.403099 -373.118896) (xy 435.372059 -373.178621)
			(xy 435.334103 -373.234206) (xy 435.312312 -373.259858) (xy 435.30651 -373.266999) (xy 435.299998 -373.284193)
			(xy 435.299612 -373.293386) (xy 435.299612 -373.451374) (xy 435.299213 -373.46155) (xy 435.291428 -373.480354)
			(xy 435.277034 -373.494741) (xy 435.258226 -373.502518) (xy 435.24805 -373.502936) (xy 434.53177 -373.502936)
			(xy 434.521607 -373.502491) (xy 434.502832 -373.494701) (xy 434.488467 -373.480321) (xy 434.480698 -373.461537)
			(xy 434.480208 -373.451374) (xy 434.480208 -373.293386) (xy 434.479803 -373.284198) (xy 434.473286 -373.267014)
			(xy 434.467508 -373.259858) (xy 434.445755 -373.234178) (xy 434.407807 -373.178595) (xy 434.376774 -373.118875)
			(xy 434.3531 -373.055874) (xy 434.337126 -372.990495) (xy 434.32908 -372.923676) (xy 434.329077 -372.856375)
			(xy 434.337117 -372.789555) (xy 434.353085 -372.724175) (xy 434.376753 -372.661172) (xy 434.40778 -372.601449)
			(xy 434.445723 -372.545863) (xy 434.467508 -372.52021) (xy 434.473326 -372.51308) (xy 434.479828 -372.495878)
			(xy 434.480208 -372.486682) (xy 434.480208 -371.993414) (xy 434.479789 -371.984228) (xy 434.473281 -371.967043)
			(xy 434.467508 -371.959886) (xy 434.445684 -371.934264) (xy 434.407738 -371.878673) (xy 434.376708 -371.818945)
			(xy 434.353039 -371.755936) (xy 434.33707 -371.690551) (xy 434.329029 -371.623725) (xy 433.226383 -371.623725)
			(xy 433.226618 -371.62435) (xy 433.24259 -371.689734) (xy 433.250633 -371.756557) (xy 433.250632 -371.823864)
			(xy 433.242586 -371.890687) (xy 433.226612 -371.95607) (xy 433.202938 -372.019075) (xy 433.171903 -372.078799)
			(xy 433.133953 -372.134386) (xy 433.112164 -372.160038) (xy 433.106364 -372.167181) (xy 433.099852 -372.184373)
			(xy 433.099464 -372.193566) (xy 433.099464 -372.351554) (xy 433.098999 -372.361722) (xy 433.091229 -372.380516)
			(xy 433.076856 -372.394902) (xy 433.05807 -372.402689) (xy 433.047902 -372.403116) (xy 432.331622 -372.403116)
			(xy 432.321446 -372.402717) (xy 432.302643 -372.394931) (xy 432.288256 -372.380537) (xy 432.280478 -372.36173)
			(xy 432.28006 -372.351554) (xy 432.28006 -372.193566) (xy 432.279653 -372.184379) (xy 432.273135 -372.167195)
			(xy 432.26736 -372.160038) (xy 432.245586 -372.134375) (xy 432.207635 -372.07879) (xy 432.1766 -372.019069)
			(xy 432.152925 -371.956065) (xy 432.136951 -371.890684) (xy 432.128905 -371.823863) (xy 432.128904 -371.756558)
			(xy 432.136947 -371.689736) (xy 432.152919 -371.624355) (xy 432.176591 -371.561351) (xy 432.207624 -371.501628)
			(xy 432.245573 -371.446042) (xy 432.26736 -371.42039) (xy 432.273151 -371.413241) (xy 432.279667 -371.396053)
			(xy 432.28006 -371.386862) (xy 432.28006 -370.89334) (xy 432.279617 -370.884157) (xy 432.273125 -370.866972)
			(xy 432.26736 -370.859812) (xy 432.24556 -370.83417) (xy 432.20761 -370.778582) (xy 432.176576 -370.718858)
			(xy 432.152903 -370.655852) (xy 432.136931 -370.590468) (xy 432.128887 -370.523644) (xy 428.850825 -370.523644)
			(xy 428.842782 -370.590464) (xy 428.826811 -370.655846) (xy 428.80314 -370.71885) (xy 428.772109 -370.778573)
			(xy 428.734163 -370.83416) (xy 428.712376 -370.859812) (xy 428.706589 -370.866964) (xy 428.700069 -370.884149)
			(xy 428.699676 -370.89334) (xy 428.699676 -371.386862) (xy 428.70011 -371.396047) (xy 428.706608 -371.413231)
			(xy 428.712376 -371.42039) (xy 428.734177 -371.446031) (xy 428.772125 -371.501619) (xy 428.803156 -371.561345)
			(xy 428.826615 -371.623785) (xy 429.928709 -371.623785) (xy 429.928713 -371.556358) (xy 429.936793 -371.489417)
			(xy 429.952833 -371.423925) (xy 429.976602 -371.360827) (xy 430.007759 -371.30103) (xy 430.045853 -371.245395)
			(xy 430.06772 -371.21973) (xy 430.073531 -371.212595) (xy 430.080036 -371.195397) (xy 430.08042 -371.186202)
			(xy 430.08042 -371.028722) (xy 430.080944 -371.018599) (xy 430.088661 -370.999882) (xy 430.102935 -370.985526)
			(xy 430.121608 -370.977702) (xy 430.131728 -370.97716) (xy 430.848008 -370.97716) (xy 430.858158 -370.977614)
			(xy 430.876902 -370.985405) (xy 430.891224 -370.999791) (xy 430.898931 -371.018571) (xy 430.899316 -371.028722)
			(xy 430.899316 -371.186202) (xy 430.899722 -371.19539) (xy 430.906238 -371.212574) (xy 430.912016 -371.21973)
			(xy 430.933842 -371.245426) (xy 430.971931 -371.301057) (xy 431.003082 -371.360849) (xy 431.026848 -371.423942)
			(xy 431.042886 -371.489427) (xy 431.050964 -371.556361) (xy 431.050968 -371.623782) (xy 431.042896 -371.690717)
			(xy 431.026865 -371.756204) (xy 431.003106 -371.819299) (xy 430.97196 -371.879094) (xy 430.933877 -371.934729)
			(xy 430.912016 -371.960394) (xy 430.906241 -371.967555) (xy 430.899713 -371.984733) (xy 430.899316 -371.993922)
			(xy 430.899316 -372.486174) (xy 430.899735 -372.49536) (xy 430.906242 -372.512545) (xy 430.912016 -372.519702)
			(xy 430.933913 -372.54534) (xy 430.971999 -372.600979) (xy 431.003148 -372.660779) (xy 431.026909 -372.723879)
			(xy 431.042942 -372.789371) (xy 431.051015 -372.856313) (xy 431.051012 -372.923739) (xy 431.042933 -372.990679)
			(xy 431.026894 -373.05617) (xy 431.003127 -373.119268) (xy 430.971973 -373.179065) (xy 430.933881 -373.2347)
			(xy 430.912016 -373.260366) (xy 430.906211 -373.267505) (xy 430.899701 -373.2847) (xy 430.899316 -373.293894)
			(xy 430.899316 -373.451374) (xy 430.898851 -373.461504) (xy 430.891124 -373.480233) (xy 430.87683 -373.494592)
			(xy 430.858136 -373.502405) (xy 430.848008 -373.502936) (xy 430.131728 -373.502936) (xy 430.12158 -373.502456)
			(xy 430.102835 -373.494677) (xy 430.088512 -373.480298) (xy 430.080805 -373.461523) (xy 430.08042 -373.451374)
			(xy 430.08042 -373.293894) (xy 430.080008 -373.284707) (xy 430.073495 -373.267523) (xy 430.06772 -373.260366)
			(xy 430.045889 -373.234674) (xy 430.007798 -373.179043) (xy 429.976644 -373.119251) (xy 429.952877 -373.056158)
			(xy 429.936839 -372.990672) (xy 429.92876 -372.923736) (xy 429.928757 -372.856315) (xy 429.93683 -372.789379)
			(xy 429.952862 -372.723891) (xy 429.976624 -372.660796) (xy 430.007771 -372.601) (xy 430.045857 -372.545367)
			(xy 430.06772 -372.519702) (xy 430.073501 -372.512546) (xy 430.080024 -372.495364) (xy 430.08042 -372.486174)
			(xy 430.08042 -371.993922) (xy 430.079995 -371.984737) (xy 430.073491 -371.967552) (xy 430.06772 -371.960394)
			(xy 430.045818 -371.93476) (xy 430.007729 -371.879121) (xy 429.976579 -371.819321) (xy 429.952816 -371.75622)
			(xy 429.936783 -371.690727) (xy 429.928709 -371.623785) (xy 428.826615 -371.623785) (xy 428.826828 -371.624351)
			(xy 428.842799 -371.689734) (xy 428.850842 -371.756558) (xy 428.850841 -371.823863) (xy 428.842795 -371.890687)
			(xy 428.826821 -371.95607) (xy 428.803148 -372.019075) (xy 428.772114 -372.078799) (xy 428.734164 -372.134386)
			(xy 428.712376 -372.160038) (xy 428.706578 -372.167182) (xy 428.700065 -372.184374) (xy 428.699676 -372.193566)
			(xy 428.699676 -372.351554) (xy 428.699199 -372.361721) (xy 428.691432 -372.380512) (xy 428.677062 -372.394898)
			(xy 428.65828 -372.402687) (xy 428.648114 -372.403116) (xy 427.931834 -372.403116) (xy 427.921659 -372.402707)
			(xy 427.902856 -372.394925) (xy 427.888469 -372.380534) (xy 427.880691 -372.361729) (xy 427.880272 -372.351554)
			(xy 427.880272 -372.193566) (xy 427.879884 -372.184376) (xy 427.873356 -372.167192) (xy 427.867572 -372.160038)
			(xy 427.845797 -372.134375) (xy 427.807846 -372.078791) (xy 427.77681 -372.019069) (xy 427.753135 -371.956066)
			(xy 427.73716 -371.890685) (xy 427.729114 -371.823863) (xy 427.729113 -371.756558) (xy 427.737156 -371.689736)
			(xy 427.753129 -371.624354) (xy 427.776801 -371.56135) (xy 427.807835 -371.501627) (xy 427.845784 -371.446042)
			(xy 427.867572 -371.42039) (xy 427.873364 -371.413242) (xy 427.879879 -371.396053) (xy 427.880272 -371.386862)
			(xy 427.880272 -370.89334) (xy 427.879849 -370.884154) (xy 427.873345 -370.866969) (xy 427.867572 -370.859812)
			(xy 427.845772 -370.83417) (xy 427.807821 -370.778583) (xy 427.776786 -370.718858) (xy 427.753113 -370.655852)
			(xy 427.73714 -370.590468) (xy 427.729096 -370.523644) (xy 424.451056 -370.523644) (xy 424.451056 -370.523703)
			(xy 424.442981 -370.59064) (xy 424.426947 -370.656129) (xy 424.403183 -370.719225) (xy 424.372033 -370.779021)
			(xy 424.333944 -370.834655) (xy 424.31208 -370.86032) (xy 424.30629 -370.86747) (xy 424.299772 -370.884657)
			(xy 424.29938 -370.893848) (xy 424.29938 -371.386354) (xy 424.299817 -371.395538) (xy 424.306312 -371.412723)
			(xy 424.31208 -371.419882) (xy 424.333958 -371.445536) (xy 424.372048 -371.501171) (xy 424.403199 -371.560969)
			(xy 424.426835 -371.623725) (xy 425.528941 -371.623725) (xy 425.528945 -371.556418) (xy 425.536992 -371.489593)
			(xy 425.552969 -371.424208) (xy 425.576645 -371.361202) (xy 425.607682 -371.301478) (xy 425.645634 -371.24589)
			(xy 425.667424 -371.220238) (xy 425.673232 -371.213101) (xy 425.679739 -371.195904) (xy 425.680124 -371.18671)
			(xy 425.680124 -371.028722) (xy 425.680582 -371.018554) (xy 425.688357 -370.999762) (xy 425.702732 -370.985377)
			(xy 425.721518 -370.977589) (xy 425.731686 -370.97716) (xy 426.447966 -370.97716) (xy 426.458138 -370.977592)
			(xy 426.476936 -370.98537) (xy 426.491323 -370.999754) (xy 426.499105 -371.01855) (xy 426.499528 -371.028722)
			(xy 426.499528 -371.18671) (xy 426.499927 -371.195898) (xy 426.506448 -371.213083) (xy 426.512228 -371.220238)
			(xy 426.533979 -371.24592) (xy 426.571931 -371.301502) (xy 426.602968 -371.361221) (xy 426.626645 -371.424221)
			(xy 426.642621 -371.4896) (xy 426.650669 -371.55642) (xy 426.650672 -371.623723) (xy 426.642631 -371.690543)
			(xy 426.626661 -371.755924) (xy 426.602991 -371.818927) (xy 426.571961 -371.878649) (xy 426.534014 -371.934234)
			(xy 426.512228 -371.959886) (xy 426.506404 -371.967011) (xy 426.499908 -371.984217) (xy 426.499528 -371.993414)
			(xy 426.499528 -372.486682) (xy 426.49994 -372.495869) (xy 426.506452 -372.513054) (xy 426.512228 -372.52021)
			(xy 426.53405 -372.545834) (xy 426.572 -372.601424) (xy 426.603034 -372.661151) (xy 426.626706 -372.724159)
			(xy 426.642678 -372.789545) (xy 426.65072 -372.856371) (xy 426.650717 -372.92368) (xy 426.642669 -372.990505)
			(xy 426.626691 -373.05589) (xy 426.603013 -373.118896) (xy 426.571974 -373.17862) (xy 426.534019 -373.234206)
			(xy 426.512228 -373.259858) (xy 426.506416 -373.266992) (xy 426.499912 -373.284191) (xy 426.499528 -373.293386)
			(xy 426.499528 -373.451374) (xy 426.499114 -373.461548) (xy 426.491331 -373.480349) (xy 426.476942 -373.494736)
			(xy 426.45814 -373.502515) (xy 426.447966 -373.502936) (xy 425.731686 -373.502936) (xy 425.72151 -373.502547)
			(xy 425.70271 -373.494752) (xy 425.688325 -373.480356) (xy 425.680545 -373.46155) (xy 425.680124 -373.451374)
			(xy 425.680124 -373.293386) (xy 425.679715 -373.284199) (xy 425.6732 -373.267015) (xy 425.667424 -373.259858)
			(xy 425.64567 -373.234178) (xy 425.607722 -373.178595) (xy 425.576688 -373.118875) (xy 425.553014 -373.055874)
			(xy 425.537039 -372.990496) (xy 425.528992 -372.923677) (xy 425.528989 -372.856375) (xy 425.53703 -372.789555)
			(xy 425.552999 -372.724174) (xy 425.576667 -372.661171) (xy 425.607695 -372.601449) (xy 425.645639 -372.545863)
			(xy 425.667424 -372.52021) (xy 425.673244 -372.513082) (xy 425.679744 -372.495878) (xy 425.680124 -372.486682)
			(xy 425.680124 -371.993414) (xy 425.679702 -371.984228) (xy 425.673196 -371.967044) (xy 425.667424 -371.959886)
			(xy 425.645599 -371.934264) (xy 425.607653 -371.878673) (xy 425.576622 -371.818945) (xy 425.552952 -371.755937)
			(xy 425.536982 -371.690551) (xy 425.528941 -371.623725) (xy 424.426835 -371.623725) (xy 424.426964 -371.624067)
			(xy 424.442999 -371.689558) (xy 424.451074 -371.756498) (xy 424.451072 -371.823923) (xy 424.442995 -371.890863)
			(xy 424.426957 -371.956353) (xy 424.403191 -372.01945) (xy 424.372037 -372.079247) (xy 424.333946 -372.134881)
			(xy 424.31208 -372.160546) (xy 424.306279 -372.167688) (xy 424.299768 -372.184881) (xy 424.29938 -372.194074)
			(xy 424.29938 -372.351554) (xy 424.298836 -372.361675) (xy 424.291127 -372.380392) (xy 424.276858 -372.394749)
			(xy 424.25819 -372.402573) (xy 424.248072 -372.403116) (xy 423.531792 -372.403116) (xy 423.521685 -372.402622)
			(xy 423.50301 -372.394884) (xy 423.488716 -372.38059) (xy 423.480978 -372.361915) (xy 423.480484 -372.351808)
			(xy 423.480484 -372.194074) (xy 423.48009 -372.184885) (xy 423.473565 -372.167701) (xy 423.467784 -372.160546)
			(xy 423.445934 -372.134869) (xy 423.407846 -372.079236) (xy 423.376696 -372.019441) (xy 423.352932 -371.956346)
			(xy 423.336896 -371.890858) (xy 423.328819 -371.823922) (xy 423.328818 -371.756499) (xy 423.336892 -371.689562)
			(xy 423.352925 -371.624074) (xy 423.376687 -371.560978) (xy 423.407835 -371.501182) (xy 423.445921 -371.445547)
			(xy 423.467784 -371.419882) (xy 423.473569 -371.412728) (xy 423.480091 -371.395544) (xy 423.480484 -371.386354)
			(xy 423.480484 -370.893848) (xy 423.480055 -370.884663) (xy 423.473555 -370.867478) (xy 423.467784 -370.86032)
			(xy 423.445909 -370.834664) (xy 423.407821 -370.779028) (xy 423.376672 -370.71923) (xy 423.352909 -370.656132)
			(xy 423.336875 -370.590642) (xy 423.328801 -370.523703) (xy 420.05073 -370.523703) (xy 420.042694 -370.590464)
			(xy 420.026724 -370.655845) (xy 420.003054 -370.718849) (xy 419.972023 -370.778573) (xy 419.934078 -370.834159)
			(xy 419.912292 -370.859812) (xy 419.906507 -370.866965) (xy 419.899986 -370.88415) (xy 419.899592 -370.89334)
			(xy 419.899592 -371.386862) (xy 419.900022 -371.396047) (xy 419.906522 -371.413231) (xy 419.912292 -371.42039)
			(xy 419.934093 -371.446031) (xy 419.972039 -371.50162) (xy 420.00307 -371.561345) (xy 420.026528 -371.623785)
			(xy 421.128621 -371.623785) (xy 421.128625 -371.556358) (xy 421.136705 -371.489416) (xy 421.152746 -371.423925)
			(xy 421.176516 -371.360826) (xy 421.207673 -371.301029) (xy 421.245769 -371.245395) (xy 421.267636 -371.21973)
			(xy 421.273449 -371.212597) (xy 421.279953 -371.195397) (xy 421.280336 -371.186202) (xy 421.280336 -371.028722)
			(xy 421.280844 -371.018597) (xy 421.288564 -370.999877) (xy 421.302844 -370.98552) (xy 421.321522 -370.9777)
			(xy 421.331644 -370.97716) (xy 422.047924 -370.97716) (xy 422.058029 -370.977664) (xy 422.076701 -370.985402)
			(xy 422.090993 -370.999693) (xy 422.098734 -371.018363) (xy 422.099232 -371.028468) (xy 422.099232 -371.186202)
			(xy 422.099656 -371.195387) (xy 422.106162 -371.212571) (xy 422.111932 -371.21973) (xy 422.133758 -371.245427)
			(xy 422.171845 -371.301057) (xy 422.202996 -371.36085) (xy 422.226761 -371.423942) (xy 422.242798 -371.489427)
			(xy 422.250876 -371.556361) (xy 422.25088 -371.623781) (xy 422.242808 -371.690717) (xy 422.226778 -371.756203)
			(xy 422.203019 -371.819298) (xy 422.171875 -371.879094) (xy 422.133793 -371.934728) (xy 422.111932 -371.960394)
			(xy 422.106147 -371.967547) (xy 422.099627 -371.984732) (xy 422.099232 -371.993922) (xy 422.099232 -372.486174)
			(xy 422.09967 -372.495358) (xy 422.106166 -372.512542) (xy 422.111932 -372.519702) (xy 422.133828 -372.54534)
			(xy 422.171914 -372.600979) (xy 422.203061 -372.66078) (xy 422.226822 -372.72388) (xy 422.242854 -372.789372)
			(xy 422.250927 -372.856313) (xy 422.250924 -372.923738) (xy 422.242845 -372.990678) (xy 422.226807 -373.056169)
			(xy 422.20304 -373.119267) (xy 422.171888 -373.179064) (xy 422.133797 -373.2347) (xy 422.111932 -373.260366)
			(xy 422.106117 -373.267498) (xy 422.099615 -373.284699) (xy 422.099232 -373.293894) (xy 422.099232 -373.451374)
			(xy 422.098751 -373.461503) (xy 422.091027 -373.480228) (xy 422.076738 -373.494587) (xy 422.05805 -373.502402)
			(xy 422.047924 -373.502936) (xy 421.331644 -373.502936) (xy 421.321529 -373.502449) (xy 421.302833 -373.494722)
			(xy 421.288519 -373.480427) (xy 421.280765 -373.461743) (xy 421.280336 -373.451628) (xy 421.280336 -373.293894)
			(xy 421.279921 -373.284708) (xy 421.27341 -373.267524) (xy 421.267636 -373.260366) (xy 421.245804 -373.234674)
			(xy 421.207712 -373.179044) (xy 421.176558 -373.119252) (xy 421.15279 -373.056158) (xy 421.136751 -372.990672)
			(xy 421.128672 -372.923736) (xy 421.128669 -372.856315) (xy 421.136742 -372.789378) (xy 421.152775 -372.72389)
			(xy 421.176537 -372.660795) (xy 421.207686 -372.601) (xy 421.245773 -372.545367) (xy 421.267636 -372.519702)
			(xy 421.273419 -372.512547) (xy 421.279941 -372.495364) (xy 421.280336 -372.486174) (xy 421.280336 -371.993922)
			(xy 421.279907 -371.984737) (xy 421.273406 -371.967553) (xy 421.267636 -371.960394) (xy 421.245733 -371.93476)
			(xy 421.207643 -371.879122) (xy 421.176492 -371.819322) (xy 421.152729 -371.756221) (xy 421.136695 -371.690727)
			(xy 421.128621 -371.623785) (xy 420.026528 -371.623785) (xy 420.026741 -371.624351) (xy 420.042712 -371.689734)
			(xy 420.050754 -371.756558) (xy 420.050753 -371.823863) (xy 420.042708 -371.890686) (xy 420.026734 -371.956069)
			(xy 420.003061 -372.019074) (xy 419.972028 -372.078798) (xy 419.93408 -372.134385) (xy 419.912292 -372.160038)
			(xy 419.906496 -372.167183) (xy 419.899981 -372.184374) (xy 419.899592 -372.193566) (xy 419.899592 -372.351554)
			(xy 419.899099 -372.361719) (xy 419.891335 -372.380507) (xy 419.876971 -372.394892) (xy 419.858194 -372.402684)
			(xy 419.84803 -372.403116) (xy 419.13175 -372.403116) (xy 419.121576 -372.402694) (xy 419.102773 -372.394917)
			(xy 419.088385 -372.38053) (xy 419.080607 -372.361728) (xy 419.080188 -372.351554) (xy 419.080188 -372.193566)
			(xy 419.079797 -372.184377) (xy 419.07327 -372.167192) (xy 419.067488 -372.160038) (xy 419.045713 -372.134375)
			(xy 419.00776 -372.078791) (xy 418.976724 -372.01907) (xy 418.953048 -371.956067) (xy 418.937072 -371.890685)
			(xy 418.929026 -371.823863) (xy 418.929025 -371.756558) (xy 418.937069 -371.689736) (xy 418.953042 -371.624354)
			(xy 418.976715 -371.561349) (xy 419.007749 -371.501627) (xy 419.0457 -371.446041) (xy 419.067488 -371.42039)
			(xy 419.07327 -371.413234) (xy 419.079794 -371.396052) (xy 419.080188 -371.386862) (xy 419.080188 -370.89334)
			(xy 419.079761 -370.884154) (xy 419.07326 -370.86697) (xy 419.067488 -370.859812) (xy 419.045687 -370.83417)
			(xy 419.007735 -370.778583) (xy 418.9767 -370.718859) (xy 418.953026 -370.655853) (xy 418.937052 -370.590469)
			(xy 418.929008 -370.523644) (xy 389.250706 -370.523644) (xy 389.242663 -370.590465) (xy 389.226691 -370.655847)
			(xy 389.203019 -370.718851) (xy 389.171987 -370.778574) (xy 389.134039 -370.83416) (xy 389.112252 -370.859812)
			(xy 389.106462 -370.866962) (xy 389.099945 -370.884149) (xy 389.099552 -370.89334) (xy 389.099552 -371.386862)
			(xy 389.099991 -371.396046) (xy 389.106486 -371.41323) (xy 389.112252 -371.42039) (xy 389.134054 -371.446031)
			(xy 389.172003 -371.501618) (xy 389.203036 -371.561344) (xy 389.226474 -371.623725) (xy 390.32912 -371.623725)
			(xy 390.329123 -371.556418) (xy 390.337171 -371.489593) (xy 390.353146 -371.42421) (xy 390.376822 -371.361204)
			(xy 390.407857 -371.301479) (xy 390.445807 -371.245891) (xy 390.467596 -371.220238) (xy 390.473401 -371.213099)
			(xy 390.479911 -371.195904) (xy 390.480296 -371.18671) (xy 390.480296 -371.028722) (xy 390.48085 -371.018571)
			(xy 390.48861 -370.99981) (xy 390.502956 -370.985446) (xy 390.521707 -370.977663) (xy 390.531858 -370.97716)
			(xy 391.248138 -370.97716) (xy 391.258301 -370.977603) (xy 391.277075 -370.985394) (xy 391.29144 -370.999775)
			(xy 391.299209 -371.018558) (xy 391.2997 -371.028722) (xy 391.2997 -371.18671) (xy 391.300106 -371.195898)
			(xy 391.306623 -371.213082) (xy 391.3124 -371.220238) (xy 391.334149 -371.245921) (xy 391.372097 -371.301504)
			(xy 391.403129 -371.361224) (xy 391.426803 -371.424224) (xy 391.442777 -371.489602) (xy 391.450824 -371.556421)
			(xy 391.450827 -371.623722) (xy 391.442787 -371.690541) (xy 391.42682 -371.755921) (xy 391.403153 -371.818924)
			(xy 391.372126 -371.878647) (xy 391.334184 -371.934233) (xy 391.3124 -371.959886) (xy 391.306584 -371.967018)
			(xy 391.300081 -371.984219) (xy 391.2997 -371.993414) (xy 391.2997 -372.486682) (xy 391.300119 -372.495868)
			(xy 391.306627 -372.513053) (xy 391.3124 -372.52021) (xy 391.33422 -372.545835) (xy 391.372165 -372.601426)
			(xy 391.403195 -372.661154) (xy 391.426864 -372.724162) (xy 391.442833 -372.789547) (xy 391.450874 -372.856372)
			(xy 391.450871 -372.923679) (xy 391.442824 -372.990503) (xy 391.426849 -373.055887) (xy 391.403174 -373.118893)
			(xy 391.372139 -373.178617) (xy 391.334189 -373.234205) (xy 391.3124 -373.259858) (xy 391.306596 -373.266998)
			(xy 391.300086 -373.284193) (xy 391.2997 -373.293386) (xy 391.2997 -373.451374) (xy 391.299146 -373.461525)
			(xy 391.291388 -373.480287) (xy 391.277041 -373.494652) (xy 391.258289 -373.502434) (xy 391.248138 -373.502936)
			(xy 390.531858 -373.502936) (xy 390.521694 -373.5025) (xy 390.502919 -373.494707) (xy 390.488555 -373.480324)
			(xy 390.480786 -373.461538) (xy 390.480296 -373.451374) (xy 390.480296 -373.293386) (xy 390.479893 -373.284198)
			(xy 390.473374 -373.267014) (xy 390.467596 -373.259858) (xy 390.445843 -373.234178) (xy 390.407896 -373.178594)
			(xy 390.376864 -373.118874) (xy 390.353191 -373.055874) (xy 390.337217 -372.990495) (xy 390.329171 -372.923676)
			(xy 390.329167 -372.856375) (xy 390.337208 -372.789555) (xy 390.353176 -372.724175) (xy 390.376843 -372.661173)
			(xy 390.40787 -372.60145) (xy 390.445812 -372.545863) (xy 390.467596 -372.52021) (xy 390.473413 -372.513079)
			(xy 390.479916 -372.495878) (xy 390.480296 -372.486682) (xy 390.480296 -371.993414) (xy 390.47988 -371.984227)
			(xy 390.47337 -371.967043) (xy 390.467596 -371.959886) (xy 390.445772 -371.934264) (xy 390.407827 -371.878672)
			(xy 390.376798 -371.818944) (xy 390.353129 -371.755936) (xy 390.33716 -371.69055) (xy 390.32912 -371.623725)
			(xy 389.226474 -371.623725) (xy 389.226709 -371.62435) (xy 389.242681 -371.689733) (xy 389.250724 -371.756557)
			(xy 389.250723 -371.823864) (xy 389.242677 -371.890687) (xy 389.226702 -371.956071) (xy 389.203028 -372.019076)
			(xy 389.171992 -372.0788) (xy 389.134041 -372.134386) (xy 389.112252 -372.160038) (xy 389.106451 -372.16718)
			(xy 389.09994 -372.184373) (xy 389.099552 -372.193566) (xy 389.099552 -372.351554) (xy 389.099098 -372.361724)
			(xy 389.091327 -372.380519) (xy 389.07695 -372.394906) (xy 389.05816 -372.402691) (xy 389.04799 -372.403116)
			(xy 388.33171 -372.403116) (xy 388.321533 -372.402727) (xy 388.30273 -372.394937) (xy 388.288343 -372.38054)
			(xy 388.280566 -372.361731) (xy 388.280148 -372.351554) (xy 388.280148 -372.193566) (xy 388.279743 -372.184378)
			(xy 388.273225 -372.167195) (xy 388.267448 -372.160038) (xy 388.245674 -372.134375) (xy 388.207724 -372.07879)
			(xy 388.17669 -372.019068) (xy 388.153016 -371.956065) (xy 388.137042 -371.890684) (xy 388.128996 -371.823863)
			(xy 388.128995 -371.756558) (xy 388.137038 -371.689737) (xy 388.15301 -371.624355) (xy 388.176681 -371.561351)
			(xy 388.207713 -371.501628) (xy 388.245661 -371.446042) (xy 388.267448 -371.42039) (xy 388.273237 -371.41324)
			(xy 388.279755 -371.396053) (xy 388.280148 -371.386862) (xy 388.280148 -370.89334) (xy 388.279708 -370.884156)
			(xy 388.273214 -370.866972) (xy 388.267448 -370.859812) (xy 388.245648 -370.83417) (xy 388.207699 -370.778582)
			(xy 388.176666 -370.718857) (xy 388.152993 -370.655851) (xy 388.137021 -370.590468) (xy 388.128977 -370.523644)
			(xy 384.850915 -370.523644) (xy 384.842872 -370.590465) (xy 384.826901 -370.655846) (xy 384.80323 -370.71885)
			(xy 384.772198 -370.778573) (xy 384.734251 -370.83416) (xy 384.712464 -370.859812) (xy 384.706675 -370.866963)
			(xy 384.700157 -370.884149) (xy 384.699764 -370.89334) (xy 384.699764 -371.386862) (xy 384.700201 -371.396046)
			(xy 384.706697 -371.41323) (xy 384.712464 -371.42039) (xy 384.734266 -371.446031) (xy 384.772214 -371.501619)
			(xy 384.803246 -371.561344) (xy 384.826706 -371.623785) (xy 385.9288 -371.623785) (xy 385.928804 -371.556358)
			(xy 385.936884 -371.489417) (xy 385.952923 -371.423926) (xy 385.976692 -371.360827) (xy 386.007848 -371.30103)
			(xy 386.045941 -371.245395) (xy 386.067808 -371.21973) (xy 386.073618 -371.212594) (xy 386.080124 -371.195396)
			(xy 386.080508 -371.186202) (xy 386.080508 -371.028722) (xy 386.081044 -371.018601) (xy 386.088758 -370.999886)
			(xy 386.103029 -370.98553) (xy 386.121698 -370.977704) (xy 386.131816 -370.97716) (xy 386.848096 -370.97716)
			(xy 386.858245 -370.977624) (xy 386.876989 -370.985411) (xy 386.891311 -370.999794) (xy 386.899019 -371.018571)
			(xy 386.899404 -371.028722) (xy 386.899404 -371.186202) (xy 386.899812 -371.195389) (xy 386.906327 -371.212574)
			(xy 386.912104 -371.21973) (xy 386.93393 -371.245426) (xy 386.97202 -371.301056) (xy 387.003172 -371.360848)
			(xy 387.026938 -371.423941) (xy 387.042976 -371.489426) (xy 387.051055 -371.556361) (xy 387.051059 -371.623782)
			(xy 387.042987 -371.690717) (xy 387.026955 -371.756204) (xy 387.003196 -371.8193) (xy 386.972049 -371.879095)
			(xy 386.933966 -371.934729) (xy 386.912104 -371.960394) (xy 386.906328 -371.967554) (xy 386.899801 -371.984733)
			(xy 386.899404 -371.993922) (xy 386.899404 -372.486174) (xy 386.899826 -372.49536) (xy 386.906331 -372.512545)
			(xy 386.912104 -372.519702) (xy 386.934001 -372.54534) (xy 386.972089 -372.600978) (xy 387.003238 -372.660778)
			(xy 387.027 -372.723879) (xy 387.043033 -372.789371) (xy 387.051106 -372.856312) (xy 387.051103 -372.923739)
			(xy 387.043024 -372.990679) (xy 387.026985 -373.05617) (xy 387.003217 -373.119268) (xy 386.972062 -373.179066)
			(xy 386.93397 -373.234701) (xy 386.912104 -373.260366) (xy 386.906297 -373.267504) (xy 386.899789 -373.2847)
			(xy 386.899404 -373.293894) (xy 386.899404 -373.451374) (xy 386.898854 -373.461494) (xy 386.891142 -373.480206)
			(xy 386.876876 -373.494562) (xy 386.858212 -373.50239) (xy 386.848096 -373.502936) (xy 386.131816 -373.502936)
			(xy 386.121667 -373.502466) (xy 386.102922 -373.494683) (xy 386.0886 -373.480301) (xy 386.080893 -373.461524)
			(xy 386.080508 -373.451374) (xy 386.080508 -373.293894) (xy 386.080099 -373.284707) (xy 386.073584 -373.267523)
			(xy 386.067808 -373.260366) (xy 386.045977 -373.234673) (xy 386.007887 -373.179043) (xy 385.976734 -373.119251)
			(xy 385.952968 -373.056157) (xy 385.93693 -372.990671) (xy 385.928851 -372.923736) (xy 385.928848 -372.856315)
			(xy 385.936921 -372.789379) (xy 385.952953 -372.723892) (xy 385.976713 -372.660796) (xy 386.007861 -372.601001)
			(xy 386.045946 -372.545367) (xy 386.067808 -372.519702) (xy 386.073587 -372.512544) (xy 386.080112 -372.495363)
			(xy 386.080508 -372.486174) (xy 386.080508 -371.993922) (xy 386.080085 -371.984736) (xy 386.07358 -371.967552)
			(xy 386.067808 -371.960394) (xy 386.045906 -371.93476) (xy 386.007818 -371.879121) (xy 385.976669 -371.819321)
			(xy 385.952906 -371.75622) (xy 385.936873 -371.690727) (xy 385.9288 -371.623785) (xy 384.826706 -371.623785)
			(xy 384.826918 -371.62435) (xy 384.84289 -371.689734) (xy 384.850933 -371.756557) (xy 384.850932 -371.823864)
			(xy 384.842886 -371.890687) (xy 384.826912 -371.95607) (xy 384.803238 -372.019075) (xy 384.772203 -372.078799)
			(xy 384.734253 -372.134386) (xy 384.712464 -372.160038) (xy 384.706664 -372.167181) (xy 384.700152 -372.184373)
			(xy 384.699764 -372.193566) (xy 384.699764 -372.351554) (xy 384.699299 -372.361722) (xy 384.691529 -372.380516)
			(xy 384.677156 -372.394902) (xy 384.65837 -372.402689) (xy 384.648202 -372.403116) (xy 383.931922 -372.403116)
			(xy 383.921746 -372.402717) (xy 383.902943 -372.394931) (xy 383.888556 -372.380537) (xy 383.880778 -372.36173)
			(xy 383.88036 -372.351554) (xy 383.88036 -372.193566) (xy 383.879953 -372.184379) (xy 383.873435 -372.167195)
			(xy 383.86766 -372.160038) (xy 383.845886 -372.134375) (xy 383.807935 -372.07879) (xy 383.7769 -372.019069)
			(xy 383.753225 -371.956065) (xy 383.737251 -371.890684) (xy 383.729205 -371.823863) (xy 383.729204 -371.756558)
			(xy 383.737247 -371.689736) (xy 383.753219 -371.624355) (xy 383.776891 -371.561351) (xy 383.807924 -371.501628)
			(xy 383.845873 -371.446042) (xy 383.86766 -371.42039) (xy 383.873451 -371.413241) (xy 383.879967 -371.396053)
			(xy 383.88036 -371.386862) (xy 383.88036 -370.89334) (xy 383.879917 -370.884157) (xy 383.873425 -370.866972)
			(xy 383.86766 -370.859812) (xy 383.84586 -370.83417) (xy 383.80791 -370.778582) (xy 383.776876 -370.718858)
			(xy 383.753203 -370.655852) (xy 383.737231 -370.590468) (xy 383.729187 -370.523644) (xy 380.451147 -370.523644)
			(xy 380.451147 -370.523703) (xy 380.443072 -370.590641) (xy 380.427037 -370.656129) (xy 380.403273 -370.719226)
			(xy 380.372122 -370.779022) (xy 380.334032 -370.834655) (xy 380.312168 -370.86032) (xy 380.306376 -370.867469)
			(xy 380.299859 -370.884657) (xy 380.299468 -370.893848) (xy 380.299468 -371.386354) (xy 380.299908 -371.395538)
			(xy 380.306402 -371.412722) (xy 380.312168 -371.419882) (xy 380.334047 -371.445535) (xy 380.372137 -371.501171)
			(xy 380.403289 -371.560968) (xy 380.426925 -371.623725) (xy 381.529032 -371.623725) (xy 381.529035 -371.556418)
			(xy 381.537083 -371.489593) (xy 381.553059 -371.424209) (xy 381.576735 -371.361203) (xy 381.607771 -371.301478)
			(xy 381.645723 -371.245891) (xy 381.667512 -371.220238) (xy 381.673319 -371.2131) (xy 381.679827 -371.195904)
			(xy 381.680212 -371.18671) (xy 381.680212 -371.028722) (xy 381.680751 -371.018569) (xy 381.688513 -370.999805)
			(xy 381.702865 -370.98544) (xy 381.721621 -370.97766) (xy 381.731774 -370.97716) (xy 382.448054 -370.97716)
			(xy 382.458225 -370.977602) (xy 382.477023 -370.985376) (xy 382.491411 -370.999757) (xy 382.499193 -371.018551)
			(xy 382.499616 -371.028722) (xy 382.499616 -371.18671) (xy 382.500018 -371.195898) (xy 382.506537 -371.213083)
			(xy 382.512316 -371.220238) (xy 382.534068 -371.24592) (xy 382.572021 -371.301501) (xy 382.603058 -371.36122)
			(xy 382.626735 -371.424221) (xy 382.642712 -371.4896) (xy 382.65076 -371.55642) (xy 382.650763 -371.623723)
			(xy 382.642722 -371.690544) (xy 382.626752 -371.755924) (xy 382.603081 -371.818927) (xy 382.57205 -371.87865)
			(xy 382.534103 -371.934234) (xy 382.512316 -371.959886) (xy 382.506502 -371.967019) (xy 382.499997 -371.984219)
			(xy 382.499616 -371.993414) (xy 382.499616 -372.486682) (xy 382.500031 -372.495869) (xy 382.506541 -372.513053)
			(xy 382.512316 -372.52021) (xy 382.534138 -372.545834) (xy 382.572089 -372.601424) (xy 382.603123 -372.661151)
			(xy 382.626796 -372.724159) (xy 382.642768 -372.789545) (xy 382.65081 -372.856371) (xy 382.650807 -372.92368)
			(xy 382.642759 -372.990506) (xy 382.626781 -373.05589) (xy 382.603103 -373.118896) (xy 382.572063 -373.17862)
			(xy 382.534107 -373.234206) (xy 382.512316 -373.259858) (xy 382.506514 -373.267) (xy 382.500002 -373.284193)
			(xy 382.499616 -373.293386) (xy 382.499616 -373.451374) (xy 382.499214 -373.46155) (xy 382.491429 -373.480352)
			(xy 382.477036 -373.49474) (xy 382.45823 -373.502517) (xy 382.448054 -373.502936) (xy 381.731774 -373.502936)
			(xy 381.721611 -373.502487) (xy 381.702837 -373.4947) (xy 381.688471 -373.48032) (xy 381.680702 -373.461537)
			(xy 381.680212 -373.451374) (xy 381.680212 -373.293386) (xy 381.679806 -373.284198) (xy 381.673289 -373.267014)
			(xy 381.667512 -373.259858) (xy 381.645758 -373.234178) (xy 381.60781 -373.178595) (xy 381.576777 -373.118875)
			(xy 381.553104 -373.055874) (xy 381.537129 -372.990496) (xy 381.529083 -372.923676) (xy 381.52908 -372.856375)
			(xy 381.53712 -372.789555) (xy 381.553088 -372.724175) (xy 381.576756 -372.661172) (xy 381.607784 -372.601449)
			(xy 381.645727 -372.545862) (xy 381.667512 -372.52021) (xy 381.673331 -372.51308) (xy 381.679832 -372.495878)
			(xy 381.680212 -372.486682) (xy 381.680212 -371.993414) (xy 381.679792 -371.984228) (xy 381.673285 -371.967044)
			(xy 381.667512 -371.959886) (xy 381.645688 -371.934264) (xy 381.607742 -371.878673) (xy 381.576712 -371.818945)
			(xy 381.553042 -371.755936) (xy 381.537073 -371.690551) (xy 381.529032 -371.623725) (xy 380.426925 -371.623725)
			(xy 380.427054 -371.624067) (xy 380.443089 -371.689558) (xy 380.451165 -371.756498) (xy 380.451163 -371.823923)
			(xy 380.443086 -371.890863) (xy 380.427048 -371.956353) (xy 380.403281 -372.019451) (xy 380.372126 -372.079247)
			(xy 380.334034 -372.134881) (xy 380.312168 -372.160546) (xy 380.306365 -372.167687) (xy 380.299855 -372.184881)
			(xy 380.299468 -372.194074) (xy 380.299468 -372.351554) (xy 380.298936 -372.361677) (xy 380.291225 -372.380395)
			(xy 380.276952 -372.394753) (xy 380.25828 -372.402575) (xy 380.24816 -372.403116) (xy 379.53188 -372.403116)
			(xy 379.521727 -372.402695) (xy 379.502977 -372.394896) (xy 379.488655 -372.3805) (xy 379.480953 -372.36171)
			(xy 379.480572 -372.351554) (xy 379.480572 -372.194074) (xy 379.480181 -372.184885) (xy 379.473655 -372.1677)
			(xy 379.467872 -372.160546) (xy 379.446023 -372.134869) (xy 379.407935 -372.079235) (xy 379.376786 -372.019441)
			(xy 379.353022 -371.956345) (xy 379.336986 -371.890858) (xy 379.32891 -371.823922) (xy 379.328909 -371.7565)
			(xy 379.336983 -371.689563) (xy 379.353016 -371.624075) (xy 379.376777 -371.560979) (xy 379.407925 -371.501183)
			(xy 379.44601 -371.445548) (xy 379.467872 -371.419882) (xy 379.473667 -371.412736) (xy 379.480181 -371.395546)
			(xy 379.480572 -371.386354) (xy 379.480572 -370.893848) (xy 379.480145 -370.884663) (xy 379.473644 -370.867478)
			(xy 379.467872 -370.86032) (xy 379.445997 -370.834664) (xy 379.407911 -370.779027) (xy 379.376762 -370.71923)
			(xy 379.353 -370.656132) (xy 379.336966 -370.590642) (xy 379.328892 -370.523703) (xy 376.050821 -370.523703)
			(xy 376.042785 -370.590464) (xy 376.026814 -370.655846) (xy 376.003143 -370.71885) (xy 375.972113 -370.778573)
			(xy 375.934166 -370.83416) (xy 375.91238 -370.859812) (xy 375.906594 -370.866964) (xy 375.900073 -370.884149)
			(xy 375.89968 -370.89334) (xy 375.89968 -371.386862) (xy 375.900113 -371.396047) (xy 375.906611 -371.413231)
			(xy 375.91238 -371.42039) (xy 375.934181 -371.446031) (xy 375.972128 -371.50162) (xy 376.00316 -371.561345)
			(xy 376.026618 -371.623785) (xy 377.128712 -371.623785) (xy 377.128716 -371.556358) (xy 377.136796 -371.489417)
			(xy 377.152836 -371.423925) (xy 377.176606 -371.360827) (xy 377.207762 -371.301029) (xy 377.245857 -371.245395)
			(xy 377.267724 -371.21973) (xy 377.273536 -371.212596) (xy 377.28004 -371.195397) (xy 377.280424 -371.186202)
			(xy 377.280424 -371.028722) (xy 377.280944 -371.018599) (xy 377.288662 -370.999881) (xy 377.302938 -370.985524)
			(xy 377.321612 -370.977702) (xy 377.331732 -370.97716) (xy 378.048012 -370.97716) (xy 378.058162 -370.977611)
			(xy 378.076907 -370.985403) (xy 378.091229 -370.99979) (xy 378.098935 -371.01857) (xy 378.09932 -371.028722)
			(xy 378.09932 -371.186202) (xy 378.099725 -371.19539) (xy 378.106242 -371.212574) (xy 378.11202 -371.21973)
			(xy 378.133846 -371.245426) (xy 378.171934 -371.301057) (xy 378.203086 -371.360849) (xy 378.226851 -371.423942)
			(xy 378.242889 -371.489427) (xy 378.250967 -371.556361) (xy 378.250971 -371.623782) (xy 378.242899 -371.690717)
			(xy 378.226868 -371.756204) (xy 378.203109 -371.819299) (xy 378.171964 -371.879094) (xy 378.133881 -371.934728)
			(xy 378.11202 -371.960394) (xy 378.106246 -371.967555) (xy 378.099717 -371.984733) (xy 378.09932 -371.993922)
			(xy 378.09932 -372.486174) (xy 378.099738 -372.49536) (xy 378.106246 -372.512545) (xy 378.11202 -372.519702)
			(xy 378.133917 -372.54534) (xy 378.172003 -372.600979) (xy 378.203151 -372.660779) (xy 378.226913 -372.723879)
			(xy 378.242945 -372.789372) (xy 378.251018 -372.856313) (xy 378.251015 -372.923739) (xy 378.242936 -372.990679)
			(xy 378.226897 -373.056169) (xy 378.20313 -373.119268) (xy 378.171977 -373.179065) (xy 378.133885 -373.2347)
			(xy 378.11202 -373.260366) (xy 378.106215 -373.267506) (xy 378.099705 -373.2847) (xy 378.09932 -373.293894)
			(xy 378.09932 -373.451374) (xy 378.098851 -373.461504) (xy 378.091125 -373.480232) (xy 378.076832 -373.494591)
			(xy 378.05814 -373.502404) (xy 378.048012 -373.502936) (xy 377.331732 -373.502936) (xy 377.321584 -373.502453)
			(xy 377.30284 -373.494675) (xy 377.288516 -373.480297) (xy 377.280809 -373.461523) (xy 377.280424 -373.451374)
			(xy 377.280424 -373.293894) (xy 377.280012 -373.284707) (xy 377.273499 -373.267523) (xy 377.267724 -373.260366)
			(xy 377.245893 -373.234674) (xy 377.207801 -373.179044) (xy 377.176648 -373.119251) (xy 377.152881 -373.056158)
			(xy 377.136842 -372.990672) (xy 377.128763 -372.923736) (xy 377.12876 -372.856315) (xy 377.136833 -372.789378)
			(xy 377.152865 -372.723891) (xy 377.176627 -372.660795) (xy 377.207775 -372.601) (xy 377.245861 -372.545367)
			(xy 377.267724 -372.519702) (xy 377.273505 -372.512546) (xy 377.280028 -372.495364) (xy 377.280424 -372.486174)
			(xy 377.280424 -371.993922) (xy 377.279998 -371.984737) (xy 377.273495 -371.967552) (xy 377.267724 -371.960394)
			(xy 377.245822 -371.93476) (xy 377.207733 -371.879122) (xy 377.176582 -371.819321) (xy 377.152819 -371.75622)
			(xy 377.136786 -371.690727) (xy 377.128712 -371.623785) (xy 376.026618 -371.623785) (xy 376.026831 -371.624351)
			(xy 376.042802 -371.689734) (xy 376.050845 -371.756558) (xy 376.050844 -371.823863) (xy 376.042799 -371.890687)
			(xy 376.026825 -371.956069) (xy 376.003151 -372.019074) (xy 375.972117 -372.078799) (xy 375.934168 -372.134386)
			(xy 375.91238 -372.160038) (xy 375.906582 -372.167182) (xy 375.900069 -372.184374) (xy 375.89968 -372.193566)
			(xy 375.89968 -372.351554) (xy 375.899199 -372.36172) (xy 375.891432 -372.380511) (xy 375.877064 -372.394896)
			(xy 375.858284 -372.402686) (xy 375.848118 -372.403116) (xy 375.131838 -372.403116) (xy 375.121663 -372.402704)
			(xy 375.102861 -372.394923) (xy 375.088473 -372.380533) (xy 375.080695 -372.361729) (xy 375.080276 -372.351554)
			(xy 375.080276 -372.193566) (xy 375.079887 -372.184376) (xy 375.073359 -372.167192) (xy 375.067576 -372.160038)
			(xy 375.045801 -372.134375) (xy 375.007849 -372.078791) (xy 374.976813 -372.019069) (xy 374.953138 -371.956066)
			(xy 374.937163 -371.890685) (xy 374.929117 -371.823863) (xy 374.929116 -371.756558) (xy 374.937159 -371.689736)
			(xy 374.953132 -371.624354) (xy 374.976805 -371.56135) (xy 375.007838 -371.501627) (xy 375.045788 -371.446042)
			(xy 375.067576 -371.42039) (xy 375.073357 -371.413233) (xy 375.079882 -371.396052) (xy 375.080276 -371.386862)
			(xy 375.080276 -370.89334) (xy 375.079852 -370.884154) (xy 375.073349 -370.866969) (xy 375.067576 -370.859812)
			(xy 375.045775 -370.83417) (xy 375.007825 -370.778583) (xy 374.97679 -370.718858) (xy 374.953116 -370.655852)
			(xy 374.937143 -370.590469) (xy 374.929099 -370.523644) (xy 345.250797 -370.523644) (xy 345.242754 -370.590465)
			(xy 345.226782 -370.655847) (xy 345.203109 -370.718851) (xy 345.172076 -370.778574) (xy 345.134128 -370.83416)
			(xy 345.11234 -370.859812) (xy 345.106548 -370.86696) (xy 345.100032 -370.884149) (xy 345.09964 -370.89334)
			(xy 345.09964 -371.386862) (xy 345.100082 -371.396046) (xy 345.106575 -371.41323) (xy 345.11234 -371.42039)
			(xy 345.134142 -371.446031) (xy 345.172092 -371.501618) (xy 345.203126 -371.561343) (xy 345.226564 -371.623726)
			(xy 346.329187 -371.623726) (xy 346.32919 -371.556417) (xy 346.337239 -371.489591) (xy 346.353217 -371.424206)
			(xy 346.376896 -371.3612) (xy 346.407936 -371.301476) (xy 346.445893 -371.24589) (xy 346.467684 -371.220238)
			(xy 346.473488 -371.213098) (xy 346.479999 -371.195904) (xy 346.480384 -371.18671) (xy 346.480384 -371.028722)
			(xy 346.480783 -371.018546) (xy 346.488569 -370.999743) (xy 346.502963 -370.985356) (xy 346.52177 -370.977578)
			(xy 346.531946 -370.97716) (xy 347.248226 -370.97716) (xy 347.258388 -370.977612) (xy 347.277162 -370.9854)
			(xy 347.291527 -370.999778) (xy 347.299297 -371.018559) (xy 347.299788 -371.028722) (xy 347.299788 -371.18671)
			(xy 347.300196 -371.195897) (xy 347.306711 -371.213082) (xy 347.312488 -371.220238) (xy 347.334237 -371.245921)
			(xy 347.372185 -371.301504) (xy 347.403219 -371.361224) (xy 347.426893 -371.424224) (xy 347.442867 -371.489602)
			(xy 347.450914 -371.556421) (xy 347.450918 -371.623722) (xy 347.442878 -371.690542) (xy 347.426909 -371.755921)
			(xy 347.403242 -371.818924) (xy 347.372215 -371.878647) (xy 347.334272 -371.934233) (xy 347.312488 -371.959886)
			(xy 347.306671 -371.967017) (xy 347.300169 -371.984218) (xy 347.299788 -371.993414) (xy 347.299788 -372.486682)
			(xy 347.30021 -372.495868) (xy 347.306716 -372.513052) (xy 347.312488 -372.52021) (xy 347.334308 -372.545835)
			(xy 347.372254 -372.601426) (xy 347.403285 -372.661154) (xy 347.426954 -372.724162) (xy 347.442924 -372.789547)
			(xy 347.450965 -372.856372) (xy 347.450962 -372.923679) (xy 347.442915 -372.990504) (xy 347.426939 -373.055887)
			(xy 347.403264 -373.118893) (xy 347.372228 -373.178618) (xy 347.334277 -373.234205) (xy 347.312488 -373.259858)
			(xy 347.306683 -373.266997) (xy 347.300174 -373.284192) (xy 347.299788 -373.293386) (xy 347.299788 -373.451374)
			(xy 347.299246 -373.461527) (xy 347.291485 -373.480291) (xy 347.277134 -373.494656) (xy 347.258378 -373.502436)
			(xy 347.248226 -373.502936) (xy 346.531946 -373.502936) (xy 346.521774 -373.502498) (xy 346.502975 -373.494723)
			(xy 346.488588 -373.480341) (xy 346.480806 -373.461546) (xy 346.480384 -373.451374) (xy 346.480384 -373.293386)
			(xy 346.479984 -373.284198) (xy 346.473464 -373.267013) (xy 346.467684 -373.259858) (xy 346.445928 -373.234179)
			(xy 346.407976 -373.178597) (xy 346.376938 -373.118878) (xy 346.353262 -373.055877) (xy 346.337285 -372.990498)
			(xy 346.329237 -372.923677) (xy 346.329234 -372.856374) (xy 346.337276 -372.789553) (xy 346.353247 -372.724172)
			(xy 346.376917 -372.661169) (xy 346.407949 -372.601447) (xy 346.445897 -372.545862) (xy 346.467684 -372.52021)
			(xy 346.473499 -372.513078) (xy 346.480003 -372.495877) (xy 346.480384 -372.486682) (xy 346.480384 -371.993414)
			(xy 346.479971 -371.984227) (xy 346.47346 -371.967042) (xy 346.467684 -371.959886) (xy 346.445858 -371.934265)
			(xy 346.407907 -371.878675) (xy 346.376873 -371.818948) (xy 346.3532 -371.755939) (xy 346.337229 -371.690553)
			(xy 346.329187 -371.623726) (xy 345.226564 -371.623726) (xy 345.226798 -371.624349) (xy 345.242771 -371.689733)
			(xy 345.250814 -371.756557) (xy 345.250813 -371.823864) (xy 345.242767 -371.890688) (xy 345.226792 -371.956071)
			(xy 345.203117 -372.019076) (xy 345.172081 -372.0788) (xy 345.134129 -372.134386) (xy 345.11234 -372.160038)
			(xy 345.106537 -372.167179) (xy 345.100028 -372.184373) (xy 345.09964 -372.193566) (xy 345.09964 -372.351554)
			(xy 345.099198 -372.361725) (xy 345.091424 -372.380523) (xy 345.077043 -372.394911) (xy 345.058249 -372.402693)
			(xy 345.048078 -372.403116) (xy 344.331798 -372.403116) (xy 344.321621 -372.402737) (xy 344.302817 -372.394942)
			(xy 344.288431 -372.380543) (xy 344.280654 -372.361732) (xy 344.280236 -372.351554) (xy 344.280236 -372.193566)
			(xy 344.279834 -372.184378) (xy 344.273314 -372.167194) (xy 344.267536 -372.160038) (xy 344.245762 -372.134374)
			(xy 344.207813 -372.078789) (xy 344.17678 -372.019067) (xy 344.153106 -371.956064) (xy 344.137132 -371.890684)
			(xy 344.129087 -371.823862) (xy 344.129086 -371.756559) (xy 344.137129 -371.689737) (xy 344.1531 -371.624356)
			(xy 344.176771 -371.561352) (xy 344.207803 -371.501629) (xy 344.245749 -371.446042) (xy 344.267536 -371.42039)
			(xy 344.273324 -371.413239) (xy 344.279843 -371.396053) (xy 344.280236 -371.386862) (xy 344.280236 -370.89334)
			(xy 344.279798 -370.884156) (xy 344.273303 -370.866972) (xy 344.267536 -370.859812) (xy 344.245736 -370.83417)
			(xy 344.207788 -370.778582) (xy 344.176756 -370.718857) (xy 344.153084 -370.655851) (xy 344.137112 -370.590468)
			(xy 344.129068 -370.523644) (xy 340.851006 -370.523644) (xy 340.842963 -370.590465) (xy 340.826991 -370.655847)
			(xy 340.803319 -370.718851) (xy 340.772287 -370.778574) (xy 340.734339 -370.83416) (xy 340.712552 -370.859812)
			(xy 340.706762 -370.866962) (xy 340.700245 -370.884149) (xy 340.699852 -370.89334) (xy 340.699852 -371.386862)
			(xy 340.700291 -371.396046) (xy 340.706786 -371.41323) (xy 340.712552 -371.42039) (xy 340.734354 -371.446031)
			(xy 340.772303 -371.501618) (xy 340.803336 -371.561344) (xy 340.826797 -371.623785) (xy 341.928891 -371.623785)
			(xy 341.928895 -371.556358) (xy 341.936974 -371.489417) (xy 341.953014 -371.423926) (xy 341.976782 -371.360828)
			(xy 342.007937 -371.301031) (xy 342.04603 -371.245395) (xy 342.067896 -371.21973) (xy 342.073704 -371.212593)
			(xy 342.080212 -371.195396) (xy 342.080596 -371.186202) (xy 342.080596 -371.028722) (xy 342.081143 -371.018602)
			(xy 342.088856 -370.99989) (xy 342.103123 -370.985534) (xy 342.121787 -370.977706) (xy 342.131904 -370.97716)
			(xy 342.848184 -370.97716) (xy 342.858332 -370.977634) (xy 342.877076 -370.985417) (xy 342.891399 -370.999797)
			(xy 342.899106 -371.018572) (xy 342.899492 -371.028722) (xy 342.899492 -371.186202) (xy 342.899903 -371.195389)
			(xy 342.906416 -371.212573) (xy 342.912192 -371.21973) (xy 342.934019 -371.245426) (xy 342.972109 -371.301056)
			(xy 343.003262 -371.360848) (xy 343.027029 -371.423941) (xy 343.043067 -371.489426) (xy 343.051146 -371.556361)
			(xy 343.05115 -371.623782) (xy 343.043077 -371.690718) (xy 343.027046 -371.756205) (xy 343.003285 -371.8193)
			(xy 342.972139 -371.879095) (xy 342.934054 -371.934729) (xy 342.912192 -371.960394) (xy 342.906415 -371.967553)
			(xy 342.899889 -371.984733) (xy 342.899492 -371.993922) (xy 342.899492 -372.486174) (xy 342.899917 -372.49536)
			(xy 342.90642 -372.512544) (xy 342.912192 -372.519702) (xy 342.93409 -372.54534) (xy 342.972178 -372.600978)
			(xy 343.003328 -372.660778) (xy 343.02709 -372.723878) (xy 343.043124 -372.789371) (xy 343.051197 -372.856312)
			(xy 343.051194 -372.923739) (xy 343.043114 -372.99068) (xy 343.027075 -373.056171) (xy 343.003307 -373.119269)
			(xy 342.972152 -373.179066) (xy 342.934058 -373.234701) (xy 342.912192 -373.260366) (xy 342.906384 -373.267503)
			(xy 342.899876 -373.2847) (xy 342.899492 -373.293894) (xy 342.899492 -373.451374) (xy 342.898953 -373.461495)
			(xy 342.89124 -373.48021) (xy 342.87697 -373.494566) (xy 342.858302 -373.502392) (xy 342.848184 -373.502936)
			(xy 342.131904 -373.502936) (xy 342.121755 -373.502476) (xy 342.103009 -373.494688) (xy 342.088687 -373.480304)
			(xy 342.080981 -373.461525) (xy 342.080596 -373.451374) (xy 342.080596 -373.293894) (xy 342.080189 -373.284706)
			(xy 342.073673 -373.267522) (xy 342.067896 -373.260366) (xy 342.046066 -373.234673) (xy 342.007976 -373.179042)
			(xy 341.976824 -373.11925) (xy 341.953058 -373.056157) (xy 341.937021 -372.990671) (xy 341.928942 -372.923736)
			(xy 341.928939 -372.856315) (xy 341.937011 -372.789379) (xy 341.953043 -372.723892) (xy 341.976803 -372.660797)
			(xy 342.00795 -372.601001) (xy 342.046034 -372.545367) (xy 342.067896 -372.519702) (xy 342.073674 -372.512543)
			(xy 342.0802 -372.495363) (xy 342.080596 -372.486174) (xy 342.080596 -371.993922) (xy 342.080176 -371.984736)
			(xy 342.073669 -371.967551) (xy 342.067896 -371.960394) (xy 342.045995 -371.934759) (xy 342.007908 -371.87912)
			(xy 341.976759 -371.81932) (xy 341.952997 -371.756219) (xy 341.936964 -371.690726) (xy 341.928891 -371.623785)
			(xy 340.826797 -371.623785) (xy 340.827009 -371.62435) (xy 340.842981 -371.689733) (xy 340.851024 -371.756557)
			(xy 340.851023 -371.823864) (xy 340.842977 -371.890687) (xy 340.827002 -371.956071) (xy 340.803328 -372.019076)
			(xy 340.772292 -372.0788) (xy 340.734341 -372.134386) (xy 340.712552 -372.160038) (xy 340.706751 -372.16718)
			(xy 340.70024 -372.184373) (xy 340.699852 -372.193566) (xy 340.699852 -372.351554) (xy 340.699398 -372.361724)
			(xy 340.691627 -372.380519) (xy 340.67725 -372.394906) (xy 340.65846 -372.402691) (xy 340.64829 -372.403116)
			(xy 339.93201 -372.403116) (xy 339.921833 -372.402727) (xy 339.90303 -372.394937) (xy 339.888643 -372.38054)
			(xy 339.880866 -372.361731) (xy 339.880448 -372.351554) (xy 339.880448 -372.193566) (xy 339.880043 -372.184378)
			(xy 339.873525 -372.167195) (xy 339.867748 -372.160038) (xy 339.845974 -372.134375) (xy 339.808024 -372.07879)
			(xy 339.77699 -372.019068) (xy 339.753316 -371.956065) (xy 339.737342 -371.890684) (xy 339.729296 -371.823863)
			(xy 339.729295 -371.756558) (xy 339.737338 -371.689737) (xy 339.75331 -371.624355) (xy 339.776981 -371.561351)
			(xy 339.808013 -371.501628) (xy 339.845961 -371.446042) (xy 339.867748 -371.42039) (xy 339.873537 -371.41324)
			(xy 339.880055 -371.396053) (xy 339.880448 -371.386862) (xy 339.880448 -370.89334) (xy 339.880008 -370.884156)
			(xy 339.873514 -370.866972) (xy 339.867748 -370.859812) (xy 339.845948 -370.83417) (xy 339.807999 -370.778582)
			(xy 339.776966 -370.718857) (xy 339.753293 -370.655851) (xy 339.737321 -370.590468) (xy 339.729277 -370.523644)
			(xy 336.451238 -370.523644) (xy 336.451238 -370.523703) (xy 336.443163 -370.590641) (xy 336.427128 -370.65613)
			(xy 336.403363 -370.719227) (xy 336.372211 -370.779022) (xy 336.334121 -370.834656) (xy 336.312256 -370.86032)
			(xy 336.306463 -370.867467) (xy 336.299947 -370.884656) (xy 336.299556 -370.893848) (xy 336.299556 -371.386354)
			(xy 336.299998 -371.395538) (xy 336.306491 -371.412722) (xy 336.312256 -371.419882) (xy 336.334135 -371.445535)
			(xy 336.372226 -371.50117) (xy 336.403379 -371.560968) (xy 336.427016 -371.623725) (xy 337.529123 -371.623725)
			(xy 337.529126 -371.556418) (xy 337.537174 -371.489593) (xy 337.55315 -371.424209) (xy 337.576825 -371.361204)
			(xy 337.60786 -371.301479) (xy 337.645811 -371.245891) (xy 337.6676 -371.220238) (xy 337.673405 -371.213099)
			(xy 337.679915 -371.195904) (xy 337.6803 -371.18671) (xy 337.6803 -371.028722) (xy 337.68085 -371.01857)
			(xy 337.68861 -370.999809) (xy 337.702958 -370.985444) (xy 337.721711 -370.977662) (xy 337.731862 -370.97716)
			(xy 338.448142 -370.97716) (xy 338.458305 -370.9776) (xy 338.477079 -370.985392) (xy 338.491444 -370.999774)
			(xy 338.499213 -371.018558) (xy 338.499704 -371.028722) (xy 338.499704 -371.18671) (xy 338.500109 -371.195898)
			(xy 338.506626 -371.213082) (xy 338.512404 -371.220238) (xy 338.534153 -371.245921) (xy 338.5721 -371.301504)
			(xy 338.603133 -371.361224) (xy 338.626806 -371.424224) (xy 338.64278 -371.489602) (xy 338.650827 -371.556421)
			(xy 338.65083 -371.623722) (xy 338.64279 -371.690541) (xy 338.626823 -371.755921) (xy 338.603156 -371.818924)
			(xy 338.57213 -371.878646) (xy 338.534188 -371.934233) (xy 338.512404 -371.959886) (xy 338.506589 -371.967018)
			(xy 338.500085 -371.984219) (xy 338.499704 -371.993414) (xy 338.499704 -372.486682) (xy 338.500122 -372.495868)
			(xy 338.50663 -372.513053) (xy 338.512404 -372.52021) (xy 338.534224 -372.545835) (xy 338.572169 -372.601427)
			(xy 338.603198 -372.661154) (xy 338.626867 -372.724162) (xy 338.642836 -372.789547) (xy 338.650877 -372.856372)
			(xy 338.650874 -372.923679) (xy 338.642827 -372.990503) (xy 338.626852 -373.055887) (xy 338.603177 -373.118892)
			(xy 338.572142 -373.178617) (xy 338.534192 -373.234205) (xy 338.512404 -373.259858) (xy 338.506601 -373.266999)
			(xy 338.50009 -373.284193) (xy 338.499704 -373.293386) (xy 338.499704 -373.451374) (xy 338.499147 -373.461525)
			(xy 338.491388 -373.480286) (xy 338.477043 -373.49465) (xy 338.458292 -373.502433) (xy 338.448142 -373.502936)
			(xy 337.731862 -373.502936) (xy 337.721699 -373.502497) (xy 337.702924 -373.494705) (xy 337.688559 -373.480323)
			(xy 337.68079 -373.461538) (xy 337.6803 -373.451374) (xy 337.6803 -373.293386) (xy 337.679896 -373.284198)
			(xy 337.673378 -373.267014) (xy 337.6676 -373.259858) (xy 337.645847 -373.234178) (xy 337.6079 -373.178595)
			(xy 337.576867 -373.118874) (xy 337.553194 -373.055874) (xy 337.53722 -372.990495) (xy 337.529174 -372.923676)
			(xy 337.52917 -372.856375) (xy 337.537211 -372.789555) (xy 337.553179 -372.724175) (xy 337.576846 -372.661172)
			(xy 337.607873 -372.601449) (xy 337.645816 -372.545863) (xy 337.6676 -372.52021) (xy 337.673417 -372.513079)
			(xy 337.67992 -372.495878) (xy 337.6803 -372.486682) (xy 337.6803 -371.993414) (xy 337.679883 -371.984228)
			(xy 337.673374 -371.967043) (xy 337.6676 -371.959886) (xy 337.645776 -371.934264) (xy 337.607831 -371.878672)
			(xy 337.576802 -371.818944) (xy 337.553133 -371.755936) (xy 337.537163 -371.69055) (xy 337.529123 -371.623725)
			(xy 336.427016 -371.623725) (xy 336.427144 -371.624066) (xy 336.44318 -371.689557) (xy 336.451256 -371.756498)
			(xy 336.451254 -371.823923) (xy 336.443176 -371.890863) (xy 336.427138 -371.956354) (xy 336.40337 -372.019451)
			(xy 336.372216 -372.079248) (xy 336.334122 -372.134881) (xy 336.312256 -372.160546) (xy 336.306452 -372.167686)
			(xy 336.299943 -372.184881) (xy 336.299556 -372.194074) (xy 336.299556 -372.351554) (xy 336.299036 -372.361678)
			(xy 336.291322 -372.380399) (xy 336.277046 -372.394757) (xy 336.258369 -372.402577) (xy 336.248248 -372.403116)
			(xy 335.531968 -372.403116) (xy 335.521814 -372.402705) (xy 335.503064 -372.394902) (xy 335.488742 -372.380502)
			(xy 335.481041 -372.36171) (xy 335.48066 -372.351554) (xy 335.48066 -372.194074) (xy 335.480249 -372.184887)
			(xy 335.473734 -372.167704) (xy 335.46796 -372.160546) (xy 335.446111 -372.134869) (xy 335.408025 -372.079235)
			(xy 335.376876 -372.01944) (xy 335.353112 -371.956345) (xy 335.337077 -371.890858) (xy 335.329001 -371.823921)
			(xy 335.329 -371.7565) (xy 335.337073 -371.689563) (xy 335.353106 -371.624075) (xy 335.376867 -371.560979)
			(xy 335.408014 -371.501183) (xy 335.446098 -371.445548) (xy 335.46796 -371.419882) (xy 335.473754 -371.412735)
			(xy 335.480269 -371.395546) (xy 335.48066 -371.386354) (xy 335.48066 -370.893848) (xy 335.480214 -370.884665)
			(xy 335.473724 -370.867481) (xy 335.46796 -370.86032) (xy 335.446086 -370.834664) (xy 335.408 -370.779027)
			(xy 335.376852 -370.719229) (xy 335.35309 -370.656131) (xy 335.337057 -370.590642) (xy 335.328983 -370.523703)
			(xy 332.050912 -370.523703) (xy 332.042876 -370.590465) (xy 332.026905 -370.655846) (xy 332.003233 -370.71885)
			(xy 331.972202 -370.778573) (xy 331.934255 -370.83416) (xy 331.912468 -370.859812) (xy 331.90668 -370.866963)
			(xy 331.900161 -370.884149) (xy 331.899768 -370.89334) (xy 331.899768 -371.386862) (xy 331.900204 -371.396046)
			(xy 331.906701 -371.41323) (xy 331.912468 -371.42039) (xy 331.934269 -371.446031) (xy 331.972217 -371.501619)
			(xy 332.00325 -371.561344) (xy 332.026709 -371.623785) (xy 333.128803 -371.623785) (xy 333.128807 -371.556358)
			(xy 333.136887 -371.489417) (xy 333.152927 -371.423926) (xy 333.176696 -371.360827) (xy 333.207851 -371.30103)
			(xy 333.245945 -371.245395) (xy 333.267812 -371.21973) (xy 333.273622 -371.212594) (xy 333.280128 -371.195397)
			(xy 333.280512 -371.186202) (xy 333.280512 -371.028722) (xy 333.281044 -371.0186) (xy 333.288759 -370.999885)
			(xy 333.303031 -370.985529) (xy 333.321701 -370.977704) (xy 333.33182 -370.97716) (xy 334.0481 -370.97716)
			(xy 334.058249 -370.977621) (xy 334.076994 -370.985409) (xy 334.091316 -370.999793) (xy 334.099023 -371.018571)
			(xy 334.099408 -371.028722) (xy 334.099408 -371.186202) (xy 334.099815 -371.195389) (xy 334.106331 -371.212574)
			(xy 334.112108 -371.21973) (xy 334.133934 -371.245426) (xy 334.172024 -371.301056) (xy 334.203176 -371.360848)
			(xy 334.226942 -371.423941) (xy 334.242979 -371.489426) (xy 334.251058 -371.556361) (xy 334.251062 -371.623782)
			(xy 334.24299 -371.690717) (xy 334.226958 -371.756204) (xy 334.203199 -371.819299) (xy 334.172053 -371.879095)
			(xy 334.133969 -371.934729) (xy 334.112108 -371.960394) (xy 334.106332 -371.967554) (xy 334.099805 -371.984733)
			(xy 334.099408 -371.993922) (xy 334.099408 -372.486174) (xy 334.099829 -372.49536) (xy 334.106335 -372.512545)
			(xy 334.112108 -372.519702) (xy 334.134005 -372.54534) (xy 334.172092 -372.600978) (xy 334.203241 -372.660779)
			(xy 334.227003 -372.723879) (xy 334.243036 -372.789371) (xy 334.251109 -372.856312) (xy 334.251106 -372.923739)
			(xy 334.243027 -372.990679) (xy 334.226988 -373.05617) (xy 334.20322 -373.119268) (xy 334.172066 -373.179065)
			(xy 334.133974 -373.234701) (xy 334.112108 -373.260366) (xy 334.106302 -373.267504) (xy 334.099793 -373.2847)
			(xy 334.099408 -373.293894) (xy 334.099408 -373.451374) (xy 334.098854 -373.461493) (xy 334.091143 -373.480205)
			(xy 334.076878 -373.49456) (xy 334.058216 -373.502389) (xy 334.0481 -373.502936) (xy 333.33182 -373.502936)
			(xy 333.321672 -373.502463) (xy 333.302927 -373.494681) (xy 333.288604 -373.4803) (xy 333.280897 -373.461524)
			(xy 333.280512 -373.451374) (xy 333.280512 -373.293894) (xy 333.280102 -373.284707) (xy 333.273588 -373.267523)
			(xy 333.267812 -373.260366) (xy 333.245981 -373.234673) (xy 333.20789 -373.179043) (xy 333.176738 -373.119251)
			(xy 333.152971 -373.056157) (xy 333.136933 -372.990672) (xy 333.128854 -372.923736) (xy 333.128851 -372.856315)
			(xy 333.136924 -372.789379) (xy 333.152956 -372.723891) (xy 333.176717 -372.660796) (xy 333.207864 -372.601001)
			(xy 333.24595 -372.545367) (xy 333.267812 -372.519702) (xy 333.273592 -372.512545) (xy 333.280116 -372.495363)
			(xy 333.280512 -372.486174) (xy 333.280512 -371.993922) (xy 333.280088 -371.984736) (xy 333.273584 -371.967552)
			(xy 333.267812 -371.960394) (xy 333.24591 -371.93476) (xy 333.207822 -371.879121) (xy 333.176672 -371.819321)
			(xy 333.15291 -371.75622) (xy 333.136876 -371.690727) (xy 333.128803 -371.623785) (xy 332.026709 -371.623785)
			(xy 332.026921 -371.62435) (xy 332.042893 -371.689734) (xy 332.050936 -371.756558) (xy 332.050935 -371.823864)
			(xy 332.042889 -371.890687) (xy 332.026915 -371.95607) (xy 332.003241 -372.019075) (xy 331.972207 -372.078799)
			(xy 331.934256 -372.134386) (xy 331.912468 -372.160038) (xy 331.906669 -372.167181) (xy 331.900156 -372.184373)
			(xy 331.899768 -372.193566) (xy 331.899768 -372.351554) (xy 331.899299 -372.361722) (xy 331.89153 -372.380514)
			(xy 331.877158 -372.394901) (xy 331.858373 -372.402688) (xy 331.848206 -372.403116) (xy 331.131926 -372.403116)
			(xy 331.12175 -372.402714) (xy 331.102948 -372.394929) (xy 331.08856 -372.380536) (xy 331.080783 -372.36173)
			(xy 331.080364 -372.351554) (xy 331.080364 -372.193566) (xy 331.079956 -372.184379) (xy 331.073439 -372.167195)
			(xy 331.067664 -372.160038) (xy 331.045889 -372.134375) (xy 331.007939 -372.078791) (xy 330.976903 -372.019069)
			(xy 330.953229 -371.956066) (xy 330.937254 -371.890684) (xy 330.929208 -371.823863) (xy 330.929207 -371.756558)
			(xy 330.93725 -371.689736) (xy 330.953222 -371.624355) (xy 330.976895 -371.561351) (xy 331.007928 -371.501628)
			(xy 331.045876 -371.446042) (xy 331.067664 -371.42039) (xy 331.073455 -371.413241) (xy 331.079971 -371.396053)
			(xy 331.080364 -371.386862) (xy 331.080364 -370.89334) (xy 331.07992 -370.884157) (xy 331.073428 -370.866973)
			(xy 331.067664 -370.859812) (xy 331.045864 -370.83417) (xy 331.007914 -370.778582) (xy 330.97688 -370.718858)
			(xy 330.953206 -370.655852) (xy 330.937234 -370.590468) (xy 330.92919 -370.523644) (xy 301.250887 -370.523644)
			(xy 301.250887 -370.523702) (xy 301.242812 -370.590639) (xy 301.226779 -370.656127) (xy 301.203017 -370.719224)
			(xy 301.171869 -370.77902) (xy 301.133783 -370.834654) (xy 301.11192 -370.86032) (xy 301.106135 -370.867473)
			(xy 301.099613 -370.884658) (xy 301.09922 -370.893848) (xy 301.09922 -371.386354) (xy 301.099648 -371.395539)
			(xy 301.106149 -371.412724) (xy 301.11192 -371.419882) (xy 301.133797 -371.445536) (xy 301.171884 -371.501173)
			(xy 301.203033 -371.560971) (xy 301.226688 -371.623785) (xy 302.328773 -371.623785) (xy 302.328777 -371.556358)
			(xy 302.336856 -371.489418) (xy 302.352895 -371.423927) (xy 302.376662 -371.360829) (xy 302.407815 -371.301031)
			(xy 302.445907 -371.245396) (xy 302.467772 -371.21973) (xy 302.47359 -371.2126) (xy 302.48009 -371.195398)
			(xy 302.480472 -371.186202) (xy 302.480472 -371.028722) (xy 302.480945 -371.018593) (xy 302.488672 -370.999866)
			(xy 302.502963 -370.985508) (xy 302.521653 -370.977693) (xy 302.53178 -370.97716) (xy 303.24806 -370.97716)
			(xy 303.258207 -370.977654) (xy 303.27695 -370.985429) (xy 303.291274 -370.999803) (xy 303.298982 -371.018574)
			(xy 303.299368 -371.028722) (xy 303.299368 -371.186202) (xy 303.299784 -371.195388) (xy 303.306294 -371.212572)
			(xy 303.312068 -371.21973) (xy 303.333896 -371.245425) (xy 303.371988 -371.301055) (xy 303.403142 -371.360847)
			(xy 303.42691 -371.42394) (xy 303.442949 -371.489425) (xy 303.451028 -371.556361) (xy 303.451031 -371.623782)
			(xy 303.442959 -371.690718) (xy 303.426926 -371.756206) (xy 303.403165 -371.819301) (xy 303.372017 -371.879096)
			(xy 303.333931 -371.934729) (xy 303.312068 -371.960394) (xy 303.306287 -371.96755) (xy 303.299764 -371.984732)
			(xy 303.299368 -371.993922) (xy 303.299368 -372.486174) (xy 303.299798 -372.495359) (xy 303.306299 -372.512543)
			(xy 303.312068 -372.519702) (xy 303.333966 -372.545339) (xy 303.372056 -372.600977) (xy 303.403207 -372.660777)
			(xy 303.426971 -372.723877) (xy 303.443005 -372.78937) (xy 303.451079 -372.856312) (xy 303.451076 -372.923739)
			(xy 303.442996 -372.99068) (xy 303.426956 -373.056172) (xy 303.403186 -373.11927) (xy 303.37203 -373.179067)
			(xy 303.333935 -373.234701) (xy 303.312068 -373.260366) (xy 303.306257 -373.267501) (xy 303.299752 -373.284699)
			(xy 303.299368 -373.293894) (xy 303.299368 -373.451374) (xy 303.298853 -373.461498) (xy 303.291135 -373.480217)
			(xy 303.276857 -373.494574) (xy 303.258181 -373.502396) (xy 303.24806 -373.502936) (xy 302.53178 -373.502936)
			(xy 302.521629 -373.502496) (xy 302.502883 -373.4947) (xy 302.488562 -373.48031) (xy 302.480856 -373.461527)
			(xy 302.480472 -373.451374) (xy 302.480472 -373.293894) (xy 302.480071 -373.284706) (xy 302.473552 -373.267521)
			(xy 302.467772 -373.260366) (xy 302.445942 -373.234673) (xy 302.407855 -373.179042) (xy 302.376704 -373.119249)
			(xy 302.352939 -373.056156) (xy 302.336902 -372.99067) (xy 302.328824 -372.923736) (xy 302.328821 -372.856315)
			(xy 302.336893 -372.78938) (xy 302.352924 -372.723893) (xy 302.376683 -372.660798) (xy 302.407828 -372.601002)
			(xy 302.445911 -372.545368) (xy 302.467772 -372.519702) (xy 302.473559 -372.51255) (xy 302.480077 -372.495364)
			(xy 302.480472 -372.486174) (xy 302.480472 -371.993922) (xy 302.480058 -371.984735) (xy 302.473548 -371.96755)
			(xy 302.467772 -371.960394) (xy 302.445872 -371.934759) (xy 302.407786 -371.87912) (xy 302.376638 -371.819319)
			(xy 302.352878 -371.756218) (xy 302.336846 -371.690726) (xy 302.328773 -371.623785) (xy 301.226688 -371.623785)
			(xy 301.226795 -371.624069) (xy 301.242829 -371.689559) (xy 301.250904 -371.756498) (xy 301.250903 -371.823923)
			(xy 301.242826 -371.890862) (xy 301.226789 -371.956351) (xy 301.203024 -372.019449) (xy 301.171873 -372.079245)
			(xy 301.133784 -372.13488) (xy 301.11192 -372.160546) (xy 301.106124 -372.167692) (xy 301.099608 -372.184882)
			(xy 301.09922 -372.194074) (xy 301.09922 -372.351554) (xy 301.098734 -372.361683) (xy 301.091014 -372.38041)
			(xy 301.076727 -372.39477) (xy 301.058038 -372.402583) (xy 301.047912 -372.403116) (xy 300.331632 -372.403116)
			(xy 300.321482 -372.402653) (xy 300.302733 -372.394871) (xy 300.288409 -372.380487) (xy 300.280705 -372.361706)
			(xy 300.280324 -372.351554) (xy 300.280324 -372.194074) (xy 300.279921 -372.184886) (xy 300.273402 -372.167702)
			(xy 300.267624 -372.160546) (xy 300.245773 -372.13487) (xy 300.207682 -372.079237) (xy 300.17653 -372.019443)
			(xy 300.152764 -371.956347) (xy 300.136726 -371.890859) (xy 300.128649 -371.823922) (xy 300.128648 -371.756499)
			(xy 300.136723 -371.689561) (xy 300.152757 -371.624073) (xy 300.176521 -371.560976) (xy 300.207671 -371.501181)
			(xy 300.24576 -371.445547) (xy 300.267624 -371.419882) (xy 300.273413 -371.412732) (xy 300.279932 -371.395545)
			(xy 300.280324 -371.386354) (xy 300.280324 -370.893848) (xy 300.279885 -370.884664) (xy 300.273391 -370.86748)
			(xy 300.267624 -370.86032) (xy 300.245747 -370.834665) (xy 300.207657 -370.779029) (xy 300.176506 -370.719232)
			(xy 300.152741 -370.656134) (xy 300.136706 -370.590643) (xy 300.128631 -370.523704) (xy 296.851096 -370.523704)
			(xy 296.843021 -370.590639) (xy 296.826988 -370.656127) (xy 296.803227 -370.719223) (xy 296.772079 -370.779019)
			(xy 296.733994 -370.834654) (xy 296.712132 -370.86032) (xy 296.706336 -370.867465) (xy 296.699823 -370.884656)
			(xy 296.699432 -370.893848) (xy 296.699432 -371.386354) (xy 296.699879 -371.395537) (xy 296.706369 -371.412721)
			(xy 296.712132 -371.419882) (xy 296.734009 -371.445536) (xy 296.772095 -371.501173) (xy 296.803243 -371.560971)
			(xy 296.826876 -371.623726) (xy 297.92898 -371.623726) (xy 297.928984 -371.556417) (xy 297.937032 -371.489591)
			(xy 297.95301 -371.424206) (xy 297.976689 -371.3612) (xy 298.007729 -371.301476) (xy 298.045685 -371.245889)
			(xy 298.067476 -371.220238) (xy 298.073279 -371.213097) (xy 298.07979 -371.195903) (xy 298.080176 -371.18671)
			(xy 298.080176 -371.028722) (xy 298.080583 -371.018547) (xy 298.088368 -370.999746) (xy 298.102759 -370.985359)
			(xy 298.121563 -370.97758) (xy 298.131738 -370.97716) (xy 298.848018 -370.97716) (xy 298.858193 -370.97755)
			(xy 298.876993 -370.985345) (xy 298.891378 -370.999741) (xy 298.899158 -371.018546) (xy 298.89958 -371.028722)
			(xy 298.89958 -371.18671) (xy 298.89999 -371.195897) (xy 298.906504 -371.213081) (xy 298.91228 -371.220238)
			(xy 298.93403 -371.245921) (xy 298.971978 -371.301504) (xy 299.003012 -371.361223) (xy 299.026686 -371.424224)
			(xy 299.042661 -371.489602) (xy 299.050708 -371.556421) (xy 299.050711 -371.623722) (xy 299.042671 -371.690542)
			(xy 299.026703 -371.755922) (xy 299.003035 -371.818925) (xy 298.972008 -371.878647) (xy 298.934065 -371.934233)
			(xy 298.91228 -371.959886) (xy 298.906462 -371.967016) (xy 298.899961 -371.984218) (xy 298.89958 -371.993414)
			(xy 298.89958 -372.486682) (xy 298.900003 -372.495868) (xy 298.906508 -372.513052) (xy 298.91228 -372.52021)
			(xy 298.934101 -372.545835) (xy 298.972047 -372.601426) (xy 299.003078 -372.661153) (xy 299.026748 -372.724161)
			(xy 299.042718 -372.789547) (xy 299.050759 -372.856372) (xy 299.050756 -372.923679) (xy 299.042709 -372.990504)
			(xy 299.026733 -373.055888) (xy 299.003057 -373.118894) (xy 298.972021 -373.178618) (xy 298.934069 -373.234206)
			(xy 298.91228 -373.259858) (xy 298.906474 -373.266996) (xy 298.899966 -373.284192) (xy 298.89958 -373.293386)
			(xy 298.89958 -373.451374) (xy 298.899115 -373.461542) (xy 298.891342 -373.480332) (xy 298.876969 -373.494717)
			(xy 298.858185 -373.502506) (xy 298.848018 -373.502936) (xy 298.131738 -373.502936) (xy 298.121566 -373.502504)
			(xy 298.102767 -373.494727) (xy 298.08838 -373.480343) (xy 298.080598 -373.461546) (xy 298.080176 -373.451374)
			(xy 298.080176 -373.293386) (xy 298.079778 -373.284197) (xy 298.073256 -373.267013) (xy 298.067476 -373.259858)
			(xy 298.045721 -373.234179) (xy 298.007768 -373.178597) (xy 297.976732 -373.118878) (xy 297.953055 -373.055877)
			(xy 297.937079 -372.990497) (xy 297.929031 -372.923677) (xy 297.929028 -372.856374) (xy 297.93707 -372.789553)
			(xy 297.95304 -372.724172) (xy 297.976711 -372.661169) (xy 298.007742 -372.601447) (xy 298.045689 -372.545862)
			(xy 298.067476 -372.52021) (xy 298.073291 -372.513077) (xy 298.079795 -372.495877) (xy 298.080176 -372.486682)
			(xy 298.080176 -371.993414) (xy 298.079765 -371.984227) (xy 298.073252 -371.967042) (xy 298.067476 -371.959886)
			(xy 298.04565 -371.934265) (xy 298.007699 -371.878675) (xy 297.976666 -371.818948) (xy 297.952993 -371.755939)
			(xy 297.937022 -371.690552) (xy 297.92898 -371.623726) (xy 296.826876 -371.623726) (xy 296.827005 -371.624069)
			(xy 296.843039 -371.689559) (xy 296.851113 -371.756498) (xy 296.851112 -371.823923) (xy 296.843035 -371.890861)
			(xy 296.826999 -371.956351) (xy 296.803235 -372.019448) (xy 296.772084 -372.079245) (xy 296.733996 -372.13488)
			(xy 296.712132 -372.160546) (xy 296.706325 -372.167684) (xy 296.699819 -372.18488) (xy 296.699432 -372.194074)
			(xy 296.699432 -372.351554) (xy 296.698935 -372.361681) (xy 296.691217 -372.380407) (xy 296.676933 -372.394765)
			(xy 296.658249 -372.402581) (xy 296.648124 -372.403116) (xy 295.931844 -372.403116) (xy 295.921695 -372.402643)
			(xy 295.902946 -372.394865) (xy 295.888622 -372.380484) (xy 295.880918 -372.361705) (xy 295.880536 -372.351554)
			(xy 295.880536 -372.194074) (xy 295.88013 -372.184887) (xy 295.873613 -372.167703) (xy 295.867836 -372.160546)
			(xy 295.845985 -372.13487) (xy 295.807893 -372.079238) (xy 295.77674 -372.019444) (xy 295.752973 -371.956348)
			(xy 295.736936 -371.89086) (xy 295.728858 -371.823922) (xy 295.728857 -371.756499) (xy 295.736932 -371.689561)
			(xy 295.752967 -371.624072) (xy 295.776731 -371.560976) (xy 295.807882 -371.50118) (xy 295.845972 -371.445547)
			(xy 295.867836 -371.419882) (xy 295.873627 -371.412733) (xy 295.880144 -371.395545) (xy 295.880536 -371.386354)
			(xy 295.880536 -370.893848) (xy 295.880095 -370.884664) (xy 295.873602 -370.86748) (xy 295.867836 -370.86032)
			(xy 295.845959 -370.834665) (xy 295.807868 -370.77903) (xy 295.776716 -370.719233) (xy 295.752951 -370.656134)
			(xy 295.736915 -370.590644) (xy 295.72884 -370.523704) (xy 292.450793 -370.523704) (xy 292.442757 -370.590465)
			(xy 292.426785 -370.655847) (xy 292.403113 -370.718851) (xy 292.37208 -370.778574) (xy 292.334131 -370.83416)
			(xy 292.312344 -370.859812) (xy 292.306553 -370.866961) (xy 292.300036 -370.884149) (xy 292.299644 -370.89334)
			(xy 292.299644 -371.386862) (xy 292.300085 -371.396046) (xy 292.306578 -371.41323) (xy 292.312344 -371.42039)
			(xy 292.334146 -371.44603) (xy 292.372096 -371.501618) (xy 292.403129 -371.561343) (xy 292.42659 -371.623785)
			(xy 293.528685 -371.623785) (xy 293.528689 -371.556358) (xy 293.536768 -371.489418) (xy 293.552807 -371.423927)
			(xy 293.576575 -371.360828) (xy 293.60773 -371.301031) (xy 293.645822 -371.245395) (xy 293.667688 -371.21973)
			(xy 293.673495 -371.212592) (xy 293.680004 -371.195396) (xy 293.680388 -371.186202) (xy 293.680388 -371.028722)
			(xy 293.680943 -371.018603) (xy 293.688654 -370.999892) (xy 293.702919 -370.985537) (xy 293.72158 -370.977708)
			(xy 293.731696 -370.97716) (xy 294.447976 -370.97716) (xy 294.458078 -370.977704) (xy 294.476748 -370.985426)
			(xy 294.491043 -370.999705) (xy 294.498785 -371.018366) (xy 294.499284 -371.028468) (xy 294.499284 -371.186202)
			(xy 294.499697 -371.195389) (xy 294.506209 -371.212573) (xy 294.511984 -371.21973) (xy 294.533811 -371.245426)
			(xy 294.571902 -371.301056) (xy 294.603055 -371.360847) (xy 294.626822 -371.42394) (xy 294.642861 -371.489426)
			(xy 294.65094 -371.556361) (xy 294.650944 -371.623782) (xy 294.642871 -371.690718) (xy 294.626839 -371.756205)
			(xy 294.603079 -371.8193) (xy 294.571932 -371.879095) (xy 294.533846 -371.934729) (xy 294.511984 -371.960394)
			(xy 294.506206 -371.967552) (xy 294.499681 -371.984733) (xy 294.499284 -371.993922) (xy 294.499284 -372.486174)
			(xy 294.49971 -372.495359) (xy 294.506213 -372.512544) (xy 294.511984 -372.519702) (xy 294.533882 -372.545339)
			(xy 294.571971 -372.600978) (xy 294.603121 -372.660777) (xy 294.626884 -372.723878) (xy 294.642917 -372.789371)
			(xy 294.650991 -372.856312) (xy 294.650988 -372.923739) (xy 294.642908 -372.99068) (xy 294.626869 -373.056171)
			(xy 294.6031 -373.119269) (xy 294.571944 -373.179066) (xy 294.533851 -373.234701) (xy 294.511984 -373.260366)
			(xy 294.506175 -373.267502) (xy 294.499668 -373.2847) (xy 294.499284 -373.293894) (xy 294.499284 -373.451374)
			(xy 294.498753 -373.461496) (xy 294.491038 -373.480212) (xy 294.476766 -373.494569) (xy 294.458095 -373.502393)
			(xy 294.447976 -373.502936) (xy 293.731696 -373.502936) (xy 293.721591 -373.502419) (xy 293.70292 -373.494687)
			(xy 293.688627 -373.4804) (xy 293.680886 -373.461732) (xy 293.680388 -373.451628) (xy 293.680388 -373.293894)
			(xy 293.679983 -373.284706) (xy 293.673466 -373.267522) (xy 293.667688 -373.260366) (xy 293.645858 -373.234673)
			(xy 293.607769 -373.179042) (xy 293.576617 -373.11925) (xy 293.552852 -373.056156) (xy 293.536814 -372.990671)
			(xy 293.528736 -372.923736) (xy 293.528733 -372.856315) (xy 293.536805 -372.789379) (xy 293.552837 -372.723892)
			(xy 293.576597 -372.660797) (xy 293.607743 -372.601002) (xy 293.645826 -372.545367) (xy 293.667688 -372.519702)
			(xy 293.673465 -372.512543) (xy 293.679992 -372.495363) (xy 293.680388 -372.486174) (xy 293.680388 -371.993922)
			(xy 293.67997 -371.984736) (xy 293.673462 -371.967551) (xy 293.667688 -371.960394) (xy 293.645787 -371.934759)
			(xy 293.6077 -371.87912) (xy 293.576552 -371.81932) (xy 293.55279 -371.756219) (xy 293.536758 -371.690726)
			(xy 293.528685 -371.623785) (xy 292.42659 -371.623785) (xy 292.426802 -371.624349) (xy 292.442775 -371.689733)
			(xy 292.450818 -371.756557) (xy 292.450817 -371.823864) (xy 292.442771 -371.890688) (xy 292.426796 -371.956071)
			(xy 292.403121 -372.019076) (xy 292.372085 -372.0788) (xy 292.334133 -372.134386) (xy 292.312344 -372.160038)
			(xy 292.306542 -372.167179) (xy 292.300032 -372.184373) (xy 292.299644 -372.193566) (xy 292.299644 -372.351554)
			(xy 292.299198 -372.361725) (xy 292.291425 -372.380522) (xy 292.277046 -372.394909) (xy 292.258253 -372.402693)
			(xy 292.248082 -372.403116) (xy 291.531802 -372.403116) (xy 291.521625 -372.402733) (xy 291.502821 -372.394941)
			(xy 291.488435 -372.380542) (xy 291.480658 -372.361732) (xy 291.48024 -372.351554) (xy 291.48024 -372.193566)
			(xy 291.479837 -372.184378) (xy 291.473317 -372.167194) (xy 291.46754 -372.160038) (xy 291.445766 -372.134374)
			(xy 291.407817 -372.07879) (xy 291.376783 -372.019068) (xy 291.353109 -371.956065) (xy 291.337135 -371.890684)
			(xy 291.32909 -371.823862) (xy 291.329089 -371.756559) (xy 291.337132 -371.689737) (xy 291.353103 -371.624356)
			(xy 291.376774 -371.561352) (xy 291.407806 -371.501628) (xy 291.445753 -371.446042) (xy 291.46754 -371.42039)
			(xy 291.473328 -371.413239) (xy 291.479847 -371.396053) (xy 291.48024 -371.386862) (xy 291.48024 -370.89334)
			(xy 291.479801 -370.884156) (xy 291.473306 -370.866972) (xy 291.46754 -370.859812) (xy 291.44574 -370.83417)
			(xy 291.407792 -370.778582) (xy 291.376759 -370.718857) (xy 291.353087 -370.655851) (xy 291.337115 -370.590468)
			(xy 291.329071 -370.523644) (xy 288.051032 -370.523644) (xy 288.051032 -370.523703) (xy 288.042957 -370.590641)
			(xy 288.026921 -370.65613) (xy 288.003156 -370.719227) (xy 287.972004 -370.779022) (xy 287.933913 -370.834656)
			(xy 287.912048 -370.86032) (xy 287.906254 -370.867467) (xy 287.899739 -370.884656) (xy 287.899348 -370.893848)
			(xy 287.899348 -371.386354) (xy 287.899792 -371.395537) (xy 287.906284 -371.412721) (xy 287.912048 -371.419882)
			(xy 287.933928 -371.445535) (xy 287.972019 -371.50117) (xy 288.003172 -371.560967) (xy 288.02681 -371.623726)
			(xy 289.128893 -371.623726) (xy 289.128896 -371.556417) (xy 289.136945 -371.489591) (xy 289.152924 -371.424206)
			(xy 289.176603 -371.3612) (xy 289.207644 -371.301475) (xy 289.2456 -371.245889) (xy 289.267392 -371.220238)
			(xy 289.273196 -371.213098) (xy 289.279707 -371.195904) (xy 289.280092 -371.18671) (xy 289.280092 -371.028722)
			(xy 289.28065 -371.018571) (xy 289.288409 -370.999811) (xy 289.302754 -370.985447) (xy 289.321504 -370.977663)
			(xy 289.331654 -370.97716) (xy 290.047934 -370.97716) (xy 290.058097 -370.977606) (xy 290.076871 -370.985396)
			(xy 290.091236 -370.999776) (xy 290.099005 -371.018559) (xy 290.099496 -371.028722) (xy 290.099496 -371.18671)
			(xy 290.099902 -371.195898) (xy 290.106419 -371.213082) (xy 290.112196 -371.220238) (xy 290.133945 -371.245921)
			(xy 290.171893 -371.301504) (xy 290.202926 -371.361224) (xy 290.226599 -371.424224) (xy 290.242574 -371.489602)
			(xy 290.250621 -371.556421) (xy 290.250624 -371.623722) (xy 290.242584 -371.690542) (xy 290.226616 -371.755921)
			(xy 290.202949 -371.818924) (xy 290.171922 -371.878647) (xy 290.13398 -371.934233) (xy 290.112196 -371.959886)
			(xy 290.10638 -371.967017) (xy 290.099877 -371.984218) (xy 290.099496 -371.993414) (xy 290.099496 -372.486682)
			(xy 290.099916 -372.495868) (xy 290.106423 -372.513053) (xy 290.112196 -372.52021) (xy 290.134016 -372.545835)
			(xy 290.171962 -372.601426) (xy 290.202991 -372.661154) (xy 290.226661 -372.724162) (xy 290.24263 -372.789547)
			(xy 290.250671 -372.856372) (xy 290.250668 -372.923679) (xy 290.242621 -372.990503) (xy 290.226646 -373.055887)
			(xy 290.202971 -373.118893) (xy 290.171935 -373.178618) (xy 290.133985 -373.234205) (xy 290.112196 -373.259858)
			(xy 290.106392 -373.266998) (xy 290.099882 -373.284192) (xy 290.099496 -373.293386) (xy 290.099496 -373.451374)
			(xy 290.098946 -373.461526) (xy 290.091187 -373.480288) (xy 290.076838 -373.494653) (xy 290.058085 -373.502435)
			(xy 290.047934 -373.502936) (xy 289.331654 -373.502936) (xy 289.32149 -373.502504) (xy 289.302715 -373.494709)
			(xy 289.28835 -373.480325) (xy 289.280582 -373.461539) (xy 289.280092 -373.451374) (xy 289.280092 -373.293386)
			(xy 289.27969 -373.284198) (xy 289.273171 -373.267014) (xy 289.267392 -373.259858) (xy 289.245636 -373.234179)
			(xy 289.207683 -373.178598) (xy 289.176645 -373.118878) (xy 289.152968 -373.055877) (xy 289.136991 -372.990498)
			(xy 289.128943 -372.923677) (xy 289.12894 -372.856374) (xy 289.136982 -372.789553) (xy 289.152953 -372.724172)
			(xy 289.176624 -372.661168) (xy 289.207656 -372.601446) (xy 289.245605 -372.545861) (xy 289.267392 -372.52021)
			(xy 289.273208 -372.513079) (xy 289.279711 -372.495878) (xy 289.280092 -372.486682) (xy 289.280092 -371.993414)
			(xy 289.279677 -371.984227) (xy 289.273167 -371.967043) (xy 289.267392 -371.959886) (xy 289.245565 -371.934265)
			(xy 289.207614 -371.878676) (xy 289.17658 -371.818948) (xy 289.152907 -371.755939) (xy 289.136935 -371.690553)
			(xy 289.128893 -371.623726) (xy 288.02681 -371.623726) (xy 288.026938 -371.624066) (xy 288.042974 -371.689557)
			(xy 288.05105 -371.756498) (xy 288.051048 -371.823923) (xy 288.04297 -371.890864) (xy 288.026932 -371.956354)
			(xy 288.003164 -372.019452) (xy 287.972008 -372.079248) (xy 287.933915 -372.134882) (xy 287.912048 -372.160546)
			(xy 287.906243 -372.167685) (xy 287.899735 -372.18488) (xy 287.899348 -372.194074) (xy 287.899348 -372.351554)
			(xy 287.898835 -372.361679) (xy 287.89112 -372.380402) (xy 287.876842 -372.39476) (xy 287.858162 -372.402579)
			(xy 287.84804 -372.403116) (xy 287.13176 -372.403116) (xy 287.121651 -372.402648) (xy 287.102975 -372.3949)
			(xy 287.088682 -372.380598) (xy 287.080946 -372.361918) (xy 287.080452 -372.351808) (xy 287.080452 -372.194074)
			(xy 287.080043 -372.184887) (xy 287.073527 -372.167703) (xy 287.067752 -372.160546) (xy 287.0459 -372.13487)
			(xy 287.007807 -372.079238) (xy 286.976653 -372.019444) (xy 286.952886 -371.956349) (xy 286.936848 -371.89086)
			(xy 286.92877 -371.823922) (xy 286.928769 -371.756499) (xy 286.936844 -371.68956) (xy 286.95288 -371.624072)
			(xy 286.976645 -371.560975) (xy 287.007797 -371.50118) (xy 287.045887 -371.445546) (xy 287.067752 -371.419882)
			(xy 287.073545 -371.412735) (xy 287.08006 -371.395546) (xy 287.080452 -371.386354) (xy 287.080452 -370.893848)
			(xy 287.080007 -370.884665) (xy 287.073516 -370.867481) (xy 287.067752 -370.86032) (xy 287.045874 -370.834665)
			(xy 287.007783 -370.779031) (xy 286.97663 -370.719233) (xy 286.952864 -370.656135) (xy 286.936828 -370.590644)
			(xy 286.928752 -370.523704) (xy 266.12088 -370.523704) (xy 266.12088 -374.423882) (xy 286.928731 -374.423882)
			(xy 286.928735 -374.356454) (xy 286.936815 -374.289512) (xy 286.952857 -374.22402) (xy 286.976628 -374.160921)
			(xy 287.007787 -374.101124) (xy 287.045884 -374.04549) (xy 287.067752 -374.019826) (xy 287.073569 -374.012695)
			(xy 287.08007 -373.995494) (xy 287.080452 -373.986298) (xy 287.080452 -373.828818) (xy 287.080942 -373.818691)
			(xy 287.088666 -373.799968) (xy 287.102951 -373.785611) (xy 287.121636 -373.777793) (xy 287.13176 -373.777256)
			(xy 287.84804 -373.777256) (xy 287.858146 -373.777751) (xy 287.876817 -373.785494) (xy 287.891108 -373.799787)
			(xy 287.898849 -373.818458) (xy 287.899348 -373.828564) (xy 287.899348 -373.986298) (xy 287.899771 -373.995484)
			(xy 287.906277 -374.012667) (xy 287.912048 -374.019826) (xy 287.933873 -374.045524) (xy 287.971966 -374.101153)
			(xy 288.003121 -374.160944) (xy 288.02689 -374.224037) (xy 288.04293 -374.289522) (xy 288.05101 -374.356458)
			(xy 288.051014 -374.423823) (xy 291.32905 -374.423823) (xy 291.329054 -374.356514) (xy 291.337102 -374.289689)
			(xy 291.35308 -374.224304) (xy 291.376757 -374.161298) (xy 291.407796 -374.101573) (xy 291.44575 -374.045986)
			(xy 291.46754 -374.020334) (xy 291.473352 -374.0132) (xy 291.479857 -373.996001) (xy 291.48024 -373.986806)
			(xy 291.48024 -373.828818) (xy 291.480678 -373.818647) (xy 291.488458 -373.799853) (xy 291.502839 -373.785467)
			(xy 291.521631 -373.777682) (xy 291.531802 -373.777256) (xy 292.248082 -373.777256) (xy 292.258255 -373.777679)
			(xy 292.277053 -373.785461) (xy 292.291439 -373.799847) (xy 292.299221 -373.818645) (xy 292.299644 -373.828818)
			(xy 292.299644 -373.986806) (xy 292.300064 -373.995992) (xy 292.306572 -374.013176) (xy 292.312344 -374.020334)
			(xy 292.334091 -374.04602) (xy 292.372042 -374.101601) (xy 292.403078 -374.16132) (xy 292.426754 -374.22432)
			(xy 292.44273 -374.289698) (xy 292.450778 -374.356517) (xy 292.450782 -374.423819) (xy 292.450774 -374.423882)
			(xy 295.728819 -374.423882) (xy 295.728822 -374.356455) (xy 295.736903 -374.289513) (xy 295.752944 -374.224021)
			(xy 295.776715 -374.160922) (xy 295.807872 -374.101125) (xy 295.845968 -374.045491) (xy 295.867836 -374.019826)
			(xy 295.873651 -374.012694) (xy 295.880154 -373.995493) (xy 295.880536 -373.986298) (xy 295.880536 -373.828818)
			(xy 295.881041 -373.818693) (xy 295.888762 -373.799973) (xy 295.903043 -373.785616) (xy 295.921722 -373.777796)
			(xy 295.931844 -373.777256) (xy 296.648124 -373.777256) (xy 296.658274 -373.777701) (xy 296.677019 -373.785496)
			(xy 296.69134 -373.799885) (xy 296.699046 -373.818666) (xy 296.699432 -373.828818) (xy 296.699432 -373.986298)
			(xy 296.699858 -373.995483) (xy 296.706362 -374.012667) (xy 296.712132 -374.019826) (xy 296.733954 -374.045526)
			(xy 296.772041 -374.101156) (xy 296.803192 -374.160948) (xy 296.826957 -374.22404) (xy 296.842995 -374.289525)
			(xy 296.851073 -374.356459) (xy 296.851077 -374.423878) (xy 296.851077 -374.423882) (xy 300.12861 -374.423882)
			(xy 300.128613 -374.356455) (xy 300.136694 -374.289513) (xy 300.152734 -374.224021) (xy 300.176504 -374.160923)
			(xy 300.207661 -374.101126) (xy 300.245757 -374.045491) (xy 300.267624 -374.019826) (xy 300.273437 -374.012693)
			(xy 300.279941 -373.995493) (xy 300.280324 -373.986298) (xy 300.280324 -373.828818) (xy 300.280841 -373.818694)
			(xy 300.28856 -373.799977) (xy 300.302837 -373.78562) (xy 300.321511 -373.777798) (xy 300.331632 -373.777256)
			(xy 301.047912 -373.777256) (xy 301.058061 -373.777711) (xy 301.076806 -373.785502) (xy 301.091127 -373.799888)
			(xy 301.098834 -373.818667) (xy 301.09922 -373.828818) (xy 301.09922 -373.986298) (xy 301.099627 -373.995486)
			(xy 301.106142 -374.01267) (xy 301.11192 -374.019826) (xy 301.133742 -374.045526) (xy 301.171831 -374.101156)
			(xy 301.202982 -374.160947) (xy 301.226748 -374.22404) (xy 301.242785 -374.289524) (xy 301.250864 -374.356458)
			(xy 301.250868 -374.423823) (xy 330.929168 -374.423823) (xy 330.929172 -374.356514) (xy 330.937221 -374.289688)
			(xy 330.953199 -374.224303) (xy 330.976878 -374.161297) (xy 331.007917 -374.101572) (xy 331.045873 -374.045986)
			(xy 331.067664 -374.020334) (xy 331.073479 -374.013202) (xy 331.079981 -373.996001) (xy 331.080364 -373.986806)
			(xy 331.080364 -373.828818) (xy 331.080779 -373.818644) (xy 331.088563 -373.799845) (xy 331.102952 -373.785458)
			(xy 331.121752 -373.777677) (xy 331.131926 -373.777256) (xy 331.848206 -373.777256) (xy 331.85838 -373.777659)
			(xy 331.877178 -373.78545) (xy 331.891564 -373.799842) (xy 331.899345 -373.818644) (xy 331.899768 -373.828818)
			(xy 331.899768 -373.986806) (xy 331.900182 -373.995993) (xy 331.906694 -374.013177) (xy 331.912468 -374.020334)
			(xy 331.934214 -374.04602) (xy 331.972164 -374.101602) (xy 332.003198 -374.161321) (xy 332.026873 -374.224321)
			(xy 332.042849 -374.289699) (xy 332.050896 -374.356518) (xy 332.0509 -374.423819) (xy 332.050892 -374.423882)
			(xy 335.328961 -374.423882) (xy 335.328965 -374.356455) (xy 335.337045 -374.289515) (xy 335.353083 -374.224024)
			(xy 335.37685 -374.160926) (xy 335.408004 -374.101128) (xy 335.446095 -374.045492) (xy 335.46796 -374.019826)
			(xy 335.473778 -374.012696) (xy 335.480278 -373.995494) (xy 335.48066 -373.986298) (xy 335.48066 -373.828818)
			(xy 335.481142 -373.81869) (xy 335.488867 -373.799965) (xy 335.503156 -373.785608) (xy 335.521842 -373.777791)
			(xy 335.531968 -373.777256) (xy 336.248248 -373.777256) (xy 336.2584 -373.777682) (xy 336.277145 -373.785485)
			(xy 336.291465 -373.799879) (xy 336.299171 -373.818664) (xy 336.299556 -373.828818) (xy 336.299556 -373.986298)
			(xy 336.299977 -373.995484) (xy 336.306484 -374.012668) (xy 336.312256 -374.019826) (xy 336.33408 -374.045525)
			(xy 336.372173 -374.101153) (xy 336.403328 -374.160944) (xy 336.427097 -374.224037) (xy 336.443136 -374.289523)
			(xy 336.451216 -374.356458) (xy 336.45122 -374.423823) (xy 339.729256 -374.423823) (xy 339.72926 -374.356514)
			(xy 339.737309 -374.289689) (xy 339.753286 -374.224304) (xy 339.776964 -374.161298) (xy 339.808003 -374.101573)
			(xy 339.845957 -374.045986) (xy 339.867748 -374.020334) (xy 339.873561 -374.013201) (xy 339.880065 -373.996001)
			(xy 339.880448 -373.986806) (xy 339.880448 -373.828818) (xy 339.880879 -373.818646) (xy 339.88866 -373.79985)
			(xy 339.903043 -373.785464) (xy 339.921838 -373.77768) (xy 339.93201 -373.777256) (xy 340.64829 -373.777256)
			(xy 340.658463 -373.777672) (xy 340.677261 -373.785457) (xy 340.691647 -373.799846) (xy 340.699429 -373.818645)
			(xy 340.699852 -373.828818) (xy 340.699852 -373.986806) (xy 340.70027 -373.995992) (xy 340.706779 -374.013176)
			(xy 340.712552 -374.020334) (xy 340.734299 -374.04602) (xy 340.772249 -374.101601) (xy 340.803285 -374.16132)
			(xy 340.82696 -374.22432) (xy 340.842936 -374.289699) (xy 340.850984 -374.356517) (xy 340.850988 -374.423819)
			(xy 340.850988 -374.423823) (xy 344.129047 -374.423823) (xy 344.129051 -374.356514) (xy 344.137099 -374.289689)
			(xy 344.153077 -374.224304) (xy 344.176754 -374.161298) (xy 344.207792 -374.101573) (xy 344.245746 -374.045986)
			(xy 344.267536 -374.020334) (xy 344.273348 -374.0132) (xy 344.279852 -373.996001) (xy 344.280236 -373.986806)
			(xy 344.280236 -373.828818) (xy 344.280678 -373.818648) (xy 344.288457 -373.799854) (xy 344.302837 -373.785468)
			(xy 344.321628 -373.777682) (xy 344.331798 -373.777256) (xy 345.048078 -373.777256) (xy 345.05825 -373.777683)
			(xy 345.077048 -373.785464) (xy 345.091434 -373.799849) (xy 345.099217 -373.818646) (xy 345.09964 -373.828818)
			(xy 345.09964 -373.986806) (xy 345.100061 -373.995992) (xy 345.106569 -374.013175) (xy 345.11234 -374.020334)
			(xy 345.134087 -374.04602) (xy 345.172038 -374.101601) (xy 345.203075 -374.16132) (xy 345.226751 -374.22432)
			(xy 345.242727 -374.289698) (xy 345.250775 -374.356517) (xy 345.250779 -374.423819) (xy 345.250779 -374.423823)
			(xy 374.929078 -374.423823) (xy 374.929081 -374.356514) (xy 374.93713 -374.289688) (xy 374.953109 -374.224303)
			(xy 374.976788 -374.161296) (xy 375.007828 -374.101572) (xy 375.045784 -374.045985) (xy 375.067576 -374.020334)
			(xy 375.07338 -374.013194) (xy 375.079891 -373.996) (xy 375.080276 -373.986806) (xy 375.080276 -373.828818)
			(xy 375.080679 -373.818643) (xy 375.088465 -373.799841) (xy 375.102858 -373.785454) (xy 375.121663 -373.777675)
			(xy 375.131838 -373.777256) (xy 375.848118 -373.777256) (xy 375.858279 -373.777719) (xy 375.877052 -373.785503)
			(xy 375.891418 -373.799878) (xy 375.899188 -373.818656) (xy 375.89968 -373.828818) (xy 375.89968 -373.986806)
			(xy 375.900092 -373.995993) (xy 375.906605 -374.013177) (xy 375.91238 -374.020334) (xy 375.934126 -374.046021)
			(xy 375.972074 -374.101603) (xy 376.003108 -374.161322) (xy 376.026783 -374.224321) (xy 376.042758 -374.289699)
			(xy 376.050805 -374.356518) (xy 376.050809 -374.423819) (xy 376.050801 -374.423882) (xy 379.32887 -374.423882)
			(xy 379.328874 -374.356455) (xy 379.336954 -374.289515) (xy 379.352993 -374.224024) (xy 379.376761 -374.160925)
			(xy 379.407915 -374.101127) (xy 379.446007 -374.045492) (xy 379.467872 -374.019826) (xy 379.473691 -374.012697)
			(xy 379.48019 -373.995494) (xy 379.480572 -373.986298) (xy 379.480572 -373.828818) (xy 379.481042 -373.818688)
			(xy 379.48877 -373.799962) (xy 379.503062 -373.785604) (xy 379.521753 -373.777789) (xy 379.53188 -373.777256)
			(xy 380.24816 -373.777256) (xy 380.258306 -373.777754) (xy 380.277049 -373.785528) (xy 380.291372 -373.799901)
			(xy 380.299081 -373.818671) (xy 380.299468 -373.828818) (xy 380.299468 -373.986298) (xy 380.299886 -373.995484)
			(xy 380.306395 -374.012668) (xy 380.312168 -374.019826) (xy 380.333992 -374.045525) (xy 380.372084 -374.101154)
			(xy 380.403238 -374.160945) (xy 380.427006 -374.224038) (xy 380.443046 -374.289523) (xy 380.451125 -374.356458)
			(xy 380.451129 -374.423823) (xy 383.729165 -374.423823) (xy 383.729169 -374.356514) (xy 383.737218 -374.289688)
			(xy 383.753196 -374.224303) (xy 383.776874 -374.161297) (xy 383.807914 -374.101572) (xy 383.845869 -374.045986)
			(xy 383.86766 -374.020334) (xy 383.873474 -374.013202) (xy 383.879977 -373.996001) (xy 383.88036 -373.986806)
			(xy 383.88036 -373.828818) (xy 383.880779 -373.818645) (xy 383.888562 -373.799846) (xy 383.90295 -373.78546)
			(xy 383.921749 -373.777678) (xy 383.931922 -373.777256) (xy 384.648202 -373.777256) (xy 384.658376 -373.777663)
			(xy 384.677174 -373.785452) (xy 384.69156 -373.799843) (xy 384.699341 -373.818644) (xy 384.699764 -373.828818)
			(xy 384.699764 -373.986806) (xy 384.700179 -373.995992) (xy 384.70669 -374.013176) (xy 384.712464 -374.020334)
			(xy 384.73421 -374.04602) (xy 384.77216 -374.101602) (xy 384.803195 -374.161321) (xy 384.82687 -374.224321)
			(xy 384.842846 -374.289699) (xy 384.850893 -374.356518) (xy 384.850897 -374.423819) (xy 384.850897 -374.423823)
			(xy 388.128956 -374.423823) (xy 388.12896 -374.356514) (xy 388.137009 -374.289689) (xy 388.152986 -374.224304)
			(xy 388.176664 -374.161298) (xy 388.207703 -374.101573) (xy 388.245657 -374.045986) (xy 388.267448 -374.020334)
			(xy 388.273261 -374.013201) (xy 388.279765 -373.996001) (xy 388.280148 -373.986806) (xy 388.280148 -373.828818)
			(xy 388.280579 -373.818646) (xy 388.28836 -373.79985) (xy 388.302743 -373.785464) (xy 388.321538 -373.77768)
			(xy 388.33171 -373.777256) (xy 389.04799 -373.777256) (xy 389.058163 -373.777672) (xy 389.076961 -373.785457)
			(xy 389.091347 -373.799846) (xy 389.099129 -373.818645) (xy 389.099552 -373.828818) (xy 389.099552 -373.986806)
			(xy 389.09997 -373.995992) (xy 389.106479 -374.013176) (xy 389.112252 -374.020334) (xy 389.133999 -374.04602)
			(xy 389.171949 -374.101601) (xy 389.202985 -374.16132) (xy 389.22666 -374.22432) (xy 389.242636 -374.289699)
			(xy 389.250684 -374.356517) (xy 389.250688 -374.423819) (xy 389.250688 -374.423823) (xy 418.928987 -374.423823)
			(xy 418.928991 -374.356514) (xy 418.93704 -374.289688) (xy 418.953019 -374.224302) (xy 418.976698 -374.161296)
			(xy 419.007739 -374.101572) (xy 419.045696 -374.045986) (xy 419.067488 -374.020334) (xy 419.073294 -374.013195)
			(xy 419.079803 -373.996) (xy 419.080188 -373.986806) (xy 419.080188 -373.828818) (xy 419.08058 -373.818641)
			(xy 419.088368 -373.799837) (xy 419.102764 -373.78545) (xy 419.121573 -373.777673) (xy 419.13175 -373.777256)
			(xy 419.84803 -373.777256) (xy 419.858192 -373.777709) (xy 419.876965 -373.785497) (xy 419.89133 -373.799875)
			(xy 419.8991 -373.818656) (xy 419.899592 -373.828818) (xy 419.899592 -373.986806) (xy 419.900001 -373.995993)
			(xy 419.906516 -374.013177) (xy 419.912292 -374.020334) (xy 419.934038 -374.04602) (xy 419.971986 -374.101603)
			(xy 420.003019 -374.161322) (xy 420.026693 -374.224322) (xy 420.042668 -374.2897) (xy 420.050715 -374.356518)
			(xy 420.050719 -374.423819) (xy 420.050711 -374.423882) (xy 423.328779 -374.423882) (xy 423.328783 -374.356455)
			(xy 423.336863 -374.289514) (xy 423.352903 -374.224023) (xy 423.376671 -374.160925) (xy 423.407825 -374.101127)
			(xy 423.445918 -374.045492) (xy 423.467784 -374.019826) (xy 423.473593 -374.012689) (xy 423.480101 -373.995492)
			(xy 423.480484 -373.986298) (xy 423.480484 -373.828818) (xy 423.480942 -373.818687) (xy 423.488672 -373.799958)
			(xy 423.502968 -373.785599) (xy 423.521663 -373.777787) (xy 423.531792 -373.777256) (xy 424.248072 -373.777256)
			(xy 424.258174 -373.777807) (xy 424.276843 -373.785527) (xy 424.291137 -373.799803) (xy 424.298881 -373.818463)
			(xy 424.29938 -373.828564) (xy 424.29938 -373.986298) (xy 424.299795 -373.995485) (xy 424.306306 -374.012669)
			(xy 424.31208 -374.019826) (xy 424.333903 -374.045525) (xy 424.371995 -374.101154) (xy 424.403148 -374.160946)
			(xy 424.426916 -374.224038) (xy 424.442955 -374.289523) (xy 424.451034 -374.356458) (xy 424.451038 -374.423823)
			(xy 427.729074 -374.423823) (xy 427.729078 -374.356514) (xy 427.737127 -374.289688) (xy 427.753106 -374.224303)
			(xy 427.776784 -374.161296) (xy 427.807824 -374.101572) (xy 427.84578 -374.045986) (xy 427.867572 -374.020334)
			(xy 427.873388 -374.013203) (xy 427.879889 -373.996001) (xy 427.880272 -373.986806) (xy 427.880272 -373.828818)
			(xy 427.880679 -373.818643) (xy 427.888465 -373.799842) (xy 427.902856 -373.785456) (xy 427.921659 -373.777676)
			(xy 427.931834 -373.777256) (xy 428.648114 -373.777256) (xy 428.658289 -373.777653) (xy 428.677087 -373.785446)
			(xy 428.691472 -373.79984) (xy 428.699253 -373.818643) (xy 428.699676 -373.828818) (xy 428.699676 -373.986806)
			(xy 428.700088 -373.995993) (xy 428.706601 -374.013177) (xy 428.712376 -374.020334) (xy 428.734122 -374.04602)
			(xy 428.772071 -374.101602) (xy 428.803105 -374.161321) (xy 428.82678 -374.224321) (xy 428.842755 -374.289699)
			(xy 428.850802 -374.356518) (xy 428.850806 -374.423819) (xy 428.850806 -374.423823) (xy 432.128865 -374.423823)
			(xy 432.128869 -374.356514) (xy 432.136918 -374.289688) (xy 432.152896 -374.224303) (xy 432.176574 -374.161297)
			(xy 432.207614 -374.101572) (xy 432.245569 -374.045986) (xy 432.26736 -374.020334) (xy 432.273174 -374.013202)
			(xy 432.279677 -373.996001) (xy 432.28006 -373.986806) (xy 432.28006 -373.828818) (xy 432.280479 -373.818645)
			(xy 432.288262 -373.799846) (xy 432.30265 -373.78546) (xy 432.321449 -373.777678) (xy 432.331622 -373.777256)
			(xy 433.047902 -373.777256) (xy 433.058076 -373.777663) (xy 433.076874 -373.785452) (xy 433.09126 -373.799843)
			(xy 433.099041 -373.818644) (xy 433.099464 -373.828818) (xy 433.099464 -373.986806) (xy 433.099879 -373.995992)
			(xy 433.10639 -374.013176) (xy 433.112164 -374.020334) (xy 433.13391 -374.04602) (xy 433.17186 -374.101602)
			(xy 433.202895 -374.161321) (xy 433.22657 -374.224321) (xy 433.242546 -374.289699) (xy 433.250593 -374.356518)
			(xy 433.250597 -374.423819) (xy 433.242557 -374.490639) (xy 433.226589 -374.556019) (xy 433.202921 -374.619021)
			(xy 433.171892 -374.678744) (xy 433.133949 -374.73433) (xy 433.112164 -374.759982) (xy 433.106346 -374.767112)
			(xy 433.099845 -374.784314) (xy 433.099464 -374.79351) (xy 433.099464 -375.286778) (xy 433.099893 -375.295963)
			(xy 433.106394 -375.313147) (xy 433.112164 -375.320306) (xy 433.133981 -375.345934) (xy 433.171929 -375.401524)
			(xy 433.202961 -375.461251) (xy 433.226632 -375.524259) (xy 433.242603 -375.589644) (xy 433.250644 -375.656469)
			(xy 433.250642 -375.723776) (xy 433.242594 -375.790601) (xy 433.226618 -375.855985) (xy 433.202942 -375.91899)
			(xy 433.171906 -375.978715) (xy 433.133954 -376.034302) (xy 433.112164 -376.059954) (xy 433.106357 -376.067092)
			(xy 433.09985 -376.084288) (xy 433.099464 -376.093482) (xy 433.099464 -376.25147) (xy 433.099011 -376.261639)
			(xy 433.091237 -376.280433) (xy 433.07686 -376.294819) (xy 433.058071 -376.302605) (xy 433.047902 -376.303032)
			(xy 432.331622 -376.303032) (xy 432.321448 -376.302617) (xy 432.302648 -376.294834) (xy 432.288262 -376.280445)
			(xy 432.280481 -376.261644) (xy 432.28006 -376.25147) (xy 432.28006 -376.093482) (xy 432.279645 -376.084296)
			(xy 432.273133 -376.067112) (xy 432.26736 -376.059954) (xy 432.245601 -376.034278) (xy 432.20765 -375.978695)
			(xy 432.176614 -375.918975) (xy 432.152939 -375.855974) (xy 432.136963 -375.790594) (xy 432.128917 -375.723774)
			(xy 432.128914 -375.656471) (xy 432.136955 -375.58965) (xy 432.152926 -375.524269) (xy 432.176596 -375.461266)
			(xy 432.207627 -375.401543) (xy 432.245574 -375.345958) (xy 432.26736 -375.320306) (xy 432.273144 -375.313152)
			(xy 432.279664 -375.295968) (xy 432.28006 -375.286778) (xy 432.28006 -374.79351) (xy 432.279632 -374.784325)
			(xy 432.273129 -374.767141) (xy 432.26736 -374.759982) (xy 432.24553 -374.734364) (xy 432.207581 -374.678773)
			(xy 432.176549 -374.619045) (xy 432.152877 -374.556036) (xy 432.136907 -374.49065) (xy 432.128865 -374.423823)
			(xy 428.850806 -374.423823) (xy 428.842766 -374.490639) (xy 428.826798 -374.556018) (xy 428.803131 -374.619021)
			(xy 428.772103 -374.678743) (xy 428.73416 -374.734329) (xy 428.712376 -374.759982) (xy 428.706559 -374.767113)
			(xy 428.700057 -374.784314) (xy 428.699676 -374.79351) (xy 428.699676 -375.286778) (xy 428.700102 -375.295963)
			(xy 428.706605 -375.313148) (xy 428.712376 -375.320306) (xy 428.734193 -375.345934) (xy 428.77214 -375.401524)
			(xy 428.803171 -375.461251) (xy 428.826841 -375.524259) (xy 428.842812 -375.589644) (xy 428.850853 -375.656469)
			(xy 428.850851 -375.723776) (xy 428.842804 -375.790601) (xy 428.826828 -375.855984) (xy 428.803152 -375.91899)
			(xy 428.772117 -375.978714) (xy 428.734165 -376.034302) (xy 428.712376 -376.059954) (xy 428.706571 -376.067093)
			(xy 428.700062 -376.084288) (xy 428.699676 -376.093482) (xy 428.699676 -376.25147) (xy 428.699212 -376.261638)
			(xy 428.691439 -376.280429) (xy 428.677066 -376.294815) (xy 428.658282 -376.302603) (xy 428.648114 -376.303032)
			(xy 427.931834 -376.303032) (xy 427.921661 -376.302607) (xy 427.902861 -376.294828) (xy 427.888474 -376.280442)
			(xy 427.880693 -376.261643) (xy 427.880272 -376.25147) (xy 427.880272 -376.093482) (xy 427.879877 -376.084293)
			(xy 427.873353 -376.067109) (xy 427.867572 -376.059954) (xy 427.845813 -376.034278) (xy 427.807861 -375.978696)
			(xy 427.776825 -375.918976) (xy 427.753149 -375.855974) (xy 427.737173 -375.790595) (xy 427.729126 -375.723774)
			(xy 427.729123 -375.656471) (xy 427.737165 -375.58965) (xy 427.753135 -375.524269) (xy 427.776806 -375.461266)
			(xy 427.807838 -375.401543) (xy 427.845785 -375.345958) (xy 427.867572 -375.320306) (xy 427.873357 -375.313153)
			(xy 427.879877 -375.295968) (xy 427.880272 -375.286778) (xy 427.880272 -374.79351) (xy 427.879863 -374.784323)
			(xy 427.873349 -374.767138) (xy 427.867572 -374.759982) (xy 427.845742 -374.734364) (xy 427.807792 -374.678774)
			(xy 427.776759 -374.619046) (xy 427.753087 -374.556037) (xy 427.737116 -374.49065) (xy 427.729074 -374.423823)
			(xy 424.451038 -374.423823) (xy 424.451038 -374.423879) (xy 424.442966 -374.490815) (xy 424.426934 -374.556302)
			(xy 424.403174 -374.619397) (xy 424.372027 -374.679192) (xy 424.333942 -374.734825) (xy 424.31208 -374.76049)
			(xy 424.30626 -374.767619) (xy 424.29976 -374.784822) (xy 424.29938 -374.794018) (xy 424.29938 -375.28627)
			(xy 424.299809 -375.295455) (xy 424.30631 -375.312639) (xy 424.31208 -375.319798) (xy 424.333974 -375.345439)
			(xy 424.372063 -375.401076) (xy 424.403214 -375.460876) (xy 424.426977 -375.523976) (xy 424.443011 -375.589468)
			(xy 424.451085 -375.656409) (xy 424.451082 -375.723836) (xy 424.443003 -375.790776) (xy 424.426964 -375.856267)
			(xy 424.403195 -375.919366) (xy 424.37204 -375.979163) (xy 424.333946 -376.034797) (xy 424.31208 -376.060462)
			(xy 424.306272 -376.067599) (xy 424.299765 -376.084796) (xy 424.29938 -376.09399) (xy 424.29938 -376.25147)
			(xy 424.29885 -376.261592) (xy 424.291135 -376.280309) (xy 424.276863 -376.294666) (xy 424.258191 -376.30249)
			(xy 424.248072 -376.303032) (xy 423.531792 -376.303032) (xy 423.521687 -376.302522) (xy 423.503015 -376.294788)
			(xy 423.488721 -376.280499) (xy 423.480981 -376.261829) (xy 423.480484 -376.251724) (xy 423.480484 -376.09399)
			(xy 423.480082 -376.084802) (xy 423.473563 -376.067617) (xy 423.467784 -376.060462) (xy 423.44595 -376.034772)
			(xy 423.407862 -375.979141) (xy 423.37671 -375.919348) (xy 423.352945 -375.856254) (xy 423.336908 -375.790768)
			(xy 423.32883 -375.723833) (xy 423.328827 -375.656412) (xy 423.3369 -375.589476) (xy 423.352932 -375.523989)
			(xy 423.376692 -375.460893) (xy 423.407838 -375.401098) (xy 423.445922 -375.345463) (xy 423.467784 -375.319798)
			(xy 423.473562 -375.31264) (xy 423.480088 -375.295459) (xy 423.480484 -375.28627) (xy 423.480484 -374.794018)
			(xy 423.480069 -374.784831) (xy 423.473559 -374.767647) (xy 423.467784 -374.76049) (xy 423.445879 -374.734859)
			(xy 423.407793 -374.679219) (xy 423.376645 -374.619418) (xy 423.352884 -374.556317) (xy 423.336852 -374.490824)
			(xy 423.328779 -374.423882) (xy 420.050711 -374.423882) (xy 420.042679 -374.490638) (xy 420.026712 -374.556018)
			(xy 420.003045 -374.61902) (xy 419.972018 -374.678743) (xy 419.934076 -374.73433) (xy 419.912292 -374.759982)
			(xy 419.906477 -374.767114) (xy 419.899974 -374.784315) (xy 419.899592 -374.79351) (xy 419.899592 -375.286778)
			(xy 419.900015 -375.295964) (xy 419.90652 -375.313148) (xy 419.912292 -375.320306) (xy 419.934108 -375.345934)
			(xy 419.972054 -375.401525) (xy 420.003084 -375.461252) (xy 420.026754 -375.52426) (xy 420.042724 -375.589644)
			(xy 420.050765 -375.656469) (xy 420.050763 -375.723776) (xy 420.042716 -375.7906) (xy 420.026741 -375.855984)
			(xy 420.003066 -375.918989) (xy 419.972031 -375.978714) (xy 419.934081 -376.034301) (xy 419.912292 -376.059954)
			(xy 419.906489 -376.067095) (xy 419.899978 -376.084289) (xy 419.899592 -376.093482) (xy 419.899592 -376.25147)
			(xy 419.899043 -376.261622) (xy 419.891284 -376.280385) (xy 419.876935 -376.29475) (xy 419.858182 -376.302531)
			(xy 419.84803 -376.303032) (xy 419.13175 -376.303032) (xy 419.121578 -376.302595) (xy 419.102779 -376.29482)
			(xy 419.088391 -376.280438) (xy 419.080609 -376.261642) (xy 419.080188 -376.25147) (xy 419.080188 -376.093482)
			(xy 419.079789 -376.084294) (xy 419.073268 -376.067109) (xy 419.067488 -376.059954) (xy 419.045728 -376.034278)
			(xy 419.007775 -375.978696) (xy 418.976738 -375.918976) (xy 418.953061 -375.855975) (xy 418.937085 -375.790595)
			(xy 418.929038 -375.723774) (xy 418.929035 -375.656471) (xy 418.937077 -375.589649) (xy 418.953048 -375.524268)
			(xy 418.97672 -375.461265) (xy 419.007752 -375.401542) (xy 419.045701 -375.345957) (xy 419.067488 -375.320306)
			(xy 419.073263 -375.313145) (xy 419.079791 -375.295967) (xy 419.080188 -375.286778) (xy 419.080188 -374.79351)
			(xy 419.079776 -374.784323) (xy 419.073264 -374.767138) (xy 419.067488 -374.759982) (xy 419.045658 -374.734364)
			(xy 419.007707 -374.678774) (xy 418.976673 -374.619046) (xy 418.953 -374.556037) (xy 418.937029 -374.49065)
			(xy 418.928987 -374.423823) (xy 389.250688 -374.423823) (xy 389.242648 -374.490639) (xy 389.226679 -374.556019)
			(xy 389.203011 -374.619022) (xy 389.171982 -374.678744) (xy 389.134037 -374.73433) (xy 389.112252 -374.759982)
			(xy 389.106432 -374.76711) (xy 389.099933 -374.784314) (xy 389.099552 -374.79351) (xy 389.099552 -375.286778)
			(xy 389.099983 -375.295963) (xy 389.106483 -375.313147) (xy 389.112252 -375.320306) (xy 389.13407 -375.345934)
			(xy 389.172018 -375.401523) (xy 389.203051 -375.46125) (xy 389.226722 -375.524258) (xy 389.242693 -375.589643)
			(xy 389.250735 -375.656469) (xy 389.250732 -375.723776) (xy 389.242685 -375.790601) (xy 389.226709 -375.855985)
			(xy 389.203032 -375.918991) (xy 389.171995 -375.978715) (xy 389.134042 -376.034302) (xy 389.112252 -376.059954)
			(xy 389.106444 -376.067091) (xy 389.099937 -376.084288) (xy 389.099552 -376.093482) (xy 389.099552 -376.25147)
			(xy 389.099111 -376.261641) (xy 389.091334 -376.280437) (xy 389.076954 -376.294823) (xy 389.058161 -376.302607)
			(xy 389.04799 -376.303032) (xy 388.33171 -376.303032) (xy 388.321535 -376.302627) (xy 388.302735 -376.29484)
			(xy 388.288349 -376.280448) (xy 388.280569 -376.261645) (xy 388.280148 -376.25147) (xy 388.280148 -376.093482)
			(xy 388.279736 -376.084295) (xy 388.273222 -376.067111) (xy 388.267448 -376.059954) (xy 388.24569 -376.034278)
			(xy 388.207739 -375.978695) (xy 388.176704 -375.918975) (xy 388.153029 -375.855973) (xy 388.137054 -375.790594)
			(xy 388.129007 -375.723774) (xy 388.129005 -375.656471) (xy 388.137046 -375.58965) (xy 388.153016 -375.52427)
			(xy 388.176686 -375.461267) (xy 388.207716 -375.401544) (xy 388.245662 -375.345958) (xy 388.267448 -375.320306)
			(xy 388.273231 -375.313151) (xy 388.279752 -375.295968) (xy 388.280148 -375.286778) (xy 388.280148 -374.79351)
			(xy 388.279722 -374.784325) (xy 388.273218 -374.767141) (xy 388.267448 -374.759982) (xy 388.245619 -374.734364)
			(xy 388.20767 -374.678773) (xy 388.176638 -374.619045) (xy 388.152968 -374.556036) (xy 388.136997 -374.490649)
			(xy 388.128956 -374.423823) (xy 384.850897 -374.423823) (xy 384.842857 -374.490639) (xy 384.826889 -374.556019)
			(xy 384.803221 -374.619021) (xy 384.772192 -374.678744) (xy 384.734249 -374.73433) (xy 384.712464 -374.759982)
			(xy 384.706646 -374.767112) (xy 384.700145 -374.784314) (xy 384.699764 -374.79351) (xy 384.699764 -375.286778)
			(xy 384.700193 -375.295963) (xy 384.706694 -375.313147) (xy 384.712464 -375.320306) (xy 384.734281 -375.345934)
			(xy 384.772229 -375.401524) (xy 384.803261 -375.461251) (xy 384.826932 -375.524259) (xy 384.842903 -375.589644)
			(xy 384.850944 -375.656469) (xy 384.850942 -375.723776) (xy 384.842894 -375.790601) (xy 384.826918 -375.855985)
			(xy 384.803242 -375.91899) (xy 384.772206 -375.978715) (xy 384.734254 -376.034302) (xy 384.712464 -376.059954)
			(xy 384.706657 -376.067092) (xy 384.70015 -376.084288) (xy 384.699764 -376.093482) (xy 384.699764 -376.25147)
			(xy 384.699311 -376.261639) (xy 384.691537 -376.280433) (xy 384.67716 -376.294819) (xy 384.658371 -376.302605)
			(xy 384.648202 -376.303032) (xy 383.931922 -376.303032) (xy 383.921748 -376.302617) (xy 383.902948 -376.294834)
			(xy 383.888562 -376.280445) (xy 383.880781 -376.261644) (xy 383.88036 -376.25147) (xy 383.88036 -376.093482)
			(xy 383.879945 -376.084296) (xy 383.873433 -376.067112) (xy 383.86766 -376.059954) (xy 383.845901 -376.034278)
			(xy 383.80795 -375.978695) (xy 383.776914 -375.918975) (xy 383.753239 -375.855974) (xy 383.737263 -375.790594)
			(xy 383.729217 -375.723774) (xy 383.729214 -375.656471) (xy 383.737255 -375.58965) (xy 383.753226 -375.524269)
			(xy 383.776896 -375.461266) (xy 383.807927 -375.401543) (xy 383.845874 -375.345958) (xy 383.86766 -375.320306)
			(xy 383.873444 -375.313152) (xy 383.879964 -375.295968) (xy 383.88036 -375.286778) (xy 383.88036 -374.79351)
			(xy 383.879932 -374.784325) (xy 383.873429 -374.767141) (xy 383.86766 -374.759982) (xy 383.84583 -374.734364)
			(xy 383.807881 -374.678773) (xy 383.776849 -374.619045) (xy 383.753177 -374.556036) (xy 383.737207 -374.49065)
			(xy 383.729165 -374.423823) (xy 380.451129 -374.423823) (xy 380.451129 -374.423879) (xy 380.443057 -374.490815)
			(xy 380.427025 -374.556302) (xy 380.403264 -374.619397) (xy 380.372116 -374.679192) (xy 380.334031 -374.734825)
			(xy 380.312168 -374.76049) (xy 380.306347 -374.767617) (xy 380.299847 -374.784822) (xy 380.299468 -374.794018)
			(xy 380.299468 -375.28627) (xy 380.2999 -375.295455) (xy 380.306399 -375.312639) (xy 380.312168 -375.319798)
			(xy 380.334063 -375.345438) (xy 380.372152 -375.401076) (xy 380.403304 -375.460875) (xy 380.427068 -375.523975)
			(xy 380.443102 -375.589468) (xy 380.451176 -375.656409) (xy 380.451173 -375.723836) (xy 380.443094 -375.790777)
			(xy 380.427054 -375.856268) (xy 380.403285 -375.919366) (xy 380.372129 -375.979163) (xy 380.334035 -376.034797)
			(xy 380.312168 -376.060462) (xy 380.306358 -376.067598) (xy 380.299852 -376.084796) (xy 380.299468 -376.09399)
			(xy 380.299468 -376.25147) (xy 380.298949 -376.261594) (xy 380.291233 -376.280313) (xy 380.276956 -376.29467)
			(xy 380.258281 -376.302492) (xy 380.24816 -376.303032) (xy 379.53188 -376.303032) (xy 379.521729 -376.302596)
			(xy 379.502982 -376.294799) (xy 379.48866 -376.280408) (xy 379.480955 -376.261623) (xy 379.480572 -376.25147)
			(xy 379.480572 -376.09399) (xy 379.480173 -376.084802) (xy 379.473652 -376.067617) (xy 379.467872 -376.060462)
			(xy 379.446038 -376.034772) (xy 379.407951 -375.97914) (xy 379.3768 -375.919347) (xy 379.353036 -375.856254)
			(xy 379.336999 -375.790768) (xy 379.328921 -375.723833) (xy 379.328918 -375.656412) (xy 379.336991 -375.589476)
			(xy 379.353022 -375.523989) (xy 379.376782 -375.460894) (xy 379.407928 -375.401098) (xy 379.446011 -375.345464)
			(xy 379.467872 -375.319798) (xy 379.473661 -375.312648) (xy 379.480178 -375.295461) (xy 379.480572 -375.28627)
			(xy 379.480572 -374.794018) (xy 379.48016 -374.784831) (xy 379.473648 -374.767646) (xy 379.467872 -374.76049)
			(xy 379.445968 -374.734858) (xy 379.407882 -374.679218) (xy 379.376735 -374.619417) (xy 379.352974 -374.556316)
			(xy 379.336943 -374.490823) (xy 379.32887 -374.423882) (xy 376.050801 -374.423882) (xy 376.042769 -374.490638)
			(xy 376.026801 -374.556018) (xy 376.003134 -374.619021) (xy 375.972107 -374.678743) (xy 375.934164 -374.734329)
			(xy 375.91238 -374.759982) (xy 375.906564 -374.767113) (xy 375.900062 -374.784315) (xy 375.89968 -374.79351)
			(xy 375.89968 -375.286778) (xy 375.900105 -375.295963) (xy 375.906609 -375.313148) (xy 375.91238 -375.320306)
			(xy 375.934197 -375.345934) (xy 375.972143 -375.401524) (xy 376.003174 -375.461252) (xy 376.026845 -375.524259)
			(xy 376.042815 -375.589644) (xy 376.050856 -375.656469) (xy 376.050854 -375.723776) (xy 376.042807 -375.7906)
			(xy 376.026831 -375.855984) (xy 376.003156 -375.91899) (xy 375.97212 -375.978714) (xy 375.934169 -376.034302)
			(xy 375.91238 -376.059954) (xy 375.906576 -376.067094) (xy 375.900066 -376.084288) (xy 375.89968 -376.093482)
			(xy 375.89968 -376.25147) (xy 375.899212 -376.261637) (xy 375.89144 -376.280428) (xy 375.877068 -376.294813)
			(xy 375.858285 -376.302602) (xy 375.848118 -376.303032) (xy 375.131838 -376.303032) (xy 375.121665 -376.302604)
			(xy 375.102866 -376.294826) (xy 375.088478 -376.280441) (xy 375.080697 -376.261643) (xy 375.080276 -376.25147)
			(xy 375.080276 -376.093482) (xy 375.07988 -376.084293) (xy 375.073357 -376.067109) (xy 375.067576 -376.059954)
			(xy 375.045817 -376.034278) (xy 375.007865 -375.978696) (xy 374.976828 -375.918976) (xy 374.953152 -375.855974)
			(xy 374.937176 -375.790595) (xy 374.929129 -375.723774) (xy 374.929126 -375.656471) (xy 374.937168 -375.58965)
			(xy 374.953138 -375.524269) (xy 374.97681 -375.461265) (xy 375.007841 -375.401543) (xy 375.045789 -375.345958)
			(xy 375.067576 -375.320306) (xy 375.07335 -375.313144) (xy 375.079879 -375.295967) (xy 375.080276 -375.286778)
			(xy 375.080276 -374.79351) (xy 375.079866 -374.784323) (xy 375.073353 -374.767138) (xy 375.067576 -374.759982)
			(xy 375.045746 -374.734365) (xy 375.007796 -374.678774) (xy 374.976762 -374.619046) (xy 374.95309 -374.556037)
			(xy 374.937119 -374.49065) (xy 374.929078 -374.423823) (xy 345.250779 -374.423823) (xy 345.242739 -374.49064)
			(xy 345.226769 -374.55602) (xy 345.2031 -374.619022) (xy 345.172071 -374.678745) (xy 345.134126 -374.73433)
			(xy 345.11234 -374.759982) (xy 345.106519 -374.767109) (xy 345.10002 -374.784314) (xy 345.09964 -374.79351)
			(xy 345.09964 -375.286778) (xy 345.100074 -375.295962) (xy 345.106573 -375.313146) (xy 345.11234 -375.320306)
			(xy 345.134158 -375.345933) (xy 345.172107 -375.401523) (xy 345.203141 -375.46125) (xy 345.226813 -375.524258)
			(xy 345.242784 -375.589643) (xy 345.250826 -375.656469) (xy 345.250823 -375.723776) (xy 345.242776 -375.790602)
			(xy 345.226799 -375.855986) (xy 345.203122 -375.918992) (xy 345.172084 -375.978716) (xy 345.13413 -376.034302)
			(xy 345.11234 -376.059954) (xy 345.106531 -376.06709) (xy 345.100025 -376.084288) (xy 345.09964 -376.093482)
			(xy 345.09964 -376.25147) (xy 345.099211 -376.261642) (xy 345.091432 -376.280441) (xy 345.077047 -376.294827)
			(xy 345.05825 -376.302609) (xy 345.048078 -376.303032) (xy 344.331798 -376.303032) (xy 344.321623 -376.302637)
			(xy 344.302822 -376.294846) (xy 344.288436 -376.280451) (xy 344.280657 -376.261646) (xy 344.280236 -376.25147)
			(xy 344.280236 -376.093482) (xy 344.279826 -376.084295) (xy 344.273311 -376.067111) (xy 344.267536 -376.059954)
			(xy 344.245778 -376.034277) (xy 344.207829 -375.978694) (xy 344.176794 -375.918974) (xy 344.15312 -375.855973)
			(xy 344.137145 -375.790594) (xy 344.129098 -375.723774) (xy 344.129096 -375.656471) (xy 344.137137 -375.589651)
			(xy 344.153106 -375.52427) (xy 344.176776 -375.461267) (xy 344.207805 -375.401544) (xy 344.24575 -375.345958)
			(xy 344.267536 -375.320306) (xy 344.273317 -375.31315) (xy 344.27984 -375.295968) (xy 344.280236 -375.286778)
			(xy 344.280236 -374.79351) (xy 344.279813 -374.784324) (xy 344.273308 -374.76714) (xy 344.267536 -374.759982)
			(xy 344.245707 -374.734364) (xy 344.20776 -374.678772) (xy 344.176728 -374.619044) (xy 344.153058 -374.556035)
			(xy 344.137088 -374.490649) (xy 344.129047 -374.423823) (xy 340.850988 -374.423823) (xy 340.842948 -374.490639)
			(xy 340.826979 -374.556019) (xy 340.803311 -374.619022) (xy 340.772282 -374.678744) (xy 340.734337 -374.73433)
			(xy 340.712552 -374.759982) (xy 340.706732 -374.76711) (xy 340.700233 -374.784314) (xy 340.699852 -374.79351)
			(xy 340.699852 -375.286778) (xy 340.700283 -375.295963) (xy 340.706783 -375.313147) (xy 340.712552 -375.320306)
			(xy 340.73437 -375.345934) (xy 340.772318 -375.401523) (xy 340.803351 -375.46125) (xy 340.827022 -375.524258)
			(xy 340.842993 -375.589643) (xy 340.851035 -375.656469) (xy 340.851032 -375.723776) (xy 340.842985 -375.790601)
			(xy 340.827009 -375.855985) (xy 340.803332 -375.918991) (xy 340.772295 -375.978715) (xy 340.734342 -376.034302)
			(xy 340.712552 -376.059954) (xy 340.706744 -376.067091) (xy 340.700237 -376.084288) (xy 340.699852 -376.093482)
			(xy 340.699852 -376.25147) (xy 340.699411 -376.261641) (xy 340.691634 -376.280437) (xy 340.677254 -376.294823)
			(xy 340.658461 -376.302607) (xy 340.64829 -376.303032) (xy 339.93201 -376.303032) (xy 339.921835 -376.302627)
			(xy 339.903035 -376.29484) (xy 339.888649 -376.280448) (xy 339.880869 -376.261645) (xy 339.880448 -376.25147)
			(xy 339.880448 -376.093482) (xy 339.880036 -376.084295) (xy 339.873522 -376.067111) (xy 339.867748 -376.059954)
			(xy 339.84599 -376.034278) (xy 339.808039 -375.978695) (xy 339.777004 -375.918975) (xy 339.753329 -375.855973)
			(xy 339.737354 -375.790594) (xy 339.729307 -375.723774) (xy 339.729305 -375.656471) (xy 339.737346 -375.58965)
			(xy 339.753316 -375.52427) (xy 339.776986 -375.461267) (xy 339.808016 -375.401544) (xy 339.845962 -375.345958)
			(xy 339.867748 -375.320306) (xy 339.873531 -375.313151) (xy 339.880052 -375.295968) (xy 339.880448 -375.286778)
			(xy 339.880448 -374.79351) (xy 339.880022 -374.784325) (xy 339.873518 -374.767141) (xy 339.867748 -374.759982)
			(xy 339.845919 -374.734364) (xy 339.80797 -374.678773) (xy 339.776938 -374.619045) (xy 339.753268 -374.556036)
			(xy 339.737297 -374.490649) (xy 339.729256 -374.423823) (xy 336.45122 -374.423823) (xy 336.45122 -374.423879)
			(xy 336.443148 -374.490815) (xy 336.427115 -374.556303) (xy 336.403354 -374.619398) (xy 336.372206 -374.679193)
			(xy 336.334119 -374.734826) (xy 336.312256 -374.76049) (xy 336.306433 -374.767616) (xy 336.299935 -374.784821)
			(xy 336.299556 -374.794018) (xy 336.299556 -375.28627) (xy 336.29999 -375.295454) (xy 336.306488 -375.312639)
			(xy 336.312256 -375.319798) (xy 336.334151 -375.345438) (xy 336.372242 -375.401075) (xy 336.403394 -375.460875)
			(xy 336.427158 -375.523975) (xy 336.443193 -375.589467) (xy 336.451267 -375.656409) (xy 336.451264 -375.723836)
			(xy 336.443185 -375.790777) (xy 336.427145 -375.856268) (xy 336.403375 -375.919367) (xy 336.372218 -375.979163)
			(xy 336.334123 -376.034797) (xy 336.312256 -376.060462) (xy 336.306445 -376.067597) (xy 336.29994 -376.084795)
			(xy 336.299556 -376.09399) (xy 336.299556 -376.25147) (xy 336.299049 -376.261595) (xy 336.29133 -376.280317)
			(xy 336.27705 -376.294674) (xy 336.258371 -376.302494) (xy 336.248248 -376.303032) (xy 335.531968 -376.303032)
			(xy 335.521816 -376.302605) (xy 335.503069 -376.294805) (xy 335.488748 -376.280411) (xy 335.481043 -376.261624)
			(xy 335.48066 -376.25147) (xy 335.48066 -376.09399) (xy 335.480241 -376.084804) (xy 335.473732 -376.06762)
			(xy 335.46796 -376.060462) (xy 335.446127 -376.034772) (xy 335.40804 -375.97914) (xy 335.37689 -375.919347)
			(xy 335.353126 -375.856253) (xy 335.33709 -375.790768) (xy 335.329012 -375.723833) (xy 335.329009 -375.656412)
			(xy 335.337082 -375.589477) (xy 335.353113 -375.52399) (xy 335.376872 -375.460894) (xy 335.408017 -375.401099)
			(xy 335.446099 -375.345464) (xy 335.46796 -375.319798) (xy 335.473747 -375.312647) (xy 335.480266 -375.295461)
			(xy 335.48066 -375.28627) (xy 335.48066 -374.794018) (xy 335.480228 -374.784833) (xy 335.473728 -374.76765)
			(xy 335.46796 -374.76049) (xy 335.446056 -374.734858) (xy 335.407971 -374.679218) (xy 335.376825 -374.619417)
			(xy 335.353065 -374.556316) (xy 335.337033 -374.490823) (xy 335.328961 -374.423882) (xy 332.050892 -374.423882)
			(xy 332.04286 -374.490639) (xy 332.026892 -374.556019) (xy 332.003224 -374.619021) (xy 331.972196 -374.678744)
			(xy 331.934253 -374.73433) (xy 331.912468 -374.759982) (xy 331.90665 -374.767112) (xy 331.900149 -374.784314)
			(xy 331.899768 -374.79351) (xy 331.899768 -375.286778) (xy 331.900196 -375.295963) (xy 331.906698 -375.313147)
			(xy 331.912468 -375.320306) (xy 331.934285 -375.345934) (xy 331.972233 -375.401524) (xy 332.003264 -375.461251)
			(xy 332.026935 -375.524259) (xy 332.042906 -375.589644) (xy 332.050947 -375.656469) (xy 332.050945 -375.723776)
			(xy 332.042898 -375.790601) (xy 332.026922 -375.855985) (xy 332.003246 -375.91899) (xy 331.972209 -375.978715)
			(xy 331.934257 -376.034302) (xy 331.912468 -376.059954) (xy 331.906662 -376.067092) (xy 331.900154 -376.084288)
			(xy 331.899768 -376.093482) (xy 331.899768 -376.25147) (xy 331.899312 -376.261639) (xy 331.891538 -376.280432)
			(xy 331.877162 -376.294817) (xy 331.858375 -376.302604) (xy 331.848206 -376.303032) (xy 331.131926 -376.303032)
			(xy 331.121752 -376.302614) (xy 331.102953 -376.294832) (xy 331.088566 -376.280444) (xy 331.080785 -376.261644)
			(xy 331.080364 -376.25147) (xy 331.080364 -376.093482) (xy 331.079948 -376.084296) (xy 331.073437 -376.067112)
			(xy 331.067664 -376.059954) (xy 331.045905 -376.034278) (xy 331.007954 -375.978695) (xy 330.976918 -375.918975)
			(xy 330.953242 -375.855974) (xy 330.937266 -375.790594) (xy 330.92922 -375.723774) (xy 330.929217 -375.656471)
			(xy 330.937258 -375.58965) (xy 330.953229 -375.524269) (xy 330.976899 -375.461266) (xy 331.007931 -375.401543)
			(xy 331.045877 -375.345958) (xy 331.067664 -375.320306) (xy 331.073448 -375.313152) (xy 331.079969 -375.295968)
			(xy 331.080364 -375.286778) (xy 331.080364 -374.79351) (xy 331.079935 -374.784325) (xy 331.073433 -374.767141)
			(xy 331.067664 -374.759982) (xy 331.045834 -374.734364) (xy 331.007885 -374.678773) (xy 330.976852 -374.619045)
			(xy 330.95318 -374.556036) (xy 330.93721 -374.49065) (xy 330.929168 -374.423823) (xy 301.250868 -374.423823)
			(xy 301.250868 -374.423878) (xy 301.242797 -374.490814) (xy 301.226766 -374.5563) (xy 301.203008 -374.619395)
			(xy 301.171863 -374.67919) (xy 301.133781 -374.734824) (xy 301.11192 -374.76049) (xy 301.106105 -374.767622)
			(xy 301.099601 -374.784823) (xy 301.09922 -374.794018) (xy 301.09922 -375.28627) (xy 301.09964 -375.295456)
			(xy 301.106146 -375.312641) (xy 301.11192 -375.319798) (xy 301.133813 -375.345439) (xy 301.171899 -375.401078)
			(xy 301.203048 -375.460877) (xy 301.226809 -375.523977) (xy 301.242842 -375.589469) (xy 301.250915 -375.65641)
			(xy 301.250912 -375.723835) (xy 301.242834 -375.790775) (xy 301.226796 -375.856266) (xy 301.203029 -375.919364)
			(xy 301.171876 -375.979161) (xy 301.133785 -376.034796) (xy 301.11192 -376.060462) (xy 301.106117 -376.067603)
			(xy 301.099605 -376.084797) (xy 301.09922 -376.09399) (xy 301.09922 -376.25147) (xy 301.098748 -376.2616)
			(xy 301.091023 -376.280328) (xy 301.076731 -376.294687) (xy 301.058039 -376.3025) (xy 301.047912 -376.303032)
			(xy 300.331632 -376.303032) (xy 300.321484 -376.302553) (xy 300.302738 -376.294774) (xy 300.288415 -376.280395)
			(xy 300.280708 -376.26162) (xy 300.280324 -376.25147) (xy 300.280324 -376.09399) (xy 300.279913 -376.084803)
			(xy 300.2734 -376.067619) (xy 300.267624 -376.060462) (xy 300.245789 -376.034773) (xy 300.207697 -375.979142)
			(xy 300.176544 -375.91935) (xy 300.152777 -375.856256) (xy 300.136739 -375.790769) (xy 300.12866 -375.723833)
			(xy 300.128658 -375.656412) (xy 300.136731 -375.589475) (xy 300.152764 -375.523987) (xy 300.176526 -375.460892)
			(xy 300.207674 -375.401096) (xy 300.245761 -375.345463) (xy 300.267624 -375.319798) (xy 300.273407 -375.312643)
			(xy 300.279929 -375.29546) (xy 300.280324 -375.28627) (xy 300.280324 -374.794018) (xy 300.2799 -374.784832)
			(xy 300.273395 -374.767648) (xy 300.267624 -374.76049) (xy 300.245718 -374.734859) (xy 300.207629 -374.67922)
			(xy 300.176479 -374.61942) (xy 300.152716 -374.556318) (xy 300.136683 -374.490825) (xy 300.12861 -374.423882)
			(xy 296.851077 -374.423882) (xy 296.843006 -374.490813) (xy 296.826976 -374.556299) (xy 296.803218 -374.619394)
			(xy 296.772074 -374.67919) (xy 296.733992 -374.734824) (xy 296.712132 -374.76049) (xy 296.706306 -374.767614)
			(xy 296.699811 -374.784821) (xy 296.699432 -374.794018) (xy 296.699432 -375.28627) (xy 296.699872 -375.295454)
			(xy 296.706366 -375.312638) (xy 296.712132 -375.319798) (xy 296.734024 -375.345439) (xy 296.77211 -375.401078)
			(xy 296.803258 -375.460878) (xy 296.827019 -375.523978) (xy 296.843051 -375.589469) (xy 296.851124 -375.65641)
			(xy 296.851121 -375.723835) (xy 296.843043 -375.790775) (xy 296.827005 -375.856265) (xy 296.803239 -375.919363)
			(xy 296.772087 -375.979161) (xy 296.733997 -376.034796) (xy 296.712132 -376.060462) (xy 296.706318 -376.067595)
			(xy 296.699816 -376.084795) (xy 296.699432 -376.09399) (xy 296.699432 -376.25147) (xy 296.698948 -376.261598)
			(xy 296.691225 -376.280324) (xy 296.676937 -376.294683) (xy 296.65825 -376.302498) (xy 296.648124 -376.303032)
			(xy 295.931844 -376.303032) (xy 295.921697 -376.302543) (xy 295.902951 -376.294768) (xy 295.888628 -376.280392)
			(xy 295.880921 -376.261619) (xy 295.880536 -376.25147) (xy 295.880536 -376.09399) (xy 295.880123 -376.084803)
			(xy 295.87361 -376.067619) (xy 295.867836 -376.060462) (xy 295.846 -376.034773) (xy 295.807908 -375.979143)
			(xy 295.776754 -375.91935) (xy 295.752987 -375.856256) (xy 295.736948 -375.79077) (xy 295.728869 -375.723834)
			(xy 295.728867 -375.656412) (xy 295.73694 -375.589475) (xy 295.752973 -375.523987) (xy 295.776736 -375.460891)
			(xy 295.807885 -375.401096) (xy 295.845973 -375.345463) (xy 295.867836 -375.319798) (xy 295.873621 -375.312644)
			(xy 295.880142 -375.29546) (xy 295.880536 -375.28627) (xy 295.880536 -374.794018) (xy 295.880109 -374.784833)
			(xy 295.873606 -374.767649) (xy 295.867836 -374.76049) (xy 295.84593 -374.734859) (xy 295.80784 -374.679221)
			(xy 295.776689 -374.61942) (xy 295.752925 -374.556319) (xy 295.736892 -374.490825) (xy 295.728819 -374.423882)
			(xy 292.450774 -374.423882) (xy 292.442742 -374.490639) (xy 292.426773 -374.55602) (xy 292.403104 -374.619022)
			(xy 292.372075 -374.678745) (xy 292.33413 -374.73433) (xy 292.312344 -374.759982) (xy 292.306523 -374.76711)
			(xy 292.300025 -374.784314) (xy 292.299644 -374.79351) (xy 292.299644 -375.286778) (xy 292.300077 -375.295962)
			(xy 292.306576 -375.313146) (xy 292.312344 -375.320306) (xy 292.334162 -375.345934) (xy 292.372111 -375.401523)
			(xy 292.403144 -375.46125) (xy 292.426816 -375.524258) (xy 292.442787 -375.589643) (xy 292.450829 -375.656469)
			(xy 292.450826 -375.723776) (xy 292.442779 -375.790601) (xy 292.426802 -375.855985) (xy 292.403125 -375.918991)
			(xy 292.372088 -375.978716) (xy 292.334134 -376.034302) (xy 292.312344 -376.059954) (xy 292.306535 -376.06709)
			(xy 292.300029 -376.084288) (xy 292.299644 -376.093482) (xy 292.299644 -376.25147) (xy 292.299211 -376.261642)
			(xy 292.291433 -376.280439) (xy 292.277049 -376.294826) (xy 292.258254 -376.302609) (xy 292.248082 -376.303032)
			(xy 291.531802 -376.303032) (xy 291.521627 -376.302634) (xy 291.502826 -376.294844) (xy 291.48844 -376.28045)
			(xy 291.480661 -376.261645) (xy 291.48024 -376.25147) (xy 291.48024 -376.093482) (xy 291.47983 -376.084295)
			(xy 291.473315 -376.067111) (xy 291.46754 -376.059954) (xy 291.445782 -376.034277) (xy 291.407832 -375.978695)
			(xy 291.376798 -375.918974) (xy 291.353123 -375.855973) (xy 291.337148 -375.790594) (xy 291.329101 -375.723774)
			(xy 291.329099 -375.656471) (xy 291.33714 -375.589651) (xy 291.35311 -375.52427) (xy 291.376779 -375.461267)
			(xy 291.407809 -375.401544) (xy 291.445754 -375.345958) (xy 291.46754 -375.320306) (xy 291.473322 -375.31315)
			(xy 291.479844 -375.295968) (xy 291.48024 -375.286778) (xy 291.48024 -374.79351) (xy 291.479816 -374.784324)
			(xy 291.473311 -374.76714) (xy 291.46754 -374.759982) (xy 291.445711 -374.734364) (xy 291.407763 -374.678773)
			(xy 291.376732 -374.619044) (xy 291.353061 -374.556035) (xy 291.337091 -374.490649) (xy 291.32905 -374.423823)
			(xy 288.051014 -374.423823) (xy 288.051014 -374.423879) (xy 288.042941 -374.490816) (xy 288.026909 -374.556303)
			(xy 288.003147 -374.619398) (xy 287.971998 -374.679193) (xy 287.933911 -374.734826) (xy 287.912048 -374.76049)
			(xy 287.906224 -374.767616) (xy 287.899727 -374.784821) (xy 287.899348 -374.794018) (xy 287.899348 -375.28627)
			(xy 287.899784 -375.295454) (xy 287.906281 -375.312638) (xy 287.912048 -375.319798) (xy 287.933943 -375.345438)
			(xy 287.972035 -375.401075) (xy 288.003187 -375.460874) (xy 288.026952 -375.523974) (xy 288.042987 -375.589467)
			(xy 288.051061 -375.656409) (xy 288.051058 -375.723836) (xy 288.042978 -375.790777) (xy 288.026938 -375.856269)
			(xy 288.003168 -375.919367) (xy 287.972011 -375.979164) (xy 287.933916 -376.034798) (xy 287.912048 -376.060462)
			(xy 287.906236 -376.067596) (xy 287.899732 -376.084795) (xy 287.899348 -376.09399) (xy 287.899348 -376.25147)
			(xy 287.898849 -376.261596) (xy 287.891129 -376.280319) (xy 287.876846 -376.294677) (xy 287.858164 -376.302495)
			(xy 287.84804 -376.303032) (xy 287.13176 -376.303032) (xy 287.121653 -376.302548) (xy 287.10298 -376.294804)
			(xy 287.088687 -376.280507) (xy 287.080948 -376.261831) (xy 287.080452 -376.251724) (xy 287.080452 -376.09399)
			(xy 287.080035 -376.084804) (xy 287.073525 -376.06762) (xy 287.067752 -376.060462) (xy 287.045916 -376.034773)
			(xy 287.007823 -375.979143) (xy 286.976668 -375.919351) (xy 286.9529 -375.856257) (xy 286.93686 -375.79077)
			(xy 286.928781 -375.723834) (xy 286.928779 -375.656411) (xy 286.936852 -375.589474) (xy 286.952886 -375.523986)
			(xy 286.976649 -375.46089) (xy 287.007799 -375.401095) (xy 287.045888 -375.345462) (xy 287.067752 -375.319798)
			(xy 287.073538 -375.312646) (xy 287.080058 -375.29546) (xy 287.080452 -375.28627) (xy 287.080452 -374.794018)
			(xy 287.080022 -374.784833) (xy 287.073521 -374.767649) (xy 287.067752 -374.76049) (xy 287.045845 -374.73486)
			(xy 287.007754 -374.679221) (xy 286.976602 -374.619421) (xy 286.952838 -374.556319) (xy 286.936804 -374.490825)
			(xy 286.928731 -374.423882) (xy 266.12088 -374.423882) (xy 266.12088 -377.534932) (xy 266.120477 -377.545004)
			(xy 266.112741 -377.563602) (xy 266.105894 -377.571) (xy 265.757406 -377.919234) (xy 265.750002 -377.926069)
			(xy 265.731406 -377.933791) (xy 265.721338 -377.93422) (xy 243.05133 -377.93422) (xy 243.04126 -377.9338)
			(xy 243.022661 -377.926078) (xy 243.015262 -377.919234) (xy 242.506246 -377.410472) (xy 242.499408 -377.40307)
			(xy 242.491685 -377.384473) (xy 242.49126 -377.374404) (xy 234.964478 -377.374404) (xy 236.356885 -378.766811)
			(xy 269.68983 -378.766811) (xy 269.68983 -378.633249) (xy 269.697894 -378.499931) (xy 269.713994 -378.367343)
			(xy 269.738069 -378.235969) (xy 269.770032 -378.106288) (xy 269.809767 -377.978774) (xy 269.857129 -377.853891)
			(xy 269.911944 -377.732096) (xy 269.974014 -377.613833) (xy 270.04311 -377.499534) (xy 270.118982 -377.389614)
			(xy 270.201352 -377.284477) (xy 270.28992 -377.184504) (xy 270.384362 -377.090062) (xy 270.484335 -377.001494)
			(xy 270.589472 -376.919124) (xy 270.699392 -376.843252) (xy 270.813691 -376.774156) (xy 270.931954 -376.712086)
			(xy 271.053749 -376.657271) (xy 271.178632 -376.609909) (xy 271.306146 -376.570174) (xy 271.435827 -376.538211)
			(xy 271.567201 -376.514136) (xy 271.699789 -376.498036) (xy 271.833107 -376.489972) (xy 271.966669 -376.489972)
			(xy 272.099987 -376.498036) (xy 272.232575 -376.514136) (xy 272.363949 -376.538211) (xy 272.49363 -376.570174)
			(xy 272.621144 -376.609909) (xy 272.746027 -376.657271) (xy 272.867822 -376.712086) (xy 272.986085 -376.774156)
			(xy 273.068299 -376.823856) (xy 289.128922 -376.823856) (xy 289.128922 -376.75655) (xy 289.136967 -376.689727)
			(xy 289.152941 -376.624344) (xy 289.176615 -376.56134) (xy 289.207651 -376.501617) (xy 289.245603 -376.446031)
			(xy 289.267392 -376.42038) (xy 289.273179 -376.413228) (xy 289.2797 -376.396043) (xy 289.280092 -376.386852)
			(xy 289.280092 -375.893584) (xy 289.279691 -375.884396) (xy 289.273171 -375.867212) (xy 289.267392 -375.860056)
			(xy 289.245634 -375.834379) (xy 289.207681 -375.778797) (xy 289.176643 -375.719078) (xy 289.152966 -375.656076)
			(xy 289.13699 -375.590696) (xy 289.128942 -375.523876) (xy 289.128939 -375.456572) (xy 289.136981 -375.389751)
			(xy 289.152952 -375.32437) (xy 289.176624 -375.261367) (xy 289.207656 -375.201644) (xy 289.245605 -375.146059)
			(xy 289.267392 -375.120408) (xy 289.273167 -375.113247) (xy 289.279695 -375.096069) (xy 289.280092 -375.08688)
			(xy 289.280092 -374.928638) (xy 289.280664 -374.918488) (xy 289.288417 -374.899729) (xy 289.302758 -374.885364)
			(xy 289.321505 -374.87758) (xy 289.331654 -374.877076) (xy 290.047934 -374.877076) (xy 290.058113 -374.877437)
			(xy 290.076915 -374.88524) (xy 290.0913 -374.899645) (xy 290.099077 -374.918459) (xy 290.099496 -374.928638)
			(xy 290.099496 -375.08688) (xy 290.099917 -375.096066) (xy 290.106423 -375.11325) (xy 290.112196 -375.120408)
			(xy 290.134014 -375.146035) (xy 290.17196 -375.201626) (xy 290.20299 -375.261353) (xy 290.226659 -375.324361)
			(xy 290.242629 -375.389746) (xy 290.25067 -375.456571) (xy 290.250667 -375.523878) (xy 290.24262 -375.590702)
			(xy 290.226645 -375.656085) (xy 290.20297 -375.719091) (xy 290.171935 -375.778816) (xy 290.133985 -375.834403)
			(xy 290.112196 -375.860056) (xy 290.106393 -375.867196) (xy 290.099882 -375.884391) (xy 290.099496 -375.893584)
			(xy 290.099496 -376.386852) (xy 290.09993 -376.396037) (xy 290.106427 -376.413221) (xy 290.112196 -376.42038)
			(xy 290.133987 -376.446029) (xy 290.171933 -376.501617) (xy 290.202964 -376.561341) (xy 290.226635 -376.624346)
			(xy 290.242607 -376.689728) (xy 290.25065 -376.756551) (xy 290.25065 -376.823855) (xy 290.250643 -376.823915)
			(xy 293.528715 -376.823915) (xy 293.528715 -376.756491) (xy 293.53679 -376.689554) (xy 293.552824 -376.624065)
			(xy 293.576588 -376.560968) (xy 293.607737 -376.501172) (xy 293.645825 -376.445537) (xy 293.667688 -376.419872)
			(xy 293.673478 -376.412722) (xy 293.679997 -376.395535) (xy 293.680388 -376.386344) (xy 293.680388 -375.894092)
			(xy 293.679984 -375.884904) (xy 293.673466 -375.86772) (xy 293.667688 -375.860564) (xy 293.645856 -375.834873)
			(xy 293.607767 -375.779242) (xy 293.576616 -375.719449) (xy 293.55285 -375.656355) (xy 293.536813 -375.59087)
			(xy 293.528735 -375.523934) (xy 293.528732 -375.456514) (xy 293.536804 -375.389578) (xy 293.552836 -375.324091)
			(xy 293.576596 -375.260995) (xy 293.607742 -375.2012) (xy 293.645826 -375.145565) (xy 293.667688 -375.1199)
			(xy 293.673466 -375.112741) (xy 293.679992 -375.095561) (xy 293.680388 -375.086372) (xy 293.680388 -374.928638)
			(xy 293.680956 -374.91852) (xy 293.688662 -374.89981) (xy 293.702923 -374.885454) (xy 293.721582 -374.877624)
			(xy 293.731696 -374.877076) (xy 294.447976 -374.877076) (xy 294.458094 -374.877535) (xy 294.476793 -374.885271)
			(xy 294.491107 -374.899574) (xy 294.498857 -374.918266) (xy 294.499284 -374.928384) (xy 294.499284 -375.086372)
			(xy 294.499711 -375.095557) (xy 294.506214 -375.112742) (xy 294.511984 -375.1199) (xy 294.53388 -375.145539)
			(xy 294.571969 -375.201177) (xy 294.603119 -375.260977) (xy 294.626882 -375.324077) (xy 294.642916 -375.389569)
			(xy 294.650989 -375.456511) (xy 294.650986 -375.523937) (xy 294.642907 -375.590878) (xy 294.626868 -375.656369)
			(xy 294.603099 -375.719467) (xy 294.571944 -375.779264) (xy 294.53385 -375.834899) (xy 294.511984 -375.860564)
			(xy 294.506176 -375.867701) (xy 294.499669 -375.884898) (xy 294.499284 -375.894092) (xy 294.499284 -376.386344)
			(xy 294.499677 -376.395533) (xy 294.506203 -376.412717) (xy 294.511984 -376.419872) (xy 294.533852 -376.445534)
			(xy 294.571942 -376.501168) (xy 294.603094 -376.560965) (xy 294.626858 -376.624062) (xy 294.642894 -376.689552)
			(xy 294.65097 -376.756491) (xy 294.650969 -376.823856) (xy 297.92901 -376.823856) (xy 297.92901 -376.75655)
			(xy 297.937054 -376.689727) (xy 297.953028 -376.624345) (xy 297.976702 -376.56134) (xy 298.007737 -376.501617)
			(xy 298.045687 -376.446032) (xy 298.067476 -376.42038) (xy 298.073261 -376.413226) (xy 298.079783 -376.396042)
			(xy 298.080176 -376.386852) (xy 298.080176 -375.893584) (xy 298.079779 -375.884395) (xy 298.073257 -375.867211)
			(xy 298.067476 -375.860056) (xy 298.045719 -375.834378) (xy 298.007766 -375.778797) (xy 297.97673 -375.719077)
			(xy 297.953054 -375.656076) (xy 297.937077 -375.590696) (xy 297.92903 -375.523876) (xy 297.929027 -375.456572)
			(xy 297.937069 -375.389751) (xy 297.953039 -375.324371) (xy 297.97671 -375.261367) (xy 298.007742 -375.201645)
			(xy 298.045689 -375.14606) (xy 298.067476 -375.120408) (xy 298.073249 -375.113246) (xy 298.079778 -375.096068)
			(xy 298.080176 -375.08688) (xy 298.080176 -374.928638) (xy 298.080596 -374.918464) (xy 298.088376 -374.899663)
			(xy 298.102763 -374.885276) (xy 298.121564 -374.877496) (xy 298.131738 -374.877076) (xy 298.848018 -374.877076)
			(xy 298.858195 -374.87745) (xy 298.876998 -374.885248) (xy 298.891383 -374.899649) (xy 298.899161 -374.91846)
			(xy 298.89958 -374.928638) (xy 298.89958 -375.08688) (xy 298.900004 -375.096066) (xy 298.906509 -375.11325)
			(xy 298.91228 -375.120408) (xy 298.934099 -375.146035) (xy 298.972045 -375.201625) (xy 299.003076 -375.261352)
			(xy 299.026746 -375.32436) (xy 299.042716 -375.389745) (xy 299.050758 -375.45657) (xy 299.050755 -375.523878)
			(xy 299.042708 -375.590702) (xy 299.026732 -375.656086) (xy 299.003056 -375.719092) (xy 298.972021 -375.778816)
			(xy 298.934069 -375.834404) (xy 298.91228 -375.860056) (xy 298.906475 -375.867195) (xy 298.899966 -375.88439)
			(xy 298.89958 -375.893584) (xy 298.89958 -376.386852) (xy 298.900018 -376.396036) (xy 298.906513 -376.413221)
			(xy 298.91228 -376.42038) (xy 298.934071 -376.446029) (xy 298.972019 -376.501616) (xy 299.003051 -376.561341)
			(xy 299.026722 -376.624345) (xy 299.042695 -376.689728) (xy 299.050731 -376.756492) (xy 302.328802 -376.756492)
			(xy 302.336877 -376.689554) (xy 302.352912 -376.624066) (xy 302.376674 -376.560969) (xy 302.407823 -376.501173)
			(xy 302.445909 -376.445538) (xy 302.467772 -376.419872) (xy 302.473572 -376.412729) (xy 302.480082 -376.395537)
			(xy 302.480472 -376.386344) (xy 302.480472 -375.894092) (xy 302.480072 -375.884904) (xy 302.473552 -375.867719)
			(xy 302.467772 -375.860564) (xy 302.44594 -375.834872) (xy 302.407853 -375.779241) (xy 302.376702 -375.719448)
			(xy 302.352937 -375.656355) (xy 302.336901 -375.590869) (xy 302.328823 -375.523934) (xy 302.32882 -375.456514)
			(xy 302.336892 -375.389578) (xy 302.352923 -375.324091) (xy 302.376682 -375.260996) (xy 302.407828 -375.2012)
			(xy 302.445911 -375.145566) (xy 302.467772 -375.1199) (xy 302.47356 -375.112749) (xy 302.480078 -375.095563)
			(xy 302.480472 -375.086372) (xy 302.480472 -374.928638) (xy 302.480959 -374.91851) (xy 302.48868 -374.899784)
			(xy 302.502967 -374.885425) (xy 302.521654 -374.87761) (xy 302.53178 -374.877076) (xy 303.24806 -374.877076)
			(xy 303.258209 -374.877554) (xy 303.276955 -374.885332) (xy 303.291279 -374.899711) (xy 303.298985 -374.918488)
			(xy 303.299368 -374.928638) (xy 303.299368 -375.086372) (xy 303.299799 -375.095557) (xy 303.306299 -375.112741)
			(xy 303.312068 -375.1199) (xy 303.333965 -375.145539) (xy 303.372054 -375.201176) (xy 303.403205 -375.260976)
			(xy 303.426969 -375.324076) (xy 303.443004 -375.389569) (xy 303.451077 -375.456511) (xy 303.451074 -375.523937)
			(xy 303.442995 -375.590878) (xy 303.426955 -375.65637) (xy 303.403186 -375.719468) (xy 303.37203 -375.779265)
			(xy 303.333935 -375.834899) (xy 303.312068 -375.860564) (xy 303.306258 -375.867699) (xy 303.299752 -375.884898)
			(xy 303.299368 -375.894092) (xy 303.299368 -376.386344) (xy 303.299764 -376.395533) (xy 303.306288 -376.412716)
			(xy 303.312068 -376.419872) (xy 303.333937 -376.445533) (xy 303.372028 -376.501168) (xy 303.40318 -376.560964)
			(xy 303.426945 -376.624062) (xy 303.442982 -376.689551) (xy 303.451058 -376.756491) (xy 303.451057 -376.823915)
			(xy 333.128833 -376.823915) (xy 333.128833 -376.756491) (xy 333.136908 -376.689553) (xy 333.152944 -376.624064)
			(xy 333.176708 -376.560967) (xy 333.207859 -376.501171) (xy 333.245948 -376.445537) (xy 333.267812 -376.419872)
			(xy 333.273604 -376.412724) (xy 333.280121 -376.395536) (xy 333.280512 -376.386344) (xy 333.280512 -375.894092)
			(xy 333.280103 -375.884905) (xy 333.273588 -375.86772) (xy 333.267812 -375.860564) (xy 333.245979 -375.834873)
			(xy 333.207889 -375.779242) (xy 333.176736 -375.71945) (xy 333.152969 -375.656356) (xy 333.136931 -375.59087)
			(xy 333.128853 -375.523935) (xy 333.12885 -375.456513) (xy 333.136923 -375.389577) (xy 333.152955 -375.32409)
			(xy 333.176716 -375.260994) (xy 333.207864 -375.201199) (xy 333.24595 -375.145565) (xy 333.267812 -375.1199)
			(xy 333.273592 -375.112743) (xy 333.280116 -375.095562) (xy 333.280512 -375.086372) (xy 333.280512 -374.928638)
			(xy 333.281057 -374.918517) (xy 333.288767 -374.899802) (xy 333.303035 -374.885446) (xy 333.321702 -374.87762)
			(xy 333.33182 -374.877076) (xy 334.0481 -374.877076) (xy 334.058251 -374.877521) (xy 334.076999 -374.885312)
			(xy 334.091321 -374.899701) (xy 334.099025 -374.918485) (xy 334.099408 -374.928638) (xy 334.099408 -375.086372)
			(xy 334.09983 -375.095558) (xy 334.106335 -375.112743) (xy 334.112108 -375.1199) (xy 334.134003 -375.145539)
			(xy 334.17209 -375.201178) (xy 334.203239 -375.260978) (xy 334.227001 -375.324078) (xy 334.243034 -375.38957)
			(xy 334.251107 -375.456511) (xy 334.251105 -375.523937) (xy 334.243026 -375.590877) (xy 334.226987 -375.656368)
			(xy 334.20322 -375.719466) (xy 334.172066 -375.779263) (xy 334.133974 -375.834899) (xy 334.112108 -375.860564)
			(xy 334.106303 -375.867703) (xy 334.099793 -375.884898) (xy 334.099408 -375.894092) (xy 334.099408 -376.386344)
			(xy 334.099795 -376.395534) (xy 334.106324 -376.412718) (xy 334.112108 -376.419872) (xy 334.133976 -376.445534)
			(xy 334.172064 -376.501169) (xy 334.203214 -376.560966) (xy 334.226977 -376.624063) (xy 334.243012 -376.689553)
			(xy 334.251088 -376.756491) (xy 334.251087 -376.823855) (xy 337.529152 -376.823855) (xy 337.529152 -376.756551)
			(xy 337.537195 -376.689729) (xy 337.553167 -376.624348) (xy 337.576837 -376.561344) (xy 337.607868 -376.50162)
			(xy 337.645814 -376.446033) (xy 337.6676 -376.42038) (xy 337.673388 -376.413228) (xy 337.679908 -376.396043)
			(xy 337.6803 -376.386852) (xy 337.6803 -375.893584) (xy 337.679897 -375.884396) (xy 337.673378 -375.867212)
			(xy 337.6676 -375.860056) (xy 337.645845 -375.834377) (xy 337.607898 -375.778794) (xy 337.576865 -375.719074)
			(xy 337.553192 -375.656073) (xy 337.537218 -375.590694) (xy 337.529172 -375.523875) (xy 337.529169 -375.456573)
			(xy 337.53721 -375.389753) (xy 337.553178 -375.324373) (xy 337.576846 -375.26137) (xy 337.607873 -375.201647)
			(xy 337.645815 -375.146061) (xy 337.6676 -375.120408) (xy 337.673376 -375.113248) (xy 337.679903 -375.096069)
			(xy 337.6803 -375.08688) (xy 337.6803 -374.928638) (xy 337.680864 -374.918487) (xy 337.688619 -374.899726)
			(xy 337.702963 -374.885361) (xy 337.721712 -374.877579) (xy 337.731862 -374.877076) (xy 338.448142 -374.877076)
			(xy 338.458307 -374.8775) (xy 338.477085 -374.885295) (xy 338.49145 -374.899683) (xy 338.499216 -374.918472)
			(xy 338.499704 -374.928638) (xy 338.499704 -375.08688) (xy 338.500123 -375.096066) (xy 338.50663 -375.113251)
			(xy 338.512404 -375.120408) (xy 338.534222 -375.146035) (xy 338.572167 -375.201626) (xy 338.603196 -375.261353)
			(xy 338.626865 -375.324361) (xy 338.642835 -375.389746) (xy 338.650876 -375.456571) (xy 338.650873 -375.523877)
			(xy 338.642826 -375.590701) (xy 338.626851 -375.656085) (xy 338.603177 -375.719091) (xy 338.572142 -375.778815)
			(xy 338.534192 -375.834403) (xy 338.512404 -375.860056) (xy 338.506602 -375.867197) (xy 338.50009 -375.884391)
			(xy 338.499704 -375.893584) (xy 338.499704 -376.386852) (xy 338.500136 -376.396037) (xy 338.506634 -376.413222)
			(xy 338.512404 -376.42038) (xy 338.534194 -376.44603) (xy 338.57214 -376.501617) (xy 338.603171 -376.561342)
			(xy 338.626842 -376.624346) (xy 338.642813 -376.689729) (xy 338.650856 -376.756551) (xy 338.650856 -376.823855)
			(xy 338.650849 -376.823915) (xy 341.928921 -376.823915) (xy 341.928921 -376.756491) (xy 341.936996 -376.689553)
			(xy 341.953031 -376.624065) (xy 341.976794 -376.560968) (xy 342.007944 -376.501172) (xy 342.046032 -376.445537)
			(xy 342.067896 -376.419872) (xy 342.073686 -376.412722) (xy 342.080205 -376.395535) (xy 342.080596 -376.386344)
			(xy 342.080596 -375.894092) (xy 342.08019 -375.884904) (xy 342.073674 -375.86772) (xy 342.067896 -375.860564)
			(xy 342.046064 -375.834873) (xy 342.007974 -375.779242) (xy 341.976822 -375.719449) (xy 341.953057 -375.656356)
			(xy 341.937019 -375.59087) (xy 341.928941 -375.523935) (xy 341.928938 -375.456513) (xy 341.93701 -375.389577)
			(xy 341.953042 -375.32409) (xy 341.976803 -375.260995) (xy 342.007949 -375.201199) (xy 342.046034 -375.145565)
			(xy 342.067896 -375.1199) (xy 342.073675 -375.112742) (xy 342.0802 -375.095561) (xy 342.080596 -375.086372)
			(xy 342.080596 -374.928638) (xy 342.081157 -374.918519) (xy 342.088864 -374.899807) (xy 342.103127 -374.885451)
			(xy 342.121789 -374.877623) (xy 342.131904 -374.877076) (xy 342.848184 -374.877076) (xy 342.858334 -374.877534)
			(xy 342.877082 -374.88532) (xy 342.891405 -374.899705) (xy 342.899109 -374.918486) (xy 342.899492 -374.928638)
			(xy 342.899492 -375.086372) (xy 342.899917 -375.095558) (xy 342.906421 -375.112742) (xy 342.912192 -375.1199)
			(xy 342.934088 -375.145539) (xy 342.972176 -375.201177) (xy 343.003326 -375.260977) (xy 343.027088 -375.324077)
			(xy 343.043122 -375.38957) (xy 343.051195 -375.456511) (xy 343.051193 -375.523937) (xy 343.043113 -375.590878)
			(xy 343.027074 -375.656369) (xy 343.003306 -375.719467) (xy 342.972151 -375.779264) (xy 342.934058 -375.834899)
			(xy 342.912192 -375.860564) (xy 342.906385 -375.867702) (xy 342.899877 -375.884898) (xy 342.899492 -375.894092)
			(xy 342.899492 -376.386344) (xy 342.899883 -376.395533) (xy 342.90641 -376.412717) (xy 342.912192 -376.419872)
			(xy 342.93406 -376.445534) (xy 342.972149 -376.501169) (xy 343.0033 -376.560965) (xy 343.027065 -376.624063)
			(xy 343.0431 -376.689552) (xy 343.051176 -376.756491) (xy 343.051175 -376.823856) (xy 346.329216 -376.823856)
			(xy 346.329216 -376.75655) (xy 346.33726 -376.689727) (xy 346.353234 -376.624345) (xy 346.376909 -376.56134)
			(xy 346.407944 -376.501617) (xy 346.445895 -376.446032) (xy 346.467684 -376.42038) (xy 346.47347 -376.413227)
			(xy 346.479991 -376.396043) (xy 346.480384 -376.386852) (xy 346.480384 -375.893584) (xy 346.479985 -375.884396)
			(xy 346.473464 -375.867211) (xy 346.467684 -375.860056) (xy 346.445926 -375.834379) (xy 346.407974 -375.778797)
			(xy 346.376937 -375.719077) (xy 346.35326 -375.656076) (xy 346.337283 -375.590696) (xy 346.329236 -375.523876)
			(xy 346.329233 -375.456572) (xy 346.337275 -375.389751) (xy 346.353246 -375.32437) (xy 346.376917 -375.261367)
			(xy 346.407949 -375.201645) (xy 346.445897 -375.14606) (xy 346.467684 -375.120408) (xy 346.473458 -375.113247)
			(xy 346.479987 -375.096069) (xy 346.480384 -375.08688) (xy 346.480384 -374.928638) (xy 346.480796 -374.918463)
			(xy 346.488577 -374.899661) (xy 346.502967 -374.885273) (xy 346.521771 -374.877495) (xy 346.531946 -374.877076)
			(xy 347.248226 -374.877076) (xy 347.258404 -374.877443) (xy 347.277207 -374.885244) (xy 347.291592 -374.899647)
			(xy 347.299369 -374.918459) (xy 347.299788 -374.928638) (xy 347.299788 -375.08688) (xy 347.300211 -375.096066)
			(xy 347.306716 -375.11325) (xy 347.312488 -375.120408) (xy 347.334306 -375.146035) (xy 347.372252 -375.201625)
			(xy 347.403283 -375.261353) (xy 347.426953 -375.324361) (xy 347.442923 -375.389746) (xy 347.450964 -375.456571)
			(xy 347.450961 -375.523878) (xy 347.442914 -375.590702) (xy 347.426938 -375.656086) (xy 347.403263 -375.719091)
			(xy 347.372228 -375.778816) (xy 347.334277 -375.834403) (xy 347.312488 -375.860056) (xy 347.306684 -375.867196)
			(xy 347.300174 -375.88439) (xy 347.299788 -375.893584) (xy 347.299788 -376.386852) (xy 347.300224 -376.396036)
			(xy 347.30672 -376.413221) (xy 347.312488 -376.42038) (xy 347.334279 -376.446029) (xy 347.372226 -376.501617)
			(xy 347.403257 -376.561341) (xy 347.426929 -376.624346) (xy 347.442901 -376.689728) (xy 347.450944 -376.756551)
			(xy 347.450944 -376.823855) (xy 347.450937 -376.823915) (xy 377.128742 -376.823915) (xy 377.128742 -376.756491)
			(xy 377.136817 -376.689553) (xy 377.152853 -376.624064) (xy 377.176618 -376.560967) (xy 377.20777 -376.501171)
			(xy 377.245859 -376.445537) (xy 377.267724 -376.419872) (xy 377.273518 -376.412725) (xy 377.280033 -376.395536)
			(xy 377.280424 -376.386344) (xy 377.280424 -375.894092) (xy 377.280012 -375.884905) (xy 377.273499 -375.867721)
			(xy 377.267724 -375.860564) (xy 377.245891 -375.834873) (xy 377.207799 -375.779243) (xy 377.176646 -375.71945)
			(xy 377.152879 -375.656357) (xy 377.136841 -375.590871) (xy 377.128762 -375.523935) (xy 377.128759 -375.456513)
			(xy 377.136832 -375.389577) (xy 377.152865 -375.324089) (xy 377.176626 -375.260993) (xy 377.207775 -375.201198)
			(xy 377.245861 -375.145565) (xy 377.267724 -375.1199) (xy 377.273506 -375.112744) (xy 377.280029 -375.095562)
			(xy 377.280424 -375.086372) (xy 377.280424 -374.928638) (xy 377.280957 -374.918516) (xy 377.28867 -374.899799)
			(xy 377.302942 -374.885442) (xy 377.321613 -374.877618) (xy 377.331732 -374.877076) (xy 378.048012 -374.877076)
			(xy 378.058164 -374.877511) (xy 378.076912 -374.885306) (xy 378.091234 -374.899698) (xy 378.098938 -374.918484)
			(xy 378.09932 -374.928638) (xy 378.09932 -375.086372) (xy 378.099739 -375.095558) (xy 378.106246 -375.112743)
			(xy 378.11202 -375.1199) (xy 378.133915 -375.14554) (xy 378.172001 -375.201178) (xy 378.203149 -375.260978)
			(xy 378.226911 -375.324078) (xy 378.242943 -375.38957) (xy 378.251016 -375.456511) (xy 378.251014 -375.523937)
			(xy 378.242935 -375.590877) (xy 378.226897 -375.656368) (xy 378.20313 -375.719466) (xy 378.171976 -375.779263)
			(xy 378.133885 -375.834898) (xy 378.11202 -375.860564) (xy 378.106216 -375.867704) (xy 378.099705 -375.884898)
			(xy 378.09932 -375.894092) (xy 378.09932 -376.386344) (xy 378.099704 -376.395534) (xy 378.106235 -376.412718)
			(xy 378.11202 -376.419872) (xy 378.133887 -376.445534) (xy 378.171974 -376.50117) (xy 378.203124 -376.560967)
			(xy 378.226887 -376.624064) (xy 378.242922 -376.689553) (xy 378.250997 -376.756491) (xy 378.250997 -376.756551)
			(xy 381.529061 -376.756551) (xy 381.537105 -376.689729) (xy 381.553076 -376.624347) (xy 381.576747 -376.561343)
			(xy 381.607779 -376.501619) (xy 381.645725 -376.446032) (xy 381.667512 -376.42038) (xy 381.673301 -376.413229)
			(xy 381.67982 -376.396043) (xy 381.680212 -376.386852) (xy 381.680212 -375.893584) (xy 381.679807 -375.884396)
			(xy 381.67329 -375.867212) (xy 381.667512 -375.860056) (xy 381.645756 -375.834378) (xy 381.607808 -375.778794)
			(xy 381.576775 -375.719074) (xy 381.553102 -375.656073) (xy 381.537127 -375.590694) (xy 381.529081 -375.523875)
			(xy 381.529078 -375.456573) (xy 381.537119 -375.389753) (xy 381.553088 -375.324373) (xy 381.576756 -375.26137)
			(xy 381.607784 -375.201647) (xy 381.645727 -375.14606) (xy 381.667512 -375.120408) (xy 381.673289 -375.113249)
			(xy 381.679815 -375.096069) (xy 381.680212 -375.08688) (xy 381.680212 -374.928638) (xy 381.680694 -374.918472)
			(xy 381.688462 -374.899683) (xy 381.702829 -374.885298) (xy 381.721609 -374.877507) (xy 381.731774 -374.877076)
			(xy 382.448054 -374.877076) (xy 382.458227 -374.877502) (xy 382.477028 -374.885279) (xy 382.491416 -374.899665)
			(xy 382.499196 -374.918465) (xy 382.499616 -374.928638) (xy 382.499616 -375.08688) (xy 382.500032 -375.096067)
			(xy 382.506541 -375.113251) (xy 382.512316 -375.120408) (xy 382.534136 -375.146034) (xy 382.572087 -375.201623)
			(xy 382.603122 -375.26135) (xy 382.626795 -375.324358) (xy 382.642767 -375.389744) (xy 382.650809 -375.45657)
			(xy 382.650806 -375.523878) (xy 382.642758 -375.590704) (xy 382.62678 -375.656088) (xy 382.603102 -375.719094)
			(xy 382.572063 -375.778818) (xy 382.534107 -375.834404) (xy 382.512316 -375.860056) (xy 382.506515 -375.867198)
			(xy 382.500002 -375.884391) (xy 382.499616 -375.893584) (xy 382.499616 -376.386852) (xy 382.500045 -376.396037)
			(xy 382.506545 -376.413222) (xy 382.512316 -376.42038) (xy 382.534109 -376.446028) (xy 382.572061 -376.501614)
			(xy 382.603096 -376.561338) (xy 382.626771 -376.624343) (xy 382.642745 -376.689726) (xy 382.650789 -376.75655)
			(xy 382.650789 -376.823856) (xy 382.650782 -376.823915) (xy 385.92883 -376.823915) (xy 385.92883 -376.756491)
			(xy 385.936905 -376.689553) (xy 385.95294 -376.624064) (xy 385.976705 -376.560967) (xy 386.007855 -376.501171)
			(xy 386.045944 -376.445537) (xy 386.067808 -376.419872) (xy 386.0736 -376.412724) (xy 386.080117 -376.395535)
			(xy 386.080508 -376.386344) (xy 386.080508 -375.894092) (xy 386.0801 -375.884905) (xy 386.073584 -375.867721)
			(xy 386.067808 -375.860564) (xy 386.045975 -375.834873) (xy 386.007885 -375.779242) (xy 385.976732 -375.71945)
			(xy 385.952966 -375.656356) (xy 385.936928 -375.59087) (xy 385.92885 -375.523935) (xy 385.928847 -375.456513)
			(xy 385.93692 -375.389577) (xy 385.952952 -375.32409) (xy 385.976713 -375.260994) (xy 386.00786 -375.201199)
			(xy 386.045946 -375.145565) (xy 386.067808 -375.1199) (xy 386.073588 -375.112743) (xy 386.080112 -375.095562)
			(xy 386.080508 -375.086372) (xy 386.080508 -374.928638) (xy 386.081057 -374.918518) (xy 386.088766 -374.899804)
			(xy 386.103033 -374.885447) (xy 386.121699 -374.877621) (xy 386.131816 -374.877076) (xy 386.848096 -374.877076)
			(xy 386.858247 -374.877524) (xy 386.876995 -374.885314) (xy 386.891317 -374.899702) (xy 386.899021 -374.918485)
			(xy 386.899404 -374.928638) (xy 386.899404 -375.086372) (xy 386.899827 -375.095558) (xy 386.906332 -375.112742)
			(xy 386.912104 -375.1199) (xy 386.933999 -375.145539) (xy 386.972087 -375.201178) (xy 387.003236 -375.260978)
			(xy 387.026998 -375.324078) (xy 387.043031 -375.38957) (xy 387.051104 -375.456511) (xy 387.051102 -375.523937)
			(xy 387.043023 -375.590877) (xy 387.026984 -375.656368) (xy 387.003216 -375.719466) (xy 386.972062 -375.779264)
			(xy 386.93397 -375.834899) (xy 386.912104 -375.860564) (xy 386.906298 -375.867703) (xy 386.899789 -375.884898)
			(xy 386.899404 -375.894092) (xy 386.899404 -376.386344) (xy 386.899792 -376.395534) (xy 386.906321 -376.412718)
			(xy 386.912104 -376.419872) (xy 386.933972 -376.445534) (xy 386.97206 -376.501169) (xy 387.00321 -376.560966)
			(xy 387.026974 -376.624063) (xy 387.043009 -376.689552) (xy 387.051085 -376.756491) (xy 387.051084 -376.823855)
			(xy 390.329149 -376.823855) (xy 390.329149 -376.756551) (xy 390.337192 -376.689729) (xy 390.353163 -376.624348)
			(xy 390.376834 -376.561344) (xy 390.407864 -376.50162) (xy 390.44581 -376.446033) (xy 390.467596 -376.42038)
			(xy 390.473383 -376.413228) (xy 390.479904 -376.396043) (xy 390.480296 -376.386852) (xy 390.480296 -375.893584)
			(xy 390.479894 -375.884396) (xy 390.473375 -375.867212) (xy 390.467596 -375.860056) (xy 390.445841 -375.834377)
			(xy 390.407894 -375.778794) (xy 390.376862 -375.719073) (xy 390.353189 -375.656072) (xy 390.337215 -375.590694)
			(xy 390.329169 -375.523875) (xy 390.329166 -375.456573) (xy 390.337207 -375.389754) (xy 390.353175 -375.324374)
			(xy 390.376842 -375.261371) (xy 390.407869 -375.201648) (xy 390.445812 -375.146061) (xy 390.467596 -375.120408)
			(xy 390.473371 -375.113248) (xy 390.479899 -375.096069) (xy 390.480296 -375.08688) (xy 390.480296 -374.928638)
			(xy 390.480864 -374.918488) (xy 390.488618 -374.899728) (xy 390.502961 -374.885363) (xy 390.521709 -374.877579)
			(xy 390.531858 -374.877076) (xy 391.248138 -374.877076) (xy 391.258303 -374.877503) (xy 391.27708 -374.885297)
			(xy 391.291445 -374.899684) (xy 391.299212 -374.918472) (xy 391.2997 -374.928638) (xy 391.2997 -375.08688)
			(xy 391.30012 -375.096066) (xy 391.306627 -375.113251) (xy 391.3124 -375.120408) (xy 391.334218 -375.146035)
			(xy 391.372163 -375.201626) (xy 391.403193 -375.261353) (xy 391.426862 -375.324361) (xy 391.442832 -375.389746)
			(xy 391.450873 -375.456571) (xy 391.45087 -375.523877) (xy 391.442823 -375.590702) (xy 391.426848 -375.656085)
			(xy 391.403173 -375.719091) (xy 391.372139 -375.778816) (xy 391.334188 -375.834403) (xy 391.3124 -375.860056)
			(xy 391.306597 -375.867197) (xy 391.300086 -375.884391) (xy 391.2997 -375.893584) (xy 391.2997 -376.386852)
			(xy 391.300133 -376.396037) (xy 391.306631 -376.413221) (xy 391.3124 -376.42038) (xy 391.33419 -376.446029)
			(xy 391.372137 -376.501617) (xy 391.403168 -376.561342) (xy 391.426838 -376.624346) (xy 391.44281 -376.689728)
			(xy 391.450853 -376.756551) (xy 391.450853 -376.823855) (xy 391.450846 -376.823915) (xy 421.128651 -376.823915)
			(xy 421.128651 -376.756491) (xy 421.136727 -376.689552) (xy 421.152763 -376.624063) (xy 421.176528 -376.560966)
			(xy 421.20768 -376.50117) (xy 421.245771 -376.445537) (xy 421.267636 -376.419872) (xy 421.273432 -376.412726)
			(xy 421.279946 -376.395536) (xy 421.280336 -376.386344) (xy 421.280336 -375.894092) (xy 421.279922 -375.884905)
			(xy 421.27341 -375.867721) (xy 421.267636 -375.860564) (xy 421.245802 -375.834873) (xy 421.20771 -375.779243)
			(xy 421.176556 -375.719451) (xy 421.152788 -375.656357) (xy 421.13675 -375.590871) (xy 421.128671 -375.523935)
			(xy 421.128668 -375.456513) (xy 421.136741 -375.389576) (xy 421.152774 -375.324089) (xy 421.176536 -375.260993)
			(xy 421.207685 -375.201198) (xy 421.245773 -375.145565) (xy 421.267636 -375.1199) (xy 421.27342 -375.112746)
			(xy 421.279941 -375.095562) (xy 421.280336 -375.086372) (xy 421.280336 -374.928638) (xy 421.280858 -374.918514)
			(xy 421.288572 -374.899795) (xy 421.302848 -374.885437) (xy 421.321523 -374.877616) (xy 421.331644 -374.877076)
			(xy 422.047924 -374.877076) (xy 422.058031 -374.877565) (xy 422.076706 -374.885306) (xy 422.090999 -374.899601)
			(xy 422.098737 -374.918277) (xy 422.099232 -374.928384) (xy 422.099232 -375.086372) (xy 422.099671 -375.095556)
			(xy 422.106166 -375.11274) (xy 422.111932 -375.1199) (xy 422.133826 -375.14554) (xy 422.171912 -375.201179)
			(xy 422.203059 -375.260979) (xy 422.22682 -375.324079) (xy 422.242853 -375.389571) (xy 422.250926 -375.456511)
			(xy 422.250923 -375.523937) (xy 422.242844 -375.590877) (xy 422.226806 -375.656367) (xy 422.20304 -375.719465)
			(xy 422.171887 -375.779263) (xy 422.133797 -375.834898) (xy 422.111932 -375.860564) (xy 422.106117 -375.867696)
			(xy 422.099615 -375.884897) (xy 422.099232 -375.894092) (xy 422.099232 -376.386344) (xy 422.099636 -376.395532)
			(xy 422.106156 -376.412715) (xy 422.111932 -376.419872) (xy 422.133799 -376.445535) (xy 422.171885 -376.50117)
			(xy 422.203034 -376.560967) (xy 422.226797 -376.624064) (xy 422.242831 -376.689553) (xy 422.250906 -376.756491)
			(xy 422.250906 -376.756551) (xy 425.52897 -376.756551) (xy 425.537014 -376.689729) (xy 425.552986 -376.624347)
			(xy 425.576658 -376.561343) (xy 425.607689 -376.501619) (xy 425.645637 -376.446032) (xy 425.667424 -376.42038)
			(xy 425.673214 -376.413231) (xy 425.679732 -376.396043) (xy 425.680124 -376.386852) (xy 425.680124 -375.893584)
			(xy 425.679716 -375.884397) (xy 425.6732 -375.867213) (xy 425.667424 -375.860056) (xy 425.645668 -375.834378)
			(xy 425.60772 -375.778795) (xy 425.576686 -375.719074) (xy 425.553012 -375.656073) (xy 425.537037 -375.590695)
			(xy 425.528991 -375.523875) (xy 425.528988 -375.456573) (xy 425.537029 -375.389753) (xy 425.552998 -375.324373)
			(xy 425.576666 -375.26137) (xy 425.607695 -375.201647) (xy 425.645639 -375.146061) (xy 425.667424 -375.120408)
			(xy 425.673202 -375.11325) (xy 425.679727 -375.096069) (xy 425.680124 -375.08688) (xy 425.680124 -374.928638)
			(xy 425.680595 -374.918471) (xy 425.688365 -374.899679) (xy 425.702736 -374.885294) (xy 425.721519 -374.877505)
			(xy 425.731686 -374.877076) (xy 426.447966 -374.877076) (xy 426.45814 -374.877493) (xy 426.476941 -374.885274)
			(xy 426.491329 -374.899662) (xy 426.499108 -374.918464) (xy 426.499528 -374.928638) (xy 426.499528 -375.08688)
			(xy 426.499941 -375.096067) (xy 426.506452 -375.113252) (xy 426.512228 -375.120408) (xy 426.534048 -375.146034)
			(xy 426.571998 -375.201623) (xy 426.603032 -375.26135) (xy 426.626705 -375.324358) (xy 426.642676 -375.389744)
			(xy 426.650718 -375.45657) (xy 426.650716 -375.523878) (xy 426.642668 -375.590704) (xy 426.62669 -375.656088)
			(xy 426.603013 -375.719094) (xy 426.571974 -375.778818) (xy 426.534019 -375.834404) (xy 426.512228 -375.860056)
			(xy 426.506416 -375.86719) (xy 426.499913 -375.884389) (xy 426.499528 -375.893584) (xy 426.499528 -376.386852)
			(xy 426.499955 -376.396037) (xy 426.506456 -376.413222) (xy 426.512228 -376.42038) (xy 426.534021 -376.446029)
			(xy 426.571971 -376.501615) (xy 426.603006 -376.561338) (xy 426.62668 -376.624344) (xy 426.642654 -376.689727)
			(xy 426.650698 -376.75655) (xy 426.650698 -376.823856) (xy 426.650691 -376.823915) (xy 429.928739 -376.823915)
			(xy 429.928739 -376.756491) (xy 429.936814 -376.689553) (xy 429.95285 -376.624064) (xy 429.976615 -376.560967)
			(xy 430.007766 -376.501171) (xy 430.045856 -376.445537) (xy 430.06772 -376.419872) (xy 430.073513 -376.412725)
			(xy 430.080029 -376.395536) (xy 430.08042 -376.386344) (xy 430.08042 -375.894092) (xy 430.080009 -375.884905)
			(xy 430.073496 -375.867721) (xy 430.06772 -375.860564) (xy 430.045887 -375.834873) (xy 430.007796 -375.779243)
			(xy 429.976643 -375.71945) (xy 429.952876 -375.656357) (xy 429.936837 -375.590871) (xy 429.928759 -375.523935)
			(xy 429.928756 -375.456513) (xy 429.936829 -375.389577) (xy 429.952861 -375.324089) (xy 429.976623 -375.260994)
			(xy 430.007771 -375.201199) (xy 430.045857 -375.145565) (xy 430.06772 -375.1199) (xy 430.073501 -375.112744)
			(xy 430.080024 -375.095562) (xy 430.08042 -375.086372) (xy 430.08042 -374.928638) (xy 430.080957 -374.918516)
			(xy 430.088669 -374.8998) (xy 430.10294 -374.885443) (xy 430.121609 -374.877619) (xy 430.131728 -374.877076)
			(xy 430.848008 -374.877076) (xy 430.85816 -374.877515) (xy 430.876907 -374.885308) (xy 430.89123 -374.899699)
			(xy 430.898933 -374.918484) (xy 430.899316 -374.928638) (xy 430.899316 -375.086372) (xy 430.899736 -375.095558)
			(xy 430.906242 -375.112743) (xy 430.912016 -375.1199) (xy 430.933911 -375.14554) (xy 430.971998 -375.201178)
			(xy 431.003146 -375.260978) (xy 431.026908 -375.324078) (xy 431.04294 -375.38957) (xy 431.051013 -375.456511)
			(xy 431.051011 -375.523937) (xy 431.042932 -375.590877) (xy 431.026893 -375.656368) (xy 431.003126 -375.719466)
			(xy 430.971973 -375.779263) (xy 430.933881 -375.834898) (xy 430.912016 -375.860564) (xy 430.906212 -375.867704)
			(xy 430.899701 -375.884898) (xy 430.899316 -375.894092) (xy 430.899316 -376.386344) (xy 430.899701 -376.395534)
			(xy 430.906232 -376.412718) (xy 430.912016 -376.419872) (xy 430.933883 -376.445534) (xy 430.971971 -376.50117)
			(xy 431.003121 -376.560966) (xy 431.026884 -376.624064) (xy 431.042918 -376.689553) (xy 431.050994 -376.756491)
			(xy 431.050994 -376.756551) (xy 434.329058 -376.756551) (xy 434.337101 -376.689729) (xy 434.353073 -376.624348)
			(xy 434.376744 -376.561343) (xy 434.407775 -376.50162) (xy 434.445721 -376.446033) (xy 434.467508 -376.42038)
			(xy 434.473296 -376.413229) (xy 434.479816 -376.396043) (xy 434.480208 -376.386852) (xy 434.480208 -375.893584)
			(xy 434.479804 -375.884396) (xy 434.473286 -375.867212) (xy 434.467508 -375.860056) (xy 434.445753 -375.834378)
			(xy 434.407805 -375.778794) (xy 434.376772 -375.719074) (xy 434.353099 -375.656073) (xy 434.337124 -375.590694)
			(xy 434.329078 -375.523875) (xy 434.329075 -375.456573) (xy 434.337116 -375.389753) (xy 434.353084 -375.324373)
			(xy 434.376752 -375.26137) (xy 434.40778 -375.201647) (xy 434.445723 -375.146061) (xy 434.467508 -375.120408)
			(xy 434.473285 -375.113249) (xy 434.479811 -375.096069) (xy 434.480208 -375.08688) (xy 434.480208 -374.928638)
			(xy 434.480694 -374.918473) (xy 434.488461 -374.899684) (xy 434.502827 -374.885299) (xy 434.521605 -374.877508)
			(xy 434.53177 -374.877076) (xy 435.24805 -374.877076) (xy 435.258223 -374.877506) (xy 435.277024 -374.885281)
			(xy 435.291412 -374.899666) (xy 435.299192 -374.918465) (xy 435.299612 -374.928638) (xy 435.299612 -375.08688)
			(xy 435.300029 -375.096067) (xy 435.306538 -375.113251) (xy 435.312312 -375.120408) (xy 435.334133 -375.146034)
			(xy 435.372084 -375.201623) (xy 435.403118 -375.26135) (xy 435.426791 -375.324358) (xy 435.442764 -375.389744)
			(xy 435.450806 -375.45657) (xy 435.450803 -375.523878) (xy 435.442755 -375.590704) (xy 435.426777 -375.656088)
			(xy 435.403099 -375.719094) (xy 435.372059 -375.778819) (xy 435.334103 -375.834404) (xy 435.312312 -375.860056)
			(xy 435.306511 -375.867198) (xy 435.299998 -375.884391) (xy 435.299612 -375.893584) (xy 435.299612 -376.386852)
			(xy 435.300042 -376.396037) (xy 435.306542 -376.413222) (xy 435.312312 -376.42038) (xy 435.334105 -376.446028)
			(xy 435.372057 -376.501614) (xy 435.403093 -376.561338) (xy 435.426768 -376.624343) (xy 435.442742 -376.689726)
			(xy 435.450786 -376.75655) (xy 435.450786 -376.823856) (xy 435.442741 -376.89068) (xy 435.426766 -376.956063)
			(xy 435.40309 -377.019068) (xy 435.372054 -377.078791) (xy 435.334101 -377.134376) (xy 435.312312 -377.160028)
			(xy 435.306522 -377.167178) (xy 435.300003 -377.184365) (xy 435.299612 -377.193556) (xy 435.299612 -377.35129)
			(xy 435.299227 -377.361467) (xy 435.291436 -377.380271) (xy 435.277038 -377.394658) (xy 435.258228 -377.402435)
			(xy 435.24805 -377.402852) (xy 434.53177 -377.402852) (xy 434.521609 -377.402391) (xy 434.502837 -377.394605)
			(xy 434.488473 -377.380229) (xy 434.480701 -377.361451) (xy 434.480208 -377.35129) (xy 434.480208 -377.193556)
			(xy 434.479817 -377.184367) (xy 434.47329 -377.167183) (xy 434.467508 -377.160028) (xy 434.445725 -377.134372)
			(xy 434.407778 -377.078786) (xy 434.376746 -377.019062) (xy 434.353075 -376.956058) (xy 434.337103 -376.890677)
			(xy 434.329059 -376.823855) (xy 434.329058 -376.756551) (xy 431.050994 -376.756551) (xy 431.050993 -376.823915)
			(xy 431.042917 -376.890853) (xy 431.026882 -376.956342) (xy 431.003118 -377.019439) (xy 430.971968 -377.079236)
			(xy 430.93388 -377.13487) (xy 430.912016 -377.160536) (xy 430.906223 -377.167684) (xy 430.899706 -377.184872)
			(xy 430.899316 -377.194064) (xy 430.899316 -377.35129) (xy 430.898864 -377.361421) (xy 430.891131 -377.380151)
			(xy 430.876834 -377.394509) (xy 430.858137 -377.402321) (xy 430.848008 -377.402852) (xy 430.131728 -377.402852)
			(xy 430.121582 -377.402357) (xy 430.10284 -377.39458) (xy 430.088518 -377.380207) (xy 430.080808 -377.361437)
			(xy 430.08042 -377.35129) (xy 430.08042 -377.194064) (xy 430.080023 -377.184876) (xy 430.0735 -377.167692)
			(xy 430.06772 -377.160536) (xy 430.045859 -377.134868) (xy 430.007769 -377.079234) (xy 429.976617 -377.019439)
			(xy 429.952852 -376.956342) (xy 429.936815 -376.890853) (xy 429.928739 -376.823915) (xy 426.650691 -376.823915)
			(xy 426.642653 -376.890679) (xy 426.626679 -376.956062) (xy 426.603004 -377.019067) (xy 426.571968 -377.07879)
			(xy 426.534017 -377.134376) (xy 426.512228 -377.160028) (xy 426.506428 -377.167171) (xy 426.499918 -377.184363)
			(xy 426.499528 -377.193556) (xy 426.499528 -377.35129) (xy 426.499127 -377.361465) (xy 426.491339 -377.380266)
			(xy 426.476946 -377.394653) (xy 426.458141 -377.402432) (xy 426.447966 -377.402852) (xy 425.731686 -377.402852)
			(xy 425.721526 -377.402378) (xy 425.702755 -377.394597) (xy 425.68839 -377.380225) (xy 425.680618 -377.36145)
			(xy 425.680124 -377.35129) (xy 425.680124 -377.193556) (xy 425.67973 -377.184367) (xy 425.673204 -377.167183)
			(xy 425.667424 -377.160028) (xy 425.645641 -377.134372) (xy 425.607693 -377.078786) (xy 425.57666 -377.019063)
			(xy 425.552988 -376.956059) (xy 425.537015 -376.890677) (xy 425.528971 -376.823855) (xy 425.52897 -376.756551)
			(xy 422.250906 -376.756551) (xy 422.250905 -376.823915) (xy 422.24283 -376.890853) (xy 422.226795 -376.956342)
			(xy 422.203032 -377.019438) (xy 422.171882 -377.079235) (xy 422.133795 -377.13487) (xy 422.111932 -377.160536)
			(xy 422.106129 -377.167677) (xy 422.09962 -377.184871) (xy 422.099232 -377.194064) (xy 422.099232 -377.35129)
			(xy 422.098764 -377.36142) (xy 422.091035 -377.380146) (xy 422.076742 -377.394503) (xy 422.058051 -377.402318)
			(xy 422.047924 -377.402852) (xy 421.331644 -377.402852) (xy 421.321544 -377.40228) (xy 421.302877 -377.394567)
			(xy 421.288583 -377.380297) (xy 421.280837 -377.361643) (xy 421.280336 -377.351544) (xy 421.280336 -377.194064)
			(xy 421.279935 -377.184876) (xy 421.273414 -377.167692) (xy 421.267636 -377.160536) (xy 421.245775 -377.134868)
			(xy 421.207684 -377.079235) (xy 421.176531 -377.019439) (xy 421.152765 -376.956343) (xy 421.136728 -376.890854)
			(xy 421.128651 -376.823915) (xy 391.450846 -376.823915) (xy 391.442809 -376.890678) (xy 391.426837 -376.956059)
			(xy 391.403165 -377.019064) (xy 391.372134 -377.078788) (xy 391.334187 -377.134375) (xy 391.3124 -377.160028)
			(xy 391.306609 -377.167177) (xy 391.300091 -377.184365) (xy 391.2997 -377.193556) (xy 391.2997 -377.35129)
			(xy 391.299159 -377.361442) (xy 391.291395 -377.380204) (xy 391.277044 -377.394568) (xy 391.25829 -377.40235)
			(xy 391.248138 -377.402852) (xy 390.531858 -377.402852) (xy 390.521696 -377.402401) (xy 390.502924 -377.394611)
			(xy 390.48856 -377.380232) (xy 390.480789 -377.361452) (xy 390.480296 -377.35129) (xy 390.480296 -377.193556)
			(xy 390.479908 -377.184366) (xy 390.473379 -377.167182) (xy 390.467596 -377.160028) (xy 390.445814 -377.134372)
			(xy 390.407867 -377.078785) (xy 390.376836 -377.019062) (xy 390.353165 -376.956058) (xy 390.337193 -376.890676)
			(xy 390.329149 -376.823855) (xy 387.051084 -376.823855) (xy 387.051084 -376.823915) (xy 387.043008 -376.890853)
			(xy 387.026972 -376.956343) (xy 387.003208 -377.01944) (xy 386.972057 -377.079236) (xy 386.933968 -377.134871)
			(xy 386.912104 -377.160536) (xy 386.90631 -377.167683) (xy 386.899794 -377.184872) (xy 386.899404 -377.194064)
			(xy 386.899404 -377.35129) (xy 386.898867 -377.361411) (xy 386.89115 -377.380123) (xy 386.87688 -377.394478)
			(xy 386.858214 -377.402306) (xy 386.848096 -377.402852) (xy 386.131816 -377.402852) (xy 386.121669 -377.402366)
			(xy 386.102927 -377.394586) (xy 386.088605 -377.380209) (xy 386.080896 -377.361438) (xy 386.080508 -377.35129)
			(xy 386.080508 -377.194064) (xy 386.080114 -377.184875) (xy 386.073589 -377.167691) (xy 386.067808 -377.160536)
			(xy 386.045948 -377.134868) (xy 386.007858 -377.079234) (xy 385.976707 -377.019438) (xy 385.952942 -376.956342)
			(xy 385.936906 -376.890853) (xy 385.92883 -376.823915) (xy 382.650782 -376.823915) (xy 382.642744 -376.89068)
			(xy 382.626769 -376.956063) (xy 382.603094 -377.019068) (xy 382.572058 -377.078791) (xy 382.534105 -377.134376)
			(xy 382.512316 -377.160028) (xy 382.506527 -377.167179) (xy 382.500007 -377.184365) (xy 382.499616 -377.193556)
			(xy 382.499616 -377.35129) (xy 382.499227 -377.361467) (xy 382.491437 -377.38027) (xy 382.47704 -377.394657)
			(xy 382.458231 -377.402434) (xy 382.448054 -377.402852) (xy 381.731774 -377.402852) (xy 381.721613 -377.402388)
			(xy 381.702842 -377.394603) (xy 381.688477 -377.380228) (xy 381.680705 -377.361451) (xy 381.680212 -377.35129)
			(xy 381.680212 -377.193556) (xy 381.67982 -377.184367) (xy 381.673294 -377.167183) (xy 381.667512 -377.160028)
			(xy 381.645729 -377.134372) (xy 381.607782 -377.078786) (xy 381.57675 -377.019062) (xy 381.553078 -376.956058)
			(xy 381.537106 -376.890677) (xy 381.529062 -376.823855) (xy 381.529061 -376.756551) (xy 378.250997 -376.756551)
			(xy 378.250996 -376.823915) (xy 378.24292 -376.890853) (xy 378.226885 -376.956342) (xy 378.203121 -377.019439)
			(xy 378.171971 -377.079235) (xy 378.133884 -377.13487) (xy 378.11202 -377.160536) (xy 378.106228 -377.167685)
			(xy 378.09971 -377.184872) (xy 378.09932 -377.194064) (xy 378.09932 -377.35129) (xy 378.098864 -377.361421)
			(xy 378.091132 -377.38015) (xy 378.076836 -377.394508) (xy 378.058141 -377.40232) (xy 378.048012 -377.402852)
			(xy 377.331732 -377.402852) (xy 377.321586 -377.402353) (xy 377.302845 -377.394578) (xy 377.288522 -377.380206)
			(xy 377.280812 -377.361437) (xy 377.280424 -377.35129) (xy 377.280424 -377.194064) (xy 377.280026 -377.184876)
			(xy 377.273503 -377.167692) (xy 377.267724 -377.160536) (xy 377.245863 -377.134868) (xy 377.207773 -377.079234)
			(xy 377.17662 -377.019439) (xy 377.152855 -376.956342) (xy 377.136819 -376.890853) (xy 377.128742 -376.823915)
			(xy 347.450937 -376.823915) (xy 347.4429 -376.890678) (xy 347.426927 -376.95606) (xy 347.403255 -377.019065)
			(xy 347.372223 -377.078788) (xy 347.334275 -377.134376) (xy 347.312488 -377.160028) (xy 347.306696 -377.167176)
			(xy 347.300179 -377.184364) (xy 347.299788 -377.193556) (xy 347.299788 -377.35129) (xy 347.299259 -377.361444)
			(xy 347.291493 -377.380208) (xy 347.277138 -377.394573) (xy 347.25838 -377.402352) (xy 347.248226 -377.402852)
			(xy 346.531946 -377.402852) (xy 346.521776 -377.402398) (xy 346.502981 -377.394627) (xy 346.488594 -377.38025)
			(xy 346.480809 -377.36146) (xy 346.480384 -377.35129) (xy 346.480384 -377.193556) (xy 346.479999 -377.184366)
			(xy 346.473468 -377.167182) (xy 346.467684 -377.160028) (xy 346.445899 -377.134373) (xy 346.407947 -377.078788)
			(xy 346.376911 -377.019065) (xy 346.353236 -376.956061) (xy 346.337262 -376.890679) (xy 346.329216 -376.823856)
			(xy 343.051175 -376.823856) (xy 343.051175 -376.823915) (xy 343.043099 -376.890854) (xy 343.027063 -376.956343)
			(xy 343.003298 -377.01944) (xy 342.972146 -377.079236) (xy 342.934056 -377.134871) (xy 342.912192 -377.160536)
			(xy 342.906397 -377.167682) (xy 342.899882 -377.184872) (xy 342.899492 -377.194064) (xy 342.899492 -377.35129)
			(xy 342.898966 -377.361412) (xy 342.891248 -377.380127) (xy 342.876974 -377.394483) (xy 342.858303 -377.402308)
			(xy 342.848184 -377.402852) (xy 342.131904 -377.402852) (xy 342.121757 -377.402376) (xy 342.103014 -377.394592)
			(xy 342.088693 -377.380212) (xy 342.080984 -377.361439) (xy 342.080596 -377.35129) (xy 342.080596 -377.194064)
			(xy 342.080204 -377.184875) (xy 342.073678 -377.167691) (xy 342.067896 -377.160536) (xy 342.046036 -377.134867)
			(xy 342.007948 -377.079233) (xy 341.976797 -377.019438) (xy 341.953033 -376.956341) (xy 341.936997 -376.890852)
			(xy 341.928921 -376.823915) (xy 338.650849 -376.823915) (xy 338.642812 -376.890677) (xy 338.62684 -376.956059)
			(xy 338.603168 -377.019064) (xy 338.572137 -377.078788) (xy 338.534191 -377.134375) (xy 338.512404 -377.160028)
			(xy 338.506614 -377.167178) (xy 338.500095 -377.184365) (xy 338.499704 -377.193556) (xy 338.499704 -377.35129)
			(xy 338.49916 -377.361442) (xy 338.491396 -377.380203) (xy 338.477047 -377.394567) (xy 338.458293 -377.402349)
			(xy 338.448142 -377.402852) (xy 337.731862 -377.402852) (xy 337.721701 -377.402397) (xy 337.702929 -377.394609)
			(xy 337.688564 -377.380231) (xy 337.680793 -377.361452) (xy 337.6803 -377.35129) (xy 337.6803 -377.193556)
			(xy 337.679911 -377.184367) (xy 337.673383 -377.167182) (xy 337.6676 -377.160028) (xy 337.645817 -377.134372)
			(xy 337.607871 -377.078785) (xy 337.57684 -377.019062) (xy 337.553168 -376.956058) (xy 337.537196 -376.890677)
			(xy 337.529152 -376.823855) (xy 334.251087 -376.823855) (xy 334.251087 -376.823915) (xy 334.243011 -376.890853)
			(xy 334.226976 -376.956342) (xy 334.203211 -377.019439) (xy 334.172061 -377.079236) (xy 334.133972 -377.134871)
			(xy 334.112108 -377.160536) (xy 334.106315 -377.167684) (xy 334.099798 -377.184872) (xy 334.099408 -377.194064)
			(xy 334.099408 -377.35129) (xy 334.098867 -377.36141) (xy 334.091151 -377.380122) (xy 334.076882 -377.394477)
			(xy 334.058217 -377.402305) (xy 334.0481 -377.402852) (xy 333.33182 -377.402852) (xy 333.321674 -377.402363)
			(xy 333.302932 -377.394584) (xy 333.288609 -377.380209) (xy 333.2809 -377.361438) (xy 333.280512 -377.35129)
			(xy 333.280512 -377.194064) (xy 333.280117 -377.184875) (xy 333.273592 -377.167691) (xy 333.267812 -377.160536)
			(xy 333.245952 -377.134868) (xy 333.207862 -377.079234) (xy 333.17671 -377.019438) (xy 333.152945 -376.956342)
			(xy 333.136909 -376.890853) (xy 333.128833 -376.823915) (xy 303.451057 -376.823915) (xy 303.44298 -376.890854)
			(xy 303.426944 -376.956344) (xy 303.403178 -377.019441) (xy 303.372025 -377.079237) (xy 303.333933 -377.134871)
			(xy 303.312068 -377.160536) (xy 303.30627 -377.16768) (xy 303.299757 -377.184871) (xy 303.299368 -377.194064)
			(xy 303.299368 -377.35129) (xy 303.298865 -377.361415) (xy 303.291142 -377.380135) (xy 303.276861 -377.394491)
			(xy 303.258182 -377.402312) (xy 303.24806 -377.402852) (xy 302.53178 -377.402852) (xy 302.521631 -377.402396)
			(xy 302.502888 -377.394604) (xy 302.488567 -377.380218) (xy 302.480859 -377.361441) (xy 302.480472 -377.35129)
			(xy 302.480472 -377.194064) (xy 302.480085 -377.184874) (xy 302.473556 -377.16769) (xy 302.467772 -377.160536)
			(xy 302.445913 -377.134867) (xy 302.407826 -377.079232) (xy 302.376677 -377.019436) (xy 302.352913 -376.95634)
			(xy 302.336879 -376.890852) (xy 302.328803 -376.823914) (xy 302.328802 -376.756492) (xy 299.050731 -376.756492)
			(xy 299.050738 -376.756551) (xy 299.050738 -376.823856) (xy 299.042693 -376.890678) (xy 299.026721 -376.95606)
			(xy 299.003048 -377.019065) (xy 298.972016 -377.078789) (xy 298.934067 -377.134376) (xy 298.91228 -377.160028)
			(xy 298.906487 -377.167175) (xy 298.899971 -377.184364) (xy 298.89958 -377.193556) (xy 298.89958 -377.35129)
			(xy 298.899059 -377.361445) (xy 298.891291 -377.38021) (xy 298.876934 -377.394575) (xy 298.858173 -377.402353)
			(xy 298.848018 -377.402852) (xy 298.131738 -377.402852) (xy 298.121568 -377.402405) (xy 298.102772 -377.39463)
			(xy 298.088385 -377.380252) (xy 298.080601 -377.36146) (xy 298.080176 -377.35129) (xy 298.080176 -377.193556)
			(xy 298.079792 -377.184366) (xy 298.073261 -377.167182) (xy 298.067476 -377.160028) (xy 298.045691 -377.134373)
			(xy 298.00774 -377.078788) (xy 297.976704 -377.019065) (xy 297.95303 -376.956061) (xy 297.937055 -376.890679)
			(xy 297.92901 -376.823856) (xy 294.650969 -376.823856) (xy 294.650969 -376.823915) (xy 294.642893 -376.890854)
			(xy 294.626856 -376.956343) (xy 294.603091 -377.019441) (xy 294.571939 -377.079237) (xy 294.533849 -377.134871)
			(xy 294.511984 -377.160536) (xy 294.506188 -377.167681) (xy 294.499673 -377.184872) (xy 294.499284 -377.194064)
			(xy 294.499284 -377.35129) (xy 294.498766 -377.361413) (xy 294.491046 -377.38013) (xy 294.47677 -377.394485)
			(xy 294.458096 -377.402309) (xy 294.447976 -377.402852) (xy 293.731696 -377.402852) (xy 293.721593 -377.402319)
			(xy 293.702925 -377.39459) (xy 293.688632 -377.380308) (xy 293.680889 -377.361646) (xy 293.680388 -377.351544)
			(xy 293.680388 -377.194064) (xy 293.679998 -377.184875) (xy 293.673471 -377.16769) (xy 293.667688 -377.160536)
			(xy 293.645828 -377.134867) (xy 293.60774 -377.079233) (xy 293.57659 -377.019437) (xy 293.552826 -376.956341)
			(xy 293.536791 -376.890852) (xy 293.528715 -376.823915) (xy 290.250643 -376.823915) (xy 290.242606 -376.890678)
			(xy 290.226633 -376.95606) (xy 290.202962 -377.019064) (xy 290.17193 -377.078788) (xy 290.133983 -377.134375)
			(xy 290.112196 -377.160028) (xy 290.106405 -377.167177) (xy 290.099887 -377.184365) (xy 290.099496 -377.193556)
			(xy 290.099496 -377.35129) (xy 290.098959 -377.361443) (xy 290.091194 -377.380205) (xy 290.076842 -377.39457)
			(xy 290.058087 -377.402351) (xy 290.047934 -377.402852) (xy 289.331654 -377.402852) (xy 289.321492 -377.402404)
			(xy 289.30272 -377.394613) (xy 289.288356 -377.380233) (xy 289.280585 -377.361452) (xy 289.280092 -377.35129)
			(xy 289.280092 -377.193556) (xy 289.279705 -377.184366) (xy 289.273176 -377.167182) (xy 289.267392 -377.160028)
			(xy 289.245607 -377.134373) (xy 289.207654 -377.078788) (xy 289.176618 -377.019066) (xy 289.152942 -376.956061)
			(xy 289.136968 -376.890679) (xy 289.128922 -376.823856) (xy 273.068299 -376.823856) (xy 273.100384 -376.843252)
			(xy 273.210304 -376.919124) (xy 273.315441 -377.001494) (xy 273.415414 -377.090062) (xy 273.509856 -377.184504)
			(xy 273.598424 -377.284477) (xy 273.680794 -377.389614) (xy 273.756666 -377.499534) (xy 273.825762 -377.613833)
			(xy 273.887832 -377.732096) (xy 273.942647 -377.853891) (xy 273.990009 -377.978774) (xy 274.029744 -378.106288)
			(xy 274.061707 -378.235969) (xy 274.077801 -378.323794) (xy 286.928742 -378.323794) (xy 286.928744 -378.256367)
			(xy 286.936824 -378.189426) (xy 286.952863 -378.123935) (xy 286.976633 -378.060837) (xy 287.007789 -378.00104)
			(xy 287.045885 -377.945406) (xy 287.067752 -377.919742) (xy 287.073562 -377.912607) (xy 287.080067 -377.895408)
			(xy 287.080452 -377.886214) (xy 287.080452 -377.728734) (xy 287.080955 -377.718608) (xy 287.088674 -377.699885)
			(xy 287.102955 -377.685528) (xy 287.121637 -377.677709) (xy 287.13176 -377.677172) (xy 287.84804 -377.677172)
			(xy 287.858148 -377.677652) (xy 287.876822 -377.685397) (xy 287.891114 -377.699695) (xy 287.898852 -377.718372)
			(xy 287.899348 -377.72848) (xy 287.899348 -377.886214) (xy 287.899763 -377.8954) (xy 287.906275 -377.912584)
			(xy 287.912048 -377.919742) (xy 287.933888 -377.945427) (xy 287.971981 -378.001058) (xy 288.003136 -378.060851)
			(xy 288.026904 -378.123945) (xy 288.042943 -378.189432) (xy 288.051021 -378.256369) (xy 288.051024 -378.323734)
			(xy 291.329062 -378.323734) (xy 291.329064 -378.256427) (xy 291.337111 -378.189602) (xy 291.353086 -378.124219)
			(xy 291.376762 -378.061213) (xy 291.407799 -378.001489) (xy 291.445751 -377.945902) (xy 291.46754 -377.92025)
			(xy 291.473345 -377.913111) (xy 291.479854 -377.895916) (xy 291.48024 -377.886722) (xy 291.48024 -377.728734)
			(xy 291.480692 -377.718564) (xy 291.488466 -377.69977) (xy 291.502843 -377.685384) (xy 291.521633 -377.677598)
			(xy 291.531802 -377.677172) (xy 292.248082 -377.677172) (xy 292.258257 -377.677579) (xy 292.277058 -377.685365)
			(xy 292.291444 -377.699756) (xy 292.299224 -377.718559) (xy 292.299644 -377.728734) (xy 292.299644 -377.886722)
			(xy 292.300056 -377.895909) (xy 292.30657 -377.913092) (xy 292.312344 -377.92025) (xy 292.334107 -377.945923)
			(xy 292.372057 -378.001506) (xy 292.403093 -378.061227) (xy 292.426768 -378.124228) (xy 292.442743 -378.189608)
			(xy 292.450789 -378.256429) (xy 292.450792 -378.323732) (xy 292.450785 -378.323794) (xy 295.72883 -378.323794)
			(xy 295.728832 -378.256367) (xy 295.736911 -378.189427) (xy 295.752951 -378.123936) (xy 295.776719 -378.060837)
			(xy 295.807875 -378.001041) (xy 295.845969 -377.945407) (xy 295.867836 -377.919742) (xy 295.873644 -377.912605)
			(xy 295.880151 -377.895408) (xy 295.880536 -377.886214) (xy 295.880536 -377.728734) (xy 295.881055 -377.71861)
			(xy 295.88877 -377.69989) (xy 295.903047 -377.685533) (xy 295.921723 -377.677712) (xy 295.931844 -377.677172)
			(xy 296.648124 -377.677172) (xy 296.658276 -377.677601) (xy 296.677024 -377.6854) (xy 296.691345 -377.699793)
			(xy 296.699049 -377.71858) (xy 296.699432 -377.728734) (xy 296.699432 -377.886214) (xy 296.699851 -377.8954)
			(xy 296.70636 -377.912584) (xy 296.712132 -377.919742) (xy 296.733969 -377.945429) (xy 296.772057 -378.001061)
			(xy 296.803207 -378.060855) (xy 296.826971 -378.123949) (xy 296.843007 -378.189435) (xy 296.851085 -378.25637)
			(xy 296.851087 -378.323791) (xy 296.851087 -378.323794) (xy 300.128621 -378.323794) (xy 300.128623 -378.256367)
			(xy 300.136702 -378.189427) (xy 300.152741 -378.123936) (xy 300.176509 -378.060838) (xy 300.207664 -378.001041)
			(xy 300.245758 -377.945407) (xy 300.267624 -377.919742) (xy 300.27343 -377.912604) (xy 300.279938 -377.895408)
			(xy 300.280324 -377.886214) (xy 300.280324 -377.728734) (xy 300.280854 -377.718611) (xy 300.288568 -377.699894)
			(xy 300.302841 -377.685537) (xy 300.321512 -377.677714) (xy 300.331632 -377.677172) (xy 301.047912 -377.677172)
			(xy 301.058063 -377.677611) (xy 301.076811 -377.685405) (xy 301.091133 -377.699796) (xy 301.098837 -377.718581)
			(xy 301.09922 -377.728734) (xy 301.09922 -377.886214) (xy 301.099619 -377.895402) (xy 301.10614 -377.912587)
			(xy 301.11192 -377.919742) (xy 301.133758 -377.945429) (xy 301.171846 -378.001061) (xy 301.202997 -378.060854)
			(xy 301.226761 -378.123948) (xy 301.242798 -378.189434) (xy 301.250876 -378.25637) (xy 301.250878 -378.323734)
			(xy 330.92918 -378.323734) (xy 330.929182 -378.256427) (xy 330.937229 -378.189602) (xy 330.953206 -378.124218)
			(xy 330.976882 -378.061212) (xy 331.00792 -378.001488) (xy 331.045874 -377.945902) (xy 331.067664 -377.92025)
			(xy 331.073472 -377.913113) (xy 331.079978 -377.895916) (xy 331.080364 -377.886722) (xy 331.080364 -377.728734)
			(xy 331.080792 -377.718561) (xy 331.088571 -377.699763) (xy 331.102956 -377.685376) (xy 331.121753 -377.677594)
			(xy 331.131926 -377.677172) (xy 331.848206 -377.677172) (xy 331.858382 -377.67756) (xy 331.877184 -377.685353)
			(xy 331.891569 -377.69975) (xy 331.899348 -377.718557) (xy 331.899768 -377.728734) (xy 331.899768 -377.886722)
			(xy 331.900175 -377.895909) (xy 331.906692 -377.913093) (xy 331.912468 -377.92025) (xy 331.93423 -377.945923)
			(xy 331.972179 -378.001507) (xy 332.003213 -378.061228) (xy 332.026887 -378.124229) (xy 332.042861 -378.189609)
			(xy 332.050907 -378.256429) (xy 332.05091 -378.323732) (xy 332.050903 -378.323793) (xy 335.328973 -378.323793)
			(xy 335.328975 -378.256368) (xy 335.337053 -378.189429) (xy 335.35309 -378.123939) (xy 335.376855 -378.060841)
			(xy 335.408007 -378.001044) (xy 335.446096 -377.945408) (xy 335.46796 -377.919742) (xy 335.473771 -377.912607)
			(xy 335.480275 -377.895409) (xy 335.48066 -377.886214) (xy 335.48066 -377.728734) (xy 335.481155 -377.718607)
			(xy 335.488875 -377.699883) (xy 335.50316 -377.685525) (xy 335.521844 -377.677708) (xy 335.531968 -377.677172)
			(xy 336.248248 -377.677172) (xy 336.258402 -377.677582) (xy 336.27715 -377.685388) (xy 336.29147 -377.699787)
			(xy 336.299173 -377.718578) (xy 336.299556 -377.728734) (xy 336.299556 -377.886214) (xy 336.299969 -377.895401)
			(xy 336.306482 -377.912585) (xy 336.312256 -377.919742) (xy 336.334096 -377.945428) (xy 336.372188 -378.001058)
			(xy 336.403343 -378.060851) (xy 336.42711 -378.123945) (xy 336.443149 -378.189433) (xy 336.451227 -378.256369)
			(xy 336.45123 -378.323734) (xy 339.729268 -378.323734) (xy 339.72927 -378.256427) (xy 339.737317 -378.189602)
			(xy 339.753293 -378.124218) (xy 339.776969 -378.061213) (xy 339.808006 -378.001489) (xy 339.845958 -377.945902)
			(xy 339.867748 -377.92025) (xy 339.873554 -377.913112) (xy 339.880062 -377.895916) (xy 339.880448 -377.886722)
			(xy 339.880448 -377.728734) (xy 339.880892 -377.718563) (xy 339.888668 -377.699768) (xy 339.903047 -377.685381)
			(xy 339.92184 -377.677597) (xy 339.93201 -377.677172) (xy 340.64829 -377.677172) (xy 340.658465 -377.677573)
			(xy 340.677266 -377.685361) (xy 340.691653 -377.699754) (xy 340.699432 -377.718559) (xy 340.699852 -377.728734)
			(xy 340.699852 -377.886722) (xy 340.700262 -377.895909) (xy 340.706777 -377.913093) (xy 340.712552 -377.92025)
			(xy 340.734314 -377.945923) (xy 340.772264 -378.001506) (xy 340.803299 -378.061227) (xy 340.826974 -378.124229)
			(xy 340.842949 -378.189608) (xy 340.850995 -378.256429) (xy 340.850998 -378.323732) (xy 340.850998 -378.323734)
			(xy 344.129059 -378.323734) (xy 344.129061 -378.256427) (xy 344.137108 -378.189603) (xy 344.153083 -378.124219)
			(xy 344.176759 -378.061213) (xy 344.207795 -378.001489) (xy 344.245747 -377.945902) (xy 344.267536 -377.92025)
			(xy 344.273341 -377.913111) (xy 344.27985 -377.895916) (xy 344.280236 -377.886722) (xy 344.280236 -377.728734)
			(xy 344.280692 -377.718565) (xy 344.288465 -377.699771) (xy 344.302841 -377.685385) (xy 344.321629 -377.677599)
			(xy 344.331798 -377.677172) (xy 345.048078 -377.677172) (xy 345.058252 -377.677583) (xy 345.077053 -377.685367)
			(xy 345.09144 -377.699757) (xy 345.099219 -377.71856) (xy 345.09964 -377.728734) (xy 345.09964 -377.886722)
			(xy 345.100053 -377.895909) (xy 345.106566 -377.913092) (xy 345.11234 -377.92025) (xy 345.134103 -377.945923)
			(xy 345.172054 -378.001506) (xy 345.203089 -378.061226) (xy 345.226764 -378.124228) (xy 345.24274 -378.189608)
			(xy 345.250786 -378.256429) (xy 345.250789 -378.323732) (xy 345.250789 -378.323734) (xy 374.929089 -378.323734)
			(xy 374.929092 -378.256427) (xy 374.937139 -378.189602) (xy 374.953116 -378.124218) (xy 374.976793 -378.061212)
			(xy 375.007831 -378.001488) (xy 375.045786 -377.945902) (xy 375.067576 -377.92025) (xy 375.073374 -377.913105)
			(xy 375.079888 -377.895915) (xy 375.080276 -377.886722) (xy 375.080276 -377.728734) (xy 375.080693 -377.71856)
			(xy 375.088474 -377.699759) (xy 375.102862 -377.685371) (xy 375.121664 -377.677592) (xy 375.131838 -377.677172)
			(xy 375.848118 -377.677172) (xy 375.858295 -377.67755) (xy 375.877097 -377.685347) (xy 375.891482 -377.699747)
			(xy 375.89926 -377.718557) (xy 375.89968 -377.728734) (xy 375.89968 -377.886722) (xy 375.900084 -377.89591)
			(xy 375.906602 -377.913094) (xy 375.91238 -377.92025) (xy 375.934142 -377.945923) (xy 375.97209 -378.001507)
			(xy 376.003123 -378.061228) (xy 376.026797 -378.12423) (xy 376.042771 -378.189609) (xy 376.050817 -378.256429)
			(xy 376.050819 -378.323732) (xy 376.050812 -378.323793) (xy 379.328882 -378.323793) (xy 379.328884 -378.256368)
			(xy 379.336962 -378.189428) (xy 379.352999 -378.123938) (xy 379.376765 -378.06084) (xy 379.407917 -378.001043)
			(xy 379.446007 -377.945408) (xy 379.467872 -377.919742) (xy 379.473684 -377.912608) (xy 379.480188 -377.895409)
			(xy 379.480572 -377.886214) (xy 379.480572 -377.728734) (xy 379.481056 -377.718606) (xy 379.488778 -377.699879)
			(xy 379.503066 -377.685521) (xy 379.521754 -377.677706) (xy 379.53188 -377.677172) (xy 380.24816 -377.677172)
			(xy 380.258308 -377.677654) (xy 380.277054 -377.685431) (xy 380.291378 -377.699809) (xy 380.299084 -377.718584)
			(xy 380.299468 -377.728734) (xy 380.299468 -377.886214) (xy 380.299878 -377.895401) (xy 380.306393 -377.912585)
			(xy 380.312168 -377.919742) (xy 380.334008 -377.945428) (xy 380.372099 -378.001059) (xy 380.403253 -378.060852)
			(xy 380.42702 -378.123946) (xy 380.443058 -378.189433) (xy 380.451137 -378.256369) (xy 380.451139 -378.323734)
			(xy 383.729177 -378.323734) (xy 383.729179 -378.256427) (xy 383.737226 -378.189602) (xy 383.753202 -378.124218)
			(xy 383.776879 -378.061212) (xy 383.807917 -378.001488) (xy 383.84587 -377.945902) (xy 383.86766 -377.92025)
			(xy 383.873468 -377.913113) (xy 383.879974 -377.895916) (xy 383.88036 -377.886722) (xy 383.88036 -377.728734)
			(xy 383.880792 -377.718562) (xy 383.88857 -377.699764) (xy 383.902954 -377.685377) (xy 383.92175 -377.677595)
			(xy 383.931922 -377.677172) (xy 384.648202 -377.677172) (xy 384.658378 -377.677563) (xy 384.677179 -377.685355)
			(xy 384.691565 -377.699751) (xy 384.699344 -377.718558) (xy 384.699764 -377.728734) (xy 384.699764 -377.886722)
			(xy 384.700172 -377.895909) (xy 384.706688 -377.913093) (xy 384.712464 -377.92025) (xy 384.734226 -377.945923)
			(xy 384.772175 -378.001507) (xy 384.803209 -378.061228) (xy 384.826884 -378.124229) (xy 384.842858 -378.189609)
			(xy 384.850904 -378.256429) (xy 384.850907 -378.323732) (xy 384.850907 -378.323734) (xy 388.128968 -378.323734)
			(xy 388.12897 -378.256427) (xy 388.137017 -378.189602) (xy 388.152993 -378.124218) (xy 388.176669 -378.061213)
			(xy 388.207706 -378.001489) (xy 388.245658 -377.945902) (xy 388.267448 -377.92025) (xy 388.273254 -377.913112)
			(xy 388.279762 -377.895916) (xy 388.280148 -377.886722) (xy 388.280148 -377.728734) (xy 388.280592 -377.718563)
			(xy 388.288368 -377.699768) (xy 388.302747 -377.685381) (xy 388.32154 -377.677597) (xy 388.33171 -377.677172)
			(xy 389.04799 -377.677172) (xy 389.058165 -377.677573) (xy 389.076966 -377.685361) (xy 389.091353 -377.699754)
			(xy 389.099132 -377.718559) (xy 389.099552 -377.728734) (xy 389.099552 -377.886722) (xy 389.099962 -377.895909)
			(xy 389.106477 -377.913093) (xy 389.112252 -377.92025) (xy 389.134014 -377.945923) (xy 389.171964 -378.001506)
			(xy 389.202999 -378.061227) (xy 389.226674 -378.124229) (xy 389.242649 -378.189608) (xy 389.250695 -378.256429)
			(xy 389.250698 -378.323732) (xy 389.250698 -378.323734) (xy 418.928998 -378.323734) (xy 418.929001 -378.256426)
			(xy 418.937048 -378.189601) (xy 418.953025 -378.124217) (xy 418.976703 -378.061211) (xy 419.007742 -378.001487)
			(xy 419.045697 -377.945902) (xy 419.067488 -377.92025) (xy 419.073287 -377.913106) (xy 419.079801 -377.895915)
			(xy 419.080188 -377.886722) (xy 419.080188 -377.728734) (xy 419.080593 -377.718558) (xy 419.088376 -377.699755)
			(xy 419.102768 -377.685367) (xy 419.121574 -377.67759) (xy 419.13175 -377.677172) (xy 419.84803 -377.677172)
			(xy 419.858208 -377.67754) (xy 419.87701 -377.685341) (xy 419.891395 -377.699744) (xy 419.899173 -377.718556)
			(xy 419.899592 -377.728734) (xy 419.899592 -377.886722) (xy 419.899993 -377.89591) (xy 419.906513 -377.913094)
			(xy 419.912292 -377.92025) (xy 419.934053 -377.945924) (xy 419.972001 -378.001508) (xy 420.003034 -378.061229)
			(xy 420.026706 -378.12423) (xy 420.04268 -378.189609) (xy 420.050726 -378.256429) (xy 420.050728 -378.323732)
			(xy 420.050721 -378.323793) (xy 423.328791 -378.323793) (xy 423.328793 -378.256368) (xy 423.336871 -378.189428)
			(xy 423.352909 -378.123938) (xy 423.376675 -378.06084) (xy 423.407828 -378.001043) (xy 423.445919 -377.945408)
			(xy 423.467784 -377.919742) (xy 423.473586 -377.9126) (xy 423.480098 -377.895407) (xy 423.480484 -377.886214)
			(xy 423.480484 -377.728734) (xy 423.480956 -377.718604) (xy 423.488681 -377.699875) (xy 423.502972 -377.685516)
			(xy 423.521664 -377.677704) (xy 423.531792 -377.677172) (xy 424.248072 -377.677172) (xy 424.258189 -377.677638)
			(xy 424.276887 -377.685372) (xy 424.291201 -377.699673) (xy 424.298953 -377.718363) (xy 424.29938 -377.72848)
			(xy 424.29938 -377.886214) (xy 424.299788 -377.895401) (xy 424.306303 -377.912585) (xy 424.31208 -377.919742)
			(xy 424.333919 -377.945428) (xy 424.37201 -378.001059) (xy 424.403163 -378.060852) (xy 424.426929 -378.123946)
			(xy 424.442967 -378.189433) (xy 424.451046 -378.256369) (xy 424.451048 -378.323734) (xy 427.729086 -378.323734)
			(xy 427.729089 -378.256427) (xy 427.737136 -378.189602) (xy 427.753113 -378.124218) (xy 427.77679 -378.061212)
			(xy 427.807828 -378.001488) (xy 427.845782 -377.945902) (xy 427.867572 -377.92025) (xy 427.873381 -377.913114)
			(xy 427.879886 -377.895916) (xy 427.880272 -377.886722) (xy 427.880272 -377.728734) (xy 427.880693 -377.71856)
			(xy 427.888473 -377.69976) (xy 427.90286 -377.685373) (xy 427.92166 -377.677593) (xy 427.931834 -377.677172)
			(xy 428.648114 -377.677172) (xy 428.658291 -377.677553) (xy 428.677092 -377.685349) (xy 428.691478 -377.699748)
			(xy 428.699256 -377.718557) (xy 428.699676 -377.728734) (xy 428.699676 -377.886722) (xy 428.700081 -377.89591)
			(xy 428.706599 -377.913094) (xy 428.712376 -377.92025) (xy 428.734137 -377.945924) (xy 428.772086 -378.001507)
			(xy 428.80312 -378.061228) (xy 428.826793 -378.12423) (xy 428.842767 -378.189609) (xy 428.850813 -378.256429)
			(xy 428.850816 -378.323732) (xy 428.850816 -378.323734) (xy 432.128877 -378.323734) (xy 432.128879 -378.256427)
			(xy 432.136926 -378.189602) (xy 432.152902 -378.124218) (xy 432.176579 -378.061212) (xy 432.207617 -378.001488)
			(xy 432.24557 -377.945902) (xy 432.26736 -377.92025) (xy 432.273168 -377.913113) (xy 432.279674 -377.895916)
			(xy 432.28006 -377.886722) (xy 432.28006 -377.728734) (xy 432.280492 -377.718562) (xy 432.28827 -377.699764)
			(xy 432.302654 -377.685377) (xy 432.32145 -377.677595) (xy 432.331622 -377.677172) (xy 433.047902 -377.677172)
			(xy 433.058078 -377.677563) (xy 433.076879 -377.685355) (xy 433.091265 -377.699751) (xy 433.099044 -377.718558)
			(xy 433.099464 -377.728734) (xy 433.099464 -377.886722) (xy 433.099872 -377.895909) (xy 433.106388 -377.913093)
			(xy 433.112164 -377.92025) (xy 433.133926 -377.945923) (xy 433.171875 -378.001507) (xy 433.202909 -378.061228)
			(xy 433.226584 -378.124229) (xy 433.242558 -378.189609) (xy 433.250604 -378.256429) (xy 433.250607 -378.323732)
			(xy 433.242565 -378.390553) (xy 433.226595 -378.455933) (xy 433.202925 -378.518937) (xy 433.171895 -378.57866)
			(xy 433.13395 -378.634246) (xy 433.112164 -378.659898) (xy 433.106381 -378.667053) (xy 433.099859 -378.684236)
			(xy 433.099464 -378.693426) (xy 433.099464 -379.186694) (xy 433.099885 -379.19588) (xy 433.106392 -379.213064)
			(xy 433.112164 -379.220222) (xy 433.133997 -379.245837) (xy 433.171944 -379.301429) (xy 433.202975 -379.361158)
			(xy 433.226645 -379.424167) (xy 433.242615 -379.489554) (xy 433.250655 -379.55638) (xy 433.250651 -379.623689)
			(xy 433.242603 -379.690515) (xy 433.226625 -379.755899) (xy 433.202947 -379.818906) (xy 433.171909 -379.878631)
			(xy 433.133955 -379.934218) (xy 433.112164 -379.95987) (xy 433.106351 -379.967003) (xy 433.099847 -379.984203)
			(xy 433.099464 -379.993398) (xy 433.099464 -380.151386) (xy 433.099025 -380.161556) (xy 433.091245 -380.180351)
			(xy 433.076864 -380.194736) (xy 433.058072 -380.202522) (xy 433.047902 -380.202948) (xy 432.331622 -380.202948)
			(xy 432.32145 -380.202518) (xy 432.302653 -380.194737) (xy 432.288267 -380.180353) (xy 432.280484 -380.161558)
			(xy 432.28006 -380.151386) (xy 432.28006 -379.993398) (xy 432.279637 -379.984212) (xy 432.273131 -379.967029)
			(xy 432.26736 -379.95987) (xy 432.245617 -379.934181) (xy 432.207665 -379.8786) (xy 432.176629 -379.818882)
			(xy 432.152953 -379.755882) (xy 432.136976 -379.690504) (xy 432.128928 -379.623685) (xy 432.128924 -379.556384)
			(xy 432.136964 -379.489564) (xy 432.152932 -379.424184) (xy 432.176601 -379.361181) (xy 432.20763 -379.301459)
			(xy 432.245575 -379.245874) (xy 432.26736 -379.220222) (xy 432.27318 -379.213093) (xy 432.279679 -379.19589)
			(xy 432.28006 -379.186694) (xy 432.28006 -378.693426) (xy 432.279624 -378.684242) (xy 432.273127 -378.667058)
			(xy 432.26736 -378.659898) (xy 432.245546 -378.634267) (xy 432.207596 -378.578678) (xy 432.176563 -378.518952)
			(xy 432.152891 -378.455945) (xy 432.136919 -378.39056) (xy 432.128877 -378.323734) (xy 428.850816 -378.323734)
			(xy 428.842774 -378.390552) (xy 428.826805 -378.455933) (xy 428.803136 -378.518936) (xy 428.772106 -378.578659)
			(xy 428.734161 -378.634245) (xy 428.712376 -378.659898) (xy 428.706595 -378.667054) (xy 428.700072 -378.684236)
			(xy 428.699676 -378.693426) (xy 428.699676 -379.186694) (xy 428.700094 -379.19588) (xy 428.706603 -379.213064)
			(xy 428.712376 -379.220222) (xy 428.734209 -379.245837) (xy 428.772155 -379.301429) (xy 428.803185 -379.361158)
			(xy 428.826855 -379.424167) (xy 428.842824 -379.489554) (xy 428.850865 -379.55638) (xy 428.85086 -379.623689)
			(xy 428.842812 -379.690514) (xy 428.826835 -379.755899) (xy 428.803157 -379.818905) (xy 428.772119 -379.87863)
			(xy 428.734166 -379.934218) (xy 428.712376 -379.95987) (xy 428.706564 -379.967004) (xy 428.70006 -379.984203)
			(xy 428.699676 -379.993398) (xy 428.699676 -380.151386) (xy 428.699156 -380.161541) (xy 428.691388 -380.180307)
			(xy 428.677031 -380.194673) (xy 428.658269 -380.20245) (xy 428.648114 -380.202948) (xy 427.931834 -380.202948)
			(xy 427.921663 -380.202508) (xy 427.902866 -380.194731) (xy 427.88848 -380.180351) (xy 427.880696 -380.161557)
			(xy 427.880272 -380.151386) (xy 427.880272 -379.993398) (xy 427.879869 -379.98421) (xy 427.873351 -379.967025)
			(xy 427.867572 -379.95987) (xy 427.845829 -379.934181) (xy 427.807876 -379.878601) (xy 427.776839 -379.818882)
			(xy 427.753162 -379.755883) (xy 427.737185 -379.690505) (xy 427.729137 -379.623686) (xy 427.729133 -379.556384)
			(xy 427.737173 -379.489564) (xy 427.753142 -379.424183) (xy 427.776811 -379.361181) (xy 427.807841 -379.301459)
			(xy 427.845786 -379.245874) (xy 427.867572 -379.220222) (xy 427.873393 -379.213094) (xy 427.879891 -379.19589)
			(xy 427.880272 -379.186694) (xy 427.880272 -378.693426) (xy 427.879856 -378.684239) (xy 427.873347 -378.667055)
			(xy 427.867572 -378.659898) (xy 427.845758 -378.634267) (xy 427.807808 -378.578678) (xy 427.776774 -378.518952)
			(xy 427.753101 -378.455945) (xy 427.737129 -378.39056) (xy 427.729086 -378.323734) (xy 424.451048 -378.323734)
			(xy 424.451048 -378.323791) (xy 424.442974 -378.390728) (xy 424.426941 -378.456216) (xy 424.403179 -378.519312)
			(xy 424.37203 -378.579107) (xy 424.333943 -378.634741) (xy 424.31208 -378.660406) (xy 424.306296 -378.66756)
			(xy 424.299775 -378.684744) (xy 424.29938 -378.693934) (xy 424.29938 -379.186186) (xy 424.299802 -379.195372)
			(xy 424.306308 -379.212556) (xy 424.31208 -379.219714) (xy 424.33399 -379.245342) (xy 424.372079 -379.300981)
			(xy 424.403228 -379.360782) (xy 424.426991 -379.423884) (xy 424.443024 -379.489378) (xy 424.451096 -379.556321)
			(xy 424.451092 -379.623748) (xy 424.443011 -379.69069) (xy 424.42697 -379.756182) (xy 424.4032 -379.819281)
			(xy 424.372043 -379.879078) (xy 424.333947 -379.934713) (xy 424.31208 -379.960378) (xy 424.306266 -379.96751)
			(xy 424.299762 -379.984711) (xy 424.29938 -379.993906) (xy 424.29938 -380.151386) (xy 424.298863 -380.161509)
			(xy 424.291143 -380.180226) (xy 424.276866 -380.194583) (xy 424.258193 -380.202406) (xy 424.248072 -380.202948)
			(xy 423.531792 -380.202948) (xy 423.521689 -380.202422) (xy 423.50302 -380.194691) (xy 423.488727 -380.180407)
			(xy 423.480984 -380.161743) (xy 423.480484 -380.15164) (xy 423.480484 -379.993906) (xy 423.480075 -379.984719)
			(xy 423.473561 -379.967534) (xy 423.467784 -379.960378) (xy 423.445966 -379.934675) (xy 423.407877 -379.879046)
			(xy 423.376725 -379.819255) (xy 423.352959 -379.756163) (xy 423.336921 -379.690678) (xy 423.328841 -379.623744)
			(xy 423.328837 -379.556325) (xy 423.336908 -379.48939) (xy 423.352938 -379.423904) (xy 423.376697 -379.360809)
			(xy 423.407841 -379.301014) (xy 423.445923 -379.245379) (xy 423.467784 -379.219714) (xy 423.473598 -379.212581)
			(xy 423.480103 -379.195381) (xy 423.480484 -379.186186) (xy 423.480484 -378.693934) (xy 423.480061 -378.684748)
			(xy 423.473557 -378.667563) (xy 423.467784 -378.660406) (xy 423.445895 -378.634762) (xy 423.407808 -378.579124)
			(xy 423.376659 -378.519324) (xy 423.352897 -378.456225) (xy 423.336864 -378.390733) (xy 423.328791 -378.323793)
			(xy 420.050721 -378.323793) (xy 420.042687 -378.390552) (xy 420.026718 -378.455932) (xy 420.003049 -378.518936)
			(xy 419.972021 -378.578659) (xy 419.934077 -378.634245) (xy 419.912292 -378.659898) (xy 419.906513 -378.667056)
			(xy 419.899988 -378.684237) (xy 419.899592 -378.693426) (xy 419.899592 -379.186694) (xy 419.900007 -379.195881)
			(xy 419.906518 -379.213065) (xy 419.912292 -379.220222) (xy 419.934124 -379.245837) (xy 419.972069 -379.30143)
			(xy 420.003099 -379.361159) (xy 420.026768 -379.424168) (xy 420.042737 -379.489554) (xy 420.050777 -379.556381)
			(xy 420.050772 -379.623689) (xy 420.042724 -379.690514) (xy 420.026747 -379.755898) (xy 420.003071 -379.818905)
			(xy 419.972034 -379.87863) (xy 419.934082 -379.934217) (xy 419.912292 -379.95987) (xy 419.906482 -379.967006)
			(xy 419.899976 -379.984204) (xy 419.899592 -379.993398) (xy 419.899592 -380.151386) (xy 419.899056 -380.161539)
			(xy 419.891292 -380.180302) (xy 419.876939 -380.194667) (xy 419.858183 -380.202447) (xy 419.84803 -380.202948)
			(xy 419.13175 -380.202948) (xy 419.12158 -380.202495) (xy 419.102784 -380.194724) (xy 419.088396 -380.180347)
			(xy 419.080612 -380.161556) (xy 419.080188 -380.151386) (xy 419.080188 -379.993398) (xy 419.079781 -379.98421)
			(xy 419.073266 -379.967026) (xy 419.067488 -379.95987) (xy 419.045744 -379.934181) (xy 419.007791 -379.878601)
			(xy 418.976753 -379.818883) (xy 418.953075 -379.755883) (xy 418.937097 -379.690505) (xy 418.929049 -379.623686)
			(xy 418.929045 -379.556383) (xy 418.937085 -379.489563) (xy 418.953055 -379.424183) (xy 418.976724 -379.36118)
			(xy 419.007755 -379.301458) (xy 419.045702 -379.245873) (xy 419.067488 -379.220222) (xy 419.073299 -379.213087)
			(xy 419.079805 -379.195889) (xy 419.080188 -379.186694) (xy 419.080188 -378.693426) (xy 419.079768 -378.68424)
			(xy 419.073262 -378.667055) (xy 419.067488 -378.659898) (xy 419.045673 -378.634268) (xy 419.007722 -378.578679)
			(xy 418.976687 -378.518953) (xy 418.953014 -378.455946) (xy 418.937041 -378.39056) (xy 418.928998 -378.323734)
			(xy 389.250698 -378.323734) (xy 389.242656 -378.390553) (xy 389.226686 -378.455934) (xy 389.203015 -378.518937)
			(xy 389.171985 -378.57866) (xy 389.134038 -378.634246) (xy 389.112252 -378.659898) (xy 389.106468 -378.667052)
			(xy 389.099947 -378.684236) (xy 389.099552 -378.693426) (xy 389.099552 -379.186694) (xy 389.099976 -379.19588)
			(xy 389.106481 -379.213063) (xy 389.112252 -379.220222) (xy 389.134085 -379.245837) (xy 389.172033 -379.301428)
			(xy 389.203065 -379.361157) (xy 389.226736 -379.424166) (xy 389.242706 -379.489553) (xy 389.250746 -379.55638)
			(xy 389.250742 -379.623689) (xy 389.242693 -379.690515) (xy 389.226715 -379.7559) (xy 389.203037 -379.818906)
			(xy 389.171998 -379.878631) (xy 389.134043 -379.934218) (xy 389.112252 -379.95987) (xy 389.106437 -379.967002)
			(xy 389.099935 -379.984203) (xy 389.099552 -379.993398) (xy 389.099552 -380.151386) (xy 389.099125 -380.161558)
			(xy 389.091342 -380.180354) (xy 389.076958 -380.19474) (xy 389.058162 -380.202524) (xy 389.04799 -380.202948)
			(xy 388.33171 -380.202948) (xy 388.321537 -380.202528) (xy 388.30274 -380.194743) (xy 388.288354 -380.180357)
			(xy 388.280571 -380.161559) (xy 388.280148 -380.151386) (xy 388.280148 -379.993398) (xy 388.279728 -379.984212)
			(xy 388.27322 -379.967028) (xy 388.267448 -379.95987) (xy 388.245705 -379.934181) (xy 388.207755 -379.8786)
			(xy 388.176719 -379.818881) (xy 388.153043 -379.755882) (xy 388.137067 -379.690504) (xy 388.129019 -379.623685)
			(xy 388.129015 -379.556384) (xy 388.137054 -379.489564) (xy 388.153023 -379.424184) (xy 388.176691 -379.361182)
			(xy 388.207719 -379.30146) (xy 388.245663 -379.245874) (xy 388.267448 -379.220222) (xy 388.273266 -379.213092)
			(xy 388.279767 -379.19589) (xy 388.280148 -379.186694) (xy 388.280148 -378.693426) (xy 388.279715 -378.684241)
			(xy 388.273216 -378.667057) (xy 388.267448 -378.659898) (xy 388.245634 -378.634267) (xy 388.207686 -378.578678)
			(xy 388.176653 -378.518951) (xy 388.152981 -378.455944) (xy 388.13701 -378.390559) (xy 388.128968 -378.323734)
			(xy 384.850907 -378.323734) (xy 384.842865 -378.390553) (xy 384.826895 -378.455933) (xy 384.803225 -378.518937)
			(xy 384.772195 -378.57866) (xy 384.73425 -378.634246) (xy 384.712464 -378.659898) (xy 384.706681 -378.667053)
			(xy 384.700159 -378.684236) (xy 384.699764 -378.693426) (xy 384.699764 -379.186694) (xy 384.700185 -379.19588)
			(xy 384.706692 -379.213064) (xy 384.712464 -379.220222) (xy 384.734297 -379.245837) (xy 384.772244 -379.301429)
			(xy 384.803275 -379.361158) (xy 384.826945 -379.424167) (xy 384.842915 -379.489554) (xy 384.850955 -379.55638)
			(xy 384.850951 -379.623689) (xy 384.842903 -379.690515) (xy 384.826925 -379.755899) (xy 384.803247 -379.818906)
			(xy 384.772209 -379.878631) (xy 384.734255 -379.934218) (xy 384.712464 -379.95987) (xy 384.706651 -379.967003)
			(xy 384.700147 -379.984203) (xy 384.699764 -379.993398) (xy 384.699764 -380.151386) (xy 384.699325 -380.161556)
			(xy 384.691545 -380.180351) (xy 384.677164 -380.194736) (xy 384.658372 -380.202522) (xy 384.648202 -380.202948)
			(xy 383.931922 -380.202948) (xy 383.92175 -380.202518) (xy 383.902953 -380.194737) (xy 383.888567 -380.180353)
			(xy 383.880784 -380.161558) (xy 383.88036 -380.151386) (xy 383.88036 -379.993398) (xy 383.879937 -379.984212)
			(xy 383.873431 -379.967029) (xy 383.86766 -379.95987) (xy 383.845917 -379.934181) (xy 383.807965 -379.8786)
			(xy 383.776929 -379.818882) (xy 383.753253 -379.755882) (xy 383.737276 -379.690504) (xy 383.729228 -379.623685)
			(xy 383.729224 -379.556384) (xy 383.737264 -379.489564) (xy 383.753232 -379.424184) (xy 383.776901 -379.361181)
			(xy 383.80793 -379.301459) (xy 383.845875 -379.245874) (xy 383.86766 -379.220222) (xy 383.87348 -379.213093)
			(xy 383.879979 -379.19589) (xy 383.88036 -379.186694) (xy 383.88036 -378.693426) (xy 383.879924 -378.684242)
			(xy 383.873427 -378.667058) (xy 383.86766 -378.659898) (xy 383.845846 -378.634267) (xy 383.807896 -378.578678)
			(xy 383.776863 -378.518952) (xy 383.753191 -378.455945) (xy 383.737219 -378.39056) (xy 383.729177 -378.323734)
			(xy 380.451139 -378.323734) (xy 380.451139 -378.323792) (xy 380.443065 -378.390729) (xy 380.427031 -378.456217)
			(xy 380.403269 -378.519313) (xy 380.372119 -378.579108) (xy 380.334032 -378.634741) (xy 380.312168 -378.660406)
			(xy 380.306382 -378.667559) (xy 380.299862 -378.684744) (xy 380.299468 -378.693934) (xy 380.299468 -379.186186)
			(xy 380.299892 -379.195372) (xy 380.306397 -379.212556) (xy 380.312168 -379.219714) (xy 380.334078 -379.245341)
			(xy 380.372168 -379.300981) (xy 380.403318 -379.360782) (xy 380.427081 -379.423884) (xy 380.443114 -379.489378)
			(xy 380.451187 -379.556321) (xy 380.451183 -379.623749) (xy 380.443102 -379.69069) (xy 380.427061 -379.756182)
			(xy 380.40329 -379.819281) (xy 380.372132 -379.879079) (xy 380.334036 -379.934713) (xy 380.312168 -379.960378)
			(xy 380.306352 -379.967509) (xy 380.29985 -379.984711) (xy 380.299468 -379.993906) (xy 380.299468 -380.151386)
			(xy 380.298962 -380.161511) (xy 380.291241 -380.18023) (xy 380.27696 -380.194587) (xy 380.258282 -380.202408)
			(xy 380.24816 -380.202948) (xy 379.53188 -380.202948) (xy 379.521731 -380.202496) (xy 379.502987 -380.194703)
			(xy 379.488666 -380.180316) (xy 379.480958 -380.161537) (xy 379.480572 -380.151386) (xy 379.480572 -379.993906)
			(xy 379.480165 -379.984718) (xy 379.47365 -379.967534) (xy 379.467872 -379.960378) (xy 379.446054 -379.934675)
			(xy 379.407966 -379.879045) (xy 379.376815 -379.819254) (xy 379.353049 -379.756162) (xy 379.337011 -379.690678)
			(xy 379.328932 -379.623744) (xy 379.328928 -379.556325) (xy 379.336999 -379.48939) (xy 379.353029 -379.423904)
			(xy 379.376787 -379.360809) (xy 379.40793 -379.301014) (xy 379.446012 -379.24538) (xy 379.467872 -379.219714)
			(xy 379.473696 -379.212589) (xy 379.480192 -379.195383) (xy 379.480572 -379.186186) (xy 379.480572 -378.693934)
			(xy 379.480152 -378.684748) (xy 379.473646 -378.667563) (xy 379.467872 -378.660406) (xy 379.445983 -378.634761)
			(xy 379.407897 -378.579123) (xy 379.376749 -378.519324) (xy 379.352988 -378.456224) (xy 379.336955 -378.390733)
			(xy 379.328882 -378.323793) (xy 376.050812 -378.323793) (xy 376.042778 -378.390552) (xy 376.026808 -378.455933)
			(xy 376.003139 -378.518936) (xy 375.97211 -378.578659) (xy 375.934166 -378.634246) (xy 375.91238 -378.659898)
			(xy 375.906599 -378.667054) (xy 375.900076 -378.684236) (xy 375.89968 -378.693426) (xy 375.89968 -379.186694)
			(xy 375.900098 -379.19588) (xy 375.906607 -379.213064) (xy 375.91238 -379.220222) (xy 375.934212 -379.245837)
			(xy 375.972159 -379.301429) (xy 376.003189 -379.361158) (xy 376.026858 -379.424168) (xy 376.042827 -379.489554)
			(xy 376.050868 -379.55638) (xy 376.050863 -379.623689) (xy 376.042815 -379.690514) (xy 376.026838 -379.755899)
			(xy 376.003161 -379.818905) (xy 375.972123 -379.87863) (xy 375.93417 -379.934218) (xy 375.91238 -379.95987)
			(xy 375.906569 -379.967005) (xy 375.900064 -379.984203) (xy 375.89968 -379.993398) (xy 375.89968 -380.151386)
			(xy 375.899156 -380.161541) (xy 375.891389 -380.180306) (xy 375.877033 -380.194671) (xy 375.858272 -380.202449)
			(xy 375.848118 -380.202948) (xy 375.131838 -380.202948) (xy 375.121667 -380.202505) (xy 375.102871 -380.19473)
			(xy 375.088484 -380.18035) (xy 375.0807 -380.161557) (xy 375.080276 -380.151386) (xy 375.080276 -379.993398)
			(xy 375.079872 -379.98421) (xy 375.073355 -379.967025) (xy 375.067576 -379.95987) (xy 375.045832 -379.934181)
			(xy 375.00788 -379.878601) (xy 374.976842 -379.818883) (xy 374.953165 -379.755883) (xy 374.937188 -379.690505)
			(xy 374.92914 -379.623686) (xy 374.929136 -379.556384) (xy 374.937176 -379.489563) (xy 374.953145 -379.424183)
			(xy 374.976814 -379.361181) (xy 375.007844 -379.301459) (xy 375.04579 -379.245874) (xy 375.067576 -379.220222)
			(xy 375.073385 -379.213086) (xy 375.079893 -379.195889) (xy 375.080276 -379.186694) (xy 375.080276 -378.693426)
			(xy 375.079859 -378.684239) (xy 375.073351 -378.667055) (xy 375.067576 -378.659898) (xy 375.045762 -378.634267)
			(xy 375.007811 -378.578679) (xy 374.976777 -378.518952) (xy 374.953104 -378.455945) (xy 374.937132 -378.39056)
			(xy 374.929089 -378.323734) (xy 345.250789 -378.323734) (xy 345.242747 -378.390553) (xy 345.226776 -378.455934)
			(xy 345.203105 -378.518938) (xy 345.172074 -378.57866) (xy 345.134127 -378.634246) (xy 345.11234 -378.659898)
			(xy 345.106554 -378.667051) (xy 345.100035 -378.684236) (xy 345.09964 -378.693426) (xy 345.09964 -379.186694)
			(xy 345.100066 -379.195879) (xy 345.10657 -379.213063) (xy 345.11234 -379.220222) (xy 345.134174 -379.245837)
			(xy 345.172123 -379.301428) (xy 345.203155 -379.361156) (xy 345.226826 -379.424166) (xy 345.242797 -379.489553)
			(xy 345.250837 -379.55638) (xy 345.250833 -379.623689) (xy 345.242784 -379.690515) (xy 345.226806 -379.7559)
			(xy 345.203127 -379.818907) (xy 345.172087 -379.878632) (xy 345.134131 -379.934218) (xy 345.11234 -379.95987)
			(xy 345.106524 -379.967001) (xy 345.100023 -379.984203) (xy 345.09964 -379.993398) (xy 345.09964 -380.151386)
			(xy 345.099224 -380.161559) (xy 345.09144 -380.180358) (xy 345.077051 -380.194744) (xy 345.058252 -380.202526)
			(xy 345.048078 -380.202948) (xy 344.331798 -380.202948) (xy 344.321625 -380.202537) (xy 344.302827 -380.194749)
			(xy 344.288442 -380.180359) (xy 344.280659 -380.16156) (xy 344.280236 -380.151386) (xy 344.280236 -379.993398)
			(xy 344.279819 -379.984212) (xy 344.273309 -379.967028) (xy 344.267536 -379.95987) (xy 344.245794 -379.93418)
			(xy 344.207844 -379.878599) (xy 344.176809 -379.818881) (xy 344.153133 -379.755881) (xy 344.137157 -379.690504)
			(xy 344.12911 -379.623685) (xy 344.129106 -379.556384) (xy 344.137145 -379.489565) (xy 344.153113 -379.424185)
			(xy 344.17678 -379.361182) (xy 344.207808 -379.30146) (xy 344.245751 -379.245874) (xy 344.267536 -379.220222)
			(xy 344.273353 -379.213091) (xy 344.279855 -379.19589) (xy 344.280236 -379.186694) (xy 344.280236 -378.693426)
			(xy 344.279805 -378.684241) (xy 344.273305 -378.667057) (xy 344.267536 -378.659898) (xy 344.245723 -378.634267)
			(xy 344.207775 -378.578677) (xy 344.176743 -378.518951) (xy 344.153072 -378.455944) (xy 344.137101 -378.390559)
			(xy 344.129059 -378.323734) (xy 340.850998 -378.323734) (xy 340.842956 -378.390553) (xy 340.826986 -378.455934)
			(xy 340.803315 -378.518937) (xy 340.772285 -378.57866) (xy 340.734338 -378.634246) (xy 340.712552 -378.659898)
			(xy 340.706768 -378.667052) (xy 340.700247 -378.684236) (xy 340.699852 -378.693426) (xy 340.699852 -379.186694)
			(xy 340.700276 -379.19588) (xy 340.706781 -379.213063) (xy 340.712552 -379.220222) (xy 340.734385 -379.245837)
			(xy 340.772333 -379.301428) (xy 340.803365 -379.361157) (xy 340.827036 -379.424166) (xy 340.843006 -379.489553)
			(xy 340.851046 -379.55638) (xy 340.851042 -379.623689) (xy 340.842993 -379.690515) (xy 340.827015 -379.7559)
			(xy 340.803337 -379.818906) (xy 340.772298 -379.878631) (xy 340.734343 -379.934218) (xy 340.712552 -379.95987)
			(xy 340.706737 -379.967002) (xy 340.700235 -379.984203) (xy 340.699852 -379.993398) (xy 340.699852 -380.151386)
			(xy 340.699425 -380.161558) (xy 340.691642 -380.180354) (xy 340.677258 -380.19474) (xy 340.658462 -380.202524)
			(xy 340.64829 -380.202948) (xy 339.93201 -380.202948) (xy 339.921837 -380.202528) (xy 339.90304 -380.194743)
			(xy 339.888654 -380.180357) (xy 339.880871 -380.161559) (xy 339.880448 -380.151386) (xy 339.880448 -379.993398)
			(xy 339.880028 -379.984212) (xy 339.87352 -379.967028) (xy 339.867748 -379.95987) (xy 339.846005 -379.934181)
			(xy 339.808055 -379.8786) (xy 339.777019 -379.818881) (xy 339.753343 -379.755882) (xy 339.737367 -379.690504)
			(xy 339.729319 -379.623685) (xy 339.729315 -379.556384) (xy 339.737354 -379.489564) (xy 339.753323 -379.424184)
			(xy 339.776991 -379.361182) (xy 339.808019 -379.30146) (xy 339.845963 -379.245874) (xy 339.867748 -379.220222)
			(xy 339.873566 -379.213092) (xy 339.880067 -379.19589) (xy 339.880448 -379.186694) (xy 339.880448 -378.693426)
			(xy 339.880015 -378.684241) (xy 339.873516 -378.667057) (xy 339.867748 -378.659898) (xy 339.845934 -378.634267)
			(xy 339.807986 -378.578678) (xy 339.776953 -378.518951) (xy 339.753281 -378.455944) (xy 339.73731 -378.390559)
			(xy 339.729268 -378.323734) (xy 336.45123 -378.323734) (xy 336.45123 -378.323792) (xy 336.443156 -378.390729)
			(xy 336.427122 -378.456217) (xy 336.403359 -378.519313) (xy 336.372208 -378.579108) (xy 336.33412 -378.634742)
			(xy 336.312256 -378.660406) (xy 336.306469 -378.667558) (xy 336.29995 -378.684743) (xy 336.299556 -378.693934)
			(xy 336.299556 -379.186186) (xy 336.299983 -379.195371) (xy 336.306486 -379.212555) (xy 336.312256 -379.219714)
			(xy 336.334167 -379.245341) (xy 336.372257 -379.30098) (xy 336.403408 -379.360781) (xy 336.427172 -379.423883)
			(xy 336.443205 -379.489377) (xy 336.451278 -379.55632) (xy 336.451274 -379.623749) (xy 336.443193 -379.690691)
			(xy 336.427151 -379.756183) (xy 336.40338 -379.819282) (xy 336.372221 -379.879079) (xy 336.334124 -379.934713)
			(xy 336.312256 -379.960378) (xy 336.306438 -379.967508) (xy 336.299937 -379.98471) (xy 336.299556 -379.993906)
			(xy 336.299556 -380.151386) (xy 336.299062 -380.161512) (xy 336.291338 -380.180234) (xy 336.277054 -380.194591)
			(xy 336.258372 -380.20241) (xy 336.248248 -380.202948) (xy 335.531968 -380.202948) (xy 335.521818 -380.202506)
			(xy 335.503074 -380.194708) (xy 335.488753 -380.180319) (xy 335.481046 -380.161538) (xy 335.48066 -380.151386)
			(xy 335.48066 -379.993906) (xy 335.480234 -379.984721) (xy 335.47373 -379.967537) (xy 335.46796 -379.960378)
			(xy 335.446143 -379.934675) (xy 335.408055 -379.879045) (xy 335.376905 -379.819253) (xy 335.35314 -379.756162)
			(xy 335.337102 -379.690678) (xy 335.329023 -379.623744) (xy 335.329019 -379.556325) (xy 335.33709 -379.48939)
			(xy 335.353119 -379.423904) (xy 335.376876 -379.36081) (xy 335.40802 -379.301015) (xy 335.4461 -379.24538)
			(xy 335.46796 -379.219714) (xy 335.473783 -379.212588) (xy 335.48028 -379.195382) (xy 335.48066 -379.186186)
			(xy 335.48066 -378.693934) (xy 335.48022 -378.68475) (xy 335.473726 -378.667566) (xy 335.46796 -378.660406)
			(xy 335.446072 -378.634761) (xy 335.407987 -378.579123) (xy 335.376839 -378.519323) (xy 335.353078 -378.456224)
			(xy 335.337046 -378.390733) (xy 335.328973 -378.323793) (xy 332.050903 -378.323793) (xy 332.042868 -378.390553)
			(xy 332.026898 -378.455933) (xy 332.003229 -378.518937) (xy 331.972199 -378.578659) (xy 331.934254 -378.634246)
			(xy 331.912468 -378.659898) (xy 331.906686 -378.667053) (xy 331.900163 -378.684236) (xy 331.899768 -378.693426)
			(xy 331.899768 -379.186694) (xy 331.900188 -379.19588) (xy 331.906696 -379.213064) (xy 331.912468 -379.220222)
			(xy 331.934301 -379.245837) (xy 331.972248 -379.301429) (xy 332.003279 -379.361158) (xy 332.026949 -379.424167)
			(xy 332.042918 -379.489554) (xy 332.050958 -379.55638) (xy 332.050954 -379.623689) (xy 332.042906 -379.690514)
			(xy 332.026928 -379.755899) (xy 332.00325 -379.818906) (xy 331.972212 -379.878631) (xy 331.934258 -379.934218)
			(xy 331.912468 -379.95987) (xy 331.906655 -379.967003) (xy 331.900151 -379.984203) (xy 331.899768 -379.993398)
			(xy 331.899768 -380.151386) (xy 331.899325 -380.161556) (xy 331.891546 -380.180349) (xy 331.877166 -380.194734)
			(xy 331.858376 -380.202521) (xy 331.848206 -380.202948) (xy 331.131926 -380.202948) (xy 331.121754 -380.202514)
			(xy 331.102958 -380.194735) (xy 331.088571 -380.180352) (xy 331.080788 -380.161558) (xy 331.080364 -380.151386)
			(xy 331.080364 -379.993398) (xy 331.07994 -379.984213) (xy 331.073434 -379.967029) (xy 331.067664 -379.95987)
			(xy 331.045921 -379.934181) (xy 331.007969 -379.8786) (xy 330.976932 -379.818882) (xy 330.953256 -379.755882)
			(xy 330.937279 -379.690504) (xy 330.929231 -379.623686) (xy 330.929227 -379.556384) (xy 330.937267 -379.489564)
			(xy 330.953235 -379.424184) (xy 330.976904 -379.361181) (xy 331.007933 -379.301459) (xy 331.045878 -379.245874)
			(xy 331.067664 -379.220222) (xy 331.073484 -379.213094) (xy 331.079983 -379.19589) (xy 331.080364 -379.186694)
			(xy 331.080364 -378.693426) (xy 331.079927 -378.684242) (xy 331.07343 -378.667058) (xy 331.067664 -378.659898)
			(xy 331.04585 -378.634267) (xy 331.0079 -378.578678) (xy 330.976866 -378.518952) (xy 330.953194 -378.455945)
			(xy 330.937222 -378.39056) (xy 330.92918 -378.323734) (xy 301.250878 -378.323734) (xy 301.250878 -378.323791)
			(xy 301.242805 -378.390727) (xy 301.226773 -378.456215) (xy 301.203013 -378.51931) (xy 301.171866 -378.579106)
			(xy 301.133782 -378.63474) (xy 301.11192 -378.660406) (xy 301.106141 -378.667564) (xy 301.099615 -378.684745)
			(xy 301.09922 -378.693934) (xy 301.09922 -379.186186) (xy 301.099632 -379.195373) (xy 301.106144 -379.212558)
			(xy 301.11192 -379.219714) (xy 301.133828 -379.245342) (xy 301.171914 -379.300983) (xy 301.203062 -379.360784)
			(xy 301.226823 -379.423886) (xy 301.242854 -379.489379) (xy 301.250926 -379.556321) (xy 301.250922 -379.623748)
			(xy 301.242842 -379.690689) (xy 301.226802 -379.75618) (xy 301.203034 -379.819279) (xy 301.171879 -379.879077)
			(xy 301.133786 -379.934712) (xy 301.11192 -379.960378) (xy 301.10611 -379.967514) (xy 301.099603 -379.984711)
			(xy 301.09922 -379.993906) (xy 301.09922 -380.151386) (xy 301.098761 -380.161517) (xy 301.09103 -380.180245)
			(xy 301.076735 -380.194603) (xy 301.058041 -380.202416) (xy 301.047912 -380.202948) (xy 300.331632 -380.202948)
			(xy 300.321486 -380.202453) (xy 300.302743 -380.194677) (xy 300.28842 -380.180304) (xy 300.280711 -380.161534)
			(xy 300.280324 -380.151386) (xy 300.280324 -379.993906) (xy 300.279906 -379.98472) (xy 300.273397 -379.967536)
			(xy 300.267624 -379.960378) (xy 300.245804 -379.934676) (xy 300.207713 -379.879047) (xy 300.176559 -379.819256)
			(xy 300.152791 -379.756164) (xy 300.136751 -379.690679) (xy 300.128672 -379.623745) (xy 300.128667 -379.556324)
			(xy 300.136739 -379.489389) (xy 300.15277 -379.423902) (xy 300.17653 -379.360807) (xy 300.207677 -379.301012)
			(xy 300.245762 -379.245379) (xy 300.267624 -379.219714) (xy 300.273442 -379.212584) (xy 300.279943 -379.195382)
			(xy 300.280324 -379.186186) (xy 300.280324 -378.693934) (xy 300.279892 -378.684749) (xy 300.273393 -378.667565)
			(xy 300.267624 -378.660406) (xy 300.245734 -378.634762) (xy 300.207644 -378.579125) (xy 300.176493 -378.519326)
			(xy 300.152729 -378.456227) (xy 300.136695 -378.390735) (xy 300.128621 -378.323794) (xy 296.851087 -378.323794)
			(xy 296.843014 -378.390727) (xy 296.826983 -378.456214) (xy 296.803223 -378.51931) (xy 296.772077 -378.579105)
			(xy 296.733993 -378.63474) (xy 296.712132 -378.660406) (xy 296.706342 -378.667556) (xy 296.699825 -378.684743)
			(xy 296.699432 -378.693934) (xy 296.699432 -379.186186) (xy 296.699864 -379.195371) (xy 296.706364 -379.212554)
			(xy 296.712132 -379.219714) (xy 296.73404 -379.245342) (xy 296.772125 -379.300983) (xy 296.803272 -379.360785)
			(xy 296.827032 -379.423886) (xy 296.843064 -379.489379) (xy 296.851135 -379.556321) (xy 296.851131 -379.623748)
			(xy 296.843051 -379.690689) (xy 296.827012 -379.75618) (xy 296.803244 -379.819279) (xy 296.77209 -379.879076)
			(xy 296.733998 -379.934712) (xy 296.712132 -379.960378) (xy 296.706312 -379.967506) (xy 296.699813 -379.98471)
			(xy 296.699432 -379.993906) (xy 296.699432 -380.151386) (xy 296.698961 -380.161515) (xy 296.691233 -380.180241)
			(xy 296.676941 -380.194599) (xy 296.658251 -380.202414) (xy 296.648124 -380.202948) (xy 295.931844 -380.202948)
			(xy 295.921699 -380.202443) (xy 295.902957 -380.194671) (xy 295.888633 -380.1803) (xy 295.880924 -380.161533)
			(xy 295.880536 -380.151386) (xy 295.880536 -379.993906) (xy 295.880115 -379.98472) (xy 295.873608 -379.967536)
			(xy 295.867836 -379.960378) (xy 295.846016 -379.934676) (xy 295.807924 -379.879048) (xy 295.776769 -379.819257)
			(xy 295.753 -379.756165) (xy 295.736961 -379.69068) (xy 295.728881 -379.623745) (xy 295.728876 -379.556324)
			(xy 295.736948 -379.489388) (xy 295.75298 -379.423901) (xy 295.776741 -379.360806) (xy 295.807888 -379.301012)
			(xy 295.845974 -379.245379) (xy 295.867836 -379.219714) (xy 295.873656 -379.212586) (xy 295.880156 -379.195382)
			(xy 295.880536 -379.186186) (xy 295.880536 -378.693934) (xy 295.880101 -378.68475) (xy 295.873604 -378.667565)
			(xy 295.867836 -378.660406) (xy 295.845945 -378.634762) (xy 295.807855 -378.579126) (xy 295.776703 -378.519327)
			(xy 295.752939 -378.456227) (xy 295.736904 -378.390735) (xy 295.72883 -378.323794) (xy 292.450785 -378.323794)
			(xy 292.44275 -378.390553) (xy 292.426779 -378.455934) (xy 292.403109 -378.518938) (xy 292.372077 -378.57866)
			(xy 292.334131 -378.634246) (xy 292.312344 -378.659898) (xy 292.306559 -378.667051) (xy 292.300039 -378.684236)
			(xy 292.299644 -378.693426) (xy 292.299644 -379.186694) (xy 292.30007 -379.195879) (xy 292.306574 -379.213063)
			(xy 292.312344 -379.220222) (xy 292.334178 -379.245837) (xy 292.372126 -379.301428) (xy 292.403158 -379.361157)
			(xy 292.426829 -379.424166) (xy 292.4428 -379.489553) (xy 292.45084 -379.55638) (xy 292.450836 -379.623689)
			(xy 292.442787 -379.690515) (xy 292.426809 -379.7559) (xy 292.40313 -379.818907) (xy 292.372091 -379.878631)
			(xy 292.334135 -379.934218) (xy 292.312344 -379.95987) (xy 292.306528 -379.967001) (xy 292.300027 -379.984203)
			(xy 292.299644 -379.993398) (xy 292.299644 -380.151386) (xy 292.299224 -380.161559) (xy 292.291441 -380.180357)
			(xy 292.277054 -380.194743) (xy 292.258255 -380.202525) (xy 292.248082 -380.202948) (xy 291.531802 -380.202948)
			(xy 291.521629 -380.202534) (xy 291.502831 -380.194747) (xy 291.488446 -380.180358) (xy 291.480663 -380.161559)
			(xy 291.48024 -380.151386) (xy 291.48024 -379.993398) (xy 291.479822 -379.984212) (xy 291.473313 -379.967028)
			(xy 291.46754 -379.95987) (xy 291.445798 -379.934181) (xy 291.407847 -379.878599) (xy 291.376812 -379.818881)
			(xy 291.353137 -379.755881) (xy 291.337161 -379.690504) (xy 291.329113 -379.623685) (xy 291.329109 -379.556384)
			(xy 291.337148 -379.489564) (xy 291.353116 -379.424185) (xy 291.376784 -379.361182) (xy 291.407812 -379.30146)
			(xy 291.445755 -379.245874) (xy 291.46754 -379.220222) (xy 291.473357 -379.213092) (xy 291.479859 -379.19589)
			(xy 291.48024 -379.186694) (xy 291.48024 -378.693426) (xy 291.479809 -378.684241) (xy 291.473309 -378.667057)
			(xy 291.46754 -378.659898) (xy 291.445727 -378.634267) (xy 291.407778 -378.578678) (xy 291.376746 -378.518951)
			(xy 291.353075 -378.455944) (xy 291.337104 -378.390559) (xy 291.329062 -378.323734) (xy 288.051024 -378.323734)
			(xy 288.051024 -378.323792) (xy 288.04295 -378.390729) (xy 288.026915 -378.456218) (xy 288.003152 -378.519314)
			(xy 287.972001 -378.579109) (xy 287.933912 -378.634742) (xy 287.912048 -378.660406) (xy 287.90626 -378.667557)
			(xy 287.899742 -378.684743) (xy 287.899348 -378.693934) (xy 287.899348 -379.186186) (xy 287.899776 -379.195371)
			(xy 287.906279 -379.212555) (xy 287.912048 -379.219714) (xy 287.933959 -379.245341) (xy 287.97205 -379.30098)
			(xy 288.003201 -379.360781) (xy 288.026965 -379.423883) (xy 288.042999 -379.489377) (xy 288.051072 -379.55632)
			(xy 288.051068 -379.623749) (xy 288.042987 -379.690691) (xy 288.026945 -379.756183) (xy 288.003173 -379.819282)
			(xy 287.972014 -379.879079) (xy 287.933917 -379.934714) (xy 287.912048 -379.960378) (xy 287.906229 -379.967507)
			(xy 287.899729 -379.98471) (xy 287.899348 -379.993906) (xy 287.899348 -380.151386) (xy 287.898862 -380.161513)
			(xy 287.891136 -380.180236) (xy 287.87685 -380.194594) (xy 287.858165 -380.202411) (xy 287.84804 -380.202948)
			(xy 287.13176 -380.202948) (xy 287.121655 -380.202449) (xy 287.102985 -380.194707) (xy 287.088693 -380.180415)
			(xy 287.080951 -380.161745) (xy 287.080452 -380.15164) (xy 287.080452 -379.993906) (xy 287.080027 -379.984721)
			(xy 287.073523 -379.967537) (xy 287.067752 -379.960378) (xy 287.045931 -379.934676) (xy 287.007838 -379.879048)
			(xy 286.976682 -379.819258) (xy 286.952913 -379.756165) (xy 286.936873 -379.69068) (xy 286.928793 -379.623745)
			(xy 286.928788 -379.556324) (xy 286.936861 -379.489388) (xy 286.952893 -379.423901) (xy 286.976654 -379.360806)
			(xy 287.007802 -379.301011) (xy 287.045889 -379.245378) (xy 287.067752 -379.219714) (xy 287.073574 -379.212587)
			(xy 287.080072 -379.195382) (xy 287.080452 -379.186186) (xy 287.080452 -378.693934) (xy 287.080014 -378.68475)
			(xy 287.073519 -378.667566) (xy 287.067752 -378.660406) (xy 287.045861 -378.634763) (xy 287.007769 -378.579126)
			(xy 286.976617 -378.519328) (xy 286.952852 -378.456228) (xy 286.936817 -378.390735) (xy 286.928742 -378.323794)
			(xy 274.077801 -378.323794) (xy 274.085782 -378.367343) (xy 274.101882 -378.499931) (xy 274.109946 -378.633249)
			(xy 274.11045 -378.70003) (xy 274.109946 -378.766811) (xy 274.101882 -378.900129) (xy 274.085782 -379.032717)
			(xy 274.061707 -379.164091) (xy 274.029744 -379.293772) (xy 273.990009 -379.421286) (xy 273.942647 -379.546169)
			(xy 273.887832 -379.667964) (xy 273.825762 -379.786227) (xy 273.756666 -379.900526) (xy 273.680794 -380.010446)
			(xy 273.598424 -380.115583) (xy 273.509856 -380.215556) (xy 273.415414 -380.309998) (xy 273.315441 -380.398566)
			(xy 273.210304 -380.480936) (xy 273.100384 -380.556808) (xy 272.986085 -380.625904) (xy 272.92786 -380.656463)
			(xy 289.128932 -380.656463) (xy 289.136975 -380.589641) (xy 289.152947 -380.524259) (xy 289.17662 -380.461255)
			(xy 289.207654 -380.401532) (xy 289.245604 -380.345947) (xy 289.267392 -380.320296) (xy 289.273172 -380.313139)
			(xy 289.279697 -380.295958) (xy 289.280092 -380.286768) (xy 289.280092 -379.7935) (xy 289.279684 -379.784313)
			(xy 289.273169 -379.767128) (xy 289.267392 -379.759972) (xy 289.24565 -379.734282) (xy 289.207696 -379.678702)
			(xy 289.176658 -379.618984) (xy 289.15298 -379.555985) (xy 289.137002 -379.490606) (xy 289.128953 -379.423787)
			(xy 289.128949 -379.356485) (xy 289.136989 -379.289665) (xy 289.152959 -379.224284) (xy 289.176628 -379.161282)
			(xy 289.207659 -379.10156) (xy 289.245606 -379.045975) (xy 289.267392 -379.020324) (xy 289.273202 -379.013189)
			(xy 289.279709 -378.995991) (xy 289.280092 -378.986796) (xy 289.280092 -378.828554) (xy 289.280595 -378.818399)
			(xy 289.288376 -378.799638) (xy 289.302738 -378.785276) (xy 289.321499 -378.777495) (xy 289.331654 -378.776992)
			(xy 290.047934 -378.776992) (xy 290.058088 -378.777504) (xy 290.076849 -378.785281) (xy 290.091212 -378.799641)
			(xy 290.098993 -378.8184) (xy 290.099496 -378.828554) (xy 290.099496 -378.986796) (xy 290.099909 -378.995983)
			(xy 290.106421 -379.013167) (xy 290.112196 -379.020324) (xy 290.13403 -379.045938) (xy 290.171975 -379.101531)
			(xy 290.203004 -379.16126) (xy 290.226673 -379.224269) (xy 290.242641 -379.289656) (xy 290.250681 -379.356482)
			(xy 290.250677 -379.42379) (xy 290.242628 -379.490615) (xy 290.226651 -379.556) (xy 290.202975 -379.619006)
			(xy 290.171938 -379.678731) (xy 290.133986 -379.734319) (xy 290.112196 -379.759972) (xy 290.106386 -379.767108)
			(xy 290.099879 -379.784305) (xy 290.099496 -379.7935) (xy 290.099496 -380.286768) (xy 290.099922 -380.295953)
			(xy 290.106425 -380.313138) (xy 290.112196 -380.320296) (xy 290.134002 -380.345932) (xy 290.171948 -380.401522)
			(xy 290.202979 -380.461248) (xy 290.226649 -380.524255) (xy 290.242619 -380.589638) (xy 290.250654 -380.656404)
			(xy 293.528724 -380.656404) (xy 293.536798 -380.589467) (xy 293.552831 -380.52398) (xy 293.576592 -380.460884)
			(xy 293.60774 -380.401088) (xy 293.645826 -380.345453) (xy 293.667688 -380.319788) (xy 293.673471 -380.312633)
			(xy 293.679994 -380.29545) (xy 293.680388 -380.28626) (xy 293.680388 -379.794008) (xy 293.679977 -379.784821)
			(xy 293.673464 -379.767636) (xy 293.667688 -379.76048) (xy 293.645872 -379.734776) (xy 293.607782 -379.679146)
			(xy 293.57663 -379.619356) (xy 293.552864 -379.556264) (xy 293.536825 -379.49078) (xy 293.528746 -379.423846)
			(xy 293.528741 -379.356426) (xy 293.536812 -379.289491) (xy 293.552842 -379.224005) (xy 293.576601 -379.16091)
			(xy 293.607745 -379.101115) (xy 293.645827 -379.045481) (xy 293.667688 -379.019816) (xy 293.673501 -379.012683)
			(xy 293.680006 -378.995483) (xy 293.680388 -378.986288) (xy 293.680388 -378.828554) (xy 293.680887 -378.818431)
			(xy 293.688621 -378.799718) (xy 293.702902 -378.785366) (xy 293.721575 -378.777539) (xy 293.731696 -378.776992)
			(xy 294.447976 -378.776992) (xy 294.458096 -378.777435) (xy 294.476798 -378.785174) (xy 294.491112 -378.799482)
			(xy 294.49886 -378.81818) (xy 294.499284 -378.8283) (xy 294.499284 -378.986288) (xy 294.499704 -378.995474)
			(xy 294.506211 -379.012658) (xy 294.511984 -379.019816) (xy 294.533896 -379.045442) (xy 294.571984 -379.101082)
			(xy 294.603134 -379.160883) (xy 294.626896 -379.223985) (xy 294.642928 -379.289479) (xy 294.651001 -379.356422)
			(xy 294.650996 -379.42385) (xy 294.642915 -379.490792) (xy 294.626874 -379.556284) (xy 294.603104 -379.619383)
			(xy 294.571947 -379.67918) (xy 294.533851 -379.734815) (xy 294.511984 -379.76048) (xy 294.506169 -379.767612)
			(xy 294.499666 -379.784813) (xy 294.499284 -379.794008) (xy 294.499284 -380.28626) (xy 294.499717 -380.295445)
			(xy 294.506215 -380.312629) (xy 294.511984 -380.319788) (xy 294.533868 -380.345437) (xy 294.571957 -380.401073)
			(xy 294.603108 -380.460872) (xy 294.626872 -380.523971) (xy 294.642906 -380.589462) (xy 294.650981 -380.656402)
			(xy 294.650981 -380.656463) (xy 297.92902 -380.656463) (xy 297.937062 -380.589641) (xy 297.953034 -380.52426)
			(xy 297.976707 -380.461256) (xy 298.00774 -380.401533) (xy 298.045688 -380.345948) (xy 298.067476 -380.320296)
			(xy 298.073254 -380.313137) (xy 298.079781 -380.295957) (xy 298.080176 -380.286768) (xy 298.080176 -379.7935)
			(xy 298.079771 -379.784312) (xy 298.073254 -379.767128) (xy 298.067476 -379.759972) (xy 298.045734 -379.734282)
			(xy 298.007782 -379.678701) (xy 297.976744 -379.618984) (xy 297.953067 -379.555984) (xy 297.93709 -379.490606)
			(xy 297.929041 -379.423787) (xy 297.929037 -379.356485) (xy 297.937077 -379.289665) (xy 297.953046 -379.224285)
			(xy 297.976715 -379.161283) (xy 298.007745 -379.101561) (xy 298.04569 -379.045976) (xy 298.067476 -379.020324)
			(xy 298.073285 -379.013187) (xy 298.079793 -378.99599) (xy 298.080176 -378.986796) (xy 298.080176 -378.828554)
			(xy 298.080597 -378.818389) (xy 298.088393 -378.799611) (xy 298.102782 -378.785246) (xy 298.121572 -378.77748)
			(xy 298.131738 -378.776992) (xy 298.848018 -378.776992) (xy 298.858171 -378.777517) (xy 298.876932 -378.785289)
			(xy 298.891295 -378.799644) (xy 298.899077 -378.818401) (xy 298.89958 -378.828554) (xy 298.89958 -378.986796)
			(xy 298.899996 -378.995982) (xy 298.906506 -379.013167) (xy 298.91228 -379.020324) (xy 298.934114 -379.045938)
			(xy 298.972061 -379.10153) (xy 299.003091 -379.161259) (xy 299.02676 -379.224269) (xy 299.042729 -379.289655)
			(xy 299.050769 -379.356482) (xy 299.050765 -379.42379) (xy 299.042716 -379.490616) (xy 299.026739 -379.556)
			(xy 299.003061 -379.619007) (xy 298.972023 -379.678732) (xy 298.93407 -379.73432) (xy 298.91228 -379.759972)
			(xy 298.906468 -379.767106) (xy 298.899963 -379.784305) (xy 298.89958 -379.7935) (xy 298.89958 -380.286768)
			(xy 298.90001 -380.295953) (xy 298.90651 -380.313137) (xy 298.91228 -380.320296) (xy 298.934087 -380.345932)
			(xy 298.972034 -380.401521) (xy 299.003065 -380.461247) (xy 299.026736 -380.524254) (xy 299.042707 -380.589638)
			(xy 299.050742 -380.656404) (xy 302.328812 -380.656404) (xy 302.336886 -380.589468) (xy 302.352918 -380.52398)
			(xy 302.376679 -380.460884) (xy 302.407826 -380.401089) (xy 302.44591 -380.345454) (xy 302.467772 -380.319788)
			(xy 302.473565 -380.312641) (xy 302.48008 -380.295451) (xy 302.480472 -380.28626) (xy 302.480472 -379.794008)
			(xy 302.480064 -379.78482) (xy 302.47355 -379.767636) (xy 302.467772 -379.76048) (xy 302.445956 -379.734775)
			(xy 302.407868 -379.679146) (xy 302.376717 -379.619355) (xy 302.352951 -379.556263) (xy 302.336913 -379.490779)
			(xy 302.328834 -379.423846) (xy 302.328829 -379.356426) (xy 302.3369 -379.289492) (xy 302.35293 -379.224006)
			(xy 302.376687 -379.160911) (xy 302.407831 -379.101116) (xy 302.445912 -379.045482) (xy 302.467772 -379.019816)
			(xy 302.473595 -379.01269) (xy 302.480092 -378.995485) (xy 302.480472 -378.986288) (xy 302.480472 -378.828554)
			(xy 302.48089 -378.81842) (xy 302.488639 -378.799692) (xy 302.502946 -378.785336) (xy 302.521648 -378.777525)
			(xy 302.53178 -378.776992) (xy 303.24806 -378.776992) (xy 303.258211 -378.777454) (xy 303.27696 -378.785235)
			(xy 303.291285 -378.79962) (xy 303.298987 -378.818402) (xy 303.299368 -378.828554) (xy 303.299368 -378.986288)
			(xy 303.299791 -378.995474) (xy 303.306296 -379.012658) (xy 303.312068 -379.019816) (xy 303.33398 -379.045442)
			(xy 303.37207 -379.101081) (xy 303.40322 -379.160883) (xy 303.426983 -379.223985) (xy 303.443016 -379.289479)
			(xy 303.451089 -379.356422) (xy 303.451084 -379.42385) (xy 303.443003 -379.490792) (xy 303.426962 -379.556284)
			(xy 303.403191 -379.619383) (xy 303.372032 -379.679181) (xy 303.333936 -379.734815) (xy 303.312068 -379.76048)
			(xy 303.306251 -379.76761) (xy 303.299749 -379.784812) (xy 303.299368 -379.794008) (xy 303.299368 -380.28626)
			(xy 303.299805 -380.295444) (xy 303.306301 -380.312628) (xy 303.312068 -380.319788) (xy 303.333953 -380.345436)
			(xy 303.372043 -380.401073) (xy 303.403195 -380.460871) (xy 303.426959 -380.52397) (xy 303.442994 -380.589461)
			(xy 303.451069 -380.656402) (xy 303.451069 -380.656404) (xy 333.128842 -380.656404) (xy 333.136916 -380.589467)
			(xy 333.15295 -380.523979) (xy 333.176713 -380.460883) (xy 333.207862 -380.401087) (xy 333.245949 -380.345453)
			(xy 333.267812 -380.319788) (xy 333.273598 -380.312635) (xy 333.280118 -380.29545) (xy 333.280512 -380.28626)
			(xy 333.280512 -379.794008) (xy 333.280095 -379.784822) (xy 333.273586 -379.767637) (xy 333.267812 -379.76048)
			(xy 333.245995 -379.734776) (xy 333.207904 -379.679147) (xy 333.17675 -379.619357) (xy 333.152983 -379.556265)
			(xy 333.136944 -379.49078) (xy 333.128864 -379.423846) (xy 333.12886 -379.356426) (xy 333.136931 -379.289491)
			(xy 333.152962 -379.224004) (xy 333.176721 -379.160909) (xy 333.207867 -379.101115) (xy 333.24595 -379.045481)
			(xy 333.267812 -379.019816) (xy 333.273628 -379.012685) (xy 333.280131 -378.995483) (xy 333.280512 -378.986288)
			(xy 333.280512 -378.828554) (xy 333.280988 -378.818428) (xy 333.288726 -378.799711) (xy 333.303015 -378.785357)
			(xy 333.321696 -378.777535) (xy 333.33182 -378.776992) (xy 334.0481 -378.776992) (xy 334.058253 -378.777422)
			(xy 334.077004 -378.785216) (xy 334.091327 -378.79961) (xy 334.099028 -378.818399) (xy 334.099408 -378.828554)
			(xy 334.099408 -378.986288) (xy 334.099822 -378.995475) (xy 334.106333 -379.012659) (xy 334.112108 -379.019816)
			(xy 334.134019 -379.045442) (xy 334.172106 -379.101083) (xy 334.203254 -379.160884) (xy 334.227015 -379.223986)
			(xy 334.243047 -379.28948) (xy 334.251119 -379.356422) (xy 334.251114 -379.42385) (xy 334.243034 -379.490791)
			(xy 334.226994 -379.556283) (xy 334.203224 -379.619382) (xy 334.172068 -379.679179) (xy 334.133975 -379.734815)
			(xy 334.112108 -379.76048) (xy 334.106296 -379.767614) (xy 334.09979 -379.784813) (xy 334.099408 -379.794008)
			(xy 334.099408 -380.28626) (xy 334.099836 -380.295445) (xy 334.106337 -380.31263) (xy 334.112108 -380.319788)
			(xy 334.133991 -380.345437) (xy 334.172079 -380.401074) (xy 334.203228 -380.460873) (xy 334.226991 -380.523972)
			(xy 334.243025 -380.589463) (xy 334.251099 -380.656402) (xy 334.251099 -380.656464) (xy 337.529162 -380.656464)
			(xy 337.537203 -380.589643) (xy 337.553173 -380.524262) (xy 337.576842 -380.461259) (xy 337.607871 -380.401536)
			(xy 337.645815 -380.345949) (xy 337.6676 -380.320296) (xy 337.673381 -380.31314) (xy 337.679905 -380.295958)
			(xy 337.6803 -380.286768) (xy 337.6803 -379.7935) (xy 337.67989 -379.784313) (xy 337.673376 -379.767129)
			(xy 337.6676 -379.759972) (xy 337.645861 -379.734281) (xy 337.607913 -379.678699) (xy 337.57688 -379.61898)
			(xy 337.553206 -379.555981) (xy 337.537231 -379.490604) (xy 337.529183 -379.423786) (xy 337.529179 -379.356486)
			(xy 337.537218 -379.289667) (xy 337.553185 -379.224288) (xy 337.57685 -379.161286) (xy 337.607876 -379.101563)
			(xy 337.645816 -379.045977) (xy 337.6676 -379.020324) (xy 337.673411 -379.013189) (xy 337.679917 -378.995991)
			(xy 337.6803 -378.986796) (xy 337.6803 -378.828554) (xy 337.680795 -378.818398) (xy 337.688577 -378.799635)
			(xy 337.702942 -378.785273) (xy 337.721706 -378.777493) (xy 337.731862 -378.776992) (xy 338.448142 -378.776992)
			(xy 338.458297 -378.777498) (xy 338.477058 -378.785278) (xy 338.49142 -378.799639) (xy 338.499201 -378.818399)
			(xy 338.499704 -378.828554) (xy 338.499704 -378.986796) (xy 338.500115 -378.995983) (xy 338.506628 -379.013167)
			(xy 338.512404 -379.020324) (xy 338.534237 -379.045938) (xy 338.572182 -379.101531) (xy 338.603211 -379.16126)
			(xy 338.626879 -379.22427) (xy 338.642847 -379.289656) (xy 338.650887 -379.356482) (xy 338.650883 -379.42379)
			(xy 338.642834 -379.490615) (xy 338.626858 -379.556) (xy 338.603181 -379.619006) (xy 338.572145 -379.678731)
			(xy 338.534193 -379.734319) (xy 338.512404 -379.759972) (xy 338.506595 -379.767108) (xy 338.500088 -379.784306)
			(xy 338.499704 -379.7935) (xy 338.499704 -380.286768) (xy 338.500129 -380.295954) (xy 338.506632 -380.313138)
			(xy 338.512404 -380.320296) (xy 338.53421 -380.345933) (xy 338.572155 -380.401522) (xy 338.603185 -380.461248)
			(xy 338.626855 -380.524255) (xy 338.642826 -380.589639) (xy 338.65086 -380.656404) (xy 341.92893 -380.656404)
			(xy 341.937004 -380.589467) (xy 341.953037 -380.523979) (xy 341.976799 -380.460883) (xy 342.007947 -380.401088)
			(xy 342.046033 -380.345453) (xy 342.067896 -380.319788) (xy 342.07368 -380.312634) (xy 342.080202 -380.29545)
			(xy 342.080596 -380.28626) (xy 342.080596 -379.794008) (xy 342.080183 -379.784821) (xy 342.073671 -379.767637)
			(xy 342.067896 -379.76048) (xy 342.046079 -379.734776) (xy 342.007989 -379.679147) (xy 341.976837 -379.619356)
			(xy 341.95307 -379.556264) (xy 341.937032 -379.49078) (xy 341.928952 -379.423846) (xy 341.928948 -379.356426)
			(xy 341.937019 -379.289491) (xy 341.953049 -379.224005) (xy 341.976807 -379.16091) (xy 342.007952 -379.101115)
			(xy 342.046035 -379.045481) (xy 342.067896 -379.019816) (xy 342.07371 -379.012683) (xy 342.080215 -378.995483)
			(xy 342.080596 -378.986288) (xy 342.080596 -378.828554) (xy 342.081088 -378.81843) (xy 342.088822 -378.799716)
			(xy 342.103106 -378.785363) (xy 342.121782 -378.777538) (xy 342.131904 -378.776992) (xy 342.848184 -378.776992)
			(xy 342.858336 -378.777434) (xy 342.877087 -378.785223) (xy 342.89141 -378.799614) (xy 342.899112 -378.8184)
			(xy 342.899492 -378.828554) (xy 342.899492 -378.986288) (xy 342.89991 -378.995474) (xy 342.906418 -379.012659)
			(xy 342.912192 -379.019816) (xy 342.934103 -379.045442) (xy 342.972191 -379.101082) (xy 343.00334 -379.160884)
			(xy 343.027102 -379.223986) (xy 343.043135 -379.28948) (xy 343.051207 -379.356422) (xy 343.051202 -379.42385)
			(xy 343.043122 -379.490792) (xy 343.027081 -379.556283) (xy 343.003311 -379.619382) (xy 342.972154 -379.67918)
			(xy 342.934059 -379.734815) (xy 342.912192 -379.76048) (xy 342.906378 -379.767613) (xy 342.899874 -379.784813)
			(xy 342.899492 -379.794008) (xy 342.899492 -380.28626) (xy 342.899923 -380.295445) (xy 342.906422 -380.312629)
			(xy 342.912192 -380.319788) (xy 342.934076 -380.345437) (xy 342.972165 -380.401074) (xy 343.003315 -380.460872)
			(xy 343.027078 -380.523971) (xy 343.043113 -380.589462) (xy 343.051187 -380.656402) (xy 343.051187 -380.656463)
			(xy 346.329226 -380.656463) (xy 346.337269 -380.589641) (xy 346.353241 -380.524259) (xy 346.376913 -380.461255)
			(xy 346.407947 -380.401533) (xy 346.445896 -380.345948) (xy 346.467684 -380.320296) (xy 346.473463 -380.313138)
			(xy 346.479989 -380.295957) (xy 346.480384 -380.286768) (xy 346.480384 -379.7935) (xy 346.479977 -379.784312)
			(xy 346.473462 -379.767128) (xy 346.467684 -379.759972) (xy 346.445942 -379.734282) (xy 346.407989 -379.678702)
			(xy 346.376951 -379.618984) (xy 346.353274 -379.555984) (xy 346.337296 -379.490606) (xy 346.329247 -379.423787)
			(xy 346.329243 -379.356485) (xy 346.337283 -379.289665) (xy 346.353252 -379.224285) (xy 346.376922 -379.161282)
			(xy 346.407952 -379.10156) (xy 346.445898 -379.045976) (xy 346.467684 -379.020324) (xy 346.473493 -379.013188)
			(xy 346.480001 -378.99599) (xy 346.480384 -378.986796) (xy 346.480384 -378.828554) (xy 346.480797 -378.818388)
			(xy 346.488595 -378.799609) (xy 346.502986 -378.785243) (xy 346.521779 -378.777479) (xy 346.531946 -378.776992)
			(xy 347.248226 -378.776992) (xy 347.25838 -378.777511) (xy 347.277141 -378.785285) (xy 347.291504 -378.799642)
			(xy 347.299285 -378.8184) (xy 347.299788 -378.828554) (xy 347.299788 -378.986796) (xy 347.300203 -378.995983)
			(xy 347.306714 -379.013167) (xy 347.312488 -379.020324) (xy 347.334322 -379.045938) (xy 347.372268 -379.10153)
			(xy 347.403297 -379.161259) (xy 347.426966 -379.224269) (xy 347.442935 -379.289656) (xy 347.450975 -379.356482)
			(xy 347.450971 -379.42379) (xy 347.442922 -379.490616) (xy 347.426945 -379.556) (xy 347.403268 -379.619007)
			(xy 347.372231 -379.678732) (xy 347.334278 -379.734319) (xy 347.312488 -379.759972) (xy 347.306677 -379.767107)
			(xy 347.300171 -379.784305) (xy 347.299788 -379.7935) (xy 347.299788 -380.286768) (xy 347.300216 -380.295953)
			(xy 347.306718 -380.313138) (xy 347.312488 -380.320296) (xy 347.334295 -380.345932) (xy 347.372241 -380.401522)
			(xy 347.403272 -380.461248) (xy 347.426942 -380.524254) (xy 347.442913 -380.589638) (xy 347.450948 -380.656404)
			(xy 377.128751 -380.656404) (xy 377.136826 -380.589466) (xy 377.15286 -380.523978) (xy 377.176623 -380.460882)
			(xy 377.207772 -380.401087) (xy 377.24586 -380.345453) (xy 377.267724 -380.319788) (xy 377.273511 -380.312636)
			(xy 377.280031 -380.295451) (xy 377.280424 -380.28626) (xy 377.280424 -379.794008) (xy 377.280005 -379.784822)
			(xy 377.273497 -379.767638) (xy 377.267724 -379.76048) (xy 377.245906 -379.734776) (xy 377.207815 -379.679148)
			(xy 377.17666 -379.619357) (xy 377.152893 -379.556265) (xy 377.136853 -379.490781) (xy 377.128773 -379.423846)
			(xy 377.128769 -379.356426) (xy 377.13684 -379.28949) (xy 377.152871 -379.224004) (xy 377.176631 -379.160909)
			(xy 377.207777 -379.101114) (xy 377.245862 -379.045481) (xy 377.267724 -379.019816) (xy 377.273542 -379.012686)
			(xy 377.280043 -378.995484) (xy 377.280424 -378.986288) (xy 377.280424 -378.828554) (xy 377.280888 -378.818426)
			(xy 377.288628 -378.799707) (xy 377.302921 -378.785353) (xy 377.321607 -378.777533) (xy 377.331732 -378.776992)
			(xy 378.048012 -378.776992) (xy 378.058166 -378.777411) (xy 378.076917 -378.785209) (xy 378.09124 -378.799607)
			(xy 378.098941 -378.818398) (xy 378.09932 -378.828554) (xy 378.09932 -378.986288) (xy 378.099731 -378.995475)
			(xy 378.106244 -379.01266) (xy 378.11202 -379.019816) (xy 378.13393 -379.045443) (xy 378.172016 -379.101083)
			(xy 378.203164 -379.160885) (xy 378.226924 -379.223987) (xy 378.242956 -379.28948) (xy 378.251028 -379.356423)
			(xy 378.251023 -379.42385) (xy 378.242943 -379.490791) (xy 378.226903 -379.556282) (xy 378.203134 -379.619381)
			(xy 378.171979 -379.679179) (xy 378.133886 -379.734814) (xy 378.11202 -379.76048) (xy 378.106209 -379.767615)
			(xy 378.099702 -379.784813) (xy 378.09932 -379.794008) (xy 378.09932 -380.28626) (xy 378.099745 -380.295446)
			(xy 378.106248 -380.312631) (xy 378.11202 -380.319788) (xy 378.133903 -380.345437) (xy 378.17199 -380.401075)
			(xy 378.203138 -380.460873) (xy 378.226901 -380.523972) (xy 378.242934 -380.589463) (xy 378.251008 -380.656403)
			(xy 378.251008 -380.656464) (xy 381.529071 -380.656464) (xy 381.537113 -380.589643) (xy 381.553083 -380.524262)
			(xy 381.576752 -380.461258) (xy 381.607782 -380.401535) (xy 381.645726 -380.345948) (xy 381.667512 -380.320296)
			(xy 381.673294 -380.313141) (xy 381.679817 -380.295958) (xy 381.680212 -380.286768) (xy 381.680212 -379.7935)
			(xy 381.679799 -379.784313) (xy 381.673287 -379.767129) (xy 381.667512 -379.759972) (xy 381.645773 -379.73428)
			(xy 381.607824 -379.678699) (xy 381.57679 -379.618981) (xy 381.553116 -379.555981) (xy 381.537141 -379.490604)
			(xy 381.529093 -379.423786) (xy 381.529089 -379.356486) (xy 381.537128 -379.289667) (xy 381.553095 -379.224288)
			(xy 381.576761 -379.161285) (xy 381.607787 -379.101563) (xy 381.645728 -379.045977) (xy 381.667512 -379.020324)
			(xy 381.673325 -379.01319) (xy 381.679829 -378.995991) (xy 381.680212 -378.986796) (xy 381.680212 -378.828554)
			(xy 381.680695 -378.818397) (xy 381.68848 -378.799631) (xy 381.702848 -378.785269) (xy 381.721616 -378.777491)
			(xy 381.731774 -378.776992) (xy 382.448054 -378.776992) (xy 382.458203 -378.77757) (xy 382.476962 -378.785321)
			(xy 382.491328 -378.79966) (xy 382.499112 -378.818406) (xy 382.499616 -378.828554) (xy 382.499616 -378.986796)
			(xy 382.500025 -378.995983) (xy 382.506539 -379.013168) (xy 382.512316 -379.020324) (xy 382.534153 -379.045936)
			(xy 382.572103 -379.101528) (xy 382.603137 -379.161256) (xy 382.626809 -379.224266) (xy 382.64278 -379.289654)
			(xy 382.650821 -379.356481) (xy 382.650816 -379.423791) (xy 382.642767 -379.490618) (xy 382.626787 -379.556003)
			(xy 382.603107 -379.61901) (xy 382.572066 -379.678734) (xy 382.534108 -379.734321) (xy 382.512316 -379.759972)
			(xy 382.506508 -379.767109) (xy 382.5 -379.784306) (xy 382.499616 -379.7935) (xy 382.499616 -380.286768)
			(xy 382.500038 -380.295954) (xy 382.506543 -380.313139) (xy 382.512316 -380.320296) (xy 382.534125 -380.345931)
			(xy 382.572076 -380.401519) (xy 382.603111 -380.461245) (xy 382.626784 -380.524251) (xy 382.642757 -380.589636)
			(xy 382.650793 -380.656404) (xy 385.928839 -380.656404) (xy 385.936913 -380.589467) (xy 385.952947 -380.523979)
			(xy 385.976709 -380.460883) (xy 386.007858 -380.401087) (xy 386.045945 -380.345453) (xy 386.067808 -380.319788)
			(xy 386.073593 -380.312635) (xy 386.080114 -380.29545) (xy 386.080508 -380.28626) (xy 386.080508 -379.794008)
			(xy 386.080092 -379.784821) (xy 386.073582 -379.767637) (xy 386.067808 -379.76048) (xy 386.045991 -379.734776)
			(xy 386.0079 -379.679147) (xy 385.976747 -379.619356) (xy 385.95298 -379.556265) (xy 385.936941 -379.49078)
			(xy 385.928861 -379.423846) (xy 385.928857 -379.356426) (xy 385.936928 -379.289491) (xy 385.952958 -379.224004)
			(xy 385.976718 -379.160909) (xy 386.007863 -379.101115) (xy 386.045947 -379.045481) (xy 386.067808 -379.019816)
			(xy 386.073624 -379.012684) (xy 386.080127 -378.995483) (xy 386.080508 -378.986288) (xy 386.080508 -378.828554)
			(xy 386.080988 -378.818428) (xy 386.088725 -378.799712) (xy 386.103012 -378.785359) (xy 386.121693 -378.777535)
			(xy 386.131816 -378.776992) (xy 386.848096 -378.776992) (xy 386.858249 -378.777425) (xy 386.877 -378.785218)
			(xy 386.891323 -378.799611) (xy 386.899024 -378.818399) (xy 386.899404 -378.828554) (xy 386.899404 -378.986288)
			(xy 386.899819 -378.995475) (xy 386.906329 -379.012659) (xy 386.912104 -379.019816) (xy 386.934015 -379.045442)
			(xy 386.972102 -379.101083) (xy 387.00325 -379.160884) (xy 387.027012 -379.223986) (xy 387.043044 -379.28948)
			(xy 387.051116 -379.356422) (xy 387.051111 -379.42385) (xy 387.043031 -379.490791) (xy 387.02699 -379.556283)
			(xy 387.003221 -379.619382) (xy 386.972065 -379.679179) (xy 386.933971 -379.734815) (xy 386.912104 -379.76048)
			(xy 386.906291 -379.767614) (xy 386.899786 -379.784813) (xy 386.899404 -379.794008) (xy 386.899404 -380.28626)
			(xy 386.899832 -380.295445) (xy 386.906333 -380.31263) (xy 386.912104 -380.319788) (xy 386.933987 -380.345437)
			(xy 386.972075 -380.401074) (xy 387.003225 -380.460872) (xy 387.026988 -380.523971) (xy 387.043022 -380.589462)
			(xy 387.051096 -380.656402) (xy 387.051096 -380.656464) (xy 390.329159 -380.656464) (xy 390.3372 -380.589643)
			(xy 390.35317 -380.524263) (xy 390.376839 -380.461259) (xy 390.407867 -380.401536) (xy 390.445811 -380.345949)
			(xy 390.467596 -380.320296) (xy 390.473376 -380.313139) (xy 390.479901 -380.295958) (xy 390.480296 -380.286768)
			(xy 390.480296 -379.7935) (xy 390.479887 -379.784313) (xy 390.473372 -379.767128) (xy 390.467596 -379.759972)
			(xy 390.445857 -379.73428) (xy 390.407909 -379.678699) (xy 390.376876 -379.61898) (xy 390.353203 -379.555981)
			(xy 390.337228 -379.490604) (xy 390.32918 -379.423786) (xy 390.329176 -379.356486) (xy 390.337215 -379.289667)
			(xy 390.353181 -379.224288) (xy 390.376847 -379.161286) (xy 390.407872 -379.101563) (xy 390.445812 -379.045977)
			(xy 390.467596 -379.020324) (xy 390.473407 -379.013189) (xy 390.479913 -378.995991) (xy 390.480296 -378.986796)
			(xy 390.480296 -378.828554) (xy 390.480795 -378.818398) (xy 390.488576 -378.799636) (xy 390.50294 -378.785274)
			(xy 390.521702 -378.777494) (xy 390.531858 -378.776992) (xy 391.248138 -378.776992) (xy 391.258293 -378.777501)
			(xy 391.277054 -378.785279) (xy 391.291416 -378.79964) (xy 391.299197 -378.8184) (xy 391.2997 -378.828554)
			(xy 391.2997 -378.986796) (xy 391.300112 -378.995983) (xy 391.306625 -379.013167) (xy 391.3124 -379.020324)
			(xy 391.334234 -379.045938) (xy 391.372178 -379.101531) (xy 391.403207 -379.16126) (xy 391.426876 -379.224269)
			(xy 391.442844 -379.289656) (xy 391.450884 -379.356482) (xy 391.45088 -379.42379) (xy 391.442831 -379.490615)
			(xy 391.426855 -379.556) (xy 391.403178 -379.619006) (xy 391.372141 -379.678731) (xy 391.334189 -379.734319)
			(xy 391.3124 -379.759972) (xy 391.30659 -379.767108) (xy 391.300083 -379.784306) (xy 391.2997 -379.7935)
			(xy 391.2997 -380.286768) (xy 391.300126 -380.295954) (xy 391.306629 -380.313138) (xy 391.3124 -380.320296)
			(xy 391.334206 -380.345933) (xy 391.372152 -380.401522) (xy 391.403182 -380.461248) (xy 391.426852 -380.524255)
			(xy 391.442822 -380.589638) (xy 391.450857 -380.656404) (xy 421.12866 -380.656404) (xy 421.136735 -380.589466)
			(xy 421.152769 -380.523978) (xy 421.176533 -380.460881) (xy 421.207683 -380.401086) (xy 421.245772 -380.345453)
			(xy 421.267636 -380.319788) (xy 421.273425 -380.312637) (xy 421.279943 -380.295451) (xy 421.280336 -380.28626)
			(xy 421.280336 -379.794008) (xy 421.279914 -379.784822) (xy 421.273408 -379.767638) (xy 421.267636 -379.76048)
			(xy 421.245818 -379.734776) (xy 421.207725 -379.679148) (xy 421.176571 -379.619358) (xy 421.152802 -379.556266)
			(xy 421.136762 -379.490781) (xy 421.128682 -379.423846) (xy 421.128678 -379.356426) (xy 421.136749 -379.28949)
			(xy 421.152781 -379.224003) (xy 421.176541 -379.160908) (xy 421.207688 -379.101114) (xy 421.245774 -379.045481)
			(xy 421.267636 -379.019816) (xy 421.273455 -379.012687) (xy 421.279956 -378.995484) (xy 421.280336 -378.986288)
			(xy 421.280336 -378.828554) (xy 421.280789 -378.818425) (xy 421.288531 -378.799703) (xy 421.302827 -378.785349)
			(xy 421.321517 -378.777531) (xy 421.331644 -378.776992) (xy 422.047924 -378.776992) (xy 422.058033 -378.777465)
			(xy 422.076711 -378.785209) (xy 422.091004 -378.79951) (xy 422.09874 -378.81819) (xy 422.099232 -378.8283)
			(xy 422.099232 -378.986288) (xy 422.099663 -378.995473) (xy 422.106164 -379.012656) (xy 422.111932 -379.019816)
			(xy 422.133842 -379.045443) (xy 422.171927 -379.101084) (xy 422.203074 -379.160885) (xy 422.226834 -379.223987)
			(xy 422.242865 -379.289481) (xy 422.250937 -379.356423) (xy 422.250932 -379.423849) (xy 422.242852 -379.49079)
			(xy 422.226813 -379.556282) (xy 422.203045 -379.61938) (xy 422.17189 -379.679178) (xy 422.133798 -379.734814)
			(xy 422.111932 -379.76048) (xy 422.106111 -379.767607) (xy 422.099613 -379.784812) (xy 422.099232 -379.794008)
			(xy 422.099232 -380.28626) (xy 422.099677 -380.295443) (xy 422.106168 -380.312627) (xy 422.111932 -380.319788)
			(xy 422.133814 -380.345438) (xy 422.171901 -380.401075) (xy 422.203049 -380.460874) (xy 422.22681 -380.523973)
			(xy 422.242843 -380.589463) (xy 422.250917 -380.656403) (xy 422.250917 -380.656463) (xy 425.52898 -380.656463)
			(xy 425.537022 -380.589642) (xy 425.552992 -380.524262) (xy 425.576662 -380.461258) (xy 425.607692 -380.401535)
			(xy 425.645638 -380.345948) (xy 425.667424 -380.320296) (xy 425.673208 -380.313142) (xy 425.679729 -380.295958)
			(xy 425.680124 -380.286768) (xy 425.680124 -379.7935) (xy 425.679709 -379.784313) (xy 425.673198 -379.767129)
			(xy 425.667424 -379.759972) (xy 425.645684 -379.734281) (xy 425.607735 -379.678699) (xy 425.5767 -379.618981)
			(xy 425.553026 -379.555982) (xy 425.53705 -379.490605) (xy 425.529002 -379.423787) (xy 425.528998 -379.356486)
			(xy 425.537037 -379.289667) (xy 425.553004 -379.224287) (xy 425.576671 -379.161285) (xy 425.607698 -379.101563)
			(xy 425.64564 -379.045977) (xy 425.667424 -379.020324) (xy 425.673238 -379.013191) (xy 425.679742 -378.995991)
			(xy 425.680124 -378.986796) (xy 425.680124 -378.828554) (xy 425.680595 -378.818395) (xy 425.688382 -378.799628)
			(xy 425.702754 -378.785264) (xy 425.721527 -378.777489) (xy 425.731686 -378.776992) (xy 426.447966 -378.776992)
			(xy 426.458116 -378.77756) (xy 426.476875 -378.785315) (xy 426.49124 -378.799657) (xy 426.499024 -378.818405)
			(xy 426.499528 -378.828554) (xy 426.499528 -378.986796) (xy 426.499934 -378.995984) (xy 426.50645 -379.013168)
			(xy 426.512228 -379.020324) (xy 426.534064 -379.045937) (xy 426.572014 -379.101528) (xy 426.603047 -379.161257)
			(xy 426.626718 -379.224267) (xy 426.642689 -379.289654) (xy 426.65073 -379.356481) (xy 426.650725 -379.423791)
			(xy 426.642676 -379.490617) (xy 426.626697 -379.556003) (xy 426.603017 -379.619009) (xy 426.571977 -379.678734)
			(xy 426.53402 -379.73432) (xy 426.512228 -379.759972) (xy 426.50641 -379.767101) (xy 426.49991 -379.784304)
			(xy 426.499528 -379.7935) (xy 426.499528 -380.286768) (xy 426.499947 -380.295954) (xy 426.506454 -380.313139)
			(xy 426.512228 -380.320296) (xy 426.534036 -380.345932) (xy 426.571987 -380.40152) (xy 426.603021 -380.461245)
			(xy 426.626694 -380.524252) (xy 426.642667 -380.589636) (xy 426.650703 -380.656404) (xy 429.928748 -380.656404)
			(xy 429.936823 -380.589467) (xy 429.952857 -380.523978) (xy 429.976619 -380.460882) (xy 430.007769 -380.401087)
			(xy 430.045857 -380.345453) (xy 430.06772 -380.319788) (xy 430.073506 -380.312636) (xy 430.080027 -380.295451)
			(xy 430.08042 -380.28626) (xy 430.08042 -379.794008) (xy 430.080001 -379.784822) (xy 430.073493 -379.767638)
			(xy 430.06772 -379.76048) (xy 430.045902 -379.734776) (xy 430.007811 -379.679148) (xy 429.976657 -379.619357)
			(xy 429.952889 -379.556265) (xy 429.93685 -379.490781) (xy 429.92877 -379.423846) (xy 429.928766 -379.356426)
			(xy 429.936837 -379.289491) (xy 429.952868 -379.224004) (xy 429.976628 -379.160909) (xy 430.007774 -379.101114)
			(xy 430.045858 -379.045481) (xy 430.06772 -379.019816) (xy 430.073537 -379.012685) (xy 430.080039 -378.995484)
			(xy 430.08042 -378.986288) (xy 430.08042 -378.828554) (xy 430.080888 -378.818427) (xy 430.088628 -378.799708)
			(xy 430.102919 -378.785354) (xy 430.121603 -378.777533) (xy 430.131728 -378.776992) (xy 430.848008 -378.776992)
			(xy 430.858162 -378.777415) (xy 430.876913 -378.785212) (xy 430.891235 -378.799608) (xy 430.898936 -378.818398)
			(xy 430.899316 -378.828554) (xy 430.899316 -378.986288) (xy 430.899728 -378.995475) (xy 430.90624 -379.01266)
			(xy 430.912016 -379.019816) (xy 430.933927 -379.045443) (xy 430.972013 -379.101083) (xy 431.003161 -379.160885)
			(xy 431.026921 -379.223987) (xy 431.042953 -379.28948) (xy 431.051025 -379.356422) (xy 431.05102 -379.42385)
			(xy 431.04294 -379.490791) (xy 431.0269 -379.556282) (xy 431.003131 -379.619381) (xy 430.971976 -379.679179)
			(xy 430.933882 -379.734814) (xy 430.912016 -379.76048) (xy 430.906205 -379.767615) (xy 430.899698 -379.784813)
			(xy 430.899316 -379.794008) (xy 430.899316 -380.28626) (xy 430.899742 -380.295446) (xy 430.906244 -380.31263)
			(xy 430.912016 -380.319788) (xy 430.933899 -380.345437) (xy 430.971986 -380.401074) (xy 431.003135 -380.460873)
			(xy 431.026897 -380.523972) (xy 431.042931 -380.589463) (xy 431.051005 -380.656403) (xy 431.051005 -380.656464)
			(xy 434.329068 -380.656464) (xy 434.33711 -380.589643) (xy 434.35308 -380.524262) (xy 434.376749 -380.461259)
			(xy 434.407778 -380.401535) (xy 434.445722 -380.345949) (xy 434.467508 -380.320296) (xy 434.47329 -380.31314)
			(xy 434.479813 -380.295958) (xy 434.480208 -380.286768) (xy 434.480208 -379.7935) (xy 434.479796 -379.784313)
			(xy 434.473283 -379.767129) (xy 434.467508 -379.759972) (xy 434.445769 -379.73428) (xy 434.407821 -379.678699)
			(xy 434.376787 -379.61898) (xy 434.353113 -379.555981) (xy 434.337137 -379.490604) (xy 434.32909 -379.423786)
			(xy 434.329086 -379.356486) (xy 434.337125 -379.289667) (xy 434.353091 -379.224288) (xy 434.376757 -379.161286)
			(xy 434.407783 -379.101563) (xy 434.445724 -379.045977) (xy 434.467508 -379.020324) (xy 434.47332 -379.01319)
			(xy 434.479825 -378.995991) (xy 434.480208 -378.986796) (xy 434.480208 -378.828554) (xy 434.480695 -378.818397)
			(xy 434.488479 -378.799633) (xy 434.502846 -378.78527) (xy 434.521613 -378.777492) (xy 434.53177 -378.776992)
			(xy 435.24805 -378.776992) (xy 435.258213 -378.777504) (xy 435.276998 -378.785264) (xy 435.291383 -378.799622)
			(xy 435.299177 -378.818392) (xy 435.299612 -378.828554) (xy 435.299612 -378.986796) (xy 435.300021 -378.995983)
			(xy 435.306535 -379.013168) (xy 435.312312 -379.020324) (xy 435.334148 -379.045937) (xy 435.372099 -379.101528)
			(xy 435.403133 -379.161256) (xy 435.426805 -379.224266) (xy 435.442776 -379.289654) (xy 435.450817 -379.356481)
			(xy 435.450813 -379.423791) (xy 435.442763 -379.490618) (xy 435.426784 -379.556003) (xy 435.403103 -379.61901)
			(xy 435.372062 -379.678734) (xy 435.334104 -379.73432) (xy 435.312312 -379.759972) (xy 435.306504 -379.767109)
			(xy 435.299996 -379.784306) (xy 435.299612 -379.7935) (xy 435.299612 -380.286768) (xy 435.300035 -380.295954)
			(xy 435.306539 -380.313139) (xy 435.312312 -380.320296) (xy 435.334121 -380.345931) (xy 435.372072 -380.401519)
			(xy 435.403107 -380.461244) (xy 435.426781 -380.524251) (xy 435.442754 -380.589636) (xy 435.450797 -380.656461)
			(xy 435.450796 -380.723769) (xy 435.442749 -380.790594) (xy 435.426772 -380.855977) (xy 435.403095 -380.918983)
			(xy 435.372057 -380.978707) (xy 435.334102 -381.034292) (xy 435.312312 -381.059944) (xy 435.306516 -381.067089)
			(xy 435.3 -381.08428) (xy 435.299612 -381.093472) (xy 435.299612 -381.251206) (xy 435.29924 -381.261384)
			(xy 435.291444 -381.280189) (xy 435.277041 -381.294575) (xy 435.258229 -381.302351) (xy 435.24805 -381.302768)
			(xy 434.53177 -381.302768) (xy 434.521611 -381.302291) (xy 434.502842 -381.294508) (xy 434.488478 -381.280138)
			(xy 434.480704 -381.261365) (xy 434.480208 -381.251206) (xy 434.480208 -381.093472) (xy 434.47981 -381.084284)
			(xy 434.473288 -381.067099) (xy 434.467508 -381.059944) (xy 434.445741 -381.034275) (xy 434.407793 -380.97869)
			(xy 434.376761 -380.918969) (xy 434.353088 -380.855967) (xy 434.337115 -380.790587) (xy 434.32907 -380.723766)
			(xy 434.329068 -380.656464) (xy 431.051005 -380.656464) (xy 431.051003 -380.723827) (xy 431.042926 -380.790767)
			(xy 431.026889 -380.856257) (xy 431.003123 -380.919354) (xy 430.971971 -380.979151) (xy 430.933881 -381.034786)
			(xy 430.912016 -381.060452) (xy 430.906217 -381.067595) (xy 430.899703 -381.084787) (xy 430.899316 -381.09398)
			(xy 430.899316 -381.251206) (xy 430.898877 -381.261338) (xy 430.891139 -381.280068) (xy 430.876838 -381.294426)
			(xy 430.858138 -381.302237) (xy 430.848008 -381.302768) (xy 430.131728 -381.302768) (xy 430.121572 -381.302355)
			(xy 430.102814 -381.294563) (xy 430.088488 -381.280163) (xy 430.080793 -381.261364) (xy 430.08042 -381.251206)
			(xy 430.08042 -381.09398) (xy 430.080015 -381.084792) (xy 430.073497 -381.067608) (xy 430.06772 -381.060452)
			(xy 430.045875 -381.034771) (xy 430.007784 -380.979139) (xy 429.976632 -380.919345) (xy 429.952865 -380.85625)
			(xy 429.936828 -380.790763) (xy 429.92875 -380.723826) (xy 429.928748 -380.656404) (xy 426.650703 -380.656404)
			(xy 426.65071 -380.656461) (xy 426.650708 -380.723769) (xy 426.642661 -380.790593) (xy 426.626685 -380.855977)
			(xy 426.603009 -380.918982) (xy 426.571971 -380.978706) (xy 426.534018 -381.034292) (xy 426.512228 -381.059944)
			(xy 426.506422 -381.067082) (xy 426.499915 -381.084278) (xy 426.499528 -381.093472) (xy 426.499528 -381.251206)
			(xy 426.49914 -381.261382) (xy 426.491347 -381.280184) (xy 426.47695 -381.294569) (xy 426.458143 -381.302348)
			(xy 426.447966 -381.302768) (xy 425.731686 -381.302768) (xy 425.721528 -381.302278) (xy 425.70276 -381.2945)
			(xy 425.688395 -381.280133) (xy 425.68062 -381.261364) (xy 425.680124 -381.251206) (xy 425.680124 -381.093472)
			(xy 425.679722 -381.084284) (xy 425.673202 -381.0671) (xy 425.667424 -381.059944) (xy 425.645656 -381.034276)
			(xy 425.607708 -380.978691) (xy 425.576675 -380.91897) (xy 425.553001 -380.855967) (xy 425.537027 -380.790587)
			(xy 425.528982 -380.723767) (xy 425.52898 -380.656463) (xy 422.250917 -380.656463) (xy 422.250915 -380.723827)
			(xy 422.242838 -380.790766) (xy 422.226801 -380.856256) (xy 422.203036 -380.919354) (xy 422.171885 -380.979151)
			(xy 422.133796 -381.034786) (xy 422.111932 -381.060452) (xy 422.106123 -381.067588) (xy 422.099618 -381.084786)
			(xy 422.099232 -381.09398) (xy 422.099232 -381.251206) (xy 422.098777 -381.261337) (xy 422.091042 -381.280063)
			(xy 422.076746 -381.29442) (xy 422.058052 -381.302234) (xy 422.047924 -381.302768) (xy 421.331644 -381.302768)
			(xy 421.32152 -381.302347) (xy 421.302812 -381.294608) (xy 421.288495 -381.280292) (xy 421.280754 -381.261584)
			(xy 421.280336 -381.25146) (xy 421.280336 -381.09398) (xy 421.279927 -381.084793) (xy 421.273412 -381.067609)
			(xy 421.267636 -381.060452) (xy 421.24579 -381.034771) (xy 421.207699 -380.97914) (xy 421.176545 -380.919346)
			(xy 421.152778 -380.856251) (xy 421.13674 -380.790764) (xy 421.128662 -380.723826) (xy 421.12866 -380.656404)
			(xy 391.450857 -380.656404) (xy 391.450864 -380.656462) (xy 391.450863 -380.723768) (xy 391.442817 -380.790591)
			(xy 391.426843 -380.855974) (xy 391.40317 -380.918979) (xy 391.372136 -380.978704) (xy 391.334188 -381.034291)
			(xy 391.3124 -381.059944) (xy 391.306602 -381.067088) (xy 391.300088 -381.08428) (xy 391.2997 -381.093472)
			(xy 391.2997 -381.251206) (xy 391.299172 -381.261359) (xy 391.291403 -381.280121) (xy 391.277048 -381.294485)
			(xy 391.258291 -381.302266) (xy 391.248138 -381.302768) (xy 390.531858 -381.302768) (xy 390.521698 -381.302301)
			(xy 390.502929 -381.294514) (xy 390.488566 -381.28014) (xy 390.480792 -381.261366) (xy 390.480296 -381.251206)
			(xy 390.480296 -381.093472) (xy 390.4799 -381.084283) (xy 390.473377 -381.067099) (xy 390.467596 -381.059944)
			(xy 390.445829 -381.034275) (xy 390.407883 -380.97869) (xy 390.376851 -380.918968) (xy 390.353179 -380.855966)
			(xy 390.337206 -380.790586) (xy 390.329161 -380.723766) (xy 390.329159 -380.656464) (xy 387.051096 -380.656464)
			(xy 387.051094 -380.723828) (xy 387.043016 -380.790767) (xy 387.026979 -380.856257) (xy 387.003213 -380.919355)
			(xy 386.97206 -380.979152) (xy 386.933969 -381.034787) (xy 386.912104 -381.060452) (xy 386.906303 -381.067594)
			(xy 386.899791 -381.084787) (xy 386.899404 -381.09398) (xy 386.899404 -381.251206) (xy 386.89888 -381.261328)
			(xy 386.891158 -381.280041) (xy 386.876884 -381.294395) (xy 386.858215 -381.302222) (xy 386.848096 -381.302768)
			(xy 386.131816 -381.302768) (xy 386.121659 -381.302365) (xy 386.102901 -381.294568) (xy 386.088576 -381.280166)
			(xy 386.080881 -381.261365) (xy 386.080508 -381.251206) (xy 386.080508 -381.09398) (xy 386.080106 -381.084792)
			(xy 386.073587 -381.067608) (xy 386.067808 -381.060452) (xy 386.045963 -381.034771) (xy 386.007874 -380.979139)
			(xy 385.976722 -380.919345) (xy 385.952956 -380.85625) (xy 385.936919 -380.790763) (xy 385.928841 -380.723826)
			(xy 385.928839 -380.656404) (xy 382.650793 -380.656404) (xy 382.6508 -380.656461) (xy 382.650799 -380.723769)
			(xy 382.642752 -380.790593) (xy 382.626775 -380.855977) (xy 382.603098 -380.918983) (xy 382.57206 -380.978707)
			(xy 382.534106 -381.034292) (xy 382.512316 -381.059944) (xy 382.50652 -381.06709) (xy 382.500005 -381.08428)
			(xy 382.499616 -381.093472) (xy 382.499616 -381.251206) (xy 382.49924 -381.261384) (xy 382.491444 -381.280187)
			(xy 382.477044 -381.294574) (xy 382.458232 -381.30235) (xy 382.448054 -381.302768) (xy 381.731774 -381.302768)
			(xy 381.721615 -381.302288) (xy 381.702847 -381.294506) (xy 381.688482 -381.280137) (xy 381.680708 -381.261365)
			(xy 381.680212 -381.251206) (xy 381.680212 -381.093472) (xy 381.679813 -381.084284) (xy 381.673291 -381.0671)
			(xy 381.667512 -381.059944) (xy 381.645745 -381.034275) (xy 381.607797 -380.978691) (xy 381.576764 -380.918969)
			(xy 381.553092 -380.855967) (xy 381.537118 -380.790587) (xy 381.529073 -380.723767) (xy 381.529071 -380.656464)
			(xy 378.251008 -380.656464) (xy 378.251006 -380.723827) (xy 378.242929 -380.790767) (xy 378.226892 -380.856257)
			(xy 378.203126 -380.919354) (xy 378.171974 -380.979151) (xy 378.133884 -381.034786) (xy 378.11202 -381.060452)
			(xy 378.106221 -381.067596) (xy 378.099707 -381.084787) (xy 378.09932 -381.09398) (xy 378.09932 -381.251206)
			(xy 378.098877 -381.261338) (xy 378.09114 -381.280067) (xy 378.07684 -381.294424) (xy 378.058142 -381.302236)
			(xy 378.048012 -381.302768) (xy 377.331732 -381.302768) (xy 377.321576 -381.302352) (xy 377.302818 -381.294561)
			(xy 377.288492 -381.280162) (xy 377.280797 -381.261364) (xy 377.280424 -381.251206) (xy 377.280424 -381.09398)
			(xy 377.280018 -381.084792) (xy 377.273501 -381.067608) (xy 377.267724 -381.060452) (xy 377.245879 -381.034771)
			(xy 377.207788 -380.979139) (xy 377.176635 -380.919345) (xy 377.152869 -380.856251) (xy 377.136831 -380.790763)
			(xy 377.128753 -380.723826) (xy 377.128751 -380.656404) (xy 347.450948 -380.656404) (xy 347.450955 -380.656462)
			(xy 347.450954 -380.723768) (xy 347.442908 -380.790592) (xy 347.426934 -380.855975) (xy 347.40326 -380.91898)
			(xy 347.372226 -380.978704) (xy 347.334276 -381.034291) (xy 347.312488 -381.059944) (xy 347.306689 -381.067087)
			(xy 347.300176 -381.084279) (xy 347.299788 -381.093472) (xy 347.299788 -381.251206) (xy 347.299272 -381.261361)
			(xy 347.2915 -381.280125) (xy 347.277142 -381.294489) (xy 347.258381 -381.302268) (xy 347.248226 -381.302768)
			(xy 346.531946 -381.302768) (xy 346.521778 -381.302299) (xy 346.502986 -381.29453) (xy 346.488599 -381.280158)
			(xy 346.480812 -381.261373) (xy 346.480384 -381.251206) (xy 346.480384 -381.093472) (xy 346.479991 -381.084283)
			(xy 346.473466 -381.067099) (xy 346.467684 -381.059944) (xy 346.445915 -381.034276) (xy 346.407962 -380.978693)
			(xy 346.376926 -380.918972) (xy 346.35325 -380.85597) (xy 346.337274 -380.790589) (xy 346.329228 -380.723767)
			(xy 346.329226 -380.656463) (xy 343.051187 -380.656463) (xy 343.051185 -380.723828) (xy 343.043107 -380.790767)
			(xy 343.027069 -380.856258) (xy 343.003303 -380.919356) (xy 342.972149 -380.979152) (xy 342.934057 -381.034787)
			(xy 342.912192 -381.060452) (xy 342.90639 -381.067593) (xy 342.899879 -381.084787) (xy 342.899492 -381.09398)
			(xy 342.899492 -381.251206) (xy 342.898979 -381.261329) (xy 342.891255 -381.280044) (xy 342.876978 -381.294399)
			(xy 342.858304 -381.302224) (xy 342.848184 -381.302768) (xy 342.131904 -381.302768) (xy 342.121746 -381.302374)
			(xy 342.102988 -381.294574) (xy 342.088663 -381.280168) (xy 342.080969 -381.261366) (xy 342.080596 -381.251206)
			(xy 342.080596 -381.09398) (xy 342.080196 -381.084792) (xy 342.073675 -381.067608) (xy 342.067896 -381.060452)
			(xy 342.046052 -381.03477) (xy 342.007963 -380.979138) (xy 341.976811 -380.919344) (xy 341.953046 -380.856249)
			(xy 341.93701 -380.790762) (xy 341.928932 -380.723826) (xy 341.92893 -380.656404) (xy 338.65086 -380.656404)
			(xy 338.650867 -380.656462) (xy 338.650866 -380.723768) (xy 338.64282 -380.790591) (xy 338.626846 -380.855974)
			(xy 338.603173 -380.918979) (xy 338.57214 -380.978704) (xy 338.534192 -381.034291) (xy 338.512404 -381.059944)
			(xy 338.506607 -381.067089) (xy 338.500092 -381.08428) (xy 338.499704 -381.093472) (xy 338.499704 -381.251206)
			(xy 338.499172 -381.261359) (xy 338.491404 -381.28012) (xy 338.47705 -381.294484) (xy 338.458295 -381.302265)
			(xy 338.448142 -381.302768) (xy 337.731862 -381.302768) (xy 337.721703 -381.302298) (xy 337.702934 -381.294512)
			(xy 337.68857 -381.280139) (xy 337.680796 -381.261366) (xy 337.6803 -381.251206) (xy 337.6803 -381.093472)
			(xy 337.679904 -381.084283) (xy 337.67338 -381.067099) (xy 337.6676 -381.059944) (xy 337.645833 -381.034275)
			(xy 337.607886 -380.97869) (xy 337.576854 -380.918969) (xy 337.553182 -380.855966) (xy 337.537209 -380.790587)
			(xy 337.529164 -380.723766) (xy 337.529162 -380.656464) (xy 334.251099 -380.656464) (xy 334.251097 -380.723828)
			(xy 334.243019 -380.790767) (xy 334.226982 -380.856257) (xy 334.203216 -380.919355) (xy 334.172063 -380.979152)
			(xy 334.133973 -381.034787) (xy 334.112108 -381.060452) (xy 334.106308 -381.067595) (xy 334.099795 -381.084787)
			(xy 334.099408 -381.09398) (xy 334.099408 -381.251206) (xy 334.09888 -381.261327) (xy 334.091159 -381.280039)
			(xy 334.076886 -381.294394) (xy 334.058218 -381.302221) (xy 334.0481 -381.302768) (xy 333.33182 -381.302768)
			(xy 333.321663 -381.302362) (xy 333.302905 -381.294567) (xy 333.28858 -381.280165) (xy 333.280885 -381.261365)
			(xy 333.280512 -381.251206) (xy 333.280512 -381.09398) (xy 333.280109 -381.084792) (xy 333.27359 -381.067608)
			(xy 333.267812 -381.060452) (xy 333.245967 -381.034771) (xy 333.207877 -380.979139) (xy 333.176725 -380.919345)
			(xy 333.152959 -380.85625) (xy 333.136922 -380.790763) (xy 333.128844 -380.723826) (xy 333.128842 -380.656404)
			(xy 303.451069 -380.656404) (xy 303.451067 -380.723828) (xy 303.442989 -380.790768) (xy 303.42695 -380.856259)
			(xy 303.403182 -380.919357) (xy 303.372027 -380.979153) (xy 303.333934 -381.034787) (xy 303.312068 -381.060452)
			(xy 303.306263 -381.067591) (xy 303.299754 -381.084786) (xy 303.299368 -381.09398) (xy 303.299368 -381.251206)
			(xy 303.298878 -381.261332) (xy 303.29115 -381.280052) (xy 303.276865 -381.294408) (xy 303.258184 -381.302228)
			(xy 303.24806 -381.302768) (xy 302.53178 -381.302768) (xy 302.521621 -381.302394) (xy 302.502861 -381.294586)
			(xy 302.488538 -381.280174) (xy 302.480844 -381.261368) (xy 302.480472 -381.251206) (xy 302.480472 -381.09398)
			(xy 302.480078 -381.084791) (xy 302.473554 -381.067607) (xy 302.467772 -381.060452) (xy 302.445929 -381.03477)
			(xy 302.407841 -380.979137) (xy 302.376691 -380.919343) (xy 302.352927 -380.856248) (xy 302.336891 -380.790762)
			(xy 302.328814 -380.723826) (xy 302.328812 -380.656404) (xy 299.050742 -380.656404) (xy 299.050749 -380.656462)
			(xy 299.050747 -380.723768) (xy 299.042702 -380.790592) (xy 299.026727 -380.855975) (xy 299.003053 -380.91898)
			(xy 298.972018 -380.978704) (xy 298.934068 -381.034292) (xy 298.91228 -381.059944) (xy 298.90648 -381.067087)
			(xy 298.899968 -381.084279) (xy 298.89958 -381.093472) (xy 298.89958 -381.251206) (xy 298.899072 -381.261362)
			(xy 298.891299 -381.280128) (xy 298.876938 -381.294492) (xy 298.858174 -381.302269) (xy 298.848018 -381.302768)
			(xy 298.131738 -381.302768) (xy 298.12157 -381.302305) (xy 298.102777 -381.294534) (xy 298.088391 -381.28016)
			(xy 298.080604 -381.261374) (xy 298.080176 -381.251206) (xy 298.080176 -381.093472) (xy 298.079785 -381.084283)
			(xy 298.073258 -381.067098) (xy 298.067476 -381.059944) (xy 298.045707 -381.034276) (xy 298.007755 -380.978693)
			(xy 297.976719 -380.918972) (xy 297.953043 -380.855969) (xy 297.937068 -380.790589) (xy 297.929022 -380.723767)
			(xy 297.92902 -380.656463) (xy 294.650981 -380.656463) (xy 294.650979 -380.723828) (xy 294.642901 -380.790768)
			(xy 294.626863 -380.856258) (xy 294.603096 -380.919356) (xy 294.571942 -380.979153) (xy 294.53385 -381.034787)
			(xy 294.511984 -381.060452) (xy 294.506181 -381.067593) (xy 294.499671 -381.084787) (xy 294.499284 -381.09398)
			(xy 294.499284 -381.251206) (xy 294.498779 -381.26133) (xy 294.491054 -381.280047) (xy 294.476773 -381.294402)
			(xy 294.458097 -381.302225) (xy 294.447976 -381.302768) (xy 293.731696 -381.302768) (xy 293.721569 -381.302386)
			(xy 293.70286 -381.294631) (xy 293.688544 -381.280303) (xy 293.680805 -381.261587) (xy 293.680388 -381.25146)
			(xy 293.680388 -381.09398) (xy 293.67999 -381.084791) (xy 293.673468 -381.067607) (xy 293.667688 -381.060452)
			(xy 293.645844 -381.03477) (xy 293.607756 -380.979138) (xy 293.576605 -380.919344) (xy 293.55284 -380.856249)
			(xy 293.536803 -380.790762) (xy 293.528726 -380.723826) (xy 293.528724 -380.656404) (xy 290.250654 -380.656404)
			(xy 290.250661 -380.656462) (xy 290.25066 -380.723768) (xy 290.242614 -380.790591) (xy 290.22664 -380.855974)
			(xy 290.202966 -380.918979) (xy 290.171933 -380.978704) (xy 290.133984 -381.034291) (xy 290.112196 -381.059944)
			(xy 290.106398 -381.067088) (xy 290.099884 -381.084279) (xy 290.099496 -381.093472) (xy 290.099496 -381.251206)
			(xy 290.098972 -381.26136) (xy 290.091202 -381.280123) (xy 290.076846 -381.294486) (xy 290.058088 -381.302267)
			(xy 290.047934 -381.302768) (xy 289.331654 -381.302768) (xy 289.321494 -381.302304) (xy 289.302725 -381.294516)
			(xy 289.288362 -381.280141) (xy 289.280588 -381.261366) (xy 289.280092 -381.251206) (xy 289.280092 -381.093472)
			(xy 289.279697 -381.084283) (xy 289.273173 -381.067099) (xy 289.267392 -381.059944) (xy 289.245622 -381.034276)
			(xy 289.207669 -380.978693) (xy 289.176632 -380.918972) (xy 289.152956 -380.85597) (xy 289.13698 -380.790589)
			(xy 289.128934 -380.723767) (xy 289.128932 -380.656463) (xy 272.92786 -380.656463) (xy 272.867822 -380.687974)
			(xy 272.746027 -380.742789) (xy 272.621144 -380.790151) (xy 272.49363 -380.829886) (xy 272.363949 -380.861849)
			(xy 272.232575 -380.885924) (xy 272.099987 -380.902024) (xy 271.966669 -380.910088) (xy 271.833107 -380.910088)
			(xy 271.699789 -380.902024) (xy 271.567201 -380.885924) (xy 271.435827 -380.861849) (xy 271.306146 -380.829886)
			(xy 271.178632 -380.790151) (xy 271.053749 -380.742789) (xy 270.931954 -380.687974) (xy 270.813691 -380.625904)
			(xy 270.699392 -380.556808) (xy 270.589472 -380.480936) (xy 270.484335 -380.398566) (xy 270.384362 -380.309998)
			(xy 270.28992 -380.215556) (xy 270.201352 -380.115583) (xy 270.118982 -380.010446) (xy 270.04311 -379.900526)
			(xy 269.974014 -379.786227) (xy 269.911944 -379.667964) (xy 269.857129 -379.546169) (xy 269.809767 -379.421286)
			(xy 269.770032 -379.293772) (xy 269.738069 -379.164091) (xy 269.713994 -379.032717) (xy 269.697894 -378.900129)
			(xy 269.68983 -378.766811) (xy 236.356885 -378.766811) (xy 237.084108 -379.494034) (xy 237.084616 -379.494542)
			(xy 237.093852 -379.502751) (xy 237.116722 -379.512039) (xy 237.129066 -379.512576) (xy 239.773968 -379.512576)
			(xy 239.786313 -379.512049) (xy 239.809185 -379.502755) (xy 239.818418 -379.494542) (xy 239.818926 -379.494034)
			(xy 240.443004 -378.869702) (xy 240.450409 -378.862868) (xy 240.469004 -378.855145) (xy 240.479072 -378.854716)
			(xy 262.036814 -378.854716) (xy 262.046885 -378.85513) (xy 262.065482 -378.862858) (xy 262.072882 -378.869702)
			(xy 262.259318 -379.056138) (xy 262.26617 -379.063529) (xy 262.273882 -379.082135) (xy 262.274304 -379.092206)
			(xy 262.274304 -382.223705) (xy 286.928753 -382.223705) (xy 286.928754 -382.15628) (xy 286.936832 -382.08934)
			(xy 286.95287 -382.02385) (xy 286.976638 -381.960752) (xy 287.007792 -381.900956) (xy 287.045886 -381.845322)
			(xy 287.067752 -381.819658) (xy 287.073555 -381.812518) (xy 287.080065 -381.795323) (xy 287.080452 -381.78613)
			(xy 287.080452 -381.628904) (xy 287.080987 -381.618801) (xy 287.088715 -381.600133) (xy 287.102996 -381.585839)
			(xy 287.121658 -381.578096) (xy 287.13176 -381.577596) (xy 287.84804 -381.577596) (xy 287.858151 -381.578052)
			(xy 287.876829 -381.585802) (xy 287.891122 -381.600108) (xy 287.898856 -381.618793) (xy 287.899348 -381.628904)
			(xy 287.899348 -381.78613) (xy 287.899755 -381.795317) (xy 287.906272 -381.812501) (xy 287.912048 -381.819658)
			(xy 287.933904 -381.84533) (xy 287.971996 -381.900963) (xy 288.00315 -381.960757) (xy 288.026917 -382.023853)
			(xy 288.042955 -382.089342) (xy 288.051033 -382.156281) (xy 288.051034 -382.223645) (xy 291.329073 -382.223645)
			(xy 291.329074 -382.15634) (xy 291.337119 -382.089516) (xy 291.353093 -382.024133) (xy 291.376767 -381.961128)
			(xy 291.407801 -381.901405) (xy 291.445751 -381.845818) (xy 291.46754 -381.820166) (xy 291.473339 -381.813022)
			(xy 291.479851 -381.795831) (xy 291.48024 -381.786638) (xy 291.48024 -381.628904) (xy 291.48062 -381.618777)
			(xy 291.488375 -381.600066) (xy 291.502703 -381.58575) (xy 291.52142 -381.578012) (xy 291.531548 -381.577596)
			(xy 292.248082 -381.577596) (xy 292.258202 -381.57814) (xy 292.276915 -381.585854) (xy 292.29127 -381.600122)
			(xy 292.299098 -381.618787) (xy 292.299644 -381.628904) (xy 292.299644 -381.786638) (xy 292.300049 -381.795826)
			(xy 292.306568 -381.813009) (xy 292.312344 -381.820166) (xy 292.334122 -381.845826) (xy 292.372072 -381.901411)
			(xy 292.403107 -381.961133) (xy 292.426781 -382.024137) (xy 292.442755 -382.089518) (xy 292.450801 -382.15634)
			(xy 292.450801 -382.223645) (xy 292.450794 -382.223705) (xy 295.728841 -382.223705) (xy 295.728842 -382.15628)
			(xy 295.73692 -382.08934) (xy 295.752957 -382.02385) (xy 295.776724 -381.960753) (xy 295.807878 -381.900957)
			(xy 295.84597 -381.845323) (xy 295.867836 -381.819658) (xy 295.873637 -381.812516) (xy 295.880148 -381.795323)
			(xy 295.880536 -381.78613) (xy 295.880536 -381.628904) (xy 295.88092 -381.618777) (xy 295.888674 -381.600067)
			(xy 295.903001 -381.585751) (xy 295.921717 -381.578012) (xy 295.931844 -381.577596) (xy 296.648124 -381.577596)
			(xy 296.658234 -381.578065) (xy 296.676912 -381.58581) (xy 296.691206 -381.600112) (xy 296.69894 -381.618794)
			(xy 296.699432 -381.628904) (xy 296.699432 -381.78613) (xy 296.699843 -381.795317) (xy 296.706358 -381.8125)
			(xy 296.712132 -381.819658) (xy 296.733985 -381.845332) (xy 296.772072 -381.900966) (xy 296.803221 -381.960761)
			(xy 296.826985 -382.023857) (xy 296.84302 -382.089345) (xy 296.851096 -382.156281) (xy 296.851097 -382.223704)
			(xy 296.851097 -382.223705) (xy 300.128632 -382.223705) (xy 300.128633 -382.15628) (xy 300.13671 -382.089341)
			(xy 300.152748 -382.023851) (xy 300.176514 -381.960753) (xy 300.207667 -381.900957) (xy 300.245759 -381.845323)
			(xy 300.267624 -381.819658) (xy 300.273424 -381.812515) (xy 300.279936 -381.795323) (xy 300.280324 -381.78613)
			(xy 300.280324 -381.628904) (xy 300.28072 -381.618779) (xy 300.288471 -381.600071) (xy 300.302794 -381.585755)
			(xy 300.321507 -381.578014) (xy 300.331632 -381.577596) (xy 301.047912 -381.577596) (xy 301.058021 -381.578075)
			(xy 301.076699 -381.585816) (xy 301.090993 -381.600115) (xy 301.098728 -381.618795) (xy 301.09922 -381.628904)
			(xy 301.09922 -381.78613) (xy 301.099611 -381.795319) (xy 301.106138 -381.812504) (xy 301.11192 -381.819658)
			(xy 301.133773 -381.845332) (xy 301.171861 -381.900965) (xy 301.203011 -381.960761) (xy 301.226775 -382.023856)
			(xy 301.242811 -382.089344) (xy 301.250887 -382.156281) (xy 301.250888 -382.223646) (xy 330.929191 -382.223646)
			(xy 330.929192 -382.156339) (xy 330.937238 -382.089516) (xy 330.953213 -382.024133) (xy 330.976888 -381.961128)
			(xy 331.007923 -381.901404) (xy 331.045875 -381.845818) (xy 331.067664 -381.820166) (xy 331.073465 -381.813025)
			(xy 331.079975 -381.795831) (xy 331.080364 -381.786638) (xy 331.080364 -381.628904) (xy 331.080824 -381.618755)
			(xy 331.088612 -381.600009) (xy 331.102996 -381.585687) (xy 331.121775 -381.577981) (xy 331.131926 -381.577596)
			(xy 331.848206 -381.577596) (xy 331.858328 -381.57812) (xy 331.877041 -381.585842) (xy 331.891395 -381.600116)
			(xy 331.899222 -381.618785) (xy 331.899768 -381.628904) (xy 331.899768 -381.786638) (xy 331.900167 -381.795826)
			(xy 331.906689 -381.81301) (xy 331.912468 -381.820166) (xy 331.934246 -381.845826) (xy 331.972195 -381.901412)
			(xy 332.003228 -381.961134) (xy 332.026901 -382.024138) (xy 332.042874 -382.089519) (xy 332.050919 -382.15634)
			(xy 332.05092 -382.223645) (xy 332.050913 -382.223704) (xy 335.328984 -382.223704) (xy 335.328985 -382.156281)
			(xy 335.337061 -382.089342) (xy 335.353096 -382.023853) (xy 335.37686 -381.960756) (xy 335.40801 -381.900959)
			(xy 335.446097 -381.845324) (xy 335.46796 -381.819658) (xy 335.473764 -381.812519) (xy 335.480273 -381.795323)
			(xy 335.48066 -381.78613) (xy 335.48066 -381.628904) (xy 335.481187 -381.6188) (xy 335.488916 -381.60013)
			(xy 335.5032 -381.585837) (xy 335.521865 -381.578095) (xy 335.531968 -381.577596) (xy 336.248248 -381.577596)
			(xy 336.258359 -381.578046) (xy 336.277038 -381.585799) (xy 336.291331 -381.600106) (xy 336.299064 -381.618792)
			(xy 336.299556 -381.628904) (xy 336.299556 -381.78613) (xy 336.299962 -381.795317) (xy 336.30648 -381.812501)
			(xy 336.312256 -381.819658) (xy 336.334112 -381.845331) (xy 336.372204 -381.900963) (xy 336.403357 -381.960758)
			(xy 336.427124 -382.023854) (xy 336.443161 -382.089342) (xy 336.451239 -382.156281) (xy 336.45124 -382.223645)
			(xy 339.729279 -382.223645) (xy 339.72928 -382.156339) (xy 339.737325 -382.089516) (xy 339.753299 -382.024133)
			(xy 339.776974 -381.961128) (xy 339.808009 -381.901404) (xy 339.845959 -381.845818) (xy 339.867748 -381.820166)
			(xy 339.873547 -381.813023) (xy 339.880059 -381.795831) (xy 339.880448 -381.786638) (xy 339.880448 -381.628904)
			(xy 339.880924 -381.618757) (xy 339.888708 -381.600014) (xy 339.903088 -381.585693) (xy 339.921861 -381.577984)
			(xy 339.93201 -381.577596) (xy 340.64829 -381.577596) (xy 340.658411 -381.578133) (xy 340.677123 -381.58585)
			(xy 340.691478 -381.60012) (xy 340.699306 -381.618786) (xy 340.699852 -381.628904) (xy 340.699852 -381.786638)
			(xy 340.700255 -381.795826) (xy 340.706775 -381.813009) (xy 340.712552 -381.820166) (xy 340.73433 -381.845826)
			(xy 340.77228 -381.901411) (xy 340.803314 -381.961134) (xy 340.826988 -382.024137) (xy 340.842962 -382.089518)
			(xy 340.851007 -382.15634) (xy 340.851007 -382.223645) (xy 344.12907 -382.223645) (xy 344.129071 -382.15634)
			(xy 344.137116 -382.089516) (xy 344.15309 -382.024134) (xy 344.176764 -381.961129) (xy 344.207798 -381.901405)
			(xy 344.245748 -381.845818) (xy 344.267536 -381.820166) (xy 344.273334 -381.813022) (xy 344.279847 -381.79583)
			(xy 344.280236 -381.786638) (xy 344.280236 -381.628904) (xy 344.280626 -381.618746) (xy 344.288427 -381.599986)
			(xy 344.302834 -381.585662) (xy 344.321637 -381.577968) (xy 344.331798 -381.577596) (xy 345.048078 -381.577596)
			(xy 345.058198 -381.578143) (xy 345.07691 -381.585856) (xy 345.091266 -381.600123) (xy 345.099094 -381.618787)
			(xy 345.09964 -381.628904) (xy 345.09964 -381.786638) (xy 345.100045 -381.795825) (xy 345.106564 -381.813009)
			(xy 345.11234 -381.820166) (xy 345.134118 -381.845826) (xy 345.172069 -381.901411) (xy 345.203104 -381.961133)
			(xy 345.226778 -382.024137) (xy 345.242752 -382.089518) (xy 345.250798 -382.15634) (xy 345.250798 -382.223645)
			(xy 345.250798 -382.223646) (xy 374.9291 -382.223646) (xy 374.929101 -382.156339) (xy 374.937147 -382.089515)
			(xy 374.953122 -382.024132) (xy 374.976798 -381.961127) (xy 375.007834 -381.901404) (xy 375.045787 -381.845818)
			(xy 375.067576 -381.820166) (xy 375.073367 -381.813016) (xy 375.079886 -381.795829) (xy 375.080276 -381.786638)
			(xy 375.080276 -381.628904) (xy 375.080724 -381.618753) (xy 375.088514 -381.600005) (xy 375.102902 -381.585683)
			(xy 375.121685 -381.577979) (xy 375.131838 -381.577596) (xy 375.848118 -381.577596) (xy 375.85824 -381.57811)
			(xy 375.876954 -381.585836) (xy 375.891308 -381.600113) (xy 375.899134 -381.618784) (xy 375.89968 -381.628904)
			(xy 375.89968 -381.786638) (xy 375.900076 -381.795827) (xy 375.9066 -381.813011) (xy 375.91238 -381.820166)
			(xy 375.934157 -381.845826) (xy 375.972105 -381.901412) (xy 376.003138 -381.961135) (xy 376.02681 -382.024138)
			(xy 376.042784 -382.089519) (xy 376.050828 -382.156341) (xy 376.050829 -382.223644) (xy 376.050822 -382.223704)
			(xy 379.328893 -382.223704) (xy 379.328894 -382.156281) (xy 379.33697 -382.089342) (xy 379.353006 -382.023853)
			(xy 379.37677 -381.960756) (xy 379.40792 -381.900959) (xy 379.446008 -381.845324) (xy 379.467872 -381.819658)
			(xy 379.473678 -381.81252) (xy 379.480185 -381.795324) (xy 379.480572 -381.78613) (xy 379.480572 -381.628904)
			(xy 379.481088 -381.618799) (xy 379.488819 -381.600126) (xy 379.503106 -381.585832) (xy 379.521775 -381.578092)
			(xy 379.53188 -381.577596) (xy 380.24816 -381.577596) (xy 380.258279 -381.578049) (xy 380.276981 -381.585783)
			(xy 380.291297 -381.600088) (xy 380.299044 -381.618785) (xy 380.299468 -381.628904) (xy 380.299468 -381.78613)
			(xy 380.299871 -381.795318) (xy 380.30639 -381.812502) (xy 380.312168 -381.819658) (xy 380.334023 -381.845331)
			(xy 380.372114 -381.900963) (xy 380.403267 -381.960758) (xy 380.427033 -382.023854) (xy 380.443071 -382.089343)
			(xy 380.451148 -382.156281) (xy 380.451149 -382.223646) (xy 383.729188 -382.223646) (xy 383.729189 -382.156339)
			(xy 383.737235 -382.089516) (xy 383.753209 -382.024133) (xy 383.776884 -381.961128) (xy 383.80792 -381.901404)
			(xy 383.845871 -381.845818) (xy 383.86766 -381.820166) (xy 383.873461 -381.813024) (xy 383.879971 -381.795831)
			(xy 383.88036 -381.786638) (xy 383.88036 -381.628904) (xy 383.880824 -381.618755) (xy 383.888611 -381.600011)
			(xy 383.902994 -381.585689) (xy 383.921771 -381.577981) (xy 383.931922 -381.577596) (xy 384.648202 -381.577596)
			(xy 384.658323 -381.578124) (xy 384.677036 -381.585844) (xy 384.691391 -381.600117) (xy 384.699218 -381.618786)
			(xy 384.699764 -381.628904) (xy 384.699764 -381.786638) (xy 384.700164 -381.795826) (xy 384.706686 -381.81301)
			(xy 384.712464 -381.820166) (xy 384.734242 -381.845826) (xy 384.772191 -381.901412) (xy 384.803224 -381.961134)
			(xy 384.826898 -382.024137) (xy 384.842871 -382.089519) (xy 384.850916 -382.15634) (xy 384.850917 -382.223645)
			(xy 388.128979 -382.223645) (xy 388.12898 -382.156339) (xy 388.137025 -382.089516) (xy 388.152999 -382.024133)
			(xy 388.176674 -381.961128) (xy 388.207709 -381.901404) (xy 388.245659 -381.845818) (xy 388.267448 -381.820166)
			(xy 388.273247 -381.813023) (xy 388.279759 -381.795831) (xy 388.280148 -381.786638) (xy 388.280148 -381.628904)
			(xy 388.280624 -381.618757) (xy 388.288408 -381.600014) (xy 388.302788 -381.585693) (xy 388.321561 -381.577984)
			(xy 388.33171 -381.577596) (xy 389.04799 -381.577596) (xy 389.058111 -381.578133) (xy 389.076823 -381.58585)
			(xy 389.091178 -381.60012) (xy 389.099006 -381.618786) (xy 389.099552 -381.628904) (xy 389.099552 -381.786638)
			(xy 389.099955 -381.795826) (xy 389.106475 -381.813009) (xy 389.112252 -381.820166) (xy 389.13403 -381.845826)
			(xy 389.17198 -381.901411) (xy 389.203014 -381.961134) (xy 389.226688 -382.024137) (xy 389.242662 -382.089518)
			(xy 389.250707 -382.15634) (xy 389.250707 -382.223645) (xy 389.250707 -382.223646) (xy 418.92901 -382.223646)
			(xy 418.92901 -382.156339) (xy 418.937056 -382.089515) (xy 418.953032 -382.024132) (xy 418.976708 -381.961127)
			(xy 419.007745 -381.901403) (xy 419.045698 -381.845818) (xy 419.067488 -381.820166) (xy 419.07328 -381.813018)
			(xy 419.079798 -381.79583) (xy 419.080188 -381.786638) (xy 419.080188 -381.628904) (xy 419.080688 -381.618797)
			(xy 419.088422 -381.600121) (xy 419.102714 -381.585827) (xy 419.121389 -381.57809) (xy 419.131496 -381.577596)
			(xy 419.84803 -381.577596) (xy 419.858153 -381.578101) (xy 419.876867 -381.58583) (xy 419.89122 -381.60011)
			(xy 419.899046 -381.618783) (xy 419.899592 -381.628904) (xy 419.899592 -381.786638) (xy 419.899986 -381.795827)
			(xy 419.906511 -381.813011) (xy 419.912292 -381.820166) (xy 419.934069 -381.845827) (xy 419.972016 -381.901413)
			(xy 420.003048 -381.961135) (xy 420.02672 -382.024139) (xy 420.042693 -382.089519) (xy 420.050737 -382.156341)
			(xy 420.050738 -382.223644) (xy 420.050731 -382.223705) (xy 423.328802 -382.223705) (xy 423.328803 -382.15628)
			(xy 423.33688 -382.089342) (xy 423.352916 -382.023852) (xy 423.37668 -381.960755) (xy 423.407831 -381.900959)
			(xy 423.44592 -381.845324) (xy 423.467784 -381.819658) (xy 423.473579 -381.812512) (xy 423.480095 -381.795322)
			(xy 423.480484 -381.78613) (xy 423.480484 -381.628904) (xy 423.480988 -381.618798) (xy 423.488721 -381.600122)
			(xy 423.503012 -381.585828) (xy 423.521686 -381.57809) (xy 423.531792 -381.577596) (xy 424.248072 -381.577596)
			(xy 424.258192 -381.578039) (xy 424.276895 -381.585777) (xy 424.29121 -381.600085) (xy 424.298957 -381.618784)
			(xy 424.29938 -381.628904) (xy 424.29938 -381.78613) (xy 424.29978 -381.795318) (xy 424.306301 -381.812502)
			(xy 424.31208 -381.819658) (xy 424.333935 -381.845331) (xy 424.372025 -381.900964) (xy 424.403177 -381.960759)
			(xy 424.426943 -382.023855) (xy 424.44298 -382.089343) (xy 424.451057 -382.156281) (xy 424.451058 -382.223646)
			(xy 427.729097 -382.223646) (xy 427.729098 -382.156339) (xy 427.737144 -382.089515) (xy 427.753119 -382.024132)
			(xy 427.776794 -381.961127) (xy 427.807831 -381.901404) (xy 427.845783 -381.845818) (xy 427.867572 -381.820166)
			(xy 427.873374 -381.813025) (xy 427.879883 -381.795831) (xy 427.880272 -381.786638) (xy 427.880272 -381.628904)
			(xy 427.880724 -381.618754) (xy 427.888513 -381.600007) (xy 427.9029 -381.585684) (xy 427.921682 -381.577979)
			(xy 427.931834 -381.577596) (xy 428.648114 -381.577596) (xy 428.658236 -381.578114) (xy 428.676949 -381.585838)
			(xy 428.691303 -381.600114) (xy 428.69913 -381.618785) (xy 428.699676 -381.628904) (xy 428.699676 -381.786638)
			(xy 428.700073 -381.795826) (xy 428.706596 -381.81301) (xy 428.712376 -381.820166) (xy 428.734154 -381.845826)
			(xy 428.772102 -381.901412) (xy 428.803135 -381.961135) (xy 428.826807 -382.024138) (xy 428.84278 -382.089519)
			(xy 428.850825 -382.15634) (xy 428.850826 -382.223644) (xy 428.850826 -382.223646) (xy 432.128888 -382.223646)
			(xy 432.128889 -382.156339) (xy 432.136935 -382.089516) (xy 432.152909 -382.024133) (xy 432.176584 -381.961128)
			(xy 432.20762 -381.901404) (xy 432.245571 -381.845818) (xy 432.26736 -381.820166) (xy 432.273161 -381.813024)
			(xy 432.279671 -381.795831) (xy 432.28006 -381.786638) (xy 432.28006 -381.628904) (xy 432.280524 -381.618755)
			(xy 432.288311 -381.600011) (xy 432.302694 -381.585689) (xy 432.321471 -381.577981) (xy 432.331622 -381.577596)
			(xy 433.047902 -381.577596) (xy 433.058023 -381.578124) (xy 433.076736 -381.585844) (xy 433.091091 -381.600117)
			(xy 433.098918 -381.618786) (xy 433.099464 -381.628904) (xy 433.099464 -381.786638) (xy 433.099864 -381.795826)
			(xy 433.106386 -381.81301) (xy 433.112164 -381.820166) (xy 433.133942 -381.845826) (xy 433.171891 -381.901412)
			(xy 433.202924 -381.961134) (xy 433.226598 -382.024137) (xy 433.242571 -382.089519) (xy 433.250616 -382.15634)
			(xy 433.250617 -382.223645) (xy 433.242574 -382.290466) (xy 433.226602 -382.355848) (xy 433.202931 -382.418852)
			(xy 433.171899 -382.478576) (xy 433.133951 -382.534162) (xy 433.112164 -382.559814) (xy 433.106374 -382.566964)
			(xy 433.099856 -382.584151) (xy 433.099464 -382.593342) (xy 433.099464 -383.086864) (xy 433.0999 -383.096048)
			(xy 433.106397 -383.113232) (xy 433.112164 -383.120392) (xy 433.133967 -383.146031) (xy 433.171916 -383.20162)
			(xy 433.202948 -383.261345) (xy 433.226386 -383.323727) (xy 434.32903 -383.323727) (xy 434.329034 -383.256419)
			(xy 434.337081 -383.189595) (xy 434.353057 -383.124211) (xy 434.376732 -383.061205) (xy 434.407768 -383.00148)
			(xy 434.445719 -382.945893) (xy 434.467508 -382.92024) (xy 434.473313 -382.913101) (xy 434.479823 -382.895906)
			(xy 434.480208 -382.886712) (xy 434.480208 -382.728724) (xy 434.480641 -382.71857) (xy 434.48843 -382.699817)
			(xy 434.502824 -382.685492) (xy 434.521614 -382.677793) (xy 434.53177 -382.677416) (xy 435.24805 -382.677416)
			(xy 435.258171 -382.677967) (xy 435.276886 -382.685674) (xy 435.291243 -382.69994) (xy 435.299068 -382.718607)
			(xy 435.299612 -382.728724) (xy 435.299612 -382.886712) (xy 435.300014 -382.8959) (xy 435.306533 -382.913084)
			(xy 435.312312 -382.92024) (xy 435.334066 -382.945921) (xy 435.372019 -383.001502) (xy 435.403056 -383.061221)
			(xy 435.426733 -383.124222) (xy 435.44271 -383.189601) (xy 435.450758 -383.256421) (xy 435.450761 -383.323724)
			(xy 435.44272 -383.390546) (xy 435.426749 -383.455926) (xy 435.403079 -383.518929) (xy 435.372047 -383.578652)
			(xy 435.334099 -383.634237) (xy 435.312312 -383.659888) (xy 435.306497 -383.66702) (xy 435.299993 -383.684221)
			(xy 435.299612 -383.693416) (xy 435.299612 -384.186684) (xy 435.300027 -384.195871) (xy 435.306537 -384.213055)
			(xy 435.312312 -384.220212) (xy 435.334137 -384.245834) (xy 435.372087 -384.301424) (xy 435.403122 -384.361151)
			(xy 435.426795 -384.42416) (xy 435.442767 -384.489546) (xy 435.450809 -384.556373) (xy 435.450805 -384.623681)
			(xy 435.442757 -384.690507) (xy 435.426779 -384.755892) (xy 435.4031 -384.818898) (xy 435.37206 -384.878623)
			(xy 435.334103 -384.934208) (xy 435.312312 -384.95986) (xy 435.306509 -384.967001) (xy 435.299998 -384.984195)
			(xy 435.299612 -384.993388) (xy 435.299612 -385.151376) (xy 435.299159 -385.161527) (xy 435.291374 -385.180277)
			(xy 435.276987 -385.194601) (xy 435.258203 -385.202303) (xy 435.24805 -385.202684) (xy 434.53177 -385.202684)
			(xy 434.521644 -385.202199) (xy 434.502927 -385.194466) (xy 434.488573 -385.180179) (xy 434.48075 -385.161499)
			(xy 434.480208 -385.151376) (xy 434.480208 -384.993388) (xy 434.479802 -384.9842) (xy 434.473285 -384.967016)
			(xy 434.467508 -384.95986) (xy 434.445757 -384.934178) (xy 434.407809 -384.878595) (xy 434.376776 -384.818876)
			(xy 434.353102 -384.755875) (xy 434.337128 -384.690497) (xy 434.329081 -384.623678) (xy 434.329078 -384.556376)
			(xy 434.337118 -384.489557) (xy 434.353086 -384.424177) (xy 434.376753 -384.361174) (xy 434.407781 -384.301451)
			(xy 434.445723 -384.245864) (xy 434.467508 -384.220212) (xy 434.473325 -384.213082) (xy 434.479827 -384.19588)
			(xy 434.480208 -384.186684) (xy 434.480208 -383.693416) (xy 434.479788 -383.68423) (xy 434.473281 -383.667046)
			(xy 434.467508 -383.659888) (xy 434.445686 -383.634265) (xy 434.40774 -383.578673) (xy 434.37671 -383.518945)
			(xy 434.353041 -383.455937) (xy 434.337071 -383.390552) (xy 434.32903 -383.323727) (xy 433.226386 -383.323727)
			(xy 433.22662 -383.324351) (xy 433.242592 -383.389735) (xy 433.250634 -383.456559) (xy 433.250633 -383.523865)
			(xy 433.242587 -383.590689) (xy 433.226613 -383.656072) (xy 433.202938 -383.719077) (xy 433.171903 -383.778801)
			(xy 433.133953 -383.834388) (xy 433.112164 -383.86004) (xy 433.106363 -383.867182) (xy 433.099852 -383.884375)
			(xy 433.099464 -383.893568) (xy 433.099464 -384.051556) (xy 433.099042 -384.061712) (xy 433.091254 -384.08047)
			(xy 433.076856 -384.094796) (xy 433.05806 -384.102491) (xy 433.047902 -384.102864) (xy 432.331622 -384.102864)
			(xy 432.321497 -384.102356) (xy 432.302777 -384.094636) (xy 432.28842 -384.080356) (xy 432.2806 -384.061678)
			(xy 432.28006 -384.051556) (xy 432.28006 -383.893568) (xy 432.279652 -383.884381) (xy 432.273135 -383.867197)
			(xy 432.26736 -383.86004) (xy 432.245587 -383.834375) (xy 432.207637 -383.778791) (xy 432.176602 -383.719069)
			(xy 432.152927 -383.656066) (xy 432.136952 -383.590686) (xy 432.128907 -383.523864) (xy 432.128905 -383.45656)
			(xy 432.136948 -383.389738) (xy 432.15292 -383.324357) (xy 432.176592 -383.261353) (xy 432.207624 -383.20163)
			(xy 432.245573 -383.146044) (xy 432.26736 -383.120392) (xy 432.27315 -383.113242) (xy 432.279667 -383.096055)
			(xy 432.28006 -383.086864) (xy 432.28006 -382.593342) (xy 432.279616 -382.584159) (xy 432.273125 -382.566975)
			(xy 432.26736 -382.559814) (xy 432.245562 -382.53417) (xy 432.207612 -382.478583) (xy 432.176578 -382.418858)
			(xy 432.152905 -382.355853) (xy 432.136932 -382.290469) (xy 432.128888 -382.223646) (xy 428.850826 -382.223646)
			(xy 428.842783 -382.290466) (xy 428.826812 -382.355848) (xy 428.803141 -382.418852) (xy 428.772109 -382.478575)
			(xy 428.734163 -382.534162) (xy 428.712376 -382.559814) (xy 428.706588 -382.566965) (xy 428.700069 -382.584151)
			(xy 428.699676 -382.593342) (xy 428.699676 -383.086864) (xy 428.700109 -383.096049) (xy 428.706607 -383.113233)
			(xy 428.712376 -383.120392) (xy 428.734179 -383.146031) (xy 428.772126 -383.20162) (xy 428.803158 -383.261345)
			(xy 428.826616 -383.323786) (xy 429.928711 -383.323786) (xy 429.928714 -383.25636) (xy 429.936794 -383.189418)
			(xy 429.952834 -383.123927) (xy 429.976603 -383.060829) (xy 430.007759 -383.001032) (xy 430.045853 -382.945397)
			(xy 430.06772 -382.919732) (xy 430.07353 -382.912597) (xy 430.080036 -382.895398) (xy 430.08042 -382.886204)
			(xy 430.08042 -382.728724) (xy 430.080836 -382.718601) (xy 430.08858 -382.699894) (xy 430.102897 -382.685578)
			(xy 430.121605 -382.677835) (xy 430.131728 -382.677416) (xy 430.848008 -382.677416) (xy 430.858133 -382.67781)
			(xy 430.87684 -382.685564) (xy 430.891154 -382.699887) (xy 430.898896 -382.718599) (xy 430.899316 -382.728724)
			(xy 430.899316 -382.886204) (xy 430.899721 -382.895392) (xy 430.906238 -382.912576) (xy 430.912016 -382.919732)
			(xy 430.933844 -382.945427) (xy 430.971933 -383.001057) (xy 431.003084 -383.06085) (xy 431.02685 -383.123943)
			(xy 431.042887 -383.189428) (xy 431.050966 -383.256363) (xy 431.050969 -383.323783) (xy 431.042897 -383.390719)
			(xy 431.026866 -383.456206) (xy 431.003106 -383.519301) (xy 430.971961 -383.579096) (xy 430.933877 -383.634731)
			(xy 430.912016 -383.660396) (xy 430.90624 -383.667556) (xy 430.899713 -383.684735) (xy 430.899316 -383.693924)
			(xy 430.899316 -384.186176) (xy 430.899734 -384.195362) (xy 430.906242 -384.212547) (xy 430.912016 -384.219704)
			(xy 430.933915 -384.24534) (xy 430.972001 -384.300979) (xy 431.00315 -384.36078) (xy 431.026911 -384.42388)
			(xy 431.042944 -384.489373) (xy 431.051016 -384.556314) (xy 431.051013 -384.62374) (xy 431.042934 -384.690681)
			(xy 431.026895 -384.756171) (xy 431.003128 -384.81927) (xy 430.971974 -384.879067) (xy 430.933882 -384.934702)
			(xy 430.912016 -384.960368) (xy 430.90621 -384.967507) (xy 430.8997 -384.984702) (xy 430.899316 -384.993896)
			(xy 430.899316 -385.151376) (xy 430.898865 -385.161495) (xy 430.891128 -385.180195) (xy 430.876822 -385.19451)
			(xy 430.858127 -385.202259) (xy 430.848008 -385.202684) (xy 430.131728 -385.202684) (xy 430.121605 -385.202261)
			(xy 430.102899 -385.194519) (xy 430.088583 -385.180204) (xy 430.08084 -385.161499) (xy 430.08042 -385.151376)
			(xy 430.08042 -384.993896) (xy 430.080008 -384.984709) (xy 430.073495 -384.967525) (xy 430.06772 -384.960368)
			(xy 430.045891 -384.934674) (xy 430.0078 -384.879044) (xy 429.976646 -384.819252) (xy 429.952879 -384.756159)
			(xy 429.936841 -384.690673) (xy 429.928761 -384.623738) (xy 429.928758 -384.556316) (xy 429.936831 -384.48938)
			(xy 429.952863 -384.423893) (xy 429.976624 -384.360797) (xy 430.007772 -384.301002) (xy 430.045857 -384.245369)
			(xy 430.06772 -384.219704) (xy 430.0735 -384.212547) (xy 430.080024 -384.195365) (xy 430.08042 -384.186176)
			(xy 430.08042 -383.693924) (xy 430.079994 -383.684739) (xy 430.073491 -383.667554) (xy 430.06772 -383.660396)
			(xy 430.04582 -383.63476) (xy 430.007731 -383.579122) (xy 429.976581 -383.519322) (xy 429.952818 -383.456221)
			(xy 429.936784 -383.390728) (xy 429.928711 -383.323786) (xy 428.826616 -383.323786) (xy 428.826829 -383.324352)
			(xy 428.842801 -383.389735) (xy 428.850843 -383.456559) (xy 428.850842 -383.523865) (xy 428.842797 -383.590688)
			(xy 428.826822 -383.656071) (xy 428.803148 -383.719077) (xy 428.772114 -383.778801) (xy 428.734164 -383.834388)
			(xy 428.712376 -383.86004) (xy 428.706577 -383.867183) (xy 428.700065 -383.884375) (xy 428.699676 -383.893568)
			(xy 428.699676 -384.051556) (xy 428.699242 -384.06171) (xy 428.691456 -384.080466) (xy 428.677063 -384.094792)
			(xy 428.65827 -384.102489) (xy 428.648114 -384.102864) (xy 427.931834 -384.102864) (xy 427.92171 -384.102345)
			(xy 427.90299 -384.09463) (xy 427.888633 -384.080353) (xy 427.880812 -384.061677) (xy 427.880272 -384.051556)
			(xy 427.880272 -383.893568) (xy 427.879883 -383.884378) (xy 427.873355 -383.867194) (xy 427.867572 -383.86004)
			(xy 427.845799 -383.834375) (xy 427.807848 -383.778791) (xy 427.776812 -383.71907) (xy 427.753137 -383.656067)
			(xy 427.737162 -383.590686) (xy 427.729116 -383.523864) (xy 427.729114 -383.45656) (xy 427.737157 -383.389738)
			(xy 427.75313 -383.324356) (xy 427.776802 -383.261352) (xy 427.807835 -383.201629) (xy 427.845784 -383.146044)
			(xy 427.867572 -383.120392) (xy 427.873363 -383.113243) (xy 427.879879 -383.096055) (xy 427.880272 -383.086864)
			(xy 427.880272 -382.593342) (xy 427.879848 -382.584156) (xy 427.873344 -382.566971) (xy 427.867572 -382.559814)
			(xy 427.845774 -382.53417) (xy 427.807823 -382.478583) (xy 427.776788 -382.418859) (xy 427.753115 -382.355853)
			(xy 427.737141 -382.29047) (xy 427.729097 -382.223646) (xy 424.451058 -382.223646) (xy 424.451058 -382.223704)
			(xy 424.442983 -382.290642) (xy 424.426948 -382.356131) (xy 424.403184 -382.419227) (xy 424.372033 -382.479023)
			(xy 424.333944 -382.534657) (xy 424.31208 -382.560322) (xy 424.306289 -382.567471) (xy 424.299772 -382.584659)
			(xy 424.29938 -382.59385) (xy 424.29938 -383.086356) (xy 424.299816 -383.09554) (xy 424.306312 -383.112725)
			(xy 424.31208 -383.119884) (xy 424.33396 -383.145536) (xy 424.37205 -383.201172) (xy 424.403201 -383.26097)
			(xy 424.426837 -383.323727) (xy 425.528942 -383.323727) (xy 425.528946 -383.256419) (xy 425.536993 -383.189594)
			(xy 425.55297 -383.12421) (xy 425.576646 -383.061204) (xy 425.607682 -383.00148) (xy 425.645635 -382.945892)
			(xy 425.667424 -382.92024) (xy 425.673231 -382.913103) (xy 425.679739 -382.895906) (xy 425.680124 -382.886712)
			(xy 425.680124 -382.728724) (xy 425.680536 -382.7186) (xy 425.688281 -382.699892) (xy 425.702599 -382.685576)
			(xy 425.721308 -382.677834) (xy 425.731432 -382.677416) (xy 426.447966 -382.677416) (xy 426.458088 -382.677954)
			(xy 426.476803 -382.685666) (xy 426.49116 -382.699937) (xy 426.498984 -382.718606) (xy 426.499528 -382.728724)
			(xy 426.499528 -382.886712) (xy 426.499926 -382.895901) (xy 426.506447 -382.913085) (xy 426.512228 -382.92024)
			(xy 426.533981 -382.945921) (xy 426.571933 -383.001502) (xy 426.60297 -383.061222) (xy 426.626646 -383.124223)
			(xy 426.642623 -383.189602) (xy 426.65067 -383.256422) (xy 426.650673 -383.323724) (xy 426.642632 -383.390545)
			(xy 426.626662 -383.455926) (xy 426.602992 -383.518929) (xy 426.571961 -383.578651) (xy 426.534014 -383.634236)
			(xy 426.512228 -383.659888) (xy 426.506403 -383.667013) (xy 426.499907 -383.684219) (xy 426.499528 -383.693416)
			(xy 426.499528 -384.186684) (xy 426.499939 -384.195871) (xy 426.506451 -384.213056) (xy 426.512228 -384.220212)
			(xy 426.534052 -384.245834) (xy 426.572002 -384.301424) (xy 426.603036 -384.361152) (xy 426.626708 -384.42416)
			(xy 426.64268 -384.489546) (xy 426.650721 -384.556373) (xy 426.650718 -384.623681) (xy 426.64267 -384.690507)
			(xy 426.626692 -384.755892) (xy 426.603014 -384.818898) (xy 426.571974 -384.878622) (xy 426.534019 -384.934208)
			(xy 426.512228 -384.95986) (xy 426.506415 -384.966993) (xy 426.499912 -384.984193) (xy 426.499528 -384.993388)
			(xy 426.499528 -385.151376) (xy 426.499065 -385.161494) (xy 426.49133 -385.180191) (xy 426.477028 -385.194505)
			(xy 426.458337 -385.202257) (xy 426.44822 -385.202684) (xy 425.731686 -385.202684) (xy 425.721561 -385.202185)
			(xy 425.702845 -385.194457) (xy 425.68849 -385.180175) (xy 425.680667 -385.161498) (xy 425.680124 -385.151376)
			(xy 425.680124 -384.993388) (xy 425.679714 -384.984201) (xy 425.6732 -384.967017) (xy 425.667424 -384.95986)
			(xy 425.645672 -384.934178) (xy 425.607723 -384.878596) (xy 425.576689 -384.818876) (xy 425.553015 -384.755876)
			(xy 425.53704 -384.690497) (xy 425.528994 -384.623678) (xy 425.52899 -384.556376) (xy 425.537031 -384.489556)
			(xy 425.552999 -384.424176) (xy 425.576667 -384.361173) (xy 425.607696 -384.301451) (xy 425.645639 -384.245865)
			(xy 425.667424 -384.220212) (xy 425.673243 -384.213083) (xy 425.679744 -384.19588) (xy 425.680124 -384.186684)
			(xy 425.680124 -383.693416) (xy 425.679701 -383.68423) (xy 425.673195 -383.667046) (xy 425.667424 -383.659888)
			(xy 425.645601 -383.634265) (xy 425.607655 -383.578674) (xy 425.576624 -383.518946) (xy 425.552954 -383.455938)
			(xy 425.536984 -383.390552) (xy 425.528942 -383.323727) (xy 424.426837 -383.323727) (xy 424.426965 -383.324068)
			(xy 424.443 -383.389559) (xy 424.451075 -383.456499) (xy 424.451074 -383.523925) (xy 424.442996 -383.590864)
			(xy 424.426958 -383.656355) (xy 424.403191 -383.719452) (xy 424.372038 -383.779249) (xy 424.333946 -383.834883)
			(xy 424.31208 -383.860548) (xy 424.306278 -383.867689) (xy 424.299767 -383.884883) (xy 424.29938 -383.894076)
			(xy 424.29938 -384.051556) (xy 424.298947 -384.061678) (xy 424.29121 -384.080385) (xy 424.276898 -384.094701)
			(xy 424.258194 -384.102444) (xy 424.248072 -384.102864) (xy 423.531792 -384.102864) (xy 423.521665 -384.10249)
			(xy 423.502954 -384.094732) (xy 423.488639 -384.080402) (xy 423.4809 -384.061684) (xy 423.480484 -384.051556)
			(xy 423.480484 -383.894076) (xy 423.480089 -383.884887) (xy 423.473565 -383.867703) (xy 423.467784 -383.860548)
			(xy 423.445936 -383.83487) (xy 423.407848 -383.779237) (xy 423.376698 -383.719442) (xy 423.352933 -383.656347)
			(xy 423.336897 -383.59086) (xy 423.32882 -383.523923) (xy 423.328819 -383.456501) (xy 423.336893 -383.389564)
			(xy 423.352926 -383.324076) (xy 423.376688 -383.26098) (xy 423.407836 -383.201184) (xy 423.445922 -383.145549)
			(xy 423.467784 -383.119884) (xy 423.473568 -383.11273) (xy 423.480091 -383.095546) (xy 423.480484 -383.086356)
			(xy 423.480484 -382.59385) (xy 423.480054 -382.584665) (xy 423.473554 -382.56748) (xy 423.467784 -382.560322)
			(xy 423.445911 -382.534665) (xy 423.407823 -382.479029) (xy 423.376674 -382.419231) (xy 423.352911 -382.356133)
			(xy 423.336877 -382.290643) (xy 423.328802 -382.223705) (xy 420.050731 -382.223705) (xy 420.042695 -382.290466)
			(xy 420.026725 -382.355847) (xy 420.003054 -382.418851) (xy 419.972024 -382.478574) (xy 419.934078 -382.534161)
			(xy 419.912292 -382.559814) (xy 419.906506 -382.566967) (xy 419.899985 -382.584151) (xy 419.899592 -382.593342)
			(xy 419.899592 -383.086864) (xy 419.900021 -383.096049) (xy 419.906522 -383.113234) (xy 419.912292 -383.120392)
			(xy 419.934094 -383.146032) (xy 419.972041 -383.201621) (xy 420.003072 -383.261346) (xy 420.02653 -383.323787)
			(xy 421.128623 -383.323787) (xy 421.128626 -383.256359) (xy 421.136706 -383.189418) (xy 421.152747 -383.123926)
			(xy 421.176516 -383.060828) (xy 421.207673 -383.001031) (xy 421.245769 -382.945397) (xy 421.267636 -382.919732)
			(xy 421.273449 -382.912598) (xy 421.279953 -382.895399) (xy 421.280336 -382.886204) (xy 421.280336 -382.728724)
			(xy 421.280736 -382.718599) (xy 421.288483 -382.699889) (xy 421.302805 -382.685572) (xy 421.321518 -382.677832)
			(xy 421.331644 -382.677416) (xy 422.047924 -382.677416) (xy 422.058036 -382.677866) (xy 422.076718 -382.685614)
			(xy 422.091013 -382.699922) (xy 422.098744 -382.718611) (xy 422.099232 -382.728724) (xy 422.099232 -382.886204)
			(xy 422.099656 -382.895389) (xy 422.106162 -382.912573) (xy 422.111932 -382.919732) (xy 422.133759 -382.945427)
			(xy 422.171847 -383.001058) (xy 422.202998 -383.06085) (xy 422.226762 -383.123943) (xy 422.242799 -383.189428)
			(xy 422.250878 -383.256363) (xy 422.250881 -383.323783) (xy 422.242809 -383.390718) (xy 422.226778 -383.456205)
			(xy 422.20302 -383.5193) (xy 422.171875 -383.579096) (xy 422.133793 -383.63473) (xy 422.111932 -383.660396)
			(xy 422.106146 -383.667549) (xy 422.099627 -383.684734) (xy 422.099232 -383.693924) (xy 422.099232 -384.186176)
			(xy 422.099669 -384.19536) (xy 422.106166 -384.212544) (xy 422.111932 -384.219704) (xy 422.13383 -384.245341)
			(xy 422.171916 -384.30098) (xy 422.203063 -384.36078) (xy 422.226824 -384.423881) (xy 422.242856 -384.489373)
			(xy 422.250928 -384.556314) (xy 422.250925 -384.62374) (xy 422.242846 -384.69068) (xy 422.226808 -384.756171)
			(xy 422.203041 -384.819269) (xy 422.171888 -384.879066) (xy 422.133797 -384.934702) (xy 422.111932 -384.960368)
			(xy 422.106116 -384.967499) (xy 422.099615 -384.984701) (xy 422.099232 -384.993896) (xy 422.099232 -385.151376)
			(xy 422.098696 -385.161479) (xy 422.090972 -385.180151) (xy 422.076691 -385.194445) (xy 422.058027 -385.202187)
			(xy 422.047924 -385.202684) (xy 421.331644 -385.202684) (xy 421.321522 -385.202247) (xy 421.302817 -385.194511)
			(xy 421.2885 -385.1802) (xy 421.280756 -385.161497) (xy 421.280336 -385.151376) (xy 421.280336 -384.993896)
			(xy 421.27992 -384.98471) (xy 421.27341 -384.967526) (xy 421.267636 -384.960368) (xy 421.245806 -384.934674)
			(xy 421.207714 -384.879045) (xy 421.17656 -384.819253) (xy 421.152792 -384.756159) (xy 421.136753 -384.690673)
			(xy 421.128674 -384.623738) (xy 421.12867 -384.556316) (xy 421.136743 -384.48938) (xy 421.152776 -384.423892)
			(xy 421.176538 -384.360797) (xy 421.207686 -384.301002) (xy 421.245773 -384.245369) (xy 421.267636 -384.219704)
			(xy 421.273418 -384.212549) (xy 421.27994 -384.195366) (xy 421.280336 -384.186176) (xy 421.280336 -383.693924)
			(xy 421.279906 -383.684739) (xy 421.273405 -383.667555) (xy 421.267636 -383.660396) (xy 421.245735 -383.634761)
			(xy 421.207645 -383.579123) (xy 421.176494 -383.519323) (xy 421.152731 -383.456222) (xy 421.136696 -383.390729)
			(xy 421.128623 -383.323787) (xy 420.02653 -383.323787) (xy 420.026742 -383.324352) (xy 420.042713 -383.389736)
			(xy 420.050756 -383.456559) (xy 420.050754 -383.523865) (xy 420.042709 -383.590688) (xy 420.026735 -383.656071)
			(xy 420.003062 -383.719076) (xy 419.972028 -383.7788) (xy 419.93408 -383.834387) (xy 419.912292 -383.86004)
			(xy 419.906495 -383.867185) (xy 419.899981 -383.884376) (xy 419.899592 -383.893568) (xy 419.899592 -384.051556)
			(xy 419.899148 -384.061677) (xy 419.891413 -384.080381) (xy 419.877104 -384.094697) (xy 419.858404 -384.102442)
			(xy 419.848284 -384.102864) (xy 419.13175 -384.102864) (xy 419.121627 -384.102333) (xy 419.102908 -384.094622)
			(xy 419.08855 -384.080349) (xy 419.080728 -384.061676) (xy 419.080188 -384.051556) (xy 419.080188 -383.893568)
			(xy 419.079796 -383.884379) (xy 419.07327 -383.867194) (xy 419.067488 -383.86004) (xy 419.045715 -383.834376)
			(xy 419.007762 -383.778792) (xy 418.976725 -383.719071) (xy 418.95305 -383.656068) (xy 418.937074 -383.590686)
			(xy 418.929028 -383.523864) (xy 418.929026 -383.45656) (xy 418.93707 -383.389737) (xy 418.953042 -383.324355)
			(xy 418.976716 -383.261351) (xy 419.00775 -383.201629) (xy 419.0457 -383.146043) (xy 419.067488 -383.120392)
			(xy 419.073269 -383.113236) (xy 419.079793 -383.096054) (xy 419.080188 -383.086864) (xy 419.080188 -382.593342)
			(xy 419.07976 -382.584157) (xy 419.073259 -382.566972) (xy 419.067488 -382.559814) (xy 419.045689 -382.534171)
			(xy 419.007737 -382.478584) (xy 418.976702 -382.41886) (xy 418.953027 -382.355854) (xy 418.937054 -382.29047)
			(xy 418.92901 -382.223646) (xy 389.250707 -382.223646) (xy 389.242664 -382.290467) (xy 389.226692 -382.355848)
			(xy 389.20302 -382.418853) (xy 389.171987 -382.478576) (xy 389.134039 -382.534162) (xy 389.112252 -382.559814)
			(xy 389.106461 -382.566963) (xy 389.099944 -382.584151) (xy 389.099552 -382.593342) (xy 389.099552 -383.086864)
			(xy 389.09999 -383.096048) (xy 389.106485 -383.113232) (xy 389.112252 -383.120392) (xy 389.134056 -383.146031)
			(xy 389.172005 -383.201619) (xy 389.203038 -383.261344) (xy 389.226475 -383.323726) (xy 390.329121 -383.323726)
			(xy 390.329125 -383.256419) (xy 390.337172 -383.189595) (xy 390.353147 -383.124211) (xy 390.376822 -383.061206)
			(xy 390.407857 -383.001481) (xy 390.445807 -382.945893) (xy 390.467596 -382.92024) (xy 390.4734 -382.9131)
			(xy 390.47991 -382.895906) (xy 390.480296 -382.886712) (xy 390.480296 -382.728724) (xy 390.480741 -382.718572)
			(xy 390.488528 -382.699821) (xy 390.502918 -382.685497) (xy 390.521704 -382.677795) (xy 390.531858 -382.677416)
			(xy 391.248138 -382.677416) (xy 391.258264 -382.677895) (xy 391.276982 -382.685631) (xy 391.291336 -382.699919)
			(xy 391.299158 -382.7186) (xy 391.2997 -382.728724) (xy 391.2997 -382.886712) (xy 391.300105 -382.8959)
			(xy 391.306622 -382.913084) (xy 391.3124 -382.92024) (xy 391.334151 -382.945922) (xy 391.372099 -383.001505)
			(xy 391.403131 -383.061225) (xy 391.426804 -383.124225) (xy 391.442779 -383.189603) (xy 391.450825 -383.256422)
			(xy 391.450828 -383.323724) (xy 391.442788 -383.390543) (xy 391.42682 -383.455923) (xy 391.403153 -383.518926)
			(xy 391.372126 -383.578649) (xy 391.334184 -383.634235) (xy 391.3124 -383.659888) (xy 391.306584 -383.667019)
			(xy 391.300081 -383.68422) (xy 391.2997 -383.693416) (xy 391.2997 -384.186684) (xy 391.300118 -384.19587)
			(xy 391.306626 -384.213055) (xy 391.3124 -384.220212) (xy 391.334222 -384.245836) (xy 391.372167 -384.301427)
			(xy 391.403197 -384.361155) (xy 391.426866 -384.424163) (xy 391.442835 -384.489548) (xy 391.450876 -384.556374)
			(xy 391.450872 -384.623681) (xy 391.442825 -384.690505) (xy 391.42685 -384.755889) (xy 391.403175 -384.818895)
			(xy 391.372139 -384.878619) (xy 391.334189 -384.934207) (xy 391.3124 -384.95986) (xy 391.306595 -384.967)
			(xy 391.300086 -384.984194) (xy 391.2997 -384.993388) (xy 391.2997 -385.151376) (xy 391.299259 -385.161529)
			(xy 391.291471 -385.180281) (xy 391.27708 -385.194605) (xy 391.258292 -385.202305) (xy 391.248138 -385.202684)
			(xy 390.531858 -385.202684) (xy 390.521732 -385.202209) (xy 390.503014 -385.194471) (xy 390.48866 -385.180182)
			(xy 390.480838 -385.1615) (xy 390.480296 -385.151376) (xy 390.480296 -384.993388) (xy 390.479892 -384.9842)
			(xy 390.473374 -384.967016) (xy 390.467596 -384.95986) (xy 390.445845 -384.934178) (xy 390.407898 -384.878595)
			(xy 390.376865 -384.818875) (xy 390.353192 -384.755875) (xy 390.337218 -384.690496) (xy 390.329172 -384.623678)
			(xy 390.329169 -384.556376) (xy 390.337209 -384.489557) (xy 390.353176 -384.424177) (xy 390.376843 -384.361174)
			(xy 390.40787 -384.301452) (xy 390.445812 -384.245865) (xy 390.467596 -384.220212) (xy 390.473412 -384.21308)
			(xy 390.479915 -384.19588) (xy 390.480296 -384.186684) (xy 390.480296 -383.693416) (xy 390.479879 -383.68423)
			(xy 390.47337 -383.667045) (xy 390.467596 -383.659888) (xy 390.445774 -383.634264) (xy 390.407829 -383.578673)
			(xy 390.3768 -383.518945) (xy 390.353131 -383.455937) (xy 390.337162 -383.390552) (xy 390.329121 -383.323726)
			(xy 389.226475 -383.323726) (xy 389.22671 -383.324351) (xy 389.242682 -383.389735) (xy 389.250725 -383.456559)
			(xy 389.250724 -383.523865) (xy 389.242678 -383.590689) (xy 389.226703 -383.656072) (xy 389.203028 -383.719078)
			(xy 389.171992 -383.778802) (xy 389.134041 -383.834388) (xy 389.112252 -383.86004) (xy 389.10645 -383.867181)
			(xy 389.09994 -383.884375) (xy 389.099552 -383.893568) (xy 389.099552 -384.051556) (xy 389.099043 -384.061701)
			(xy 389.091272 -384.080442) (xy 389.076902 -384.094765) (xy 389.058136 -384.102476) (xy 389.04799 -384.102864)
			(xy 388.33171 -384.102864) (xy 388.321584 -384.102365) (xy 388.302864 -384.094642) (xy 388.288508 -384.080359)
			(xy 388.280687 -384.061679) (xy 388.280148 -384.051556) (xy 388.280148 -383.893568) (xy 388.279742 -383.884381)
			(xy 388.273224 -383.867197) (xy 388.267448 -383.86004) (xy 388.245676 -383.834375) (xy 388.207726 -383.778791)
			(xy 388.176692 -383.719069) (xy 388.153018 -383.656066) (xy 388.137043 -383.590685) (xy 388.128998 -383.523864)
			(xy 388.128996 -383.45656) (xy 388.137039 -383.389738) (xy 388.15301 -383.324357) (xy 388.176682 -383.261353)
			(xy 388.207714 -383.20163) (xy 388.245661 -383.146044) (xy 388.267448 -383.120392) (xy 388.273236 -383.113241)
			(xy 388.279755 -383.096055) (xy 388.280148 -383.086864) (xy 388.280148 -382.593342) (xy 388.279707 -382.584158)
			(xy 388.273213 -382.566974) (xy 388.267448 -382.559814) (xy 388.24565 -382.53417) (xy 388.207701 -382.478583)
			(xy 388.176668 -382.418858) (xy 388.152995 -382.355852) (xy 388.137022 -382.290469) (xy 388.128979 -382.223645)
			(xy 384.850917 -382.223645) (xy 384.842874 -382.290466) (xy 384.826902 -382.355848) (xy 384.803231 -382.418852)
			(xy 384.772199 -382.478576) (xy 384.734251 -382.534162) (xy 384.712464 -382.559814) (xy 384.706674 -382.566964)
			(xy 384.700156 -382.584151) (xy 384.699764 -382.593342) (xy 384.699764 -383.086864) (xy 384.7002 -383.096048)
			(xy 384.706697 -383.113232) (xy 384.712464 -383.120392) (xy 384.734267 -383.146031) (xy 384.772216 -383.20162)
			(xy 384.803248 -383.261345) (xy 384.826708 -383.323786) (xy 385.928802 -383.323786) (xy 385.928805 -383.25636)
			(xy 385.936885 -383.189419) (xy 385.952924 -383.123928) (xy 385.976693 -383.060829) (xy 386.007848 -383.001032)
			(xy 386.045942 -382.945397) (xy 386.067808 -382.919732) (xy 386.073617 -382.912596) (xy 386.080124 -382.895398)
			(xy 386.080508 -382.886204) (xy 386.080508 -382.728724) (xy 386.080936 -382.718602) (xy 386.088677 -382.699897)
			(xy 386.102991 -382.685582) (xy 386.121694 -382.677837) (xy 386.131816 -382.677416) (xy 386.848096 -382.677416)
			(xy 386.85822 -382.67782) (xy 386.876927 -382.685569) (xy 386.891242 -382.69989) (xy 386.898984 -382.7186)
			(xy 386.899404 -382.728724) (xy 386.899404 -382.886204) (xy 386.899811 -382.895391) (xy 386.906327 -382.912576)
			(xy 386.912104 -382.919732) (xy 386.933932 -382.945426) (xy 386.972022 -383.001057) (xy 387.003174 -383.060849)
			(xy 387.02694 -383.123942) (xy 387.042978 -383.189428) (xy 387.051057 -383.256363) (xy 387.05106 -383.323783)
			(xy 387.042988 -383.390719) (xy 387.026956 -383.456206) (xy 387.003196 -383.519301) (xy 386.97205 -383.579097)
			(xy 386.933966 -383.634731) (xy 386.912104 -383.660396) (xy 386.906327 -383.667555) (xy 386.899801 -383.684735)
			(xy 386.899404 -383.693924) (xy 386.899404 -384.186176) (xy 386.899825 -384.195362) (xy 386.906331 -384.212547)
			(xy 386.912104 -384.219704) (xy 386.934003 -384.24534) (xy 386.972091 -384.300979) (xy 387.003239 -384.360779)
			(xy 387.027001 -384.42388) (xy 387.043034 -384.489372) (xy 387.051107 -384.556314) (xy 387.051104 -384.62374)
			(xy 387.043025 -384.690681) (xy 387.026985 -384.756172) (xy 387.003217 -384.81927) (xy 386.972063 -384.879068)
			(xy 386.93397 -384.934703) (xy 386.912104 -384.960368) (xy 386.906297 -384.967506) (xy 386.899788 -384.984702)
			(xy 386.899404 -384.993896) (xy 386.899404 -385.151376) (xy 386.898965 -385.161496) (xy 386.891225 -385.180199)
			(xy 386.876916 -385.194514) (xy 386.858216 -385.202261) (xy 386.848096 -385.202684) (xy 386.131816 -385.202684)
			(xy 386.121693 -385.202271) (xy 386.102986 -385.194525) (xy 386.088671 -385.180207) (xy 386.080928 -385.1615)
			(xy 386.080508 -385.151376) (xy 386.080508 -384.993896) (xy 386.080098 -384.984709) (xy 386.073584 -384.967525)
			(xy 386.067808 -384.960368) (xy 386.045979 -384.934674) (xy 386.007889 -384.879044) (xy 385.976736 -384.819251)
			(xy 385.95297 -384.756158) (xy 385.936931 -384.690673) (xy 385.928852 -384.623738) (xy 385.928849 -384.556317)
			(xy 385.936922 -384.489381) (xy 385.952954 -384.423893) (xy 385.976714 -384.360798) (xy 386.007861 -384.301003)
			(xy 386.045946 -384.245369) (xy 386.067808 -384.219704) (xy 386.073586 -384.212546) (xy 386.080112 -384.195365)
			(xy 386.080508 -384.186176) (xy 386.080508 -383.693924) (xy 386.080084 -383.684738) (xy 386.07358 -383.667554)
			(xy 386.067808 -383.660396) (xy 386.045908 -383.63476) (xy 386.00782 -383.579122) (xy 385.976671 -383.519321)
			(xy 385.952908 -383.456221) (xy 385.936875 -383.390728) (xy 385.928802 -383.323786) (xy 384.826708 -383.323786)
			(xy 384.82692 -383.324351) (xy 384.842892 -383.389735) (xy 384.850934 -383.456559) (xy 384.850933 -383.523865)
			(xy 384.842887 -383.590689) (xy 384.826913 -383.656072) (xy 384.803238 -383.719077) (xy 384.772203 -383.778801)
			(xy 384.734253 -383.834388) (xy 384.712464 -383.86004) (xy 384.706663 -383.867182) (xy 384.700152 -383.884375)
			(xy 384.699764 -383.893568) (xy 384.699764 -384.051556) (xy 384.699342 -384.061712) (xy 384.691554 -384.08047)
			(xy 384.677156 -384.094796) (xy 384.65836 -384.102491) (xy 384.648202 -384.102864) (xy 383.931922 -384.102864)
			(xy 383.921797 -384.102356) (xy 383.903077 -384.094636) (xy 383.88872 -384.080356) (xy 383.8809 -384.061678)
			(xy 383.88036 -384.051556) (xy 383.88036 -383.893568) (xy 383.879952 -383.884381) (xy 383.873435 -383.867197)
			(xy 383.86766 -383.86004) (xy 383.845887 -383.834375) (xy 383.807937 -383.778791) (xy 383.776902 -383.719069)
			(xy 383.753227 -383.656066) (xy 383.737252 -383.590686) (xy 383.729207 -383.523864) (xy 383.729205 -383.45656)
			(xy 383.737248 -383.389738) (xy 383.75322 -383.324357) (xy 383.776892 -383.261353) (xy 383.807924 -383.20163)
			(xy 383.845873 -383.146044) (xy 383.86766 -383.120392) (xy 383.87345 -383.113242) (xy 383.879967 -383.096055)
			(xy 383.88036 -383.086864) (xy 383.88036 -382.593342) (xy 383.879916 -382.584159) (xy 383.873425 -382.566975)
			(xy 383.86766 -382.559814) (xy 383.845862 -382.53417) (xy 383.807912 -382.478583) (xy 383.776878 -382.418858)
			(xy 383.753205 -382.355853) (xy 383.737232 -382.290469) (xy 383.729188 -382.223646) (xy 380.451149 -382.223646)
			(xy 380.451149 -382.223704) (xy 380.443073 -382.290642) (xy 380.427038 -382.356131) (xy 380.403273 -382.419228)
			(xy 380.372122 -382.479024) (xy 380.334032 -382.534657) (xy 380.312168 -382.560322) (xy 380.306375 -382.56747)
			(xy 380.299859 -382.584658) (xy 380.299468 -382.59385) (xy 380.299468 -383.086356) (xy 380.299907 -383.09554)
			(xy 380.306401 -383.112724) (xy 380.312168 -383.119884) (xy 380.334049 -383.145536) (xy 380.372139 -383.201171)
			(xy 380.403291 -383.260969) (xy 380.426928 -383.323727) (xy 381.529033 -383.323727) (xy 381.529037 -383.256419)
			(xy 381.537084 -383.189595) (xy 381.55306 -383.124211) (xy 381.576736 -383.061205) (xy 381.607772 -383.00148)
			(xy 381.645723 -382.945893) (xy 381.667512 -382.92024) (xy 381.673318 -382.913101) (xy 381.679827 -382.895906)
			(xy 381.680212 -382.886712) (xy 381.680212 -382.728724) (xy 381.680641 -382.71857) (xy 381.688431 -382.699816)
			(xy 381.702826 -382.685491) (xy 381.721618 -382.677793) (xy 381.731774 -382.677416) (xy 382.448054 -382.677416)
			(xy 382.458175 -382.677964) (xy 382.47689 -382.685672) (xy 382.491247 -382.699939) (xy 382.499072 -382.718606)
			(xy 382.499616 -382.728724) (xy 382.499616 -382.886712) (xy 382.500017 -382.8959) (xy 382.506537 -382.913085)
			(xy 382.512316 -382.92024) (xy 382.53407 -382.945921) (xy 382.572023 -383.001502) (xy 382.60306 -383.061221)
			(xy 382.626737 -383.124222) (xy 382.642713 -383.189601) (xy 382.650761 -383.256421) (xy 382.650764 -383.323724)
			(xy 382.642723 -383.390545) (xy 382.626753 -383.455926) (xy 382.603082 -383.518929) (xy 382.57205 -383.578652)
			(xy 382.534103 -383.634236) (xy 382.512316 -383.659888) (xy 382.506501 -383.667021) (xy 382.499997 -383.684221)
			(xy 382.499616 -383.693416) (xy 382.499616 -384.186684) (xy 382.50003 -384.195871) (xy 382.506541 -384.213055)
			(xy 382.512316 -384.220212) (xy 382.53414 -384.245834) (xy 382.572091 -384.301424) (xy 382.603125 -384.361151)
			(xy 382.626798 -384.42416) (xy 382.64277 -384.489546) (xy 382.650812 -384.556373) (xy 382.650808 -384.623681)
			(xy 382.64276 -384.690507) (xy 382.626782 -384.755892) (xy 382.603103 -384.818898) (xy 382.572063 -384.878622)
			(xy 382.534107 -384.934208) (xy 382.512316 -384.95986) (xy 382.506513 -384.967001) (xy 382.500002 -384.984195)
			(xy 382.499616 -384.993388) (xy 382.499616 -385.151376) (xy 382.499159 -385.161527) (xy 382.491375 -385.180275)
			(xy 382.476989 -385.194599) (xy 382.458206 -385.202303) (xy 382.448054 -385.202684) (xy 381.731774 -385.202684)
			(xy 381.721649 -385.202196) (xy 381.702931 -385.194464) (xy 381.688577 -385.180179) (xy 381.680754 -385.161499)
			(xy 381.680212 -385.151376) (xy 381.680212 -384.993388) (xy 381.679805 -384.984201) (xy 381.673289 -384.967016)
			(xy 381.667512 -384.95986) (xy 381.64576 -384.934178) (xy 381.607812 -384.878596) (xy 381.576779 -384.818876)
			(xy 381.553105 -384.755875) (xy 381.537131 -384.690497) (xy 381.529084 -384.623678) (xy 381.529081 -384.556376)
			(xy 381.537121 -384.489557) (xy 381.553089 -384.424177) (xy 381.576757 -384.361174) (xy 381.607784 -384.301451)
			(xy 381.645727 -384.245864) (xy 381.667512 -384.220212) (xy 381.67333 -384.213082) (xy 381.679831 -384.19588)
			(xy 381.680212 -384.186684) (xy 381.680212 -383.693416) (xy 381.679791 -383.68423) (xy 381.673285 -383.667046)
			(xy 381.667512 -383.659888) (xy 381.64569 -383.634265) (xy 381.607744 -383.578673) (xy 381.576714 -383.518946)
			(xy 381.553044 -383.455937) (xy 381.537074 -383.390552) (xy 381.529033 -383.323727) (xy 380.426928 -383.323727)
			(xy 380.427056 -383.324068) (xy 380.443091 -383.389559) (xy 380.451166 -383.456499) (xy 380.451165 -383.523925)
			(xy 380.443087 -383.590865) (xy 380.427049 -383.656355) (xy 380.403281 -383.719453) (xy 380.372127 -383.779249)
			(xy 380.334034 -383.834883) (xy 380.312168 -383.860548) (xy 380.306364 -383.867688) (xy 380.299855 -383.884883)
			(xy 380.299468 -383.894076) (xy 380.299468 -384.051556) (xy 380.299047 -384.06168) (xy 380.291308 -384.080388)
			(xy 380.276992 -384.094705) (xy 380.258284 -384.102446) (xy 380.24816 -384.102864) (xy 379.53188 -384.102864)
			(xy 379.521752 -384.1025) (xy 379.503041 -384.094738) (xy 379.488726 -384.080405) (xy 379.480988 -384.061685)
			(xy 379.480572 -384.051556) (xy 379.480572 -383.894076) (xy 379.48018 -383.884887) (xy 379.473654 -383.867702)
			(xy 379.467872 -383.860548) (xy 379.446025 -383.834869) (xy 379.407937 -383.779236) (xy 379.376788 -383.719441)
			(xy 379.353024 -383.656346) (xy 379.336988 -383.590859) (xy 379.328911 -383.523923) (xy 379.32891 -383.456501)
			(xy 379.336984 -383.389564) (xy 379.353017 -383.324077) (xy 379.376778 -383.260981) (xy 379.407925 -383.201185)
			(xy 379.44601 -383.14555) (xy 379.467872 -383.119884) (xy 379.473667 -383.112738) (xy 379.48018 -383.095548)
			(xy 379.480572 -383.086356) (xy 379.480572 -382.59385) (xy 379.480144 -382.584665) (xy 379.473643 -382.56748)
			(xy 379.467872 -382.560322) (xy 379.445999 -382.534664) (xy 379.407913 -382.479028) (xy 379.376764 -382.419231)
			(xy 379.353002 -382.356133) (xy 379.336968 -382.290643) (xy 379.328893 -382.223704) (xy 376.050822 -382.223704)
			(xy 376.042786 -382.290466) (xy 376.026815 -382.355847) (xy 376.003144 -382.418851) (xy 375.972113 -382.478575)
			(xy 375.934167 -382.534162) (xy 375.91238 -382.559814) (xy 375.906593 -382.566966) (xy 375.900073 -382.584151)
			(xy 375.89968 -382.593342) (xy 375.89968 -383.086864) (xy 375.900112 -383.096049) (xy 375.906611 -383.113233)
			(xy 375.91238 -383.120392) (xy 375.934183 -383.146031) (xy 375.97213 -383.20162) (xy 376.003162 -383.261346)
			(xy 376.02662 -383.323786) (xy 377.128714 -383.323786) (xy 377.128717 -383.256359) (xy 377.136797 -383.189418)
			(xy 377.152837 -383.123927) (xy 377.176606 -383.060828) (xy 377.207762 -383.001031) (xy 377.245857 -382.945397)
			(xy 377.267724 -382.919732) (xy 377.273535 -382.912597) (xy 377.28004 -382.895399) (xy 377.280424 -382.886204)
			(xy 377.280424 -382.728724) (xy 377.280836 -382.7186) (xy 377.288581 -382.699892) (xy 377.302899 -382.685576)
			(xy 377.321608 -382.677834) (xy 377.331732 -382.677416) (xy 378.048012 -382.677416) (xy 378.058137 -382.677806)
			(xy 378.076844 -382.685561) (xy 378.091159 -382.699886) (xy 378.098901 -382.718598) (xy 378.09932 -382.728724)
			(xy 378.09932 -382.886204) (xy 378.099724 -382.895392) (xy 378.106241 -382.912576) (xy 378.11202 -382.919732)
			(xy 378.133848 -382.945427) (xy 378.171936 -383.001058) (xy 378.203088 -383.06085) (xy 378.226853 -383.123943)
			(xy 378.24289 -383.189428) (xy 378.250969 -383.256363) (xy 378.250972 -383.323783) (xy 378.2429 -383.390719)
			(xy 378.226869 -383.456205) (xy 378.20311 -383.519301) (xy 378.171964 -383.579096) (xy 378.133881 -383.63473)
			(xy 378.11202 -383.660396) (xy 378.106245 -383.667557) (xy 378.099717 -383.684735) (xy 378.09932 -383.693924)
			(xy 378.09932 -384.186176) (xy 378.099737 -384.195363) (xy 378.106245 -384.212547) (xy 378.11202 -384.219704)
			(xy 378.133919 -384.24534) (xy 378.172005 -384.30098) (xy 378.203153 -384.36078) (xy 378.226914 -384.423881)
			(xy 378.242947 -384.489373) (xy 378.251019 -384.556314) (xy 378.251016 -384.62374) (xy 378.242937 -384.69068)
			(xy 378.226898 -384.756171) (xy 378.203131 -384.81927) (xy 378.171977 -384.879067) (xy 378.133885 -384.934702)
			(xy 378.11202 -384.960368) (xy 378.106214 -384.967507) (xy 378.099704 -384.984702) (xy 378.09932 -384.993896)
			(xy 378.09932 -385.151376) (xy 378.098865 -385.161494) (xy 378.091128 -385.180194) (xy 378.076824 -385.194508)
			(xy 378.05813 -385.202258) (xy 378.048012 -385.202684) (xy 377.331732 -385.202684) (xy 377.32161 -385.202258)
			(xy 377.302903 -385.194517) (xy 377.288587 -385.180203) (xy 377.280844 -385.161498) (xy 377.280424 -385.151376)
			(xy 377.280424 -384.993896) (xy 377.280011 -384.984709) (xy 377.273499 -384.967525) (xy 377.267724 -384.960368)
			(xy 377.245895 -384.934674) (xy 377.207803 -384.879044) (xy 377.17665 -384.819252) (xy 377.152882 -384.756159)
			(xy 377.136844 -384.690673) (xy 377.128765 -384.623738) (xy 377.128761 -384.556316) (xy 377.136834 -384.48938)
			(xy 377.152866 -384.423893) (xy 377.176627 -384.360797) (xy 377.207775 -384.301002) (xy 377.245861 -384.245369)
			(xy 377.267724 -384.219704) (xy 377.273504 -384.212547) (xy 377.280028 -384.195365) (xy 377.280424 -384.186176)
			(xy 377.280424 -383.693924) (xy 377.279997 -383.684739) (xy 377.273494 -383.667555) (xy 377.267724 -383.660396)
			(xy 377.245824 -383.63476) (xy 377.207735 -383.579122) (xy 377.176584 -383.519322) (xy 377.152821 -383.456221)
			(xy 377.136787 -383.390728) (xy 377.128714 -383.323786) (xy 376.02662 -383.323786) (xy 376.026833 -383.324352)
			(xy 376.042804 -383.389735) (xy 376.050846 -383.456559) (xy 376.050845 -383.523865) (xy 376.0428 -383.590688)
			(xy 376.026826 -383.656071) (xy 376.003152 -383.719076) (xy 375.972118 -383.778801) (xy 375.934168 -383.834388)
			(xy 375.91238 -383.86004) (xy 375.906582 -383.867184) (xy 375.900069 -383.884375) (xy 375.89968 -383.893568)
			(xy 375.89968 -384.051556) (xy 375.899242 -384.06171) (xy 375.891457 -384.080465) (xy 375.877065 -384.094791)
			(xy 375.858274 -384.102488) (xy 375.848118 -384.102864) (xy 375.131838 -384.102864) (xy 375.121714 -384.102342)
			(xy 375.102995 -384.094628) (xy 375.088637 -384.080352) (xy 375.080816 -384.061677) (xy 375.080276 -384.051556)
			(xy 375.080276 -383.893568) (xy 375.079886 -383.884379) (xy 375.073359 -383.867194) (xy 375.067576 -383.86004)
			(xy 375.045803 -383.834375) (xy 375.007851 -383.778792) (xy 374.976815 -383.71907) (xy 374.95314 -383.656067)
			(xy 374.937165 -383.590686) (xy 374.929119 -383.523864) (xy 374.929117 -383.45656) (xy 374.93716 -383.389738)
			(xy 374.953133 -383.324356) (xy 374.976805 -383.261352) (xy 375.007839 -383.201629) (xy 375.045788 -383.146044)
			(xy 375.067576 -383.120392) (xy 375.073356 -383.113235) (xy 375.079881 -383.096054) (xy 375.080276 -383.086864)
			(xy 375.080276 -382.593342) (xy 375.079851 -382.584156) (xy 375.073348 -382.566971) (xy 375.067576 -382.559814)
			(xy 375.045777 -382.53417) (xy 375.007826 -382.478584) (xy 374.976792 -382.418859) (xy 374.953118 -382.355853)
			(xy 374.937144 -382.29047) (xy 374.9291 -382.223646) (xy 345.250798 -382.223646) (xy 345.242755 -382.290467)
			(xy 345.226782 -382.355849) (xy 345.20311 -382.418853) (xy 345.172077 -382.478576) (xy 345.134128 -382.534162)
			(xy 345.11234 -382.559814) (xy 345.106548 -382.566962) (xy 345.100032 -382.584151) (xy 345.09964 -382.593342)
			(xy 345.09964 -383.086864) (xy 345.100081 -383.096048) (xy 345.106575 -383.113232) (xy 345.11234 -383.120392)
			(xy 345.134144 -383.146031) (xy 345.172094 -383.201619) (xy 345.203127 -383.261344) (xy 345.226566 -383.323727)
			(xy 346.329188 -383.323727) (xy 346.329192 -383.256419) (xy 346.33724 -383.189593) (xy 346.353218 -383.124208)
			(xy 346.376897 -383.061202) (xy 346.407937 -383.001478) (xy 346.445893 -382.945892) (xy 346.467684 -382.92024)
			(xy 346.473487 -382.913099) (xy 346.479998 -382.895905) (xy 346.480384 -382.886712) (xy 346.480384 -382.728724)
			(xy 346.480841 -382.718573) (xy 346.488625 -382.699825) (xy 346.503011 -382.685501) (xy 346.521794 -382.677797)
			(xy 346.531946 -382.677416) (xy 347.248226 -382.677416) (xy 347.258351 -382.677904) (xy 347.277069 -382.685636)
			(xy 347.291423 -382.699921) (xy 347.299246 -382.718601) (xy 347.299788 -382.728724) (xy 347.299788 -382.886712)
			(xy 347.300195 -382.895899) (xy 347.306711 -382.913084) (xy 347.312488 -382.92024) (xy 347.33424 -382.945922)
			(xy 347.372188 -383.001504) (xy 347.403221 -383.061224) (xy 347.426895 -383.124225) (xy 347.442869 -383.189603)
			(xy 347.450916 -383.256422) (xy 347.450919 -383.323724) (xy 347.442879 -383.390543) (xy 347.426911 -383.455923)
			(xy 347.403243 -383.518926) (xy 347.372216 -383.578649) (xy 347.334273 -383.634236) (xy 347.312488 -383.659888)
			(xy 347.30667 -383.667018) (xy 347.300169 -383.68422) (xy 347.299788 -383.693416) (xy 347.299788 -384.186684)
			(xy 347.300209 -384.19587) (xy 347.306715 -384.213054) (xy 347.312488 -384.220212) (xy 347.33431 -384.245835)
			(xy 347.372256 -384.301427) (xy 347.403286 -384.361154) (xy 347.426956 -384.424163) (xy 347.442926 -384.489548)
			(xy 347.450967 -384.556373) (xy 347.450963 -384.623681) (xy 347.442916 -384.690505) (xy 347.42694 -384.755889)
			(xy 347.403264 -384.818895) (xy 347.372228 -384.87862) (xy 347.334277 -384.934207) (xy 347.312488 -384.95986)
			(xy 347.306682 -384.966999) (xy 347.300173 -384.984194) (xy 347.299788 -384.993388) (xy 347.299788 -385.151376)
			(xy 347.299359 -385.16153) (xy 347.291569 -385.180284) (xy 347.277174 -385.194609) (xy 347.258382 -385.202307)
			(xy 347.248226 -385.202684) (xy 346.531946 -385.202684) (xy 346.521825 -385.202136) (xy 346.50311 -385.194428)
			(xy 346.488753 -385.180161) (xy 346.480928 -385.161494) (xy 346.480384 -385.151376) (xy 346.480384 -384.993388)
			(xy 346.479983 -384.9842) (xy 346.473463 -384.967015) (xy 346.467684 -384.95986) (xy 346.44593 -384.934179)
			(xy 346.407977 -384.878598) (xy 346.37694 -384.818879) (xy 346.353263 -384.755878) (xy 346.337287 -384.690499)
			(xy 346.329239 -384.623679) (xy 346.329236 -384.556376) (xy 346.337277 -384.489555) (xy 346.353247 -384.424174)
			(xy 346.376918 -384.361171) (xy 346.40795 -384.301448) (xy 346.445897 -384.245864) (xy 346.467684 -384.220212)
			(xy 346.473499 -384.213079) (xy 346.480003 -384.195879) (xy 346.480384 -384.186684) (xy 346.480384 -383.693416)
			(xy 346.47997 -383.684229) (xy 346.473459 -383.667045) (xy 346.467684 -383.659888) (xy 346.44586 -383.634266)
			(xy 346.407909 -383.578676) (xy 346.376875 -383.518949) (xy 346.353202 -383.45594) (xy 346.33723 -383.390554)
			(xy 346.329188 -383.323727) (xy 345.226566 -383.323727) (xy 345.2268 -383.32435) (xy 345.242773 -383.389734)
			(xy 345.250816 -383.456559) (xy 345.250814 -383.523865) (xy 345.242768 -383.590689) (xy 345.226793 -383.656073)
			(xy 345.203118 -383.719078) (xy 345.172081 -383.778802) (xy 345.134129 -383.834388) (xy 345.11234 -383.86004)
			(xy 345.106537 -383.86718) (xy 345.100028 -383.884375) (xy 345.09964 -383.893568) (xy 345.09964 -384.051556)
			(xy 345.099143 -384.061702) (xy 345.09137 -384.080446) (xy 345.076996 -384.094769) (xy 345.058226 -384.102478)
			(xy 345.048078 -384.102864) (xy 344.331798 -384.102864) (xy 344.321672 -384.102375) (xy 344.302951 -384.094647)
			(xy 344.288595 -384.080362) (xy 344.280775 -384.06168) (xy 344.280236 -384.051556) (xy 344.280236 -383.893568)
			(xy 344.279833 -383.88438) (xy 344.273313 -383.867196) (xy 344.267536 -383.86004) (xy 344.245764 -383.834375)
			(xy 344.207815 -383.77879) (xy 344.176781 -383.719068) (xy 344.153108 -383.656066) (xy 344.137134 -383.590685)
			(xy 344.129089 -383.523864) (xy 344.129087 -383.45656) (xy 344.13713 -383.389739) (xy 344.153101 -383.324358)
			(xy 344.176772 -383.261354) (xy 344.207803 -383.201631) (xy 344.24575 -383.146044) (xy 344.267536 -383.120392)
			(xy 344.273323 -383.11324) (xy 344.279843 -383.096055) (xy 344.280236 -383.086864) (xy 344.280236 -382.593342)
			(xy 344.279797 -382.584158) (xy 344.273303 -382.566974) (xy 344.267536 -382.559814) (xy 344.245738 -382.53417)
			(xy 344.20779 -382.478582) (xy 344.176757 -382.418858) (xy 344.153085 -382.355852) (xy 344.137113 -382.290469)
			(xy 344.12907 -382.223645) (xy 340.851007 -382.223645) (xy 340.842964 -382.290467) (xy 340.826992 -382.355848)
			(xy 340.80332 -382.418853) (xy 340.772287 -382.478576) (xy 340.734339 -382.534162) (xy 340.712552 -382.559814)
			(xy 340.706761 -382.566963) (xy 340.700244 -382.584151) (xy 340.699852 -382.593342) (xy 340.699852 -383.086864)
			(xy 340.70029 -383.096048) (xy 340.706785 -383.113232) (xy 340.712552 -383.120392) (xy 340.734356 -383.146031)
			(xy 340.772305 -383.201619) (xy 340.803338 -383.261344) (xy 340.826798 -383.323786) (xy 341.928893 -383.323786)
			(xy 341.928896 -383.25636) (xy 341.936975 -383.189419) (xy 341.953015 -383.123928) (xy 341.976783 -383.06083)
			(xy 342.007937 -383.001032) (xy 342.04603 -382.945397) (xy 342.067896 -382.919732) (xy 342.073703 -382.912594)
			(xy 342.080212 -382.895398) (xy 342.080596 -382.886204) (xy 342.080596 -382.728724) (xy 342.081035 -382.718604)
			(xy 342.088775 -382.699901) (xy 342.103084 -382.685586) (xy 342.121784 -382.677839) (xy 342.131904 -382.677416)
			(xy 342.848184 -382.677416) (xy 342.858307 -382.677829) (xy 342.877014 -382.685575) (xy 342.891329 -382.699893)
			(xy 342.899072 -382.7186) (xy 342.899492 -382.728724) (xy 342.899492 -382.886204) (xy 342.899902 -382.895391)
			(xy 342.906416 -382.912575) (xy 342.912192 -382.919732) (xy 342.934021 -382.945426) (xy 342.972111 -383.001056)
			(xy 343.003264 -383.060849) (xy 343.02703 -383.123942) (xy 343.043069 -383.189427) (xy 343.051148 -383.256362)
			(xy 343.051151 -383.323783) (xy 343.043078 -383.390719) (xy 343.027046 -383.456207) (xy 343.003286 -383.519302)
			(xy 342.972139 -383.579097) (xy 342.934054 -383.634731) (xy 342.912192 -383.660396) (xy 342.906414 -383.667554)
			(xy 342.899888 -383.684735) (xy 342.899492 -383.693924) (xy 342.899492 -384.186176) (xy 342.899916 -384.195362)
			(xy 342.90642 -384.212546) (xy 342.912192 -384.219704) (xy 342.934092 -384.24534) (xy 342.97218 -384.300978)
			(xy 343.003329 -384.360779) (xy 343.027092 -384.423879) (xy 343.043125 -384.489372) (xy 343.051198 -384.556314)
			(xy 343.051195 -384.62374) (xy 343.043115 -384.690681) (xy 343.027076 -384.756172) (xy 343.003307 -384.819271)
			(xy 342.972152 -384.879068) (xy 342.934058 -384.934703) (xy 342.912192 -384.960368) (xy 342.906383 -384.967504)
			(xy 342.899876 -384.984702) (xy 342.899492 -384.993896) (xy 342.899492 -385.151376) (xy 342.899064 -385.161498)
			(xy 342.891323 -385.180203) (xy 342.877009 -385.194518) (xy 342.858306 -385.202263) (xy 342.848184 -385.202684)
			(xy 342.131904 -385.202684) (xy 342.12178 -385.20228) (xy 342.103073 -385.194531) (xy 342.088758 -385.18021)
			(xy 342.081016 -385.1615) (xy 342.080596 -385.151376) (xy 342.080596 -384.993896) (xy 342.080189 -384.984709)
			(xy 342.073673 -384.967524) (xy 342.067896 -384.960368) (xy 342.046068 -384.934674) (xy 342.007978 -384.879043)
			(xy 341.976826 -384.819251) (xy 341.95306 -384.756158) (xy 341.937022 -384.690672) (xy 341.928943 -384.623737)
			(xy 341.92894 -384.556317) (xy 341.937012 -384.489381) (xy 341.953044 -384.423894) (xy 341.976804 -384.360799)
			(xy 342.00795 -384.301003) (xy 342.046034 -384.245369) (xy 342.067896 -384.219704) (xy 342.073673 -384.212545)
			(xy 342.080199 -384.195365) (xy 342.080596 -384.186176) (xy 342.080596 -383.693924) (xy 342.080175 -383.684738)
			(xy 342.073669 -383.667553) (xy 342.067896 -383.660396) (xy 342.045997 -383.63476) (xy 342.007909 -383.579121)
			(xy 341.976761 -383.519321) (xy 341.952999 -383.45622) (xy 341.936966 -383.390728) (xy 341.928893 -383.323786)
			(xy 340.826798 -383.323786) (xy 340.82701 -383.324351) (xy 340.842982 -383.389735) (xy 340.851025 -383.456559)
			(xy 340.851024 -383.523865) (xy 340.842978 -383.590689) (xy 340.827003 -383.656072) (xy 340.803328 -383.719078)
			(xy 340.772292 -383.778802) (xy 340.734341 -383.834388) (xy 340.712552 -383.86004) (xy 340.70675 -383.867181)
			(xy 340.70024 -383.884375) (xy 340.699852 -383.893568) (xy 340.699852 -384.051556) (xy 340.699343 -384.061701)
			(xy 340.691572 -384.080442) (xy 340.677202 -384.094765) (xy 340.658436 -384.102476) (xy 340.64829 -384.102864)
			(xy 339.93201 -384.102864) (xy 339.921884 -384.102365) (xy 339.903164 -384.094642) (xy 339.888808 -384.080359)
			(xy 339.880987 -384.061679) (xy 339.880448 -384.051556) (xy 339.880448 -383.893568) (xy 339.880042 -383.884381)
			(xy 339.873524 -383.867197) (xy 339.867748 -383.86004) (xy 339.845976 -383.834375) (xy 339.808026 -383.778791)
			(xy 339.776992 -383.719069) (xy 339.753318 -383.656066) (xy 339.737343 -383.590685) (xy 339.729298 -383.523864)
			(xy 339.729296 -383.45656) (xy 339.737339 -383.389738) (xy 339.75331 -383.324357) (xy 339.776982 -383.261353)
			(xy 339.808014 -383.20163) (xy 339.845961 -383.146044) (xy 339.867748 -383.120392) (xy 339.873536 -383.113241)
			(xy 339.880055 -383.096055) (xy 339.880448 -383.086864) (xy 339.880448 -382.593342) (xy 339.880007 -382.584158)
			(xy 339.873513 -382.566974) (xy 339.867748 -382.559814) (xy 339.84595 -382.53417) (xy 339.808001 -382.478583)
			(xy 339.776968 -382.418858) (xy 339.753295 -382.355852) (xy 339.737322 -382.290469) (xy 339.729279 -382.223645)
			(xy 336.45124 -382.223645) (xy 336.45124 -382.223704) (xy 336.443164 -382.290643) (xy 336.427128 -382.356132)
			(xy 336.403363 -382.419228) (xy 336.372211 -382.479024) (xy 336.334121 -382.534658) (xy 336.312256 -382.560322)
			(xy 336.306462 -382.567469) (xy 336.299947 -382.584658) (xy 336.299556 -382.59385) (xy 336.299556 -383.086356)
			(xy 336.299997 -383.09554) (xy 336.306491 -383.112724) (xy 336.312256 -383.119884) (xy 336.334137 -383.145536)
			(xy 336.372228 -383.201171) (xy 336.403381 -383.260969) (xy 336.427018 -383.323726) (xy 337.529124 -383.323726)
			(xy 337.529128 -383.256419) (xy 337.537175 -383.189595) (xy 337.55315 -383.124211) (xy 337.576825 -383.061205)
			(xy 337.607861 -383.001481) (xy 337.645811 -382.945893) (xy 337.6676 -382.92024) (xy 337.673405 -382.9131)
			(xy 337.679914 -382.895906) (xy 337.6803 -382.886712) (xy 337.6803 -382.728724) (xy 337.680741 -382.718571)
			(xy 337.688529 -382.699819) (xy 337.70292 -382.685495) (xy 337.721708 -382.677795) (xy 337.731862 -382.677416)
			(xy 338.448142 -382.677416) (xy 338.458268 -382.677891) (xy 338.476986 -382.685629) (xy 338.49134 -382.699918)
			(xy 338.499162 -382.7186) (xy 338.499704 -382.728724) (xy 338.499704 -382.886712) (xy 338.500108 -382.8959)
			(xy 338.506626 -382.913084) (xy 338.512404 -382.92024) (xy 338.534155 -382.945922) (xy 338.572102 -383.001505)
			(xy 338.603135 -383.061225) (xy 338.626808 -383.124225) (xy 338.642782 -383.189604) (xy 338.650828 -383.256422)
			(xy 338.650831 -383.323724) (xy 338.642791 -383.390543) (xy 338.626824 -383.455923) (xy 338.603157 -383.518926)
			(xy 338.57213 -383.578648) (xy 338.534188 -383.634235) (xy 338.512404 -383.659888) (xy 338.506588 -383.66702)
			(xy 338.500085 -383.68422) (xy 338.499704 -383.693416) (xy 338.499704 -384.186684) (xy 338.500121 -384.19587)
			(xy 338.50663 -384.213055) (xy 338.512404 -384.220212) (xy 338.534226 -384.245836) (xy 338.572171 -384.301427)
			(xy 338.6032 -384.361155) (xy 338.626869 -384.424163) (xy 338.642838 -384.489548) (xy 338.650879 -384.556374)
			(xy 338.650875 -384.623681) (xy 338.642828 -384.690505) (xy 338.626853 -384.755889) (xy 338.603178 -384.818894)
			(xy 338.572143 -384.878619) (xy 338.534193 -384.934207) (xy 338.512404 -384.95986) (xy 338.5066 -384.967)
			(xy 338.50009 -384.984194) (xy 338.499704 -384.993388) (xy 338.499704 -385.151376) (xy 338.499259 -385.161528)
			(xy 338.491472 -385.180279) (xy 338.477082 -385.194603) (xy 338.458296 -385.202305) (xy 338.448142 -385.202684)
			(xy 337.731862 -385.202684) (xy 337.721736 -385.202205) (xy 337.703018 -385.194469) (xy 337.688664 -385.180181)
			(xy 337.680842 -385.1615) (xy 337.6803 -385.151376) (xy 337.6803 -384.993388) (xy 337.679895 -384.9842)
			(xy 337.673378 -384.967016) (xy 337.6676 -384.95986) (xy 337.645849 -384.934178) (xy 337.607901 -384.878595)
			(xy 337.576869 -384.818875) (xy 337.553196 -384.755875) (xy 337.537221 -384.690497) (xy 337.529175 -384.623678)
			(xy 337.529172 -384.556376) (xy 337.537212 -384.489557) (xy 337.55318 -384.424177) (xy 337.576847 -384.361174)
			(xy 337.607874 -384.301451) (xy 337.645816 -384.245865) (xy 337.6676 -384.220212) (xy 337.673416 -384.213081)
			(xy 337.679919 -384.19588) (xy 337.6803 -384.186684) (xy 337.6803 -383.693416) (xy 337.679882 -383.68423)
			(xy 337.673374 -383.667045) (xy 337.6676 -383.659888) (xy 337.645778 -383.634264) (xy 337.607833 -383.578673)
			(xy 337.576803 -383.518945) (xy 337.553134 -383.455937) (xy 337.537165 -383.390552) (xy 337.529124 -383.323726)
			(xy 336.427018 -383.323726) (xy 336.427146 -383.324067) (xy 336.443182 -383.389559) (xy 336.451257 -383.456499)
			(xy 336.451256 -383.523925) (xy 336.443177 -383.590865) (xy 336.427139 -383.656356) (xy 336.403371 -383.719453)
			(xy 336.372216 -383.77925) (xy 336.334122 -383.834883) (xy 336.312256 -383.860548) (xy 336.306451 -383.867687)
			(xy 336.299943 -383.884882) (xy 336.299556 -383.894076) (xy 336.299556 -384.051556) (xy 336.29898 -384.061655)
			(xy 336.291267 -384.080321) (xy 336.276999 -384.094616) (xy 336.258346 -384.102362) (xy 336.248248 -384.102864)
			(xy 335.531968 -384.102864) (xy 335.521839 -384.102509) (xy 335.503128 -384.094744) (xy 335.488813 -384.080408)
			(xy 335.481076 -384.061686) (xy 335.48066 -384.051556) (xy 335.48066 -383.894076) (xy 335.480248 -383.884889)
			(xy 335.473734 -383.867706) (xy 335.46796 -383.860548) (xy 335.446113 -383.834869) (xy 335.408027 -383.779236)
			(xy 335.376877 -383.719441) (xy 335.353114 -383.656346) (xy 335.337079 -383.590859) (xy 335.329002 -383.523923)
			(xy 335.329001 -383.456501) (xy 335.337074 -383.389565) (xy 335.353107 -383.324077) (xy 335.376868 -383.260981)
			(xy 335.408014 -383.201185) (xy 335.446098 -383.14555) (xy 335.46796 -383.119884) (xy 335.473753 -383.112737)
			(xy 335.480268 -383.095548) (xy 335.48066 -383.086356) (xy 335.48066 -382.59385) (xy 335.480213 -382.584667)
			(xy 335.473723 -382.567483) (xy 335.46796 -382.560322) (xy 335.446088 -382.534664) (xy 335.408002 -382.479028)
			(xy 335.376854 -382.41923) (xy 335.353092 -382.356132) (xy 335.337058 -382.290643) (xy 335.328984 -382.223704)
			(xy 332.050913 -382.223704) (xy 332.042877 -382.290466) (xy 332.026905 -382.355848) (xy 332.003234 -382.418852)
			(xy 331.972202 -382.478575) (xy 331.934255 -382.534162) (xy 331.912468 -382.559814) (xy 331.906679 -382.566964)
			(xy 331.90016 -382.584151) (xy 331.899768 -382.593342) (xy 331.899768 -383.086864) (xy 331.900203 -383.096048)
			(xy 331.9067 -383.113233) (xy 331.912468 -383.120392) (xy 331.934271 -383.146031) (xy 331.972219 -383.20162)
			(xy 332.003251 -383.261345) (xy 332.026711 -383.323786) (xy 333.128805 -383.323786) (xy 333.128808 -383.25636)
			(xy 333.136888 -383.189419) (xy 333.152927 -383.123927) (xy 333.176696 -383.060829) (xy 333.207852 -383.001032)
			(xy 333.245945 -382.945397) (xy 333.267812 -382.919732) (xy 333.273621 -382.912596) (xy 333.280128 -382.895398)
			(xy 333.280512 -382.886204) (xy 333.280512 -382.728724) (xy 333.280936 -382.718602) (xy 333.288678 -382.699896)
			(xy 333.302993 -382.685581) (xy 333.321698 -382.677837) (xy 333.33182 -382.677416) (xy 334.0481 -382.677416)
			(xy 334.058224 -382.677816) (xy 334.076931 -382.685568) (xy 334.091246 -382.699889) (xy 334.098988 -382.718599)
			(xy 334.099408 -382.728724) (xy 334.099408 -382.886204) (xy 334.099815 -382.895392) (xy 334.106331 -382.912576)
			(xy 334.112108 -382.919732) (xy 334.133936 -382.945427) (xy 334.172026 -383.001057) (xy 334.203177 -383.060849)
			(xy 334.226943 -383.123942) (xy 334.242981 -383.189428) (xy 334.25106 -383.256363) (xy 334.251063 -383.323783)
			(xy 334.242991 -383.390719) (xy 334.226959 -383.456206) (xy 334.2032 -383.519301) (xy 334.172053 -383.579096)
			(xy 334.13397 -383.634731) (xy 334.112108 -383.660396) (xy 334.106332 -383.667556) (xy 334.099805 -383.684735)
			(xy 334.099408 -383.693924) (xy 334.099408 -384.186176) (xy 334.099828 -384.195362) (xy 334.106335 -384.212547)
			(xy 334.112108 -384.219704) (xy 334.134007 -384.24534) (xy 334.172094 -384.300979) (xy 334.203243 -384.360779)
			(xy 334.227005 -384.42388) (xy 334.243037 -384.489373) (xy 334.25111 -384.556314) (xy 334.251107 -384.62374)
			(xy 334.243028 -384.690681) (xy 334.226989 -384.756172) (xy 334.203221 -384.81927) (xy 334.172066 -384.879067)
			(xy 334.133974 -384.934703) (xy 334.112108 -384.960368) (xy 334.106301 -384.967506) (xy 334.099792 -384.984702)
			(xy 334.099408 -384.993896) (xy 334.099408 -385.151376) (xy 334.098965 -385.161496) (xy 334.091226 -385.180198)
			(xy 334.076918 -385.194512) (xy 334.05822 -385.20226) (xy 334.0481 -385.202684) (xy 333.33182 -385.202684)
			(xy 333.321697 -385.202267) (xy 333.302991 -385.194523) (xy 333.288675 -385.180206) (xy 333.280932 -385.161499)
			(xy 333.280512 -385.151376) (xy 333.280512 -384.993896) (xy 333.280101 -384.984709) (xy 333.273587 -384.967525)
			(xy 333.267812 -384.960368) (xy 333.245983 -384.934674) (xy 333.207892 -384.879044) (xy 333.176739 -384.819252)
			(xy 333.152973 -384.756158) (xy 333.136934 -384.690673) (xy 333.128855 -384.623738) (xy 333.128852 -384.556316)
			(xy 333.136925 -384.48938) (xy 333.152957 -384.423893) (xy 333.176717 -384.360798) (xy 333.207865 -384.301003)
			(xy 333.24595 -384.245369) (xy 333.267812 -384.219704) (xy 333.273591 -384.212546) (xy 333.280116 -384.195365)
			(xy 333.280512 -384.186176) (xy 333.280512 -383.693924) (xy 333.280088 -383.684738) (xy 333.273583 -383.667554)
			(xy 333.267812 -383.660396) (xy 333.245912 -383.63476) (xy 333.207824 -383.579122) (xy 333.176674 -383.519322)
			(xy 333.152911 -383.456221) (xy 333.136878 -383.390728) (xy 333.128805 -383.323786) (xy 332.026711 -383.323786)
			(xy 332.026923 -383.324351) (xy 332.042895 -383.389735) (xy 332.050937 -383.456559) (xy 332.050936 -383.523865)
			(xy 332.04289 -383.590689) (xy 332.026916 -383.656072) (xy 332.003242 -383.719077) (xy 331.972207 -383.778801)
			(xy 331.934257 -383.834388) (xy 331.912468 -383.86004) (xy 331.906668 -383.867183) (xy 331.900156 -383.884375)
			(xy 331.899768 -383.893568) (xy 331.899768 -384.051556) (xy 331.899342 -384.061711) (xy 331.891555 -384.080469)
			(xy 331.877159 -384.094795) (xy 331.858363 -384.10249) (xy 331.848206 -384.102864) (xy 331.131926 -384.102864)
			(xy 331.121801 -384.102352) (xy 331.103082 -384.094634) (xy 331.088724 -384.080355) (xy 331.080904 -384.061678)
			(xy 331.080364 -384.051556) (xy 331.080364 -383.893568) (xy 331.079955 -383.884381) (xy 331.073439 -383.867198)
			(xy 331.067664 -383.86004) (xy 331.045891 -383.834375) (xy 331.00794 -383.778791) (xy 330.976905 -383.71907)
			(xy 330.95323 -383.656067) (xy 330.937256 -383.590686) (xy 330.92921 -383.523864) (xy 330.929208 -383.45656)
			(xy 330.937251 -383.389738) (xy 330.953223 -383.324356) (xy 330.976895 -383.261352) (xy 331.007928 -383.20163)
			(xy 331.045877 -383.146044) (xy 331.067664 -383.120392) (xy 331.073454 -383.113243) (xy 331.079971 -383.096055)
			(xy 331.080364 -383.086864) (xy 331.080364 -382.593342) (xy 331.079919 -382.584159) (xy 331.073428 -382.566975)
			(xy 331.067664 -382.559814) (xy 331.045866 -382.53417) (xy 331.007916 -382.478583) (xy 330.976881 -382.418859)
			(xy 330.953208 -382.355853) (xy 330.937235 -382.29047) (xy 330.929191 -382.223646) (xy 301.250888 -382.223646)
			(xy 301.250888 -382.223704) (xy 301.242813 -382.290641) (xy 301.226779 -382.356129) (xy 301.203017 -382.419226)
			(xy 301.171869 -382.479022) (xy 301.133783 -382.534656) (xy 301.11192 -382.560322) (xy 301.106134 -382.567475)
			(xy 301.099612 -382.584659) (xy 301.09922 -382.59385) (xy 301.09922 -383.086356) (xy 301.099647 -383.095542)
			(xy 301.106148 -383.112726) (xy 301.11192 -383.119884) (xy 301.133799 -383.145537) (xy 301.171886 -383.201173)
			(xy 301.203035 -383.260972) (xy 301.22669 -383.323786) (xy 302.328775 -383.323786) (xy 302.328778 -383.25636)
			(xy 302.336857 -383.18942) (xy 302.352895 -383.123929) (xy 302.376662 -383.060831) (xy 302.407816 -383.001033)
			(xy 302.445907 -382.945398) (xy 302.467772 -382.919732) (xy 302.473589 -382.912601) (xy 302.480089 -382.895399)
			(xy 302.480472 -382.886204) (xy 302.480472 -382.728724) (xy 302.480935 -382.718606) (xy 302.48867 -382.699909)
			(xy 302.502972 -382.685595) (xy 302.521663 -382.677843) (xy 302.53178 -382.677416) (xy 303.24806 -382.677416)
			(xy 303.258182 -382.677849) (xy 303.276888 -382.685587) (xy 303.291204 -382.699899) (xy 303.298948 -382.718602)
			(xy 303.299368 -382.728724) (xy 303.299368 -382.886204) (xy 303.299783 -382.89539) (xy 303.306294 -382.912575)
			(xy 303.312068 -382.919732) (xy 303.333898 -382.945426) (xy 303.37199 -383.001056) (xy 303.403144 -383.060847)
			(xy 303.426911 -383.123941) (xy 303.44295 -383.189427) (xy 303.451029 -383.256362) (xy 303.451033 -383.323784)
			(xy 303.44296 -383.39072) (xy 303.426927 -383.456208) (xy 303.403166 -383.519303) (xy 303.372017 -383.579098)
			(xy 303.333931 -383.634731) (xy 303.312068 -383.660396) (xy 303.306286 -383.667552) (xy 303.299764 -383.684734)
			(xy 303.299368 -383.693924) (xy 303.299368 -384.186176) (xy 303.299797 -384.195361) (xy 303.306299 -384.212545)
			(xy 303.312068 -384.219704) (xy 303.333968 -384.24534) (xy 303.372058 -384.300978) (xy 303.403209 -384.360778)
			(xy 303.426973 -384.423878) (xy 303.443007 -384.489371) (xy 303.45108 -384.556313) (xy 303.451077 -384.623741)
			(xy 303.442997 -384.690682) (xy 303.426957 -384.756173) (xy 303.403187 -384.819272) (xy 303.37203 -384.879069)
			(xy 303.333935 -384.934703) (xy 303.312068 -384.960368) (xy 303.306256 -384.967502) (xy 303.299751 -384.984701)
			(xy 303.299368 -384.993896) (xy 303.299368 -385.151376) (xy 303.298964 -385.161501) (xy 303.291218 -385.18021)
			(xy 303.276897 -385.194527) (xy 303.258185 -385.202267) (xy 303.24806 -385.202684) (xy 302.53178 -385.202684)
			(xy 302.521654 -385.2023) (xy 302.502947 -385.194542) (xy 302.488633 -385.180216) (xy 302.480891 -385.161502)
			(xy 302.480472 -385.151376) (xy 302.480472 -384.993896) (xy 302.48007 -384.984708) (xy 302.473551 -384.967523)
			(xy 302.467772 -384.960368) (xy 302.445944 -384.934673) (xy 302.407856 -384.879042) (xy 302.376706 -384.81925)
			(xy 302.352941 -384.756157) (xy 302.336904 -384.690672) (xy 302.328825 -384.623737) (xy 302.328822 -384.556317)
			(xy 302.336894 -384.489382) (xy 302.352925 -384.423895) (xy 302.376684 -384.3608) (xy 302.407829 -384.301004)
			(xy 302.445911 -384.24537) (xy 302.467772 -384.219704) (xy 302.473558 -384.212552) (xy 302.480077 -384.195366)
			(xy 302.480472 -384.186176) (xy 302.480472 -383.693924) (xy 302.480057 -383.684737) (xy 302.473547 -383.667552)
			(xy 302.467772 -383.660396) (xy 302.445874 -383.634759) (xy 302.407788 -383.57912) (xy 302.37664 -383.51932)
			(xy 302.352879 -383.456219) (xy 302.336847 -383.390727) (xy 302.328775 -383.323786) (xy 301.22669 -383.323786)
			(xy 301.226797 -383.32407) (xy 301.242831 -383.38956) (xy 301.250905 -383.4565) (xy 301.250904 -383.523924)
			(xy 301.242827 -383.590863) (xy 301.22679 -383.656353) (xy 301.203025 -383.71945) (xy 301.171874 -383.779247)
			(xy 301.133784 -383.834882) (xy 301.11192 -383.860548) (xy 301.106123 -383.867693) (xy 301.099608 -383.884884)
			(xy 301.09922 -383.894076) (xy 301.09922 -384.051556) (xy 301.098748 -384.061673) (xy 301.091018 -384.080372)
			(xy 301.076719 -384.094687) (xy 301.058029 -384.102437) (xy 301.047912 -384.102864) (xy 300.331632 -384.102864)
			(xy 300.321507 -384.102457) (xy 300.302797 -384.094713) (xy 300.28848 -384.080393) (xy 300.28074 -384.061681)
			(xy 300.280324 -384.051556) (xy 300.280324 -383.894076) (xy 300.27992 -383.884888) (xy 300.273402 -383.867704)
			(xy 300.267624 -383.860548) (xy 300.245775 -383.83487) (xy 300.207684 -383.779238) (xy 300.176531 -383.719444)
			(xy 300.152765 -383.656349) (xy 300.136728 -383.590861) (xy 300.12865 -383.523923) (xy 300.128649 -383.456501)
			(xy 300.136724 -383.389563) (xy 300.152758 -383.324074) (xy 300.176522 -383.260978) (xy 300.207672 -383.201183)
			(xy 300.24576 -383.145549) (xy 300.267624 -383.119884) (xy 300.273413 -383.112733) (xy 300.279931 -383.095547)
			(xy 300.280324 -383.086356) (xy 300.280324 -382.59385) (xy 300.279884 -382.584666) (xy 300.273391 -382.567482)
			(xy 300.267624 -382.560322) (xy 300.245749 -382.534665) (xy 300.207659 -382.47903) (xy 300.176508 -382.419233)
			(xy 300.152743 -382.356135) (xy 300.136708 -382.290645) (xy 300.128632 -382.223705) (xy 296.851097 -382.223705)
			(xy 296.843022 -382.290641) (xy 296.826989 -382.356129) (xy 296.803227 -382.419225) (xy 296.77208 -382.479021)
			(xy 296.733994 -382.534656) (xy 296.712132 -382.560322) (xy 296.706335 -382.567467) (xy 296.699823 -382.584658)
			(xy 296.699432 -382.59385) (xy 296.699432 -383.086356) (xy 296.699878 -383.095539) (xy 296.706368 -383.112723)
			(xy 296.712132 -383.119884) (xy 296.734011 -383.145537) (xy 296.772097 -383.201174) (xy 296.803245 -383.260972)
			(xy 296.826877 -383.323727) (xy 297.928982 -383.323727) (xy 297.928985 -383.256419) (xy 297.937033 -383.189593)
			(xy 297.953011 -383.124208) (xy 297.97669 -383.061202) (xy 298.007729 -383.001478) (xy 298.045685 -382.945891)
			(xy 298.067476 -382.92024) (xy 298.073278 -382.913098) (xy 298.07979 -382.895905) (xy 298.080176 -382.886712)
			(xy 298.080176 -382.728724) (xy 298.080641 -382.718574) (xy 298.088424 -382.699827) (xy 298.102807 -382.685504)
			(xy 298.121587 -382.677799) (xy 298.131738 -382.677416) (xy 298.848018 -382.677416) (xy 298.858143 -382.677911)
			(xy 298.87686 -382.68564) (xy 298.891215 -382.699923) (xy 298.899038 -382.718602) (xy 298.89958 -382.728724)
			(xy 298.89958 -382.886712) (xy 298.899989 -382.895899) (xy 298.906504 -382.913083) (xy 298.91228 -382.92024)
			(xy 298.934031 -382.945922) (xy 298.97198 -383.001504) (xy 299.003014 -383.061224) (xy 299.026688 -383.124225)
			(xy 299.042663 -383.189603) (xy 299.050709 -383.256422) (xy 299.050713 -383.323724) (xy 299.042672 -383.390544)
			(xy 299.026704 -383.455924) (xy 299.003036 -383.518926) (xy 298.972008 -383.578649) (xy 298.934065 -383.634235)
			(xy 298.91228 -383.659888) (xy 298.906461 -383.667017) (xy 298.89996 -383.68422) (xy 298.89958 -383.693416)
			(xy 298.89958 -384.186684) (xy 298.900003 -384.19587) (xy 298.906508 -384.213054) (xy 298.91228 -384.220212)
			(xy 298.934103 -384.245835) (xy 298.972049 -384.301426) (xy 299.00308 -384.361154) (xy 299.02675 -384.424162)
			(xy 299.04272 -384.489548) (xy 299.050761 -384.556373) (xy 299.050757 -384.623681) (xy 299.04271 -384.690506)
			(xy 299.026734 -384.75589) (xy 299.003058 -384.818895) (xy 298.972021 -384.87862) (xy 298.934069 -384.934208)
			(xy 298.91228 -384.95986) (xy 298.906473 -384.966998) (xy 298.899965 -384.984194) (xy 298.89958 -384.993388)
			(xy 298.89958 -385.151376) (xy 298.899159 -385.161531) (xy 298.891367 -385.180287) (xy 298.87697 -385.194612)
			(xy 298.858175 -385.202309) (xy 298.848018 -385.202684) (xy 298.131738 -385.202684) (xy 298.121617 -385.202143)
			(xy 298.102901 -385.194432) (xy 298.088544 -385.180162) (xy 298.08072 -385.161494) (xy 298.080176 -385.151376)
			(xy 298.080176 -384.993388) (xy 298.079777 -384.9842) (xy 298.073256 -384.967015) (xy 298.067476 -384.95986)
			(xy 298.045723 -384.934179) (xy 298.00777 -384.878598) (xy 297.976733 -384.818878) (xy 297.953057 -384.755878)
			(xy 297.93708 -384.690499) (xy 297.929033 -384.623679) (xy 297.92903 -384.556376) (xy 297.937071 -384.489555)
			(xy 297.953041 -384.424174) (xy 297.976711 -384.361171) (xy 298.007742 -384.301449) (xy 298.045689 -384.245864)
			(xy 298.067476 -384.220212) (xy 298.07329 -384.213079) (xy 298.079795 -384.195879) (xy 298.080176 -384.186684)
			(xy 298.080176 -383.693416) (xy 298.079764 -383.684229) (xy 298.073252 -383.667044) (xy 298.067476 -383.659888)
			(xy 298.045651 -383.634266) (xy 298.007701 -383.578676) (xy 297.976668 -383.518948) (xy 297.952995 -383.45594)
			(xy 297.937024 -383.390554) (xy 297.928982 -383.323727) (xy 296.826877 -383.323727) (xy 296.827007 -383.324071)
			(xy 296.84304 -383.389561) (xy 296.851114 -383.4565) (xy 296.851113 -383.523924) (xy 296.843036 -383.590863)
			(xy 296.827 -383.656352) (xy 296.803235 -383.71945) (xy 296.772084 -383.779247) (xy 296.733996 -383.834882)
			(xy 296.712132 -383.860548) (xy 296.706324 -383.867685) (xy 296.699818 -383.884882) (xy 296.699432 -383.894076)
			(xy 296.699432 -384.051556) (xy 296.698949 -384.061672) (xy 296.691221 -384.080368) (xy 296.676925 -384.094683)
			(xy 296.658239 -384.102435) (xy 296.648124 -384.102864) (xy 295.931844 -384.102864) (xy 295.92172 -384.102447)
			(xy 295.90301 -384.094707) (xy 295.888693 -384.08039) (xy 295.880953 -384.06168) (xy 295.880536 -384.051556)
			(xy 295.880536 -383.894076) (xy 295.880129 -383.884889) (xy 295.873612 -383.867705) (xy 295.867836 -383.860548)
			(xy 295.845986 -383.83487) (xy 295.807895 -383.779238) (xy 295.776742 -383.719444) (xy 295.752975 -383.656349)
			(xy 295.736937 -383.590861) (xy 295.728859 -383.523924) (xy 295.728858 -383.4565) (xy 295.736933 -383.389563)
			(xy 295.752968 -383.324074) (xy 295.776732 -383.260978) (xy 295.807883 -383.201182) (xy 295.845972 -383.145549)
			(xy 295.867836 -383.119884) (xy 295.873626 -383.112735) (xy 295.880144 -383.095547) (xy 295.880536 -383.086356)
			(xy 295.880536 -382.59385) (xy 295.880094 -382.584666) (xy 295.873601 -382.567482) (xy 295.867836 -382.560322)
			(xy 295.845961 -382.534665) (xy 295.80787 -382.479031) (xy 295.776718 -382.419233) (xy 295.752953 -382.356135)
			(xy 295.736917 -382.290645) (xy 295.728841 -382.223705) (xy 292.450794 -382.223705) (xy 292.442758 -382.290467)
			(xy 292.426786 -382.355849) (xy 292.403113 -382.418853) (xy 292.37208 -382.478576) (xy 292.334131 -382.534162)
			(xy 292.312344 -382.559814) (xy 292.306552 -382.566962) (xy 292.300036 -382.584151) (xy 292.299644 -382.593342)
			(xy 292.299644 -383.086864) (xy 292.300084 -383.096048) (xy 292.306578 -383.113232) (xy 292.312344 -383.120392)
			(xy 292.334148 -383.146031) (xy 292.372098 -383.201619) (xy 292.403131 -383.261344) (xy 292.426592 -383.323786)
			(xy 293.528687 -383.323786) (xy 293.52869 -383.25636) (xy 293.536769 -383.189419) (xy 293.552808 -383.123928)
			(xy 293.576576 -383.06083) (xy 293.60773 -383.001033) (xy 293.645822 -382.945397) (xy 293.667688 -382.919732)
			(xy 293.673495 -382.912594) (xy 293.680004 -382.895398) (xy 293.680388 -382.886204) (xy 293.680388 -382.728724)
			(xy 293.680835 -382.718605) (xy 293.688573 -382.699904) (xy 293.70288 -382.685589) (xy 293.721577 -382.677841)
			(xy 293.731696 -382.677416) (xy 294.447976 -382.677416) (xy 294.458099 -382.677836) (xy 294.476805 -382.685579)
			(xy 294.491121 -382.699895) (xy 294.498864 -382.718601) (xy 294.499284 -382.728724) (xy 294.499284 -382.886204)
			(xy 294.499696 -382.895391) (xy 294.506209 -382.912575) (xy 294.511984 -382.919732) (xy 294.533813 -382.945426)
			(xy 294.571904 -383.001056) (xy 294.603057 -383.060848) (xy 294.626824 -383.123941) (xy 294.642863 -383.189427)
			(xy 294.650942 -383.256362) (xy 294.650945 -383.323784) (xy 294.642872 -383.39072) (xy 294.62684 -383.456207)
			(xy 294.603079 -383.519302) (xy 294.571932 -383.579097) (xy 294.533846 -383.634731) (xy 294.511984 -383.660396)
			(xy 294.506205 -383.667553) (xy 294.49968 -383.684735) (xy 294.499284 -383.693924) (xy 294.499284 -384.186176)
			(xy 294.499709 -384.195361) (xy 294.506213 -384.212546) (xy 294.511984 -384.219704) (xy 294.533884 -384.24534)
			(xy 294.571973 -384.300978) (xy 294.603123 -384.360778) (xy 294.626885 -384.423879) (xy 294.642919 -384.489372)
			(xy 294.650992 -384.556314) (xy 294.650989 -384.62374) (xy 294.642909 -384.690681) (xy 294.626869 -384.756173)
			(xy 294.603101 -384.819271) (xy 294.571945 -384.879068) (xy 294.533851 -384.934703) (xy 294.511984 -384.960368)
			(xy 294.506174 -384.967504) (xy 294.499668 -384.984702) (xy 294.499284 -384.993896) (xy 294.499284 -385.151376)
			(xy 294.498864 -385.161499) (xy 294.491121 -385.180205) (xy 294.476805 -385.194521) (xy 294.458099 -385.202264)
			(xy 294.447976 -385.202684) (xy 293.731696 -385.202684) (xy 293.721571 -385.202287) (xy 293.702865 -385.194534)
			(xy 293.68855 -385.180212) (xy 293.680808 -385.161501) (xy 293.680388 -385.151376) (xy 293.680388 -384.993896)
			(xy 293.679982 -384.984708) (xy 293.673466 -384.967524) (xy 293.667688 -384.960368) (xy 293.64586 -384.934673)
			(xy 293.607771 -384.879043) (xy 293.576619 -384.819251) (xy 293.552854 -384.756158) (xy 293.536816 -384.690672)
			(xy 293.528737 -384.623737) (xy 293.528734 -384.556317) (xy 293.536806 -384.489381) (xy 293.552838 -384.423894)
			(xy 293.576597 -384.360799) (xy 293.607743 -384.301004) (xy 293.645827 -384.245369) (xy 293.667688 -384.219704)
			(xy 293.673464 -384.212544) (xy 293.679991 -384.195365) (xy 293.680388 -384.186176) (xy 293.680388 -383.693924)
			(xy 293.679969 -383.684738) (xy 293.673462 -383.667553) (xy 293.667688 -383.660396) (xy 293.645789 -383.63476)
			(xy 293.607702 -383.579121) (xy 293.576554 -383.51932) (xy 293.552792 -383.45622) (xy 293.53676 -383.390727)
			(xy 293.528687 -383.323786) (xy 292.426592 -383.323786) (xy 292.426804 -383.32435) (xy 292.442776 -383.389734)
			(xy 292.450819 -383.456559) (xy 292.450818 -383.523865) (xy 292.442772 -383.590689) (xy 292.426797 -383.656073)
			(xy 292.403121 -383.719078) (xy 292.372085 -383.778802) (xy 292.334133 -383.834388) (xy 292.312344 -383.86004)
			(xy 292.306541 -383.86718) (xy 292.300032 -383.884375) (xy 292.299644 -383.893568) (xy 292.299644 -384.051556)
			(xy 292.299149 -384.06167) (xy 292.291423 -384.080364) (xy 292.277132 -384.094679) (xy 292.258449 -384.102433)
			(xy 292.248336 -384.102864) (xy 291.531802 -384.102864) (xy 291.521676 -384.102372) (xy 291.502956 -384.094645)
			(xy 291.488599 -384.080361) (xy 291.480779 -384.06168) (xy 291.48024 -384.051556) (xy 291.48024 -383.893568)
			(xy 291.479836 -383.88438) (xy 291.473317 -383.867197) (xy 291.46754 -383.86004) (xy 291.445768 -383.834375)
			(xy 291.407819 -383.77879) (xy 291.376785 -383.719068) (xy 291.353111 -383.656066) (xy 291.337137 -383.590685)
			(xy 291.329092 -383.523864) (xy 291.32909 -383.45656) (xy 291.337133 -383.389739) (xy 291.353104 -383.324357)
			(xy 291.376775 -383.261354) (xy 291.407806 -383.20163) (xy 291.445753 -383.146044) (xy 291.46754 -383.120392)
			(xy 291.473328 -383.113241) (xy 291.479847 -383.096055) (xy 291.48024 -383.086864) (xy 291.48024 -382.593342)
			(xy 291.4798 -382.584158) (xy 291.473306 -382.566974) (xy 291.46754 -382.559814) (xy 291.445742 -382.53417)
			(xy 291.407794 -382.478582) (xy 291.376761 -382.418858) (xy 291.353088 -382.355852) (xy 291.337116 -382.290469)
			(xy 291.329073 -382.223645) (xy 288.051034 -382.223645) (xy 288.051034 -382.223704) (xy 288.042958 -382.290643)
			(xy 288.026922 -382.356132) (xy 288.003157 -382.419229) (xy 287.972004 -382.479024) (xy 287.933913 -382.534658)
			(xy 287.912048 -382.560322) (xy 287.906253 -382.567468) (xy 287.899739 -382.584658) (xy 287.899348 -382.59385)
			(xy 287.899348 -383.086356) (xy 287.899791 -383.095539) (xy 287.906283 -383.112723) (xy 287.912048 -383.119884)
			(xy 287.93393 -383.145535) (xy 287.972021 -383.201171) (xy 288.003174 -383.260968) (xy 288.026812 -383.323727)
			(xy 289.128894 -383.323727) (xy 289.128898 -383.256418) (xy 289.136946 -383.189593) (xy 289.152924 -383.124208)
			(xy 289.176604 -383.061202) (xy 289.207644 -383.001477) (xy 289.245601 -382.945891) (xy 289.267392 -382.92024)
			(xy 289.273196 -382.9131) (xy 289.279706 -382.895905) (xy 289.280092 -382.886712) (xy 289.280092 -382.728724)
			(xy 289.280535 -382.718604) (xy 289.288274 -382.699902) (xy 289.302582 -382.685588) (xy 289.32128 -382.67784)
			(xy 289.3314 -382.677416) (xy 290.047934 -382.677416) (xy 290.05806 -382.677898) (xy 290.076777 -382.685632)
			(xy 290.091132 -382.69992) (xy 290.098954 -382.7186) (xy 290.099496 -382.728724) (xy 290.099496 -382.886712)
			(xy 290.099901 -382.8959) (xy 290.106419 -382.913084) (xy 290.112196 -382.92024) (xy 290.133947 -382.945922)
			(xy 290.171895 -383.001505) (xy 290.202928 -383.061225) (xy 290.226601 -383.124225) (xy 290.242576 -383.189603)
			(xy 290.250622 -383.256422) (xy 290.250625 -383.323724) (xy 290.242585 -383.390543) (xy 290.226617 -383.455923)
			(xy 290.20295 -383.518926) (xy 290.171923 -383.578649) (xy 290.133981 -383.634235) (xy 290.112196 -383.659888)
			(xy 290.106379 -383.667019) (xy 290.099877 -383.68422) (xy 290.099496 -383.693416) (xy 290.099496 -384.186684)
			(xy 290.099915 -384.19587) (xy 290.106423 -384.213055) (xy 290.112196 -384.220212) (xy 290.134018 -384.245836)
			(xy 290.171963 -384.301427) (xy 290.202993 -384.361155) (xy 290.226662 -384.424163) (xy 290.242632 -384.489548)
			(xy 290.250673 -384.556373) (xy 290.250669 -384.623681) (xy 290.242622 -384.690505) (xy 290.226646 -384.755889)
			(xy 290.202971 -384.818895) (xy 290.171936 -384.87862) (xy 290.133985 -384.934207) (xy 290.112196 -384.95986)
			(xy 290.106391 -384.966999) (xy 290.099881 -384.984194) (xy 290.099496 -384.993388) (xy 290.099496 -385.151376)
			(xy 290.099064 -385.161497) (xy 290.091323 -385.180201) (xy 290.077011 -385.194517) (xy 290.058309 -385.202262)
			(xy 290.048188 -385.202684) (xy 289.331654 -385.202684) (xy 289.321527 -385.202212) (xy 289.30281 -385.194473)
			(xy 289.288456 -385.180183) (xy 289.280634 -385.1615) (xy 289.280092 -385.151376) (xy 289.280092 -384.993388)
			(xy 289.279689 -384.9842) (xy 289.273171 -384.967016) (xy 289.267392 -384.95986) (xy 289.245638 -384.934179)
			(xy 289.207685 -384.878598) (xy 289.176647 -384.818879) (xy 289.15297 -384.755878) (xy 289.136993 -384.690499)
			(xy 289.128945 -384.623679) (xy 289.128942 -384.556375) (xy 289.136983 -384.489554) (xy 289.152954 -384.424174)
			(xy 289.176625 -384.36117) (xy 289.207657 -384.301448) (xy 289.245605 -384.245863) (xy 289.267392 -384.220212)
			(xy 289.273208 -384.21308) (xy 289.279711 -384.195879) (xy 289.280092 -384.186684) (xy 289.280092 -383.693416)
			(xy 289.279676 -383.684229) (xy 289.273167 -383.667045) (xy 289.267392 -383.659888) (xy 289.245567 -383.634266)
			(xy 289.207616 -383.578676) (xy 289.176581 -383.518949) (xy 289.152908 -383.45594) (xy 289.136936 -383.390554)
			(xy 289.128894 -383.323727) (xy 288.026812 -383.323727) (xy 288.02694 -383.324067) (xy 288.042976 -383.389558)
			(xy 288.051051 -383.456499) (xy 288.05105 -383.523925) (xy 288.042971 -383.590865) (xy 288.026933 -383.656356)
			(xy 288.003164 -383.719454) (xy 287.972009 -383.77925) (xy 287.933915 -383.834884) (xy 287.912048 -383.860548)
			(xy 287.906242 -383.867686) (xy 287.899734 -383.884882) (xy 287.899348 -383.894076) (xy 287.899348 -384.051556)
			(xy 287.898849 -384.06167) (xy 287.891124 -384.080363) (xy 287.876834 -384.094677) (xy 287.858153 -384.102432)
			(xy 287.84804 -384.102864) (xy 287.13176 -384.102864) (xy 287.12163 -384.102516) (xy 287.102919 -384.094748)
			(xy 287.088605 -384.08041) (xy 287.080868 -384.061686) (xy 287.080452 -384.051556) (xy 287.080452 -383.894076)
			(xy 287.080042 -383.884889) (xy 287.073527 -383.867705) (xy 287.067752 -383.860548) (xy 287.045902 -383.834871)
			(xy 287.007809 -383.779239) (xy 286.976655 -383.719445) (xy 286.952888 -383.65635) (xy 286.936849 -383.590862)
			(xy 286.928772 -383.523924) (xy 286.92877 -383.4565) (xy 286.936845 -383.389562) (xy 286.952881 -383.324073)
			(xy 286.976645 -383.260977) (xy 287.007797 -383.201182) (xy 287.045887 -383.145548) (xy 287.067752 -383.119884)
			(xy 287.073544 -383.112736) (xy 287.08006 -383.095547) (xy 287.080452 -383.086356) (xy 287.080452 -382.59385)
			(xy 287.080006 -382.584667) (xy 287.073516 -382.567483) (xy 287.067752 -382.560322) (xy 287.045876 -382.534666)
			(xy 287.007785 -382.479031) (xy 286.976631 -382.419234) (xy 286.952865 -382.356136) (xy 286.936829 -382.290645)
			(xy 286.928753 -382.223705) (xy 262.274304 -382.223705) (xy 262.274304 -385.608376) (xy 454.303373 -385.608376)
			(xy 454.303373 -385.479236) (xy 454.311323 -385.350341) (xy 454.327193 -385.222181) (xy 454.350922 -385.09524)
			(xy 454.382421 -384.970001) (xy 454.42157 -384.846938) (xy 454.468221 -384.726519) (xy 454.522196 -384.6092)
			(xy 454.583291 -384.495426) (xy 454.651274 -384.385629) (xy 454.725888 -384.280226) (xy 454.806849 -384.179616)
			(xy 454.893849 -384.084181) (xy 454.98656 -383.994282) (xy 455.08463 -383.910261) (xy 455.187685 -383.832437)
			(xy 455.295336 -383.761105) (xy 455.407175 -383.696535) (xy 455.522776 -383.638973) (xy 455.641701 -383.588636)
			(xy 455.7635 -383.545716) (xy 455.88771 -383.510375) (xy 456.013859 -383.482748) (xy 456.141471 -383.462939)
			(xy 456.27006 -383.451023) (xy 456.399138 -383.447047) (xy 456.528216 -383.451023) (xy 456.656805 -383.462939)
			(xy 456.784417 -383.482748) (xy 456.910566 -383.510375) (xy 457.034776 -383.545716) (xy 457.156575 -383.588636)
			(xy 457.2755 -383.638973) (xy 457.391101 -383.696535) (xy 457.50294 -383.761105) (xy 457.610591 -383.832437)
			(xy 457.713646 -383.910261) (xy 457.811716 -383.994282) (xy 457.904427 -384.084181) (xy 457.991427 -384.179616)
			(xy 458.072388 -384.280226) (xy 458.147002 -384.385629) (xy 458.214985 -384.495426) (xy 458.27608 -384.6092)
			(xy 458.330055 -384.726519) (xy 458.376706 -384.846938) (xy 458.415855 -384.970001) (xy 458.447354 -385.09524)
			(xy 458.471083 -385.222181) (xy 458.486953 -385.350341) (xy 458.494903 -385.479236) (xy 458.4954 -385.543806)
			(xy 458.494903 -385.608376) (xy 458.486953 -385.737271) (xy 458.471083 -385.865431) (xy 458.447354 -385.992372)
			(xy 458.415855 -386.117611) (xy 458.376706 -386.240674) (xy 458.330055 -386.361093) (xy 458.27608 -386.478412)
			(xy 458.214985 -386.592186) (xy 458.147002 -386.701983) (xy 458.072388 -386.807386) (xy 457.991427 -386.907996)
			(xy 457.904427 -387.003431) (xy 457.811716 -387.09333) (xy 457.713646 -387.177351) (xy 457.610591 -387.255175)
			(xy 457.50294 -387.326507) (xy 457.391101 -387.391077) (xy 457.2755 -387.448639) (xy 457.156575 -387.498976)
			(xy 457.034776 -387.541896) (xy 456.910566 -387.577237) (xy 456.784417 -387.604864) (xy 456.656805 -387.624673)
			(xy 456.528216 -387.636589) (xy 456.399138 -387.640566) (xy 456.27006 -387.636589) (xy 456.141471 -387.624673)
			(xy 456.013859 -387.604864) (xy 455.88771 -387.577237) (xy 455.7635 -387.541896) (xy 455.641701 -387.498976)
			(xy 455.522776 -387.448639) (xy 455.407175 -387.391077) (xy 455.295336 -387.326507) (xy 455.187685 -387.255175)
			(xy 455.08463 -387.177351) (xy 454.98656 -387.09333) (xy 454.893849 -387.003431) (xy 454.806849 -386.907996)
			(xy 454.725888 -386.807386) (xy 454.651274 -386.701983) (xy 454.583291 -386.592186) (xy 454.522196 -386.478412)
			(xy 454.468221 -386.361093) (xy 454.42157 -386.240674) (xy 454.382421 -386.117611) (xy 454.350922 -385.992372)
			(xy 454.327193 -385.865431) (xy 454.311323 -385.737271) (xy 454.303373 -385.608376) (xy 262.274304 -385.608376)
			(xy 262.274304 -387.892798) (xy 262.273903 -387.902871) (xy 262.266168 -387.92147) (xy 262.259318 -387.928866)
			(xy 259.197602 -390.990582) (xy 259.190193 -390.997411) (xy 259.171601 -391.005138) (xy 259.161534 -391.005568)
			(xy 245.155466 -391.005568) (xy 245.143121 -391.006101) (xy 245.120249 -391.015389) (xy 245.111016 -391.023602)
			(xy 245.110508 -391.02411) (xy 244.084602 -392.050016) (xy 244.076151 -392.059207) (xy 244.066584 -392.082246)
			(xy 244.06606 -392.09472) (xy 244.06606 -397.823885) (xy 286.928734 -397.823885) (xy 286.928737 -397.756458)
			(xy 286.936817 -397.689516) (xy 286.952859 -397.624024) (xy 286.976629 -397.560925) (xy 287.007787 -397.501128)
			(xy 287.045884 -397.445494) (xy 287.067752 -397.41983) (xy 287.073567 -397.412698) (xy 287.080069 -397.395497)
			(xy 287.080452 -397.386302) (xy 287.080452 -396.89405) (xy 287.080006 -396.884867) (xy 287.073516 -396.867683)
			(xy 287.067752 -396.860522) (xy 287.045876 -396.834866) (xy 287.007785 -396.779231) (xy 286.976631 -396.719434)
			(xy 286.952865 -396.656336) (xy 286.936829 -396.590845) (xy 286.928753 -396.523905) (xy 286.928754 -396.45648)
			(xy 286.936832 -396.38954) (xy 286.95287 -396.32405) (xy 286.976638 -396.260952) (xy 287.007792 -396.201156)
			(xy 287.045886 -396.145522) (xy 287.067752 -396.119858) (xy 287.073555 -396.112718) (xy 287.080065 -396.095523)
			(xy 287.080452 -396.08633) (xy 287.080452 -395.92885) (xy 287.080968 -395.918725) (xy 287.088682 -395.900003)
			(xy 287.102959 -395.885644) (xy 287.121638 -395.877825) (xy 287.13176 -395.877288) (xy 287.84804 -395.877288)
			(xy 287.858195 -395.877689) (xy 287.876946 -395.885495) (xy 287.891268 -395.899898) (xy 287.898968 -395.918693)
			(xy 287.899348 -395.92885) (xy 287.899348 -396.08633) (xy 287.899755 -396.095517) (xy 287.906272 -396.112701)
			(xy 287.912048 -396.119858) (xy 287.933904 -396.14553) (xy 287.971996 -396.201163) (xy 288.00315 -396.260957)
			(xy 288.026917 -396.324053) (xy 288.042955 -396.389542) (xy 288.051033 -396.456481) (xy 288.051034 -396.523904)
			(xy 288.042958 -396.590843) (xy 288.026922 -396.656332) (xy 288.003157 -396.719429) (xy 287.972004 -396.779224)
			(xy 287.933913 -396.834858) (xy 287.912048 -396.860522) (xy 287.906253 -396.867668) (xy 287.899739 -396.884858)
			(xy 287.899348 -396.89405) (xy 287.899348 -397.386302) (xy 287.899769 -397.395488) (xy 287.906276 -397.412672)
			(xy 287.912048 -397.41983) (xy 287.933876 -397.445525) (xy 287.97197 -397.501154) (xy 288.000733 -397.556355)
			(xy 289.128926 -397.556355) (xy 289.13697 -397.489532) (xy 289.152943 -397.42415) (xy 289.176617 -397.361145)
			(xy 289.207652 -397.301423) (xy 289.245603 -397.245837) (xy 289.267392 -397.220186) (xy 289.273176 -397.213032)
			(xy 289.279698 -397.195848) (xy 289.280092 -397.186658) (xy 289.280092 -397.028924) (xy 289.280541 -397.018772)
			(xy 289.288327 -397.000022) (xy 289.302715 -396.985698) (xy 289.321501 -396.977996) (xy 289.331654 -396.977616)
			(xy 290.047934 -396.977616) (xy 290.05806 -396.978098) (xy 290.076777 -396.985832) (xy 290.091132 -397.00012)
			(xy 290.098954 -397.0188) (xy 290.099496 -397.028924) (xy 290.099496 -397.186658) (xy 290.099927 -397.195843)
			(xy 290.106426 -397.213027) (xy 290.112196 -397.220186) (xy 290.133992 -397.245831) (xy 290.171939 -397.301419)
			(xy 290.20297 -397.361144) (xy 290.22664 -397.424149) (xy 290.242612 -397.489532) (xy 290.250654 -397.556355)
			(xy 290.250653 -397.62366) (xy 290.242609 -397.690483) (xy 290.226636 -397.755865) (xy 290.202963 -397.81887)
			(xy 290.200388 -397.823825) (xy 291.329053 -397.823825) (xy 291.329057 -397.756517) (xy 291.337105 -397.689692)
			(xy 291.353082 -397.624308) (xy 291.376759 -397.561302) (xy 291.407796 -397.501577) (xy 291.44575 -397.44599)
			(xy 291.46754 -397.420338) (xy 291.47335 -397.413203) (xy 291.479856 -397.396004) (xy 291.48024 -397.38681)
			(xy 291.48024 -396.893542) (xy 291.4798 -396.884358) (xy 291.473306 -396.867174) (xy 291.46754 -396.860014)
			(xy 291.445742 -396.83437) (xy 291.407794 -396.778782) (xy 291.376761 -396.719058) (xy 291.353088 -396.656052)
			(xy 291.337116 -396.590669) (xy 291.329073 -396.523845) (xy 291.329074 -396.45654) (xy 291.337119 -396.389716)
			(xy 291.353093 -396.324333) (xy 291.376767 -396.261328) (xy 291.407801 -396.201605) (xy 291.445751 -396.146018)
			(xy 291.46754 -396.120366) (xy 291.473339 -396.113222) (xy 291.479851 -396.096031) (xy 291.48024 -396.086838)
			(xy 291.48024 -395.92885) (xy 291.480705 -395.918681) (xy 291.488474 -395.899887) (xy 291.502847 -395.885501)
			(xy 291.521634 -395.877714) (xy 291.531802 -395.877288) (xy 292.248082 -395.877288) (xy 292.258259 -395.87768)
			(xy 292.277063 -395.885468) (xy 292.29145 -395.899864) (xy 292.299227 -395.918673) (xy 292.299644 -395.92885)
			(xy 292.299644 -396.086838) (xy 292.300049 -396.096026) (xy 292.306568 -396.113209) (xy 292.312344 -396.120366)
			(xy 292.334122 -396.146026) (xy 292.372072 -396.201611) (xy 292.403107 -396.261333) (xy 292.426781 -396.324337)
			(xy 292.442755 -396.389718) (xy 292.450801 -396.45654) (xy 292.450801 -396.523845) (xy 292.442758 -396.590667)
			(xy 292.426786 -396.656049) (xy 292.403113 -396.719053) (xy 292.37208 -396.778776) (xy 292.334131 -396.834362)
			(xy 292.312344 -396.860014) (xy 292.306552 -396.867162) (xy 292.300036 -396.884351) (xy 292.299644 -396.893542)
			(xy 292.299644 -397.38681) (xy 292.300062 -397.395996) (xy 292.306572 -397.41318) (xy 292.312344 -397.420338)
			(xy 292.334095 -397.446021) (xy 292.372046 -397.501602) (xy 292.40047 -397.556296) (xy 293.528718 -397.556296)
			(xy 293.536793 -397.489359) (xy 293.552827 -397.42387) (xy 293.576589 -397.360774) (xy 293.607738 -397.300978)
			(xy 293.645825 -397.245343) (xy 293.667688 -397.219678) (xy 293.673475 -397.212526) (xy 293.679996 -397.195341)
			(xy 293.680388 -397.18615) (xy 293.680388 -397.028924) (xy 293.680835 -397.018805) (xy 293.688573 -397.000104)
			(xy 293.70288 -396.985789) (xy 293.721577 -396.978041) (xy 293.731696 -396.977616) (xy 294.447976 -396.977616)
			(xy 294.458099 -396.978036) (xy 294.476805 -396.985779) (xy 294.491121 -397.000095) (xy 294.498864 -397.018801)
			(xy 294.499284 -397.028924) (xy 294.499284 -397.18615) (xy 294.499722 -397.195334) (xy 294.506217 -397.212519)
			(xy 294.511984 -397.219678) (xy 294.533858 -397.245335) (xy 294.571948 -397.30097) (xy 294.603099 -397.360767)
			(xy 294.626863 -397.423865) (xy 294.642899 -397.489356) (xy 294.650974 -397.556295) (xy 294.650973 -397.62372)
			(xy 294.642896 -397.690659) (xy 294.626859 -397.756149) (xy 294.603093 -397.819246) (xy 294.600676 -397.823885)
			(xy 295.728821 -397.823885) (xy 295.728825 -397.756458) (xy 295.736905 -397.689516) (xy 295.752946 -397.624025)
			(xy 295.776716 -397.560926) (xy 295.807873 -397.501129) (xy 295.845969 -397.445495) (xy 295.867836 -397.41983)
			(xy 295.873649 -397.412697) (xy 295.880153 -397.395497) (xy 295.880536 -397.386302) (xy 295.880536 -396.89405)
			(xy 295.880094 -396.884866) (xy 295.873601 -396.867682) (xy 295.867836 -396.860522) (xy 295.845961 -396.834865)
			(xy 295.80787 -396.779231) (xy 295.776718 -396.719433) (xy 295.752953 -396.656335) (xy 295.736917 -396.590845)
			(xy 295.728841 -396.523905) (xy 295.728842 -396.45648) (xy 295.73692 -396.38954) (xy 295.752957 -396.32405)
			(xy 295.776724 -396.260953) (xy 295.807878 -396.201157) (xy 295.84597 -396.145523) (xy 295.867836 -396.119858)
			(xy 295.873637 -396.112716) (xy 295.880148 -396.095523) (xy 295.880536 -396.08633) (xy 295.880536 -395.92885)
			(xy 295.881067 -395.918727) (xy 295.888778 -395.900008) (xy 295.903051 -395.88565) (xy 295.921724 -395.877828)
			(xy 295.931844 -395.877288) (xy 296.648124 -395.877288) (xy 296.658278 -395.877702) (xy 296.677029 -395.885503)
			(xy 296.691351 -395.899902) (xy 296.699052 -395.918694) (xy 296.699432 -395.92885) (xy 296.699432 -396.08633)
			(xy 296.699843 -396.095517) (xy 296.706358 -396.1127) (xy 296.712132 -396.119858) (xy 296.733985 -396.145532)
			(xy 296.772072 -396.201166) (xy 296.803221 -396.260961) (xy 296.826985 -396.324057) (xy 296.84302 -396.389545)
			(xy 296.851096 -396.456481) (xy 296.851097 -396.523904) (xy 296.843022 -396.590841) (xy 296.826989 -396.656329)
			(xy 296.803227 -396.719425) (xy 296.77208 -396.779221) (xy 296.733994 -396.834856) (xy 296.712132 -396.860522)
			(xy 296.706335 -396.867667) (xy 296.699823 -396.884858) (xy 296.699432 -396.89405) (xy 296.699432 -397.386302)
			(xy 296.699856 -397.395487) (xy 296.706362 -397.412671) (xy 296.712132 -397.41983) (xy 296.733958 -397.445527)
			(xy 296.772045 -397.501157) (xy 296.800802 -397.556355) (xy 297.929014 -397.556355) (xy 297.937057 -397.489532)
			(xy 297.95303 -397.42415) (xy 297.976704 -397.361146) (xy 298.007738 -397.301423) (xy 298.045688 -397.245838)
			(xy 298.067476 -397.220186) (xy 298.073258 -397.21303) (xy 298.079782 -397.195848) (xy 298.080176 -397.186658)
			(xy 298.080176 -397.028924) (xy 298.080641 -397.018774) (xy 298.088424 -397.000027) (xy 298.102807 -396.985704)
			(xy 298.121587 -396.977999) (xy 298.131738 -396.977616) (xy 298.848018 -396.977616) (xy 298.858143 -396.978111)
			(xy 298.87686 -396.98584) (xy 298.891215 -397.000123) (xy 298.899038 -397.018802) (xy 298.89958 -397.028924)
			(xy 298.89958 -397.186658) (xy 298.900015 -397.195842) (xy 298.906512 -397.213027) (xy 298.91228 -397.220186)
			(xy 298.934077 -397.24583) (xy 298.972024 -397.301418) (xy 299.003056 -397.361143) (xy 299.026728 -397.424149)
			(xy 299.042699 -397.489532) (xy 299.050742 -397.556355) (xy 299.050741 -397.62366) (xy 299.042697 -397.690483)
			(xy 299.026723 -397.755866) (xy 299.00305 -397.818871) (xy 299.000445 -397.823885) (xy 300.128612 -397.823885)
			(xy 300.128616 -397.756458) (xy 300.136696 -397.689517) (xy 300.152736 -397.624025) (xy 300.176506 -397.560927)
			(xy 300.207662 -397.501129) (xy 300.245757 -397.445495) (xy 300.267624 -397.41983) (xy 300.273436 -397.412696)
			(xy 300.27994 -397.395497) (xy 300.280324 -397.386302) (xy 300.280324 -396.89405) (xy 300.279884 -396.884866)
			(xy 300.273391 -396.867682) (xy 300.267624 -396.860522) (xy 300.245749 -396.834865) (xy 300.207659 -396.77923)
			(xy 300.176508 -396.719433) (xy 300.152743 -396.656335) (xy 300.136708 -396.590845) (xy 300.128632 -396.523905)
			(xy 300.128633 -396.45648) (xy 300.13671 -396.389541) (xy 300.152748 -396.324051) (xy 300.176514 -396.260953)
			(xy 300.207667 -396.201157) (xy 300.245759 -396.145523) (xy 300.267624 -396.119858) (xy 300.273424 -396.112715)
			(xy 300.279936 -396.095523) (xy 300.280324 -396.08633) (xy 300.280324 -395.92885) (xy 300.280867 -395.918728)
			(xy 300.288576 -395.900011) (xy 300.302845 -395.885654) (xy 300.321514 -395.87783) (xy 300.331632 -395.877288)
			(xy 301.047912 -395.877288) (xy 301.058065 -395.877711) (xy 301.076816 -395.885509) (xy 301.091138 -395.899904)
			(xy 301.09884 -395.918694) (xy 301.09922 -395.92885) (xy 301.09922 -396.08633) (xy 301.099611 -396.095519)
			(xy 301.106138 -396.112704) (xy 301.11192 -396.119858) (xy 301.133773 -396.145532) (xy 301.171861 -396.201165)
			(xy 301.203011 -396.260961) (xy 301.226775 -396.324056) (xy 301.242811 -396.389544) (xy 301.250887 -396.456481)
			(xy 301.250888 -396.523904) (xy 301.242813 -396.590841) (xy 301.226779 -396.656329) (xy 301.203017 -396.719426)
			(xy 301.171869 -396.779222) (xy 301.133783 -396.834856) (xy 301.11192 -396.860522) (xy 301.106134 -396.867675)
			(xy 301.099612 -396.884859) (xy 301.09922 -396.89405) (xy 301.09922 -397.386302) (xy 301.099625 -397.39549)
			(xy 301.106142 -397.412674) (xy 301.11192 -397.41983) (xy 301.133746 -397.445526) (xy 301.171834 -397.501157)
			(xy 301.200562 -397.556296) (xy 302.328806 -397.556296) (xy 302.336881 -397.489359) (xy 302.352914 -397.423871)
			(xy 302.376676 -397.360775) (xy 302.407824 -397.300979) (xy 302.44591 -397.245344) (xy 302.467772 -397.219678)
			(xy 302.473569 -397.212534) (xy 302.480081 -397.195342) (xy 302.480472 -397.18615) (xy 302.480472 -397.028924)
			(xy 302.480935 -397.018806) (xy 302.48867 -397.000109) (xy 302.502972 -396.985795) (xy 302.521663 -396.978043)
			(xy 302.53178 -396.977616) (xy 303.24806 -396.977616) (xy 303.258182 -396.978049) (xy 303.276888 -396.985787)
			(xy 303.291204 -397.000099) (xy 303.298948 -397.018802) (xy 303.299368 -397.028924) (xy 303.299368 -397.18615)
			(xy 303.299809 -397.195334) (xy 303.306302 -397.212518) (xy 303.312068 -397.219678) (xy 303.333943 -397.245335)
			(xy 303.372033 -397.30097) (xy 303.403185 -397.360767) (xy 303.426951 -397.423865) (xy 303.442986 -397.489355)
			(xy 303.451062 -397.556295) (xy 303.451061 -397.62372) (xy 303.442984 -397.69066) (xy 303.426946 -397.75615)
			(xy 303.403179 -397.819247) (xy 303.372026 -397.879043) (xy 303.333934 -397.934677) (xy 303.312068 -397.960342)
			(xy 303.306267 -397.967484) (xy 303.299756 -397.984677) (xy 303.299368 -397.99387) (xy 303.299368 -398.486376)
			(xy 303.299797 -398.495561) (xy 303.306299 -398.512745) (xy 303.312068 -398.519904) (xy 303.333968 -398.54554)
			(xy 303.372058 -398.601178) (xy 303.403209 -398.660978) (xy 303.426973 -398.724078) (xy 303.443007 -398.789571)
			(xy 303.45108 -398.856513) (xy 303.451077 -398.923941) (xy 303.442997 -398.990882) (xy 303.426957 -399.056373)
			(xy 303.403187 -399.119472) (xy 303.37203 -399.179269) (xy 303.333935 -399.234903) (xy 303.312068 -399.260568)
			(xy 303.306256 -399.267702) (xy 303.299751 -399.284901) (xy 303.299368 -399.294096) (xy 303.299368 -399.451576)
			(xy 303.298964 -399.461701) (xy 303.291218 -399.48041) (xy 303.276897 -399.494727) (xy 303.258185 -399.502467)
			(xy 303.24806 -399.502884) (xy 302.53178 -399.502884) (xy 302.521654 -399.5025) (xy 302.502947 -399.494742)
			(xy 302.488633 -399.480416) (xy 302.480891 -399.461702) (xy 302.480472 -399.451576) (xy 302.480472 -399.294096)
			(xy 302.48007 -399.284908) (xy 302.473551 -399.267723) (xy 302.467772 -399.260568) (xy 302.445944 -399.234873)
			(xy 302.407856 -399.179242) (xy 302.376706 -399.11945) (xy 302.352941 -399.056357) (xy 302.336904 -398.990872)
			(xy 302.328825 -398.923937) (xy 302.328822 -398.856517) (xy 302.336894 -398.789582) (xy 302.352925 -398.724095)
			(xy 302.376684 -398.661) (xy 302.407829 -398.601204) (xy 302.445911 -398.54557) (xy 302.467772 -398.519904)
			(xy 302.473558 -398.512752) (xy 302.480077 -398.495566) (xy 302.480472 -398.486376) (xy 302.480472 -397.99387)
			(xy 302.480082 -397.98468) (xy 302.473555 -397.967496) (xy 302.467772 -397.960342) (xy 302.445919 -397.934668)
			(xy 302.407832 -397.879034) (xy 302.376682 -397.819239) (xy 302.352919 -397.756143) (xy 302.336883 -397.690656)
			(xy 302.328807 -397.623719) (xy 302.328806 -397.556296) (xy 301.200562 -397.556296) (xy 301.202986 -397.560949)
			(xy 301.226751 -397.624042) (xy 301.242789 -397.689527) (xy 301.250867 -397.756461) (xy 301.250871 -397.823882)
			(xy 301.242799 -397.890817) (xy 301.226768 -397.956304) (xy 301.203009 -398.019399) (xy 301.171864 -398.079194)
			(xy 301.133781 -398.134828) (xy 301.11192 -398.160494) (xy 301.106146 -398.167655) (xy 301.099617 -398.184833)
			(xy 301.09922 -398.194022) (xy 301.09922 -398.351502) (xy 301.098774 -398.361634) (xy 301.091038 -398.380362)
			(xy 301.076739 -398.39472) (xy 301.058042 -398.402532) (xy 301.047912 -398.403064) (xy 300.331632 -398.403064)
			(xy 300.321475 -398.402652) (xy 300.302717 -398.39486) (xy 300.288391 -398.38046) (xy 300.280696 -398.361661)
			(xy 300.280324 -398.351502) (xy 300.280324 -398.194022) (xy 300.279898 -398.184837) (xy 300.273395 -398.167652)
			(xy 300.267624 -398.160494) (xy 300.245722 -398.13486) (xy 300.207633 -398.079222) (xy 300.176482 -398.019421)
			(xy 300.152719 -397.95632) (xy 300.136686 -397.890827) (xy 300.128612 -397.823885) (xy 299.000445 -397.823885)
			(xy 298.972017 -397.878595) (xy 298.934068 -397.934182) (xy 298.91228 -397.959834) (xy 298.906484 -397.96698)
			(xy 298.89997 -397.98417) (xy 298.89958 -397.993362) (xy 298.89958 -398.486884) (xy 298.900003 -398.49607)
			(xy 298.906508 -398.513254) (xy 298.91228 -398.520412) (xy 298.934103 -398.546035) (xy 298.972049 -398.601626)
			(xy 299.00308 -398.661354) (xy 299.02675 -398.724362) (xy 299.04272 -398.789748) (xy 299.050761 -398.856573)
			(xy 299.050757 -398.923881) (xy 299.04271 -398.990706) (xy 299.026734 -399.05609) (xy 299.003058 -399.119095)
			(xy 298.972021 -399.17882) (xy 298.934069 -399.234408) (xy 298.91228 -399.26006) (xy 298.906473 -399.267198)
			(xy 298.899965 -399.284394) (xy 298.89958 -399.293588) (xy 298.89958 -399.451576) (xy 298.899159 -399.461731)
			(xy 298.891367 -399.480487) (xy 298.87697 -399.494812) (xy 298.858175 -399.502509) (xy 298.848018 -399.502884)
			(xy 298.131738 -399.502884) (xy 298.121617 -399.502343) (xy 298.102901 -399.494632) (xy 298.088544 -399.480362)
			(xy 298.08072 -399.461694) (xy 298.080176 -399.451576) (xy 298.080176 -399.293588) (xy 298.079777 -399.2844)
			(xy 298.073256 -399.267215) (xy 298.067476 -399.26006) (xy 298.045723 -399.234379) (xy 298.00777 -399.178798)
			(xy 297.976733 -399.119078) (xy 297.953057 -399.056078) (xy 297.93708 -398.990699) (xy 297.929033 -398.923879)
			(xy 297.92903 -398.856576) (xy 297.937071 -398.789755) (xy 297.953041 -398.724374) (xy 297.976711 -398.661371)
			(xy 298.007742 -398.601649) (xy 298.045689 -398.546064) (xy 298.067476 -398.520412) (xy 298.07329 -398.513279)
			(xy 298.079795 -398.496079) (xy 298.080176 -398.486884) (xy 298.080176 -397.993362) (xy 298.079789 -397.984172)
			(xy 298.07326 -397.966988) (xy 298.067476 -397.959834) (xy 298.045697 -397.934174) (xy 298.007746 -397.87859)
			(xy 297.97671 -397.818868) (xy 297.953035 -397.755864) (xy 297.93706 -397.690482) (xy 297.929015 -397.62366)
			(xy 297.929014 -397.556355) (xy 296.800802 -397.556355) (xy 296.803196 -397.56095) (xy 296.826961 -397.624042)
			(xy 296.842998 -397.689527) (xy 296.851076 -397.756461) (xy 296.85108 -397.823881) (xy 296.843008 -397.890817)
			(xy 296.826978 -397.956303) (xy 296.803219 -398.019398) (xy 296.772075 -398.079194) (xy 296.733993 -398.134828)
			(xy 296.712132 -398.160494) (xy 296.706347 -398.167647) (xy 296.699827 -398.184832) (xy 296.699432 -398.194022)
			(xy 296.699432 -398.351502) (xy 296.698974 -398.361632) (xy 296.691241 -398.380359) (xy 296.676945 -398.394716)
			(xy 296.658252 -398.40253) (xy 296.648124 -398.403064) (xy 295.931844 -398.403064) (xy 295.921688 -398.402642)
			(xy 295.90293 -398.394854) (xy 295.888604 -398.380456) (xy 295.880909 -398.36166) (xy 295.880536 -398.351502)
			(xy 295.880536 -398.194022) (xy 295.880107 -398.184837) (xy 295.873606 -398.167653) (xy 295.867836 -398.160494)
			(xy 295.845933 -398.13486) (xy 295.807843 -398.079222) (xy 295.776692 -398.019422) (xy 295.752929 -397.956321)
			(xy 295.736895 -397.890827) (xy 295.728821 -397.823885) (xy 294.600676 -397.823885) (xy 294.57194 -397.879043)
			(xy 294.533849 -397.934677) (xy 294.511984 -397.960342) (xy 294.506185 -397.967486) (xy 294.499672 -397.984677)
			(xy 294.499284 -397.99387) (xy 294.499284 -398.486376) (xy 294.499709 -398.495561) (xy 294.506213 -398.512746)
			(xy 294.511984 -398.519904) (xy 294.533884 -398.54554) (xy 294.571973 -398.601178) (xy 294.603123 -398.660978)
			(xy 294.626885 -398.724079) (xy 294.642919 -398.789572) (xy 294.650992 -398.856514) (xy 294.650989 -398.92394)
			(xy 294.642909 -398.990881) (xy 294.626869 -399.056373) (xy 294.603101 -399.119471) (xy 294.571945 -399.179268)
			(xy 294.533851 -399.234903) (xy 294.511984 -399.260568) (xy 294.506174 -399.267704) (xy 294.499668 -399.284902)
			(xy 294.499284 -399.294096) (xy 294.499284 -399.451576) (xy 294.498864 -399.461699) (xy 294.491121 -399.480405)
			(xy 294.476805 -399.494721) (xy 294.458099 -399.502464) (xy 294.447976 -399.502884) (xy 293.731696 -399.502884)
			(xy 293.721571 -399.502487) (xy 293.702865 -399.494734) (xy 293.68855 -399.480412) (xy 293.680808 -399.461701)
			(xy 293.680388 -399.451576) (xy 293.680388 -399.294096) (xy 293.679982 -399.284908) (xy 293.673466 -399.267724)
			(xy 293.667688 -399.260568) (xy 293.64586 -399.234873) (xy 293.607771 -399.179243) (xy 293.576619 -399.119451)
			(xy 293.552854 -399.056358) (xy 293.536816 -398.990872) (xy 293.528737 -398.923937) (xy 293.528734 -398.856517)
			(xy 293.536806 -398.789581) (xy 293.552838 -398.724094) (xy 293.576597 -398.660999) (xy 293.607743 -398.601204)
			(xy 293.645827 -398.545569) (xy 293.667688 -398.519904) (xy 293.673464 -398.512744) (xy 293.679991 -398.495565)
			(xy 293.680388 -398.486376) (xy 293.680388 -397.99387) (xy 293.679995 -397.984681) (xy 293.673469 -397.967497)
			(xy 293.667688 -397.960342) (xy 293.645834 -397.934668) (xy 293.607746 -397.879035) (xy 293.576596 -397.81924)
			(xy 293.552831 -397.756144) (xy 293.536796 -397.690656) (xy 293.528719 -397.623719) (xy 293.528718 -397.556296)
			(xy 292.40047 -397.556296) (xy 292.403082 -397.561322) (xy 292.426757 -397.624322) (xy 292.442733 -397.689701)
			(xy 292.450781 -397.75652) (xy 292.450784 -397.823823) (xy 292.442744 -397.890643) (xy 292.426774 -397.956023)
			(xy 292.403105 -398.019026) (xy 292.372075 -398.078748) (xy 292.33413 -398.134334) (xy 292.312344 -398.159986)
			(xy 292.306522 -398.167113) (xy 292.300024 -398.184318) (xy 292.299644 -398.193514) (xy 292.299644 -398.351502)
			(xy 292.299237 -398.361676) (xy 292.291448 -398.380474) (xy 292.277057 -398.39486) (xy 292.258256 -398.402641)
			(xy 292.248082 -398.403064) (xy 291.531802 -398.403064) (xy 291.521645 -398.402565) (xy 291.502876 -398.394792)
			(xy 291.488511 -398.380427) (xy 291.480736 -398.361659) (xy 291.48024 -398.351502) (xy 291.48024 -398.193514)
			(xy 291.479814 -398.184329) (xy 291.473311 -398.167145) (xy 291.46754 -398.159986) (xy 291.445715 -398.134365)
			(xy 291.407767 -398.078774) (xy 291.376735 -398.019046) (xy 291.353065 -397.956037) (xy 291.337094 -397.890651)
			(xy 291.329053 -397.823825) (xy 290.200388 -397.823825) (xy 290.171931 -397.878594) (xy 290.133983 -397.934181)
			(xy 290.112196 -397.959834) (xy 290.106402 -397.966981) (xy 290.099886 -397.98417) (xy 290.099496 -397.993362)
			(xy 290.099496 -398.486884) (xy 290.099915 -398.49607) (xy 290.106423 -398.513255) (xy 290.112196 -398.520412)
			(xy 290.134018 -398.546036) (xy 290.171963 -398.601627) (xy 290.202993 -398.661355) (xy 290.226662 -398.724363)
			(xy 290.242632 -398.789748) (xy 290.250673 -398.856573) (xy 290.250669 -398.923881) (xy 290.242622 -398.990705)
			(xy 290.226646 -399.056089) (xy 290.202971 -399.119095) (xy 290.171936 -399.17882) (xy 290.133985 -399.234407)
			(xy 290.112196 -399.26006) (xy 290.106391 -399.267199) (xy 290.099881 -399.284394) (xy 290.099496 -399.293588)
			(xy 290.099496 -399.451576) (xy 290.099059 -399.461729) (xy 290.09127 -399.480482) (xy 290.076878 -399.494806)
			(xy 290.058089 -399.502506) (xy 290.047934 -399.502884) (xy 289.331654 -399.502884) (xy 289.321527 -399.502412)
			(xy 289.30281 -399.494673) (xy 289.288456 -399.480383) (xy 289.280634 -399.4617) (xy 289.280092 -399.451576)
			(xy 289.280092 -399.293588) (xy 289.279689 -399.2844) (xy 289.273171 -399.267216) (xy 289.267392 -399.26006)
			(xy 289.245638 -399.234379) (xy 289.207685 -399.178798) (xy 289.176647 -399.119079) (xy 289.15297 -399.056078)
			(xy 289.136993 -398.990699) (xy 289.128945 -398.923879) (xy 289.128942 -398.856575) (xy 289.136983 -398.789754)
			(xy 289.152954 -398.724374) (xy 289.176625 -398.66137) (xy 289.207657 -398.601648) (xy 289.245605 -398.546063)
			(xy 289.267392 -398.520412) (xy 289.273208 -398.51328) (xy 289.279711 -398.496079) (xy 289.280092 -398.486884)
			(xy 289.280092 -397.993362) (xy 289.279702 -397.984173) (xy 289.273175 -397.966988) (xy 289.267392 -397.959834)
			(xy 289.245612 -397.934174) (xy 289.20766 -397.87859) (xy 289.176623 -397.818868) (xy 289.152948 -397.755865)
			(xy 289.136972 -397.690483) (xy 289.128927 -397.62366) (xy 289.128926 -397.556355) (xy 288.000733 -397.556355)
			(xy 288.003125 -397.560946) (xy 288.026894 -397.624039) (xy 288.042933 -397.689525) (xy 288.051013 -397.756461)
			(xy 288.051016 -397.823882) (xy 288.042944 -397.890819) (xy 288.026911 -397.956307) (xy 288.003148 -398.019402)
			(xy 287.971999 -398.079197) (xy 287.933912 -398.13483) (xy 287.912048 -398.160494) (xy 287.906265 -398.167649)
			(xy 287.899744 -398.184832) (xy 287.899348 -398.194022) (xy 287.899348 -398.351502) (xy 287.898875 -398.36163)
			(xy 287.891144 -398.380354) (xy 287.876853 -398.39471) (xy 287.858166 -398.402527) (xy 287.84804 -398.403064)
			(xy 287.13176 -398.403064) (xy 287.121599 -398.40271) (xy 287.102839 -398.394895) (xy 287.088515 -398.380477)
			(xy 287.080824 -398.361666) (xy 287.080452 -398.351502) (xy 287.080452 -398.194022) (xy 287.08002 -398.184837)
			(xy 287.07352 -398.167653) (xy 287.067752 -398.160494) (xy 287.045849 -398.13486) (xy 287.007758 -398.079223)
			(xy 286.976606 -398.019423) (xy 286.952842 -397.956321) (xy 286.936807 -397.890828) (xy 286.928734 -397.823885)
			(xy 244.06606 -397.823885) (xy 244.06606 -399.830544) (xy 244.065668 -399.840617) (xy 244.057925 -399.859215)
			(xy 244.051074 -399.866612) (xy 243.052346 -400.865594) (xy 243.044923 -400.872406) (xy 243.026341 -400.880142)
			(xy 243.016278 -400.88058) (xy 238.99114 -400.88058) (xy 238.978794 -400.881097) (xy 238.955921 -400.890396)
			(xy 238.94669 -400.898614) (xy 238.946182 -400.899122) (xy 238.121507 -401.723797) (xy 286.928745 -401.723797)
			(xy 286.928747 -401.65637) (xy 286.936826 -401.58943) (xy 286.952865 -401.523939) (xy 286.976634 -401.460841)
			(xy 287.00779 -401.401044) (xy 287.045885 -401.34541) (xy 287.067752 -401.319746) (xy 287.07356 -401.312609)
			(xy 287.080067 -401.295412) (xy 287.080452 -401.286218) (xy 287.080452 -400.793966) (xy 287.080046 -400.784779)
			(xy 287.073528 -400.767595) (xy 287.067752 -400.760438) (xy 287.045892 -400.734769) (xy 287.0078 -400.679136)
			(xy 286.976646 -400.619341) (xy 286.952879 -400.556244) (xy 286.936842 -400.490755) (xy 286.928764 -400.423817)
			(xy 286.928764 -400.356392) (xy 286.93684 -400.289454) (xy 286.952876 -400.223964) (xy 286.976642 -400.160867)
			(xy 287.007795 -400.101072) (xy 287.045887 -400.045438) (xy 287.067752 -400.019774) (xy 287.073549 -400.012629)
			(xy 287.080062 -399.995438) (xy 287.080452 -399.986246) (xy 287.080452 -399.828766) (xy 287.080899 -399.818636)
			(xy 287.08864 -399.799911) (xy 287.102939 -399.785556) (xy 287.121632 -399.77774) (xy 287.13176 -399.777204)
			(xy 287.84804 -399.777204) (xy 287.858197 -399.777589) (xy 287.876951 -399.785399) (xy 287.891273 -399.799806)
			(xy 287.898971 -399.818606) (xy 287.899348 -399.828766) (xy 287.899348 -399.986246) (xy 287.899796 -399.995429)
			(xy 287.906285 -400.012613) (xy 287.912048 -400.019774) (xy 287.93392 -400.045433) (xy 287.972012 -400.101068)
			(xy 288.003165 -400.160864) (xy 288.026931 -400.223962) (xy 288.042968 -400.289452) (xy 288.051044 -400.356392)
			(xy 288.051043 -400.423817) (xy 288.042966 -400.490757) (xy 288.026928 -400.556247) (xy 288.003161 -400.619344)
			(xy 287.972007 -400.67914) (xy 287.933914 -400.734774) (xy 287.912048 -400.760438) (xy 287.906246 -400.767579)
			(xy 287.899736 -400.784773) (xy 287.899348 -400.793966) (xy 287.899348 -401.286218) (xy 287.899761 -401.295405)
			(xy 287.906274 -401.312588) (xy 287.912048 -401.319746) (xy 287.933892 -401.345428) (xy 287.971985 -401.401059)
			(xy 288.00314 -401.460852) (xy 288.026907 -401.523947) (xy 288.042946 -401.589435) (xy 288.051024 -401.656372)
			(xy 288.051026 -401.723795) (xy 288.042952 -401.790733) (xy 288.026917 -401.856221) (xy 288.003153 -401.919317)
			(xy 287.972002 -401.979113) (xy 287.933912 -402.034746) (xy 287.912048 -402.06041) (xy 287.906258 -402.06756)
			(xy 287.899741 -402.084747) (xy 287.899348 -402.093938) (xy 287.899348 -402.251418) (xy 287.898888 -402.261547)
			(xy 287.891152 -402.280271) (xy 287.876858 -402.294627) (xy 287.858167 -402.302444) (xy 287.84804 -402.30298)
			(xy 287.13176 -402.30298) (xy 287.121601 -402.302611) (xy 287.102844 -402.294798) (xy 287.088521 -402.280385)
			(xy 287.080826 -402.26158) (xy 287.080452 -402.251418) (xy 287.080452 -402.093938) (xy 287.080012 -402.084754)
			(xy 287.073518 -402.06757) (xy 287.067752 -402.06041) (xy 287.045865 -402.034763) (xy 287.007773 -401.979127)
			(xy 286.97662 -401.919329) (xy 286.952855 -401.85623) (xy 286.93682 -401.790738) (xy 286.928745 -401.723797)
			(xy 238.121507 -401.723797) (xy 237.044738 -402.800566) (xy 237.036256 -402.809732) (xy 237.030424 -402.823819)
			(xy 289.128886 -402.823819) (xy 289.12889 -402.756509) (xy 289.13694 -402.689682) (xy 289.15292 -402.624297)
			(xy 289.1766 -402.56129) (xy 289.207642 -402.501565) (xy 289.2456 -402.445979) (xy 289.267392 -402.420328)
			(xy 289.273201 -402.413191) (xy 289.279708 -402.395994) (xy 289.280092 -402.3868) (xy 289.280092 -401.893532)
			(xy 289.279668 -401.884346) (xy 289.273164 -401.867162) (xy 289.267392 -401.860004) (xy 289.245583 -401.834369)
			(xy 289.207631 -401.778781) (xy 289.176596 -401.719056) (xy 289.152922 -401.656049) (xy 289.136949 -401.590664)
			(xy 289.128906 -401.523839) (xy 289.128907 -401.456531) (xy 289.136954 -401.389706) (xy 289.152931 -401.324322)
			(xy 289.176608 -401.261317) (xy 289.207647 -401.201593) (xy 289.245601 -401.146007) (xy 289.267392 -401.120356)
			(xy 289.273189 -401.113211) (xy 289.279704 -401.09602) (xy 289.280092 -401.086828) (xy 289.280092 -400.92884)
			(xy 289.280554 -400.918689) (xy 289.288335 -400.89994) (xy 289.30272 -400.885615) (xy 289.321502 -400.877913)
			(xy 289.331654 -400.877532) (xy 290.047934 -400.877532) (xy 290.058062 -400.877998) (xy 290.076782 -400.885736)
			(xy 290.091137 -400.900028) (xy 290.098957 -400.918714) (xy 290.099496 -400.92884) (xy 290.099496 -401.086828)
			(xy 290.099893 -401.096017) (xy 290.106416 -401.113201) (xy 290.112196 -401.120356) (xy 290.133963 -401.146025)
			(xy 290.17191 -401.20161) (xy 290.202942 -401.261331) (xy 290.226615 -401.324334) (xy 290.242588 -401.389713)
			(xy 290.250633 -401.456534) (xy 290.250635 -401.523836) (xy 290.242593 -401.590657) (xy 290.226624 -401.656038)
			(xy 290.202955 -401.719041) (xy 290.200515 -401.723737) (xy 291.329064 -401.723737) (xy 291.329066 -401.65643)
			(xy 291.337113 -401.589606) (xy 291.353088 -401.524222) (xy 291.376763 -401.461217) (xy 291.407799 -401.401493)
			(xy 291.445751 -401.345906) (xy 291.46754 -401.320254) (xy 291.473344 -401.313114) (xy 291.479853 -401.295919)
			(xy 291.48024 -401.286726) (xy 291.48024 -400.793458) (xy 291.479841 -400.78427) (xy 291.473319 -400.767086)
			(xy 291.46754 -400.75993) (xy 291.445758 -400.734273) (xy 291.407809 -400.678687) (xy 291.376776 -400.618964)
			(xy 291.353103 -400.55596) (xy 291.337129 -400.490579) (xy 291.329085 -400.423757) (xy 291.329084 -400.356452)
			(xy 291.337128 -400.28963) (xy 291.3531 -400.224248) (xy 291.376772 -400.161244) (xy 291.407805 -400.101521)
			(xy 291.445753 -400.045934) (xy 291.46754 -400.020282) (xy 291.473332 -400.013134) (xy 291.479848 -399.995945)
			(xy 291.48024 -399.986754) (xy 291.48024 -399.828766) (xy 291.480706 -399.818606) (xy 291.488492 -399.799835)
			(xy 291.502866 -399.785471) (xy 291.521641 -399.777698) (xy 291.531802 -399.777204) (xy 292.248082 -399.777204)
			(xy 292.258234 -399.777747) (xy 292.276997 -399.785509) (xy 292.291361 -399.79986) (xy 292.299143 -399.818614)
			(xy 292.299644 -399.828766) (xy 292.299644 -399.986754) (xy 292.300089 -399.995937) (xy 292.30658 -400.013121)
			(xy 292.312344 -400.020282) (xy 292.334138 -400.045929) (xy 292.372088 -400.101516) (xy 292.403122 -400.16124)
			(xy 292.426795 -400.224245) (xy 292.442768 -400.289628) (xy 292.450812 -400.356452) (xy 292.450811 -400.423757)
			(xy 292.442766 -400.490581) (xy 292.426792 -400.555963) (xy 292.403118 -400.618968) (xy 292.372083 -400.678692)
			(xy 292.334132 -400.734278) (xy 292.312344 -400.75993) (xy 292.306545 -400.767073) (xy 292.300033 -400.784266)
			(xy 292.299644 -400.793458) (xy 292.299644 -401.286726) (xy 292.300054 -401.295913) (xy 292.306569 -401.313097)
			(xy 292.312344 -401.320254) (xy 292.33411 -401.345924) (xy 292.372061 -401.401507) (xy 292.403096 -401.461228)
			(xy 292.426771 -401.524231) (xy 292.442746 -401.589611) (xy 292.450792 -401.656432) (xy 292.450794 -401.723735)
			(xy 292.442752 -401.790557) (xy 292.426781 -401.855938) (xy 292.40311 -401.918941) (xy 292.372078 -401.978664)
			(xy 292.334131 -402.03425) (xy 292.312344 -402.059902) (xy 292.306557 -402.067054) (xy 292.300038 -402.084239)
			(xy 292.299644 -402.09343) (xy 292.299644 -402.251418) (xy 292.299181 -402.261579) (xy 292.291397 -402.280352)
			(xy 292.277022 -402.294718) (xy 292.258244 -402.302488) (xy 292.248082 -402.30298) (xy 291.531802 -402.30298)
			(xy 291.521647 -402.302465) (xy 291.502881 -402.294695) (xy 291.488516 -402.280336) (xy 291.480739 -402.261573)
			(xy 291.48024 -402.251418) (xy 291.48024 -402.09343) (xy 291.479806 -402.084246) (xy 291.473308 -402.067061)
			(xy 291.46754 -402.059902) (xy 291.44573 -402.034268) (xy 291.407782 -401.978679) (xy 291.37675 -401.918953)
			(xy 291.353078 -401.855946) (xy 291.337107 -401.790561) (xy 291.329064 -401.723737) (xy 290.200515 -401.723737)
			(xy 290.171926 -401.778764) (xy 290.133981 -401.834351) (xy 290.112196 -401.860004) (xy 290.106415 -401.86716)
			(xy 290.099891 -401.884342) (xy 290.099496 -401.893532) (xy 290.099496 -402.3868) (xy 290.099907 -402.395987)
			(xy 290.10642 -402.413171) (xy 290.112196 -402.420328) (xy 290.133935 -402.44602) (xy 290.171883 -402.501601)
			(xy 290.202916 -402.56132) (xy 290.22659 -402.624319) (xy 290.242566 -402.689696) (xy 290.250613 -402.756514)
			(xy 290.250617 -402.823814) (xy 290.250609 -402.823878) (xy 293.528678 -402.823878) (xy 293.528683 -402.75645)
			(xy 293.536763 -402.689509) (xy 293.552803 -402.624017) (xy 293.576572 -402.560919) (xy 293.607728 -402.501121)
			(xy 293.645822 -402.445485) (xy 293.667688 -402.41982) (xy 293.6735 -402.412685) (xy 293.680006 -402.395487)
			(xy 293.680388 -402.386292) (xy 293.680388 -401.89404) (xy 293.679961 -401.884854) (xy 293.67346 -401.86767)
			(xy 293.667688 -401.860512) (xy 293.645805 -401.834863) (xy 293.607717 -401.779226) (xy 293.576568 -401.719427)
			(xy 293.552806 -401.656328) (xy 293.536772 -401.590837) (xy 293.528698 -401.523897) (xy 293.5287 -401.456472)
			(xy 293.536777 -401.389533) (xy 293.552815 -401.324043) (xy 293.576581 -401.260945) (xy 293.607733 -401.201149)
			(xy 293.645823 -401.145513) (xy 293.667688 -401.119848) (xy 293.673488 -401.112705) (xy 293.680001 -401.095513)
			(xy 293.680388 -401.08632) (xy 293.680388 -400.92884) (xy 293.680849 -400.918722) (xy 293.688581 -400.900021)
			(xy 293.702884 -400.885706) (xy 293.721578 -400.877957) (xy 293.731696 -400.877532) (xy 294.447976 -400.877532)
			(xy 294.458101 -400.877936) (xy 294.47681 -400.885682) (xy 294.491127 -400.900003) (xy 294.498867 -400.918715)
			(xy 294.499284 -400.92884) (xy 294.499284 -401.08632) (xy 294.499688 -401.095508) (xy 294.506206 -401.112692)
			(xy 294.511984 -401.119848) (xy 294.533829 -401.145529) (xy 294.571919 -401.201161) (xy 294.603072 -401.260955)
			(xy 294.626838 -401.32405) (xy 294.642875 -401.389537) (xy 294.650953 -401.456474) (xy 294.650955 -401.523896)
			(xy 294.64288 -401.590833) (xy 294.626847 -401.656322) (xy 294.603084 -401.719418) (xy 294.600803 -401.723797)
			(xy 295.728833 -401.723797) (xy 295.728835 -401.65637) (xy 295.736913 -401.58943) (xy 295.752952 -401.523939)
			(xy 295.77672 -401.460841) (xy 295.807876 -401.401045) (xy 295.845969 -401.345411) (xy 295.867836 -401.319746)
			(xy 295.873643 -401.312608) (xy 295.88015 -401.295412) (xy 295.880536 -401.286218) (xy 295.880536 -400.793966)
			(xy 295.880134 -400.784778) (xy 295.873614 -400.767594) (xy 295.867836 -400.760438) (xy 295.845977 -400.734769)
			(xy 295.807885 -400.679135) (xy 295.776732 -400.61934) (xy 295.752966 -400.556244) (xy 295.736929 -400.490755)
			(xy 295.728852 -400.423816) (xy 295.728852 -400.356393) (xy 295.736928 -400.289454) (xy 295.752964 -400.223965)
			(xy 295.776729 -400.160868) (xy 295.807881 -400.101072) (xy 295.845971 -400.045439) (xy 295.867836 -400.019774)
			(xy 295.873631 -400.012628) (xy 295.880146 -399.995438) (xy 295.880536 -399.986246) (xy 295.880536 -399.828766)
			(xy 295.880999 -399.818638) (xy 295.888737 -399.799916) (xy 295.90303 -399.785561) (xy 295.921718 -399.777743)
			(xy 295.931844 -399.777204) (xy 296.648124 -399.777204) (xy 296.65828 -399.777602) (xy 296.677034 -399.785406)
			(xy 296.691357 -399.79981) (xy 296.699055 -399.818608) (xy 296.699432 -399.828766) (xy 296.699432 -399.986246)
			(xy 296.699883 -399.995429) (xy 296.70637 -400.012613) (xy 296.712132 -400.019774) (xy 296.734001 -400.045435)
			(xy 296.772087 -400.101071) (xy 296.803236 -400.160868) (xy 296.826998 -400.223965) (xy 296.843032 -400.289455)
			(xy 296.851107 -400.356393) (xy 296.851107 -400.423816) (xy 296.843031 -400.490754) (xy 296.826996 -400.556243)
			(xy 296.803232 -400.61934) (xy 296.772083 -400.679137) (xy 296.733995 -400.734772) (xy 296.712132 -400.760438)
			(xy 296.706329 -400.767578) (xy 296.69982 -400.784773) (xy 296.699432 -400.793966) (xy 296.699432 -401.286218)
			(xy 296.699849 -401.295404) (xy 296.70636 -401.312588) (xy 296.712132 -401.319746) (xy 296.733973 -401.34543)
			(xy 296.77206 -401.401062) (xy 296.80321 -401.460856) (xy 296.826974 -401.523951) (xy 296.84301 -401.589437)
			(xy 296.851088 -401.656373) (xy 296.85109 -401.723794) (xy 296.843016 -401.79073) (xy 296.826984 -401.856218)
			(xy 296.803224 -401.919314) (xy 296.772078 -401.979109) (xy 296.733994 -402.034744) (xy 296.712132 -402.06041)
			(xy 296.70634 -402.067558) (xy 296.699825 -402.084747) (xy 296.699432 -402.093938) (xy 296.699432 -402.251418)
			(xy 296.698988 -402.261549) (xy 296.691249 -402.280276) (xy 296.676949 -402.294633) (xy 296.658253 -402.302447)
			(xy 296.648124 -402.30298) (xy 295.931844 -402.30298) (xy 295.92169 -402.302542) (xy 295.902935 -402.294757)
			(xy 295.888609 -402.280365) (xy 295.880912 -402.261574) (xy 295.880536 -402.251418) (xy 295.880536 -402.093938)
			(xy 295.880099 -402.084754) (xy 295.873603 -402.06757) (xy 295.867836 -402.06041) (xy 295.845949 -402.034763)
			(xy 295.807859 -401.979127) (xy 295.776707 -401.919328) (xy 295.752942 -401.856229) (xy 295.736907 -401.790737)
			(xy 295.728833 -401.723797) (xy 294.600803 -401.723797) (xy 294.571935 -401.779213) (xy 294.533847 -401.834847)
			(xy 294.511984 -401.860512) (xy 294.506198 -401.867665) (xy 294.499678 -401.88485) (xy 294.499284 -401.89404)
			(xy 294.499284 -402.386292) (xy 294.499702 -402.395478) (xy 294.506211 -402.412662) (xy 294.511984 -402.41982)
			(xy 294.533801 -402.445524) (xy 294.571893 -402.501152) (xy 294.603046 -402.560943) (xy 294.626814 -402.624035)
			(xy 294.642853 -402.68952) (xy 294.650933 -402.756454) (xy 294.650937 -402.823819) (xy 297.928973 -402.823819)
			(xy 297.928978 -402.756509) (xy 297.937027 -402.689683) (xy 297.953006 -402.624297) (xy 297.976686 -402.561291)
			(xy 298.007727 -402.501566) (xy 298.045684 -402.445979) (xy 298.067476 -402.420328) (xy 298.073283 -402.41319)
			(xy 298.079792 -402.395994) (xy 298.080176 -402.3868) (xy 298.080176 -401.893532) (xy 298.079756 -401.884346)
			(xy 298.07325 -401.867161) (xy 298.067476 -401.860004) (xy 298.045668 -401.834368) (xy 298.007717 -401.77878)
			(xy 297.976683 -401.719055) (xy 297.953009 -401.656048) (xy 297.937037 -401.590664) (xy 297.928993 -401.523839)
			(xy 297.928995 -401.456531) (xy 297.937042 -401.389707) (xy 297.953018 -401.324323) (xy 297.976695 -401.261318)
			(xy 298.007732 -401.201594) (xy 298.045686 -401.146008) (xy 298.067476 -401.120356) (xy 298.073271 -401.113209)
			(xy 298.079787 -401.09602) (xy 298.080176 -401.086828) (xy 298.080176 -400.92884) (xy 298.080654 -400.918691)
			(xy 298.088432 -400.899945) (xy 298.102811 -400.885621) (xy 298.121588 -400.877915) (xy 298.131738 -400.877532)
			(xy 298.848018 -400.877532) (xy 298.858145 -400.878011) (xy 298.876865 -400.885744) (xy 298.89122 -400.900032)
			(xy 298.89904 -400.918716) (xy 298.89958 -400.92884) (xy 298.89958 -401.086828) (xy 298.899981 -401.096016)
			(xy 298.906502 -401.1132) (xy 298.91228 -401.120356) (xy 298.934048 -401.146024) (xy 298.971996 -401.201609)
			(xy 299.003029 -401.261331) (xy 299.026702 -401.324333) (xy 299.042676 -401.389713) (xy 299.050721 -401.456533)
			(xy 299.050723 -401.523837) (xy 299.042681 -401.590657) (xy 299.026711 -401.656038) (xy 299.003041 -401.719042)
			(xy 299.000571 -401.723796) (xy 300.128624 -401.723796) (xy 300.128626 -401.656371) (xy 300.136704 -401.58943)
			(xy 300.152743 -401.52394) (xy 300.17651 -401.460842) (xy 300.207665 -401.401045) (xy 300.245758 -401.345411)
			(xy 300.267624 -401.319746) (xy 300.273429 -401.312607) (xy 300.279938 -401.295412) (xy 300.280324 -401.286218)
			(xy 300.280324 -400.793966) (xy 300.279925 -400.784778) (xy 300.273403 -400.767594) (xy 300.267624 -400.760438)
			(xy 300.245765 -400.734768) (xy 300.207675 -400.679135) (xy 300.176522 -400.61934) (xy 300.152757 -400.556243)
			(xy 300.13672 -400.490755) (xy 300.128643 -400.423816) (xy 300.128643 -400.356393) (xy 300.136719 -400.289454)
			(xy 300.152754 -400.223965) (xy 300.176519 -400.160869) (xy 300.20767 -400.101073) (xy 300.24576 -400.045439)
			(xy 300.267624 -400.019774) (xy 300.273417 -400.012626) (xy 300.279933 -399.995438) (xy 300.280324 -399.986246)
			(xy 300.280324 -399.828766) (xy 300.280798 -399.818639) (xy 300.288534 -399.79992) (xy 300.302824 -399.785566)
			(xy 300.321507 -399.777745) (xy 300.331632 -399.777204) (xy 301.047912 -399.777204) (xy 301.058067 -399.777612)
			(xy 301.076821 -399.785412) (xy 301.091144 -399.799813) (xy 301.098843 -399.818608) (xy 301.09922 -399.828766)
			(xy 301.09922 -399.986246) (xy 301.099652 -399.995431) (xy 301.10615 -400.012616) (xy 301.11192 -400.019774)
			(xy 301.133789 -400.045435) (xy 301.171876 -400.10107) (xy 301.203026 -400.160867) (xy 301.226789 -400.223965)
			(xy 301.242823 -400.289454) (xy 301.250898 -400.356393) (xy 301.250898 -400.423816) (xy 301.242821 -400.490755)
			(xy 301.226786 -400.556244) (xy 301.203022 -400.619341) (xy 301.171872 -400.679137) (xy 301.133784 -400.734772)
			(xy 301.11192 -400.760438) (xy 301.106127 -400.767586) (xy 301.09961 -400.784774) (xy 301.09922 -400.793966)
			(xy 301.09922 -401.286218) (xy 301.099617 -401.295407) (xy 301.106139 -401.312591) (xy 301.11192 -401.319746)
			(xy 301.133762 -401.345429) (xy 301.17185 -401.401062) (xy 301.203 -401.460856) (xy 301.226765 -401.52395)
			(xy 301.242801 -401.589437) (xy 301.250878 -401.656373) (xy 301.25088 -401.723794) (xy 301.242807 -401.790731)
			(xy 301.226775 -401.856218) (xy 301.203014 -401.919314) (xy 301.171867 -401.97911) (xy 301.133782 -402.034744)
			(xy 301.11192 -402.06041) (xy 301.106139 -402.067566) (xy 301.099614 -402.084748) (xy 301.09922 -402.093938)
			(xy 301.09922 -402.251418) (xy 301.098787 -402.261551) (xy 301.091046 -402.28028) (xy 301.076743 -402.294637)
			(xy 301.058043 -402.302449) (xy 301.047912 -402.30298) (xy 300.331632 -402.30298) (xy 300.321477 -402.302552)
			(xy 300.302722 -402.294763) (xy 300.288396 -402.280368) (xy 300.280699 -402.261575) (xy 300.280324 -402.251418)
			(xy 300.280324 -402.093938) (xy 300.27989 -402.084753) (xy 300.273392 -402.067569) (xy 300.267624 -402.06041)
			(xy 300.245738 -402.034763) (xy 300.207648 -401.979126) (xy 300.176497 -401.919328) (xy 300.152733 -401.856229)
			(xy 300.136698 -401.790737) (xy 300.128624 -401.723796) (xy 299.000571 -401.723796) (xy 298.972011 -401.778765)
			(xy 298.934066 -401.834352) (xy 298.91228 -401.860004) (xy 298.906497 -401.867159) (xy 298.899975 -401.884342)
			(xy 298.89958 -401.893532) (xy 298.89958 -402.3868) (xy 298.899994 -402.395987) (xy 298.906505 -402.413171)
			(xy 298.91228 -402.420328) (xy 298.93402 -402.446019) (xy 298.971969 -402.501601) (xy 299.003003 -402.561319)
			(xy 299.026678 -402.624318) (xy 299.042653 -402.689696) (xy 299.050701 -402.756513) (xy 299.050705 -402.823814)
			(xy 299.050697 -402.823877) (xy 302.328766 -402.823877) (xy 302.328771 -402.75645) (xy 302.336851 -402.689509)
			(xy 302.35289 -402.624018) (xy 302.376659 -402.560919) (xy 302.407814 -402.501122) (xy 302.445906 -402.445486)
			(xy 302.467772 -402.41982) (xy 302.473594 -402.412693) (xy 302.480091 -402.395488) (xy 302.480472 -402.386292)
			(xy 302.480472 -401.89404) (xy 302.480049 -401.884854) (xy 302.473545 -401.867669) (xy 302.467772 -401.860512)
			(xy 302.445889 -401.834863) (xy 302.407803 -401.779225) (xy 302.376655 -401.719426) (xy 302.352893 -401.656328)
			(xy 302.33686 -401.590837) (xy 302.328786 -401.523897) (xy 302.328788 -401.456473) (xy 302.336865 -401.389534)
			(xy 302.352902 -401.324044) (xy 302.376667 -401.260946) (xy 302.407819 -401.201149) (xy 302.445908 -401.145514)
			(xy 302.467772 -401.119848) (xy 302.473582 -401.112713) (xy 302.480087 -401.095514) (xy 302.480472 -401.08632)
			(xy 302.480472 -400.92884) (xy 302.480948 -400.918724) (xy 302.488678 -400.900026) (xy 302.502976 -400.885712)
			(xy 302.521664 -400.87796) (xy 302.53178 -400.877532) (xy 303.24806 -400.877532) (xy 303.258184 -400.87795)
			(xy 303.276893 -400.885691) (xy 303.291209 -400.900007) (xy 303.29895 -400.918716) (xy 303.299368 -400.92884)
			(xy 303.299368 -401.08632) (xy 303.299776 -401.095507) (xy 303.306292 -401.112691) (xy 303.312068 -401.119848)
			(xy 303.333913 -401.145529) (xy 303.372005 -401.20116) (xy 303.403158 -401.260954) (xy 303.426925 -401.324049)
			(xy 303.442963 -401.389537) (xy 303.451041 -401.456474) (xy 303.451043 -401.523896) (xy 303.442968 -401.590834)
			(xy 303.426934 -401.656322) (xy 303.40317 -401.719418) (xy 303.37202 -401.779214) (xy 303.333932 -401.834847)
			(xy 303.312068 -401.860512) (xy 303.30628 -401.867663) (xy 303.299761 -401.884849) (xy 303.299368 -401.89404)
			(xy 303.299368 -402.386292) (xy 303.299789 -402.395478) (xy 303.306296 -402.412662) (xy 303.312068 -402.41982)
			(xy 303.333886 -402.445524) (xy 303.371978 -402.501152) (xy 303.403133 -402.560942) (xy 303.426901 -402.624034)
			(xy 303.442941 -402.689519) (xy 303.451021 -402.756454) (xy 303.451025 -402.823874) (xy 303.442954 -402.89081)
			(xy 303.426922 -402.956297) (xy 303.403162 -403.019392) (xy 303.372015 -403.079186) (xy 303.33393 -403.134819)
			(xy 303.312068 -403.160484) (xy 303.306249 -403.167613) (xy 303.299749 -403.184816) (xy 303.299368 -403.194012)
			(xy 303.299368 -403.351492) (xy 303.298977 -403.361618) (xy 303.291225 -403.380328) (xy 303.276901 -403.394643)
			(xy 303.258186 -403.402383) (xy 303.24806 -403.4028) (xy 302.53178 -403.4028) (xy 302.52167 -403.402331)
			(xy 302.502991 -403.394587) (xy 302.488697 -403.380285) (xy 302.480963 -403.361602) (xy 302.480472 -403.351492)
			(xy 302.480472 -403.194012) (xy 302.480062 -403.184825) (xy 302.473549 -403.16764) (xy 302.467772 -403.160484)
			(xy 302.445862 -403.134857) (xy 302.407776 -403.079216) (xy 302.376629 -403.019415) (xy 302.352869 -402.956313)
			(xy 302.336838 -402.890819) (xy 302.328766 -402.823877) (xy 299.050697 -402.823877) (xy 299.042666 -402.890633)
			(xy 299.026699 -402.956013) (xy 299.003032 -403.019015) (xy 298.972006 -403.078737) (xy 298.934064 -403.134323)
			(xy 298.91228 -403.159976) (xy 298.906466 -403.167109) (xy 298.899963 -403.184309) (xy 298.89958 -403.193504)
			(xy 298.89958 -403.351492) (xy 298.899171 -403.361648) (xy 298.891375 -403.380404) (xy 298.876974 -403.394729)
			(xy 298.858176 -403.402425) (xy 298.848018 -403.4028) (xy 298.131738 -403.4028) (xy 298.121619 -403.402243)
			(xy 298.102906 -403.394535) (xy 298.08855 -403.380271) (xy 298.080722 -403.361608) (xy 298.080176 -403.351492)
			(xy 298.080176 -403.193504) (xy 298.079769 -403.184316) (xy 298.073254 -403.167132) (xy 298.067476 -403.159976)
			(xy 298.04564 -403.134363) (xy 298.00769 -403.078772) (xy 297.976657 -403.019043) (xy 297.952985 -402.956034)
			(xy 297.937014 -402.890646) (xy 297.928973 -402.823819) (xy 294.650937 -402.823819) (xy 294.650937 -402.823874)
			(xy 294.642866 -402.890809) (xy 294.626835 -402.956296) (xy 294.603076 -403.019391) (xy 294.57193 -403.079186)
			(xy 294.533846 -403.134819) (xy 294.511984 -403.160484) (xy 294.506167 -403.167615) (xy 294.499665 -403.184816)
			(xy 294.499284 -403.194012) (xy 294.499284 -403.351492) (xy 294.498877 -403.361616) (xy 294.491129 -403.380322)
			(xy 294.476809 -403.394638) (xy 294.4581 -403.40238) (xy 294.447976 -403.4028) (xy 293.731696 -403.4028)
			(xy 293.721573 -403.402387) (xy 293.70287 -403.394638) (xy 293.688556 -403.38032) (xy 293.68081 -403.361615)
			(xy 293.680388 -403.351492) (xy 293.680388 -403.194012) (xy 293.679975 -403.184825) (xy 293.673464 -403.167641)
			(xy 293.667688 -403.160484) (xy 293.645777 -403.134857) (xy 293.607691 -403.079217) (xy 293.576543 -403.019415)
			(xy 293.552782 -402.956314) (xy 293.53675 -402.89082) (xy 293.528678 -402.823878) (xy 290.250609 -402.823878)
			(xy 290.242579 -402.890633) (xy 290.226612 -402.956012) (xy 290.202946 -403.019014) (xy 290.17192 -403.078737)
			(xy 290.133979 -403.134323) (xy 290.112196 -403.159976) (xy 290.106384 -403.16711) (xy 290.099879 -403.184309)
			(xy 290.099496 -403.193504) (xy 290.099496 -403.351492) (xy 290.099072 -403.361646) (xy 290.091278 -403.380399)
			(xy 290.076882 -403.394723) (xy 290.05809 -403.402422) (xy 290.047934 -403.4028) (xy 289.331654 -403.4028)
			(xy 289.321529 -403.402312) (xy 289.302815 -403.394577) (xy 289.288461 -403.380292) (xy 289.280637 -403.361614)
			(xy 289.280092 -403.351492) (xy 289.280092 -403.193504) (xy 289.279682 -403.184317) (xy 289.273168 -403.167132)
			(xy 289.267392 -403.159976) (xy 289.245556 -403.134363) (xy 289.207605 -403.078772) (xy 289.176571 -403.019044)
			(xy 289.152898 -402.956034) (xy 289.136927 -402.890647) (xy 289.128886 -402.823819) (xy 237.030424 -402.823819)
			(xy 237.026709 -402.832791) (xy 237.026196 -402.84527) (xy 237.026196 -405.623708) (xy 286.928756 -405.623708)
			(xy 286.928757 -405.556283) (xy 286.936834 -405.489343) (xy 286.952872 -405.423853) (xy 286.976639 -405.360756)
			(xy 287.007793 -405.30096) (xy 287.045886 -405.245326) (xy 287.067752 -405.219662) (xy 287.073554 -405.212521)
			(xy 287.080064 -405.195327) (xy 287.080452 -405.186134) (xy 287.080452 -404.693882) (xy 287.080039 -404.684695)
			(xy 287.073526 -404.667512) (xy 287.067752 -404.660354) (xy 287.045908 -404.634672) (xy 287.007815 -404.579041)
			(xy 286.97666 -404.519248) (xy 286.952893 -404.456153) (xy 286.936854 -404.390665) (xy 286.928776 -404.323728)
			(xy 286.928774 -404.256305) (xy 286.936848 -404.189367) (xy 286.952883 -404.123879) (xy 286.976647 -404.060783)
			(xy 287.007798 -404.000987) (xy 287.045888 -403.945354) (xy 287.067752 -403.91969) (xy 287.073542 -403.91254)
			(xy 287.080059 -403.895353) (xy 287.080452 -403.886162) (xy 287.080452 -403.728682) (xy 287.080912 -403.718553)
			(xy 287.088648 -403.699829) (xy 287.102942 -403.685473) (xy 287.121633 -403.677656) (xy 287.13176 -403.67712)
			(xy 287.84804 -403.67712) (xy 287.858199 -403.677489) (xy 287.876956 -403.685302) (xy 287.891279 -403.699715)
			(xy 287.898974 -403.71852) (xy 287.899348 -403.728682) (xy 287.899348 -403.886162) (xy 287.899788 -403.895346)
			(xy 287.906282 -403.91253) (xy 287.912048 -403.91969) (xy 287.933935 -403.945337) (xy 287.972027 -404.000973)
			(xy 288.00318 -404.060771) (xy 288.026945 -404.12387) (xy 288.04298 -404.189362) (xy 288.051055 -404.256303)
			(xy 288.051053 -404.32373) (xy 288.042974 -404.39067) (xy 288.026935 -404.456161) (xy 288.003166 -404.519259)
			(xy 287.97201 -404.579056) (xy 287.933915 -404.63469) (xy 287.912048 -404.660354) (xy 287.90624 -404.667491)
			(xy 287.899733 -404.684688) (xy 287.899348 -404.693882) (xy 287.899348 -405.186134) (xy 287.899754 -405.195321)
			(xy 287.906272 -405.212505) (xy 287.912048 -405.219662) (xy 287.933908 -405.245331) (xy 287.972 -405.300964)
			(xy 288.003154 -405.360759) (xy 288.026921 -405.423856) (xy 288.042958 -405.489345) (xy 288.051036 -405.556283)
			(xy 288.051036 -405.623708) (xy 288.04296 -405.690646) (xy 288.026924 -405.756136) (xy 288.003158 -405.819233)
			(xy 287.972005 -405.879028) (xy 287.933913 -405.934662) (xy 287.912048 -405.960326) (xy 287.906251 -405.967471)
			(xy 287.899738 -405.984662) (xy 287.899348 -405.993854) (xy 287.899348 -406.151334) (xy 287.898901 -406.161464)
			(xy 287.89116 -406.180189) (xy 287.876861 -406.194544) (xy 287.858168 -406.20236) (xy 287.84804 -406.202896)
			(xy 287.13176 -406.202896) (xy 287.121603 -406.202511) (xy 287.102849 -406.194701) (xy 287.088527 -406.180294)
			(xy 287.080829 -406.161494) (xy 287.080452 -406.151334) (xy 287.080452 -405.993854) (xy 287.080004 -405.984671)
			(xy 287.073515 -405.967487) (xy 287.067752 -405.960326) (xy 287.04588 -405.934667) (xy 287.007788 -405.879032)
			(xy 286.976635 -405.819236) (xy 286.952869 -405.756138) (xy 286.936832 -405.690648) (xy 286.928756 -405.623708)
			(xy 237.026196 -405.623708) (xy 237.026196 -406.72373) (xy 289.128897 -406.72373) (xy 289.1289 -406.656422)
			(xy 289.136948 -406.589596) (xy 289.152926 -406.524211) (xy 289.176605 -406.461205) (xy 289.207645 -406.401481)
			(xy 289.245601 -406.345895) (xy 289.267392 -406.320244) (xy 289.273194 -406.313103) (xy 289.279706 -406.295909)
			(xy 289.280092 -406.286716) (xy 289.280092 -405.793448) (xy 289.279661 -405.784263) (xy 289.273162 -405.767078)
			(xy 289.267392 -405.75992) (xy 289.245599 -405.734272) (xy 289.207647 -405.678686) (xy 289.176611 -405.618962)
			(xy 289.152936 -405.555957) (xy 289.136961 -405.490574) (xy 289.128917 -405.42375) (xy 289.128917 -405.356444)
			(xy 289.136962 -405.28962) (xy 289.152937 -405.224237) (xy 289.176613 -405.161232) (xy 289.20765 -405.101509)
			(xy 289.245602 -405.045923) (xy 289.267392 -405.020272) (xy 289.273182 -405.013122) (xy 289.279701 -404.995935)
			(xy 289.280092 -404.986744) (xy 289.280092 -404.828756) (xy 289.280486 -404.8186) (xy 289.288294 -404.799848)
			(xy 289.302699 -404.785527) (xy 289.321496 -404.777827) (xy 289.331654 -404.777448) (xy 290.047934 -404.777448)
			(xy 290.058064 -404.777899) (xy 290.076787 -404.785639) (xy 290.091143 -404.799936) (xy 290.098959 -404.818628)
			(xy 290.099496 -404.828756) (xy 290.099496 -404.986744) (xy 290.099886 -404.995933) (xy 290.106414 -405.013117)
			(xy 290.112196 -405.020272) (xy 290.133979 -405.045928) (xy 290.171925 -405.101515) (xy 290.202957 -405.161238)
			(xy 290.226628 -405.224242) (xy 290.242601 -405.289623) (xy 290.250644 -405.356445) (xy 290.250645 -405.423749)
			(xy 290.242602 -405.490571) (xy 290.22663 -405.555952) (xy 290.202959 -405.618957) (xy 290.200522 -405.623648)
			(xy 291.329076 -405.623648) (xy 291.329076 -405.556343) (xy 291.337121 -405.48952) (xy 291.353095 -405.424137)
			(xy 291.376768 -405.361132) (xy 291.407802 -405.301409) (xy 291.445752 -405.245822) (xy 291.46754 -405.22017)
			(xy 291.473337 -405.213025) (xy 291.47985 -405.195834) (xy 291.48024 -405.186642) (xy 291.48024 -404.693374)
			(xy 291.479833 -404.684187) (xy 291.473316 -404.667003) (xy 291.46754 -404.659846) (xy 291.445774 -404.634176)
			(xy 291.407825 -404.578592) (xy 291.37679 -404.518871) (xy 291.353116 -404.455869) (xy 291.337142 -404.390489)
			(xy 291.329096 -404.323668) (xy 291.329094 -404.256365) (xy 291.337136 -404.189544) (xy 291.353106 -404.124163)
			(xy 291.376777 -404.061159) (xy 291.407808 -404.001436) (xy 291.445754 -403.94585) (xy 291.46754 -403.920198)
			(xy 291.473325 -403.913045) (xy 291.479846 -403.89586) (xy 291.48024 -403.88667) (xy 291.48024 -403.728682)
			(xy 291.480718 -403.718523) (xy 291.488499 -403.699753) (xy 291.50287 -403.685388) (xy 291.521643 -403.677615)
			(xy 291.531802 -403.67712) (xy 292.248082 -403.67712) (xy 292.258236 -403.677648) (xy 292.277002 -403.685413)
			(xy 292.291367 -403.699768) (xy 292.299145 -403.718528) (xy 292.299644 -403.728682) (xy 292.299644 -403.88667)
			(xy 292.300081 -403.895854) (xy 292.306577 -403.913038) (xy 292.312344 -403.920198) (xy 292.334154 -403.945832)
			(xy 292.372103 -404.001421) (xy 292.403137 -404.061147) (xy 292.426809 -404.124153) (xy 292.442781 -404.189538)
			(xy 292.450824 -404.256363) (xy 292.450822 -404.32367) (xy 292.442775 -404.390495) (xy 292.426799 -404.455878)
			(xy 292.403123 -404.518884) (xy 292.372086 -404.578608) (xy 292.334134 -404.634194) (xy 292.312344 -404.659846)
			(xy 292.306539 -404.666985) (xy 292.300031 -404.68418) (xy 292.299644 -404.693374) (xy 292.299644 -405.186642)
			(xy 292.300047 -405.19583) (xy 292.306567 -405.213013) (xy 292.312344 -405.22017) (xy 292.334126 -405.245827)
			(xy 292.372076 -405.301412) (xy 292.403111 -405.361135) (xy 292.426785 -405.424139) (xy 292.442758 -405.489521)
			(xy 292.450803 -405.556343) (xy 292.450804 -405.623648) (xy 292.44276 -405.69047) (xy 292.426787 -405.755852)
			(xy 292.403114 -405.818857) (xy 292.372081 -405.87858) (xy 292.334132 -405.934166) (xy 292.312344 -405.959818)
			(xy 292.30655 -405.966965) (xy 292.300035 -405.984154) (xy 292.299644 -405.993346) (xy 292.299644 -406.151334)
			(xy 292.299194 -406.161496) (xy 292.291405 -406.18027) (xy 292.277026 -406.194634) (xy 292.258245 -406.202404)
			(xy 292.248082 -406.202896) (xy 291.531802 -406.202896) (xy 291.521649 -406.202366) (xy 291.502886 -406.194598)
			(xy 291.488522 -406.180244) (xy 291.480741 -406.161487) (xy 291.48024 -406.151334) (xy 291.48024 -405.993346)
			(xy 291.479799 -405.984162) (xy 291.473306 -405.966978) (xy 291.46754 -405.959818) (xy 291.445746 -405.934171)
			(xy 291.407797 -405.878584) (xy 291.376764 -405.818859) (xy 291.353092 -405.755854) (xy 291.337119 -405.690471)
			(xy 291.329076 -405.623648) (xy 290.200522 -405.623648) (xy 290.171928 -405.67868) (xy 290.133982 -405.734267)
			(xy 290.112196 -405.75992) (xy 290.106408 -405.767071) (xy 290.099888 -405.784257) (xy 290.099496 -405.793448)
			(xy 290.099496 -406.286716) (xy 290.099899 -406.295904) (xy 290.106418 -406.313088) (xy 290.112196 -406.320244)
			(xy 290.133951 -406.345922) (xy 290.171899 -406.401506) (xy 290.202931 -406.461226) (xy 290.226605 -406.524227)
			(xy 290.242579 -406.589606) (xy 290.250625 -406.656425) (xy 290.250628 -406.723727) (xy 290.250621 -406.723789)
			(xy 293.52869 -406.723789) (xy 293.528692 -406.656363) (xy 293.536771 -406.589423) (xy 293.55281 -406.523932)
			(xy 293.576577 -406.460834) (xy 293.607731 -406.401037) (xy 293.645823 -406.345401) (xy 293.667688 -406.319736)
			(xy 293.673493 -406.312597) (xy 293.680003 -406.295402) (xy 293.680388 -406.286208) (xy 293.680388 -405.793956)
			(xy 293.680002 -405.784766) (xy 293.673472 -405.767582) (xy 293.667688 -405.760428) (xy 293.645821 -405.734766)
			(xy 293.607733 -405.679131) (xy 293.576583 -405.619334) (xy 293.552819 -405.556237) (xy 293.536785 -405.490747)
			(xy 293.528709 -405.423809) (xy 293.52871 -405.356385) (xy 293.536786 -405.289447) (xy 293.552821 -405.223958)
			(xy 293.576585 -405.160861) (xy 293.607736 -405.101064) (xy 293.645824 -405.045429) (xy 293.667688 -405.019764)
			(xy 293.673481 -405.012616) (xy 293.679998 -404.995428) (xy 293.680388 -404.986236) (xy 293.680388 -404.828756)
			(xy 293.680849 -404.818646) (xy 293.688599 -404.799969) (xy 293.702903 -404.785676) (xy 293.721586 -404.777941)
			(xy 293.731696 -404.777448) (xy 294.447976 -404.777448) (xy 294.458077 -404.778003) (xy 294.476745 -404.785723)
			(xy 294.491038 -404.799998) (xy 294.498783 -404.818656) (xy 294.499284 -404.828756) (xy 294.499284 -404.986236)
			(xy 294.49968 -404.995425) (xy 294.506204 -405.012609) (xy 294.511984 -405.019764) (xy 294.533845 -405.045432)
			(xy 294.571934 -405.101066) (xy 294.603086 -405.160862) (xy 294.626851 -405.223958) (xy 294.642888 -405.289447)
			(xy 294.650964 -405.356385) (xy 294.650964 -405.423809) (xy 294.642889 -405.490747) (xy 294.626853 -405.556236)
			(xy 294.603089 -405.619333) (xy 294.60081 -405.623708) (xy 295.728844 -405.623708) (xy 295.728845 -405.556283)
			(xy 295.736922 -405.489344) (xy 295.752959 -405.423854) (xy 295.776725 -405.360757) (xy 295.807879 -405.30096)
			(xy 295.84597 -405.245327) (xy 295.867836 -405.219662) (xy 295.873636 -405.212519) (xy 295.880148 -405.195327)
			(xy 295.880536 -405.186134) (xy 295.880536 -404.693882) (xy 295.880126 -404.684695) (xy 295.873611 -404.667511)
			(xy 295.867836 -404.660354) (xy 295.845992 -404.634672) (xy 295.807901 -404.57904) (xy 295.776747 -404.519247)
			(xy 295.75298 -404.456152) (xy 295.736942 -404.390665) (xy 295.728864 -404.323728) (xy 295.728862 -404.256305)
			(xy 295.736936 -404.189368) (xy 295.75297 -404.123879) (xy 295.776733 -404.060783) (xy 295.807884 -404.000988)
			(xy 295.845972 -403.945355) (xy 295.867836 -403.91969) (xy 295.873624 -403.912539) (xy 295.880143 -403.895353)
			(xy 295.880536 -403.886162) (xy 295.880536 -403.728682) (xy 295.881011 -403.718555) (xy 295.888744 -403.699834)
			(xy 295.903034 -403.685478) (xy 295.921719 -403.677659) (xy 295.931844 -403.67712) (xy 296.648124 -403.67712)
			(xy 296.658282 -403.677502) (xy 296.677039 -403.685309) (xy 296.691362 -403.699718) (xy 296.699058 -403.718521)
			(xy 296.699432 -403.728682) (xy 296.699432 -403.886162) (xy 296.699876 -403.895345) (xy 296.706368 -403.912529)
			(xy 296.712132 -403.91969) (xy 296.734016 -403.945338) (xy 296.772102 -404.000976) (xy 296.80325 -404.060775)
			(xy 296.827012 -404.123874) (xy 296.843045 -404.189364) (xy 296.851118 -404.256304) (xy 296.851117 -404.323729)
			(xy 296.843039 -404.390668) (xy 296.827002 -404.456158) (xy 296.803237 -404.519256) (xy 296.772085 -404.579053)
			(xy 296.733996 -404.634688) (xy 296.712132 -404.660354) (xy 296.706322 -404.667489) (xy 296.699817 -404.684688)
			(xy 296.699432 -404.693882) (xy 296.699432 -405.186134) (xy 296.699841 -405.195321) (xy 296.706357 -405.212505)
			(xy 296.712132 -405.219662) (xy 296.733989 -405.245333) (xy 296.772076 -405.300967) (xy 296.803225 -405.360763)
			(xy 296.826988 -405.423859) (xy 296.843023 -405.489347) (xy 296.851099 -405.556284) (xy 296.851099 -405.623707)
			(xy 296.843025 -405.690644) (xy 296.826991 -405.756132) (xy 296.803229 -405.819229) (xy 296.77208 -405.879025)
			(xy 296.733994 -405.93466) (xy 296.712132 -405.960326) (xy 296.706334 -405.96747) (xy 296.699822 -405.984662)
			(xy 296.699432 -405.993854) (xy 296.699432 -406.151334) (xy 296.699001 -406.161466) (xy 296.691256 -406.180194)
			(xy 296.676953 -406.19455) (xy 296.658254 -406.202363) (xy 296.648124 -406.202896) (xy 295.931844 -406.202896)
			(xy 295.921692 -406.202442) (xy 295.90294 -406.19466) (xy 295.888615 -406.180273) (xy 295.880915 -406.161487)
			(xy 295.880536 -406.151334) (xy 295.880536 -405.993854) (xy 295.880092 -405.984671) (xy 295.873601 -405.967486)
			(xy 295.867836 -405.960326) (xy 295.845965 -405.934666) (xy 295.807874 -405.879032) (xy 295.776722 -405.819235)
			(xy 295.752956 -405.756137) (xy 295.73692 -405.690647) (xy 295.728844 -405.623708) (xy 294.60081 -405.623708)
			(xy 294.571938 -405.679129) (xy 294.533848 -405.734763) (xy 294.511984 -405.760428) (xy 294.506191 -405.767576)
			(xy 294.499675 -405.784764) (xy 294.499284 -405.793956) (xy 294.499284 -406.286208) (xy 294.499694 -406.295395)
			(xy 294.506208 -406.312579) (xy 294.511984 -406.319736) (xy 294.533817 -406.345427) (xy 294.571908 -406.401057)
			(xy 294.603061 -406.46085) (xy 294.626827 -406.523943) (xy 294.642866 -406.58943) (xy 294.650944 -406.656365)
			(xy 294.650947 -406.72373) (xy 297.928985 -406.72373) (xy 297.928988 -406.656422) (xy 297.937036 -406.589596)
			(xy 297.953013 -406.524212) (xy 297.976691 -406.461206) (xy 298.00773 -406.401482) (xy 298.045685 -406.345896)
			(xy 298.067476 -406.320244) (xy 298.073276 -406.313101) (xy 298.079789 -406.295909) (xy 298.080176 -406.286716)
			(xy 298.080176 -405.793448) (xy 298.079748 -405.784263) (xy 298.073247 -405.767078) (xy 298.067476 -405.75992)
			(xy 298.045683 -405.734272) (xy 298.007732 -405.678685) (xy 297.976697 -405.618962) (xy 297.953023 -405.555957)
			(xy 297.937049 -405.490574) (xy 297.929005 -405.42375) (xy 297.929005 -405.356444) (xy 297.93705 -405.28962)
			(xy 297.953025 -405.224238) (xy 297.9767 -405.161233) (xy 298.007735 -405.101509) (xy 298.045687 -405.045924)
			(xy 298.067476 -405.020272) (xy 298.073264 -405.013121) (xy 298.079785 -404.995935) (xy 298.080176 -404.986744)
			(xy 298.080176 -404.828756) (xy 298.080585 -404.818602) (xy 298.088391 -404.799853) (xy 298.102791 -404.785532)
			(xy 298.121582 -404.77783) (xy 298.131738 -404.777448) (xy 298.848018 -404.777448) (xy 298.858147 -404.777912)
			(xy 298.87687 -404.785647) (xy 298.891226 -404.79994) (xy 298.899043 -404.818629) (xy 298.89958 -404.828756)
			(xy 298.89958 -404.986744) (xy 298.899973 -404.995933) (xy 298.906499 -405.013117) (xy 298.91228 -405.020272)
			(xy 298.934063 -405.045928) (xy 298.972011 -405.101514) (xy 299.003043 -405.161237) (xy 299.026716 -405.224241)
			(xy 299.042688 -405.289623) (xy 299.050732 -405.356445) (xy 299.050733 -405.423749) (xy 299.042689 -405.490571)
			(xy 299.026717 -405.555953) (xy 299.003046 -405.618957) (xy 299.000577 -405.623708) (xy 300.128635 -405.623708)
			(xy 300.128635 -405.556283) (xy 300.136712 -405.489344) (xy 300.152749 -405.423854) (xy 300.176515 -405.360757)
			(xy 300.207668 -405.300961) (xy 300.245759 -405.245327) (xy 300.267624 -405.219662) (xy 300.273422 -405.212518)
			(xy 300.279935 -405.195326) (xy 300.280324 -405.186134) (xy 300.280324 -404.693882) (xy 300.279917 -404.684695)
			(xy 300.273401 -404.66751) (xy 300.267624 -404.660354) (xy 300.245781 -404.634671) (xy 300.20769 -404.57904)
			(xy 300.176537 -404.519246) (xy 300.15277 -404.456152) (xy 300.136733 -404.390664) (xy 300.128655 -404.323728)
			(xy 300.128653 -404.256305) (xy 300.136727 -404.189368) (xy 300.152761 -404.12388) (xy 300.176523 -404.060784)
			(xy 300.207673 -404.000989) (xy 300.245761 -403.945355) (xy 300.267624 -403.91969) (xy 300.27341 -403.912538)
			(xy 300.27993 -403.895352) (xy 300.280324 -403.886162) (xy 300.280324 -403.728682) (xy 300.280811 -403.718556)
			(xy 300.288542 -403.699837) (xy 300.302828 -403.685482) (xy 300.321509 -403.677661) (xy 300.331632 -403.67712)
			(xy 301.047912 -403.67712) (xy 301.058069 -403.677512) (xy 301.076826 -403.685315) (xy 301.09115 -403.699721)
			(xy 301.098846 -403.718522) (xy 301.09922 -403.728682) (xy 301.09922 -403.886162) (xy 301.099644 -403.895348)
			(xy 301.106147 -403.912533) (xy 301.11192 -403.91969) (xy 301.133805 -403.945338) (xy 301.171892 -404.000975)
			(xy 301.20304 -404.060774) (xy 301.226802 -404.123873) (xy 301.242836 -404.189364) (xy 301.250909 -404.256304)
			(xy 301.250907 -404.323729) (xy 301.24283 -404.390668) (xy 301.226793 -404.456158) (xy 301.203027 -404.519256)
			(xy 301.171875 -404.579053) (xy 301.133785 -404.634688) (xy 301.11192 -404.660354) (xy 301.10612 -404.667497)
			(xy 301.099607 -404.684689) (xy 301.09922 -404.693882) (xy 301.09922 -405.186134) (xy 301.099609 -405.195323)
			(xy 301.106137 -405.212508) (xy 301.11192 -405.219662) (xy 301.133777 -405.245332) (xy 301.171865 -405.300967)
			(xy 301.203015 -405.360762) (xy 301.226778 -405.423859) (xy 301.242814 -405.489347) (xy 301.25089 -405.556284)
			(xy 301.25089 -405.623707) (xy 301.242815 -405.690644) (xy 301.226781 -405.756133) (xy 301.203018 -405.819229)
			(xy 301.17187 -405.879026) (xy 301.133783 -405.93466) (xy 301.11192 -405.960326) (xy 301.106132 -405.967478)
			(xy 301.099612 -405.984663) (xy 301.09922 -405.993854) (xy 301.09922 -406.151334) (xy 301.0988 -406.161468)
			(xy 301.091054 -406.180197) (xy 301.076747 -406.194554) (xy 301.058044 -406.202365) (xy 301.047912 -406.202896)
			(xy 300.331632 -406.202896) (xy 300.321479 -406.202452) (xy 300.302727 -406.194667) (xy 300.288402 -406.180276)
			(xy 300.280702 -406.161488) (xy 300.280324 -406.151334) (xy 300.280324 -405.993854) (xy 300.279882 -405.98467)
			(xy 300.27339 -405.967486) (xy 300.267624 -405.960326) (xy 300.245753 -405.934666) (xy 300.207663 -405.879031)
			(xy 300.176511 -405.819235) (xy 300.152747 -405.756137) (xy 300.136711 -405.690647) (xy 300.128635 -405.623708)
			(xy 299.000577 -405.623708) (xy 298.972014 -405.678681) (xy 298.934067 -405.734268) (xy 298.91228 -405.75992)
			(xy 298.90649 -405.76707) (xy 298.899972 -405.784257) (xy 298.89958 -405.793448) (xy 298.89958 -406.286716)
			(xy 298.899987 -406.295903) (xy 298.906503 -406.313088) (xy 298.91228 -406.320244) (xy 298.934035 -406.345922)
			(xy 298.971984 -406.401506) (xy 299.003018 -406.461226) (xy 299.026691 -406.524227) (xy 299.042666 -406.589606)
			(xy 299.050712 -406.656425) (xy 299.050715 -406.723727) (xy 299.050708 -406.723789) (xy 302.328777 -406.723789)
			(xy 302.32878 -406.656363) (xy 302.336859 -406.589423) (xy 302.352897 -406.523933) (xy 302.376664 -406.460835)
			(xy 302.407816 -406.401037) (xy 302.445907 -406.345402) (xy 302.467772 -406.319736) (xy 302.473587 -406.312604)
			(xy 302.480089 -406.295403) (xy 302.480472 -406.286208) (xy 302.480472 -405.793956) (xy 302.480089 -405.784766)
			(xy 302.473557 -405.767581) (xy 302.467772 -405.760428) (xy 302.445905 -405.734766) (xy 302.407818 -405.67913)
			(xy 302.376669 -405.619333) (xy 302.352907 -405.556236) (xy 302.336872 -405.490747) (xy 302.328797 -405.423809)
			(xy 302.328798 -405.356385) (xy 302.336873 -405.289447) (xy 302.352908 -405.223958) (xy 302.376672 -405.160861)
			(xy 302.407821 -405.101065) (xy 302.445909 -405.04543) (xy 302.467772 -405.019764) (xy 302.473575 -405.012624)
			(xy 302.480084 -404.995429) (xy 302.480472 -404.986236) (xy 302.480472 -404.828756) (xy 302.480948 -404.818648)
			(xy 302.488695 -404.799974) (xy 302.502994 -404.785682) (xy 302.521672 -404.777944) (xy 302.53178 -404.777448)
			(xy 303.24806 -404.777448) (xy 303.25816 -404.778017) (xy 303.276827 -404.785732) (xy 303.291121 -404.800002)
			(xy 303.298867 -404.818657) (xy 303.299368 -404.828756) (xy 303.299368 -404.986236) (xy 303.299768 -404.995424)
			(xy 303.30629 -405.012608) (xy 303.312068 -405.019764) (xy 303.333929 -405.045432) (xy 303.37202 -405.101065)
			(xy 303.403173 -405.160861) (xy 303.426939 -405.223957) (xy 303.442975 -405.289447) (xy 303.451052 -405.356385)
			(xy 303.451052 -405.423809) (xy 303.442976 -405.490748) (xy 303.42694 -405.556237) (xy 303.403175 -405.619334)
			(xy 303.372023 -405.67913) (xy 303.333933 -405.734763) (xy 303.312068 -405.760428) (xy 303.306273 -405.767574)
			(xy 303.299758 -405.784764) (xy 303.299368 -405.793956) (xy 303.299368 -406.286208) (xy 303.299781 -406.295395)
			(xy 303.306294 -406.312579) (xy 303.312068 -406.319736) (xy 303.333902 -406.345427) (xy 303.371993 -406.401057)
			(xy 303.403147 -406.460849) (xy 303.426915 -406.523943) (xy 303.442953 -406.589429) (xy 303.451032 -406.656365)
			(xy 303.451035 -406.723787) (xy 303.442962 -406.790724) (xy 303.426929 -406.856211) (xy 303.403167 -406.919307)
			(xy 303.372018 -406.979102) (xy 303.333931 -407.034735) (xy 303.312068 -407.0604) (xy 303.306285 -407.067555)
			(xy 303.299763 -407.084738) (xy 303.299368 -407.093928) (xy 303.299368 -407.251408) (xy 303.29899 -407.261535)
			(xy 303.291233 -407.280245) (xy 303.276904 -407.29456) (xy 303.258187 -407.302299) (xy 303.24806 -407.302716)
			(xy 302.53178 -407.302716) (xy 302.521672 -407.302232) (xy 302.502996 -407.294491) (xy 302.488703 -407.280194)
			(xy 302.480966 -407.261516) (xy 302.480472 -407.251408) (xy 302.480472 -407.093928) (xy 302.480055 -407.084741)
			(xy 302.473547 -407.067557) (xy 302.467772 -407.0604) (xy 302.445878 -407.03476) (xy 302.407792 -406.979121)
			(xy 302.376644 -406.919321) (xy 302.352883 -406.856221) (xy 302.33685 -406.790729) (xy 302.328777 -406.723789)
			(xy 299.050708 -406.723789) (xy 299.042674 -406.790547) (xy 299.026705 -406.855927) (xy 299.003037 -406.91893)
			(xy 298.972009 -406.978653) (xy 298.934065 -407.034239) (xy 298.91228 -407.059892) (xy 298.906502 -407.06705)
			(xy 298.899977 -407.084231) (xy 298.89958 -407.09342) (xy 298.89958 -407.251408) (xy 298.899184 -407.261565)
			(xy 298.891382 -407.280321) (xy 298.876978 -407.294645) (xy 298.858177 -407.302341) (xy 298.848018 -407.302716)
			(xy 298.131738 -407.302716) (xy 298.121608 -407.302241) (xy 298.10288 -407.294517) (xy 298.088521 -407.280227)
			(xy 298.080708 -407.261535) (xy 298.080176 -407.251408) (xy 298.080176 -407.09342) (xy 298.079762 -407.084233)
			(xy 298.073252 -407.067048) (xy 298.067476 -407.059892) (xy 298.045656 -407.034266) (xy 298.007706 -406.978677)
			(xy 297.976672 -406.91895) (xy 297.952999 -406.855942) (xy 297.937027 -406.790556) (xy 297.928985 -406.72373)
			(xy 294.650947 -406.72373) (xy 294.650947 -406.723787) (xy 294.642874 -406.790723) (xy 294.626842 -406.856211)
			(xy 294.60308 -406.919306) (xy 294.571933 -406.979101) (xy 294.533847 -407.034735) (xy 294.511984 -407.0604)
			(xy 294.506203 -407.067556) (xy 294.49968 -407.084738) (xy 294.499284 -407.093928) (xy 294.499284 -407.251408)
			(xy 294.49889 -407.261533) (xy 294.491136 -407.28024) (xy 294.476813 -407.294554) (xy 294.458101 -407.302296)
			(xy 294.447976 -407.302716) (xy 293.731696 -407.302716) (xy 293.721589 -407.302218) (xy 293.702914 -407.294482)
			(xy 293.68862 -407.28019) (xy 293.680882 -407.261515) (xy 293.680388 -407.251408) (xy 293.680388 -407.093928)
			(xy 293.679967 -407.084742) (xy 293.673461 -407.067557) (xy 293.667688 -407.0604) (xy 293.645793 -407.03476)
			(xy 293.607706 -406.979122) (xy 293.576557 -406.919322) (xy 293.552796 -406.856222) (xy 293.536763 -406.79073)
			(xy 293.52869 -406.723789) (xy 290.250621 -406.723789) (xy 290.242587 -406.790547) (xy 290.226619 -406.855927)
			(xy 290.202951 -406.91893) (xy 290.171924 -406.978653) (xy 290.133981 -407.034239) (xy 290.112196 -407.059892)
			(xy 290.10642 -407.067052) (xy 290.099893 -407.084231) (xy 290.099496 -407.09342) (xy 290.099496 -407.251408)
			(xy 290.099085 -407.261563) (xy 290.091286 -407.280316) (xy 290.076886 -407.29464) (xy 290.058091 -407.302338)
			(xy 290.047934 -407.302716) (xy 289.331654 -407.302716) (xy 289.321519 -407.30231) (xy 289.302788 -407.294559)
			(xy 289.288432 -407.280248) (xy 289.280622 -407.261541) (xy 289.280092 -407.251408) (xy 289.280092 -407.09342)
			(xy 289.279674 -407.084234) (xy 289.273166 -407.067049) (xy 289.267392 -407.059892) (xy 289.245571 -407.034266)
			(xy 289.20762 -406.978677) (xy 289.176585 -406.918951) (xy 289.152912 -406.855943) (xy 289.136939 -406.790557)
			(xy 289.128897 -406.72373) (xy 237.026196 -406.72373) (xy 237.026196 -409.523887) (xy 286.928735 -409.523887)
			(xy 286.928738 -409.456459) (xy 286.936818 -409.389518) (xy 286.952859 -409.324026) (xy 286.97663 -409.260927)
			(xy 287.007788 -409.20113) (xy 287.045884 -409.145496) (xy 287.067752 -409.119832) (xy 287.073566 -409.1127)
			(xy 287.080069 -409.095499) (xy 287.080452 -409.086304) (xy 287.080452 -408.594052) (xy 287.080005 -408.584869)
			(xy 287.073516 -408.567685) (xy 287.067752 -408.560524) (xy 287.045878 -408.534866) (xy 287.007786 -408.479232)
			(xy 286.976633 -408.419435) (xy 286.952867 -408.356337) (xy 286.936831 -408.290847) (xy 286.928755 -408.223907)
			(xy 286.928755 -408.156481) (xy 286.936833 -408.089542) (xy 286.952871 -408.024051) (xy 286.976638 -407.960954)
			(xy 287.007793 -407.901158) (xy 287.045886 -407.845524) (xy 287.067752 -407.81986) (xy 287.073554 -407.812719)
			(xy 287.080064 -407.795525) (xy 287.080452 -407.786332) (xy 287.080452 -407.628852) (xy 287.080945 -407.618746)
			(xy 287.088689 -407.600076) (xy 287.102983 -407.585785) (xy 287.121654 -407.578043) (xy 287.13176 -407.577544)
			(xy 287.84804 -407.577544) (xy 287.858144 -407.578051) (xy 287.876813 -407.585791) (xy 287.891104 -407.600081)
			(xy 287.898847 -407.618748) (xy 287.899348 -407.628852) (xy 287.899348 -407.786332) (xy 287.899755 -407.795519)
			(xy 287.906272 -407.812703) (xy 287.912048 -407.81986) (xy 287.933906 -407.845531) (xy 287.971998 -407.901163)
			(xy 288.003152 -407.960958) (xy 288.026919 -408.024055) (xy 288.042957 -408.089543) (xy 288.051034 -408.156482)
			(xy 288.051035 -408.223906) (xy 288.042959 -408.290845) (xy 288.026923 -408.356334) (xy 288.003157 -408.419431)
			(xy 287.972004 -408.479226) (xy 287.933913 -408.53486) (xy 287.912048 -408.560524) (xy 287.906252 -408.56767)
			(xy 287.899739 -408.58486) (xy 287.899348 -408.594052) (xy 287.899348 -409.086304) (xy 287.899768 -409.09549)
			(xy 287.906276 -409.112674) (xy 287.912048 -409.119832) (xy 287.933878 -409.145526) (xy 287.971972 -409.201155)
			(xy 288.003127 -409.260947) (xy 288.026895 -409.32404) (xy 288.042935 -409.389526) (xy 288.051014 -409.456462)
			(xy 288.051018 -409.523884) (xy 288.042945 -409.590821) (xy 288.026911 -409.656308) (xy 288.003149 -409.719404)
			(xy 287.971999 -409.779199) (xy 287.933912 -409.834832) (xy 287.912048 -409.860496) (xy 287.906264 -409.86765)
			(xy 287.899743 -409.884834) (xy 287.899348 -409.894024) (xy 287.899348 -410.051504) (xy 287.898819 -410.061607)
			(xy 287.891089 -410.080276) (xy 287.876806 -410.094569) (xy 287.858143 -410.102312) (xy 287.84804 -410.102812)
			(xy 287.13176 -410.102812) (xy 287.12165 -410.102348) (xy 287.102973 -410.094599) (xy 287.08868 -410.080296)
			(xy 287.080945 -410.061614) (xy 287.080452 -410.051504) (xy 287.080452 -409.894024) (xy 287.080019 -409.884839)
			(xy 287.07352 -409.867655) (xy 287.067752 -409.860496) (xy 287.045851 -409.834861) (xy 287.00776 -409.779223)
			(xy 286.976608 -409.719423) (xy 286.952843 -409.656322) (xy 286.936809 -409.590829) (xy 286.928735 -409.523887)
			(xy 237.026196 -409.523887) (xy 237.026196 -410.623642) (xy 289.128908 -410.623642) (xy 289.12891 -410.556334)
			(xy 289.136956 -410.48951) (xy 289.152933 -410.424126) (xy 289.176609 -410.361121) (xy 289.207648 -410.301397)
			(xy 289.245602 -410.245811) (xy 289.267392 -410.22016) (xy 289.273187 -410.213014) (xy 289.279703 -410.195824)
			(xy 289.280092 -410.186632) (xy 289.280092 -409.693364) (xy 289.279701 -409.684175) (xy 289.273174 -409.66699)
			(xy 289.267392 -409.659836) (xy 289.245614 -409.634175) (xy 289.207662 -409.578591) (xy 289.176625 -409.518869)
			(xy 289.152949 -409.455866) (xy 289.136974 -409.390484) (xy 289.128928 -409.323662) (xy 289.128927 -409.256356)
			(xy 289.136971 -409.189534) (xy 289.152944 -409.124152) (xy 289.176618 -409.061147) (xy 289.207653 -409.001425)
			(xy 289.245603 -408.945839) (xy 289.267392 -408.920188) (xy 289.273175 -408.913033) (xy 289.279698 -408.89585)
			(xy 289.280092 -408.88666) (xy 289.280092 -408.728672) (xy 289.280498 -408.718517) (xy 289.288302 -408.699766)
			(xy 289.302703 -408.685443) (xy 289.321497 -408.677743) (xy 289.331654 -408.677364) (xy 290.047934 -408.677364)
			(xy 290.058066 -408.677799) (xy 290.076792 -408.685543) (xy 290.091148 -408.699845) (xy 290.098962 -408.718542)
			(xy 290.099496 -408.728672) (xy 290.099496 -408.88666) (xy 290.099926 -408.895845) (xy 290.106426 -408.91303)
			(xy 290.112196 -408.920188) (xy 290.133994 -408.945831) (xy 290.171941 -409.00142) (xy 290.202971 -409.061145)
			(xy 290.226642 -409.12415) (xy 290.242613 -409.189533) (xy 290.250656 -409.256356) (xy 290.250655 -409.323662)
			(xy 290.24261 -409.390484) (xy 290.226637 -409.455867) (xy 290.202964 -409.518872) (xy 290.200389 -409.523827)
			(xy 291.329055 -409.523827) (xy 291.329058 -409.456519) (xy 291.337106 -409.389694) (xy 291.353082 -409.32431)
			(xy 291.376759 -409.261304) (xy 291.407797 -409.201579) (xy 291.44575 -409.145992) (xy 291.46754 -409.12034)
			(xy 291.47335 -409.113204) (xy 291.479855 -409.096006) (xy 291.48024 -409.086812) (xy 291.48024 -408.593544)
			(xy 291.4798 -408.58436) (xy 291.473306 -408.567176) (xy 291.46754 -408.560016) (xy 291.445744 -408.53437)
			(xy 291.407796 -408.478783) (xy 291.376763 -408.419059) (xy 291.35309 -408.356053) (xy 291.337118 -408.29067)
			(xy 291.329074 -408.223847) (xy 291.329075 -408.156541) (xy 291.33712 -408.089718) (xy 291.353094 -408.024335)
			(xy 291.376767 -407.96133) (xy 291.407802 -407.901607) (xy 291.445752 -407.84602) (xy 291.46754 -407.820368)
			(xy 291.473338 -407.813224) (xy 291.479851 -407.796032) (xy 291.48024 -407.78684) (xy 291.48024 -407.628852)
			(xy 291.480583 -407.61869) (xy 291.488402 -407.599929) (xy 291.502823 -407.585606) (xy 291.521637 -407.577915)
			(xy 291.531802 -407.577544) (xy 292.248082 -407.577544) (xy 292.258208 -407.578041) (xy 292.27693 -407.585764)
			(xy 292.291287 -407.600047) (xy 292.299106 -407.618729) (xy 292.299644 -407.628852) (xy 292.299644 -407.78684)
			(xy 292.300048 -407.796028) (xy 292.306567 -407.813211) (xy 292.312344 -407.820368) (xy 292.334124 -407.846026)
			(xy 292.372074 -407.901612) (xy 292.403109 -407.961334) (xy 292.426783 -408.024338) (xy 292.442757 -408.089719)
			(xy 292.450802 -408.156542) (xy 292.450803 -408.223846) (xy 292.442759 -408.290669) (xy 292.426786 -408.356051)
			(xy 292.403114 -408.419055) (xy 292.372081 -408.478778) (xy 292.334132 -408.534364) (xy 292.312344 -408.560016)
			(xy 292.306551 -408.567164) (xy 292.300036 -408.584353) (xy 292.299644 -408.593544) (xy 292.299644 -409.086812)
			(xy 292.300061 -409.095998) (xy 292.306571 -409.113182) (xy 292.312344 -409.12034) (xy 292.334097 -409.146021)
			(xy 292.372048 -409.201603) (xy 292.403083 -409.261322) (xy 292.426759 -409.324323) (xy 292.442735 -409.389702)
			(xy 292.450782 -409.456522) (xy 292.450786 -409.523824) (xy 292.442745 -409.590645) (xy 292.426775 -409.656025)
			(xy 292.403106 -409.719028) (xy 292.372076 -409.77875) (xy 292.33413 -409.834336) (xy 292.312344 -409.859988)
			(xy 292.306521 -409.867114) (xy 292.300024 -409.884319) (xy 292.299644 -409.893516) (xy 292.299644 -410.051504)
			(xy 292.299182 -410.061653) (xy 292.291394 -410.080397) (xy 292.27701 -410.094718) (xy 292.258233 -410.102426)
			(xy 292.248082 -410.102812) (xy 291.531802 -410.102812) (xy 291.521682 -410.102273) (xy 291.502971 -410.094556)
			(xy 291.488616 -410.080286) (xy 291.480788 -410.061621) (xy 291.48024 -410.051504) (xy 291.48024 -409.893516)
			(xy 291.479813 -409.884331) (xy 291.47331 -409.867147) (xy 291.46754 -409.859988) (xy 291.445717 -409.834365)
			(xy 291.407769 -409.778774) (xy 291.376737 -409.719047) (xy 291.353066 -409.656039) (xy 291.337096 -409.590653)
			(xy 291.329055 -409.523827) (xy 290.200389 -409.523827) (xy 290.171931 -409.578596) (xy 290.133983 -409.634183)
			(xy 290.112196 -409.659836) (xy 290.106401 -409.666982) (xy 290.099886 -409.684172) (xy 290.099496 -409.693364)
			(xy 290.099496 -410.186632) (xy 290.099891 -410.195821) (xy 290.106415 -410.213005) (xy 290.112196 -410.22016)
			(xy 290.133967 -410.245826) (xy 290.171914 -410.301411) (xy 290.202946 -410.361133) (xy 290.226618 -410.424136)
			(xy 290.242591 -410.489516) (xy 290.250636 -410.556336) (xy 290.250638 -410.62364) (xy 290.250631 -410.6237)
			(xy 293.528701 -410.6237) (xy 293.528702 -410.556276) (xy 293.53678 -410.489336) (xy 293.552816 -410.423847)
			(xy 293.576582 -410.360749) (xy 293.607734 -410.300952) (xy 293.645824 -410.245317) (xy 293.667688 -410.219652)
			(xy 293.673486 -410.212508) (xy 293.68 -410.195317) (xy 293.680388 -410.186124) (xy 293.680388 -409.693872)
			(xy 293.679994 -409.684683) (xy 293.673469 -409.667499) (xy 293.667688 -409.660344) (xy 293.645836 -409.634669)
			(xy 293.607748 -409.579035) (xy 293.576597 -409.519241) (xy 293.552833 -409.456145) (xy 293.536797 -409.390657)
			(xy 293.52872 -409.32372) (xy 293.528719 -409.256298) (xy 293.536794 -409.189361) (xy 293.552828 -409.123872)
			(xy 293.57659 -409.060776) (xy 293.607739 -409.00098) (xy 293.645825 -408.945345) (xy 293.667688 -408.91968)
			(xy 293.673474 -408.912527) (xy 293.679995 -408.895343) (xy 293.680388 -408.886152) (xy 293.680388 -408.728672)
			(xy 293.680862 -408.718563) (xy 293.688606 -408.699886) (xy 293.702907 -408.685593) (xy 293.721587 -408.677857)
			(xy 293.731696 -408.677364) (xy 294.447976 -408.677364) (xy 294.458079 -408.677904) (xy 294.47675 -408.685627)
			(xy 294.491044 -408.699907) (xy 294.498786 -408.71857) (xy 294.499284 -408.728672) (xy 294.499284 -408.886152)
			(xy 294.499721 -408.895336) (xy 294.506216 -408.912521) (xy 294.511984 -408.91968) (xy 294.53386 -408.945335)
			(xy 294.57195 -409.000971) (xy 294.603101 -409.060768) (xy 294.626865 -409.123866) (xy 294.6429 -409.189357)
			(xy 294.650975 -409.256297) (xy 294.650974 -409.323721) (xy 294.642897 -409.390661) (xy 294.62686 -409.456151)
			(xy 294.603093 -409.519248) (xy 294.600676 -409.523887) (xy 295.728823 -409.523887) (xy 295.728826 -409.456459)
			(xy 295.736906 -409.389518) (xy 295.752947 -409.324026) (xy 295.776716 -409.260928) (xy 295.807873 -409.201131)
			(xy 295.845969 -409.145497) (xy 295.867836 -409.119832) (xy 295.873649 -409.112698) (xy 295.880153 -409.095499)
			(xy 295.880536 -409.086304) (xy 295.880536 -408.594052) (xy 295.880093 -408.584869) (xy 295.873601 -408.567684)
			(xy 295.867836 -408.560524) (xy 295.845963 -408.534866) (xy 295.807872 -408.479231) (xy 295.77672 -408.419434)
			(xy 295.752954 -408.356336) (xy 295.736918 -408.290846) (xy 295.728843 -408.223907) (xy 295.728843 -408.156481)
			(xy 295.736921 -408.089542) (xy 295.752958 -408.024052) (xy 295.776725 -407.960955) (xy 295.807878 -407.901159)
			(xy 295.84597 -407.845525) (xy 295.867836 -407.81986) (xy 295.873637 -407.812718) (xy 295.880148 -407.795525)
			(xy 295.880536 -407.786332) (xy 295.880536 -407.628852) (xy 295.880947 -407.618736) (xy 295.888707 -407.60005)
			(xy 295.903027 -407.585755) (xy 295.921727 -407.578029) (xy 295.931844 -407.577544) (xy 296.648124 -407.577544)
			(xy 296.658227 -407.578064) (xy 296.676895 -407.585799) (xy 296.691187 -407.600084) (xy 296.698931 -407.618749)
			(xy 296.699432 -407.628852) (xy 296.699432 -407.786332) (xy 296.699842 -407.795519) (xy 296.706357 -407.812703)
			(xy 296.712132 -407.81986) (xy 296.733987 -407.845532) (xy 296.772074 -407.901167) (xy 296.803223 -407.960962)
			(xy 296.826986 -408.024058) (xy 296.843021 -408.089546) (xy 296.851097 -408.156483) (xy 296.851098 -408.223905)
			(xy 296.843024 -408.290842) (xy 296.82699 -408.356331) (xy 296.803228 -408.419427) (xy 296.77208 -408.479223)
			(xy 296.733994 -408.534858) (xy 296.712132 -408.560524) (xy 296.706334 -408.567668) (xy 296.699822 -408.58486)
			(xy 296.699432 -408.594052) (xy 296.699432 -409.086304) (xy 296.699856 -409.095489) (xy 296.706362 -409.112673)
			(xy 296.712132 -409.119832) (xy 296.733959 -409.145527) (xy 296.772047 -409.201158) (xy 296.803198 -409.26095)
			(xy 296.826962 -409.324043) (xy 296.842999 -409.389528) (xy 296.851078 -409.456463) (xy 296.851081 -409.523883)
			(xy 296.843009 -409.590818) (xy 296.826978 -409.656305) (xy 296.80322 -409.7194) (xy 296.772075 -409.779196)
			(xy 296.733993 -409.83483) (xy 296.712132 -409.860496) (xy 296.706346 -409.867649) (xy 296.699827 -409.884834)
			(xy 296.699432 -409.894024) (xy 296.699432 -410.051504) (xy 296.698919 -410.061609) (xy 296.691186 -410.080281)
			(xy 296.676898 -410.094575) (xy 296.658229 -410.102315) (xy 296.648124 -410.102812) (xy 295.931844 -410.102812)
			(xy 295.921726 -410.102348) (xy 295.903026 -410.094617) (xy 295.88871 -410.080315) (xy 295.880961 -410.061622)
			(xy 295.880536 -410.051504) (xy 295.880536 -409.894024) (xy 295.880106 -409.884839) (xy 295.873605 -409.867655)
			(xy 295.867836 -409.860496) (xy 295.845935 -409.834861) (xy 295.807845 -409.779223) (xy 295.776694 -409.719423)
			(xy 295.752931 -409.656322) (xy 295.736896 -409.590829) (xy 295.728823 -409.523887) (xy 294.600676 -409.523887)
			(xy 294.57194 -409.579045) (xy 294.533849 -409.634679) (xy 294.511984 -409.660344) (xy 294.506184 -409.667487)
			(xy 294.499672 -409.684679) (xy 294.499284 -409.693872) (xy 294.499284 -410.186124) (xy 294.499686 -410.195312)
			(xy 294.506206 -410.212496) (xy 294.511984 -410.219652) (xy 294.533833 -410.24533) (xy 294.571923 -410.300962)
			(xy 294.603075 -410.360757) (xy 294.626841 -410.423852) (xy 294.642878 -410.489339) (xy 294.650956 -410.556277)
			(xy 294.650957 -410.623641) (xy 297.928996 -410.623641) (xy 297.928998 -410.556334) (xy 297.937044 -410.48951)
			(xy 297.95302 -410.424127) (xy 297.976696 -410.361121) (xy 298.007733 -410.301398) (xy 298.045686 -410.245812)
			(xy 298.067476 -410.22016) (xy 298.073269 -410.213012) (xy 298.079787 -410.195824) (xy 298.080176 -410.186632)
			(xy 298.080176 -409.693364) (xy 298.079788 -409.684174) (xy 298.07326 -409.66699) (xy 298.067476 -409.659836)
			(xy 298.045699 -409.634175) (xy 298.007747 -409.57859) (xy 297.976712 -409.518868) (xy 297.953037 -409.455865)
			(xy 297.937062 -409.390484) (xy 297.929016 -409.323661) (xy 297.929015 -409.256357) (xy 297.937058 -409.189534)
			(xy 297.953031 -409.124152) (xy 297.976704 -409.061148) (xy 298.007738 -409.001425) (xy 298.045688 -408.94584)
			(xy 298.067476 -408.920188) (xy 298.073257 -408.913032) (xy 298.079782 -408.89585) (xy 298.080176 -408.88666)
			(xy 298.080176 -408.728672) (xy 298.080598 -408.718519) (xy 298.088398 -408.699771) (xy 298.102794 -408.685449)
			(xy 298.121583 -408.677746) (xy 298.131738 -408.677364) (xy 298.848018 -408.677364) (xy 298.858149 -408.677812)
			(xy 298.876875 -408.68555) (xy 298.891232 -408.699849) (xy 298.899046 -408.718543) (xy 298.89958 -408.728672)
			(xy 298.89958 -408.88666) (xy 298.900014 -408.895845) (xy 298.906512 -408.913029) (xy 298.91228 -408.920188)
			(xy 298.934079 -408.945831) (xy 298.972026 -409.001419) (xy 299.003058 -409.061144) (xy 299.026729 -409.12415)
			(xy 299.042701 -409.189533) (xy 299.050744 -409.256356) (xy 299.050743 -409.323662) (xy 299.042698 -409.390485)
			(xy 299.026724 -409.455868) (xy 299.003051 -409.518873) (xy 299.000446 -409.523886) (xy 300.128614 -409.523886)
			(xy 300.128617 -409.456459) (xy 300.136697 -409.389518) (xy 300.152737 -409.324027) (xy 300.176506 -409.260928)
			(xy 300.207662 -409.201131) (xy 300.245757 -409.145497) (xy 300.267624 -409.119832) (xy 300.273435 -409.112697)
			(xy 300.27994 -409.095499) (xy 300.280324 -409.086304) (xy 300.280324 -408.594052) (xy 300.279883 -408.584868)
			(xy 300.27339 -408.567684) (xy 300.267624 -408.560524) (xy 300.245751 -408.534866) (xy 300.207661 -408.479231)
			(xy 300.17651 -408.419434) (xy 300.152745 -408.356336) (xy 300.136709 -408.290846) (xy 300.128634 -408.223906)
			(xy 300.128634 -408.156482) (xy 300.136711 -408.089542) (xy 300.152748 -408.024053) (xy 300.176514 -407.960955)
			(xy 300.207667 -407.901159) (xy 300.245759 -407.845525) (xy 300.267624 -407.81986) (xy 300.273423 -407.812717)
			(xy 300.279935 -407.795525) (xy 300.280324 -407.786332) (xy 300.280324 -407.628852) (xy 300.280747 -407.618737)
			(xy 300.288504 -407.600053) (xy 300.302821 -407.585759) (xy 300.321516 -407.578031) (xy 300.331632 -407.577544)
			(xy 301.047912 -407.577544) (xy 301.058015 -407.578074) (xy 301.076682 -407.585805) (xy 301.090975 -407.600088)
			(xy 301.098719 -407.61875) (xy 301.09922 -407.628852) (xy 301.09922 -407.786332) (xy 301.09961 -407.795521)
			(xy 301.106137 -407.812706) (xy 301.11192 -407.81986) (xy 301.133775 -407.845532) (xy 301.171863 -407.901166)
			(xy 301.203013 -407.960962) (xy 301.226777 -408.024057) (xy 301.242812 -408.089545) (xy 301.250888 -408.156483)
			(xy 301.250889 -408.223905) (xy 301.242814 -408.290843) (xy 301.22678 -408.356331) (xy 301.203018 -408.419427)
			(xy 301.171869 -408.479224) (xy 301.133783 -408.534858) (xy 301.11192 -408.560524) (xy 301.106133 -408.567676)
			(xy 301.099612 -408.584861) (xy 301.09922 -408.594052) (xy 301.09922 -409.086304) (xy 301.099624 -409.095492)
			(xy 301.106141 -409.112676) (xy 301.11192 -409.119832) (xy 301.133748 -409.145527) (xy 301.171836 -409.201158)
			(xy 301.202988 -409.26095) (xy 301.226753 -409.324043) (xy 301.24279 -409.389528) (xy 301.250869 -409.456463)
			(xy 301.250872 -409.523883) (xy 301.2428 -409.590819) (xy 301.226769 -409.656305) (xy 301.20301 -409.719401)
			(xy 301.171864 -409.779196) (xy 301.133781 -409.83483) (xy 301.11192 -409.860496) (xy 301.106145 -409.867657)
			(xy 301.099617 -409.884835) (xy 301.09922 -409.894024) (xy 301.09922 -410.051504) (xy 301.098719 -410.06161)
			(xy 301.090983 -410.080285) (xy 301.076692 -410.094579) (xy 301.058018 -410.102317) (xy 301.047912 -410.102812)
			(xy 300.331632 -410.102812) (xy 300.321513 -410.102358) (xy 300.302812 -410.094623) (xy 300.288497 -410.080318)
			(xy 300.280749 -410.061623) (xy 300.280324 -410.051504) (xy 300.280324 -409.894024) (xy 300.279897 -409.884839)
			(xy 300.273394 -409.867655) (xy 300.267624 -409.860496) (xy 300.245724 -409.83486) (xy 300.207635 -409.779222)
			(xy 300.176484 -409.719422) (xy 300.152721 -409.656321) (xy 300.136687 -409.590828) (xy 300.128614 -409.523886)
			(xy 299.000446 -409.523886) (xy 298.972017 -409.578597) (xy 298.934068 -409.634184) (xy 298.91228 -409.659836)
			(xy 298.906483 -409.666981) (xy 298.899969 -409.684172) (xy 298.89958 -409.693364) (xy 298.89958 -410.186632)
			(xy 298.899979 -410.19582) (xy 298.906501 -410.213004) (xy 298.91228 -410.22016) (xy 298.934052 -410.245825)
			(xy 298.972 -410.30141) (xy 299.003032 -410.361132) (xy 299.026705 -410.424135) (xy 299.042679 -410.489515)
			(xy 299.050724 -410.556336) (xy 299.050725 -410.62364) (xy 299.050718 -410.6237) (xy 302.328789 -410.6237)
			(xy 302.32879 -410.556276) (xy 302.336867 -410.489337) (xy 302.352904 -410.423847) (xy 302.376668 -410.36075)
			(xy 302.407819 -410.300953) (xy 302.445908 -410.245318) (xy 302.467772 -410.219652) (xy 302.47358 -410.212515)
			(xy 302.480086 -410.195318) (xy 302.480472 -410.186124) (xy 302.480472 -409.693872) (xy 302.480082 -409.684683)
			(xy 302.473555 -409.667498) (xy 302.467772 -409.660344) (xy 302.445921 -409.634669) (xy 302.407834 -409.579035)
			(xy 302.376684 -409.51924) (xy 302.35292 -409.456144) (xy 302.336885 -409.390657) (xy 302.328808 -409.32372)
			(xy 302.328807 -409.256298) (xy 302.336882 -409.189361) (xy 302.352915 -409.123873) (xy 302.376677 -409.060777)
			(xy 302.407824 -409.000981) (xy 302.44591 -408.945346) (xy 302.467772 -408.91968) (xy 302.473568 -408.912535)
			(xy 302.480081 -408.895344) (xy 302.480472 -408.886152) (xy 302.480472 -408.728672) (xy 302.480961 -408.718565)
			(xy 302.488703 -408.699891) (xy 302.502998 -408.685599) (xy 302.521673 -408.67786) (xy 302.53178 -408.677364)
			(xy 303.24806 -408.677364) (xy 303.258175 -408.677848) (xy 303.276871 -408.685576) (xy 303.291186 -408.699872)
			(xy 303.298939 -408.718557) (xy 303.299368 -408.728672) (xy 303.299368 -408.886152) (xy 303.299809 -408.895336)
			(xy 303.306302 -408.91252) (xy 303.312068 -408.91968) (xy 303.333945 -408.945335) (xy 303.372035 -409.00097)
			(xy 303.403187 -409.060768) (xy 303.426952 -409.123866) (xy 303.442988 -409.189356) (xy 303.451063 -409.256296)
			(xy 303.451062 -409.323722) (xy 303.442985 -409.390661) (xy 303.426947 -409.456151) (xy 303.40318 -409.519249)
			(xy 303.372026 -409.579045) (xy 303.333934 -409.634679) (xy 303.312068 -409.660344) (xy 303.306266 -409.667485)
			(xy 303.299755 -409.684679) (xy 303.299368 -409.693872) (xy 303.299368 -410.186124) (xy 303.299774 -410.195312)
			(xy 303.306291 -410.212495) (xy 303.312068 -410.219652) (xy 303.333917 -410.24533) (xy 303.372009 -410.300962)
			(xy 303.403162 -410.360756) (xy 303.426928 -410.423851) (xy 303.442966 -410.489339) (xy 303.451044 -410.556276)
			(xy 303.451045 -410.6237) (xy 303.44297 -410.690637) (xy 303.426935 -410.756126) (xy 303.403172 -410.819222)
			(xy 303.372021 -410.879018) (xy 303.333932 -410.934651) (xy 303.312068 -410.960316) (xy 303.306278 -410.967466)
			(xy 303.29976 -410.984653) (xy 303.299368 -410.993844) (xy 303.299368 -411.151324) (xy 303.299003 -411.161452)
			(xy 303.291241 -411.180162) (xy 303.276909 -411.194477) (xy 303.258189 -411.202216) (xy 303.24806 -411.202632)
			(xy 302.53178 -411.202632) (xy 302.521674 -411.202132) (xy 302.503001 -411.194394) (xy 302.488708 -411.180102)
			(xy 302.480969 -411.16143) (xy 302.480472 -411.151324) (xy 302.480472 -410.993844) (xy 302.480047 -410.984658)
			(xy 302.473544 -410.967474) (xy 302.467772 -410.960316) (xy 302.445893 -410.934663) (xy 302.407807 -410.879026)
			(xy 302.376658 -410.819228) (xy 302.352896 -410.75613) (xy 302.336863 -410.690639) (xy 302.328789 -410.6237)
			(xy 299.050718 -410.6237) (xy 299.042683 -410.690461) (xy 299.026712 -410.755842) (xy 299.003042 -410.818846)
			(xy 298.972012 -410.878569) (xy 298.934066 -410.934156) (xy 298.91228 -410.959808) (xy 298.906495 -410.966961)
			(xy 298.899974 -410.984146) (xy 298.89958 -410.993336) (xy 298.89958 -411.151324) (xy 298.899198 -411.161482)
			(xy 298.891391 -411.180239) (xy 298.876982 -411.194562) (xy 298.858179 -411.202258) (xy 298.848018 -411.202632)
			(xy 298.131738 -411.202632) (xy 298.12161 -411.202141) (xy 298.102885 -411.194421) (xy 298.088526 -411.180135)
			(xy 298.080711 -411.161449) (xy 298.080176 -411.151324) (xy 298.080176 -410.993336) (xy 298.079754 -410.98415)
			(xy 298.073249 -410.966965) (xy 298.067476 -410.959808) (xy 298.045672 -410.934169) (xy 298.007721 -410.878582)
			(xy 297.976686 -410.818857) (xy 297.953013 -410.75585) (xy 297.93704 -410.690466) (xy 297.928996 -410.623641)
			(xy 294.650957 -410.623641) (xy 294.650957 -410.623699) (xy 294.642883 -410.690637) (xy 294.626848 -410.756125)
			(xy 294.603085 -410.819221) (xy 294.571935 -410.879017) (xy 294.533848 -410.934651) (xy 294.511984 -410.960316)
			(xy 294.506196 -410.967467) (xy 294.499677 -410.984653) (xy 294.499284 -410.993844) (xy 294.499284 -411.151324)
			(xy 294.498834 -411.161436) (xy 294.491086 -411.180118) (xy 294.476778 -411.194413) (xy 294.458089 -411.202144)
			(xy 294.447976 -411.202632) (xy 293.731696 -411.202632) (xy 293.721591 -411.202119) (xy 293.702919 -411.194386)
			(xy 293.688625 -411.180098) (xy 293.680885 -411.161429) (xy 293.680388 -411.151324) (xy 293.680388 -410.993844)
			(xy 293.679959 -410.984659) (xy 293.673459 -410.967474) (xy 293.667688 -410.960316) (xy 293.645809 -410.934664)
			(xy 293.607721 -410.879027) (xy 293.576572 -410.819229) (xy 293.552809 -410.75613) (xy 293.536775 -410.69064)
			(xy 293.528701 -410.6237) (xy 290.250631 -410.6237) (xy 290.242595 -410.69046) (xy 290.226625 -410.755841)
			(xy 290.202956 -410.818845) (xy 290.171926 -410.878568) (xy 290.133982 -410.934155) (xy 290.112196 -410.959808)
			(xy 290.106413 -410.966963) (xy 290.09989 -410.984146) (xy 290.099496 -410.993336) (xy 290.099496 -411.151324)
			(xy 290.099098 -411.16148) (xy 290.091294 -411.180234) (xy 290.07689 -411.194557) (xy 290.058092 -411.202255)
			(xy 290.047934 -411.202632) (xy 289.331654 -411.202632) (xy 289.321521 -411.20221) (xy 289.302793 -411.194462)
			(xy 289.288438 -411.180156) (xy 289.280625 -411.161455) (xy 289.280092 -411.151324) (xy 289.280092 -410.993336)
			(xy 289.279666 -410.98415) (xy 289.273164 -410.966966) (xy 289.267392 -410.959808) (xy 289.245587 -410.934169)
			(xy 289.207635 -410.878582) (xy 289.1766 -410.818857) (xy 289.152925 -410.755851) (xy 289.136952 -410.690467)
			(xy 289.128908 -410.623642) (xy 237.026196 -410.623642) (xy 237.026196 -412.022036) (xy 237.025817 -412.032111)
			(xy 237.018067 -412.05071) (xy 237.01121 -412.058104) (xy 235.742988 -413.326326) (xy 235.735589 -413.333168)
			(xy 235.716989 -413.340886) (xy 235.70692 -413.341312) (xy 208.85277 -413.341312) (xy 208.842696 -413.340925)
			(xy 208.824097 -413.33318) (xy 208.816702 -413.326326) (xy 207.328262 -411.83814) (xy 207.321442 -411.830725)
			(xy 207.313712 -411.812137) (xy 207.313276 -411.802072) (xy 207.313276 -389.778748) (xy 207.312741 -389.766404)
			(xy 207.303453 -389.743532) (xy 207.295242 -389.734298) (xy 207.294734 -389.73379) (xy 204.725778 -387.165088)
			(xy 204.718937 -387.157689) (xy 204.711218 -387.139089) (xy 204.710792 -387.12902) (xy 204.710792 -374.725946)
			(xy 204.710253 -374.713602) (xy 204.700967 -374.690731) (xy 204.692758 -374.681496) (xy 204.69225 -374.680988)
			(xy 204.627226 -374.615964) (xy 204.620381 -374.608567) (xy 204.612664 -374.589966) (xy 204.61224 -374.579896)
			(xy 204.61224 -371.090444) (xy 204.611612 -371.07799) (xy 204.602074 -371.054978) (xy 204.593698 -371.04574)
			(xy 204.485494 -370.93779) (xy 204.478656 -370.930388) (xy 204.470935 -370.91179) (xy 204.470508 -370.901722)
			(xy 173.519592 -370.901722) (xy 173.519592 -371.386862) (xy 173.520022 -371.396047) (xy 173.526522 -371.413231)
			(xy 173.532292 -371.42039) (xy 173.554093 -371.446031) (xy 173.592039 -371.50162) (xy 173.62307 -371.561345)
			(xy 173.646506 -371.623725) (xy 174.74915 -371.623725) (xy 174.749154 -371.556417) (xy 174.757201 -371.489592)
			(xy 174.773178 -371.424208) (xy 174.796855 -371.361202) (xy 174.827893 -371.301477) (xy 174.865846 -371.24589)
			(xy 174.887636 -371.220238) (xy 174.893446 -371.213102) (xy 174.899952 -371.195904) (xy 174.900336 -371.18671)
			(xy 174.900336 -371.028722) (xy 174.900782 -371.018552) (xy 174.908559 -370.999758) (xy 174.922938 -370.985373)
			(xy 174.941728 -370.977587) (xy 174.951898 -370.97716) (xy 175.668178 -370.97716) (xy 175.678351 -370.977583)
			(xy 175.697149 -370.985364) (xy 175.711536 -370.999751) (xy 175.719317 -371.018549) (xy 175.71974 -371.028722)
			(xy 175.71974 -371.18671) (xy 175.720159 -371.195896) (xy 175.726668 -371.21308) (xy 175.73244 -371.220238)
			(xy 175.754191 -371.245921) (xy 175.792142 -371.301502) (xy 175.823178 -371.361221) (xy 175.846854 -371.424222)
			(xy 175.86283 -371.489601) (xy 175.870878 -371.55642) (xy 175.870881 -371.623723) (xy 175.862841 -371.690543)
			(xy 175.846871 -371.755923) (xy 175.823202 -371.818926) (xy 175.792172 -371.878649) (xy 175.754226 -371.934234)
			(xy 175.73244 -371.959886) (xy 175.726617 -371.967012) (xy 175.72012 -371.984218) (xy 175.71974 -371.993414)
			(xy 175.71974 -372.486682) (xy 175.720172 -372.495867) (xy 175.726672 -372.51305) (xy 175.73244 -372.52021)
			(xy 175.754262 -372.545834) (xy 175.792211 -372.601424) (xy 175.823244 -372.661151) (xy 175.846916 -372.72416)
			(xy 175.862887 -372.789545) (xy 175.870929 -372.856371) (xy 175.870926 -372.92368) (xy 175.862878 -372.990505)
			(xy 175.846901 -373.055889) (xy 175.823223 -373.118895) (xy 175.792185 -373.17862) (xy 175.754231 -373.234206)
			(xy 175.73244 -373.259858) (xy 175.726629 -373.266993) (xy 175.720125 -373.284191) (xy 175.71974 -373.293386)
			(xy 175.71974 -373.451374) (xy 175.719314 -373.461547) (xy 175.711534 -373.480345) (xy 175.697148 -373.494731)
			(xy 175.678351 -373.502513) (xy 175.668178 -373.502936) (xy 174.951898 -373.502936) (xy 174.941723 -373.502537)
			(xy 174.922923 -373.494747) (xy 174.908538 -373.480353) (xy 174.900757 -373.461549) (xy 174.900336 -373.451374)
			(xy 174.900336 -373.293386) (xy 174.899925 -373.284199) (xy 174.893411 -373.267015) (xy 174.887636 -373.259858)
			(xy 174.865882 -373.234178) (xy 174.827932 -373.178596) (xy 174.796898 -373.118876) (xy 174.773223 -373.055875)
			(xy 174.757248 -372.990496) (xy 174.749201 -372.923677) (xy 174.749198 -372.856374) (xy 174.757239 -372.789554)
			(xy 174.773208 -372.724174) (xy 174.796877 -372.661171) (xy 174.827906 -372.601448) (xy 174.865851 -372.545862)
			(xy 174.887636 -372.52021) (xy 174.893458 -372.513083) (xy 174.899957 -372.495878) (xy 174.900336 -372.486682)
			(xy 174.900336 -371.993414) (xy 174.899911 -371.984229) (xy 174.893407 -371.967044) (xy 174.887636 -371.959886)
			(xy 174.865811 -371.934265) (xy 174.827863 -371.878674) (xy 174.796832 -371.818946) (xy 174.773161 -371.755937)
			(xy 174.757191 -371.690551) (xy 174.74915 -371.623725) (xy 173.646506 -371.623725) (xy 173.646741 -371.624351)
			(xy 173.662712 -371.689734) (xy 173.670754 -371.756558) (xy 173.670753 -371.823863) (xy 173.662708 -371.890686)
			(xy 173.646734 -371.956069) (xy 173.623061 -372.019074) (xy 173.592028 -372.078798) (xy 173.55408 -372.134385)
			(xy 173.532292 -372.160038) (xy 173.526496 -372.167183) (xy 173.519981 -372.184374) (xy 173.519592 -372.193566)
			(xy 173.519592 -372.351554) (xy 173.519099 -372.361719) (xy 173.511335 -372.380507) (xy 173.496971 -372.394892)
			(xy 173.478194 -372.402684) (xy 173.46803 -372.403116) (xy 172.75175 -372.403116) (xy 172.741576 -372.402694)
			(xy 172.722773 -372.394917) (xy 172.708385 -372.38053) (xy 172.700607 -372.361728) (xy 172.700188 -372.351554)
			(xy 172.700188 -372.193566) (xy 172.699797 -372.184377) (xy 172.69327 -372.167192) (xy 172.687488 -372.160038)
			(xy 172.665713 -372.134375) (xy 172.62776 -372.078791) (xy 172.596724 -372.01907) (xy 172.573048 -371.956067)
			(xy 172.557072 -371.890685) (xy 172.549026 -371.823863) (xy 172.549025 -371.756558) (xy 172.557069 -371.689736)
			(xy 172.573042 -371.624354) (xy 172.596715 -371.561349) (xy 172.627749 -371.501627) (xy 172.6657 -371.446041)
			(xy 172.687488 -371.42039) (xy 172.69327 -371.413234) (xy 172.699794 -371.396052) (xy 172.700188 -371.386862)
			(xy 172.700188 -370.89334) (xy 172.699761 -370.884154) (xy 172.69326 -370.86697) (xy 172.687488 -370.859812)
			(xy 172.665687 -370.83417) (xy 172.627735 -370.778583) (xy 172.5967 -370.718859) (xy 172.573026 -370.655853)
			(xy 172.557052 -370.590469) (xy 172.549008 -370.523644) (xy 169.270946 -370.523644) (xy 169.262904 -370.590464)
			(xy 169.246933 -370.655845) (xy 169.223264 -370.718849) (xy 169.192234 -370.778572) (xy 169.15429 -370.834159)
			(xy 169.132504 -370.859812) (xy 169.12672 -370.866966) (xy 169.120198 -370.88415) (xy 169.119804 -370.89334)
			(xy 169.119804 -371.386862) (xy 169.120231 -371.396047) (xy 169.126733 -371.413232) (xy 169.132504 -371.42039)
			(xy 169.154304 -371.446031) (xy 169.19225 -371.50162) (xy 169.22328 -371.561346) (xy 169.246737 -371.623785)
			(xy 170.348831 -371.623785) (xy 170.348834 -371.556358) (xy 170.356914 -371.489416) (xy 170.372955 -371.423924)
			(xy 170.396726 -371.360825) (xy 170.427884 -371.301029) (xy 170.46598 -371.245394) (xy 170.487848 -371.21973)
			(xy 170.493663 -371.212598) (xy 170.500165 -371.195397) (xy 170.500548 -371.186202) (xy 170.500548 -371.028722)
			(xy 170.501045 -371.018596) (xy 170.508767 -370.999873) (xy 170.52305 -370.985516) (xy 170.541732 -370.977698)
			(xy 170.551856 -370.97716) (xy 171.268136 -370.97716) (xy 171.278287 -370.977591) (xy 171.297033 -370.985391)
			(xy 171.311354 -370.999784) (xy 171.319059 -371.018568) (xy 171.319444 -371.028722) (xy 171.319444 -371.186202)
			(xy 171.319866 -371.195388) (xy 171.326373 -371.212571) (xy 171.332144 -371.21973) (xy 171.353973 -371.245425)
			(xy 171.392066 -371.301054) (xy 171.423222 -371.360846) (xy 171.44699 -371.423939) (xy 171.46303 -371.489425)
			(xy 171.47111 -371.556361) (xy 171.471113 -371.623782) (xy 171.46304 -371.690719) (xy 171.447007 -371.756207)
			(xy 171.423245 -371.819302) (xy 171.392096 -371.879097) (xy 171.354008 -371.93473) (xy 171.332144 -371.960394)
			(xy 171.326361 -371.967548) (xy 171.31984 -371.984732) (xy 171.319444 -371.993922) (xy 171.319444 -372.486174)
			(xy 171.319879 -372.495358) (xy 171.326377 -372.512542) (xy 171.332144 -372.519702) (xy 171.354043 -372.545339)
			(xy 171.392135 -372.600976) (xy 171.423287 -372.660776) (xy 171.447052 -372.723876) (xy 171.463087 -372.789369)
			(xy 171.471161 -372.856312) (xy 171.471158 -372.923739) (xy 171.463077 -372.990681) (xy 171.447037 -373.056172)
			(xy 171.423266 -373.119271) (xy 171.392108 -373.179068) (xy 171.354012 -373.234702) (xy 171.332144 -373.260366)
			(xy 171.32633 -373.267499) (xy 171.319827 -373.284699) (xy 171.319444 -373.293894) (xy 171.319444 -373.451374)
			(xy 171.318952 -373.461501) (xy 171.31123 -373.480225) (xy 171.296945 -373.494583) (xy 171.27826 -373.5024)
			(xy 171.268136 -373.502936) (xy 170.551856 -373.502936) (xy 170.541704 -373.502515) (xy 170.522957 -373.494712)
			(xy 170.508637 -373.480316) (xy 170.500932 -373.461529) (xy 170.500548 -373.451374) (xy 170.500548 -373.293894)
			(xy 170.50013 -373.284708) (xy 170.493621 -373.267524) (xy 170.487848 -373.260366) (xy 170.466016 -373.234674)
			(xy 170.427923 -373.179044) (xy 170.396768 -373.119252) (xy 170.373 -373.056159) (xy 170.356961 -372.990673)
			(xy 170.348881 -372.923736) (xy 170.348878 -372.856315) (xy 170.356951 -372.789378) (xy 170.372985 -372.72389)
			(xy 170.396747 -372.660794) (xy 170.427897 -372.600999) (xy 170.465984 -372.545366) (xy 170.487848 -372.519702)
			(xy 170.493632 -372.512548) (xy 170.500153 -372.495364) (xy 170.500548 -372.486174) (xy 170.500548 -371.993922)
			(xy 170.500117 -371.984737) (xy 170.493617 -371.967553) (xy 170.487848 -371.960394) (xy 170.465945 -371.93476)
			(xy 170.427854 -371.879122) (xy 170.396703 -371.819322) (xy 170.372938 -371.756221) (xy 170.356904 -371.690728)
			(xy 170.348831 -371.623785) (xy 169.246737 -371.623785) (xy 169.24695 -371.624352) (xy 169.262921 -371.689735)
			(xy 169.270963 -371.756558) (xy 169.270962 -371.823863) (xy 169.262917 -371.890686) (xy 169.246944 -371.956068)
			(xy 169.223271 -372.019073) (xy 169.192239 -372.078798) (xy 169.154291 -372.134385) (xy 169.132504 -372.160038)
			(xy 169.126709 -372.167185) (xy 169.120193 -372.184374) (xy 169.119804 -372.193566) (xy 169.119804 -372.351554)
			(xy 169.1193 -372.361717) (xy 169.111537 -372.380503) (xy 169.097177 -372.394888) (xy 169.078405 -372.402682)
			(xy 169.068242 -372.403116) (xy 168.351962 -372.403116) (xy 168.341782 -372.402766) (xy 168.322978 -372.39496)
			(xy 168.308593 -372.380552) (xy 168.300817 -372.361734) (xy 168.3004 -372.351554) (xy 168.3004 -372.193566)
			(xy 168.300006 -372.184377) (xy 168.293481 -372.167193) (xy 168.2877 -372.160038) (xy 168.265927 -372.134374)
			(xy 168.227981 -372.078788) (xy 168.196949 -372.019066) (xy 168.173277 -371.956063) (xy 168.157304 -371.890683)
			(xy 168.14926 -371.823862) (xy 168.149258 -371.756559) (xy 168.1573 -371.689738) (xy 168.173271 -371.624357)
			(xy 168.19694 -371.561353) (xy 168.22797 -371.50163) (xy 168.265914 -371.446043) (xy 168.2877 -371.42039)
			(xy 168.293483 -371.413235) (xy 168.300006 -371.396052) (xy 168.3004 -371.386862) (xy 168.3004 -370.89334)
			(xy 168.299971 -370.884155) (xy 168.29347 -370.86697) (xy 168.2877 -370.859812) (xy 168.265902 -370.834169)
			(xy 168.227956 -370.77858) (xy 168.196925 -370.718855) (xy 168.173255 -370.65585) (xy 168.157284 -370.590467)
			(xy 168.149241 -370.523644) (xy 164.871178 -370.523644) (xy 164.871178 -370.523702) (xy 164.863103 -370.59064)
			(xy 164.847069 -370.656128) (xy 164.823307 -370.719224) (xy 164.792158 -370.77902) (xy 164.754071 -370.834655)
			(xy 164.732208 -370.86032) (xy 164.726421 -370.867472) (xy 164.7199 -370.884657) (xy 164.719508 -370.893848)
			(xy 164.719508 -371.386354) (xy 164.719938 -371.395539) (xy 164.726438 -371.412724) (xy 164.732208 -371.419882)
			(xy 164.754085 -371.445536) (xy 164.792173 -371.501172) (xy 164.823323 -371.56097) (xy 164.846957 -371.623726)
			(xy 165.949062 -371.623726) (xy 165.949066 -371.556417) (xy 165.957114 -371.489592) (xy 165.973091 -371.424207)
			(xy 165.996769 -371.361201) (xy 166.027807 -371.301477) (xy 166.065761 -371.24589) (xy 166.087552 -371.220238)
			(xy 166.093364 -371.213104) (xy 166.099868 -371.195905) (xy 166.100252 -371.18671) (xy 166.100252 -371.028722)
			(xy 166.100682 -371.01855) (xy 166.108463 -370.999753) (xy 166.122847 -370.985367) (xy 166.141642 -370.977584)
			(xy 166.151814 -370.97716) (xy 166.868094 -370.97716) (xy 166.878268 -370.977569) (xy 166.897067 -370.985356)
			(xy 166.911453 -370.999747) (xy 166.919234 -371.018548) (xy 166.919656 -371.028722) (xy 166.919656 -371.18671)
			(xy 166.920071 -371.195896) (xy 166.926582 -371.21308) (xy 166.932356 -371.220238) (xy 166.954106 -371.245921)
			(xy 166.992057 -371.301503) (xy 167.023092 -371.361222) (xy 167.046767 -371.424223) (xy 167.062743 -371.489601)
			(xy 167.07079 -371.55642) (xy 167.070793 -371.623722) (xy 167.062753 -371.690543) (xy 167.046784 -371.755923)
			(xy 167.023115 -371.818926) (xy 166.992086 -371.878648) (xy 166.954141 -371.934234) (xy 166.932356 -371.959886)
			(xy 166.926535 -371.967014) (xy 166.920036 -371.984218) (xy 166.919656 -371.993414) (xy 166.919656 -372.486682)
			(xy 166.920085 -372.495867) (xy 166.926586 -372.513051) (xy 166.932356 -372.52021) (xy 166.954177 -372.545834)
			(xy 166.992126 -372.601425) (xy 167.023158 -372.661152) (xy 167.046829 -372.72416) (xy 167.0628 -372.789546)
			(xy 167.070841 -372.856372) (xy 167.070838 -372.923679) (xy 167.06279 -372.990504) (xy 167.046814 -373.055889)
			(xy 167.023137 -373.118895) (xy 166.992099 -373.178619) (xy 166.954146 -373.234206) (xy 166.932356 -373.259858)
			(xy 166.926547 -373.266994) (xy 166.920041 -373.284192) (xy 166.919656 -373.293386) (xy 166.919656 -373.451374)
			(xy 166.919215 -373.461545) (xy 166.911437 -373.48034) (xy 166.897057 -373.494726) (xy 166.878264 -373.502511)
			(xy 166.868094 -373.502936) (xy 166.151814 -373.502936) (xy 166.14164 -373.502524) (xy 166.122841 -373.494739)
			(xy 166.108454 -373.480349) (xy 166.100673 -373.461548) (xy 166.100252 -373.451374) (xy 166.100252 -373.293386)
			(xy 166.099837 -373.2842) (xy 166.093325 -373.267016) (xy 166.087552 -373.259858) (xy 166.065797 -373.234178)
			(xy 166.027847 -373.178596) (xy 165.996811 -373.118877) (xy 165.973136 -373.055876) (xy 165.95716 -372.990497)
			(xy 165.949113 -372.923677) (xy 165.94911 -372.856374) (xy 165.957151 -372.789554) (xy 165.973121 -372.724173)
			(xy 165.99679 -372.66117) (xy 166.02782 -372.601448) (xy 166.065766 -372.545862) (xy 166.087552 -372.52021)
			(xy 166.093376 -372.513084) (xy 166.099873 -372.495879) (xy 166.100252 -372.486682) (xy 166.100252 -371.993414)
			(xy 166.099824 -371.984229) (xy 166.093321 -371.967045) (xy 166.087552 -371.959886) (xy 166.065726 -371.934265)
			(xy 166.027778 -371.878674) (xy 165.996745 -371.818947) (xy 165.973074 -371.755938) (xy 165.957104 -371.690552)
			(xy 165.949062 -371.623726) (xy 164.846957 -371.623726) (xy 164.847086 -371.624068) (xy 164.86312 -371.689559)
			(xy 164.871195 -371.756498) (xy 164.871194 -371.823923) (xy 164.863116 -371.890862) (xy 164.84708 -371.956352)
			(xy 164.823314 -372.019449) (xy 164.792162 -372.079246) (xy 164.754073 -372.134881) (xy 164.732208 -372.160546)
			(xy 164.72641 -372.16769) (xy 164.719896 -372.184881) (xy 164.719508 -372.194074) (xy 164.719508 -372.351554)
			(xy 164.718937 -372.361672) (xy 164.711233 -372.380383) (xy 164.696973 -372.394739) (xy 164.678314 -372.402568)
			(xy 164.6682 -372.403116) (xy 163.95192 -372.403116) (xy 163.941769 -372.402662) (xy 163.92302 -372.394876)
			(xy 163.908697 -372.38049) (xy 163.900993 -372.361707) (xy 163.900612 -372.351554) (xy 163.900612 -372.194074)
			(xy 163.900212 -372.184886) (xy 163.893691 -372.167702) (xy 163.887912 -372.160546) (xy 163.866061 -372.13487)
			(xy 163.827971 -372.079237) (xy 163.796819 -372.019442) (xy 163.773054 -371.956347) (xy 163.757017 -371.890859)
			(xy 163.74894 -371.823922) (xy 163.748939 -371.756499) (xy 163.757013 -371.689562) (xy 163.773048 -371.624073)
			(xy 163.796811 -371.560977) (xy 163.827961 -371.501181) (xy 163.866048 -371.445547) (xy 163.887912 -371.419882)
			(xy 163.8937 -371.412731) (xy 163.900219 -371.395545) (xy 163.900612 -371.386354) (xy 163.900612 -370.893848)
			(xy 163.900176 -370.884664) (xy 163.89368 -370.867479) (xy 163.887912 -370.86032) (xy 163.866036 -370.834665)
			(xy 163.827947 -370.779029) (xy 163.796796 -370.719232) (xy 163.773032 -370.656133) (xy 163.756997 -370.590643)
			(xy 163.748922 -370.523703) (xy 160.470875 -370.523703) (xy 160.462839 -370.590466) (xy 160.446866 -370.655848)
			(xy 160.423192 -370.718852) (xy 160.392158 -370.778575) (xy 160.354208 -370.83416) (xy 160.33242 -370.859812)
			(xy 160.326638 -370.866968) (xy 160.320114 -370.88415) (xy 160.31972 -370.89334) (xy 160.31972 -371.386862)
			(xy 160.320144 -371.396048) (xy 160.326647 -371.413233) (xy 160.33242 -371.42039) (xy 160.354223 -371.44603)
			(xy 160.392174 -371.501618) (xy 160.423209 -371.561342) (xy 160.44667 -371.623784) (xy 161.548767 -371.623784)
			(xy 161.548771 -371.556358) (xy 161.55685 -371.489418) (xy 161.572888 -371.423928) (xy 161.596655 -371.360829)
			(xy 161.627808 -371.301032) (xy 161.665899 -371.245396) (xy 161.687764 -371.21973) (xy 161.693581 -371.212599)
			(xy 161.700082 -371.195397) (xy 161.700464 -371.186202) (xy 161.700464 -371.028722) (xy 161.700945 -371.018594)
			(xy 161.70867 -370.999868) (xy 161.722959 -370.985511) (xy 161.741646 -370.977695) (xy 161.751772 -370.97716)
			(xy 162.468052 -370.97716) (xy 162.478166 -370.977654) (xy 162.496861 -370.985379) (xy 162.511176 -370.999671)
			(xy 162.51893 -371.018354) (xy 162.51936 -371.028468) (xy 162.51936 -371.186202) (xy 162.519778 -371.195388)
			(xy 162.526287 -371.212572) (xy 162.53206 -371.21973) (xy 162.553888 -371.245425) (xy 162.591981 -371.301055)
			(xy 162.623135 -371.360846) (xy 162.646903 -371.423939) (xy 162.662942 -371.489425) (xy 162.671022 -371.556361)
			(xy 162.671025 -371.623782) (xy 162.662953 -371.690719) (xy 162.64692 -371.756206) (xy 162.623158 -371.819302)
			(xy 162.59201 -371.879096) (xy 162.553923 -371.934729) (xy 162.53206 -371.960394) (xy 162.526278 -371.96755)
			(xy 162.519756 -371.984732) (xy 162.51936 -371.993922) (xy 162.51936 -372.486174) (xy 162.519791 -372.495359)
			(xy 162.526291 -372.512543) (xy 162.53206 -372.519702) (xy 162.553959 -372.545339) (xy 162.592049 -372.600977)
			(xy 162.623201 -372.660776) (xy 162.646965 -372.723877) (xy 162.662999 -372.78937) (xy 162.671073 -372.856312)
			(xy 162.67107 -372.923739) (xy 162.66299 -372.99068) (xy 162.646949 -373.056172) (xy 162.62318 -373.11927)
			(xy 162.592023 -373.179067) (xy 162.553927 -373.234701) (xy 162.53206 -373.260366) (xy 162.526248 -373.2675)
			(xy 162.519743 -373.284699) (xy 162.51936 -373.293894) (xy 162.51936 -373.451374) (xy 162.518852 -373.461499)
			(xy 162.511133 -373.48022) (xy 162.496853 -373.494577) (xy 162.478174 -373.502397) (xy 162.468052 -373.502936)
			(xy 161.751772 -373.502936) (xy 161.741666 -373.502439) (xy 161.722994 -373.494699) (xy 161.708701 -373.480406)
			(xy 161.700961 -373.461734) (xy 161.700464 -373.451628) (xy 161.700464 -373.293894) (xy 161.700042 -373.284708)
			(xy 161.693535 -373.267525) (xy 161.687764 -373.260366) (xy 161.665935 -373.234673) (xy 161.627847 -373.179041)
			(xy 161.596697 -373.119249) (xy 161.572933 -373.056155) (xy 161.556896 -372.99067) (xy 161.548818 -372.923736)
			(xy 161.548815 -372.856315) (xy 161.556887 -372.78938) (xy 161.572918 -372.723893) (xy 161.596676 -372.660798)
			(xy 161.627821 -372.601003) (xy 161.665903 -372.545368) (xy 161.687764 -372.519702) (xy 161.69355 -372.51255)
			(xy 161.700069 -372.495364) (xy 161.700464 -372.486174) (xy 161.700464 -371.993922) (xy 161.700029 -371.984738)
			(xy 161.693531 -371.967554) (xy 161.687764 -371.960394) (xy 161.665864 -371.934759) (xy 161.627779 -371.879119)
			(xy 161.596632 -371.819319) (xy 161.572871 -371.756218) (xy 161.55684 -371.690725) (xy 161.548767 -371.623784)
			(xy 160.44667 -371.623784) (xy 160.446882 -371.624348) (xy 160.462856 -371.689733) (xy 160.470899 -371.756557)
			(xy 160.470898 -371.823864) (xy 160.462852 -371.890688) (xy 160.446876 -371.956072) (xy 160.4232 -372.019077)
			(xy 160.392163 -372.078801) (xy 160.35421 -372.134386) (xy 160.33242 -372.160038) (xy 160.326627 -372.167186)
			(xy 160.32011 -372.184374) (xy 160.31972 -372.193566) (xy 160.31972 -372.351554) (xy 160.319297 -372.361728)
			(xy 160.31152 -372.38053) (xy 160.297133 -372.394918) (xy 160.278332 -372.402697) (xy 160.268158 -372.403116)
			(xy 159.551878 -372.403116) (xy 159.541699 -372.402753) (xy 159.522895 -372.394952) (xy 159.50851 -372.380547)
			(xy 159.500734 -372.361733) (xy 159.500316 -372.351554) (xy 159.500316 -372.193566) (xy 159.499919 -372.184378)
			(xy 159.493396 -372.167193) (xy 159.487616 -372.160038) (xy 159.465843 -372.134374) (xy 159.427895 -372.078789)
			(xy 159.396862 -372.019067) (xy 159.37319 -371.956064) (xy 159.357216 -371.890683) (xy 159.349172 -371.823862)
			(xy 159.34917 -371.756559) (xy 159.357213 -371.689738) (xy 159.373184 -371.624356) (xy 159.396854 -371.561353)
			(xy 159.427884 -371.501629) (xy 159.46583 -371.446042) (xy 159.487616 -371.42039) (xy 159.493401 -371.413237)
			(xy 159.499922 -371.396052) (xy 159.500316 -371.386862) (xy 159.500316 -370.89334) (xy 159.499883 -370.884155)
			(xy 159.493385 -370.866971) (xy 159.487616 -370.859812) (xy 159.465817 -370.834169) (xy 159.42787 -370.778581)
			(xy 159.396839 -370.718856) (xy 159.373168 -370.65585) (xy 159.357196 -370.590467) (xy 159.349153 -370.523644)
			(xy 129.670828 -370.523644) (xy 129.662785 -370.590464) (xy 129.646814 -370.655846) (xy 129.623143 -370.71885)
			(xy 129.592113 -370.778573) (xy 129.554166 -370.83416) (xy 129.53238 -370.859812) (xy 129.526594 -370.866964)
			(xy 129.520073 -370.884149) (xy 129.51968 -370.89334) (xy 129.51968 -371.386862) (xy 129.520113 -371.396047)
			(xy 129.526611 -371.413231) (xy 129.53238 -371.42039) (xy 129.554181 -371.446031) (xy 129.592128 -371.50162)
			(xy 129.62316 -371.561345) (xy 129.646596 -371.623725) (xy 130.749241 -371.623725) (xy 130.749245 -371.556418)
			(xy 130.757292 -371.489593) (xy 130.773269 -371.424208) (xy 130.796945 -371.361202) (xy 130.827982 -371.301478)
			(xy 130.865934 -371.24589) (xy 130.887724 -371.220238) (xy 130.893532 -371.213101) (xy 130.900039 -371.195904)
			(xy 130.900424 -371.18671) (xy 130.900424 -371.028722) (xy 130.900882 -371.018554) (xy 130.908657 -370.999762)
			(xy 130.923032 -370.985377) (xy 130.941818 -370.977589) (xy 130.951986 -370.97716) (xy 131.668266 -370.97716)
			(xy 131.678438 -370.977592) (xy 131.697236 -370.98537) (xy 131.711623 -370.999754) (xy 131.719405 -371.01855)
			(xy 131.719828 -371.028722) (xy 131.719828 -371.18671) (xy 131.720227 -371.195898) (xy 131.726748 -371.213083)
			(xy 131.732528 -371.220238) (xy 131.754279 -371.24592) (xy 131.792231 -371.301502) (xy 131.823268 -371.361221)
			(xy 131.846945 -371.424221) (xy 131.862921 -371.4896) (xy 131.870969 -371.55642) (xy 131.870972 -371.623723)
			(xy 131.862931 -371.690543) (xy 131.846961 -371.755924) (xy 131.823291 -371.818927) (xy 131.792261 -371.878649)
			(xy 131.754314 -371.934234) (xy 131.732528 -371.959886) (xy 131.726704 -371.967011) (xy 131.720208 -371.984217)
			(xy 131.719828 -371.993414) (xy 131.719828 -372.486682) (xy 131.72024 -372.495869) (xy 131.726752 -372.513054)
			(xy 131.732528 -372.52021) (xy 131.75435 -372.545834) (xy 131.7923 -372.601424) (xy 131.823334 -372.661151)
			(xy 131.847006 -372.724159) (xy 131.862978 -372.789545) (xy 131.87102 -372.856371) (xy 131.871017 -372.92368)
			(xy 131.862969 -372.990505) (xy 131.846991 -373.05589) (xy 131.823313 -373.118896) (xy 131.792274 -373.17862)
			(xy 131.754319 -373.234206) (xy 131.732528 -373.259858) (xy 131.726716 -373.266992) (xy 131.720212 -373.284191)
			(xy 131.719828 -373.293386) (xy 131.719828 -373.451374) (xy 131.719414 -373.461548) (xy 131.711631 -373.480349)
			(xy 131.697242 -373.494736) (xy 131.67844 -373.502515) (xy 131.668266 -373.502936) (xy 130.951986 -373.502936)
			(xy 130.94181 -373.502547) (xy 130.92301 -373.494752) (xy 130.908625 -373.480356) (xy 130.900845 -373.46155)
			(xy 130.900424 -373.451374) (xy 130.900424 -373.293386) (xy 130.900015 -373.284199) (xy 130.8935 -373.267015)
			(xy 130.887724 -373.259858) (xy 130.86597 -373.234178) (xy 130.828022 -373.178595) (xy 130.796988 -373.118875)
			(xy 130.773314 -373.055874) (xy 130.757339 -372.990496) (xy 130.749292 -372.923677) (xy 130.749289 -372.856375)
			(xy 130.75733 -372.789555) (xy 130.773299 -372.724174) (xy 130.796967 -372.661171) (xy 130.827995 -372.601449)
			(xy 130.865939 -372.545863) (xy 130.887724 -372.52021) (xy 130.893544 -372.513082) (xy 130.900044 -372.495878)
			(xy 130.900424 -372.486682) (xy 130.900424 -371.993414) (xy 130.900002 -371.984228) (xy 130.893496 -371.967044)
			(xy 130.887724 -371.959886) (xy 130.865899 -371.934264) (xy 130.827953 -371.878673) (xy 130.796922 -371.818945)
			(xy 130.773252 -371.755937) (xy 130.757282 -371.690551) (xy 130.749241 -371.623725) (xy 129.646596 -371.623725)
			(xy 129.646831 -371.624351) (xy 129.662802 -371.689734) (xy 129.670845 -371.756558) (xy 129.670844 -371.823863)
			(xy 129.662799 -371.890687) (xy 129.646825 -371.956069) (xy 129.623151 -372.019074) (xy 129.592117 -372.078799)
			(xy 129.554168 -372.134386) (xy 129.53238 -372.160038) (xy 129.526582 -372.167182) (xy 129.520069 -372.184374)
			(xy 129.51968 -372.193566) (xy 129.51968 -372.351554) (xy 129.519199 -372.36172) (xy 129.511432 -372.380511)
			(xy 129.497064 -372.394896) (xy 129.478284 -372.402686) (xy 129.468118 -372.403116) (xy 128.751838 -372.403116)
			(xy 128.741663 -372.402704) (xy 128.722861 -372.394923) (xy 128.708473 -372.380533) (xy 128.700695 -372.361729)
			(xy 128.700276 -372.351554) (xy 128.700276 -372.193566) (xy 128.699887 -372.184376) (xy 128.693359 -372.167192)
			(xy 128.687576 -372.160038) (xy 128.665801 -372.134375) (xy 128.627849 -372.078791) (xy 128.596813 -372.019069)
			(xy 128.573138 -371.956066) (xy 128.557163 -371.890685) (xy 128.549117 -371.823863) (xy 128.549116 -371.756558)
			(xy 128.557159 -371.689736) (xy 128.573132 -371.624354) (xy 128.596805 -371.56135) (xy 128.627838 -371.501627)
			(xy 128.665788 -371.446042) (xy 128.687576 -371.42039) (xy 128.693357 -371.413233) (xy 128.699882 -371.396052)
			(xy 128.700276 -371.386862) (xy 128.700276 -370.89334) (xy 128.699852 -370.884154) (xy 128.693349 -370.866969)
			(xy 128.687576 -370.859812) (xy 128.665775 -370.83417) (xy 128.627825 -370.778583) (xy 128.59679 -370.718858)
			(xy 128.573116 -370.655852) (xy 128.557143 -370.590469) (xy 128.549099 -370.523644) (xy 125.271037 -370.523644)
			(xy 125.262994 -370.590464) (xy 125.247024 -370.655845) (xy 125.223354 -370.718849) (xy 125.192323 -370.778573)
			(xy 125.154378 -370.834159) (xy 125.132592 -370.859812) (xy 125.126807 -370.866965) (xy 125.120286 -370.88415)
			(xy 125.119892 -370.89334) (xy 125.119892 -371.386862) (xy 125.120322 -371.396047) (xy 125.126822 -371.413231)
			(xy 125.132592 -371.42039) (xy 125.154393 -371.446031) (xy 125.192339 -371.50162) (xy 125.22337 -371.561345)
			(xy 125.246828 -371.623785) (xy 126.348921 -371.623785) (xy 126.348925 -371.556358) (xy 126.357005 -371.489416)
			(xy 126.373046 -371.423925) (xy 126.396816 -371.360826) (xy 126.427973 -371.301029) (xy 126.466069 -371.245395)
			(xy 126.487936 -371.21973) (xy 126.493749 -371.212597) (xy 126.500253 -371.195397) (xy 126.500636 -371.186202)
			(xy 126.500636 -371.028722) (xy 126.501144 -371.018597) (xy 126.508864 -370.999877) (xy 126.523144 -370.98552)
			(xy 126.541822 -370.9777) (xy 126.551944 -370.97716) (xy 127.268224 -370.97716) (xy 127.278375 -370.977601)
			(xy 127.29712 -370.985397) (xy 127.311441 -370.999787) (xy 127.319147 -371.018569) (xy 127.319532 -371.028722)
			(xy 127.319532 -371.186202) (xy 127.319956 -371.195387) (xy 127.326462 -371.212571) (xy 127.332232 -371.21973)
			(xy 127.354058 -371.245427) (xy 127.392145 -371.301057) (xy 127.423296 -371.36085) (xy 127.447061 -371.423942)
			(xy 127.463098 -371.489427) (xy 127.471176 -371.556361) (xy 127.47118 -371.623781) (xy 127.463108 -371.690717)
			(xy 127.447078 -371.756203) (xy 127.423319 -371.819298) (xy 127.392175 -371.879094) (xy 127.354093 -371.934728)
			(xy 127.332232 -371.960394) (xy 127.326447 -371.967547) (xy 127.319927 -371.984732) (xy 127.319532 -371.993922)
			(xy 127.319532 -372.486174) (xy 127.31997 -372.495358) (xy 127.326466 -372.512542) (xy 127.332232 -372.519702)
			(xy 127.354128 -372.54534) (xy 127.392214 -372.600979) (xy 127.423361 -372.66078) (xy 127.447122 -372.72388)
			(xy 127.463154 -372.789372) (xy 127.471227 -372.856313) (xy 127.471224 -372.923738) (xy 127.463145 -372.990678)
			(xy 127.447107 -373.056169) (xy 127.42334 -373.119267) (xy 127.392188 -373.179064) (xy 127.354097 -373.2347)
			(xy 127.332232 -373.260366) (xy 127.326417 -373.267498) (xy 127.319915 -373.284699) (xy 127.319532 -373.293894)
			(xy 127.319532 -373.451374) (xy 127.319051 -373.461503) (xy 127.311327 -373.480228) (xy 127.297038 -373.494587)
			(xy 127.27835 -373.502402) (xy 127.268224 -373.502936) (xy 126.551944 -373.502936) (xy 126.541797 -373.502443)
			(xy 126.523053 -373.494669) (xy 126.508729 -373.480294) (xy 126.501021 -373.461522) (xy 126.500636 -373.451374)
			(xy 126.500636 -373.293894) (xy 126.500221 -373.284708) (xy 126.49371 -373.267524) (xy 126.487936 -373.260366)
			(xy 126.466104 -373.234674) (xy 126.428012 -373.179044) (xy 126.396858 -373.119252) (xy 126.37309 -373.056158)
			(xy 126.357051 -372.990672) (xy 126.348972 -372.923736) (xy 126.348969 -372.856315) (xy 126.357042 -372.789378)
			(xy 126.373075 -372.72389) (xy 126.396837 -372.660795) (xy 126.427986 -372.601) (xy 126.466073 -372.545367)
			(xy 126.487936 -372.519702) (xy 126.493719 -372.512547) (xy 126.500241 -372.495364) (xy 126.500636 -372.486174)
			(xy 126.500636 -371.993922) (xy 126.500207 -371.984737) (xy 126.493706 -371.967553) (xy 126.487936 -371.960394)
			(xy 126.466033 -371.93476) (xy 126.427943 -371.879122) (xy 126.396792 -371.819322) (xy 126.373029 -371.756221)
			(xy 126.356995 -371.690727) (xy 126.348921 -371.623785) (xy 125.246828 -371.623785) (xy 125.247041 -371.624351)
			(xy 125.263012 -371.689734) (xy 125.271054 -371.756558) (xy 125.271053 -371.823863) (xy 125.263008 -371.890686)
			(xy 125.247034 -371.956069) (xy 125.223361 -372.019074) (xy 125.192328 -372.078798) (xy 125.15438 -372.134385)
			(xy 125.132592 -372.160038) (xy 125.126796 -372.167183) (xy 125.120281 -372.184374) (xy 125.119892 -372.193566)
			(xy 125.119892 -372.351554) (xy 125.119399 -372.361719) (xy 125.111635 -372.380507) (xy 125.097271 -372.394892)
			(xy 125.078494 -372.402684) (xy 125.06833 -372.403116) (xy 124.35205 -372.403116) (xy 124.341876 -372.402694)
			(xy 124.323073 -372.394917) (xy 124.308685 -372.38053) (xy 124.300907 -372.361728) (xy 124.300488 -372.351554)
			(xy 124.300488 -372.193566) (xy 124.300097 -372.184377) (xy 124.29357 -372.167192) (xy 124.287788 -372.160038)
			(xy 124.266013 -372.134375) (xy 124.22806 -372.078791) (xy 124.197024 -372.01907) (xy 124.173348 -371.956067)
			(xy 124.157372 -371.890685) (xy 124.149326 -371.823863) (xy 124.149325 -371.756558) (xy 124.157369 -371.689736)
			(xy 124.173342 -371.624354) (xy 124.197015 -371.561349) (xy 124.228049 -371.501627) (xy 124.266 -371.446041)
			(xy 124.287788 -371.42039) (xy 124.29357 -371.413234) (xy 124.300094 -371.396052) (xy 124.300488 -371.386862)
			(xy 124.300488 -370.89334) (xy 124.300061 -370.884154) (xy 124.29356 -370.86697) (xy 124.287788 -370.859812)
			(xy 124.265987 -370.83417) (xy 124.228035 -370.778583) (xy 124.197 -370.718859) (xy 124.173326 -370.655853)
			(xy 124.157352 -370.590469) (xy 124.149308 -370.523644) (xy 120.871269 -370.523644) (xy 120.871269 -370.523702)
			(xy 120.863194 -370.59064) (xy 120.847159 -370.656128) (xy 120.823396 -370.719225) (xy 120.792247 -370.779021)
			(xy 120.754159 -370.834655) (xy 120.732296 -370.86032) (xy 120.726508 -370.867471) (xy 120.719988 -370.884657)
			(xy 120.719596 -370.893848) (xy 120.719596 -371.386354) (xy 120.720029 -371.395539) (xy 120.726527 -371.412723)
			(xy 120.732296 -371.419882) (xy 120.754174 -371.445536) (xy 120.792262 -371.501172) (xy 120.823413 -371.56097)
			(xy 120.847047 -371.623725) (xy 121.949153 -371.623725) (xy 121.949157 -371.556417) (xy 121.957205 -371.489592)
			(xy 121.973182 -371.424208) (xy 121.996859 -371.361202) (xy 122.027896 -371.301477) (xy 122.06585 -371.24589)
			(xy 122.08764 -371.220238) (xy 122.09345 -371.213103) (xy 122.099956 -371.195904) (xy 122.10034 -371.18671)
			(xy 122.10034 -371.028722) (xy 122.100782 -371.018552) (xy 122.10856 -370.999757) (xy 122.12294 -370.985371)
			(xy 122.141732 -370.977586) (xy 122.151902 -370.97716) (xy 122.868182 -370.97716) (xy 122.878355 -370.977579)
			(xy 122.897154 -370.985362) (xy 122.91154 -370.99975) (xy 122.919322 -371.018549) (xy 122.919744 -371.028722)
			(xy 122.919744 -371.18671) (xy 122.920162 -371.195896) (xy 122.926672 -371.21308) (xy 122.932444 -371.220238)
			(xy 122.954195 -371.245921) (xy 122.992146 -371.301502) (xy 123.023182 -371.361222) (xy 123.046857 -371.424222)
			(xy 123.062833 -371.489601) (xy 123.070881 -371.55642) (xy 123.070884 -371.623723) (xy 123.062844 -371.690543)
			(xy 123.046874 -371.755923) (xy 123.023205 -371.818926) (xy 122.992175 -371.878648) (xy 122.95423 -371.934234)
			(xy 122.932444 -371.959886) (xy 122.926622 -371.967013) (xy 122.920124 -371.984218) (xy 122.919744 -371.993414)
			(xy 122.919744 -372.486682) (xy 122.920175 -372.495867) (xy 122.926676 -372.513051) (xy 122.932444 -372.52021)
			(xy 122.954266 -372.545834) (xy 122.992215 -372.601424) (xy 123.023248 -372.661152) (xy 123.046919 -372.72416)
			(xy 123.06289 -372.789546) (xy 123.070932 -372.856372) (xy 123.070929 -372.92368) (xy 123.062881 -372.990505)
			(xy 123.046904 -373.055889) (xy 123.023227 -373.118895) (xy 122.992188 -373.17862) (xy 122.954234 -373.234206)
			(xy 122.932444 -373.259858) (xy 122.926633 -373.266993) (xy 122.920129 -373.284192) (xy 122.919744 -373.293386)
			(xy 122.919744 -373.451374) (xy 122.919314 -373.461546) (xy 122.911534 -373.480344) (xy 122.89715 -373.49473)
			(xy 122.878354 -373.502513) (xy 122.868182 -373.502936) (xy 122.151902 -373.502936) (xy 122.141727 -373.502534)
			(xy 122.122928 -373.494745) (xy 122.108542 -373.480352) (xy 122.100761 -373.461549) (xy 122.10034 -373.451374)
			(xy 122.10034 -373.293386) (xy 122.099928 -373.284199) (xy 122.093415 -373.267015) (xy 122.08764 -373.259858)
			(xy 122.065886 -373.234178) (xy 122.027936 -373.178596) (xy 121.996901 -373.118876) (xy 121.973226 -373.055875)
			(xy 121.957251 -372.990496) (xy 121.949204 -372.923677) (xy 121.949201 -372.856374) (xy 121.957242 -372.789554)
			(xy 121.973211 -372.724174) (xy 121.99688 -372.661171) (xy 122.02791 -372.601448) (xy 122.065855 -372.545862)
			(xy 122.08764 -372.52021) (xy 122.093462 -372.513083) (xy 122.099961 -372.495878) (xy 122.10034 -372.486682)
			(xy 122.10034 -371.993414) (xy 122.099914 -371.984229) (xy 122.093411 -371.967045) (xy 122.08764 -371.959886)
			(xy 122.065815 -371.934265) (xy 122.027867 -371.878674) (xy 121.996835 -371.818946) (xy 121.973165 -371.755937)
			(xy 121.957194 -371.690551) (xy 121.949153 -371.623725) (xy 120.847047 -371.623725) (xy 120.847176 -371.624068)
			(xy 120.863211 -371.689558) (xy 120.871286 -371.756498) (xy 120.871284 -371.823923) (xy 120.863207 -371.890862)
			(xy 120.84717 -371.956352) (xy 120.823404 -372.01945) (xy 120.792252 -372.079246) (xy 120.754161 -372.134881)
			(xy 120.732296 -372.160546) (xy 120.726497 -372.167689) (xy 120.719984 -372.184881) (xy 120.719596 -372.194074)
			(xy 120.719596 -372.351554) (xy 120.719037 -372.361673) (xy 120.711331 -372.380387) (xy 120.697067 -372.394743)
			(xy 120.678404 -372.40257) (xy 120.668288 -372.403116) (xy 119.952008 -372.403116) (xy 119.941856 -372.402672)
			(xy 119.923107 -372.394882) (xy 119.908784 -372.380493) (xy 119.901081 -372.361707) (xy 119.9007 -372.351554)
			(xy 119.9007 -372.194074) (xy 119.900303 -372.184885) (xy 119.89378 -372.167701) (xy 119.888 -372.160546)
			(xy 119.86615 -372.134869) (xy 119.828061 -372.079237) (xy 119.796909 -372.019442) (xy 119.773144 -371.956346)
			(xy 119.757108 -371.890859) (xy 119.749031 -371.823922) (xy 119.74903 -371.756499) (xy 119.757104 -371.689562)
			(xy 119.773138 -371.624074) (xy 119.796901 -371.560977) (xy 119.82805 -371.501182) (xy 119.866137 -371.445547)
			(xy 119.888 -371.419882) (xy 119.893787 -371.41273) (xy 119.900307 -371.395545) (xy 119.9007 -371.386354)
			(xy 119.9007 -370.893848) (xy 119.900267 -370.884663) (xy 119.893769 -370.867479) (xy 119.888 -370.86032)
			(xy 119.866124 -370.834664) (xy 119.828036 -370.779029) (xy 119.796886 -370.719231) (xy 119.773122 -370.656133)
			(xy 119.757088 -370.590643) (xy 119.749013 -370.523703) (xy 116.470966 -370.523703) (xy 116.462929 -370.590466)
			(xy 116.446956 -370.655848) (xy 116.423282 -370.718853) (xy 116.392247 -370.778575) (xy 116.354297 -370.834161)
			(xy 116.332508 -370.859812) (xy 116.326725 -370.866967) (xy 116.320202 -370.88415) (xy 116.319808 -370.89334)
			(xy 116.319808 -371.386862) (xy 116.320235 -371.396047) (xy 116.326737 -371.413232) (xy 116.332508 -371.42039)
			(xy 116.354311 -371.44603) (xy 116.392263 -371.501617) (xy 116.423299 -371.561342) (xy 116.446761 -371.623785)
			(xy 117.548834 -371.623785) (xy 117.548837 -371.556358) (xy 117.556917 -371.489416) (xy 117.572959 -371.423924)
			(xy 117.596729 -371.360825) (xy 117.627887 -371.301028) (xy 117.665984 -371.245394) (xy 117.687852 -371.21973)
			(xy 117.693667 -371.212598) (xy 117.700169 -371.195397) (xy 117.700552 -371.186202) (xy 117.700552 -371.028722)
			(xy 117.701045 -371.018595) (xy 117.708768 -370.999872) (xy 117.723052 -370.985515) (xy 117.741736 -370.977697)
			(xy 117.75186 -370.97716) (xy 118.46814 -370.97716) (xy 118.478292 -370.977588) (xy 118.497037 -370.985389)
			(xy 118.511358 -370.999783) (xy 118.519063 -371.018568) (xy 118.519448 -371.028722) (xy 118.519448 -371.186202)
			(xy 118.519869 -371.195388) (xy 118.526376 -371.212572) (xy 118.532148 -371.21973) (xy 118.553976 -371.245425)
			(xy 118.59207 -371.301054) (xy 118.623225 -371.360846) (xy 118.646994 -371.423939) (xy 118.663033 -371.489425)
			(xy 118.671113 -371.556361) (xy 118.671116 -371.623782) (xy 118.663044 -371.690719) (xy 118.647011 -371.756207)
			(xy 118.623248 -371.819302) (xy 118.592099 -371.879097) (xy 118.554012 -371.93473) (xy 118.532148 -371.960394)
			(xy 118.526365 -371.967549) (xy 118.519844 -371.984732) (xy 118.519448 -371.993922) (xy 118.519448 -372.486174)
			(xy 118.519882 -372.495358) (xy 118.52638 -372.512542) (xy 118.532148 -372.519702) (xy 118.554047 -372.545339)
			(xy 118.592138 -372.600976) (xy 118.62329 -372.660776) (xy 118.647055 -372.723877) (xy 118.66309 -372.78937)
			(xy 118.671164 -372.856312) (xy 118.671161 -372.923739) (xy 118.663081 -372.990681) (xy 118.64704 -373.056172)
			(xy 118.62327 -373.119271) (xy 118.592112 -373.179068) (xy 118.554016 -373.234702) (xy 118.532148 -373.260366)
			(xy 118.526334 -373.267499) (xy 118.519831 -373.284699) (xy 118.519448 -373.293894) (xy 118.519448 -373.451374)
			(xy 118.518952 -373.461501) (xy 118.51123 -373.480223) (xy 118.496947 -373.494581) (xy 118.478264 -373.502399)
			(xy 118.46814 -373.502936) (xy 117.75186 -373.502936) (xy 117.741708 -373.502512) (xy 117.722961 -373.49471)
			(xy 117.708641 -373.480315) (xy 117.700936 -373.461528) (xy 117.700552 -373.451374) (xy 117.700552 -373.293894)
			(xy 117.700133 -373.284708) (xy 117.693624 -373.267524) (xy 117.687852 -373.260366) (xy 117.66602 -373.234674)
			(xy 117.627926 -373.179045) (xy 117.596771 -373.119253) (xy 117.573003 -373.056159) (xy 117.556964 -372.990673)
			(xy 117.548884 -372.923737) (xy 117.548881 -372.856315) (xy 117.556954 -372.789378) (xy 117.572988 -372.72389)
			(xy 117.596751 -372.660794) (xy 117.6279 -372.600999) (xy 117.665988 -372.545366) (xy 117.687852 -372.519702)
			(xy 117.693637 -372.512549) (xy 117.700157 -372.495364) (xy 117.700552 -372.486174) (xy 117.700552 -371.993922)
			(xy 117.70012 -371.984737) (xy 117.69362 -371.967553) (xy 117.687852 -371.960394) (xy 117.665949 -371.93476)
			(xy 117.627858 -371.879123) (xy 117.596706 -371.819323) (xy 117.572942 -371.756221) (xy 117.556907 -371.690728)
			(xy 117.548834 -371.623785) (xy 116.446761 -371.623785) (xy 116.446973 -371.624348) (xy 116.462946 -371.689732)
			(xy 116.47099 -371.756557) (xy 116.470989 -371.823864) (xy 116.462943 -371.890689) (xy 116.446967 -371.956072)
			(xy 116.42329 -372.019077) (xy 116.392252 -372.078801) (xy 116.354298 -372.134387) (xy 116.332508 -372.160038)
			(xy 116.326714 -372.167185) (xy 116.320197 -372.184374) (xy 116.319808 -372.193566) (xy 116.319808 -372.351554)
			(xy 116.31923 -372.361703) (xy 116.311479 -372.380462) (xy 116.29714 -372.394828) (xy 116.278394 -372.402612)
			(xy 116.268246 -372.403116) (xy 115.551966 -372.403116) (xy 115.541786 -372.402763) (xy 115.522982 -372.394958)
			(xy 115.508597 -372.380551) (xy 115.500821 -372.361734) (xy 115.500404 -372.351554) (xy 115.500404 -372.193566)
			(xy 115.500009 -372.184377) (xy 115.493485 -372.167193) (xy 115.487704 -372.160038) (xy 115.465931 -372.134374)
			(xy 115.427984 -372.078788) (xy 115.396952 -372.019066) (xy 115.37328 -371.956063) (xy 115.357307 -371.890683)
			(xy 115.349263 -371.823862) (xy 115.349261 -371.756559) (xy 115.357303 -371.689738) (xy 115.373274 -371.624357)
			(xy 115.396944 -371.561353) (xy 115.427973 -371.50163) (xy 115.465918 -371.446043) (xy 115.487704 -371.42039)
			(xy 115.493488 -371.413236) (xy 115.50001 -371.396052) (xy 115.500404 -371.386862) (xy 115.500404 -370.89334)
			(xy 115.499974 -370.884155) (xy 115.493474 -370.86697) (xy 115.487704 -370.859812) (xy 115.465906 -370.834169)
			(xy 115.427959 -370.77858) (xy 115.396929 -370.718855) (xy 115.373258 -370.65585) (xy 115.357287 -370.590467)
			(xy 115.349244 -370.523644) (xy 85.670941 -370.523644) (xy 85.670941 -370.523703) (xy 85.662866 -370.590641)
			(xy 85.646831 -370.65613) (xy 85.623066 -370.719226) (xy 85.591915 -370.779022) (xy 85.553825 -370.834655)
			(xy 85.53196 -370.86032) (xy 85.526167 -370.867468) (xy 85.519651 -370.884656) (xy 85.51926 -370.893848)
			(xy 85.51926 -371.386354) (xy 85.519701 -371.395538) (xy 85.526194 -371.412722) (xy 85.53196 -371.419882)
			(xy 85.553839 -371.445535) (xy 85.59193 -371.501171) (xy 85.623082 -371.560968) (xy 85.646742 -371.623785)
			(xy 86.748803 -371.623785) (xy 86.748807 -371.556358) (xy 86.756887 -371.489417) (xy 86.772927 -371.423926)
			(xy 86.796696 -371.360827) (xy 86.827851 -371.30103) (xy 86.865945 -371.245395) (xy 86.887812 -371.21973)
			(xy 86.893622 -371.212594) (xy 86.900128 -371.195397) (xy 86.900512 -371.186202) (xy 86.900512 -371.028722)
			(xy 86.901044 -371.0186) (xy 86.908759 -370.999885) (xy 86.923031 -370.985529) (xy 86.941701 -370.977704)
			(xy 86.95182 -370.97716) (xy 87.6681 -370.97716) (xy 87.678204 -370.977684) (xy 87.696874 -370.985414)
			(xy 87.711168 -370.999699) (xy 87.718909 -371.018365) (xy 87.719408 -371.028468) (xy 87.719408 -371.186202)
			(xy 87.719815 -371.195389) (xy 87.726331 -371.212574) (xy 87.732108 -371.21973) (xy 87.753934 -371.245426)
			(xy 87.792024 -371.301056) (xy 87.823176 -371.360848) (xy 87.846942 -371.423941) (xy 87.862979 -371.489426)
			(xy 87.871058 -371.556361) (xy 87.871062 -371.623782) (xy 87.86299 -371.690717) (xy 87.846958 -371.756204)
			(xy 87.823199 -371.819299) (xy 87.792053 -371.879095) (xy 87.753969 -371.934729) (xy 87.732108 -371.960394)
			(xy 87.726332 -371.967554) (xy 87.719805 -371.984733) (xy 87.719408 -371.993922) (xy 87.719408 -372.486174)
			(xy 87.719829 -372.49536) (xy 87.726335 -372.512545) (xy 87.732108 -372.519702) (xy 87.754005 -372.54534)
			(xy 87.792092 -372.600978) (xy 87.823241 -372.660779) (xy 87.847003 -372.723879) (xy 87.863036 -372.789371)
			(xy 87.871109 -372.856312) (xy 87.871106 -372.923739) (xy 87.863027 -372.990679) (xy 87.846988 -373.05617)
			(xy 87.82322 -373.119268) (xy 87.792066 -373.179065) (xy 87.753974 -373.234701) (xy 87.732108 -373.260366)
			(xy 87.726302 -373.267504) (xy 87.719793 -373.2847) (xy 87.719408 -373.293894) (xy 87.719408 -373.451374)
			(xy 87.718854 -373.461493) (xy 87.711143 -373.480205) (xy 87.696878 -373.49456) (xy 87.678216 -373.502389)
			(xy 87.6681 -373.502936) (xy 86.95182 -373.502936) (xy 86.941717 -373.502399) (xy 86.923046 -373.494675)
			(xy 86.908752 -373.480394) (xy 86.90101 -373.461731) (xy 86.900512 -373.451628) (xy 86.900512 -373.293894)
			(xy 86.900102 -373.284707) (xy 86.893588 -373.267523) (xy 86.887812 -373.260366) (xy 86.865981 -373.234673)
			(xy 86.82789 -373.179043) (xy 86.796738 -373.119251) (xy 86.772971 -373.056157) (xy 86.756933 -372.990672)
			(xy 86.748854 -372.923736) (xy 86.748851 -372.856315) (xy 86.756924 -372.789379) (xy 86.772956 -372.723891)
			(xy 86.796717 -372.660796) (xy 86.827864 -372.601001) (xy 86.86595 -372.545367) (xy 86.887812 -372.519702)
			(xy 86.893592 -372.512545) (xy 86.900116 -372.495363) (xy 86.900512 -372.486174) (xy 86.900512 -371.993922)
			(xy 86.900088 -371.984736) (xy 86.893584 -371.967552) (xy 86.887812 -371.960394) (xy 86.86591 -371.93476)
			(xy 86.827822 -371.879121) (xy 86.796672 -371.819321) (xy 86.77291 -371.75622) (xy 86.756876 -371.690727)
			(xy 86.748803 -371.623785) (xy 85.646742 -371.623785) (xy 85.646848 -371.624067) (xy 85.662883 -371.689557)
			(xy 85.670959 -371.756498) (xy 85.670957 -371.823923) (xy 85.662879 -371.890863) (xy 85.646841 -371.956354)
			(xy 85.623074 -372.019451) (xy 85.591919 -372.079248) (xy 85.553826 -372.134881) (xy 85.53196 -372.160546)
			(xy 85.526156 -372.167686) (xy 85.519647 -372.184881) (xy 85.51926 -372.194074) (xy 85.51926 -372.351554)
			(xy 85.518736 -372.361678) (xy 85.511023 -372.380398) (xy 85.496748 -372.394756) (xy 85.478073 -372.402576)
			(xy 85.467952 -372.403116) (xy 84.751672 -372.403116) (xy 84.741563 -372.402638) (xy 84.722888 -372.394894)
			(xy 84.708594 -372.380596) (xy 84.700858 -372.361917) (xy 84.700364 -372.351808) (xy 84.700364 -372.194074)
			(xy 84.699952 -372.184887) (xy 84.693438 -372.167704) (xy 84.687664 -372.160546) (xy 84.665815 -372.134869)
			(xy 84.627728 -372.079235) (xy 84.596579 -372.01944) (xy 84.572816 -371.956345) (xy 84.55678 -371.890858)
			(xy 84.548704 -371.823921) (xy 84.548703 -371.7565) (xy 84.556776 -371.689563) (xy 84.572809 -371.624075)
			(xy 84.59657 -371.560979) (xy 84.627717 -371.501183) (xy 84.665802 -371.445548) (xy 84.687664 -371.419882)
			(xy 84.693459 -371.412736) (xy 84.699973 -371.395546) (xy 84.700364 -371.386354) (xy 84.700364 -370.893848)
			(xy 84.699917 -370.884665) (xy 84.693427 -370.867481) (xy 84.687664 -370.86032) (xy 84.66579 -370.834664)
			(xy 84.627704 -370.779027) (xy 84.596555 -370.719229) (xy 84.572793 -370.656131) (xy 84.55676 -370.590642)
			(xy 84.548686 -370.523703) (xy 81.27115 -370.523703) (xy 81.263075 -370.590641) (xy 81.24704 -370.656129)
			(xy 81.223276 -370.719226) (xy 81.192125 -370.779021) (xy 81.154036 -370.834655) (xy 81.132172 -370.86032)
			(xy 81.126381 -370.867469) (xy 81.119864 -370.884657) (xy 81.119472 -370.893848) (xy 81.119472 -371.386354)
			(xy 81.119911 -371.395538) (xy 81.126405 -371.412722) (xy 81.132172 -371.419882) (xy 81.154051 -371.445535)
			(xy 81.192141 -371.501171) (xy 81.223293 -371.560969) (xy 81.246928 -371.623725) (xy 82.349035 -371.623725)
			(xy 82.349038 -371.556418) (xy 82.357086 -371.489593) (xy 82.373062 -371.424209) (xy 82.396738 -371.361203)
			(xy 82.427775 -371.301478) (xy 82.465727 -371.24589) (xy 82.487516 -371.220238) (xy 82.493323 -371.2131)
			(xy 82.499831 -371.195904) (xy 82.500216 -371.18671) (xy 82.500216 -371.028722) (xy 82.500751 -371.018568)
			(xy 82.508514 -370.999804) (xy 82.522867 -370.985439) (xy 82.541625 -370.977659) (xy 82.551778 -370.97716)
			(xy 83.268058 -370.97716) (xy 83.27823 -370.977599) (xy 83.297028 -370.985374) (xy 83.311415 -370.999756)
			(xy 83.319197 -371.018551) (xy 83.31962 -371.028722) (xy 83.31962 -371.18671) (xy 83.320021 -371.195898)
			(xy 83.326541 -371.213083) (xy 83.33232 -371.220238) (xy 83.354072 -371.24592) (xy 83.392024 -371.301501)
			(xy 83.423061 -371.361221) (xy 83.446738 -371.424221) (xy 83.462715 -371.4896) (xy 83.470763 -371.55642)
			(xy 83.470766 -371.623723) (xy 83.462725 -371.690544) (xy 83.446755 -371.755924) (xy 83.423085 -371.818927)
			(xy 83.392054 -371.878649) (xy 83.354107 -371.934234) (xy 83.33232 -371.959886) (xy 83.326507 -371.96702)
			(xy 83.320001 -371.984219) (xy 83.31962 -371.993414) (xy 83.31962 -372.486682) (xy 83.320034 -372.495869)
			(xy 83.326545 -372.513054) (xy 83.33232 -372.52021) (xy 83.354142 -372.545834) (xy 83.392093 -372.601424)
			(xy 83.423127 -372.661151) (xy 83.446799 -372.724159) (xy 83.462771 -372.789545) (xy 83.470813 -372.856371)
			(xy 83.47081 -372.92368) (xy 83.462762 -372.990505) (xy 83.446784 -373.05589) (xy 83.423106 -373.118896)
			(xy 83.392066 -373.17862) (xy 83.354111 -373.234206) (xy 83.33232 -373.259858) (xy 83.326519 -373.267)
			(xy 83.320006 -373.284193) (xy 83.31962 -373.293386) (xy 83.31962 -373.451374) (xy 83.319214 -373.461549)
			(xy 83.311429 -373.480351) (xy 83.297038 -373.494738) (xy 83.278233 -373.502517) (xy 83.268058 -373.502936)
			(xy 82.551778 -373.502936) (xy 82.541602 -373.502553) (xy 82.522802 -373.494756) (xy 82.508417 -373.480358)
			(xy 82.500637 -373.461551) (xy 82.500216 -373.451374) (xy 82.500216 -373.293386) (xy 82.499809 -373.284199)
			(xy 82.493293 -373.267014) (xy 82.487516 -373.259858) (xy 82.465763 -373.234178) (xy 82.427814 -373.178595)
			(xy 82.396781 -373.118875) (xy 82.373107 -373.055874) (xy 82.357133 -372.990496) (xy 82.349086 -372.923677)
			(xy 82.349083 -372.856375) (xy 82.357123 -372.789555) (xy 82.373092 -372.724175) (xy 82.39676 -372.661172)
			(xy 82.427788 -372.601449) (xy 82.465731 -372.545863) (xy 82.487516 -372.52021) (xy 82.493335 -372.513081)
			(xy 82.499836 -372.495878) (xy 82.500216 -372.486682) (xy 82.500216 -371.993414) (xy 82.499795 -371.984228)
			(xy 82.493288 -371.967044) (xy 82.487516 -371.959886) (xy 82.465692 -371.934264) (xy 82.427745 -371.878673)
			(xy 82.396715 -371.818945) (xy 82.373045 -371.755936) (xy 82.357076 -371.690551) (xy 82.349035 -371.623725)
			(xy 81.246928 -371.623725) (xy 81.247057 -371.624067) (xy 81.263092 -371.689558) (xy 81.271168 -371.756498)
			(xy 81.271166 -371.823923) (xy 81.263089 -371.890863) (xy 81.247051 -371.956353) (xy 81.223284 -372.019451)
			(xy 81.19213 -372.079247) (xy 81.154038 -372.134881) (xy 81.132172 -372.160546) (xy 81.12637 -372.167687)
			(xy 81.119859 -372.184881) (xy 81.119472 -372.194074) (xy 81.119472 -372.351554) (xy 81.118936 -372.361676)
			(xy 81.111226 -372.380394) (xy 81.096954 -372.394752) (xy 81.078283 -372.402574) (xy 81.068164 -372.403116)
			(xy 80.351884 -372.403116) (xy 80.341776 -372.402628) (xy 80.323101 -372.394888) (xy 80.308807 -372.380592)
			(xy 80.30107 -372.361916) (xy 80.300576 -372.351808) (xy 80.300576 -372.194074) (xy 80.300184 -372.184885)
			(xy 80.293658 -372.1677) (xy 80.287876 -372.160546) (xy 80.266027 -372.134869) (xy 80.227939 -372.079236)
			(xy 80.196789 -372.019441) (xy 80.173025 -371.956346) (xy 80.156989 -371.890858) (xy 80.148913 -371.823922)
			(xy 80.148912 -371.756499) (xy 80.156986 -371.689563) (xy 80.173019 -371.624075) (xy 80.196781 -371.560978)
			(xy 80.227928 -371.501182) (xy 80.266014 -371.445548) (xy 80.287876 -371.419882) (xy 80.29366 -371.412728)
			(xy 80.300183 -371.395544) (xy 80.300576 -371.386354) (xy 80.300576 -370.893848) (xy 80.300148 -370.884663)
			(xy 80.293647 -370.867478) (xy 80.287876 -370.86032) (xy 80.266001 -370.834664) (xy 80.227914 -370.779028)
			(xy 80.196765 -370.71923) (xy 80.173003 -370.656132) (xy 80.156969 -370.590642) (xy 80.148895 -370.523703)
			(xy 76.870824 -370.523703) (xy 76.862788 -370.590464) (xy 76.846817 -370.655845) (xy 76.823147 -370.718849)
			(xy 76.792116 -370.778573) (xy 76.75417 -370.83416) (xy 76.732384 -370.859812) (xy 76.726598 -370.866965)
			(xy 76.720078 -370.88415) (xy 76.719684 -370.89334) (xy 76.719684 -371.386862) (xy 76.720116 -371.396047)
			(xy 76.726615 -371.413231) (xy 76.732384 -371.42039) (xy 76.754185 -371.446031) (xy 76.792132 -371.50162)
			(xy 76.823163 -371.561345) (xy 76.846621 -371.623785) (xy 77.948715 -371.623785) (xy 77.948719 -371.556358)
			(xy 77.956799 -371.489417) (xy 77.972839 -371.423925) (xy 77.996609 -371.360826) (xy 78.027766 -371.301029)
			(xy 78.065861 -371.245395) (xy 78.087728 -371.21973) (xy 78.09354 -371.212596) (xy 78.100045 -371.195397)
			(xy 78.100428 -371.186202) (xy 78.100428 -371.028722) (xy 78.100944 -371.018598) (xy 78.108662 -370.99988)
			(xy 78.12294 -370.985523) (xy 78.141615 -370.977701) (xy 78.151736 -370.97716) (xy 78.868016 -370.97716)
			(xy 78.878121 -370.977671) (xy 78.896792 -370.985407) (xy 78.911084 -370.999695) (xy 78.918826 -371.018363)
			(xy 78.919324 -371.028468) (xy 78.919324 -371.186202) (xy 78.919728 -371.19539) (xy 78.926245 -371.212575)
			(xy 78.932024 -371.21973) (xy 78.95385 -371.245426) (xy 78.991938 -371.301057) (xy 79.023089 -371.360849)
			(xy 79.046854 -371.423942) (xy 79.062892 -371.489427) (xy 79.07097 -371.556361) (xy 79.070974 -371.623782)
			(xy 79.062902 -371.690717) (xy 79.046871 -371.756203) (xy 79.023112 -371.819299) (xy 78.991967 -371.879094)
			(xy 78.953885 -371.934728) (xy 78.932024 -371.960394) (xy 78.92625 -371.967556) (xy 78.919721 -371.984733)
			(xy 78.919324 -371.993922) (xy 78.919324 -372.486174) (xy 78.919741 -372.495361) (xy 78.926249 -372.512545)
			(xy 78.932024 -372.519702) (xy 78.953921 -372.54534) (xy 78.992007 -372.600979) (xy 79.023155 -372.660779)
			(xy 79.046916 -372.72388) (xy 79.062948 -372.789372) (xy 79.071021 -372.856313) (xy 79.071018 -372.923738)
			(xy 79.062939 -372.990679) (xy 79.046901 -373.056169) (xy 79.023134 -373.119267) (xy 78.99198 -373.179065)
			(xy 78.953889 -373.2347) (xy 78.932024 -373.260366) (xy 78.92622 -373.267506) (xy 78.919709 -373.2847)
			(xy 78.919324 -373.293894) (xy 78.919324 -373.451374) (xy 78.918851 -373.461504) (xy 78.911125 -373.480231)
			(xy 78.896834 -373.49459) (xy 78.878143 -373.502403) (xy 78.868016 -373.502936) (xy 78.151736 -373.502936)
			(xy 78.14162 -373.502455) (xy 78.122924 -373.494726) (xy 78.10861 -373.480429) (xy 78.100857 -373.461743)
			(xy 78.100428 -373.451628) (xy 78.100428 -373.293894) (xy 78.100015 -373.284707) (xy 78.093503 -373.267523)
			(xy 78.087728 -373.260366) (xy 78.065896 -373.234674) (xy 78.027805 -373.179044) (xy 77.996651 -373.119251)
			(xy 77.972884 -373.056158) (xy 77.956845 -372.990672) (xy 77.948766 -372.923736) (xy 77.948763 -372.856315)
			(xy 77.956836 -372.789378) (xy 77.972869 -372.723891) (xy 77.99663 -372.660795) (xy 78.027779 -372.601)
			(xy 78.065865 -372.545367) (xy 78.087728 -372.519702) (xy 78.09351 -372.512547) (xy 78.100033 -372.495364)
			(xy 78.100428 -372.486174) (xy 78.100428 -371.993922) (xy 78.100001 -371.984737) (xy 78.093498 -371.967553)
			(xy 78.087728 -371.960394) (xy 78.065826 -371.93476) (xy 78.027736 -371.879122) (xy 77.996586 -371.819321)
			(xy 77.972822 -371.75622) (xy 77.956789 -371.690727) (xy 77.948715 -371.623785) (xy 76.846621 -371.623785)
			(xy 76.846834 -371.624351) (xy 76.862805 -371.689734) (xy 76.870848 -371.756558) (xy 76.870847 -371.823863)
			(xy 76.862802 -371.890687) (xy 76.846828 -371.956069) (xy 76.823155 -372.019074) (xy 76.792121 -372.078798)
			(xy 76.754172 -372.134386) (xy 76.732384 -372.160038) (xy 76.726587 -372.167183) (xy 76.720073 -372.184374)
			(xy 76.719684 -372.193566) (xy 76.719684 -372.351554) (xy 76.719199 -372.36172) (xy 76.711433 -372.380509)
			(xy 76.697067 -372.394895) (xy 76.678287 -372.402686) (xy 76.668122 -372.403116) (xy 75.951842 -372.403116)
			(xy 75.941667 -372.402701) (xy 75.922865 -372.394921) (xy 75.908477 -372.380532) (xy 75.900699 -372.361729)
			(xy 75.90028 -372.351554) (xy 75.90028 -372.193566) (xy 75.899891 -372.184377) (xy 75.893363 -372.167192)
			(xy 75.88758 -372.160038) (xy 75.865805 -372.134375) (xy 75.827853 -372.078791) (xy 75.796817 -372.019069)
			(xy 75.773141 -371.956066) (xy 75.757166 -371.890685) (xy 75.74912 -371.823863) (xy 75.749119 -371.756558)
			(xy 75.757162 -371.689736) (xy 75.773135 -371.624354) (xy 75.796808 -371.56135) (xy 75.827842 -371.501627)
			(xy 75.865792 -371.446042) (xy 75.88758 -371.42039) (xy 75.893361 -371.413234) (xy 75.899886 -371.396052)
			(xy 75.90028 -371.386862) (xy 75.90028 -370.89334) (xy 75.899855 -370.884154) (xy 75.893352 -370.866969)
			(xy 75.88758 -370.859812) (xy 75.865779 -370.83417) (xy 75.827828 -370.778583) (xy 75.796793 -370.718859)
			(xy 75.773119 -370.655853) (xy 75.757146 -370.590469) (xy 75.749102 -370.523644) (xy 72.471063 -370.523644)
			(xy 72.471063 -370.523702) (xy 72.462988 -370.59064) (xy 72.446953 -370.656129) (xy 72.42319 -370.719225)
			(xy 72.39204 -370.779021) (xy 72.353952 -370.834655) (xy 72.332088 -370.86032) (xy 72.326299 -370.867471)
			(xy 72.31978 -370.884657) (xy 72.319388 -370.893848) (xy 72.319388 -371.386354) (xy 72.319823 -371.395539)
			(xy 72.32632 -371.412723) (xy 72.332088 -371.419882) (xy 72.353966 -371.445536) (xy 72.392055 -371.501172)
			(xy 72.423206 -371.560969) (xy 72.446841 -371.623725) (xy 73.548947 -371.623725) (xy 73.548951 -371.556417)
			(xy 73.556998 -371.489592) (xy 73.572975 -371.424208) (xy 73.596652 -371.361202) (xy 73.627689 -371.301477)
			(xy 73.665642 -371.24589) (xy 73.687432 -371.220238) (xy 73.693242 -371.213102) (xy 73.699748 -371.195904)
			(xy 73.700132 -371.18671) (xy 73.700132 -371.028722) (xy 73.700582 -371.018553) (xy 73.708359 -370.99976)
			(xy 73.722736 -370.985374) (xy 73.741525 -370.977587) (xy 73.751694 -370.97716) (xy 74.467974 -370.97716)
			(xy 74.478147 -370.977586) (xy 74.496945 -370.985366) (xy 74.511331 -370.999752) (xy 74.519113 -371.018549)
			(xy 74.519536 -371.028722) (xy 74.519536 -371.18671) (xy 74.519956 -371.195896) (xy 74.526464 -371.21308)
			(xy 74.532236 -371.220238) (xy 74.553987 -371.245921) (xy 74.591939 -371.301502) (xy 74.622975 -371.361221)
			(xy 74.646651 -371.424222) (xy 74.662627 -371.489601) (xy 74.670675 -371.55642) (xy 74.670678 -371.623723)
			(xy 74.662638 -371.690543) (xy 74.646668 -371.755924) (xy 74.622998 -371.818926) (xy 74.591968 -371.878649)
			(xy 74.554022 -371.934234) (xy 74.532236 -371.959886) (xy 74.526413 -371.967012) (xy 74.519916 -371.984217)
			(xy 74.519536 -371.993414) (xy 74.519536 -372.486682) (xy 74.519969 -372.495866) (xy 74.526468 -372.51305)
			(xy 74.532236 -372.52021) (xy 74.554058 -372.545834) (xy 74.592008 -372.601424) (xy 74.623041 -372.661151)
			(xy 74.646713 -372.724159) (xy 74.662684 -372.789545) (xy 74.670726 -372.856371) (xy 74.670723 -372.92368)
			(xy 74.662675 -372.990505) (xy 74.646698 -373.055889) (xy 74.62302 -373.118896) (xy 74.591981 -373.17862)
			(xy 74.554027 -373.234206) (xy 74.532236 -373.259858) (xy 74.526425 -373.266992) (xy 74.519921 -373.284191)
			(xy 74.519536 -373.293386) (xy 74.519536 -373.451374) (xy 74.519114 -373.461547) (xy 74.511333 -373.480346)
			(xy 74.496946 -373.494733) (xy 74.478147 -373.502514) (xy 74.467974 -373.502936) (xy 73.751694 -373.502936)
			(xy 73.741519 -373.50254) (xy 73.722719 -373.494749) (xy 73.708333 -373.480354) (xy 73.700553 -373.461549)
			(xy 73.700132 -373.451374) (xy 73.700132 -373.293386) (xy 73.699722 -373.284199) (xy 73.693207 -373.267015)
			(xy 73.687432 -373.259858) (xy 73.665678 -373.234178) (xy 73.627729 -373.178595) (xy 73.596694 -373.118876)
			(xy 73.57302 -373.055875) (xy 73.557045 -372.990496) (xy 73.548998 -372.923677) (xy 73.548995 -372.856374)
			(xy 73.557036 -372.789554) (xy 73.573005 -372.724174) (xy 73.596674 -372.661171) (xy 73.627702 -372.601448)
			(xy 73.665647 -372.545862) (xy 73.687432 -372.52021) (xy 73.693253 -372.513083) (xy 73.699753 -372.495878)
			(xy 73.700132 -372.486682) (xy 73.700132 -371.993414) (xy 73.699708 -371.984228) (xy 73.693203 -371.967044)
			(xy 73.687432 -371.959886) (xy 73.665607 -371.934265) (xy 73.62766 -371.878674) (xy 73.596629 -371.818946)
			(xy 73.572958 -371.755937) (xy 73.556988 -371.690551) (xy 73.548947 -371.623725) (xy 72.446841 -371.623725)
			(xy 72.44697 -371.624068) (xy 72.463005 -371.689558) (xy 72.47108 -371.756498) (xy 72.471078 -371.823923)
			(xy 72.463001 -371.890862) (xy 72.446964 -371.956352) (xy 72.423197 -372.01945) (xy 72.392044 -372.079246)
			(xy 72.353953 -372.134881) (xy 72.332088 -372.160546) (xy 72.326288 -372.167689) (xy 72.319776 -372.184881)
			(xy 72.319388 -372.194074) (xy 72.319388 -372.351554) (xy 72.318836 -372.361674) (xy 72.311129 -372.380389)
			(xy 72.296863 -372.394746) (xy 72.278197 -372.402572) (xy 72.26808 -372.403116) (xy 71.5518 -372.403116)
			(xy 71.541648 -372.402679) (xy 71.522899 -372.394886) (xy 71.508576 -372.380494) (xy 71.500873 -372.361708)
			(xy 71.500492 -372.351554) (xy 71.500492 -372.194074) (xy 71.500096 -372.184885) (xy 71.493573 -372.167701)
			(xy 71.487792 -372.160546) (xy 71.465942 -372.134869) (xy 71.427853 -372.079236) (xy 71.396703 -372.019442)
			(xy 71.372938 -371.956346) (xy 71.356902 -371.890859) (xy 71.348825 -371.823922) (xy 71.348824 -371.756499)
			(xy 71.356898 -371.689562) (xy 71.372932 -371.624074) (xy 71.396694 -371.560978) (xy 71.427843 -371.501182)
			(xy 71.465929 -371.445547) (xy 71.487792 -371.419882) (xy 71.493578 -371.412729) (xy 71.500099 -371.395545)
			(xy 71.500492 -371.386354) (xy 71.500492 -370.893848) (xy 71.500061 -370.884663) (xy 71.493562 -370.867478)
			(xy 71.487792 -370.86032) (xy 71.465917 -370.834664) (xy 71.427829 -370.779028) (xy 71.396679 -370.719231)
			(xy 71.372916 -370.656133) (xy 71.356881 -370.590642) (xy 71.348807 -370.523703) (xy 58.103008 -370.523703)
			(xy 58.103008 -371.310662) (xy 58.102522 -371.337931) (xy 58.09476 -371.391915) (xy 58.079395 -371.444245)
			(xy 58.056738 -371.493855) (xy 58.027252 -371.539736) (xy 57.991537 -371.580953) (xy 57.95032 -371.616668)
			(xy 57.904439 -371.646154) (xy 57.854829 -371.668811) (xy 57.802499 -371.684176) (xy 57.748515 -371.691938)
			(xy 57.693977 -371.691938) (xy 57.639993 -371.684176) (xy 57.587663 -371.668811) (xy 57.538053 -371.646154)
			(xy 57.492172 -371.616668) (xy 57.450955 -371.580953) (xy 57.41524 -371.539736) (xy 57.385754 -371.493855)
			(xy 57.363097 -371.444245) (xy 57.347732 -371.391915) (xy 57.33997 -371.337931) (xy 57.339484 -371.310662)
			(xy 54.729888 -371.310662) (xy 54.729402 -371.337931) (xy 54.72164 -371.391915) (xy 54.706275 -371.444245)
			(xy 54.683618 -371.493855) (xy 54.654132 -371.539736) (xy 54.618417 -371.580953) (xy 54.5772 -371.616668)
			(xy 54.531319 -371.646154) (xy 54.481709 -371.668811) (xy 54.429379 -371.684176) (xy 54.375395 -371.691938)
			(xy 54.320857 -371.691938) (xy 54.266873 -371.684176) (xy 54.214543 -371.668811) (xy 54.164933 -371.646154)
			(xy 54.119052 -371.616668) (xy 54.077835 -371.580953) (xy 54.04212 -371.539736) (xy 54.012634 -371.493855)
			(xy 53.989977 -371.444245) (xy 53.974612 -371.391915) (xy 53.96685 -371.337931) (xy 53.966364 -371.310662)
			(xy 48.196948 -371.310662) (xy 48.223223 -371.361224) (xy 48.246896 -371.424224) (xy 48.262871 -371.489602)
			(xy 48.270918 -371.556421) (xy 48.270921 -371.623722) (xy 48.262881 -371.690542) (xy 48.246913 -371.755921)
			(xy 48.223246 -371.818924) (xy 48.192219 -371.878647) (xy 48.154277 -371.934234) (xy 48.132492 -371.959886)
			(xy 48.126675 -371.967017) (xy 48.120173 -371.984218) (xy 48.119792 -371.993414) (xy 48.119792 -372.486682)
			(xy 48.120213 -372.495868) (xy 48.126719 -372.513052) (xy 48.132492 -372.52021) (xy 48.154312 -372.545835)
			(xy 48.192258 -372.601426) (xy 48.223288 -372.661154) (xy 48.246958 -372.724162) (xy 48.262927 -372.789547)
			(xy 48.270968 -372.856372) (xy 48.270965 -372.923679) (xy 48.262918 -372.990504) (xy 48.246942 -373.055887)
			(xy 48.223267 -373.118893) (xy 48.192232 -373.178618) (xy 48.154281 -373.234205) (xy 48.132492 -373.259858)
			(xy 48.126687 -373.266997) (xy 48.120178 -373.284192) (xy 48.119792 -373.293386) (xy 48.119792 -373.451374)
			(xy 48.119246 -373.461526) (xy 48.111486 -373.480289) (xy 48.097136 -373.494655) (xy 48.078382 -373.502435)
			(xy 48.06823 -373.502936) (xy 47.35195 -373.502936) (xy 47.341778 -373.502495) (xy 47.32298 -373.494721)
			(xy 47.308592 -373.48034) (xy 47.30081 -373.461545) (xy 47.300388 -373.451374) (xy 47.300388 -373.293386)
			(xy 47.299987 -373.284198) (xy 47.293467 -373.267013) (xy 47.287688 -373.259858) (xy 47.265932 -373.234179)
			(xy 47.227979 -373.178598) (xy 47.196942 -373.118878) (xy 47.173265 -373.055877) (xy 47.157288 -372.990498)
			(xy 47.14924 -372.923677) (xy 47.149237 -372.856374) (xy 47.157279 -372.789553) (xy 47.17325 -372.724172)
			(xy 47.196921 -372.661169) (xy 47.227953 -372.601446) (xy 47.265901 -372.545861) (xy 47.287688 -372.52021)
			(xy 47.293504 -372.513078) (xy 47.300007 -372.495878) (xy 47.300388 -372.486682) (xy 47.300388 -371.993414)
			(xy 47.299974 -371.984227) (xy 47.293463 -371.967043) (xy 47.287688 -371.959886) (xy 47.265861 -371.934265)
			(xy 47.227911 -371.878675) (xy 47.196876 -371.818948) (xy 47.173204 -371.755939) (xy 47.157232 -371.690553)
			(xy 47.14919 -371.623726) (xy 46.046568 -371.623726) (xy 46.046802 -371.624349) (xy 46.062775 -371.689733)
			(xy 46.070818 -371.756557) (xy 46.070817 -371.823864) (xy 46.062771 -371.890688) (xy 46.046796 -371.956071)
			(xy 46.023121 -372.019076) (xy 45.992085 -372.0788) (xy 45.954133 -372.134386) (xy 45.932344 -372.160038)
			(xy 45.926542 -372.167179) (xy 45.920032 -372.184373) (xy 45.919644 -372.193566) (xy 45.919644 -372.351554)
			(xy 45.919198 -372.361725) (xy 45.911425 -372.380522) (xy 45.897046 -372.394909) (xy 45.878253 -372.402693)
			(xy 45.868082 -372.403116) (xy 45.151802 -372.403116) (xy 45.141625 -372.402733) (xy 45.122821 -372.394941)
			(xy 45.108435 -372.380542) (xy 45.100658 -372.361732) (xy 45.10024 -372.351554) (xy 45.10024 -372.193566)
			(xy 45.099837 -372.184378) (xy 45.093317 -372.167194) (xy 45.08754 -372.160038) (xy 45.065766 -372.134374)
			(xy 45.027817 -372.07879) (xy 44.996783 -372.019068) (xy 44.973109 -371.956065) (xy 44.957135 -371.890684)
			(xy 44.94909 -371.823862) (xy 44.949089 -371.756559) (xy 44.957132 -371.689737) (xy 44.973103 -371.624356)
			(xy 44.996774 -371.561352) (xy 45.027806 -371.501628) (xy 45.065753 -371.446042) (xy 45.08754 -371.42039)
			(xy 45.093328 -371.413239) (xy 45.099847 -371.396053) (xy 45.10024 -371.386862) (xy 45.10024 -370.89334)
			(xy 45.099801 -370.884156) (xy 45.093306 -370.866972) (xy 45.08754 -370.859812) (xy 45.06574 -370.83417)
			(xy 45.027792 -370.778582) (xy 44.996759 -370.718857) (xy 44.973087 -370.655851) (xy 44.957115 -370.590468)
			(xy 44.949071 -370.523644) (xy 41.671032 -370.523644) (xy 41.671032 -370.523703) (xy 41.662957 -370.590641)
			(xy 41.646921 -370.65613) (xy 41.623156 -370.719227) (xy 41.592004 -370.779022) (xy 41.553913 -370.834656)
			(xy 41.532048 -370.86032) (xy 41.526254 -370.867467) (xy 41.519739 -370.884656) (xy 41.519348 -370.893848)
			(xy 41.519348 -371.386354) (xy 41.519792 -371.395537) (xy 41.526284 -371.412721) (xy 41.532048 -371.419882)
			(xy 41.553928 -371.445535) (xy 41.592019 -371.50117) (xy 41.623172 -371.560967) (xy 41.646832 -371.623785)
			(xy 42.748894 -371.623785) (xy 42.748898 -371.556358) (xy 42.756977 -371.489417) (xy 42.773017 -371.423926)
			(xy 42.796785 -371.360828) (xy 42.827941 -371.30103) (xy 42.866034 -371.245395) (xy 42.8879 -371.21973)
			(xy 42.893709 -371.212593) (xy 42.900216 -371.195396) (xy 42.9006 -371.186202) (xy 42.9006 -371.028722)
			(xy 42.901143 -371.018602) (xy 42.908856 -370.999888) (xy 42.923125 -370.985533) (xy 42.941791 -370.977706)
			(xy 42.951908 -370.97716) (xy 43.668188 -370.97716) (xy 43.678336 -370.977631) (xy 43.697081 -370.985415)
			(xy 43.711403 -370.999796) (xy 43.71911 -371.018572) (xy 43.719496 -371.028722) (xy 43.719496 -371.186202)
			(xy 43.719906 -371.195389) (xy 43.72642 -371.212573) (xy 43.732196 -371.21973) (xy 43.754023 -371.245426)
			(xy 43.792113 -371.301056) (xy 43.823265 -371.360848) (xy 43.847032 -371.423941) (xy 43.86307 -371.489426)
			(xy 43.871149 -371.556361) (xy 43.871153 -371.623782) (xy 43.86308 -371.690718) (xy 43.847049 -371.756205)
			(xy 43.823289 -371.8193) (xy 43.792142 -371.879095) (xy 43.754058 -371.934729) (xy 43.732196 -371.960394)
			(xy 43.726419 -371.967553) (xy 43.719893 -371.984733) (xy 43.719496 -371.993922) (xy 43.719496 -372.486174)
			(xy 43.71992 -372.49536) (xy 43.726424 -372.512544) (xy 43.732196 -372.519702) (xy 43.754094 -372.54534)
			(xy 43.792181 -372.600978) (xy 43.823331 -372.660778) (xy 43.847093 -372.723878) (xy 43.863127 -372.789371)
			(xy 43.8712 -372.856312) (xy 43.871197 -372.923739) (xy 43.863117 -372.990679) (xy 43.847078 -373.05617)
			(xy 43.82331 -373.119269) (xy 43.792155 -373.179066) (xy 43.754062 -373.234701) (xy 43.732196 -373.260366)
			(xy 43.726388 -373.267503) (xy 43.71988 -373.2847) (xy 43.719496 -373.293894) (xy 43.719496 -373.451374)
			(xy 43.718953 -373.461495) (xy 43.711241 -373.480208) (xy 43.696972 -373.494564) (xy 43.678306 -373.502391)
			(xy 43.668188 -373.502936) (xy 42.951908 -373.502936) (xy 42.941759 -373.502473) (xy 42.923014 -373.494686)
			(xy 42.908691 -373.480303) (xy 42.900985 -373.461525) (xy 42.9006 -373.451374) (xy 42.9006 -373.293894)
			(xy 42.900193 -373.284707) (xy 42.893677 -373.267522) (xy 42.8879 -373.260366) (xy 42.866069 -373.234673)
			(xy 42.82798 -373.179043) (xy 42.796828 -373.11925) (xy 42.773061 -373.056157) (xy 42.757024 -372.990671)
			(xy 42.748945 -372.923736) (xy 42.748942 -372.856315) (xy 42.757014 -372.789379) (xy 42.773046 -372.723892)
			(xy 42.796807 -372.660796) (xy 42.827953 -372.601001) (xy 42.866038 -372.545367) (xy 42.8879 -372.519702)
			(xy 42.893678 -372.512544) (xy 42.900204 -372.495363) (xy 42.9006 -372.486174) (xy 42.9006 -371.993922)
			(xy 42.900179 -371.984736) (xy 42.893673 -371.967551) (xy 42.8879 -371.960394) (xy 42.865999 -371.93476)
			(xy 42.827911 -371.879121) (xy 42.796762 -371.81932) (xy 42.773 -371.756219) (xy 42.756967 -371.690726)
			(xy 42.748894 -371.623785) (xy 41.646832 -371.623785) (xy 41.646938 -371.624066) (xy 41.662974 -371.689557)
			(xy 41.67105 -371.756498) (xy 41.671048 -371.823923) (xy 41.66297 -371.890864) (xy 41.646932 -371.956354)
			(xy 41.623164 -372.019452) (xy 41.592008 -372.079248) (xy 41.553915 -372.134882) (xy 41.532048 -372.160546)
			(xy 41.526243 -372.167685) (xy 41.519735 -372.18488) (xy 41.519348 -372.194074) (xy 41.519348 -372.351554)
			(xy 41.518835 -372.361679) (xy 41.51112 -372.380402) (xy 41.496842 -372.39476) (xy 41.478162 -372.402579)
			(xy 41.46804 -372.403116) (xy 40.75176 -372.403116) (xy 40.741605 -372.402711) (xy 40.722855 -372.394906)
			(xy 40.708534 -372.380504) (xy 40.700833 -372.361711) (xy 40.700452 -372.351554) (xy 40.700452 -372.194074)
			(xy 40.700043 -372.184887) (xy 40.693527 -372.167703) (xy 40.687752 -372.160546) (xy 40.6659 -372.13487)
			(xy 40.627807 -372.079238) (xy 40.596653 -372.019444) (xy 40.572886 -371.956349) (xy 40.556848 -371.89086)
			(xy 40.54877 -371.823922) (xy 40.548769 -371.756499) (xy 40.556844 -371.68956) (xy 40.57288 -371.624072)
			(xy 40.596645 -371.560975) (xy 40.627797 -371.50118) (xy 40.665887 -371.445546) (xy 40.687752 -371.419882)
			(xy 40.693545 -371.412735) (xy 40.70006 -371.395546) (xy 40.700452 -371.386354) (xy 40.700452 -370.893848)
			(xy 40.700007 -370.884665) (xy 40.693516 -370.867481) (xy 40.687752 -370.86032) (xy 40.665874 -370.834665)
			(xy 40.627783 -370.779031) (xy 40.59663 -370.719233) (xy 40.572864 -370.656135) (xy 40.556828 -370.590644)
			(xy 40.548752 -370.523704) (xy 37.271241 -370.523704) (xy 37.263166 -370.590641) (xy 37.247131 -370.65613)
			(xy 37.223366 -370.719226) (xy 37.192215 -370.779022) (xy 37.154125 -370.834655) (xy 37.13226 -370.86032)
			(xy 37.126467 -370.867468) (xy 37.119951 -370.884656) (xy 37.11956 -370.893848) (xy 37.11956 -371.386354)
			(xy 37.120001 -371.395538) (xy 37.126494 -371.412722) (xy 37.13226 -371.419882) (xy 37.154139 -371.445535)
			(xy 37.19223 -371.501171) (xy 37.223382 -371.560968) (xy 37.247019 -371.623725) (xy 38.349126 -371.623725)
			(xy 38.349129 -371.556418) (xy 38.357177 -371.489593) (xy 38.373153 -371.424209) (xy 38.396828 -371.361203)
			(xy 38.427864 -371.301478) (xy 38.465815 -371.245891) (xy 38.487604 -371.220238) (xy 38.49341 -371.213099)
			(xy 38.499919 -371.195904) (xy 38.500304 -371.18671) (xy 38.500304 -371.028722) (xy 38.50085 -371.01857)
			(xy 38.508611 -370.999808) (xy 38.522961 -370.985443) (xy 38.541714 -370.977661) (xy 38.551866 -370.97716)
			(xy 39.268146 -370.97716) (xy 39.278309 -370.977596) (xy 39.297084 -370.98539) (xy 39.311448 -370.999773)
			(xy 39.319217 -371.018558) (xy 39.319708 -371.028722) (xy 39.319708 -371.18671) (xy 39.320112 -371.195898)
			(xy 39.32663 -371.213082) (xy 39.332408 -371.220238) (xy 39.35416 -371.24592) (xy 39.392113 -371.301501)
			(xy 39.423151 -371.36122) (xy 39.446829 -371.424221) (xy 39.462806 -371.4896) (xy 39.470854 -371.55642)
			(xy 39.470857 -371.623723) (xy 39.462816 -371.690544) (xy 39.446845 -371.755925) (xy 39.423175 -371.818928)
			(xy 39.392143 -371.87865) (xy 39.354195 -371.934235) (xy 39.332408 -371.959886) (xy 39.326593 -371.967018)
			(xy 39.320089 -371.984219) (xy 39.319708 -371.993414) (xy 39.319708 -372.486682) (xy 39.320125 -372.495868)
			(xy 39.326634 -372.513053) (xy 39.332408 -372.52021) (xy 39.354231 -372.545834) (xy 39.392182 -372.601423)
			(xy 39.423217 -372.66115) (xy 39.44689 -372.724158) (xy 39.462862 -372.789545) (xy 39.470904 -372.856371)
			(xy 39.470901 -372.92368) (xy 39.462853 -372.990506) (xy 39.446875 -373.05589) (xy 39.423196 -373.118897)
			(xy 39.392156 -373.178621) (xy 39.354199 -373.234207) (xy 39.332408 -373.259858) (xy 39.326605 -373.266999)
			(xy 39.320094 -373.284193) (xy 39.319708 -373.293386) (xy 39.319708 -373.451374) (xy 39.319147 -373.461525)
			(xy 39.311389 -373.480284) (xy 39.297045 -373.494649) (xy 39.278296 -373.502432) (xy 39.268146 -373.502936)
			(xy 38.551866 -373.502936) (xy 38.541703 -373.502494) (xy 38.522928 -373.494703) (xy 38.508563 -373.480322)
			(xy 38.500794 -373.461538) (xy 38.500304 -373.451374) (xy 38.500304 -373.293386) (xy 38.4999 -373.284198)
			(xy 38.493382 -373.267014) (xy 38.487604 -373.259858) (xy 38.465851 -373.234178) (xy 38.427903 -373.178595)
			(xy 38.39687 -373.118875) (xy 38.373197 -373.055874) (xy 38.357223 -372.990495) (xy 38.349177 -372.923676)
			(xy 38.349174 -372.856375) (xy 38.357214 -372.789555) (xy 38.373182 -372.724175) (xy 38.396849 -372.661172)
			(xy 38.427877 -372.601449) (xy 38.465819 -372.545863) (xy 38.487604 -372.52021) (xy 38.493422 -372.51308)
			(xy 38.499924 -372.495878) (xy 38.500304 -372.486682) (xy 38.500304 -371.993414) (xy 38.499886 -371.984228)
			(xy 38.493378 -371.967043) (xy 38.487604 -371.959886) (xy 38.46578 -371.934264) (xy 38.427835 -371.878672)
			(xy 38.396805 -371.818944) (xy 38.373136 -371.755936) (xy 38.357167 -371.69055) (xy 38.349126 -371.623725)
			(xy 37.247019 -371.623725) (xy 37.247148 -371.624067) (xy 37.263183 -371.689557) (xy 37.271259 -371.756498)
			(xy 37.271257 -371.823923) (xy 37.263179 -371.890863) (xy 37.247141 -371.956354) (xy 37.223374 -372.019451)
			(xy 37.192219 -372.079248) (xy 37.154126 -372.134881) (xy 37.13226 -372.160546) (xy 37.126456 -372.167686)
			(xy 37.119947 -372.184881) (xy 37.11956 -372.194074) (xy 37.11956 -372.351554) (xy 37.119036 -372.361678)
			(xy 37.111323 -372.380398) (xy 37.097048 -372.394756) (xy 37.078373 -372.402576) (xy 37.068252 -372.403116)
			(xy 36.351972 -372.403116) (xy 36.341818 -372.402702) (xy 36.323068 -372.3949) (xy 36.308746 -372.380501)
			(xy 36.301045 -372.36171) (xy 36.300664 -372.351554) (xy 36.300664 -372.194074) (xy 36.300252 -372.184887)
			(xy 36.293738 -372.167704) (xy 36.287964 -372.160546) (xy 36.266115 -372.134869) (xy 36.228028 -372.079235)
			(xy 36.196879 -372.01944) (xy 36.173116 -371.956345) (xy 36.15708 -371.890858) (xy 36.149004 -371.823921)
			(xy 36.149003 -371.7565) (xy 36.157076 -371.689563) (xy 36.173109 -371.624075) (xy 36.19687 -371.560979)
			(xy 36.228017 -371.501183) (xy 36.266102 -371.445548) (xy 36.287964 -371.419882) (xy 36.293759 -371.412736)
			(xy 36.300273 -371.395546) (xy 36.300664 -371.386354) (xy 36.300664 -370.893848) (xy 36.300217 -370.884665)
			(xy 36.293727 -370.867481) (xy 36.287964 -370.86032) (xy 36.26609 -370.834664) (xy 36.228004 -370.779027)
			(xy 36.196855 -370.719229) (xy 36.173093 -370.656131) (xy 36.15706 -370.590642) (xy 36.148986 -370.523703)
			(xy 32.870915 -370.523703) (xy 32.862879 -370.590465) (xy 32.846908 -370.655846) (xy 32.823237 -370.71885)
			(xy 32.792205 -370.778573) (xy 32.754259 -370.83416) (xy 32.732472 -370.859812) (xy 32.726684 -370.866963)
			(xy 32.720165 -370.884149) (xy 32.719772 -370.89334) (xy 32.719772 -371.386862) (xy 32.720207 -371.396046)
			(xy 32.726704 -371.413231) (xy 32.732472 -371.42039) (xy 32.754273 -371.446031) (xy 32.792221 -371.501619)
			(xy 32.823253 -371.561344) (xy 32.846713 -371.623785) (xy 33.948806 -371.623785) (xy 33.94881 -371.556358)
			(xy 33.95689 -371.489417) (xy 33.97293 -371.423925) (xy 33.996699 -371.360827) (xy 34.027855 -371.30103)
			(xy 34.065949 -371.245395) (xy 34.087816 -371.21973) (xy 34.093627 -371.212595) (xy 34.100132 -371.195397)
			(xy 34.100516 -371.186202) (xy 34.100516 -371.028722) (xy 34.101044 -371.0186) (xy 34.10876 -370.999883)
			(xy 34.123033 -370.985527) (xy 34.141705 -370.977703) (xy 34.151824 -370.97716) (xy 34.868104 -370.97716)
			(xy 34.878253 -370.977618) (xy 34.896998 -370.985407) (xy 34.91132 -370.999792) (xy 34.919027 -371.018571)
			(xy 34.919412 -371.028722) (xy 34.919412 -371.186202) (xy 34.919819 -371.19539) (xy 34.926334 -371.212574)
			(xy 34.932112 -371.21973) (xy 34.953938 -371.245426) (xy 34.992027 -371.301057) (xy 35.023179 -371.360849)
			(xy 35.046945 -371.423941) (xy 35.062982 -371.489427) (xy 35.071061 -371.556361) (xy 35.071065 -371.623782)
			(xy 35.062993 -371.690717) (xy 35.046962 -371.756204) (xy 35.023202 -371.819299) (xy 34.992057 -371.879094)
			(xy 34.953973 -371.934729) (xy 34.932112 -371.960394) (xy 34.926337 -371.967555) (xy 34.919809 -371.984733)
			(xy 34.919412 -371.993922) (xy 34.919412 -372.486174) (xy 34.919832 -372.49536) (xy 34.926338 -372.512545)
			(xy 34.932112 -372.519702) (xy 34.954009 -372.54534) (xy 34.992096 -372.600979) (xy 35.023244 -372.660779)
			(xy 35.047006 -372.723879) (xy 35.063039 -372.789371) (xy 35.071112 -372.856312) (xy 35.071109 -372.923739)
			(xy 35.06303 -372.990679) (xy 35.046991 -373.05617) (xy 35.023224 -373.119268) (xy 34.99207 -373.179065)
			(xy 34.953978 -373.234701) (xy 34.932112 -373.260366) (xy 34.926306 -373.267505) (xy 34.919797 -373.2847)
			(xy 34.919412 -373.293894) (xy 34.919412 -373.451374) (xy 34.918854 -373.461493) (xy 34.911144 -373.480203)
			(xy 34.89688 -373.494559) (xy 34.878219 -373.502388) (xy 34.868104 -373.502936) (xy 34.151824 -373.502936)
			(xy 34.141676 -373.50246) (xy 34.122931 -373.494679) (xy 34.108608 -373.480299) (xy 34.100901 -373.461524)
			(xy 34.100516 -373.451374) (xy 34.100516 -373.293894) (xy 34.100105 -373.284707) (xy 34.093592 -373.267523)
			(xy 34.087816 -373.260366) (xy 34.065985 -373.234673) (xy 34.027894 -373.179043) (xy 33.996741 -373.119251)
			(xy 33.972974 -373.056158) (xy 33.956936 -372.990672) (xy 33.948857 -372.923736) (xy 33.948854 -372.856315)
			(xy 33.956927 -372.789379) (xy 33.972959 -372.723891) (xy 33.99672 -372.660796) (xy 34.027868 -372.601001)
			(xy 34.065953 -372.545367) (xy 34.087816 -372.519702) (xy 34.093596 -372.512545) (xy 34.10012 -372.495364)
			(xy 34.100516 -372.486174) (xy 34.100516 -371.993922) (xy 34.100092 -371.984736) (xy 34.093587 -371.967552)
			(xy 34.087816 -371.960394) (xy 34.065914 -371.93476) (xy 34.027826 -371.879121) (xy 33.996676 -371.819321)
			(xy 33.972913 -371.75622) (xy 33.956879 -371.690727) (xy 33.948806 -371.623785) (xy 32.846713 -371.623785)
			(xy 32.846925 -371.62435) (xy 32.862896 -371.689734) (xy 32.870939 -371.756558) (xy 32.870938 -371.823864)
			(xy 32.862892 -371.890687) (xy 32.846918 -371.95607) (xy 32.823244 -372.019075) (xy 32.79221 -372.078799)
			(xy 32.75426 -372.134386) (xy 32.732472 -372.160038) (xy 32.726673 -372.167181) (xy 32.72016 -372.184373)
			(xy 32.719772 -372.193566) (xy 32.719772 -372.351554) (xy 32.719299 -372.361721) (xy 32.711531 -372.380513)
			(xy 32.69716 -372.394899) (xy 32.678377 -372.402688) (xy 32.66821 -372.403116) (xy 31.95193 -372.403116)
			(xy 31.941755 -372.40271) (xy 31.922952 -372.394927) (xy 31.908564 -372.380535) (xy 31.900787 -372.361729)
			(xy 31.900368 -372.351554) (xy 31.900368 -372.193566) (xy 31.899959 -372.184379) (xy 31.893443 -372.167195)
			(xy 31.887668 -372.160038) (xy 31.865893 -372.134375) (xy 31.827942 -372.078791) (xy 31.796907 -372.019069)
			(xy 31.773232 -371.956066) (xy 31.757257 -371.890685) (xy 31.749211 -371.823863) (xy 31.74921 -371.756558)
			(xy 31.757253 -371.689736) (xy 31.773226 -371.624354) (xy 31.796898 -371.56135) (xy 31.827931 -371.501627)
			(xy 31.86588 -371.446042) (xy 31.887668 -371.42039) (xy 31.89346 -371.413242) (xy 31.899975 -371.396053)
			(xy 31.900368 -371.386862) (xy 31.900368 -370.89334) (xy 31.899923 -370.884157) (xy 31.893432 -370.866973)
			(xy 31.887668 -370.859812) (xy 31.865868 -370.83417) (xy 31.827917 -370.778583) (xy 31.796883 -370.718858)
			(xy 31.77321 -370.655852) (xy 31.757237 -370.590468) (xy 31.749193 -370.523644) (xy 28.471153 -370.523644)
			(xy 28.471153 -370.523703) (xy 28.463078 -370.59064) (xy 28.447043 -370.656129) (xy 28.42328 -370.719226)
			(xy 28.392129 -370.779021) (xy 28.35404 -370.834655) (xy 28.332176 -370.86032) (xy 28.326386 -370.867469)
			(xy 28.319868 -370.884657) (xy 28.319476 -370.893848) (xy 28.319476 -371.386354) (xy 28.319914 -371.395538)
			(xy 28.326409 -371.412722) (xy 28.332176 -371.419882) (xy 28.354055 -371.445535) (xy 28.392144 -371.501171)
			(xy 28.423296 -371.560969) (xy 28.446931 -371.623725) (xy 29.549038 -371.623725) (xy 29.549042 -371.556418)
			(xy 29.557089 -371.489593) (xy 29.573066 -371.424209) (xy 29.596742 -371.361203) (xy 29.627778 -371.301478)
			(xy 29.665731 -371.24589) (xy 29.68752 -371.220238) (xy 29.693328 -371.213101) (xy 29.699835 -371.195904)
			(xy 29.70022 -371.18671) (xy 29.70022 -371.028722) (xy 29.700682 -371.018554) (xy 29.708456 -370.999763)
			(xy 29.72283 -370.985378) (xy 29.741614 -370.97759) (xy 29.751782 -370.97716) (xy 30.468062 -370.97716)
			(xy 30.478234 -370.977596) (xy 30.497032 -370.985372) (xy 30.511419 -370.999755) (xy 30.519201 -371.01855)
			(xy 30.519624 -371.028722) (xy 30.519624 -371.18671) (xy 30.520024 -371.195898) (xy 30.526544 -371.213083)
			(xy 30.532324 -371.220238) (xy 30.554075 -371.24592) (xy 30.592028 -371.301502) (xy 30.623065 -371.361221)
			(xy 30.646741 -371.424221) (xy 30.662718 -371.4896) (xy 30.670766 -371.55642) (xy 30.670769 -371.623723)
			(xy 30.662728 -371.690543) (xy 30.646758 -371.755924) (xy 30.623088 -371.818927) (xy 30.592057 -371.878649)
			(xy 30.554111 -371.934234) (xy 30.532324 -371.959886) (xy 30.526511 -371.96702) (xy 30.520005 -371.984219)
			(xy 30.519624 -371.993414) (xy 30.519624 -372.486682) (xy 30.520037 -372.495869) (xy 30.526548 -372.513054)
			(xy 30.532324 -372.52021) (xy 30.554146 -372.545834) (xy 30.592096 -372.601424) (xy 30.62313 -372.661151)
			(xy 30.646803 -372.724159) (xy 30.662774 -372.789545) (xy 30.670816 -372.856371) (xy 30.670813 -372.92368)
			(xy 30.662765 -372.990505) (xy 30.646788 -373.05589) (xy 30.623109 -373.118896) (xy 30.59207 -373.17862)
			(xy 30.554115 -373.234206) (xy 30.532324 -373.259858) (xy 30.526523 -373.267) (xy 30.52001 -373.284193)
			(xy 30.519624 -373.293386) (xy 30.519624 -373.451374) (xy 30.519214 -373.461549) (xy 30.51143 -373.48035)
			(xy 30.49704 -373.494737) (xy 30.478237 -373.502516) (xy 30.468062 -373.502936) (xy 29.751782 -373.502936)
			(xy 29.741606 -373.50255) (xy 29.722806 -373.494754) (xy 29.708421 -373.480357) (xy 29.700641 -373.46155)
			(xy 29.70022 -373.451374) (xy 29.70022 -373.293386) (xy 29.699812 -373.284199) (xy 29.693297 -373.267015)
			(xy 29.68752 -373.259858) (xy 29.665767 -373.234178) (xy 29.627818 -373.178595) (xy 29.596784 -373.118875)
			(xy 29.57311 -373.055874) (xy 29.557136 -372.990496) (xy 29.549089 -372.923677) (xy 29.549086 -372.856375)
			(xy 29.557127 -372.789555) (xy 29.573095 -372.724175) (xy 29.596763 -372.661172) (xy 29.627792 -372.601449)
			(xy 29.665735 -372.545863) (xy 29.68752 -372.52021) (xy 29.69334 -372.513081) (xy 29.69984 -372.495878)
			(xy 29.70022 -372.486682) (xy 29.70022 -371.993414) (xy 29.699798 -371.984228) (xy 29.693292 -371.967044)
			(xy 29.68752 -371.959886) (xy 29.665695 -371.934264) (xy 29.627749 -371.878673) (xy 29.596718 -371.818945)
			(xy 29.573049 -371.755937) (xy 29.557079 -371.690551) (xy 29.549038 -371.623725) (xy 28.446931 -371.623725)
			(xy 28.44706 -371.624067) (xy 28.463096 -371.689558) (xy 28.471171 -371.756498) (xy 28.471169 -371.823923)
			(xy 28.463092 -371.890863) (xy 28.447054 -371.956353) (xy 28.423287 -372.01945) (xy 28.392134 -372.079247)
			(xy 28.354042 -372.134881) (xy 28.332176 -372.160546) (xy 28.326375 -372.167688) (xy 28.319864 -372.184881)
			(xy 28.319476 -372.194074) (xy 28.319476 -372.351554) (xy 28.318936 -372.361676) (xy 28.311226 -372.380393)
			(xy 28.296956 -372.39475) (xy 28.278287 -372.402574) (xy 28.268168 -372.403116) (xy 27.551888 -372.403116)
			(xy 27.541781 -372.402625) (xy 27.523105 -372.394886) (xy 27.508811 -372.380591) (xy 27.501074 -372.361916)
			(xy 27.50058 -372.351808) (xy 27.50058 -372.194074) (xy 27.500187 -372.184885) (xy 27.493662 -372.167701)
			(xy 27.48788 -372.160546) (xy 27.46603 -372.134869) (xy 27.427943 -372.079236) (xy 27.396792 -372.019441)
			(xy 27.373028 -371.956346) (xy 27.356993 -371.890858) (xy 27.348916 -371.823922) (xy 27.348915 -371.756499)
			(xy 27.356989 -371.689562) (xy 27.373022 -371.624074) (xy 27.396784 -371.560978) (xy 27.427932 -371.501182)
			(xy 27.466018 -371.445548) (xy 27.48788 -371.419882) (xy 27.493664 -371.412728) (xy 27.500187 -371.395544)
			(xy 27.50058 -371.386354) (xy 27.50058 -370.893848) (xy 27.500151 -370.884663) (xy 27.493651 -370.867478)
			(xy 27.48788 -370.86032) (xy 27.466005 -370.834664) (xy 27.427918 -370.779028) (xy 27.396769 -370.71923)
			(xy 27.373006 -370.656132) (xy 27.356972 -370.590642) (xy 27.348898 -370.523703) (xy 0.508 -370.523703)
			(xy 0.508 -372.100847) (xy 8.642336 -372.100847) (xy 8.642336 -372.040913) (xy 8.650159 -371.981491)
			(xy 8.665671 -371.923598) (xy 8.688607 -371.868226) (xy 8.718575 -371.81632) (xy 8.755061 -371.768771)
			(xy 8.797441 -371.726391) (xy 8.84499 -371.689905) (xy 8.896896 -371.659937) (xy 8.952268 -371.637001)
			(xy 9.010161 -371.621489) (xy 9.069583 -371.613666) (xy 9.09955 -371.613176) (xy 9.96315 -371.613176)
			(xy 9.993118 -371.613658) (xy 10.052541 -371.621481) (xy 10.110435 -371.636994) (xy 10.165808 -371.65993)
			(xy 10.217714 -371.689898) (xy 10.265264 -371.726385) (xy 10.307645 -371.768766) (xy 10.344132 -371.816316)
			(xy 10.3741 -371.868222) (xy 10.397036 -371.923595) (xy 10.412549 -371.981489) (xy 10.420372 -372.040912)
			(xy 10.420372 -372.100848) (xy 10.412549 -372.160271) (xy 10.397036 -372.218165) (xy 10.3741 -372.273538)
			(xy 10.344132 -372.325444) (xy 10.307645 -372.372994) (xy 10.265264 -372.415375) (xy 10.217714 -372.451862)
			(xy 10.165808 -372.48183) (xy 10.110435 -372.504766) (xy 10.052541 -372.520279) (xy 9.993118 -372.528102)
			(xy 9.96315 -372.528592) (xy 9.09955 -372.528592) (xy 9.069583 -372.528094) (xy 9.010161 -372.520271)
			(xy 8.952268 -372.504759) (xy 8.896896 -372.481823) (xy 8.84499 -372.451855) (xy 8.797441 -372.415369)
			(xy 8.755061 -372.372989) (xy 8.718575 -372.32544) (xy 8.688607 -372.273534) (xy 8.665671 -372.218162)
			(xy 8.650159 -372.160269) (xy 8.642336 -372.100847) (xy 0.508 -372.100847) (xy 0.508 -374.423871)
			(xy 27.348897 -374.423871) (xy 27.348897 -374.356446) (xy 27.356974 -374.289508) (xy 27.37301 -374.224019)
			(xy 27.396774 -374.160922) (xy 27.427926 -374.101125) (xy 27.466016 -374.045491) (xy 27.48788 -374.019826)
			(xy 27.493688 -374.012689) (xy 27.500197 -373.995492) (xy 27.50058 -373.986298) (xy 27.50058 -373.828818)
			(xy 27.501042 -373.818688) (xy 27.508772 -373.799959) (xy 27.523066 -373.785601) (xy 27.54176 -373.777788)
			(xy 27.551888 -373.777256) (xy 28.268168 -373.777256) (xy 28.278269 -373.77781) (xy 28.296938 -373.785529)
			(xy 28.311233 -373.799804) (xy 28.318977 -373.818463) (xy 28.319476 -373.828564) (xy 28.319476 -373.986298)
			(xy 28.319892 -373.995484) (xy 28.326402 -374.012669) (xy 28.332176 -374.019826) (xy 28.354038 -374.045493)
			(xy 28.392127 -374.101127) (xy 28.423278 -374.160923) (xy 28.447043 -374.22402) (xy 28.463078 -374.289509)
			(xy 28.471154 -374.356447) (xy 28.471155 -374.423823) (xy 31.749171 -374.423823) (xy 31.749175 -374.356514)
			(xy 31.757224 -374.289688) (xy 31.773202 -374.224303) (xy 31.796881 -374.161297) (xy 31.827921 -374.101572)
			(xy 31.865877 -374.045986) (xy 31.887668 -374.020334) (xy 31.893483 -374.013202) (xy 31.899985 -373.996001)
			(xy 31.900368 -373.986806) (xy 31.900368 -373.828818) (xy 31.900779 -373.818644) (xy 31.908564 -373.799844)
			(xy 31.922954 -373.785457) (xy 31.941756 -373.777677) (xy 31.95193 -373.777256) (xy 32.66821 -373.777256)
			(xy 32.678384 -373.777656) (xy 32.697183 -373.785448) (xy 32.711568 -373.799841) (xy 32.719349 -373.818643)
			(xy 32.719772 -373.828818) (xy 32.719772 -373.986806) (xy 32.720185 -373.995993) (xy 32.726697 -374.013177)
			(xy 32.732472 -374.020334) (xy 32.754218 -374.04602) (xy 32.792167 -374.101602) (xy 32.823202 -374.161321)
			(xy 32.846876 -374.224321) (xy 32.862852 -374.289699) (xy 32.870899 -374.356518) (xy 32.870903 -374.423819)
			(xy 32.870895 -374.423882) (xy 36.148964 -374.423882) (xy 36.148968 -374.356455) (xy 36.157048 -374.289515)
			(xy 36.173087 -374.224024) (xy 36.196854 -374.160925) (xy 36.228007 -374.101128) (xy 36.266099 -374.045492)
			(xy 36.287964 -374.019826) (xy 36.293782 -374.012697) (xy 36.300282 -373.995494) (xy 36.300664 -373.986298)
			(xy 36.300664 -373.828818) (xy 36.301142 -373.818689) (xy 36.308868 -373.799964) (xy 36.323158 -373.785606)
			(xy 36.341846 -373.777791) (xy 36.351972 -373.777256) (xy 37.068252 -373.777256) (xy 37.078398 -373.77776)
			(xy 37.09714 -373.785532) (xy 37.111464 -373.799903) (xy 37.119173 -373.818671) (xy 37.11956 -373.828818)
			(xy 37.11956 -373.986298) (xy 37.11998 -373.995484) (xy 37.126488 -374.012668) (xy 37.13226 -374.019826)
			(xy 37.154084 -374.045525) (xy 37.192177 -374.101153) (xy 37.223331 -374.160945) (xy 37.2471 -374.224037)
			(xy 37.263139 -374.289523) (xy 37.271219 -374.356458) (xy 37.271223 -374.423879) (xy 37.271223 -374.423882)
			(xy 40.548731 -374.423882) (xy 40.548735 -374.356454) (xy 40.556815 -374.289512) (xy 40.572857 -374.22402)
			(xy 40.596628 -374.160921) (xy 40.627787 -374.101124) (xy 40.665884 -374.04549) (xy 40.687752 -374.019826)
			(xy 40.693569 -374.012695) (xy 40.70007 -373.995494) (xy 40.700452 -373.986298) (xy 40.700452 -373.828818)
			(xy 40.700942 -373.818691) (xy 40.708666 -373.799968) (xy 40.722951 -373.785611) (xy 40.741636 -373.777793)
			(xy 40.75176 -373.777256) (xy 41.46804 -373.777256) (xy 41.478191 -373.777688) (xy 41.496936 -373.785489)
			(xy 41.511256 -373.799881) (xy 41.518963 -373.818665) (xy 41.519348 -373.828818) (xy 41.519348 -373.986298)
			(xy 41.519771 -373.995484) (xy 41.526277 -374.012667) (xy 41.532048 -374.019826) (xy 41.553873 -374.045524)
			(xy 41.591966 -374.101153) (xy 41.623121 -374.160944) (xy 41.64689 -374.224037) (xy 41.66293 -374.289522)
			(xy 41.67101 -374.356458) (xy 41.671014 -374.423823) (xy 44.94905 -374.423823) (xy 44.949054 -374.356514)
			(xy 44.957102 -374.289689) (xy 44.97308 -374.224304) (xy 44.996757 -374.161298) (xy 45.027796 -374.101573)
			(xy 45.06575 -374.045986) (xy 45.08754 -374.020334) (xy 45.093352 -374.0132) (xy 45.099857 -373.996001)
			(xy 45.10024 -373.986806) (xy 45.10024 -373.828818) (xy 45.100678 -373.818647) (xy 45.108458 -373.799853)
			(xy 45.122839 -373.785467) (xy 45.141631 -373.777682) (xy 45.151802 -373.777256) (xy 45.868082 -373.777256)
			(xy 45.878255 -373.777679) (xy 45.897053 -373.785461) (xy 45.911439 -373.799847) (xy 45.919221 -373.818645)
			(xy 45.919644 -373.828818) (xy 45.919644 -373.986806) (xy 45.920064 -373.995992) (xy 45.926572 -374.013176)
			(xy 45.932344 -374.020334) (xy 45.954091 -374.04602) (xy 45.992042 -374.101601) (xy 46.023078 -374.16132)
			(xy 46.046754 -374.22432) (xy 46.06273 -374.289698) (xy 46.070778 -374.356517) (xy 46.070782 -374.423819)
			(xy 46.070774 -374.423882) (xy 71.348786 -374.423882) (xy 71.348789 -374.356455) (xy 71.356869 -374.289514)
			(xy 71.372909 -374.224023) (xy 71.396677 -374.160924) (xy 71.427833 -374.101127) (xy 71.465926 -374.045491)
			(xy 71.487792 -374.019826) (xy 71.493602 -374.01269) (xy 71.500109 -373.995492) (xy 71.500492 -373.986298)
			(xy 71.500492 -373.828818) (xy 71.50104 -373.818698) (xy 71.508753 -373.799987) (xy 71.52302 -373.785631)
			(xy 71.541684 -373.777803) (xy 71.5518 -373.777256) (xy 72.26808 -373.777256) (xy 72.278227 -373.777737)
			(xy 72.296971 -373.785518) (xy 72.311293 -373.799896) (xy 72.319002 -373.818669) (xy 72.319388 -373.828818)
			(xy 72.319388 -373.986298) (xy 72.319802 -373.995485) (xy 72.326313 -374.012669) (xy 72.332088 -374.019826)
			(xy 72.353911 -374.045525) (xy 72.392002 -374.101154) (xy 72.423155 -374.160946) (xy 72.446922 -374.224038)
			(xy 72.462961 -374.289523) (xy 72.47104 -374.356458) (xy 72.471044 -374.423823) (xy 75.749081 -374.423823)
			(xy 75.749084 -374.356514) (xy 75.757133 -374.289688) (xy 75.773112 -374.224303) (xy 75.796791 -374.161296)
			(xy 75.827832 -374.101572) (xy 75.865788 -374.045985) (xy 75.88758 -374.020334) (xy 75.893385 -374.013194)
			(xy 75.899895 -373.996) (xy 75.90028 -373.986806) (xy 75.90028 -373.828818) (xy 75.900679 -373.818642)
			(xy 75.908466 -373.79984) (xy 75.92286 -373.785453) (xy 75.941666 -373.777675) (xy 75.951842 -373.777256)
			(xy 76.668122 -373.777256) (xy 76.678283 -373.777716) (xy 76.697057 -373.785501) (xy 76.711422 -373.799877)
			(xy 76.719192 -373.818656) (xy 76.719684 -373.828818) (xy 76.719684 -373.986806) (xy 76.720095 -373.995993)
			(xy 76.726608 -374.013177) (xy 76.732384 -374.020334) (xy 76.754129 -374.046021) (xy 76.792078 -374.101603)
			(xy 76.823112 -374.161322) (xy 76.846786 -374.224322) (xy 76.862761 -374.289699) (xy 76.870808 -374.356518)
			(xy 76.870812 -374.423819) (xy 76.870804 -374.423882) (xy 80.148873 -374.423882) (xy 80.148877 -374.356455)
			(xy 80.156957 -374.289515) (xy 80.172996 -374.224023) (xy 80.196764 -374.160925) (xy 80.227918 -374.101127)
			(xy 80.26601 -374.045492) (xy 80.287876 -374.019826) (xy 80.293684 -374.012689) (xy 80.300193 -373.995492)
			(xy 80.300576 -373.986298) (xy 80.300576 -373.828818) (xy 80.301042 -373.818688) (xy 80.308771 -373.79996)
			(xy 80.323064 -373.785602) (xy 80.341756 -373.777789) (xy 80.351884 -373.777256) (xy 81.068164 -373.777256)
			(xy 81.078265 -373.777814) (xy 81.096934 -373.785531) (xy 81.111228 -373.799806) (xy 81.118972 -373.818464)
			(xy 81.119472 -373.828564) (xy 81.119472 -373.986298) (xy 81.119889 -373.995484) (xy 81.126399 -374.012668)
			(xy 81.132172 -374.019826) (xy 81.153996 -374.045525) (xy 81.192087 -374.101154) (xy 81.223242 -374.160945)
			(xy 81.247009 -374.224038) (xy 81.263049 -374.289523) (xy 81.271128 -374.356458) (xy 81.271132 -374.423879)
			(xy 81.271132 -374.423882) (xy 84.548664 -374.423882) (xy 84.548668 -374.356455) (xy 84.556748 -374.289515)
			(xy 84.572787 -374.224024) (xy 84.596554 -374.160925) (xy 84.627707 -374.101128) (xy 84.665799 -374.045492)
			(xy 84.687664 -374.019826) (xy 84.693482 -374.012697) (xy 84.699982 -373.995494) (xy 84.700364 -373.986298)
			(xy 84.700364 -373.828818) (xy 84.700842 -373.818689) (xy 84.708568 -373.799964) (xy 84.722858 -373.785606)
			(xy 84.741546 -373.777791) (xy 84.751672 -373.777256) (xy 85.467952 -373.777256) (xy 85.478066 -373.777754)
			(xy 85.49676 -373.785478) (xy 85.511074 -373.799769) (xy 85.518829 -373.818451) (xy 85.51926 -373.828564)
			(xy 85.51926 -373.986298) (xy 85.51968 -373.995484) (xy 85.526188 -374.012668) (xy 85.53196 -374.019826)
			(xy 85.553784 -374.045525) (xy 85.591877 -374.101153) (xy 85.623031 -374.160945) (xy 85.6468 -374.224037)
			(xy 85.662839 -374.289523) (xy 85.670919 -374.356458) (xy 85.670923 -374.423822) (xy 115.349223 -374.423822)
			(xy 115.349227 -374.356515) (xy 115.357275 -374.28969) (xy 115.373251 -374.224306) (xy 115.396927 -374.1613)
			(xy 115.427963 -374.101574) (xy 115.465915 -374.045987) (xy 115.487704 -374.020334) (xy 115.493512 -374.013197)
			(xy 115.50002 -373.996) (xy 115.500404 -373.986806) (xy 115.500404 -373.828818) (xy 115.500947 -373.818666)
			(xy 115.508709 -373.799903) (xy 115.52306 -373.785539) (xy 115.541814 -373.777757) (xy 115.551966 -373.777256)
			(xy 116.268246 -373.777256) (xy 116.278409 -373.777696) (xy 116.297183 -373.785489) (xy 116.311547 -373.799871)
			(xy 116.319316 -373.818654) (xy 116.319808 -373.828818) (xy 116.319808 -373.986806) (xy 116.320214 -373.995994)
			(xy 116.32673 -374.013178) (xy 116.332508 -374.020334) (xy 116.354256 -374.046019) (xy 116.39221 -374.1016)
			(xy 116.423248 -374.161318) (xy 116.446925 -374.224319) (xy 116.462903 -374.289697) (xy 116.470951 -374.356517)
			(xy 116.470955 -374.42382) (xy 116.470948 -374.423882) (xy 119.748992 -374.423882) (xy 119.748995 -374.356455)
			(xy 119.757075 -374.289514) (xy 119.773115 -374.224022) (xy 119.796884 -374.160924) (xy 119.82804 -374.101126)
			(xy 119.866134 -374.045491) (xy 119.888 -374.019826) (xy 119.89381 -374.012691) (xy 119.900317 -373.995493)
			(xy 119.9007 -373.986298) (xy 119.9007 -373.828818) (xy 119.90124 -373.818697) (xy 119.908955 -373.799984)
			(xy 119.923224 -373.785629) (xy 119.94189 -373.777802) (xy 119.952008 -373.777256) (xy 120.668288 -373.777256)
			(xy 120.678436 -373.777731) (xy 120.69718 -373.785514) (xy 120.711502 -373.799894) (xy 120.71921 -373.818669)
			(xy 120.719596 -373.828818) (xy 120.719596 -373.986298) (xy 120.720008 -373.995485) (xy 120.726521 -374.012669)
			(xy 120.732296 -374.019826) (xy 120.754119 -374.045525) (xy 120.792209 -374.101155) (xy 120.823362 -374.160946)
			(xy 120.847129 -374.224039) (xy 120.863167 -374.289524) (xy 120.871246 -374.356458) (xy 120.87125 -374.423823)
			(xy 124.149287 -374.423823) (xy 124.149291 -374.356514) (xy 124.15734 -374.289688) (xy 124.173319 -374.224302)
			(xy 124.196998 -374.161296) (xy 124.228039 -374.101572) (xy 124.265996 -374.045986) (xy 124.287788 -374.020334)
			(xy 124.293594 -374.013195) (xy 124.300103 -373.996) (xy 124.300488 -373.986806) (xy 124.300488 -373.828818)
			(xy 124.30088 -373.818641) (xy 124.308668 -373.799837) (xy 124.323064 -373.78545) (xy 124.341873 -373.777673)
			(xy 124.35205 -373.777256) (xy 125.06833 -373.777256) (xy 125.078492 -373.777709) (xy 125.097265 -373.785497)
			(xy 125.11163 -373.799875) (xy 125.1194 -373.818656) (xy 125.119892 -373.828818) (xy 125.119892 -373.986806)
			(xy 125.120301 -373.995993) (xy 125.126816 -374.013177) (xy 125.132592 -374.020334) (xy 125.154338 -374.04602)
			(xy 125.192286 -374.101603) (xy 125.223319 -374.161322) (xy 125.246993 -374.224322) (xy 125.262968 -374.2897)
			(xy 125.271015 -374.356518) (xy 125.271019 -374.423819) (xy 125.271019 -374.423823) (xy 128.549078 -374.423823)
			(xy 128.549081 -374.356514) (xy 128.55713 -374.289688) (xy 128.573109 -374.224303) (xy 128.596788 -374.161296)
			(xy 128.627828 -374.101572) (xy 128.665784 -374.045985) (xy 128.687576 -374.020334) (xy 128.69338 -374.013194)
			(xy 128.699891 -373.996) (xy 128.700276 -373.986806) (xy 128.700276 -373.828818) (xy 128.700679 -373.818643)
			(xy 128.708465 -373.799841) (xy 128.722858 -373.785454) (xy 128.741663 -373.777675) (xy 128.751838 -373.777256)
			(xy 129.468118 -373.777256) (xy 129.478279 -373.777719) (xy 129.497052 -373.785503) (xy 129.511418 -373.799878)
			(xy 129.519188 -373.818656) (xy 129.51968 -373.828818) (xy 129.51968 -373.986806) (xy 129.520092 -373.995993)
			(xy 129.526605 -374.013177) (xy 129.53238 -374.020334) (xy 129.554126 -374.046021) (xy 129.592074 -374.101603)
			(xy 129.623108 -374.161322) (xy 129.646783 -374.224321) (xy 129.662758 -374.289699) (xy 129.670805 -374.356518)
			(xy 129.670809 -374.423819) (xy 129.670809 -374.423822) (xy 159.349132 -374.423822) (xy 159.349136 -374.356514)
			(xy 159.357184 -374.289689) (xy 159.373161 -374.224305) (xy 159.396837 -374.161299) (xy 159.427874 -374.101574)
			(xy 159.465826 -374.045986) (xy 159.487616 -374.020334) (xy 159.493425 -374.013198) (xy 159.499932 -373.996)
			(xy 159.500316 -373.986806) (xy 159.500316 -373.828818) (xy 159.500847 -373.818664) (xy 159.508612 -373.799899)
			(xy 159.522966 -373.785534) (xy 159.541724 -373.777755) (xy 159.551878 -373.777256) (xy 160.268158 -373.777256)
			(xy 160.278329 -373.777699) (xy 160.297126 -373.785473) (xy 160.311513 -373.799854) (xy 160.319297 -373.818647)
			(xy 160.31972 -373.828818) (xy 160.31972 -373.986806) (xy 160.320123 -373.995994) (xy 160.326641 -374.013179)
			(xy 160.33242 -374.020334) (xy 160.354168 -374.04602) (xy 160.39212 -374.1016) (xy 160.423158 -374.161319)
			(xy 160.446835 -374.224319) (xy 160.462812 -374.289698) (xy 160.47086 -374.356517) (xy 160.470864 -374.42382)
			(xy 160.470857 -374.423882) (xy 163.748901 -374.423882) (xy 163.748904 -374.356455) (xy 163.756985 -374.289514)
			(xy 163.773025 -374.224022) (xy 163.796794 -374.160923) (xy 163.827951 -374.101126) (xy 163.866045 -374.045491)
			(xy 163.887912 -374.019826) (xy 163.893724 -374.012692) (xy 163.900229 -373.995493) (xy 163.900612 -373.986298)
			(xy 163.900612 -373.828818) (xy 163.90114 -373.818696) (xy 163.908857 -373.79998) (xy 163.92313 -373.785624)
			(xy 163.941801 -373.7778) (xy 163.95192 -373.777256) (xy 164.6682 -373.777256) (xy 164.678349 -373.777721)
			(xy 164.697092 -373.785508) (xy 164.711414 -373.799891) (xy 164.719122 -373.818668) (xy 164.719508 -373.828818)
			(xy 164.719508 -373.986298) (xy 164.719917 -373.995485) (xy 164.726431 -374.01267) (xy 164.732208 -374.019826)
			(xy 164.75403 -374.045525) (xy 164.79212 -374.101155) (xy 164.823272 -374.160947) (xy 164.847038 -374.224039)
			(xy 164.863076 -374.289524) (xy 164.871155 -374.356458) (xy 164.871159 -374.423822) (xy 168.14922 -374.423822)
			(xy 168.149224 -374.356515) (xy 168.157272 -374.28969) (xy 168.173248 -374.224306) (xy 168.196924 -374.1613)
			(xy 168.22796 -374.101575) (xy 168.265911 -374.045987) (xy 168.2877 -374.020334) (xy 168.293507 -374.013196)
			(xy 168.300015 -373.996) (xy 168.3004 -373.986806) (xy 168.3004 -373.828818) (xy 168.300947 -373.818666)
			(xy 168.308709 -373.799905) (xy 168.323058 -373.78554) (xy 168.341811 -373.777758) (xy 168.351962 -373.777256)
			(xy 169.068242 -373.777256) (xy 169.078405 -373.777699) (xy 169.097178 -373.785491) (xy 169.111543 -373.799872)
			(xy 169.119312 -373.818655) (xy 169.119804 -373.828818) (xy 169.119804 -373.986806) (xy 169.120211 -373.995994)
			(xy 169.126727 -374.013178) (xy 169.132504 -374.020334) (xy 169.154249 -374.046021) (xy 169.192196 -374.101603)
			(xy 169.223229 -374.161322) (xy 169.246902 -374.224322) (xy 169.262877 -374.2897) (xy 169.270924 -374.356518)
			(xy 169.270928 -374.423819) (xy 169.270928 -374.423823) (xy 172.548987 -374.423823) (xy 172.548991 -374.356514)
			(xy 172.55704 -374.289688) (xy 172.573019 -374.224302) (xy 172.596698 -374.161296) (xy 172.627739 -374.101572)
			(xy 172.665696 -374.045986) (xy 172.687488 -374.020334) (xy 172.693294 -374.013195) (xy 172.699803 -373.996)
			(xy 172.700188 -373.986806) (xy 172.700188 -373.828818) (xy 172.70058 -373.818641) (xy 172.708368 -373.799837)
			(xy 172.722764 -373.78545) (xy 172.741573 -373.777673) (xy 172.75175 -373.777256) (xy 173.46803 -373.777256)
			(xy 173.478192 -373.777709) (xy 173.496965 -373.785497) (xy 173.51133 -373.799875) (xy 173.5191 -373.818656)
			(xy 173.519592 -373.828818) (xy 173.519592 -373.986806) (xy 173.520001 -373.995993) (xy 173.526516 -374.013177)
			(xy 173.532292 -374.020334) (xy 173.554038 -374.04602) (xy 173.591986 -374.101603) (xy 173.623019 -374.161322)
			(xy 173.646693 -374.224322) (xy 173.662668 -374.2897) (xy 173.670715 -374.356518) (xy 173.670719 -374.423819)
			(xy 173.662679 -374.490638) (xy 173.646712 -374.556018) (xy 173.623045 -374.61902) (xy 173.592018 -374.678743)
			(xy 173.554076 -374.73433) (xy 173.532292 -374.759982) (xy 173.526477 -374.767114) (xy 173.519974 -374.784315)
			(xy 173.519592 -374.79351) (xy 173.519592 -375.286778) (xy 173.520015 -375.295964) (xy 173.52652 -375.313148)
			(xy 173.532292 -375.320306) (xy 173.554108 -375.345934) (xy 173.592054 -375.401525) (xy 173.623084 -375.461252)
			(xy 173.646754 -375.52426) (xy 173.662724 -375.589644) (xy 173.670765 -375.656469) (xy 173.670763 -375.723776)
			(xy 173.662716 -375.7906) (xy 173.646741 -375.855984) (xy 173.623066 -375.918989) (xy 173.592031 -375.978714)
			(xy 173.554081 -376.034301) (xy 173.532292 -376.059954) (xy 173.526489 -376.067095) (xy 173.519978 -376.084289)
			(xy 173.519592 -376.093482) (xy 173.519592 -376.25147) (xy 173.519043 -376.261622) (xy 173.511284 -376.280385)
			(xy 173.496935 -376.29475) (xy 173.478182 -376.302531) (xy 173.46803 -376.303032) (xy 172.75175 -376.303032)
			(xy 172.741578 -376.302595) (xy 172.722779 -376.29482) (xy 172.708391 -376.280438) (xy 172.700609 -376.261642)
			(xy 172.700188 -376.25147) (xy 172.700188 -376.093482) (xy 172.699789 -376.084294) (xy 172.693268 -376.067109)
			(xy 172.687488 -376.059954) (xy 172.665728 -376.034278) (xy 172.627775 -375.978696) (xy 172.596738 -375.918976)
			(xy 172.573061 -375.855975) (xy 172.557085 -375.790595) (xy 172.549038 -375.723774) (xy 172.549035 -375.656471)
			(xy 172.557077 -375.589649) (xy 172.573048 -375.524268) (xy 172.59672 -375.461265) (xy 172.627752 -375.401542)
			(xy 172.665701 -375.345957) (xy 172.687488 -375.320306) (xy 172.693263 -375.313145) (xy 172.699791 -375.295967)
			(xy 172.700188 -375.286778) (xy 172.700188 -374.79351) (xy 172.699776 -374.784323) (xy 172.693264 -374.767138)
			(xy 172.687488 -374.759982) (xy 172.665658 -374.734364) (xy 172.627707 -374.678774) (xy 172.596673 -374.619046)
			(xy 172.573 -374.556037) (xy 172.557029 -374.49065) (xy 172.548987 -374.423823) (xy 169.270928 -374.423823)
			(xy 169.262888 -374.490638) (xy 169.246921 -374.556017) (xy 169.223255 -374.61902) (xy 169.192229 -374.678743)
			(xy 169.154288 -374.734329) (xy 169.132504 -374.759982) (xy 169.126691 -374.767115) (xy 169.120186 -374.784315)
			(xy 169.119804 -374.79351) (xy 169.119804 -375.286778) (xy 169.120224 -375.295964) (xy 169.126731 -375.313149)
			(xy 169.132504 -375.320306) (xy 169.15432 -375.345935) (xy 169.192265 -375.401525) (xy 169.223295 -375.461253)
			(xy 169.246964 -375.52426) (xy 169.262933 -375.589645) (xy 169.270974 -375.656469) (xy 169.270972 -375.723776)
			(xy 169.262925 -375.7906) (xy 169.24695 -375.855983) (xy 169.223276 -375.918989) (xy 169.192242 -375.978713)
			(xy 169.154292 -376.034301) (xy 169.132504 -376.059954) (xy 169.126702 -376.067096) (xy 169.120191 -376.084289)
			(xy 169.119804 -376.093482) (xy 169.119804 -376.25147) (xy 169.119243 -376.261621) (xy 169.111487 -376.280381)
			(xy 169.097142 -376.294746) (xy 169.078392 -376.302529) (xy 169.068242 -376.303032) (xy 168.351962 -376.303032)
			(xy 168.341798 -376.302597) (xy 168.323022 -376.294804) (xy 168.308657 -376.280421) (xy 168.30089 -376.261635)
			(xy 168.3004 -376.25147) (xy 168.3004 -376.093482) (xy 168.299998 -376.084294) (xy 168.293479 -376.06711)
			(xy 168.2877 -376.059954) (xy 168.265943 -376.034277) (xy 168.227996 -375.978693) (xy 168.196963 -375.918973)
			(xy 168.173291 -375.855972) (xy 168.157317 -375.790593) (xy 168.149271 -375.723774) (xy 168.149268 -375.656472)
			(xy 168.157309 -375.589652) (xy 168.173277 -375.524272) (xy 168.196945 -375.461269) (xy 168.227973 -375.401546)
			(xy 168.265915 -375.345959) (xy 168.2877 -375.320306) (xy 168.293477 -375.313147) (xy 168.300003 -375.295967)
			(xy 168.3004 -375.286778) (xy 168.3004 -374.79351) (xy 168.299985 -374.784323) (xy 168.293475 -374.767139)
			(xy 168.2877 -374.759982) (xy 168.265872 -374.734363) (xy 168.227927 -374.678771) (xy 168.196898 -374.619043)
			(xy 168.173229 -374.556034) (xy 168.15726 -374.490648) (xy 168.14922 -374.423822) (xy 164.871159 -374.423822)
			(xy 164.871159 -374.423879) (xy 164.863088 -374.490814) (xy 164.847057 -374.5563) (xy 164.823298 -374.619396)
			(xy 164.792152 -374.679191) (xy 164.754069 -374.734825) (xy 164.732208 -374.76049) (xy 164.726392 -374.767621)
			(xy 164.719889 -374.784822) (xy 164.719508 -374.794018) (xy 164.719508 -375.28627) (xy 164.719931 -375.295456)
			(xy 164.726435 -375.31264) (xy 164.732208 -375.319798) (xy 164.754101 -375.345439) (xy 164.792188 -375.401077)
			(xy 164.823337 -375.460877) (xy 164.8471 -375.523977) (xy 164.863133 -375.589469) (xy 164.871206 -375.65641)
			(xy 164.871203 -375.723835) (xy 164.863125 -375.790776) (xy 164.847086 -375.856266) (xy 164.823319 -375.919364)
			(xy 164.792165 -375.979161) (xy 164.754073 -376.034797) (xy 164.732208 -376.060462) (xy 164.726404 -376.067602)
			(xy 164.719893 -376.084796) (xy 164.719508 -376.09399) (xy 164.719508 -376.25147) (xy 164.71895 -376.261589)
			(xy 164.711241 -376.2803) (xy 164.696977 -376.294656) (xy 164.678316 -376.302485) (xy 164.6682 -376.303032)
			(xy 163.95192 -376.303032) (xy 163.941771 -376.302563) (xy 163.923025 -376.29478) (xy 163.908702 -376.280398)
			(xy 163.900996 -376.26162) (xy 163.900612 -376.25147) (xy 163.900612 -376.09399) (xy 163.900204 -376.084803)
			(xy 163.893689 -376.067618) (xy 163.887912 -376.060462) (xy 163.866077 -376.034773) (xy 163.827987 -375.979142)
			(xy 163.796834 -375.919349) (xy 163.773068 -375.856255) (xy 163.75703 -375.790769) (xy 163.748951 -375.723833)
			(xy 163.748949 -375.656412) (xy 163.757022 -375.589475) (xy 163.773054 -375.523988) (xy 163.796816 -375.460892)
			(xy 163.827963 -375.401097) (xy 163.866049 -375.345463) (xy 163.887912 -375.319798) (xy 163.893693 -375.312642)
			(xy 163.900217 -375.29546) (xy 163.900612 -375.28627) (xy 163.900612 -374.794018) (xy 163.90019 -374.784832)
			(xy 163.893684 -374.767648) (xy 163.887912 -374.76049) (xy 163.866006 -374.734859) (xy 163.827918 -374.67922)
			(xy 163.796769 -374.619419) (xy 163.773006 -374.556318) (xy 163.756973 -374.490824) (xy 163.748901 -374.423882)
			(xy 160.470857 -374.423882) (xy 160.462823 -374.49064) (xy 160.446853 -374.556021) (xy 160.423184 -374.619023)
			(xy 160.392153 -374.678745) (xy 160.354206 -374.73433) (xy 160.33242 -374.759982) (xy 160.326608 -374.767117)
			(xy 160.320102 -374.784315) (xy 160.31972 -374.79351) (xy 160.31972 -375.286778) (xy 160.320136 -375.295965)
			(xy 160.326645 -375.313149) (xy 160.33242 -375.320306) (xy 160.354238 -375.345933) (xy 160.392189 -375.401522)
			(xy 160.423223 -375.461249) (xy 160.446896 -375.524257) (xy 160.462868 -375.589643) (xy 160.470911 -375.656468)
			(xy 160.470908 -375.723777) (xy 160.46286 -375.790602) (xy 160.446883 -375.855986) (xy 160.423205 -375.918992)
			(xy 160.392166 -375.978716) (xy 160.354211 -376.034302) (xy 160.33242 -376.059954) (xy 160.32662 -376.067097)
			(xy 160.320107 -376.084289) (xy 160.31972 -376.093482) (xy 160.31972 -376.25147) (xy 160.31931 -376.261645)
			(xy 160.311528 -376.280447) (xy 160.297137 -376.294834) (xy 160.278333 -376.302613) (xy 160.268158 -376.303032)
			(xy 159.551878 -376.303032) (xy 159.541701 -376.302653) (xy 159.5229 -376.294855) (xy 159.508515 -376.280456)
			(xy 159.500737 -376.261647) (xy 159.500316 -376.25147) (xy 159.500316 -376.093482) (xy 159.499911 -376.084294)
			(xy 159.493393 -376.06711) (xy 159.487616 -376.059954) (xy 159.465858 -376.034277) (xy 159.42791 -375.978694)
			(xy 159.396877 -375.918973) (xy 159.373203 -375.855972) (xy 159.357229 -375.790593) (xy 159.349183 -375.723774)
			(xy 159.34918 -375.656471) (xy 159.357221 -375.589651) (xy 159.37319 -375.524271) (xy 159.396858 -375.461268)
			(xy 159.427887 -375.401545) (xy 159.465831 -375.345958) (xy 159.487616 -375.320306) (xy 159.493394 -375.313148)
			(xy 159.499919 -375.295967) (xy 159.500316 -375.286778) (xy 159.500316 -374.79351) (xy 159.499897 -374.784324)
			(xy 159.493389 -374.76714) (xy 159.487616 -374.759982) (xy 159.465788 -374.734364) (xy 159.427842 -374.678772)
			(xy 159.396811 -374.619043) (xy 159.373142 -374.556034) (xy 159.357173 -374.490648) (xy 159.349132 -374.423822)
			(xy 129.670809 -374.423822) (xy 129.662769 -374.490638) (xy 129.646801 -374.556018) (xy 129.623134 -374.619021)
			(xy 129.592107 -374.678743) (xy 129.554164 -374.734329) (xy 129.53238 -374.759982) (xy 129.526564 -374.767113)
			(xy 129.520062 -374.784315) (xy 129.51968 -374.79351) (xy 129.51968 -375.286778) (xy 129.520105 -375.295963)
			(xy 129.526609 -375.313148) (xy 129.53238 -375.320306) (xy 129.554197 -375.345934) (xy 129.592143 -375.401524)
			(xy 129.623174 -375.461252) (xy 129.646845 -375.524259) (xy 129.662815 -375.589644) (xy 129.670856 -375.656469)
			(xy 129.670854 -375.723776) (xy 129.662807 -375.7906) (xy 129.646831 -375.855984) (xy 129.623156 -375.91899)
			(xy 129.59212 -375.978714) (xy 129.554169 -376.034302) (xy 129.53238 -376.059954) (xy 129.526576 -376.067094)
			(xy 129.520066 -376.084288) (xy 129.51968 -376.093482) (xy 129.51968 -376.25147) (xy 129.519212 -376.261637)
			(xy 129.51144 -376.280428) (xy 129.497068 -376.294813) (xy 129.478285 -376.302602) (xy 129.468118 -376.303032)
			(xy 128.751838 -376.303032) (xy 128.741665 -376.302604) (xy 128.722866 -376.294826) (xy 128.708478 -376.280441)
			(xy 128.700697 -376.261643) (xy 128.700276 -376.25147) (xy 128.700276 -376.093482) (xy 128.69988 -376.084293)
			(xy 128.693357 -376.067109) (xy 128.687576 -376.059954) (xy 128.665817 -376.034278) (xy 128.627865 -375.978696)
			(xy 128.596828 -375.918976) (xy 128.573152 -375.855974) (xy 128.557176 -375.790595) (xy 128.549129 -375.723774)
			(xy 128.549126 -375.656471) (xy 128.557168 -375.58965) (xy 128.573138 -375.524269) (xy 128.59681 -375.461265)
			(xy 128.627841 -375.401543) (xy 128.665789 -375.345958) (xy 128.687576 -375.320306) (xy 128.69335 -375.313144)
			(xy 128.699879 -375.295967) (xy 128.700276 -375.286778) (xy 128.700276 -374.79351) (xy 128.699866 -374.784323)
			(xy 128.693353 -374.767138) (xy 128.687576 -374.759982) (xy 128.665746 -374.734365) (xy 128.627796 -374.678774)
			(xy 128.596762 -374.619046) (xy 128.57309 -374.556037) (xy 128.557119 -374.49065) (xy 128.549078 -374.423823)
			(xy 125.271019 -374.423823) (xy 125.262979 -374.490638) (xy 125.247012 -374.556018) (xy 125.223345 -374.61902)
			(xy 125.192318 -374.678743) (xy 125.154376 -374.73433) (xy 125.132592 -374.759982) (xy 125.126777 -374.767114)
			(xy 125.120274 -374.784315) (xy 125.119892 -374.79351) (xy 125.119892 -375.286778) (xy 125.120315 -375.295964)
			(xy 125.12682 -375.313148) (xy 125.132592 -375.320306) (xy 125.154408 -375.345934) (xy 125.192354 -375.401525)
			(xy 125.223384 -375.461252) (xy 125.247054 -375.52426) (xy 125.263024 -375.589644) (xy 125.271065 -375.656469)
			(xy 125.271063 -375.723776) (xy 125.263016 -375.7906) (xy 125.247041 -375.855984) (xy 125.223366 -375.918989)
			(xy 125.192331 -375.978714) (xy 125.154381 -376.034301) (xy 125.132592 -376.059954) (xy 125.126789 -376.067095)
			(xy 125.120278 -376.084289) (xy 125.119892 -376.093482) (xy 125.119892 -376.25147) (xy 125.119343 -376.261622)
			(xy 125.111584 -376.280385) (xy 125.097235 -376.29475) (xy 125.078482 -376.302531) (xy 125.06833 -376.303032)
			(xy 124.35205 -376.303032) (xy 124.341878 -376.302595) (xy 124.323079 -376.29482) (xy 124.308691 -376.280438)
			(xy 124.300909 -376.261642) (xy 124.300488 -376.25147) (xy 124.300488 -376.093482) (xy 124.300089 -376.084294)
			(xy 124.293568 -376.067109) (xy 124.287788 -376.059954) (xy 124.266028 -376.034278) (xy 124.228075 -375.978696)
			(xy 124.197038 -375.918976) (xy 124.173361 -375.855975) (xy 124.157385 -375.790595) (xy 124.149338 -375.723774)
			(xy 124.149335 -375.656471) (xy 124.157377 -375.589649) (xy 124.173348 -375.524268) (xy 124.19702 -375.461265)
			(xy 124.228052 -375.401542) (xy 124.266001 -375.345957) (xy 124.287788 -375.320306) (xy 124.293563 -375.313145)
			(xy 124.300091 -375.295967) (xy 124.300488 -375.286778) (xy 124.300488 -374.79351) (xy 124.300076 -374.784323)
			(xy 124.293564 -374.767138) (xy 124.287788 -374.759982) (xy 124.265958 -374.734364) (xy 124.228007 -374.678774)
			(xy 124.196973 -374.619046) (xy 124.1733 -374.556037) (xy 124.157329 -374.49065) (xy 124.149287 -374.423823)
			(xy 120.87125 -374.423823) (xy 120.87125 -374.423879) (xy 120.863178 -374.490814) (xy 120.847147 -374.556301)
			(xy 120.823388 -374.619396) (xy 120.792242 -374.679191) (xy 120.754158 -374.734825) (xy 120.732296 -374.76049)
			(xy 120.726478 -374.76762) (xy 120.719976 -374.784822) (xy 120.719596 -374.794018) (xy 120.719596 -375.28627)
			(xy 120.720022 -375.295456) (xy 120.726525 -375.31264) (xy 120.732296 -375.319798) (xy 120.75419 -375.345439)
			(xy 120.792278 -375.401077) (xy 120.823427 -375.460876) (xy 120.84719 -375.523976) (xy 120.863223 -375.589468)
			(xy 120.871297 -375.656409) (xy 120.871294 -375.723836) (xy 120.863215 -375.790776) (xy 120.847177 -375.856267)
			(xy 120.823409 -375.919365) (xy 120.792254 -375.979162) (xy 120.754162 -376.034797) (xy 120.732296 -376.060462)
			(xy 120.72649 -376.067601) (xy 120.719981 -376.084796) (xy 120.719596 -376.09399) (xy 120.719596 -376.25147)
			(xy 120.71905 -376.26159) (xy 120.711339 -376.280304) (xy 120.697071 -376.29466) (xy 120.678405 -376.302487)
			(xy 120.668288 -376.303032) (xy 119.952008 -376.303032) (xy 119.941858 -376.302572) (xy 119.923112 -376.294786)
			(xy 119.90879 -376.280401) (xy 119.901084 -376.261621) (xy 119.9007 -376.25147) (xy 119.9007 -376.09399)
			(xy 119.900294 -376.084802) (xy 119.893777 -376.067618) (xy 119.888 -376.060462) (xy 119.866166 -376.034772)
			(xy 119.828076 -375.979141) (xy 119.796924 -375.919349) (xy 119.773158 -375.856255) (xy 119.75712 -375.790769)
			(xy 119.749042 -375.723833) (xy 119.749039 -375.656412) (xy 119.757112 -375.589476) (xy 119.773145 -375.523988)
			(xy 119.796905 -375.460893) (xy 119.828053 -375.401097) (xy 119.866138 -375.345463) (xy 119.888 -375.319798)
			(xy 119.89378 -375.312641) (xy 119.900305 -375.29546) (xy 119.9007 -375.28627) (xy 119.9007 -374.794018)
			(xy 119.900281 -374.784832) (xy 119.893773 -374.767647) (xy 119.888 -374.76049) (xy 119.866095 -374.734859)
			(xy 119.828007 -374.679219) (xy 119.796858 -374.619418) (xy 119.773097 -374.556317) (xy 119.757064 -374.490824)
			(xy 119.748992 -374.423882) (xy 116.470948 -374.423882) (xy 116.462914 -374.49064) (xy 116.446944 -374.556021)
			(xy 116.423273 -374.619024) (xy 116.392242 -374.678746) (xy 116.354295 -374.734331) (xy 116.332508 -374.759982)
			(xy 116.326695 -374.767116) (xy 116.32019 -374.784315) (xy 116.319808 -374.79351) (xy 116.319808 -375.286778)
			(xy 116.320227 -375.295964) (xy 116.326734 -375.313149) (xy 116.332508 -375.320306) (xy 116.354327 -375.345933)
			(xy 116.392278 -375.401522) (xy 116.423313 -375.461249) (xy 116.446986 -375.524256) (xy 116.462959 -375.589642)
			(xy 116.471001 -375.656468) (xy 116.470999 -375.723777) (xy 116.462951 -375.790602) (xy 116.446973 -375.855987)
			(xy 116.423295 -375.918993) (xy 116.392255 -375.978717) (xy 116.354299 -376.034303) (xy 116.332508 -376.059954)
			(xy 116.326707 -376.067096) (xy 116.320195 -376.084289) (xy 116.319808 -376.093482) (xy 116.319808 -376.25147)
			(xy 116.319243 -376.26162) (xy 116.311487 -376.28038) (xy 116.297144 -376.294745) (xy 116.278395 -376.302528)
			(xy 116.268246 -376.303032) (xy 115.551966 -376.303032) (xy 115.541802 -376.302594) (xy 115.523027 -376.294803)
			(xy 115.508662 -376.28042) (xy 115.500894 -376.261634) (xy 115.500404 -376.25147) (xy 115.500404 -376.093482)
			(xy 115.500002 -376.084294) (xy 115.493483 -376.06711) (xy 115.487704 -376.059954) (xy 115.465947 -376.034277)
			(xy 115.427999 -375.978693) (xy 115.396967 -375.918973) (xy 115.373294 -375.855972) (xy 115.35732 -375.790593)
			(xy 115.349274 -375.723774) (xy 115.349271 -375.656472) (xy 115.357312 -375.589652) (xy 115.37328 -375.524271)
			(xy 115.396948 -375.461268) (xy 115.427976 -375.401545) (xy 115.465919 -375.345959) (xy 115.487704 -375.320306)
			(xy 115.493481 -375.313147) (xy 115.500007 -375.295967) (xy 115.500404 -375.286778) (xy 115.500404 -374.79351)
			(xy 115.499988 -374.784323) (xy 115.493478 -374.767139) (xy 115.487704 -374.759982) (xy 115.465876 -374.734363)
			(xy 115.427931 -374.678771) (xy 115.396901 -374.619043) (xy 115.373232 -374.556034) (xy 115.357263 -374.490648)
			(xy 115.349223 -374.423822) (xy 85.670923 -374.423822) (xy 85.670923 -374.423879) (xy 85.662851 -374.490815)
			(xy 85.646818 -374.556302) (xy 85.623057 -374.619398) (xy 85.591909 -374.679192) (xy 85.553823 -374.734826)
			(xy 85.53196 -374.76049) (xy 85.526138 -374.767617) (xy 85.519639 -374.784822) (xy 85.51926 -374.794018)
			(xy 85.51926 -375.28627) (xy 85.519694 -375.295454) (xy 85.526192 -375.312639) (xy 85.53196 -375.319798)
			(xy 85.553855 -375.345438) (xy 85.591945 -375.401075) (xy 85.623097 -375.460875) (xy 85.646861 -375.523975)
			(xy 85.662896 -375.589467) (xy 85.67097 -375.656409) (xy 85.670967 -375.723836) (xy 85.662888 -375.790777)
			(xy 85.646848 -375.856268) (xy 85.623079 -375.919367) (xy 85.591922 -375.979163) (xy 85.553827 -376.034797)
			(xy 85.53196 -376.060462) (xy 85.52615 -376.067597) (xy 85.519644 -376.084796) (xy 85.51926 -376.09399)
			(xy 85.51926 -376.25147) (xy 85.518749 -376.261595) (xy 85.511031 -376.280315) (xy 85.496752 -376.294673)
			(xy 85.478074 -376.302493) (xy 85.467952 -376.303032) (xy 84.751672 -376.303032) (xy 84.741565 -376.302539)
			(xy 84.722893 -376.294798) (xy 84.7086 -376.280504) (xy 84.700861 -376.261831) (xy 84.700364 -376.251724)
			(xy 84.700364 -376.09399) (xy 84.699944 -376.084804) (xy 84.693436 -376.06762) (xy 84.687664 -376.060462)
			(xy 84.665831 -376.034772) (xy 84.627744 -375.97914) (xy 84.596594 -375.919347) (xy 84.572829 -375.856253)
			(xy 84.556793 -375.790768) (xy 84.548715 -375.723833) (xy 84.548712 -375.656412) (xy 84.556785 -375.589477)
			(xy 84.572816 -375.52399) (xy 84.596575 -375.460894) (xy 84.62772 -375.401099) (xy 84.665803 -375.345464)
			(xy 84.687664 -375.319798) (xy 84.693452 -375.312647) (xy 84.69997 -375.295461) (xy 84.700364 -375.28627)
			(xy 84.700364 -374.794018) (xy 84.699931 -374.784834) (xy 84.693432 -374.76765) (xy 84.687664 -374.76049)
			(xy 84.66576 -374.734858) (xy 84.627675 -374.679218) (xy 84.596528 -374.619417) (xy 84.572768 -374.556316)
			(xy 84.556736 -374.490823) (xy 84.548664 -374.423882) (xy 81.271132 -374.423882) (xy 81.26306 -374.490815)
			(xy 81.247028 -374.556302) (xy 81.223267 -374.619397) (xy 81.19212 -374.679192) (xy 81.154034 -374.734825)
			(xy 81.132172 -374.76049) (xy 81.126351 -374.767618) (xy 81.119852 -374.784822) (xy 81.119472 -374.794018)
			(xy 81.119472 -375.28627) (xy 81.119903 -375.295455) (xy 81.126403 -375.312639) (xy 81.132172 -375.319798)
			(xy 81.154066 -375.345438) (xy 81.192156 -375.401076) (xy 81.223307 -375.460875) (xy 81.247071 -375.523975)
			(xy 81.263105 -375.589468) (xy 81.271179 -375.656409) (xy 81.271176 -375.723836) (xy 81.263097 -375.790777)
			(xy 81.247057 -375.856268) (xy 81.223289 -375.919366) (xy 81.192133 -375.979163) (xy 81.154039 -376.034797)
			(xy 81.132172 -376.060462) (xy 81.126363 -376.067598) (xy 81.119856 -376.084796) (xy 81.119472 -376.09399)
			(xy 81.119472 -376.25147) (xy 81.118949 -376.261593) (xy 81.111234 -376.280312) (xy 81.096958 -376.294669)
			(xy 81.078284 -376.302491) (xy 81.068164 -376.303032) (xy 80.351884 -376.303032) (xy 80.341778 -376.302529)
			(xy 80.323106 -376.294792) (xy 80.308813 -376.280501) (xy 80.301073 -376.26183) (xy 80.300576 -376.251724)
			(xy 80.300576 -376.09399) (xy 80.300176 -376.084802) (xy 80.293656 -376.067617) (xy 80.287876 -376.060462)
			(xy 80.266042 -376.034772) (xy 80.227954 -375.97914) (xy 80.196804 -375.919347) (xy 80.173039 -375.856254)
			(xy 80.157002 -375.790768) (xy 80.148924 -375.723833) (xy 80.148921 -375.656412) (xy 80.156994 -375.589476)
			(xy 80.173025 -375.523989) (xy 80.196785 -375.460894) (xy 80.227931 -375.401098) (xy 80.266015 -375.345464)
			(xy 80.287876 -375.319798) (xy 80.293653 -375.312639) (xy 80.30018 -375.295459) (xy 80.300576 -375.28627)
			(xy 80.300576 -374.794018) (xy 80.300163 -374.784831) (xy 80.293652 -374.767646) (xy 80.287876 -374.76049)
			(xy 80.265972 -374.734858) (xy 80.227886 -374.679218) (xy 80.196738 -374.619417) (xy 80.172977 -374.556316)
			(xy 80.156946 -374.490823) (xy 80.148873 -374.423882) (xy 76.870804 -374.423882) (xy 76.862772 -374.490638)
			(xy 76.846805 -374.556018) (xy 76.823138 -374.619021) (xy 76.79211 -374.678743) (xy 76.754168 -374.734329)
			(xy 76.732384 -374.759982) (xy 76.726568 -374.767114) (xy 76.720066 -374.784315) (xy 76.719684 -374.79351)
			(xy 76.719684 -375.286778) (xy 76.720108 -375.295964) (xy 76.726613 -375.313148) (xy 76.732384 -375.320306)
			(xy 76.754201 -375.345934) (xy 76.792147 -375.401525) (xy 76.823178 -375.461252) (xy 76.846848 -375.524259)
			(xy 76.862818 -375.589644) (xy 76.870859 -375.656469) (xy 76.870857 -375.723776) (xy 76.86281 -375.7906)
			(xy 76.846834 -375.855984) (xy 76.823159 -375.91899) (xy 76.792124 -375.978714) (xy 76.754173 -376.034302)
			(xy 76.732384 -376.059954) (xy 76.72658 -376.067094) (xy 76.72007 -376.084289) (xy 76.719684 -376.093482)
			(xy 76.719684 -376.25147) (xy 76.719212 -376.261637) (xy 76.711441 -376.280427) (xy 76.69707 -376.294812)
			(xy 76.678288 -376.302602) (xy 76.668122 -376.303032) (xy 75.951842 -376.303032) (xy 75.941669 -376.302601)
			(xy 75.92287 -376.294824) (xy 75.908482 -376.28044) (xy 75.900701 -376.261643) (xy 75.90028 -376.25147)
			(xy 75.90028 -376.093482) (xy 75.899883 -376.084293) (xy 75.893361 -376.067109) (xy 75.88758 -376.059954)
			(xy 75.865821 -376.034278) (xy 75.827868 -375.978696) (xy 75.796831 -375.918976) (xy 75.773155 -375.855975)
			(xy 75.757179 -375.790595) (xy 75.749132 -375.723774) (xy 75.749129 -375.656471) (xy 75.757171 -375.58965)
			(xy 75.773142 -375.524269) (xy 75.796813 -375.461265) (xy 75.827845 -375.401543) (xy 75.865793 -375.345958)
			(xy 75.88758 -375.320306) (xy 75.893354 -375.313145) (xy 75.899883 -375.295967) (xy 75.90028 -375.286778)
			(xy 75.90028 -374.79351) (xy 75.89987 -374.784323) (xy 75.893357 -374.767138) (xy 75.88758 -374.759982)
			(xy 75.865749 -374.734365) (xy 75.827799 -374.678774) (xy 75.796765 -374.619046) (xy 75.773093 -374.556037)
			(xy 75.757122 -374.49065) (xy 75.749081 -374.423823) (xy 72.471044 -374.423823) (xy 72.471044 -374.423879)
			(xy 72.462972 -374.490814) (xy 72.446941 -374.556301) (xy 72.423181 -374.619396) (xy 72.392034 -374.679191)
			(xy 72.35395 -374.734825) (xy 72.332088 -374.76049) (xy 72.326269 -374.76762) (xy 72.319768 -374.784822)
			(xy 72.319388 -374.794018) (xy 72.319388 -375.28627) (xy 72.319815 -375.295455) (xy 72.326317 -375.31264)
			(xy 72.332088 -375.319798) (xy 72.353982 -375.345439) (xy 72.39207 -375.401076) (xy 72.423221 -375.460876)
			(xy 72.446984 -375.523976) (xy 72.463017 -375.589468) (xy 72.471091 -375.656409) (xy 72.471088 -375.723836)
			(xy 72.463009 -375.790776) (xy 72.44697 -375.856267) (xy 72.423202 -375.919365) (xy 72.392047 -375.979162)
			(xy 72.353954 -376.034797) (xy 72.332088 -376.060462) (xy 72.326281 -376.0676) (xy 72.319773 -376.084796)
			(xy 72.319388 -376.09399) (xy 72.319388 -376.25147) (xy 72.31885 -376.261591) (xy 72.311137 -376.280307)
			(xy 72.296867 -376.294663) (xy 72.278198 -376.302488) (xy 72.26808 -376.303032) (xy 71.5518 -376.303032)
			(xy 71.54165 -376.302579) (xy 71.522904 -376.294789) (xy 71.508582 -376.280403) (xy 71.500876 -376.261622)
			(xy 71.500492 -376.25147) (xy 71.500492 -376.09399) (xy 71.500088 -376.084802) (xy 71.49357 -376.067618)
			(xy 71.487792 -376.060462) (xy 71.465958 -376.034772) (xy 71.427869 -375.979141) (xy 71.396717 -375.919348)
			(xy 71.372952 -375.856255) (xy 71.356914 -375.790769) (xy 71.348836 -375.723833) (xy 71.348833 -375.656412)
			(xy 71.356906 -375.589476) (xy 71.372938 -375.523989) (xy 71.396699 -375.460893) (xy 71.427845 -375.401098)
			(xy 71.46593 -375.345463) (xy 71.487792 -375.319798) (xy 71.493571 -375.31264) (xy 71.500096 -375.295459)
			(xy 71.500492 -375.28627) (xy 71.500492 -374.794018) (xy 71.500075 -374.784832) (xy 71.493566 -374.767647)
			(xy 71.487792 -374.76049) (xy 71.465887 -374.734859) (xy 71.4278 -374.679219) (xy 71.396652 -374.619418)
			(xy 71.37289 -374.556317) (xy 71.356858 -374.490824) (xy 71.348786 -374.423882) (xy 46.070774 -374.423882)
			(xy 46.062742 -374.490639) (xy 46.046773 -374.55602) (xy 46.023104 -374.619022) (xy 45.992075 -374.678745)
			(xy 45.95413 -374.73433) (xy 45.932344 -374.759982) (xy 45.926523 -374.76711) (xy 45.920025 -374.784314)
			(xy 45.919644 -374.79351) (xy 45.919644 -375.286778) (xy 45.920077 -375.295962) (xy 45.926576 -375.313146)
			(xy 45.932344 -375.320306) (xy 45.954162 -375.345934) (xy 45.992111 -375.401523) (xy 46.023144 -375.46125)
			(xy 46.046816 -375.524258) (xy 46.062787 -375.589643) (xy 46.070829 -375.656469) (xy 46.070826 -375.723776)
			(xy 46.062779 -375.790601) (xy 46.046802 -375.855985) (xy 46.023125 -375.918991) (xy 45.992088 -375.978716)
			(xy 45.954134 -376.034302) (xy 45.932344 -376.059954) (xy 45.926535 -376.06709) (xy 45.920029 -376.084288)
			(xy 45.919644 -376.093482) (xy 45.919644 -376.25147) (xy 45.919211 -376.261642) (xy 45.911433 -376.280439)
			(xy 45.897049 -376.294826) (xy 45.878254 -376.302609) (xy 45.868082 -376.303032) (xy 45.151802 -376.303032)
			(xy 45.141627 -376.302634) (xy 45.122826 -376.294844) (xy 45.10844 -376.28045) (xy 45.100661 -376.261645)
			(xy 45.10024 -376.25147) (xy 45.10024 -376.093482) (xy 45.09983 -376.084295) (xy 45.093315 -376.067111)
			(xy 45.08754 -376.059954) (xy 45.065782 -376.034277) (xy 45.027832 -375.978695) (xy 44.996798 -375.918974)
			(xy 44.973123 -375.855973) (xy 44.957148 -375.790594) (xy 44.949101 -375.723774) (xy 44.949099 -375.656471)
			(xy 44.95714 -375.589651) (xy 44.97311 -375.52427) (xy 44.996779 -375.461267) (xy 45.027809 -375.401544)
			(xy 45.065754 -375.345958) (xy 45.08754 -375.320306) (xy 45.093322 -375.31315) (xy 45.099844 -375.295968)
			(xy 45.10024 -375.286778) (xy 45.10024 -374.79351) (xy 45.099816 -374.784324) (xy 45.093311 -374.76714)
			(xy 45.08754 -374.759982) (xy 45.065711 -374.734364) (xy 45.027763 -374.678773) (xy 44.996732 -374.619044)
			(xy 44.973061 -374.556035) (xy 44.957091 -374.490649) (xy 44.94905 -374.423823) (xy 41.671014 -374.423823)
			(xy 41.671014 -374.423879) (xy 41.662941 -374.490816) (xy 41.646909 -374.556303) (xy 41.623147 -374.619398)
			(xy 41.591998 -374.679193) (xy 41.553911 -374.734826) (xy 41.532048 -374.76049) (xy 41.526224 -374.767616)
			(xy 41.519727 -374.784821) (xy 41.519348 -374.794018) (xy 41.519348 -375.28627) (xy 41.519784 -375.295454)
			(xy 41.526281 -375.312638) (xy 41.532048 -375.319798) (xy 41.553943 -375.345438) (xy 41.592035 -375.401075)
			(xy 41.623187 -375.460874) (xy 41.646952 -375.523974) (xy 41.662987 -375.589467) (xy 41.671061 -375.656409)
			(xy 41.671058 -375.723836) (xy 41.662978 -375.790777) (xy 41.646938 -375.856269) (xy 41.623168 -375.919367)
			(xy 41.592011 -375.979164) (xy 41.553916 -376.034798) (xy 41.532048 -376.060462) (xy 41.526236 -376.067596)
			(xy 41.519732 -376.084795) (xy 41.519348 -376.09399) (xy 41.519348 -376.25147) (xy 41.518849 -376.261596)
			(xy 41.511129 -376.280319) (xy 41.496846 -376.294677) (xy 41.478164 -376.302495) (xy 41.46804 -376.303032)
			(xy 40.75176 -376.303032) (xy 40.741607 -376.302612) (xy 40.72286 -376.294809) (xy 40.708539 -376.280413)
			(xy 40.700835 -376.261625) (xy 40.700452 -376.25147) (xy 40.700452 -376.09399) (xy 40.700035 -376.084804)
			(xy 40.693525 -376.06762) (xy 40.687752 -376.060462) (xy 40.665916 -376.034773) (xy 40.627823 -375.979143)
			(xy 40.596668 -375.919351) (xy 40.5729 -375.856257) (xy 40.55686 -375.79077) (xy 40.548781 -375.723834)
			(xy 40.548779 -375.656411) (xy 40.556852 -375.589474) (xy 40.572886 -375.523986) (xy 40.596649 -375.46089)
			(xy 40.627799 -375.401095) (xy 40.665888 -375.345462) (xy 40.687752 -375.319798) (xy 40.693538 -375.312646)
			(xy 40.700058 -375.29546) (xy 40.700452 -375.28627) (xy 40.700452 -374.794018) (xy 40.700022 -374.784833)
			(xy 40.693521 -374.767649) (xy 40.687752 -374.76049) (xy 40.665845 -374.73486) (xy 40.627754 -374.679221)
			(xy 40.596602 -374.619421) (xy 40.572838 -374.556319) (xy 40.556804 -374.490825) (xy 40.548731 -374.423882)
			(xy 37.271223 -374.423882) (xy 37.263151 -374.490815) (xy 37.247118 -374.556302) (xy 37.223357 -374.619398)
			(xy 37.192209 -374.679192) (xy 37.154123 -374.734826) (xy 37.13226 -374.76049) (xy 37.126438 -374.767617)
			(xy 37.119939 -374.784822) (xy 37.11956 -374.794018) (xy 37.11956 -375.28627) (xy 37.119994 -375.295454)
			(xy 37.126492 -375.312639) (xy 37.13226 -375.319798) (xy 37.154155 -375.345438) (xy 37.192245 -375.401075)
			(xy 37.223397 -375.460875) (xy 37.247161 -375.523975) (xy 37.263196 -375.589467) (xy 37.27127 -375.656409)
			(xy 37.271267 -375.723836) (xy 37.263188 -375.790777) (xy 37.247148 -375.856268) (xy 37.223379 -375.919367)
			(xy 37.192222 -375.979163) (xy 37.154127 -376.034797) (xy 37.13226 -376.060462) (xy 37.12645 -376.067597)
			(xy 37.119944 -376.084796) (xy 37.11956 -376.09399) (xy 37.11956 -376.25147) (xy 37.119049 -376.261595)
			(xy 37.111331 -376.280315) (xy 37.097052 -376.294673) (xy 37.078374 -376.302493) (xy 37.068252 -376.303032)
			(xy 36.351972 -376.303032) (xy 36.34182 -376.302602) (xy 36.323073 -376.294803) (xy 36.308752 -376.28041)
			(xy 36.301047 -376.261624) (xy 36.300664 -376.25147) (xy 36.300664 -376.09399) (xy 36.300244 -376.084804)
			(xy 36.293736 -376.06762) (xy 36.287964 -376.060462) (xy 36.266131 -376.034772) (xy 36.228044 -375.97914)
			(xy 36.196894 -375.919347) (xy 36.173129 -375.856253) (xy 36.157093 -375.790768) (xy 36.149015 -375.723833)
			(xy 36.149012 -375.656412) (xy 36.157085 -375.589477) (xy 36.173116 -375.52399) (xy 36.196875 -375.460894)
			(xy 36.22802 -375.401099) (xy 36.266103 -375.345464) (xy 36.287964 -375.319798) (xy 36.293752 -375.312647)
			(xy 36.30027 -375.295461) (xy 36.300664 -375.28627) (xy 36.300664 -374.794018) (xy 36.300231 -374.784834)
			(xy 36.293732 -374.76765) (xy 36.287964 -374.76049) (xy 36.26606 -374.734858) (xy 36.227975 -374.679218)
			(xy 36.196828 -374.619417) (xy 36.173068 -374.556316) (xy 36.157036 -374.490823) (xy 36.148964 -374.423882)
			(xy 32.870895 -374.423882) (xy 32.862863 -374.490639) (xy 32.846895 -374.556018) (xy 32.823227 -374.619021)
			(xy 32.7922 -374.678743) (xy 32.754257 -374.73433) (xy 32.732472 -374.759982) (xy 32.726654 -374.767112)
			(xy 32.720153 -374.784314) (xy 32.719772 -374.79351) (xy 32.719772 -375.286778) (xy 32.720199 -375.295963)
			(xy 32.726702 -375.313147) (xy 32.732472 -375.320306) (xy 32.754289 -375.345934) (xy 32.792236 -375.401524)
			(xy 32.823268 -375.461251) (xy 32.846938 -375.524259) (xy 32.862909 -375.589644) (xy 32.87095 -375.656469)
			(xy 32.870948 -375.723776) (xy 32.862901 -375.790601) (xy 32.846925 -375.855984) (xy 32.823249 -375.91899)
			(xy 32.792213 -375.978715) (xy 32.754261 -376.034302) (xy 32.732472 -376.059954) (xy 32.726666 -376.067093)
			(xy 32.720158 -376.084288) (xy 32.719772 -376.093482) (xy 32.719772 -376.25147) (xy 32.719312 -376.261638)
			(xy 32.711538 -376.28043) (xy 32.697164 -376.294816) (xy 32.678378 -376.302604) (xy 32.66821 -376.303032)
			(xy 31.95193 -376.303032) (xy 31.941757 -376.302611) (xy 31.922957 -376.29483) (xy 31.90857 -376.280443)
			(xy 31.900789 -376.261643) (xy 31.900368 -376.25147) (xy 31.900368 -376.093482) (xy 31.899951 -376.084296)
			(xy 31.89344 -376.067112) (xy 31.887668 -376.059954) (xy 31.865909 -376.034278) (xy 31.827957 -375.978696)
			(xy 31.796921 -375.918976) (xy 31.773245 -375.855974) (xy 31.75727 -375.790595) (xy 31.749223 -375.723774)
			(xy 31.74922 -375.656471) (xy 31.757261 -375.58965) (xy 31.773232 -375.524269) (xy 31.796903 -375.461266)
			(xy 31.827934 -375.401543) (xy 31.865881 -375.345958) (xy 31.887668 -375.320306) (xy 31.893453 -375.313153)
			(xy 31.899973 -375.295968) (xy 31.900368 -375.286778) (xy 31.900368 -374.79351) (xy 31.899938 -374.784325)
			(xy 31.893436 -374.767142) (xy 31.887668 -374.759982) (xy 31.865838 -374.734364) (xy 31.827888 -374.678774)
			(xy 31.796855 -374.619046) (xy 31.773184 -374.556036) (xy 31.757213 -374.49065) (xy 31.749171 -374.423823)
			(xy 28.471155 -374.423823) (xy 28.471155 -374.42387) (xy 28.463079 -374.490809) (xy 28.447044 -374.556297)
			(xy 28.423279 -374.619394) (xy 28.392129 -374.67919) (xy 28.35404 -374.734825) (xy 28.332176 -374.76049)
			(xy 28.326356 -374.767618) (xy 28.319856 -374.784822) (xy 28.319476 -374.794018) (xy 28.319476 -375.28627)
			(xy 28.319906 -375.295455) (xy 28.326407 -375.312639) (xy 28.332176 -375.319798) (xy 28.35407 -375.345439)
			(xy 28.39216 -375.401076) (xy 28.42331 -375.460875) (xy 28.447074 -375.523976) (xy 28.463108 -375.589468)
			(xy 28.471182 -375.656409) (xy 28.471179 -375.723836) (xy 28.4631 -375.790777) (xy 28.447061 -375.856268)
			(xy 28.423292 -375.919366) (xy 28.392136 -375.979163) (xy 28.354043 -376.034797) (xy 28.332176 -376.060462)
			(xy 28.326368 -376.067599) (xy 28.319861 -376.084796) (xy 28.319476 -376.09399) (xy 28.319476 -376.25147)
			(xy 28.31895 -376.261593) (xy 28.311235 -376.28031) (xy 28.29696 -376.294667) (xy 28.278288 -376.30249)
			(xy 28.268168 -376.303032) (xy 27.551888 -376.303032) (xy 27.541783 -376.302525) (xy 27.52311 -376.29479)
			(xy 27.508817 -376.2805) (xy 27.501077 -376.261829) (xy 27.50058 -376.251724) (xy 27.50058 -376.09399)
			(xy 27.500179 -376.084802) (xy 27.493659 -376.067617) (xy 27.48788 -376.060462) (xy 27.466046 -376.034772)
			(xy 27.427958 -375.979141) (xy 27.396807 -375.919348) (xy 27.373042 -375.856254) (xy 27.357005 -375.790768)
			(xy 27.348927 -375.723833) (xy 27.348924 -375.656412) (xy 27.356997 -375.589476) (xy 27.373029 -375.523989)
			(xy 27.396789 -375.460894) (xy 27.427935 -375.401098) (xy 27.466019 -375.345464) (xy 27.48788 -375.319798)
			(xy 27.493658 -375.312639) (xy 27.500184 -375.295459) (xy 27.50058 -375.28627) (xy 27.50058 -374.794018)
			(xy 27.500166 -374.784831) (xy 27.493655 -374.767646) (xy 27.48788 -374.76049) (xy 27.466014 -374.734827)
			(xy 27.427924 -374.679192) (xy 27.396773 -374.619396) (xy 27.373009 -374.556299) (xy 27.356973 -374.490809)
			(xy 27.348897 -374.423871) (xy 0.508 -374.423871) (xy 0.508 -376.756551) (xy 29.549067 -376.756551)
			(xy 29.557111 -376.689729) (xy 29.573083 -376.624347) (xy 29.596754 -376.561343) (xy 29.627786 -376.501619)
			(xy 29.665733 -376.446032) (xy 29.68752 -376.42038) (xy 29.69331 -376.41323) (xy 29.699828 -376.396043)
			(xy 29.70022 -376.386852) (xy 29.70022 -375.893584) (xy 29.699813 -375.884397) (xy 29.693297 -375.867212)
			(xy 29.68752 -375.860056) (xy 29.665765 -375.834378) (xy 29.627816 -375.778794) (xy 29.596782 -375.719074)
			(xy 29.573109 -375.656073) (xy 29.557134 -375.590694) (xy 29.549088 -375.523875) (xy 29.549085 -375.456573)
			(xy 29.557126 -375.389753) (xy 29.573095 -375.324373) (xy 29.596763 -375.26137) (xy 29.627791 -375.201647)
			(xy 29.665735 -375.146061) (xy 29.68752 -375.120408) (xy 29.693298 -375.11325) (xy 29.699823 -375.096069)
			(xy 29.70022 -375.08688) (xy 29.70022 -374.928638) (xy 29.700695 -374.918471) (xy 29.708464 -374.899681)
			(xy 29.722834 -374.885295) (xy 29.741616 -374.877506) (xy 29.751782 -374.877076) (xy 30.468062 -374.877076)
			(xy 30.478236 -374.877496) (xy 30.497037 -374.885276) (xy 30.511424 -374.899663) (xy 30.519204 -374.918464)
			(xy 30.519624 -374.928638) (xy 30.519624 -375.08688) (xy 30.520038 -375.096067) (xy 30.526548 -375.113252)
			(xy 30.532324 -375.120408) (xy 30.554144 -375.146034) (xy 30.592094 -375.201623) (xy 30.623128 -375.26135)
			(xy 30.646801 -375.324358) (xy 30.662773 -375.389744) (xy 30.670815 -375.45657) (xy 30.670812 -375.523878)
			(xy 30.662764 -375.590704) (xy 30.646787 -375.656088) (xy 30.623109 -375.719094) (xy 30.59207 -375.778818)
			(xy 30.554115 -375.834404) (xy 30.532324 -375.860056) (xy 30.526524 -375.867199) (xy 30.520011 -375.884391)
			(xy 30.519624 -375.893584) (xy 30.519624 -376.386852) (xy 30.520052 -376.396037) (xy 30.526553 -376.413222)
			(xy 30.532324 -376.42038) (xy 30.554117 -376.446028) (xy 30.592068 -376.501615) (xy 30.623103 -376.561338)
			(xy 30.646777 -376.624343) (xy 30.662751 -376.689726) (xy 30.670795 -376.75655) (xy 30.670795 -376.823856)
			(xy 30.670788 -376.823915) (xy 33.948836 -376.823915) (xy 33.948836 -376.756491) (xy 33.956911 -376.689553)
			(xy 33.972947 -376.624064) (xy 33.996711 -376.560967) (xy 34.027862 -376.501171) (xy 34.065952 -376.445537)
			(xy 34.087816 -376.419872) (xy 34.093609 -376.412724) (xy 34.100125 -376.395536) (xy 34.100516 -376.386344)
			(xy 34.100516 -375.894092) (xy 34.100106 -375.884905) (xy 34.093592 -375.867721) (xy 34.087816 -375.860564)
			(xy 34.065983 -375.834873) (xy 34.027892 -375.779243) (xy 33.996739 -375.71945) (xy 33.972973 -375.656357)
			(xy 33.956934 -375.59087) (xy 33.948856 -375.523935) (xy 33.948853 -375.456513) (xy 33.956926 -375.389577)
			(xy 33.972958 -375.324089) (xy 33.99672 -375.260994) (xy 34.027867 -375.201199) (xy 34.065953 -375.145565)
			(xy 34.087816 -375.1199) (xy 34.093597 -375.112744) (xy 34.10012 -375.095562) (xy 34.100516 -375.086372)
			(xy 34.100516 -374.928638) (xy 34.101057 -374.918517) (xy 34.108768 -374.899801) (xy 34.123038 -374.885444)
			(xy 34.141706 -374.87762) (xy 34.151824 -374.877076) (xy 34.868104 -374.877076) (xy 34.878255 -374.877518)
			(xy 34.897003 -374.88531) (xy 34.911325 -374.8997) (xy 34.919029 -374.918485) (xy 34.919412 -374.928638)
			(xy 34.919412 -375.086372) (xy 34.919833 -375.095558) (xy 34.926339 -375.112743) (xy 34.932112 -375.1199)
			(xy 34.954007 -375.14554) (xy 34.992094 -375.201178) (xy 35.023243 -375.260978) (xy 35.047004 -375.324078)
			(xy 35.063037 -375.38957) (xy 35.07111 -375.456511) (xy 35.071108 -375.523937) (xy 35.063029 -375.590877)
			(xy 35.04699 -375.656368) (xy 35.023223 -375.719466) (xy 34.992069 -375.779263) (xy 34.953977 -375.834899)
			(xy 34.932112 -375.860564) (xy 34.926307 -375.867703) (xy 34.919797 -375.884898) (xy 34.919412 -375.894092)
			(xy 34.919412 -376.386344) (xy 34.919798 -376.395534) (xy 34.926328 -376.412718) (xy 34.932112 -376.419872)
			(xy 34.953979 -376.445534) (xy 34.992067 -376.501169) (xy 35.023217 -376.560966) (xy 35.046981 -376.624063)
			(xy 35.063015 -376.689553) (xy 35.071091 -376.756491) (xy 35.071091 -376.756551) (xy 38.349155 -376.756551)
			(xy 38.357198 -376.689729) (xy 38.37317 -376.624348) (xy 38.396841 -376.561343) (xy 38.427872 -376.50162)
			(xy 38.465818 -376.446033) (xy 38.487604 -376.42038) (xy 38.493392 -376.413229) (xy 38.499912 -376.396043)
			(xy 38.500304 -376.386852) (xy 38.500304 -375.893584) (xy 38.499901 -375.884396) (xy 38.493382 -375.867212)
			(xy 38.487604 -375.860056) (xy 38.465849 -375.834378) (xy 38.427901 -375.778794) (xy 38.396869 -375.719074)
			(xy 38.373195 -375.656073) (xy 38.357221 -375.590694) (xy 38.349175 -375.523875) (xy 38.349172 -375.456573)
			(xy 38.357213 -375.389753) (xy 38.373181 -375.324373) (xy 38.396849 -375.26137) (xy 38.427876 -375.201647)
			(xy 38.465819 -375.146061) (xy 38.487604 -375.120408) (xy 38.49338 -375.113248) (xy 38.499907 -375.096069)
			(xy 38.500304 -375.08688) (xy 38.500304 -374.928638) (xy 38.500794 -374.918473) (xy 38.50856 -374.899686)
			(xy 38.522925 -374.885301) (xy 38.541702 -374.877508) (xy 38.551866 -374.877076) (xy 39.268146 -374.877076)
			(xy 39.278311 -374.877497) (xy 39.297089 -374.885293) (xy 39.311454 -374.899682) (xy 39.31922 -374.918472)
			(xy 39.319708 -374.928638) (xy 39.319708 -375.08688) (xy 39.320126 -375.096066) (xy 39.326634 -375.113251)
			(xy 39.332408 -375.120408) (xy 39.354229 -375.146034) (xy 39.39218 -375.201623) (xy 39.423215 -375.261349)
			(xy 39.446888 -375.324357) (xy 39.462861 -375.389743) (xy 39.470903 -375.45657) (xy 39.4709 -375.523878)
			(xy 39.462852 -375.590704) (xy 39.446874 -375.656089) (xy 39.423195 -375.719095) (xy 39.392155 -375.778819)
			(xy 39.354199 -375.834405) (xy 39.332408 -375.860056) (xy 39.326606 -375.867197) (xy 39.320094 -375.884391)
			(xy 39.319708 -375.893584) (xy 39.319708 -376.386852) (xy 39.320139 -376.396037) (xy 39.326638 -376.413222)
			(xy 39.332408 -376.42038) (xy 39.354201 -376.446028) (xy 39.392153 -376.501614) (xy 39.423189 -376.561338)
			(xy 39.446864 -376.624343) (xy 39.462839 -376.689726) (xy 39.470883 -376.75655) (xy 39.470883 -376.823856)
			(xy 39.470876 -376.823915) (xy 42.748924 -376.823915) (xy 42.748924 -376.756491) (xy 42.756999 -376.689553)
			(xy 42.773034 -376.624064) (xy 42.796798 -376.560968) (xy 42.827948 -376.501172) (xy 42.866036 -376.445537)
			(xy 42.8879 -376.419872) (xy 42.893691 -376.412723) (xy 42.900209 -376.395535) (xy 42.9006 -376.386344)
			(xy 42.9006 -375.894092) (xy 42.900194 -375.884904) (xy 42.893677 -375.86772) (xy 42.8879 -375.860564)
			(xy 42.866067 -375.834873) (xy 42.827978 -375.779242) (xy 42.796826 -375.719449) (xy 42.77306 -375.656356)
			(xy 42.757022 -375.59087) (xy 42.748944 -375.523935) (xy 42.748941 -375.456513) (xy 42.757013 -375.389577)
			(xy 42.773045 -375.32409) (xy 42.796806 -375.260995) (xy 42.827953 -375.201199) (xy 42.866038 -375.145565)
			(xy 42.8879 -375.1199) (xy 42.893679 -375.112742) (xy 42.900204 -375.095561) (xy 42.9006 -375.086372)
			(xy 42.9006 -374.928638) (xy 42.901157 -374.918519) (xy 42.908865 -374.899806) (xy 42.923129 -374.88545)
			(xy 42.941792 -374.877622) (xy 42.951908 -374.877076) (xy 43.668188 -374.877076) (xy 43.678338 -374.877531)
			(xy 43.697086 -374.885318) (xy 43.711409 -374.899704) (xy 43.719113 -374.918486) (xy 43.719496 -374.928638)
			(xy 43.719496 -375.086372) (xy 43.719921 -375.095558) (xy 43.726424 -375.112742) (xy 43.732196 -375.1199)
			(xy 43.754092 -375.145539) (xy 43.79218 -375.201177) (xy 43.823329 -375.260977) (xy 43.847092 -375.324077)
			(xy 43.863125 -375.38957) (xy 43.871198 -375.456511) (xy 43.871196 -375.523937) (xy 43.863116 -375.590878)
			(xy 43.847077 -375.656369) (xy 43.823309 -375.719467) (xy 43.792155 -375.779264) (xy 43.754062 -375.834899)
			(xy 43.732196 -375.860564) (xy 43.726389 -375.867702) (xy 43.719881 -375.884898) (xy 43.719496 -375.894092)
			(xy 43.719496 -376.386344) (xy 43.719886 -376.395533) (xy 43.726414 -376.412717) (xy 43.732196 -376.419872)
			(xy 43.754064 -376.445534) (xy 43.792153 -376.501169) (xy 43.823304 -376.560965) (xy 43.847068 -376.624063)
			(xy 43.863103 -376.689552) (xy 43.871179 -376.756491) (xy 43.871178 -376.823856) (xy 47.149219 -376.823856)
			(xy 47.149219 -376.75655) (xy 47.157264 -376.689727) (xy 47.173238 -376.624344) (xy 47.196912 -376.56134)
			(xy 47.227948 -376.501617) (xy 47.265899 -376.446031) (xy 47.287688 -376.42038) (xy 47.293474 -376.413227)
			(xy 47.299995 -376.396043) (xy 47.300388 -376.386852) (xy 47.300388 -375.893584) (xy 47.299988 -375.884396)
			(xy 47.293468 -375.867211) (xy 47.287688 -375.860056) (xy 47.26593 -375.834379) (xy 47.227977 -375.778797)
			(xy 47.19694 -375.719077) (xy 47.173263 -375.656076) (xy 47.157287 -375.590696) (xy 47.149239 -375.523876)
			(xy 47.149236 -375.456572) (xy 47.157278 -375.389751) (xy 47.173249 -375.32437) (xy 47.19692 -375.261367)
			(xy 47.227952 -375.201644) (xy 47.265901 -375.146059) (xy 47.287688 -375.120408) (xy 47.293462 -375.113247)
			(xy 47.299991 -375.096069) (xy 47.300388 -375.08688) (xy 47.300388 -374.928892) (xy 47.300815 -374.918739)
			(xy 47.308611 -374.899989) (xy 47.323006 -374.885666) (xy 47.341795 -374.877965) (xy 47.35195 -374.877584)
			(xy 48.06823 -374.877584) (xy 48.078364 -374.878003) (xy 48.097094 -374.885749) (xy 48.111451 -374.900056)
			(xy 48.119261 -374.91876) (xy 48.119792 -374.928892) (xy 48.119792 -375.08688) (xy 48.120214 -375.096066)
			(xy 48.12672 -375.11325) (xy 48.132492 -375.120408) (xy 48.15431 -375.146035) (xy 48.192256 -375.201626)
			(xy 48.223286 -375.261353) (xy 48.246956 -375.324361) (xy 48.262926 -375.389746) (xy 48.270967 -375.456571)
			(xy 48.270964 -375.523878) (xy 48.262917 -375.590702) (xy 48.246942 -375.656085) (xy 48.223267 -375.719091)
			(xy 48.192231 -375.778816) (xy 48.154281 -375.834403) (xy 48.132492 -375.860056) (xy 48.126688 -375.867196)
			(xy 48.120178 -375.884391) (xy 48.119792 -375.893584) (xy 48.119792 -376.386852) (xy 48.120227 -376.396037)
			(xy 48.126724 -376.413221) (xy 48.132492 -376.42038) (xy 48.154283 -376.446029) (xy 48.192229 -376.501617)
			(xy 48.223261 -376.561341) (xy 48.246932 -376.624346) (xy 48.262904 -376.689728) (xy 48.270947 -376.756551)
			(xy 73.548976 -376.756551) (xy 73.55702 -376.689728) (xy 73.572992 -376.624347) (xy 73.596664 -376.561342)
			(xy 73.627697 -376.501619) (xy 73.665645 -376.446032) (xy 73.687432 -376.42038) (xy 73.693224 -376.413231)
			(xy 73.699741 -376.396043) (xy 73.700132 -376.386852) (xy 73.700132 -375.893584) (xy 73.699722 -375.884397)
			(xy 73.693208 -375.867213) (xy 73.687432 -375.860056) (xy 73.665676 -375.834378) (xy 73.627727 -375.778795)
			(xy 73.596693 -375.719075) (xy 73.573018 -375.656074) (xy 73.557043 -375.590695) (xy 73.548997 -375.523875)
			(xy 73.548994 -375.456573) (xy 73.557035 -375.389753) (xy 73.573004 -375.324372) (xy 73.596673 -375.261369)
			(xy 73.627702 -375.201647) (xy 73.665647 -375.14606) (xy 73.687432 -375.120408) (xy 73.693212 -375.113251)
			(xy 73.699736 -375.096069) (xy 73.700132 -375.08688) (xy 73.700132 -374.928638) (xy 73.700595 -374.91847)
			(xy 73.708366 -374.899677) (xy 73.72274 -374.885291) (xy 73.741526 -374.877504) (xy 73.751694 -374.877076)
			(xy 74.467974 -374.877076) (xy 74.478149 -374.877486) (xy 74.49695 -374.88527) (xy 74.511337 -374.89966)
			(xy 74.519116 -374.918463) (xy 74.519536 -374.928638) (xy 74.519536 -375.08688) (xy 74.51997 -375.096064)
			(xy 74.526469 -375.113248) (xy 74.532236 -375.120408) (xy 74.554056 -375.146034) (xy 74.592006 -375.201623)
			(xy 74.623039 -375.26135) (xy 74.646711 -375.324358) (xy 74.662683 -375.389744) (xy 74.670725 -375.45657)
			(xy 74.670722 -375.523878) (xy 74.662674 -375.590703) (xy 74.646697 -375.656088) (xy 74.623019 -375.719094)
			(xy 74.591981 -375.778818) (xy 74.554027 -375.834404) (xy 74.532236 -375.860056) (xy 74.526425 -375.867191)
			(xy 74.519921 -375.88439) (xy 74.519536 -375.893584) (xy 74.519536 -376.386852) (xy 74.519983 -376.396035)
			(xy 74.526473 -376.413219) (xy 74.532236 -376.42038) (xy 74.554028 -376.446029) (xy 74.591979 -376.501615)
			(xy 74.623013 -376.561339) (xy 74.646687 -376.624344) (xy 74.66266 -376.689727) (xy 74.670704 -376.75655)
			(xy 74.670704 -376.823856) (xy 74.670697 -376.823915) (xy 77.948745 -376.823915) (xy 77.948745 -376.756491)
			(xy 77.956821 -376.689553) (xy 77.972856 -376.624063) (xy 77.996621 -376.560967) (xy 78.027773 -376.501171)
			(xy 78.065863 -376.445537) (xy 78.087728 -376.419872) (xy 78.093523 -376.412726) (xy 78.100038 -376.395536)
			(xy 78.100428 -376.386344) (xy 78.100428 -375.894092) (xy 78.100016 -375.884905) (xy 78.093503 -375.867721)
			(xy 78.087728 -375.860564) (xy 78.065894 -375.834873) (xy 78.027803 -375.779243) (xy 77.996649 -375.719451)
			(xy 77.972882 -375.656357) (xy 77.956844 -375.590871) (xy 77.948765 -375.523935) (xy 77.948762 -375.456513)
			(xy 77.956835 -375.389577) (xy 77.972868 -375.324089) (xy 77.99663 -375.260993) (xy 78.027778 -375.201198)
			(xy 78.065865 -375.145565) (xy 78.087728 -375.1199) (xy 78.093511 -375.112745) (xy 78.100033 -375.095562)
			(xy 78.100428 -375.086372) (xy 78.100428 -374.928638) (xy 78.100958 -374.918515) (xy 78.108671 -374.899797)
			(xy 78.122944 -374.88544) (xy 78.141616 -374.877618) (xy 78.151736 -374.877076) (xy 78.868016 -374.877076)
			(xy 78.878123 -374.877572) (xy 78.896797 -374.88531) (xy 78.91109 -374.899603) (xy 78.918828 -374.918277)
			(xy 78.919324 -374.928384) (xy 78.919324 -375.086372) (xy 78.919742 -375.095558) (xy 78.92625 -375.112743)
			(xy 78.932024 -375.1199) (xy 78.953919 -375.14554) (xy 78.992005 -375.201178) (xy 79.023153 -375.260978)
			(xy 79.046914 -375.324079) (xy 79.062947 -375.38957) (xy 79.07102 -375.456511) (xy 79.071017 -375.523937)
			(xy 79.062938 -375.590877) (xy 79.0469 -375.656367) (xy 79.023133 -375.719466) (xy 78.99198 -375.779263)
			(xy 78.953889 -375.834898) (xy 78.932024 -375.860564) (xy 78.926221 -375.867704) (xy 78.919709 -375.884898)
			(xy 78.919324 -375.894092) (xy 78.919324 -376.386344) (xy 78.919708 -376.395534) (xy 78.926239 -376.412718)
			(xy 78.932024 -376.419872) (xy 78.953891 -376.445534) (xy 78.991978 -376.50117) (xy 79.023127 -376.560967)
			(xy 79.04689 -376.624064) (xy 79.062925 -376.689553) (xy 79.071 -376.756491) (xy 79.071 -376.756551)
			(xy 82.349064 -376.756551) (xy 82.357108 -376.689729) (xy 82.373079 -376.624347) (xy 82.396751 -376.561343)
			(xy 82.427782 -376.501619) (xy 82.465729 -376.446032) (xy 82.487516 -376.42038) (xy 82.493305 -376.41323)
			(xy 82.499824 -376.396043) (xy 82.500216 -376.386852) (xy 82.500216 -375.893584) (xy 82.49981 -375.884396)
			(xy 82.493293 -375.867212) (xy 82.487516 -375.860056) (xy 82.46576 -375.834378) (xy 82.427812 -375.778795)
			(xy 82.396779 -375.719074) (xy 82.373105 -375.656073) (xy 82.357131 -375.590694) (xy 82.349084 -375.523875)
			(xy 82.349081 -375.456573) (xy 82.357122 -375.389753) (xy 82.373091 -375.324373) (xy 82.396759 -375.26137)
			(xy 82.427787 -375.201647) (xy 82.465731 -375.14606) (xy 82.487516 -375.120408) (xy 82.493294 -375.113249)
			(xy 82.499819 -375.096069) (xy 82.500216 -375.08688) (xy 82.500216 -374.928638) (xy 82.500694 -374.918472)
			(xy 82.508463 -374.899682) (xy 82.522832 -374.885297) (xy 82.541612 -374.877506) (xy 82.551778 -374.877076)
			(xy 83.268058 -374.877076) (xy 83.278232 -374.877499) (xy 83.297033 -374.885277) (xy 83.31142 -374.899664)
			(xy 83.3192 -374.918464) (xy 83.31962 -374.928638) (xy 83.31962 -375.08688) (xy 83.320035 -375.096067)
			(xy 83.326545 -375.113251) (xy 83.33232 -375.120408) (xy 83.35414 -375.146034) (xy 83.392091 -375.201623)
			(xy 83.423125 -375.26135) (xy 83.446798 -375.324358) (xy 83.46277 -375.389744) (xy 83.470812 -375.45657)
			(xy 83.470809 -375.523878) (xy 83.462761 -375.590704) (xy 83.446784 -375.656088) (xy 83.423105 -375.719094)
			(xy 83.392066 -375.778818) (xy 83.354111 -375.834404) (xy 83.33232 -375.860056) (xy 83.326519 -375.867199)
			(xy 83.320007 -375.884391) (xy 83.31962 -375.893584) (xy 83.31962 -376.386852) (xy 83.320049 -376.396037)
			(xy 83.326549 -376.413222) (xy 83.33232 -376.42038) (xy 83.354113 -376.446028) (xy 83.392064 -376.501614)
			(xy 83.4231 -376.561338) (xy 83.446774 -376.624343) (xy 83.462748 -376.689726) (xy 83.470792 -376.75655)
			(xy 83.470792 -376.823856) (xy 83.470785 -376.823915) (xy 86.748833 -376.823915) (xy 86.748833 -376.756491)
			(xy 86.756908 -376.689553) (xy 86.772944 -376.624064) (xy 86.796708 -376.560967) (xy 86.827859 -376.501171)
			(xy 86.865948 -376.445537) (xy 86.887812 -376.419872) (xy 86.893604 -376.412724) (xy 86.900121 -376.395536)
			(xy 86.900512 -376.386344) (xy 86.900512 -375.894092) (xy 86.900103 -375.884905) (xy 86.893588 -375.86772)
			(xy 86.887812 -375.860564) (xy 86.865979 -375.834873) (xy 86.827889 -375.779242) (xy 86.796736 -375.71945)
			(xy 86.772969 -375.656356) (xy 86.756931 -375.59087) (xy 86.748853 -375.523935) (xy 86.74885 -375.456513)
			(xy 86.756923 -375.389577) (xy 86.772955 -375.32409) (xy 86.796716 -375.260994) (xy 86.827864 -375.201199)
			(xy 86.86595 -375.145565) (xy 86.887812 -375.1199) (xy 86.893592 -375.112743) (xy 86.900116 -375.095562)
			(xy 86.900512 -375.086372) (xy 86.900512 -374.928638) (xy 86.901057 -374.918517) (xy 86.908767 -374.899802)
			(xy 86.923035 -374.885446) (xy 86.941702 -374.87762) (xy 86.95182 -374.877076) (xy 87.6681 -374.877076)
			(xy 87.678206 -374.877585) (xy 87.696879 -374.885318) (xy 87.711173 -374.899607) (xy 87.718912 -374.918278)
			(xy 87.719408 -374.928384) (xy 87.719408 -375.086372) (xy 87.71983 -375.095558) (xy 87.726335 -375.112743)
			(xy 87.732108 -375.1199) (xy 87.754003 -375.145539) (xy 87.79209 -375.201178) (xy 87.798441 -375.213371)
			(xy 104.681961 -375.213371) (xy 104.681961 -375.153429) (xy 104.689785 -375.094001) (xy 104.7053 -375.036103)
			(xy 104.72824 -374.980725) (xy 104.758212 -374.928815) (xy 104.794703 -374.881262) (xy 104.837089 -374.838879)
			(xy 104.884645 -374.802391) (xy 104.936557 -374.772424) (xy 104.991937 -374.749489) (xy 105.049837 -374.733978)
			(xy 105.109265 -374.726159) (xy 105.139236 -374.725692) (xy 106.002836 -374.725692) (xy 106.032802 -374.726184)
			(xy 106.092221 -374.734011) (xy 106.15011 -374.749527) (xy 106.205479 -374.772465) (xy 106.25738 -374.802434)
			(xy 106.304926 -374.838921) (xy 106.347303 -374.881301) (xy 106.383786 -374.92885) (xy 106.413751 -374.980753)
			(xy 106.436685 -375.036124) (xy 106.452196 -375.094014) (xy 106.460018 -375.153434) (xy 106.460018 -375.213366)
			(xy 106.452196 -375.272786) (xy 106.436685 -375.330676) (xy 106.413751 -375.386047) (xy 106.383786 -375.43795)
			(xy 106.347303 -375.485499) (xy 106.304926 -375.527879) (xy 106.25738 -375.564366) (xy 106.205479 -375.594335)
			(xy 106.15011 -375.617273) (xy 106.092221 -375.632789) (xy 106.032802 -375.640616) (xy 106.002836 -375.641108)
			(xy 105.139236 -375.641108) (xy 105.109265 -375.640641) (xy 105.049837 -375.632822) (xy 104.991937 -375.617311)
			(xy 104.936557 -375.594376) (xy 104.884645 -375.564409) (xy 104.837089 -375.527921) (xy 104.794703 -375.485538)
			(xy 104.758212 -375.437985) (xy 104.72824 -375.386075) (xy 104.7053 -375.330697) (xy 104.689785 -375.272799)
			(xy 104.681961 -375.213371) (xy 87.798441 -375.213371) (xy 87.823239 -375.260978) (xy 87.847001 -375.324078)
			(xy 87.863034 -375.38957) (xy 87.871107 -375.456511) (xy 87.871105 -375.523937) (xy 87.863026 -375.590877)
			(xy 87.846987 -375.656368) (xy 87.82322 -375.719466) (xy 87.792066 -375.779263) (xy 87.753974 -375.834899)
			(xy 87.732108 -375.860564) (xy 87.726303 -375.867703) (xy 87.719793 -375.884898) (xy 87.719408 -375.894092)
			(xy 87.719408 -376.386344) (xy 87.719795 -376.395534) (xy 87.726324 -376.412718) (xy 87.732108 -376.419872)
			(xy 87.753976 -376.445534) (xy 87.792064 -376.501169) (xy 87.823214 -376.560966) (xy 87.846977 -376.624063)
			(xy 87.863012 -376.689553) (xy 87.871088 -376.756491) (xy 87.871087 -376.823915) (xy 117.548863 -376.823915)
			(xy 117.548863 -376.756491) (xy 117.556939 -376.689552) (xy 117.572976 -376.624062) (xy 117.596742 -376.560965)
			(xy 117.627895 -376.50117) (xy 117.665986 -376.445536) (xy 117.687852 -376.419872) (xy 117.693649 -376.412728)
			(xy 117.700162 -376.395536) (xy 117.700552 -376.386344) (xy 117.700552 -375.894092) (xy 117.700134 -375.884906)
			(xy 117.693625 -375.867722) (xy 117.687852 -375.860564) (xy 117.666018 -375.834874) (xy 117.627925 -375.779244)
			(xy 117.59677 -375.719452) (xy 117.573001 -375.656358) (xy 117.556962 -375.590871) (xy 117.548883 -375.523935)
			(xy 117.54888 -375.456513) (xy 117.556953 -375.389576) (xy 117.572987 -375.324088) (xy 117.59675 -375.260992)
			(xy 117.6279 -375.201197) (xy 117.665988 -375.145564) (xy 117.687852 -375.1199) (xy 117.693638 -375.112747)
			(xy 117.700157 -375.095562) (xy 117.700552 -375.086372) (xy 117.700552 -374.928638) (xy 117.701058 -374.918512)
			(xy 117.708776 -374.89979) (xy 117.723056 -374.885432) (xy 117.741737 -374.877613) (xy 117.75186 -374.877076)
			(xy 118.46814 -374.877076) (xy 118.478294 -374.877488) (xy 118.497042 -374.885293) (xy 118.511363 -374.899691)
			(xy 118.519066 -374.918482) (xy 118.519448 -374.928638) (xy 118.519448 -375.086372) (xy 118.519883 -375.095556)
			(xy 118.526381 -375.11274) (xy 118.532148 -375.1199) (xy 118.554045 -375.145538) (xy 118.592136 -375.201176)
			(xy 118.623289 -375.260975) (xy 118.647053 -375.324075) (xy 118.663088 -375.389568) (xy 118.671162 -375.45651)
			(xy 118.671159 -375.523938) (xy 118.66308 -375.590879) (xy 118.647039 -375.656371) (xy 118.623269 -375.719469)
			(xy 118.592112 -375.779266) (xy 118.554016 -375.8349) (xy 118.532148 -375.860564) (xy 118.526335 -375.867698)
			(xy 118.519832 -375.884897) (xy 118.519448 -375.894092) (xy 118.519448 -376.386344) (xy 118.519849 -376.395532)
			(xy 118.52637 -376.412715) (xy 118.532148 -376.419872) (xy 118.554018 -376.445533) (xy 118.59211 -376.501167)
			(xy 118.623263 -376.560963) (xy 118.647029 -376.624061) (xy 118.663066 -376.689551) (xy 118.671143 -376.75649)
			(xy 118.671143 -376.756551) (xy 121.949182 -376.756551) (xy 121.957226 -376.689728) (xy 121.973199 -376.624346)
			(xy 121.996871 -376.561342) (xy 122.027904 -376.501618) (xy 122.065852 -376.446032) (xy 122.08764 -376.42038)
			(xy 122.093433 -376.413232) (xy 122.099949 -376.396044) (xy 122.10034 -376.386852) (xy 122.10034 -375.893584)
			(xy 122.099929 -375.884397) (xy 122.093415 -375.867213) (xy 122.08764 -375.860056) (xy 122.065884 -375.834378)
			(xy 122.027934 -375.778795) (xy 121.996899 -375.719075) (xy 121.973225 -375.656074) (xy 121.95725 -375.590695)
			(xy 121.949203 -375.523875) (xy 121.9492 -375.456573) (xy 121.957241 -375.389752) (xy 121.973211 -375.324372)
			(xy 121.99688 -375.261369) (xy 122.027909 -375.201646) (xy 122.065854 -375.14606) (xy 122.08764 -375.120408)
			(xy 122.093421 -375.113252) (xy 122.099944 -375.09607) (xy 122.10034 -375.08688) (xy 122.10034 -374.928638)
			(xy 122.100795 -374.918469) (xy 122.108568 -374.899674) (xy 122.122944 -374.885288) (xy 122.141733 -374.877502)
			(xy 122.151902 -374.877076) (xy 122.868182 -374.877076) (xy 122.878357 -374.877479) (xy 122.897159 -374.885265)
			(xy 122.911546 -374.899658) (xy 122.919325 -374.918463) (xy 122.919744 -374.928638) (xy 122.919744 -375.08688)
			(xy 122.920176 -375.096065) (xy 122.926676 -375.113249) (xy 122.932444 -375.120408) (xy 122.954264 -375.146034)
			(xy 122.992213 -375.201624) (xy 123.023246 -375.261351) (xy 123.046917 -375.324359) (xy 123.062889 -375.389744)
			(xy 123.070931 -375.45657) (xy 123.070928 -375.523878) (xy 123.06288 -375.590703) (xy 123.046903 -375.656087)
			(xy 123.023226 -375.719093) (xy 122.992188 -375.778818) (xy 122.954234 -375.834404) (xy 122.932444 -375.860056)
			(xy 122.926634 -375.867192) (xy 122.920129 -375.88439) (xy 122.919744 -375.893584) (xy 122.919744 -376.386852)
			(xy 122.92019 -376.396035) (xy 122.92668 -376.413219) (xy 122.932444 -376.42038) (xy 122.954236 -376.446029)
			(xy 122.992186 -376.501615) (xy 123.02322 -376.561339) (xy 123.046893 -376.624344) (xy 123.062866 -376.689727)
			(xy 123.07091 -376.75655) (xy 123.07091 -376.823856) (xy 123.070903 -376.823915) (xy 126.348951 -376.823915)
			(xy 126.348951 -376.756491) (xy 126.357027 -376.689552) (xy 126.373063 -376.624063) (xy 126.396828 -376.560966)
			(xy 126.42798 -376.50117) (xy 126.466071 -376.445537) (xy 126.487936 -376.419872) (xy 126.493732 -376.412726)
			(xy 126.500246 -376.395536) (xy 126.500636 -376.386344) (xy 126.500636 -375.894092) (xy 126.500222 -375.884905)
			(xy 126.49371 -375.867721) (xy 126.487936 -375.860564) (xy 126.466102 -375.834873) (xy 126.42801 -375.779243)
			(xy 126.396856 -375.719451) (xy 126.373088 -375.656357) (xy 126.35705 -375.590871) (xy 126.348971 -375.523935)
			(xy 126.348968 -375.456513) (xy 126.357041 -375.389576) (xy 126.373074 -375.324089) (xy 126.396836 -375.260993)
			(xy 126.427985 -375.201198) (xy 126.466073 -375.145565) (xy 126.487936 -375.1199) (xy 126.49372 -375.112746)
			(xy 126.500241 -375.095562) (xy 126.500636 -375.086372) (xy 126.500636 -374.928638) (xy 126.501158 -374.918514)
			(xy 126.508872 -374.899795) (xy 126.523148 -374.885437) (xy 126.541823 -374.877616) (xy 126.551944 -374.877076)
			(xy 127.268224 -374.877076) (xy 127.278377 -374.877501) (xy 127.297125 -374.8853) (xy 127.311447 -374.899695)
			(xy 127.31915 -374.918483) (xy 127.319532 -374.928638) (xy 127.319532 -375.086372) (xy 127.319971 -375.095556)
			(xy 127.326466 -375.11274) (xy 127.332232 -375.1199) (xy 127.354126 -375.14554) (xy 127.392212 -375.201179)
			(xy 127.423359 -375.260979) (xy 127.44712 -375.324079) (xy 127.463153 -375.389571) (xy 127.471226 -375.456511)
			(xy 127.471223 -375.523937) (xy 127.463144 -375.590877) (xy 127.447106 -375.656367) (xy 127.42334 -375.719465)
			(xy 127.392187 -375.779263) (xy 127.354097 -375.834898) (xy 127.332232 -375.860564) (xy 127.326417 -375.867696)
			(xy 127.319915 -375.884897) (xy 127.319532 -375.894092) (xy 127.319532 -376.386344) (xy 127.319936 -376.395532)
			(xy 127.326456 -376.412715) (xy 127.332232 -376.419872) (xy 127.354099 -376.445535) (xy 127.392185 -376.50117)
			(xy 127.423334 -376.560967) (xy 127.447097 -376.624064) (xy 127.463131 -376.689553) (xy 127.471206 -376.756491)
			(xy 127.471206 -376.756551) (xy 130.74927 -376.756551) (xy 130.757314 -376.689729) (xy 130.773286 -376.624347)
			(xy 130.796958 -376.561343) (xy 130.827989 -376.501619) (xy 130.865937 -376.446032) (xy 130.887724 -376.42038)
			(xy 130.893514 -376.413231) (xy 130.900032 -376.396043) (xy 130.900424 -376.386852) (xy 130.900424 -375.893584)
			(xy 130.900016 -375.884397) (xy 130.8935 -375.867213) (xy 130.887724 -375.860056) (xy 130.865968 -375.834378)
			(xy 130.82802 -375.778795) (xy 130.796986 -375.719074) (xy 130.773312 -375.656073) (xy 130.757337 -375.590695)
			(xy 130.749291 -375.523875) (xy 130.749288 -375.456573) (xy 130.757329 -375.389753) (xy 130.773298 -375.324373)
			(xy 130.796966 -375.26137) (xy 130.827995 -375.201647) (xy 130.865939 -375.146061) (xy 130.887724 -375.120408)
			(xy 130.893502 -375.11325) (xy 130.900027 -375.096069) (xy 130.900424 -375.08688) (xy 130.900424 -374.928638)
			(xy 130.900895 -374.918471) (xy 130.908665 -374.899679) (xy 130.923036 -374.885294) (xy 130.941819 -374.877505)
			(xy 130.951986 -374.877076) (xy 131.668266 -374.877076) (xy 131.67844 -374.877493) (xy 131.697241 -374.885274)
			(xy 131.711629 -374.899662) (xy 131.719408 -374.918464) (xy 131.719828 -374.928638) (xy 131.719828 -375.08688)
			(xy 131.720241 -375.096067) (xy 131.726752 -375.113252) (xy 131.732528 -375.120408) (xy 131.754348 -375.146034)
			(xy 131.792298 -375.201623) (xy 131.823332 -375.26135) (xy 131.847005 -375.324358) (xy 131.862976 -375.389744)
			(xy 131.871018 -375.45657) (xy 131.871016 -375.523878) (xy 131.862968 -375.590704) (xy 131.84699 -375.656088)
			(xy 131.823313 -375.719094) (xy 131.792274 -375.778818) (xy 131.754319 -375.834404) (xy 131.732528 -375.860056)
			(xy 131.726716 -375.86719) (xy 131.720213 -375.884389) (xy 131.719828 -375.893584) (xy 131.719828 -376.386852)
			(xy 131.720255 -376.396037) (xy 131.726756 -376.413222) (xy 131.732528 -376.42038) (xy 131.754321 -376.446029)
			(xy 131.792271 -376.501615) (xy 131.823306 -376.561338) (xy 131.84698 -376.624344) (xy 131.862954 -376.689727)
			(xy 131.870991 -376.756492) (xy 161.548796 -376.756492) (xy 161.556871 -376.689554) (xy 161.572905 -376.624066)
			(xy 161.596667 -376.560969) (xy 161.627816 -376.501173) (xy 161.665902 -376.445538) (xy 161.687764 -376.419872)
			(xy 161.693563 -376.412729) (xy 161.700074 -376.395536) (xy 161.700464 -376.386344) (xy 161.700464 -375.894092)
			(xy 161.700043 -375.884906) (xy 161.693535 -375.867723) (xy 161.687764 -375.860564) (xy 161.665933 -375.834872)
			(xy 161.627845 -375.779241) (xy 161.596695 -375.719448) (xy 161.572931 -375.656354) (xy 161.556894 -375.590869)
			(xy 161.548816 -375.523934) (xy 161.548814 -375.456514) (xy 161.556886 -375.389578) (xy 161.572917 -375.324092)
			(xy 161.596676 -375.260996) (xy 161.627821 -375.201201) (xy 161.665903 -375.145566) (xy 161.687764 -375.1199)
			(xy 161.693551 -375.112748) (xy 161.70007 -375.095562) (xy 161.700464 -375.086372) (xy 161.700464 -374.928638)
			(xy 161.700959 -374.918511) (xy 161.708678 -374.899786) (xy 161.722963 -374.885428) (xy 161.741647 -374.877611)
			(xy 161.751772 -374.877076) (xy 162.468052 -374.877076) (xy 162.478168 -374.877555) (xy 162.496866 -374.885283)
			(xy 162.511181 -374.89958) (xy 162.518933 -374.918268) (xy 162.51936 -374.928384) (xy 162.51936 -375.086372)
			(xy 162.519793 -375.095557) (xy 162.526292 -375.112741) (xy 162.53206 -375.1199) (xy 162.553957 -375.145539)
			(xy 162.592047 -375.201176) (xy 162.623199 -375.260976) (xy 162.646963 -375.324076) (xy 162.662997 -375.389569)
			(xy 162.671071 -375.456511) (xy 162.671068 -375.523938) (xy 162.662989 -375.590879) (xy 162.646949 -375.65637)
			(xy 162.623179 -375.719468) (xy 162.592022 -375.779265) (xy 162.553927 -375.834899) (xy 162.53206 -375.860564)
			(xy 162.526249 -375.867699) (xy 162.519744 -375.884897) (xy 162.51936 -375.894092) (xy 162.51936 -376.386344)
			(xy 162.519758 -376.395532) (xy 162.526281 -376.412716) (xy 162.53206 -376.419872) (xy 162.553929 -376.445533)
			(xy 162.592021 -376.501167) (xy 162.623173 -376.560964) (xy 162.646939 -376.624061) (xy 162.662975 -376.689551)
			(xy 162.671052 -376.756491) (xy 162.671051 -376.823855) (xy 165.949092 -376.823855) (xy 165.949092 -376.756551)
			(xy 165.957136 -376.689728) (xy 165.973109 -376.624346) (xy 165.996782 -376.561342) (xy 166.027815 -376.501618)
			(xy 166.065764 -376.446032) (xy 166.087552 -376.42038) (xy 166.093346 -376.413233) (xy 166.099861 -376.396044)
			(xy 166.100252 -376.386852) (xy 166.100252 -375.893584) (xy 166.099838 -375.884397) (xy 166.093326 -375.867214)
			(xy 166.087552 -375.860056) (xy 166.065795 -375.834378) (xy 166.027845 -375.778796) (xy 165.996809 -375.719076)
			(xy 165.973134 -375.656075) (xy 165.957159 -375.590695) (xy 165.949112 -375.523875) (xy 165.949109 -375.456573)
			(xy 165.95715 -375.389752) (xy 165.97312 -375.324371) (xy 165.99679 -375.261368) (xy 166.02782 -375.201646)
			(xy 166.065766 -375.14606) (xy 166.087552 -375.120408) (xy 166.093334 -375.113253) (xy 166.099856 -375.09607)
			(xy 166.100252 -375.08688) (xy 166.100252 -374.928638) (xy 166.100695 -374.918467) (xy 166.10847 -374.899671)
			(xy 166.12285 -374.885284) (xy 166.141643 -374.8775) (xy 166.151814 -374.877076) (xy 166.868094 -374.877076)
			(xy 166.87827 -374.87747) (xy 166.897072 -374.88526) (xy 166.911458 -374.899655) (xy 166.919237 -374.918462)
			(xy 166.919656 -374.928638) (xy 166.919656 -375.08688) (xy 166.920085 -375.096065) (xy 166.926587 -375.113249)
			(xy 166.932356 -375.120408) (xy 166.954175 -375.146034) (xy 166.992124 -375.201624) (xy 167.023156 -375.261351)
			(xy 167.046827 -375.324359) (xy 167.062798 -375.389745) (xy 167.07084 -375.45657) (xy 167.070837 -375.523878)
			(xy 167.062789 -375.590703) (xy 167.046813 -375.656087) (xy 167.023136 -375.719093) (xy 166.992099 -375.778817)
			(xy 166.954146 -375.834404) (xy 166.932356 -375.860056) (xy 166.926548 -375.867193) (xy 166.920041 -375.88439)
			(xy 166.919656 -375.893584) (xy 166.919656 -376.386852) (xy 166.920099 -376.396035) (xy 166.926591 -376.41322)
			(xy 166.932356 -376.42038) (xy 166.954148 -376.446029) (xy 166.992097 -376.501616) (xy 167.02313 -376.56134)
			(xy 167.046803 -376.624345) (xy 167.062776 -376.689727) (xy 167.07082 -376.75655) (xy 167.07082 -376.823856)
			(xy 167.070813 -376.823915) (xy 170.34886 -376.823915) (xy 170.34886 -376.756491) (xy 170.356936 -376.689552)
			(xy 170.372972 -376.624063) (xy 170.396738 -376.560966) (xy 170.427891 -376.50117) (xy 170.465983 -376.445536)
			(xy 170.487848 -376.419872) (xy 170.493645 -376.412727) (xy 170.500158 -376.395536) (xy 170.500548 -376.386344)
			(xy 170.500548 -375.894092) (xy 170.500131 -375.884906) (xy 170.493621 -375.867722) (xy 170.487848 -375.860564)
			(xy 170.466014 -375.834874) (xy 170.427921 -375.779244) (xy 170.396766 -375.719452) (xy 170.372998 -375.656358)
			(xy 170.356959 -375.590871) (xy 170.34888 -375.523935) (xy 170.348877 -375.456513) (xy 170.35695 -375.389576)
			(xy 170.372984 -375.324088) (xy 170.396747 -375.260992) (xy 170.427896 -375.201197) (xy 170.465984 -375.145564)
			(xy 170.487848 -375.1199) (xy 170.493633 -375.112747) (xy 170.500153 -375.095562) (xy 170.500548 -375.086372)
			(xy 170.500548 -374.928638) (xy 170.501058 -374.918513) (xy 170.508775 -374.899791) (xy 170.523054 -374.885433)
			(xy 170.541734 -374.877614) (xy 170.551856 -374.877076) (xy 171.268136 -374.877076) (xy 171.278289 -374.877492)
			(xy 171.297038 -374.885295) (xy 171.311359 -374.899692) (xy 171.319062 -374.918482) (xy 171.319444 -374.928638)
			(xy 171.319444 -375.086372) (xy 171.31988 -375.095556) (xy 171.326377 -375.11274) (xy 171.332144 -375.1199)
			(xy 171.354041 -375.145538) (xy 171.392133 -375.201175) (xy 171.423285 -375.260975) (xy 171.44705 -375.324075)
			(xy 171.463085 -375.389568) (xy 171.471159 -375.45651) (xy 171.471156 -375.523938) (xy 171.463076 -375.590879)
			(xy 171.447036 -375.656371) (xy 171.423266 -375.719469) (xy 171.392108 -375.779266) (xy 171.354012 -375.8349)
			(xy 171.332144 -375.860564) (xy 171.326331 -375.867697) (xy 171.319828 -375.884897) (xy 171.319444 -375.894092)
			(xy 171.319444 -376.386344) (xy 171.319845 -376.395532) (xy 171.326366 -376.412716) (xy 171.332144 -376.419872)
			(xy 171.354014 -376.445533) (xy 171.392106 -376.501167) (xy 171.42326 -376.560963) (xy 171.447026 -376.624061)
			(xy 171.463063 -376.689551) (xy 171.47114 -376.75649) (xy 171.47114 -376.756551) (xy 174.749179 -376.756551)
			(xy 174.757223 -376.689728) (xy 174.773195 -376.624346) (xy 174.796868 -376.561342) (xy 174.8279 -376.501619)
			(xy 174.865848 -376.446032) (xy 174.887636 -376.42038) (xy 174.893428 -376.413232) (xy 174.899945 -376.396043)
			(xy 174.900336 -376.386852) (xy 174.900336 -375.893584) (xy 174.899926 -375.884397) (xy 174.893411 -375.867213)
			(xy 174.887636 -375.860056) (xy 174.86588 -375.834378) (xy 174.82793 -375.778795) (xy 174.796896 -375.719075)
			(xy 174.773222 -375.656074) (xy 174.757246 -375.590695) (xy 174.7492 -375.523875) (xy 174.749197 -375.456573)
			(xy 174.757238 -375.389752) (xy 174.773207 -375.324372) (xy 174.796876 -375.261369) (xy 174.827906 -375.201646)
			(xy 174.865851 -375.14606) (xy 174.887636 -375.120408) (xy 174.893416 -375.113251) (xy 174.89994 -375.096069)
			(xy 174.900336 -375.08688) (xy 174.900336 -374.928638) (xy 174.900795 -374.918469) (xy 174.908567 -374.899676)
			(xy 174.922942 -374.88529) (xy 174.941729 -374.877503) (xy 174.951898 -374.877076) (xy 175.668178 -374.877076)
			(xy 175.678353 -374.877483) (xy 175.697154 -374.885268) (xy 175.711541 -374.899659) (xy 175.71932 -374.918463)
			(xy 175.71974 -374.928638) (xy 175.71974 -375.08688) (xy 175.720173 -375.096064) (xy 175.726672 -375.113248)
			(xy 175.73244 -375.120408) (xy 175.75426 -375.146034) (xy 175.792209 -375.201624) (xy 175.823242 -375.261351)
			(xy 175.846914 -375.324359) (xy 175.862886 -375.389744) (xy 175.870928 -375.45657) (xy 175.870925 -375.523878)
			(xy 175.862877 -375.590703) (xy 175.8469 -375.656087) (xy 175.823223 -375.719093) (xy 175.792185 -375.778818)
			(xy 175.754231 -375.834404) (xy 175.73244 -375.860056) (xy 175.72663 -375.867191) (xy 175.720125 -375.88439)
			(xy 175.71974 -375.893584) (xy 175.71974 -376.386852) (xy 175.720186 -376.396035) (xy 175.726676 -376.413219)
			(xy 175.73244 -376.42038) (xy 175.754232 -376.446029) (xy 175.792182 -376.501615) (xy 175.823216 -376.561339)
			(xy 175.84689 -376.624344) (xy 175.862863 -376.689727) (xy 175.870907 -376.75655) (xy 175.870907 -376.823856)
			(xy 175.862862 -376.890679) (xy 175.846888 -376.956062) (xy 175.823214 -377.019066) (xy 175.792179 -377.07879)
			(xy 175.754228 -377.134376) (xy 175.73244 -377.160028) (xy 175.726642 -377.167172) (xy 175.72013 -377.184364)
			(xy 175.71974 -377.193556) (xy 175.71974 -377.35129) (xy 175.719328 -377.361464) (xy 175.711542 -377.380262)
			(xy 175.697152 -377.394648) (xy 175.678352 -377.40243) (xy 175.668178 -377.402852) (xy 174.951898 -377.402852)
			(xy 174.941725 -377.402438) (xy 174.922928 -377.39465) (xy 174.908543 -377.380262) (xy 174.90076 -377.361463)
			(xy 174.900336 -377.35129) (xy 174.900336 -377.193556) (xy 174.899939 -377.184368) (xy 174.893415 -377.167184)
			(xy 174.887636 -377.160028) (xy 174.865852 -377.134373) (xy 174.827903 -377.078787) (xy 174.79687 -377.019063)
			(xy 174.773197 -376.956059) (xy 174.757224 -376.890678) (xy 174.74918 -376.823855) (xy 174.749179 -376.756551)
			(xy 171.47114 -376.756551) (xy 171.471139 -376.823916) (xy 171.463062 -376.890855) (xy 171.447024 -376.956345)
			(xy 171.423257 -377.019442) (xy 171.392103 -377.079238) (xy 171.35401 -377.134872) (xy 171.332144 -377.160536)
			(xy 171.326343 -377.167678) (xy 171.319832 -377.184871) (xy 171.319444 -377.194064) (xy 171.319444 -377.35129)
			(xy 171.318965 -377.361418) (xy 171.311237 -377.380142) (xy 171.296948 -377.394499) (xy 171.278262 -377.402316)
			(xy 171.268136 -377.402852) (xy 170.551856 -377.402852) (xy 170.541706 -377.402415) (xy 170.522962 -377.394615)
			(xy 170.508642 -377.380224) (xy 170.500935 -377.361442) (xy 170.500548 -377.35129) (xy 170.500548 -377.194064)
			(xy 170.500144 -377.184876) (xy 170.493625 -377.167693) (xy 170.487848 -377.160536) (xy 170.465986 -377.134868)
			(xy 170.427894 -377.079235) (xy 170.396741 -377.01944) (xy 170.372974 -376.956343) (xy 170.356937 -376.890854)
			(xy 170.34886 -376.823915) (xy 167.070813 -376.823915) (xy 167.062775 -376.890679) (xy 167.046801 -376.956061)
			(xy 167.023128 -377.019066) (xy 166.992094 -377.07879) (xy 166.954144 -377.134376) (xy 166.932356 -377.160028)
			(xy 166.92656 -377.167173) (xy 166.920046 -377.184364) (xy 166.919656 -377.193556) (xy 166.919656 -377.35129)
			(xy 166.919228 -377.361462) (xy 166.911445 -377.380257) (xy 166.897061 -377.394643) (xy 166.878266 -377.402427)
			(xy 166.868094 -377.402852) (xy 166.151814 -377.402852) (xy 166.141642 -377.402425) (xy 166.122846 -377.394642)
			(xy 166.10846 -377.380258) (xy 166.100676 -377.361462) (xy 166.100252 -377.35129) (xy 166.100252 -377.193556)
			(xy 166.099851 -377.184368) (xy 166.09333 -377.167185) (xy 166.087552 -377.160028) (xy 166.065768 -377.134373)
			(xy 166.027818 -377.078787) (xy 165.996784 -377.019064) (xy 165.97311 -376.95606) (xy 165.957137 -376.890678)
			(xy 165.949092 -376.823855) (xy 162.671051 -376.823855) (xy 162.671051 -376.823915) (xy 162.662974 -376.890855)
			(xy 162.646937 -376.956344) (xy 162.623171 -377.019442) (xy 162.592017 -377.079238) (xy 162.553926 -377.134871)
			(xy 162.53206 -377.160536) (xy 162.526261 -377.167679) (xy 162.519749 -377.184871) (xy 162.51936 -377.194064)
			(xy 162.51936 -377.35129) (xy 162.518865 -377.361416) (xy 162.511141 -377.380137) (xy 162.496857 -377.394494)
			(xy 162.478175 -377.402313) (xy 162.468052 -377.402852) (xy 161.751772 -377.402852) (xy 161.741668 -377.402339)
			(xy 161.722999 -377.394602) (xy 161.708707 -377.380314) (xy 161.700964 -377.361648) (xy 161.700464 -377.351544)
			(xy 161.700464 -377.194064) (xy 161.700057 -377.184877) (xy 161.69354 -377.167693) (xy 161.687764 -377.160536)
			(xy 161.665905 -377.134867) (xy 161.627819 -377.079232) (xy 161.59667 -377.019436) (xy 161.572907 -376.95634)
			(xy 161.556872 -376.890852) (xy 161.548797 -376.823914) (xy 161.548796 -376.756492) (xy 131.870991 -376.756492)
			(xy 131.870998 -376.75655) (xy 131.870998 -376.823856) (xy 131.862953 -376.890679) (xy 131.846979 -376.956062)
			(xy 131.823304 -377.019067) (xy 131.792268 -377.07879) (xy 131.754317 -377.134376) (xy 131.732528 -377.160028)
			(xy 131.726728 -377.167171) (xy 131.720218 -377.184363) (xy 131.719828 -377.193556) (xy 131.719828 -377.35129)
			(xy 131.719427 -377.361465) (xy 131.711639 -377.380266) (xy 131.697246 -377.394653) (xy 131.678441 -377.402432)
			(xy 131.668266 -377.402852) (xy 130.951986 -377.402852) (xy 130.941826 -377.402378) (xy 130.923055 -377.394597)
			(xy 130.90869 -377.380225) (xy 130.900918 -377.36145) (xy 130.900424 -377.35129) (xy 130.900424 -377.193556)
			(xy 130.90003 -377.184367) (xy 130.893504 -377.167183) (xy 130.887724 -377.160028) (xy 130.865941 -377.134372)
			(xy 130.827993 -377.078786) (xy 130.79696 -377.019063) (xy 130.773288 -376.956059) (xy 130.757315 -376.890677)
			(xy 130.749271 -376.823855) (xy 130.74927 -376.756551) (xy 127.471206 -376.756551) (xy 127.471205 -376.823915)
			(xy 127.46313 -376.890853) (xy 127.447095 -376.956342) (xy 127.423332 -377.019438) (xy 127.392182 -377.079235)
			(xy 127.354095 -377.13487) (xy 127.332232 -377.160536) (xy 127.326429 -377.167677) (xy 127.31992 -377.184871)
			(xy 127.319532 -377.194064) (xy 127.319532 -377.35129) (xy 127.319064 -377.36142) (xy 127.311335 -377.380146)
			(xy 127.297042 -377.394503) (xy 127.278351 -377.402318) (xy 127.268224 -377.402852) (xy 126.551944 -377.402852)
			(xy 126.541799 -377.402343) (xy 126.523058 -377.394572) (xy 126.508735 -377.380202) (xy 126.501024 -377.361436)
			(xy 126.500636 -377.35129) (xy 126.500636 -377.194064) (xy 126.500235 -377.184876) (xy 126.493714 -377.167692)
			(xy 126.487936 -377.160536) (xy 126.466075 -377.134868) (xy 126.427984 -377.079235) (xy 126.396831 -377.019439)
			(xy 126.373065 -376.956343) (xy 126.357028 -376.890854) (xy 126.348951 -376.823915) (xy 123.070903 -376.823915)
			(xy 123.062865 -376.890679) (xy 123.046891 -376.956062) (xy 123.023217 -377.019066) (xy 122.992183 -377.07879)
			(xy 122.954232 -377.134376) (xy 122.932444 -377.160028) (xy 122.926646 -377.167172) (xy 122.920134 -377.184364)
			(xy 122.919744 -377.193556) (xy 122.919744 -377.35129) (xy 122.919328 -377.361463) (xy 122.911543 -377.380261)
			(xy 122.897154 -377.394647) (xy 122.878355 -377.402429) (xy 122.868182 -377.402852) (xy 122.151902 -377.402852)
			(xy 122.141729 -377.402434) (xy 122.122933 -377.394648) (xy 122.108547 -377.380261) (xy 122.100764 -377.361463)
			(xy 122.10034 -377.35129) (xy 122.10034 -377.193556) (xy 122.099942 -377.184368) (xy 122.093419 -377.167184)
			(xy 122.08764 -377.160028) (xy 122.065856 -377.134373) (xy 122.027907 -377.078787) (xy 121.996873 -377.019064)
			(xy 121.9732 -376.95606) (xy 121.957227 -376.890678) (xy 121.949183 -376.823855) (xy 121.949182 -376.756551)
			(xy 118.671143 -376.756551) (xy 118.671142 -376.823916) (xy 118.663065 -376.890855) (xy 118.647028 -376.956345)
			(xy 118.623261 -377.019442) (xy 118.592107 -377.079238) (xy 118.554014 -377.134872) (xy 118.532148 -377.160536)
			(xy 118.526347 -377.167678) (xy 118.519836 -377.184871) (xy 118.519448 -377.194064) (xy 118.519448 -377.35129)
			(xy 118.518965 -377.361418) (xy 118.511238 -377.380141) (xy 118.496951 -377.394498) (xy 118.478265 -377.402315)
			(xy 118.46814 -377.402852) (xy 117.75186 -377.402852) (xy 117.74171 -377.402412) (xy 117.722967 -377.394613)
			(xy 117.708647 -377.380223) (xy 117.700939 -377.361442) (xy 117.700552 -377.35129) (xy 117.700552 -377.194064)
			(xy 117.700147 -377.184876) (xy 117.693628 -377.167693) (xy 117.687852 -377.160536) (xy 117.66599 -377.134868)
			(xy 117.627898 -377.079235) (xy 117.596744 -377.01944) (xy 117.572977 -376.956343) (xy 117.55694 -376.890854)
			(xy 117.548863 -376.823915) (xy 87.871087 -376.823915) (xy 87.863011 -376.890853) (xy 87.846976 -376.956342)
			(xy 87.823211 -377.019439) (xy 87.792061 -377.079236) (xy 87.753972 -377.134871) (xy 87.732108 -377.160536)
			(xy 87.726315 -377.167684) (xy 87.719798 -377.184872) (xy 87.719408 -377.194064) (xy 87.719408 -377.35129)
			(xy 87.718867 -377.36141) (xy 87.711151 -377.380122) (xy 87.696882 -377.394477) (xy 87.678217 -377.402305)
			(xy 87.6681 -377.402852) (xy 86.95182 -377.402852) (xy 86.941719 -377.4023) (xy 86.923051 -377.394578)
			(xy 86.908757 -377.380303) (xy 86.901013 -377.361644) (xy 86.900512 -377.351544) (xy 86.900512 -377.194064)
			(xy 86.900117 -377.184875) (xy 86.893592 -377.167691) (xy 86.887812 -377.160536) (xy 86.865952 -377.134868)
			(xy 86.827862 -377.079234) (xy 86.79671 -377.019438) (xy 86.772945 -376.956342) (xy 86.756909 -376.890853)
			(xy 86.748833 -376.823915) (xy 83.470785 -376.823915) (xy 83.462747 -376.89068) (xy 83.446772 -376.956063)
			(xy 83.423097 -377.019067) (xy 83.392061 -377.078791) (xy 83.354109 -377.134376) (xy 83.33232 -377.160028)
			(xy 83.326531 -377.167179) (xy 83.320011 -377.184365) (xy 83.31962 -377.193556) (xy 83.31962 -377.35129)
			(xy 83.319227 -377.361466) (xy 83.311438 -377.380269) (xy 83.297042 -377.394655) (xy 83.278234 -377.402433)
			(xy 83.268058 -377.402852) (xy 82.551778 -377.402852) (xy 82.541618 -377.402385) (xy 82.522846 -377.394601)
			(xy 82.508481 -377.380227) (xy 82.500709 -377.361451) (xy 82.500216 -377.35129) (xy 82.500216 -377.193556)
			(xy 82.499823 -377.184367) (xy 82.493297 -377.167183) (xy 82.487516 -377.160028) (xy 82.465733 -377.134372)
			(xy 82.427785 -377.078786) (xy 82.396753 -377.019063) (xy 82.373081 -376.956059) (xy 82.357109 -376.890677)
			(xy 82.349065 -376.823855) (xy 82.349064 -376.756551) (xy 79.071 -376.756551) (xy 79.070999 -376.823915)
			(xy 79.062924 -376.890853) (xy 79.046888 -376.956342) (xy 79.023125 -377.019439) (xy 78.991975 -377.079235)
			(xy 78.953887 -377.13487) (xy 78.932024 -377.160536) (xy 78.926232 -377.167685) (xy 78.919714 -377.184872)
			(xy 78.919324 -377.194064) (xy 78.919324 -377.35129) (xy 78.918864 -377.36142) (xy 78.911133 -377.380148)
			(xy 78.896838 -377.394506) (xy 78.878144 -377.402319) (xy 78.868016 -377.402852) (xy 78.151736 -377.402852)
			(xy 78.141636 -377.402286) (xy 78.122969 -377.39457) (xy 78.108674 -377.380299) (xy 78.100929 -377.361643)
			(xy 78.100428 -377.351544) (xy 78.100428 -377.194064) (xy 78.100029 -377.184876) (xy 78.093507 -377.167692)
			(xy 78.087728 -377.160536) (xy 78.065867 -377.134868) (xy 78.027776 -377.079235) (xy 77.996624 -377.019439)
			(xy 77.972858 -376.956342) (xy 77.956822 -376.890853) (xy 77.948745 -376.823915) (xy 74.670697 -376.823915)
			(xy 74.662659 -376.890679) (xy 74.646685 -376.956062) (xy 74.623011 -377.019067) (xy 74.591976 -377.07879)
			(xy 74.554025 -377.134376) (xy 74.532236 -377.160028) (xy 74.526437 -377.167171) (xy 74.519926 -377.184364)
			(xy 74.519536 -377.193556) (xy 74.519536 -377.35129) (xy 74.519127 -377.361464) (xy 74.511341 -377.380264)
			(xy 74.49695 -377.39465) (xy 74.478148 -377.402431) (xy 74.467974 -377.402852) (xy 73.751694 -377.402852)
			(xy 73.741521 -377.402441) (xy 73.722724 -377.394652) (xy 73.708339 -377.380263) (xy 73.700556 -377.361463)
			(xy 73.700132 -377.35129) (xy 73.700132 -377.193556) (xy 73.699736 -377.184367) (xy 73.693212 -377.167184)
			(xy 73.687432 -377.160028) (xy 73.665648 -377.134373) (xy 73.6277 -377.078786) (xy 73.596667 -377.019063)
			(xy 73.572994 -376.956059) (xy 73.557021 -376.890677) (xy 73.548977 -376.823855) (xy 73.548976 -376.756551)
			(xy 48.270947 -376.756551) (xy 48.270947 -376.823855) (xy 48.262903 -376.890678) (xy 48.24693 -376.95606)
			(xy 48.223258 -377.019064) (xy 48.192226 -377.078788) (xy 48.154279 -377.134375) (xy 48.132492 -377.160028)
			(xy 48.1267 -377.167176) (xy 48.120183 -377.184365) (xy 48.119792 -377.193556) (xy 48.119792 -377.351544)
			(xy 48.119414 -377.361702) (xy 48.111603 -377.380457) (xy 48.097193 -377.394779) (xy 48.07839 -377.402476)
			(xy 48.06823 -377.402852) (xy 47.35195 -377.402852) (xy 47.341825 -377.402332) (xy 47.323104 -377.394619)
			(xy 47.308746 -377.380343) (xy 47.300926 -377.361666) (xy 47.300388 -377.351544) (xy 47.300388 -377.193556)
			(xy 47.300002 -377.184366) (xy 47.293472 -377.167182) (xy 47.287688 -377.160028) (xy 47.265903 -377.134373)
			(xy 47.227951 -377.078788) (xy 47.196914 -377.019066) (xy 47.173239 -376.956061) (xy 47.157265 -376.890679)
			(xy 47.149219 -376.823856) (xy 43.871178 -376.823856) (xy 43.871178 -376.823915) (xy 43.863102 -376.890854)
			(xy 43.847066 -376.956343) (xy 43.823301 -377.01944) (xy 43.79215 -377.079236) (xy 43.75406 -377.134871)
			(xy 43.732196 -377.160536) (xy 43.726401 -377.167682) (xy 43.719886 -377.184872) (xy 43.719496 -377.194064)
			(xy 43.719496 -377.35129) (xy 43.718966 -377.361412) (xy 43.711248 -377.380126) (xy 43.696976 -377.394481)
			(xy 43.678307 -377.402307) (xy 43.668188 -377.402852) (xy 42.951908 -377.402852) (xy 42.941761 -377.402373)
			(xy 42.923019 -377.39459) (xy 42.908697 -377.380211) (xy 42.900988 -377.361439) (xy 42.9006 -377.35129)
			(xy 42.9006 -377.194064) (xy 42.900207 -377.184875) (xy 42.893682 -377.167691) (xy 42.8879 -377.160536)
			(xy 42.86604 -377.134868) (xy 42.827951 -377.079233) (xy 42.7968 -377.019438) (xy 42.773036 -376.956341)
			(xy 42.757 -376.890853) (xy 42.748924 -376.823915) (xy 39.470876 -376.823915) (xy 39.462838 -376.89068)
			(xy 39.446863 -376.956063) (xy 39.423187 -377.019068) (xy 39.39215 -377.078791) (xy 39.354198 -377.134377)
			(xy 39.332408 -377.160028) (xy 39.326618 -377.167178) (xy 39.320099 -377.184365) (xy 39.319708 -377.193556)
			(xy 39.319708 -377.35129) (xy 39.31916 -377.361441) (xy 39.311397 -377.380202) (xy 39.297049 -377.394566)
			(xy 39.278297 -377.402349) (xy 39.268146 -377.402852) (xy 38.551866 -377.402852) (xy 38.541705 -377.402394)
			(xy 38.522933 -377.394607) (xy 38.508569 -377.38023) (xy 38.500797 -377.361452) (xy 38.500304 -377.35129)
			(xy 38.500304 -377.193556) (xy 38.499914 -377.184367) (xy 38.493386 -377.167183) (xy 38.487604 -377.160028)
			(xy 38.465821 -377.134372) (xy 38.427875 -377.078785) (xy 38.396843 -377.019062) (xy 38.373172 -376.956058)
			(xy 38.357199 -376.890677) (xy 38.349156 -376.823855) (xy 38.349155 -376.756551) (xy 35.071091 -376.756551)
			(xy 35.07109 -376.823915) (xy 35.063014 -376.890853) (xy 35.046979 -376.956342) (xy 35.023215 -377.019439)
			(xy 34.992064 -377.079236) (xy 34.953976 -377.134871) (xy 34.932112 -377.160536) (xy 34.926319 -377.167684)
			(xy 34.919802 -377.184872) (xy 34.919412 -377.194064) (xy 34.919412 -377.35129) (xy 34.918867 -377.36141)
			(xy 34.911152 -377.380121) (xy 34.896884 -377.394476) (xy 34.878221 -377.402304) (xy 34.868104 -377.402852)
			(xy 34.151824 -377.402852) (xy 34.141678 -377.40236) (xy 34.122936 -377.394582) (xy 34.108614 -377.380208)
			(xy 34.100904 -377.361438) (xy 34.100516 -377.35129) (xy 34.100516 -377.194064) (xy 34.10012 -377.184875)
			(xy 34.093596 -377.167691) (xy 34.087816 -377.160536) (xy 34.065955 -377.134868) (xy 34.027866 -377.079234)
			(xy 33.996714 -377.019438) (xy 33.972949 -376.956342) (xy 33.956912 -376.890853) (xy 33.948836 -376.823915)
			(xy 30.670788 -376.823915) (xy 30.66275 -376.89068) (xy 30.646775 -376.956062) (xy 30.6231 -377.019067)
			(xy 30.592065 -377.078791) (xy 30.554113 -377.134376) (xy 30.532324 -377.160028) (xy 30.526536 -377.167179)
			(xy 30.520015 -377.184365) (xy 30.519624 -377.193556) (xy 30.519624 -377.35129) (xy 30.519227 -377.361466)
			(xy 30.511438 -377.380267) (xy 30.497044 -377.394654) (xy 30.478238 -377.402433) (xy 30.468062 -377.402852)
			(xy 29.751782 -377.402852) (xy 29.741622 -377.402381) (xy 29.72285 -377.394599) (xy 29.708485 -377.380226)
			(xy 29.700713 -377.36145) (xy 29.70022 -377.35129) (xy 29.70022 -377.193556) (xy 29.699827 -377.184367)
			(xy 29.693301 -377.167183) (xy 29.68752 -377.160028) (xy 29.665737 -377.134372) (xy 29.627789 -377.078786)
			(xy 29.596757 -377.019063) (xy 29.573084 -376.956059) (xy 29.557112 -376.890677) (xy 29.549068 -376.823855)
			(xy 29.549067 -376.756551) (xy 0.508 -376.756551) (xy 0.508 -378.323793) (xy 27.348888 -378.323793)
			(xy 27.34889 -378.256368) (xy 27.356968 -378.189428) (xy 27.373006 -378.123938) (xy 27.396772 -378.06084)
			(xy 27.427925 -378.001043) (xy 27.466015 -377.945408) (xy 27.48788 -377.919742) (xy 27.493681 -377.9126)
			(xy 27.500194 -377.895407) (xy 27.50058 -377.886214) (xy 27.50058 -377.728734) (xy 27.501056 -377.718605)
			(xy 27.50878 -377.699877) (xy 27.52307 -377.685518) (xy 27.541761 -377.677705) (xy 27.551888 -377.677172)
			(xy 28.268168 -377.677172) (xy 28.278285 -377.677641) (xy 28.296983 -377.685374) (xy 28.311297 -377.699674)
			(xy 28.319048 -377.718363) (xy 28.319476 -377.72848) (xy 28.319476 -377.886214) (xy 28.319885 -377.895401)
			(xy 28.3264 -377.912585) (xy 28.332176 -377.919742) (xy 28.354015 -377.945428) (xy 28.392106 -378.001059)
			(xy 28.42326 -378.060852) (xy 28.447026 -378.123946) (xy 28.463064 -378.189433) (xy 28.471143 -378.256369)
			(xy 28.471145 -378.323734) (xy 31.749183 -378.323734) (xy 31.749186 -378.256427) (xy 31.757233 -378.189602)
			(xy 31.773209 -378.124218) (xy 31.796886 -378.061212) (xy 31.827924 -378.001488) (xy 31.865878 -377.945902)
			(xy 31.887668 -377.92025) (xy 31.893477 -377.913114) (xy 31.899982 -377.895916) (xy 31.900368 -377.886722)
			(xy 31.900368 -377.728734) (xy 31.900793 -377.718561) (xy 31.908572 -377.699761) (xy 31.922958 -377.685374)
			(xy 31.941757 -377.677593) (xy 31.95193 -377.677172) (xy 32.66821 -377.677172) (xy 32.678386 -377.677557)
			(xy 32.697188 -377.685351) (xy 32.711574 -377.699749) (xy 32.719352 -377.718557) (xy 32.719772 -377.728734)
			(xy 32.719772 -377.886722) (xy 32.720178 -377.89591) (xy 32.726695 -377.913094) (xy 32.732472 -377.92025)
			(xy 32.754234 -377.945924) (xy 32.792182 -378.001507) (xy 32.823216 -378.061228) (xy 32.84689 -378.12423)
			(xy 32.862864 -378.189609) (xy 32.87091 -378.256429) (xy 32.870913 -378.323732) (xy 32.870906 -378.323793)
			(xy 36.148976 -378.323793) (xy 36.148978 -378.256368) (xy 36.157056 -378.189429) (xy 36.173093 -378.123939)
			(xy 36.196859 -378.060841) (xy 36.22801 -378.001044) (xy 36.2661 -377.945408) (xy 36.287964 -377.919742)
			(xy 36.293775 -377.912608) (xy 36.300279 -377.895409) (xy 36.300664 -377.886214) (xy 36.300664 -377.728734)
			(xy 36.301155 -377.718607) (xy 36.308876 -377.699882) (xy 36.323162 -377.685523) (xy 36.341847 -377.677707)
			(xy 36.351972 -377.677172) (xy 37.068252 -377.677172) (xy 37.0784 -377.67766) (xy 37.097145 -377.685435)
			(xy 37.11147 -377.699811) (xy 37.119176 -377.718585) (xy 37.11956 -377.728734) (xy 37.11956 -377.886214)
			(xy 37.119972 -377.895401) (xy 37.126485 -377.912585) (xy 37.13226 -377.919742) (xy 37.1541 -377.945428)
			(xy 37.192192 -378.001058) (xy 37.223346 -378.060851) (xy 37.247113 -378.123946) (xy 37.263152 -378.189433)
			(xy 37.27123 -378.256369) (xy 37.271233 -378.323792) (xy 37.271233 -378.323794) (xy 40.548742 -378.323794)
			(xy 40.548744 -378.256367) (xy 40.556824 -378.189426) (xy 40.572863 -378.123935) (xy 40.596633 -378.060837)
			(xy 40.627789 -378.00104) (xy 40.665885 -377.945406) (xy 40.687752 -377.919742) (xy 40.693562 -377.912607)
			(xy 40.700067 -377.895408) (xy 40.700452 -377.886214) (xy 40.700452 -377.728734) (xy 40.700955 -377.718608)
			(xy 40.708674 -377.699885) (xy 40.722955 -377.685528) (xy 40.741637 -377.677709) (xy 40.75176 -377.677172)
			(xy 41.46804 -377.677172) (xy 41.478193 -377.677588) (xy 41.496941 -377.685392) (xy 41.511262 -377.699789)
			(xy 41.518965 -377.718579) (xy 41.519348 -377.728734) (xy 41.519348 -377.886214) (xy 41.519763 -377.8954)
			(xy 41.526275 -377.912584) (xy 41.532048 -377.919742) (xy 41.553888 -377.945427) (xy 41.591981 -378.001058)
			(xy 41.623136 -378.060851) (xy 41.646904 -378.123945) (xy 41.662943 -378.189432) (xy 41.671021 -378.256369)
			(xy 41.671024 -378.323792) (xy 41.671024 -378.323793) (xy 71.348797 -378.323793) (xy 71.348799 -378.256368)
			(xy 71.356877 -378.189428) (xy 71.372915 -378.123937) (xy 71.396682 -378.060839) (xy 71.427835 -378.001042)
			(xy 71.465927 -377.945407) (xy 71.487792 -377.919742) (xy 71.493595 -377.912601) (xy 71.500106 -377.895407)
			(xy 71.500492 -377.886214) (xy 71.500492 -377.728734) (xy 71.501053 -377.718615) (xy 71.508761 -377.699904)
			(xy 71.523024 -377.685548) (xy 71.541685 -377.67772) (xy 71.5518 -377.677172) (xy 72.26808 -377.677172)
			(xy 72.278229 -377.677637) (xy 72.296976 -377.685421) (xy 72.311299 -377.699804) (xy 72.319005 -377.718583)
			(xy 72.319388 -377.728734) (xy 72.319388 -377.886214) (xy 72.319794 -377.895402) (xy 72.326311 -377.912586)
			(xy 72.332088 -377.919742) (xy 72.353927 -377.945428) (xy 72.392017 -378.001059) (xy 72.42317 -378.060853)
			(xy 72.446936 -378.123947) (xy 72.462973 -378.189433) (xy 72.471052 -378.25637) (xy 72.471054 -378.323734)
			(xy 75.749092 -378.323734) (xy 75.749095 -378.256427) (xy 75.757142 -378.189601) (xy 75.773119 -378.124217)
			(xy 75.796796 -378.061212) (xy 75.827835 -378.001488) (xy 75.86579 -377.945902) (xy 75.88758 -377.92025)
			(xy 75.893378 -377.913106) (xy 75.899892 -377.895915) (xy 75.90028 -377.886722) (xy 75.90028 -377.728734)
			(xy 75.900693 -377.718559) (xy 75.908474 -377.699757) (xy 75.922864 -377.68537) (xy 75.941667 -377.677591)
			(xy 75.951842 -377.677172) (xy 76.668122 -377.677172) (xy 76.678299 -377.677547) (xy 76.697101 -377.685345)
			(xy 76.711486 -377.699746) (xy 76.719264 -377.718556) (xy 76.719684 -377.728734) (xy 76.719684 -377.886722)
			(xy 76.720087 -377.89591) (xy 76.726606 -377.913094) (xy 76.732384 -377.92025) (xy 76.754146 -377.945923)
			(xy 76.792094 -378.001507) (xy 76.823127 -378.061228) (xy 76.8468 -378.12423) (xy 76.862774 -378.189609)
			(xy 76.87082 -378.256429) (xy 76.870822 -378.323732) (xy 76.870815 -378.323793) (xy 80.148885 -378.323793)
			(xy 80.148887 -378.256368) (xy 80.156965 -378.189428) (xy 80.173003 -378.123938) (xy 80.196769 -378.06084)
			(xy 80.227921 -378.001043) (xy 80.266011 -377.945408) (xy 80.287876 -377.919742) (xy 80.293677 -377.9126)
			(xy 80.30019 -377.895407) (xy 80.300576 -377.886214) (xy 80.300576 -377.728734) (xy 80.301056 -377.718605)
			(xy 80.308779 -377.699878) (xy 80.323068 -377.685519) (xy 80.341758 -377.677705) (xy 80.351884 -377.677172)
			(xy 81.068164 -377.677172) (xy 81.078281 -377.677645) (xy 81.096978 -377.685376) (xy 81.111293 -377.699675)
			(xy 81.119044 -377.718364) (xy 81.119472 -377.72848) (xy 81.119472 -377.886214) (xy 81.119882 -377.895401)
			(xy 81.126396 -377.912585) (xy 81.132172 -377.919742) (xy 81.154011 -377.945428) (xy 81.192103 -378.001059)
			(xy 81.223256 -378.060852) (xy 81.247023 -378.123946) (xy 81.263061 -378.189433) (xy 81.27114 -378.256369)
			(xy 81.271142 -378.323792) (xy 81.271142 -378.323793) (xy 84.548676 -378.323793) (xy 84.548678 -378.256368)
			(xy 84.556756 -378.189429) (xy 84.572793 -378.123939) (xy 84.596559 -378.060841) (xy 84.62771 -378.001044)
			(xy 84.6658 -377.945408) (xy 84.687664 -377.919742) (xy 84.693475 -377.912608) (xy 84.699979 -377.895409)
			(xy 84.700364 -377.886214) (xy 84.700364 -377.728734) (xy 84.700855 -377.718607) (xy 84.708576 -377.699882)
			(xy 84.722862 -377.685523) (xy 84.741547 -377.677707) (xy 84.751672 -377.677172) (xy 85.467952 -377.677172)
			(xy 85.478068 -377.677655) (xy 85.496765 -377.685382) (xy 85.51108 -377.699678) (xy 85.518832 -377.718365)
			(xy 85.51926 -377.72848) (xy 85.51926 -377.886214) (xy 85.519672 -377.895401) (xy 85.526185 -377.912585)
			(xy 85.53196 -377.919742) (xy 85.5538 -377.945428) (xy 85.591892 -378.001058) (xy 85.623046 -378.060851)
			(xy 85.646813 -378.123946) (xy 85.662852 -378.189433) (xy 85.67093 -378.256369) (xy 85.670933 -378.323734)
			(xy 115.349234 -378.323734) (xy 115.349237 -378.256427) (xy 115.357283 -378.189603) (xy 115.373258 -378.12422)
			(xy 115.396932 -378.061215) (xy 115.427966 -378.00149) (xy 115.465916 -377.945903) (xy 115.487704 -377.92025)
			(xy 115.493505 -377.913108) (xy 115.500017 -377.895915) (xy 115.500404 -377.886722) (xy 115.500404 -377.728734)
			(xy 115.500961 -377.718583) (xy 115.508717 -377.699821) (xy 115.523064 -377.685456) (xy 115.541815 -377.677674)
			(xy 115.551966 -377.677172) (xy 116.268246 -377.677172) (xy 116.278411 -377.677597) (xy 116.297188 -377.685393)
			(xy 116.311552 -377.69978) (xy 116.319319 -377.718568) (xy 116.319808 -377.728734) (xy 116.319808 -377.886722)
			(xy 116.320206 -377.895911) (xy 116.326728 -377.913095) (xy 116.332508 -377.92025) (xy 116.354272 -377.945922)
			(xy 116.392225 -378.001505) (xy 116.423262 -378.061225) (xy 116.446939 -378.124227) (xy 116.462915 -378.189607)
			(xy 116.470962 -378.256428) (xy 116.470964 -378.323732) (xy 116.470957 -378.323793) (xy 119.749003 -378.323793)
			(xy 119.749005 -378.256368) (xy 119.757084 -378.189428) (xy 119.773122 -378.123937) (xy 119.796889 -378.060839)
			(xy 119.828043 -378.001042) (xy 119.866134 -377.945407) (xy 119.888 -377.919742) (xy 119.893804 -377.912602)
			(xy 119.900314 -377.895407) (xy 119.9007 -377.886214) (xy 119.9007 -377.728734) (xy 119.901253 -377.718614)
			(xy 119.908963 -377.699902) (xy 119.923228 -377.685546) (xy 119.941892 -377.677718) (xy 119.952008 -377.677172)
			(xy 120.668288 -377.677172) (xy 120.678438 -377.677631) (xy 120.697185 -377.685417) (xy 120.711507 -377.699802)
			(xy 120.719213 -377.718582) (xy 120.719596 -377.728734) (xy 120.719596 -377.886214) (xy 120.72 -377.895402)
			(xy 120.726518 -377.912586) (xy 120.732296 -377.919742) (xy 120.754135 -377.945428) (xy 120.792224 -378.00106)
			(xy 120.823376 -378.060853) (xy 120.847142 -378.123947) (xy 120.86318 -378.189434) (xy 120.871258 -378.25637)
			(xy 120.87126 -378.323734) (xy 124.149298 -378.323734) (xy 124.149301 -378.256426) (xy 124.157348 -378.189601)
			(xy 124.173325 -378.124217) (xy 124.197003 -378.061211) (xy 124.228042 -378.001487) (xy 124.265997 -377.945902)
			(xy 124.287788 -377.92025) (xy 124.293587 -377.913106) (xy 124.300101 -377.895915) (xy 124.300488 -377.886722)
			(xy 124.300488 -377.728734) (xy 124.300893 -377.718558) (xy 124.308676 -377.699755) (xy 124.323068 -377.685367)
			(xy 124.341874 -377.67759) (xy 124.35205 -377.677172) (xy 125.06833 -377.677172) (xy 125.078508 -377.67754)
			(xy 125.09731 -377.685341) (xy 125.111695 -377.699744) (xy 125.119473 -377.718556) (xy 125.119892 -377.728734)
			(xy 125.119892 -377.886722) (xy 125.120293 -377.89591) (xy 125.126813 -377.913094) (xy 125.132592 -377.92025)
			(xy 125.154353 -377.945924) (xy 125.192301 -378.001508) (xy 125.223334 -378.061229) (xy 125.247006 -378.12423)
			(xy 125.26298 -378.189609) (xy 125.271026 -378.256429) (xy 125.271028 -378.323732) (xy 125.271028 -378.323734)
			(xy 128.549089 -378.323734) (xy 128.549092 -378.256427) (xy 128.557139 -378.189602) (xy 128.573116 -378.124218)
			(xy 128.596793 -378.061212) (xy 128.627831 -378.001488) (xy 128.665786 -377.945902) (xy 128.687576 -377.92025)
			(xy 128.693374 -377.913105) (xy 128.699888 -377.895915) (xy 128.700276 -377.886722) (xy 128.700276 -377.728734)
			(xy 128.700693 -377.71856) (xy 128.708474 -377.699759) (xy 128.722862 -377.685371) (xy 128.741664 -377.677592)
			(xy 128.751838 -377.677172) (xy 129.468118 -377.677172) (xy 129.478295 -377.67755) (xy 129.497097 -377.685347)
			(xy 129.511482 -377.699747) (xy 129.51926 -377.718557) (xy 129.51968 -377.728734) (xy 129.51968 -377.886722)
			(xy 129.520084 -377.89591) (xy 129.526602 -377.913094) (xy 129.53238 -377.92025) (xy 129.554142 -377.945923)
			(xy 129.59209 -378.001507) (xy 129.623123 -378.061228) (xy 129.646797 -378.12423) (xy 129.662771 -378.189609)
			(xy 129.670817 -378.256429) (xy 129.670819 -378.323732) (xy 129.670819 -378.323734) (xy 159.349143 -378.323734)
			(xy 159.349146 -378.256427) (xy 159.357192 -378.189603) (xy 159.373167 -378.12422) (xy 159.396842 -378.061214)
			(xy 159.427877 -378.00149) (xy 159.465827 -377.945902) (xy 159.487616 -377.92025) (xy 159.493418 -377.913109)
			(xy 159.499929 -377.895915) (xy 159.500316 -377.886722) (xy 159.500316 -377.728734) (xy 159.500791 -377.718567)
			(xy 159.508561 -377.699778) (xy 159.522931 -377.685392) (xy 159.541712 -377.677602) (xy 159.551878 -377.677172)
			(xy 160.268158 -377.677172) (xy 160.278331 -377.677599) (xy 160.297131 -377.685377) (xy 160.311519 -377.699762)
			(xy 160.319299 -377.718561) (xy 160.31972 -377.728734) (xy 160.31972 -377.886722) (xy 160.320115 -377.895911)
			(xy 160.326639 -377.913095) (xy 160.33242 -377.92025) (xy 160.354183 -377.945923) (xy 160.392136 -378.001505)
			(xy 160.423172 -378.061226) (xy 160.446848 -378.124227) (xy 160.462824 -378.189608) (xy 160.470871 -378.256429)
			(xy 160.470874 -378.323732) (xy 160.470867 -378.323793) (xy 163.748912 -378.323793) (xy 163.748914 -378.256367)
			(xy 163.756993 -378.189427) (xy 163.773031 -378.123937) (xy 163.796799 -378.060839) (xy 163.827953 -378.001042)
			(xy 163.866046 -377.945407) (xy 163.887912 -377.919742) (xy 163.893717 -377.912603) (xy 163.900226 -377.895408)
			(xy 163.900612 -377.886214) (xy 163.900612 -377.728734) (xy 163.901154 -377.718613) (xy 163.908865 -377.699898)
			(xy 163.923134 -377.685542) (xy 163.941802 -377.677716) (xy 163.95192 -377.677172) (xy 164.6682 -377.677172)
			(xy 164.678351 -377.677621) (xy 164.697098 -377.685411) (xy 164.71142 -377.699799) (xy 164.719125 -377.718582)
			(xy 164.719508 -377.728734) (xy 164.719508 -377.886214) (xy 164.71991 -377.895402) (xy 164.726429 -377.912586)
			(xy 164.732208 -377.919742) (xy 164.754046 -377.945428) (xy 164.792135 -378.00106) (xy 164.823286 -378.060853)
			(xy 164.847052 -378.123948) (xy 164.863089 -378.189434) (xy 164.871167 -378.25637) (xy 164.871169 -378.323734)
			(xy 168.149231 -378.323734) (xy 168.149234 -378.256427) (xy 168.15728 -378.189604) (xy 168.173254 -378.12422)
			(xy 168.196928 -378.061215) (xy 168.227963 -378.00149) (xy 168.265912 -377.945903) (xy 168.2877 -377.92025)
			(xy 168.2935 -377.913107) (xy 168.300013 -377.895915) (xy 168.3004 -377.886722) (xy 168.3004 -377.728734)
			(xy 168.30096 -377.718583) (xy 168.308717 -377.699822) (xy 168.323062 -377.685457) (xy 168.341812 -377.677675)
			(xy 168.351962 -377.677172) (xy 169.068242 -377.677172) (xy 169.078407 -377.6776) (xy 169.097183 -377.685394)
			(xy 169.111548 -377.699781) (xy 169.119315 -377.718569) (xy 169.119804 -377.728734) (xy 169.119804 -377.886722)
			(xy 169.120203 -377.89591) (xy 169.126724 -377.913095) (xy 169.132504 -377.92025) (xy 169.154265 -377.945924)
			(xy 169.192212 -378.001508) (xy 169.223244 -378.061229) (xy 169.246916 -378.124231) (xy 169.26289 -378.18961)
			(xy 169.270935 -378.256429) (xy 169.270937 -378.323732) (xy 169.270937 -378.323734) (xy 172.548998 -378.323734)
			(xy 172.549001 -378.256426) (xy 172.557048 -378.189601) (xy 172.573025 -378.124217) (xy 172.596703 -378.061211)
			(xy 172.627742 -378.001487) (xy 172.665697 -377.945902) (xy 172.687488 -377.92025) (xy 172.693287 -377.913106)
			(xy 172.699801 -377.895915) (xy 172.700188 -377.886722) (xy 172.700188 -377.728734) (xy 172.700593 -377.718558)
			(xy 172.708376 -377.699755) (xy 172.722768 -377.685367) (xy 172.741574 -377.67759) (xy 172.75175 -377.677172)
			(xy 173.46803 -377.677172) (xy 173.478208 -377.67754) (xy 173.49701 -377.685341) (xy 173.511395 -377.699744)
			(xy 173.519173 -377.718556) (xy 173.519592 -377.728734) (xy 173.519592 -377.886722) (xy 173.519993 -377.89591)
			(xy 173.526513 -377.913094) (xy 173.532292 -377.92025) (xy 173.554053 -377.945924) (xy 173.592001 -378.001508)
			(xy 173.623034 -378.061229) (xy 173.646706 -378.12423) (xy 173.66268 -378.189609) (xy 173.670726 -378.256429)
			(xy 173.670728 -378.323732) (xy 173.662687 -378.390552) (xy 173.646718 -378.455932) (xy 173.623049 -378.518936)
			(xy 173.592021 -378.578659) (xy 173.554077 -378.634245) (xy 173.532292 -378.659898) (xy 173.526513 -378.667056)
			(xy 173.519988 -378.684237) (xy 173.519592 -378.693426) (xy 173.519592 -378.766811) (xy 193.48983 -378.766811)
			(xy 193.48983 -378.633249) (xy 193.497894 -378.499931) (xy 193.513994 -378.367343) (xy 193.538069 -378.235969)
			(xy 193.570032 -378.106288) (xy 193.609767 -377.978774) (xy 193.657129 -377.853891) (xy 193.711944 -377.732096)
			(xy 193.774014 -377.613833) (xy 193.84311 -377.499534) (xy 193.918982 -377.389614) (xy 194.001352 -377.284477)
			(xy 194.08992 -377.184504) (xy 194.184362 -377.090062) (xy 194.284335 -377.001494) (xy 194.389472 -376.919124)
			(xy 194.499392 -376.843252) (xy 194.613691 -376.774156) (xy 194.731954 -376.712086) (xy 194.853749 -376.657271)
			(xy 194.978632 -376.609909) (xy 195.106146 -376.570174) (xy 195.235827 -376.538211) (xy 195.367201 -376.514136)
			(xy 195.499789 -376.498036) (xy 195.633107 -376.489972) (xy 195.766669 -376.489972) (xy 195.899987 -376.498036)
			(xy 196.032575 -376.514136) (xy 196.163949 -376.538211) (xy 196.29363 -376.570174) (xy 196.421144 -376.609909)
			(xy 196.546027 -376.657271) (xy 196.667822 -376.712086) (xy 196.786085 -376.774156) (xy 196.900384 -376.843252)
			(xy 197.010304 -376.919124) (xy 197.115441 -377.001494) (xy 197.215414 -377.090062) (xy 197.309856 -377.184504)
			(xy 197.398424 -377.284477) (xy 197.480794 -377.389614) (xy 197.556666 -377.499534) (xy 197.625762 -377.613833)
			(xy 197.687832 -377.732096) (xy 197.742647 -377.853891) (xy 197.790009 -377.978774) (xy 197.829744 -378.106288)
			(xy 197.861707 -378.235969) (xy 197.885782 -378.367343) (xy 197.901882 -378.499931) (xy 197.909946 -378.633249)
			(xy 197.91045 -378.70003) (xy 197.909946 -378.766811) (xy 197.901882 -378.900129) (xy 197.885782 -379.032717)
			(xy 197.861707 -379.164091) (xy 197.829744 -379.293772) (xy 197.790009 -379.421286) (xy 197.742647 -379.546169)
			(xy 197.687832 -379.667964) (xy 197.625762 -379.786227) (xy 197.556666 -379.900526) (xy 197.480794 -380.010446)
			(xy 197.398424 -380.115583) (xy 197.309856 -380.215556) (xy 197.215414 -380.309998) (xy 197.115441 -380.398566)
			(xy 197.010304 -380.480936) (xy 196.900384 -380.556808) (xy 196.786085 -380.625904) (xy 196.667822 -380.687974)
			(xy 196.546027 -380.742789) (xy 196.421144 -380.790151) (xy 196.29363 -380.829886) (xy 196.163949 -380.861849)
			(xy 196.032575 -380.885924) (xy 195.899987 -380.902024) (xy 195.766669 -380.910088) (xy 195.633107 -380.910088)
			(xy 195.499789 -380.902024) (xy 195.367201 -380.885924) (xy 195.235827 -380.861849) (xy 195.106146 -380.829886)
			(xy 194.978632 -380.790151) (xy 194.853749 -380.742789) (xy 194.731954 -380.687974) (xy 194.613691 -380.625904)
			(xy 194.499392 -380.556808) (xy 194.389472 -380.480936) (xy 194.284335 -380.398566) (xy 194.184362 -380.309998)
			(xy 194.08992 -380.215556) (xy 194.001352 -380.115583) (xy 193.918982 -380.010446) (xy 193.84311 -379.900526)
			(xy 193.774014 -379.786227) (xy 193.711944 -379.667964) (xy 193.657129 -379.546169) (xy 193.609767 -379.421286)
			(xy 193.570032 -379.293772) (xy 193.538069 -379.164091) (xy 193.513994 -379.032717) (xy 193.497894 -378.900129)
			(xy 193.48983 -378.766811) (xy 173.519592 -378.766811) (xy 173.519592 -379.186694) (xy 173.520007 -379.195881)
			(xy 173.526518 -379.213065) (xy 173.532292 -379.220222) (xy 173.554124 -379.245837) (xy 173.592069 -379.30143)
			(xy 173.623099 -379.361159) (xy 173.646768 -379.424168) (xy 173.662737 -379.489554) (xy 173.670777 -379.556381)
			(xy 173.670772 -379.623689) (xy 173.662724 -379.690514) (xy 173.646747 -379.755898) (xy 173.623071 -379.818905)
			(xy 173.592034 -379.87863) (xy 173.554082 -379.934217) (xy 173.532292 -379.95987) (xy 173.526482 -379.967006)
			(xy 173.519976 -379.984204) (xy 173.519592 -379.993398) (xy 173.519592 -380.151386) (xy 173.519056 -380.161539)
			(xy 173.511292 -380.180302) (xy 173.496939 -380.194667) (xy 173.478183 -380.202447) (xy 173.46803 -380.202948)
			(xy 172.75175 -380.202948) (xy 172.74158 -380.202495) (xy 172.722784 -380.194724) (xy 172.708396 -380.180347)
			(xy 172.700612 -380.161556) (xy 172.700188 -380.151386) (xy 172.700188 -379.993398) (xy 172.699781 -379.98421)
			(xy 172.693266 -379.967026) (xy 172.687488 -379.95987) (xy 172.665744 -379.934181) (xy 172.627791 -379.878601)
			(xy 172.596753 -379.818883) (xy 172.573075 -379.755883) (xy 172.557097 -379.690505) (xy 172.549049 -379.623686)
			(xy 172.549045 -379.556383) (xy 172.557085 -379.489563) (xy 172.573055 -379.424183) (xy 172.596724 -379.36118)
			(xy 172.627755 -379.301458) (xy 172.665702 -379.245873) (xy 172.687488 -379.220222) (xy 172.693299 -379.213087)
			(xy 172.699805 -379.195889) (xy 172.700188 -379.186694) (xy 172.700188 -378.693426) (xy 172.699768 -378.68424)
			(xy 172.693262 -378.667055) (xy 172.687488 -378.659898) (xy 172.665673 -378.634268) (xy 172.627722 -378.578679)
			(xy 172.596687 -378.518953) (xy 172.573014 -378.455946) (xy 172.557041 -378.39056) (xy 172.548998 -378.323734)
			(xy 169.270937 -378.323734) (xy 169.262897 -378.390552) (xy 169.246928 -378.455932) (xy 169.22326 -378.518935)
			(xy 169.192232 -378.578658) (xy 169.154289 -378.634245) (xy 169.132504 -378.659898) (xy 169.126726 -378.667057)
			(xy 169.1202 -378.684237) (xy 169.119804 -378.693426) (xy 169.119804 -379.186694) (xy 169.120216 -379.195881)
			(xy 169.126728 -379.213065) (xy 169.132504 -379.220222) (xy 169.154336 -379.245838) (xy 169.19228 -379.30143)
			(xy 169.223309 -379.361159) (xy 169.246977 -379.424169) (xy 169.262946 -379.489555) (xy 169.270986 -379.556381)
			(xy 169.270982 -379.623689) (xy 169.262933 -379.690513) (xy 169.246957 -379.755898) (xy 169.223281 -379.818904)
			(xy 169.192245 -379.878629) (xy 169.154293 -379.934217) (xy 169.132504 -379.95987) (xy 169.126696 -379.967007)
			(xy 169.120188 -379.984204) (xy 169.119804 -379.993398) (xy 169.119804 -380.151386) (xy 169.119256 -380.161538)
			(xy 169.111494 -380.180299) (xy 169.097146 -380.194663) (xy 169.078393 -380.202445) (xy 169.068242 -380.202948)
			(xy 168.351962 -380.202948) (xy 168.3418 -380.202497) (xy 168.323027 -380.194708) (xy 168.308663 -380.180329)
			(xy 168.300892 -380.161548) (xy 168.3004 -380.151386) (xy 168.3004 -379.993398) (xy 168.299991 -379.984211)
			(xy 168.293476 -379.967026) (xy 168.2877 -379.95987) (xy 168.265959 -379.93418) (xy 168.228011 -379.878598)
			(xy 168.196978 -379.818879) (xy 168.173304 -379.75588) (xy 168.157329 -379.690503) (xy 168.149282 -379.623685)
			(xy 168.149278 -379.556384) (xy 168.157317 -379.489565) (xy 168.173284 -379.424186) (xy 168.19695 -379.361184)
			(xy 168.227975 -379.301461) (xy 168.265916 -379.245875) (xy 168.2877 -379.220222) (xy 168.293512 -379.213088)
			(xy 168.300018 -379.195889) (xy 168.3004 -379.186694) (xy 168.3004 -378.693426) (xy 168.299977 -378.68424)
			(xy 168.293472 -378.667056) (xy 168.2877 -378.659898) (xy 168.265888 -378.634266) (xy 168.227942 -378.578676)
			(xy 168.196912 -378.518949) (xy 168.173243 -378.455942) (xy 168.157273 -378.390558) (xy 168.149231 -378.323734)
			(xy 164.871169 -378.323734) (xy 164.871169 -378.323791) (xy 164.863096 -378.390728) (xy 164.847063 -378.456215)
			(xy 164.823302 -378.519311) (xy 164.792155 -378.579106) (xy 164.75407 -378.634741) (xy 164.732208 -378.660406)
			(xy 164.726427 -378.667563) (xy 164.719903 -378.684744) (xy 164.719508 -378.693934) (xy 164.719508 -379.186186)
			(xy 164.719923 -379.195373) (xy 164.726433 -379.212557) (xy 164.732208 -379.219714) (xy 164.754117 -379.245342)
			(xy 164.792204 -379.300982) (xy 164.823352 -379.360784) (xy 164.847113 -379.423885) (xy 164.863145 -379.489379)
			(xy 164.871217 -379.556321) (xy 164.871213 -379.623748) (xy 164.863133 -379.690689) (xy 164.847093 -379.756181)
			(xy 164.823324 -379.81928) (xy 164.792168 -379.879077) (xy 164.754074 -379.934713) (xy 164.732208 -379.960378)
			(xy 164.726397 -379.967513) (xy 164.719891 -379.984711) (xy 164.719508 -379.993906) (xy 164.719508 -380.151386)
			(xy 164.718963 -380.161506) (xy 164.711249 -380.180218) (xy 164.696981 -380.194573) (xy 164.678317 -380.202401)
			(xy 164.6682 -380.202948) (xy 163.95192 -380.202948) (xy 163.941773 -380.202463) (xy 163.92303 -380.194683)
			(xy 163.908708 -380.180306) (xy 163.900999 -380.161534) (xy 163.900612 -380.151386) (xy 163.900612 -379.993906)
			(xy 163.900196 -379.98472) (xy 163.893686 -379.967535) (xy 163.887912 -379.960378) (xy 163.866093 -379.934676)
			(xy 163.828002 -379.879047) (xy 163.796849 -379.819256) (xy 163.773081 -379.756164) (xy 163.757042 -379.690679)
			(xy 163.748963 -379.623745) (xy 163.748958 -379.556324) (xy 163.75703 -379.489389) (xy 163.773061 -379.423902)
			(xy 163.79682 -379.360807) (xy 163.827966 -379.301013) (xy 163.86605 -379.245379) (xy 163.887912 -379.219714)
			(xy 163.893729 -379.212583) (xy 163.900231 -379.195382) (xy 163.900612 -379.186186) (xy 163.900612 -378.693934)
			(xy 163.900183 -378.684749) (xy 163.893682 -378.667565) (xy 163.887912 -378.660406) (xy 163.866022 -378.634762)
			(xy 163.827933 -378.579125) (xy 163.796783 -378.519326) (xy 163.77302 -378.456226) (xy 163.756986 -378.390734)
			(xy 163.748912 -378.323793) (xy 160.470867 -378.323793) (xy 160.462831 -378.390554) (xy 160.44686 -378.455935)
			(xy 160.423188 -378.518939) (xy 160.392156 -378.578661) (xy 160.354207 -378.634246) (xy 160.33242 -378.659898)
			(xy 160.326644 -378.667058) (xy 160.320116 -378.684237) (xy 160.31972 -378.693426) (xy 160.31972 -379.186694)
			(xy 160.320129 -379.195881) (xy 160.326643 -379.213066) (xy 160.33242 -379.220222) (xy 160.354254 -379.245836)
			(xy 160.392205 -379.301427) (xy 160.423238 -379.361156) (xy 160.44691 -379.424165) (xy 160.462881 -379.489552)
			(xy 160.470922 -379.55638) (xy 160.470918 -379.623689) (xy 160.462869 -379.690516) (xy 160.44689 -379.755901)
			(xy 160.42321 -379.818908) (xy 160.392169 -379.878632) (xy 160.354212 -379.934219) (xy 160.33242 -379.95987)
			(xy 160.326614 -379.967008) (xy 160.320104 -379.984204) (xy 160.31972 -379.993398) (xy 160.31972 -380.151386)
			(xy 160.319324 -380.161562) (xy 160.311536 -380.180364) (xy 160.297141 -380.194751) (xy 160.278334 -380.202529)
			(xy 160.268158 -380.202948) (xy 159.551878 -380.202948) (xy 159.541717 -380.202484) (xy 159.522945 -380.1947)
			(xy 159.50858 -380.180325) (xy 159.500808 -380.161547) (xy 159.500316 -380.151386) (xy 159.500316 -379.993398)
			(xy 159.499903 -379.984211) (xy 159.493391 -379.967027) (xy 159.487616 -379.95987) (xy 159.465874 -379.93418)
			(xy 159.427926 -379.878599) (xy 159.396892 -379.81888) (xy 159.373217 -379.75588) (xy 159.357242 -379.690503)
			(xy 159.349195 -379.623685) (xy 159.34919 -379.556384) (xy 159.35723 -379.489565) (xy 159.373197 -379.424186)
			(xy 159.396864 -379.361183) (xy 159.42789 -379.301461) (xy 159.465832 -379.245875) (xy 159.487616 -379.220222)
			(xy 159.49343 -379.213089) (xy 159.499934 -379.195889) (xy 159.500316 -379.186694) (xy 159.500316 -378.693426)
			(xy 159.49989 -378.684241) (xy 159.493387 -378.667056) (xy 159.487616 -378.659898) (xy 159.465803 -378.634267)
			(xy 159.427857 -378.578677) (xy 159.396826 -378.51895) (xy 159.373156 -378.455943) (xy 159.357185 -378.390558)
			(xy 159.349143 -378.323734) (xy 129.670819 -378.323734) (xy 129.662778 -378.390552) (xy 129.646808 -378.455933)
			(xy 129.623139 -378.518936) (xy 129.59211 -378.578659) (xy 129.554166 -378.634246) (xy 129.53238 -378.659898)
			(xy 129.526599 -378.667054) (xy 129.520076 -378.684236) (xy 129.51968 -378.693426) (xy 129.51968 -379.186694)
			(xy 129.520098 -379.19588) (xy 129.526607 -379.213064) (xy 129.53238 -379.220222) (xy 129.554212 -379.245837)
			(xy 129.592159 -379.301429) (xy 129.623189 -379.361158) (xy 129.646858 -379.424168) (xy 129.662827 -379.489554)
			(xy 129.670868 -379.55638) (xy 129.670863 -379.623689) (xy 129.662815 -379.690514) (xy 129.646838 -379.755899)
			(xy 129.623161 -379.818905) (xy 129.592123 -379.87863) (xy 129.55417 -379.934218) (xy 129.53238 -379.95987)
			(xy 129.526569 -379.967005) (xy 129.520064 -379.984203) (xy 129.51968 -379.993398) (xy 129.51968 -380.151386)
			(xy 129.519156 -380.161541) (xy 129.511389 -380.180306) (xy 129.497033 -380.194671) (xy 129.478272 -380.202449)
			(xy 129.468118 -380.202948) (xy 128.751838 -380.202948) (xy 128.741667 -380.202505) (xy 128.722871 -380.19473)
			(xy 128.708484 -380.18035) (xy 128.7007 -380.161557) (xy 128.700276 -380.151386) (xy 128.700276 -379.993398)
			(xy 128.699872 -379.98421) (xy 128.693355 -379.967025) (xy 128.687576 -379.95987) (xy 128.665832 -379.934181)
			(xy 128.62788 -379.878601) (xy 128.596842 -379.818883) (xy 128.573165 -379.755883) (xy 128.557188 -379.690505)
			(xy 128.54914 -379.623686) (xy 128.549136 -379.556384) (xy 128.557176 -379.489563) (xy 128.573145 -379.424183)
			(xy 128.596814 -379.361181) (xy 128.627844 -379.301459) (xy 128.66579 -379.245874) (xy 128.687576 -379.220222)
			(xy 128.693385 -379.213086) (xy 128.699893 -379.195889) (xy 128.700276 -379.186694) (xy 128.700276 -378.693426)
			(xy 128.699859 -378.684239) (xy 128.693351 -378.667055) (xy 128.687576 -378.659898) (xy 128.665762 -378.634267)
			(xy 128.627811 -378.578679) (xy 128.596777 -378.518952) (xy 128.573104 -378.455945) (xy 128.557132 -378.39056)
			(xy 128.549089 -378.323734) (xy 125.271028 -378.323734) (xy 125.262987 -378.390552) (xy 125.247018 -378.455932)
			(xy 125.223349 -378.518936) (xy 125.192321 -378.578659) (xy 125.154377 -378.634245) (xy 125.132592 -378.659898)
			(xy 125.126813 -378.667056) (xy 125.120288 -378.684237) (xy 125.119892 -378.693426) (xy 125.119892 -379.186694)
			(xy 125.120307 -379.195881) (xy 125.126818 -379.213065) (xy 125.132592 -379.220222) (xy 125.154424 -379.245837)
			(xy 125.192369 -379.30143) (xy 125.223399 -379.361159) (xy 125.247068 -379.424168) (xy 125.263037 -379.489554)
			(xy 125.271077 -379.556381) (xy 125.271072 -379.623689) (xy 125.263024 -379.690514) (xy 125.247047 -379.755898)
			(xy 125.223371 -379.818905) (xy 125.192334 -379.87863) (xy 125.154382 -379.934217) (xy 125.132592 -379.95987)
			(xy 125.126782 -379.967006) (xy 125.120276 -379.984204) (xy 125.119892 -379.993398) (xy 125.119892 -380.151386)
			(xy 125.119356 -380.161539) (xy 125.111592 -380.180302) (xy 125.097239 -380.194667) (xy 125.078483 -380.202447)
			(xy 125.06833 -380.202948) (xy 124.35205 -380.202948) (xy 124.34188 -380.202495) (xy 124.323084 -380.194724)
			(xy 124.308696 -380.180347) (xy 124.300912 -380.161556) (xy 124.300488 -380.151386) (xy 124.300488 -379.993398)
			(xy 124.300081 -379.98421) (xy 124.293566 -379.967026) (xy 124.287788 -379.95987) (xy 124.266044 -379.934181)
			(xy 124.228091 -379.878601) (xy 124.197053 -379.818883) (xy 124.173375 -379.755883) (xy 124.157397 -379.690505)
			(xy 124.149349 -379.623686) (xy 124.149345 -379.556383) (xy 124.157385 -379.489563) (xy 124.173355 -379.424183)
			(xy 124.197024 -379.36118) (xy 124.228055 -379.301458) (xy 124.266002 -379.245873) (xy 124.287788 -379.220222)
			(xy 124.293599 -379.213087) (xy 124.300105 -379.195889) (xy 124.300488 -379.186694) (xy 124.300488 -378.693426)
			(xy 124.300068 -378.68424) (xy 124.293562 -378.667055) (xy 124.287788 -378.659898) (xy 124.265973 -378.634268)
			(xy 124.228022 -378.578679) (xy 124.196987 -378.518953) (xy 124.173314 -378.455946) (xy 124.157341 -378.39056)
			(xy 124.149298 -378.323734) (xy 120.87126 -378.323734) (xy 120.87126 -378.323791) (xy 120.863187 -378.390728)
			(xy 120.847154 -378.456216) (xy 120.823392 -378.519311) (xy 120.792244 -378.579107) (xy 120.754159 -378.634741)
			(xy 120.732296 -378.660406) (xy 120.726514 -378.667561) (xy 120.719991 -378.684744) (xy 120.719596 -378.693934)
			(xy 120.719596 -379.186186) (xy 120.720014 -379.195372) (xy 120.726522 -379.212557) (xy 120.732296 -379.219714)
			(xy 120.754205 -379.245342) (xy 120.792293 -379.300982) (xy 120.823442 -379.360783) (xy 120.847204 -379.423885)
			(xy 120.863236 -379.489378) (xy 120.871308 -379.556321) (xy 120.871304 -379.623748) (xy 120.863224 -379.69069)
			(xy 120.847183 -379.756181) (xy 120.823414 -379.81928) (xy 120.792257 -379.879078) (xy 120.754163 -379.934713)
			(xy 120.732296 -379.960378) (xy 120.726483 -379.967512) (xy 120.719978 -379.984711) (xy 120.719596 -379.993906)
			(xy 120.719596 -380.151386) (xy 120.719063 -380.161507) (xy 120.711347 -380.180221) (xy 120.697075 -380.194577)
			(xy 120.678406 -380.202403) (xy 120.668288 -380.202948) (xy 119.952008 -380.202948) (xy 119.94186 -380.202473)
			(xy 119.923117 -380.194689) (xy 119.908795 -380.180309) (xy 119.901087 -380.161535) (xy 119.9007 -380.151386)
			(xy 119.9007 -379.993906) (xy 119.900287 -379.984719) (xy 119.893775 -379.967535) (xy 119.888 -379.960378)
			(xy 119.866181 -379.934675) (xy 119.828091 -379.879046) (xy 119.796938 -379.819255) (xy 119.773172 -379.756163)
			(xy 119.757133 -379.690679) (xy 119.749053 -379.623745) (xy 119.749049 -379.556325) (xy 119.757121 -379.489389)
			(xy 119.773151 -379.423903) (xy 119.79691 -379.360808) (xy 119.828056 -379.301013) (xy 119.866139 -379.245379)
			(xy 119.888 -379.219714) (xy 119.893816 -379.212582) (xy 119.900319 -379.195381) (xy 119.9007 -379.186186)
			(xy 119.9007 -378.693934) (xy 119.900273 -378.684749) (xy 119.893771 -378.667564) (xy 119.888 -378.660406)
			(xy 119.86611 -378.634762) (xy 119.828023 -378.579124) (xy 119.796873 -378.519325) (xy 119.77311 -378.456226)
			(xy 119.757077 -378.390734) (xy 119.749003 -378.323793) (xy 116.470957 -378.323793) (xy 116.462922 -378.390554)
			(xy 116.44695 -378.455936) (xy 116.423278 -378.518939) (xy 116.392245 -378.578662) (xy 116.354296 -378.634247)
			(xy 116.332508 -378.659898) (xy 116.326731 -378.667057) (xy 116.320204 -378.684237) (xy 116.319808 -378.693426)
			(xy 116.319808 -379.186694) (xy 116.320219 -379.195881) (xy 116.326732 -379.213066) (xy 116.332508 -379.220222)
			(xy 116.354343 -379.245836) (xy 116.392293 -379.301427) (xy 116.423328 -379.361155) (xy 116.447 -379.424165)
			(xy 116.462971 -379.489552) (xy 116.471013 -379.55638) (xy 116.471009 -379.623689) (xy 116.462959 -379.690516)
			(xy 116.44698 -379.755901) (xy 116.423299 -379.818908) (xy 116.392258 -379.878633) (xy 116.3543 -379.934219)
			(xy 116.332508 -379.95987) (xy 116.3267 -379.967007) (xy 116.320192 -379.984204) (xy 116.319808 -379.993398)
			(xy 116.319808 -380.151386) (xy 116.319256 -380.161537) (xy 116.311495 -380.180297) (xy 116.297148 -380.194661)
			(xy 116.278397 -380.202445) (xy 116.268246 -380.202948) (xy 115.551966 -380.202948) (xy 115.541804 -380.202494)
			(xy 115.523032 -380.194706) (xy 115.508667 -380.180328) (xy 115.500896 -380.161548) (xy 115.500404 -380.151386)
			(xy 115.500404 -379.993398) (xy 115.499994 -379.984211) (xy 115.49348 -379.967027) (xy 115.487704 -379.95987)
			(xy 115.465963 -379.93418) (xy 115.428015 -379.878598) (xy 115.396981 -379.81888) (xy 115.373307 -379.75588)
			(xy 115.357332 -379.690503) (xy 115.349285 -379.623685) (xy 115.349281 -379.556384) (xy 115.35732 -379.489565)
			(xy 115.373287 -379.424186) (xy 115.396953 -379.361184) (xy 115.427979 -379.301461) (xy 115.46592 -379.245875)
			(xy 115.487704 -379.220222) (xy 115.493517 -379.213088) (xy 115.500022 -379.195889) (xy 115.500404 -379.186694)
			(xy 115.500404 -378.693426) (xy 115.49998 -378.68424) (xy 115.493476 -378.667056) (xy 115.487704 -378.659898)
			(xy 115.465892 -378.634266) (xy 115.427946 -378.578676) (xy 115.396916 -378.518949) (xy 115.373246 -378.455942)
			(xy 115.357276 -378.390558) (xy 115.349234 -378.323734) (xy 85.670933 -378.323734) (xy 85.670933 -378.323792)
			(xy 85.662859 -378.390729) (xy 85.646825 -378.456217) (xy 85.623062 -378.519313) (xy 85.591912 -378.579108)
			(xy 85.553824 -378.634741) (xy 85.53196 -378.660406) (xy 85.526173 -378.667558) (xy 85.519654 -378.684743)
			(xy 85.51926 -378.693934) (xy 85.51926 -379.186186) (xy 85.519686 -379.195371) (xy 85.526189 -379.212555)
			(xy 85.53196 -379.219714) (xy 85.553871 -379.245341) (xy 85.591961 -379.30098) (xy 85.623111 -379.360781)
			(xy 85.646875 -379.423883) (xy 85.662908 -379.489377) (xy 85.670981 -379.55632) (xy 85.670977 -379.623749)
			(xy 85.662896 -379.690691) (xy 85.646854 -379.756183) (xy 85.623083 -379.819282) (xy 85.591925 -379.879079)
			(xy 85.553828 -379.934713) (xy 85.53196 -379.960378) (xy 85.526143 -379.967508) (xy 85.519641 -379.98471)
			(xy 85.51926 -379.993906) (xy 85.51926 -380.151386) (xy 85.518762 -380.161512) (xy 85.511039 -380.180233)
			(xy 85.496756 -380.194589) (xy 85.478075 -380.202409) (xy 85.467952 -380.202948) (xy 84.751672 -380.202948)
			(xy 84.741567 -380.202439) (xy 84.722898 -380.194701) (xy 84.708606 -380.180412) (xy 84.700863 -380.161744)
			(xy 84.700364 -380.15164) (xy 84.700364 -379.993906) (xy 84.699937 -379.984721) (xy 84.693433 -379.967537)
			(xy 84.687664 -379.960378) (xy 84.665846 -379.934675) (xy 84.627759 -379.879045) (xy 84.596608 -379.819254)
			(xy 84.572843 -379.756162) (xy 84.556805 -379.690678) (xy 84.548726 -379.623744) (xy 84.548722 -379.556325)
			(xy 84.556793 -379.48939) (xy 84.572822 -379.423904) (xy 84.59658 -379.36081) (xy 84.627723 -379.301014)
			(xy 84.665804 -379.24538) (xy 84.687664 -379.219714) (xy 84.693487 -379.212588) (xy 84.699984 -379.195383)
			(xy 84.700364 -379.186186) (xy 84.700364 -378.693934) (xy 84.699923 -378.68475) (xy 84.693429 -378.667566)
			(xy 84.687664 -378.660406) (xy 84.665776 -378.634761) (xy 84.62769 -378.579123) (xy 84.596543 -378.519324)
			(xy 84.572781 -378.456224) (xy 84.556749 -378.390733) (xy 84.548676 -378.323793) (xy 81.271142 -378.323793)
			(xy 81.263068 -378.390729) (xy 81.247035 -378.456217) (xy 81.223272 -378.519312) (xy 81.192123 -378.579108)
			(xy 81.154035 -378.634741) (xy 81.132172 -378.660406) (xy 81.126387 -378.667559) (xy 81.119866 -378.684744)
			(xy 81.119472 -378.693934) (xy 81.119472 -379.186186) (xy 81.119895 -379.195372) (xy 81.126401 -379.212556)
			(xy 81.132172 -379.219714) (xy 81.154082 -379.245341) (xy 81.192171 -379.300981) (xy 81.223322 -379.360782)
			(xy 81.247084 -379.423884) (xy 81.263118 -379.489378) (xy 81.27119 -379.556321) (xy 81.271186 -379.623748)
			(xy 81.263105 -379.69069) (xy 81.247064 -379.756182) (xy 81.223293 -379.819281) (xy 81.192136 -379.879079)
			(xy 81.15404 -379.934713) (xy 81.132172 -379.960378) (xy 81.126356 -379.967509) (xy 81.119854 -379.984711)
			(xy 81.119472 -379.993906) (xy 81.119472 -380.151386) (xy 81.118962 -380.16151) (xy 81.111241 -380.180229)
			(xy 81.096962 -380.194585) (xy 81.078286 -380.202407) (xy 81.068164 -380.202948) (xy 80.351884 -380.202948)
			(xy 80.34178 -380.202429) (xy 80.323111 -380.194695) (xy 80.308818 -380.180409) (xy 80.301076 -380.161744)
			(xy 80.300576 -380.15164) (xy 80.300576 -379.993906) (xy 80.300168 -379.984718) (xy 80.293654 -379.967534)
			(xy 80.287876 -379.960378) (xy 80.266058 -379.934675) (xy 80.22797 -379.879045) (xy 80.196818 -379.819254)
			(xy 80.173052 -379.756162) (xy 80.157015 -379.690678) (xy 80.148935 -379.623744) (xy 80.148931 -379.556325)
			(xy 80.157002 -379.48939) (xy 80.173032 -379.423904) (xy 80.19679 -379.360809) (xy 80.227934 -379.301014)
			(xy 80.266016 -379.24538) (xy 80.287876 -379.219714) (xy 80.293689 -379.21258) (xy 80.300195 -379.195381)
			(xy 80.300576 -379.186186) (xy 80.300576 -378.693934) (xy 80.300155 -378.684748) (xy 80.29365 -378.667563)
			(xy 80.287876 -378.660406) (xy 80.265987 -378.634761) (xy 80.227901 -378.579123) (xy 80.196753 -378.519324)
			(xy 80.172991 -378.456225) (xy 80.156958 -378.390733) (xy 80.148885 -378.323793) (xy 76.870815 -378.323793)
			(xy 76.862781 -378.390552) (xy 76.846812 -378.455933) (xy 76.823143 -378.518936) (xy 76.792114 -378.578659)
			(xy 76.75417 -378.634246) (xy 76.732384 -378.659898) (xy 76.726604 -378.667055) (xy 76.72008 -378.684236)
			(xy 76.719684 -378.693426) (xy 76.719684 -379.186694) (xy 76.720101 -379.19588) (xy 76.72661 -379.213065)
			(xy 76.732384 -379.220222) (xy 76.754216 -379.245837) (xy 76.792162 -379.30143) (xy 76.823192 -379.361158)
			(xy 76.846861 -379.424168) (xy 76.86283 -379.489554) (xy 76.870871 -379.55638) (xy 76.870866 -379.623689)
			(xy 76.862818 -379.690514) (xy 76.846841 -379.755899) (xy 76.823164 -379.818905) (xy 76.792127 -379.87863)
			(xy 76.754174 -379.934218) (xy 76.732384 -379.95987) (xy 76.726573 -379.967005) (xy 76.720068 -379.984203)
			(xy 76.719684 -379.993398) (xy 76.719684 -380.151386) (xy 76.719156 -380.16154) (xy 76.71139 -380.180305)
			(xy 76.697035 -380.19467) (xy 76.678276 -380.202449) (xy 76.668122 -380.202948) (xy 75.951842 -380.202948)
			(xy 75.941671 -380.202501) (xy 75.922875 -380.194728) (xy 75.908488 -380.180349) (xy 75.900704 -380.161556)
			(xy 75.90028 -380.151386) (xy 75.90028 -379.993398) (xy 75.899875 -379.98421) (xy 75.893358 -379.967026)
			(xy 75.88758 -379.95987) (xy 75.865836 -379.934181) (xy 75.827883 -379.878601) (xy 75.796846 -379.818883)
			(xy 75.773169 -379.755883) (xy 75.757191 -379.690505) (xy 75.749143 -379.623686) (xy 75.749139 -379.556383)
			(xy 75.757179 -379.489563) (xy 75.773148 -379.424183) (xy 75.796818 -379.36118) (xy 75.827848 -379.301458)
			(xy 75.865794 -379.245874) (xy 75.88758 -379.220222) (xy 75.89339 -379.213086) (xy 75.899897 -379.195889)
			(xy 75.90028 -379.186694) (xy 75.90028 -378.693426) (xy 75.899862 -378.68424) (xy 75.893354 -378.667055)
			(xy 75.88758 -378.659898) (xy 75.865766 -378.634267) (xy 75.827815 -378.578679) (xy 75.79678 -378.518953)
			(xy 75.773107 -378.455945) (xy 75.757135 -378.39056) (xy 75.749092 -378.323734) (xy 72.471054 -378.323734)
			(xy 72.471054 -378.323791) (xy 72.46298 -378.390728) (xy 72.446947 -378.456216) (xy 72.423186 -378.519312)
			(xy 72.392037 -378.579107) (xy 72.353951 -378.634741) (xy 72.332088 -378.660406) (xy 72.326305 -378.667561)
			(xy 72.319783 -378.684744) (xy 72.319388 -378.693934) (xy 72.319388 -379.186186) (xy 72.319808 -379.195372)
			(xy 72.326315 -379.212556) (xy 72.332088 -379.219714) (xy 72.353998 -379.245342) (xy 72.392086 -379.300981)
			(xy 72.423235 -379.360783) (xy 72.446997 -379.423884) (xy 72.46303 -379.489378) (xy 72.471102 -379.556321)
			(xy 72.471098 -379.623748) (xy 72.463017 -379.69069) (xy 72.446977 -379.756182) (xy 72.423207 -379.819281)
			(xy 72.39205 -379.879078) (xy 72.353955 -379.934713) (xy 72.332088 -379.960378) (xy 72.326274 -379.967511)
			(xy 72.31977 -379.984711) (xy 72.319388 -379.993906) (xy 72.319388 -380.151386) (xy 72.318863 -380.161508)
			(xy 72.311145 -380.180224) (xy 72.296871 -380.19458) (xy 72.278199 -380.202404) (xy 72.26808 -380.202948)
			(xy 71.5518 -380.202948) (xy 71.541652 -380.202479) (xy 71.522909 -380.194693) (xy 71.508587 -380.180311)
			(xy 71.500879 -380.161536) (xy 71.500492 -380.151386) (xy 71.500492 -379.993906) (xy 71.500081 -379.984719)
			(xy 71.493568 -379.967534) (xy 71.487792 -379.960378) (xy 71.465974 -379.934675) (xy 71.427884 -379.879046)
			(xy 71.396732 -379.819255) (xy 71.372965 -379.756163) (xy 71.356927 -379.690678) (xy 71.348847 -379.623744)
			(xy 71.348843 -379.556325) (xy 71.356914 -379.48939) (xy 71.372945 -379.423903) (xy 71.396703 -379.360808)
			(xy 71.427848 -379.301013) (xy 71.465931 -379.245379) (xy 71.487792 -379.219714) (xy 71.493607 -379.212582)
			(xy 71.500111 -379.195381) (xy 71.500492 -379.186186) (xy 71.500492 -378.693934) (xy 71.500067 -378.684748)
			(xy 71.493564 -378.667564) (xy 71.487792 -378.660406) (xy 71.465903 -378.634762) (xy 71.427815 -378.579124)
			(xy 71.396666 -378.519325) (xy 71.372904 -378.456225) (xy 71.35687 -378.390734) (xy 71.348797 -378.323793)
			(xy 41.671024 -378.323793) (xy 41.66295 -378.390729) (xy 41.646915 -378.456218) (xy 41.623152 -378.519314)
			(xy 41.592001 -378.579109) (xy 41.553912 -378.634742) (xy 41.532048 -378.660406) (xy 41.52626 -378.667557)
			(xy 41.519742 -378.684743) (xy 41.519348 -378.693934) (xy 41.519348 -379.186186) (xy 41.519776 -379.195371)
			(xy 41.526279 -379.212555) (xy 41.532048 -379.219714) (xy 41.553959 -379.245341) (xy 41.59205 -379.30098)
			(xy 41.623201 -379.360781) (xy 41.646965 -379.423883) (xy 41.662999 -379.489377) (xy 41.671072 -379.55632)
			(xy 41.671068 -379.623749) (xy 41.662987 -379.690691) (xy 41.646945 -379.756183) (xy 41.623173 -379.819282)
			(xy 41.592014 -379.879079) (xy 41.553917 -379.934714) (xy 41.532048 -379.960378) (xy 41.526229 -379.967507)
			(xy 41.519729 -379.98471) (xy 41.519348 -379.993906) (xy 41.519348 -380.151386) (xy 41.518862 -380.161513)
			(xy 41.511136 -380.180236) (xy 41.49685 -380.194594) (xy 41.478165 -380.202411) (xy 41.46804 -380.202948)
			(xy 40.75176 -380.202948) (xy 40.741609 -380.202512) (xy 40.722865 -380.194712) (xy 40.708545 -380.180321)
			(xy 40.700838 -380.161539) (xy 40.700452 -380.151386) (xy 40.700452 -379.993906) (xy 40.700027 -379.984721)
			(xy 40.693523 -379.967537) (xy 40.687752 -379.960378) (xy 40.665931 -379.934676) (xy 40.627838 -379.879048)
			(xy 40.596682 -379.819258) (xy 40.572913 -379.756165) (xy 40.556873 -379.69068) (xy 40.548793 -379.623745)
			(xy 40.548788 -379.556324) (xy 40.556861 -379.489388) (xy 40.572893 -379.423901) (xy 40.596654 -379.360806)
			(xy 40.627802 -379.301011) (xy 40.665889 -379.245378) (xy 40.687752 -379.219714) (xy 40.693574 -379.212587)
			(xy 40.700072 -379.195382) (xy 40.700452 -379.186186) (xy 40.700452 -378.693934) (xy 40.700014 -378.68475)
			(xy 40.693519 -378.667566) (xy 40.687752 -378.660406) (xy 40.665861 -378.634763) (xy 40.627769 -378.579126)
			(xy 40.596617 -378.519328) (xy 40.572852 -378.456228) (xy 40.556817 -378.390735) (xy 40.548742 -378.323794)
			(xy 37.271233 -378.323794) (xy 37.263159 -378.390729) (xy 37.247125 -378.456217) (xy 37.223362 -378.519313)
			(xy 37.192212 -378.579108) (xy 37.154124 -378.634741) (xy 37.13226 -378.660406) (xy 37.126473 -378.667558)
			(xy 37.119954 -378.684743) (xy 37.11956 -378.693934) (xy 37.11956 -379.186186) (xy 37.119986 -379.195371)
			(xy 37.126489 -379.212555) (xy 37.13226 -379.219714) (xy 37.154171 -379.245341) (xy 37.192261 -379.30098)
			(xy 37.223411 -379.360781) (xy 37.247175 -379.423883) (xy 37.263208 -379.489377) (xy 37.271281 -379.55632)
			(xy 37.271277 -379.623749) (xy 37.263196 -379.690691) (xy 37.247154 -379.756183) (xy 37.223383 -379.819282)
			(xy 37.192225 -379.879079) (xy 37.154128 -379.934713) (xy 37.13226 -379.960378) (xy 37.126443 -379.967508)
			(xy 37.119941 -379.98471) (xy 37.11956 -379.993906) (xy 37.11956 -380.151386) (xy 37.119062 -380.161512)
			(xy 37.111339 -380.180233) (xy 37.097056 -380.194589) (xy 37.078375 -380.202409) (xy 37.068252 -380.202948)
			(xy 36.351972 -380.202948) (xy 36.341822 -380.202502) (xy 36.323078 -380.194707) (xy 36.308758 -380.180318)
			(xy 36.30105 -380.161538) (xy 36.300664 -380.151386) (xy 36.300664 -379.993906) (xy 36.300237 -379.984721)
			(xy 36.293733 -379.967537) (xy 36.287964 -379.960378) (xy 36.266146 -379.934675) (xy 36.228059 -379.879045)
			(xy 36.196908 -379.819254) (xy 36.173143 -379.756162) (xy 36.157105 -379.690678) (xy 36.149026 -379.623744)
			(xy 36.149022 -379.556325) (xy 36.157093 -379.48939) (xy 36.173122 -379.423904) (xy 36.19688 -379.36081)
			(xy 36.228023 -379.301014) (xy 36.266104 -379.24538) (xy 36.287964 -379.219714) (xy 36.293787 -379.212588)
			(xy 36.300284 -379.195383) (xy 36.300664 -379.186186) (xy 36.300664 -378.693934) (xy 36.300223 -378.68475)
			(xy 36.293729 -378.667566) (xy 36.287964 -378.660406) (xy 36.266076 -378.634761) (xy 36.22799 -378.579123)
			(xy 36.196843 -378.519324) (xy 36.173081 -378.456224) (xy 36.157049 -378.390733) (xy 36.148976 -378.323793)
			(xy 32.870906 -378.323793) (xy 32.862871 -378.390552) (xy 32.846902 -378.455933) (xy 32.823232 -378.518936)
			(xy 32.792203 -378.578659) (xy 32.754258 -378.634246) (xy 32.732472 -378.659898) (xy 32.72669 -378.667053)
			(xy 32.720167 -378.684236) (xy 32.719772 -378.693426) (xy 32.719772 -379.186694) (xy 32.720191 -379.19588)
			(xy 32.726699 -379.213064) (xy 32.732472 -379.220222) (xy 32.754305 -379.245837) (xy 32.792251 -379.301429)
			(xy 32.823282 -379.361158) (xy 32.846952 -379.424167) (xy 32.862921 -379.489554) (xy 32.870962 -379.55638)
			(xy 32.870957 -379.623689) (xy 32.862909 -379.690514) (xy 32.846931 -379.755899) (xy 32.823254 -379.818905)
			(xy 32.792216 -379.87863) (xy 32.754262 -379.934218) (xy 32.732472 -379.95987) (xy 32.72666 -379.967004)
			(xy 32.720155 -379.984203) (xy 32.719772 -379.993398) (xy 32.719772 -380.151386) (xy 32.719325 -380.161556)
			(xy 32.711547 -380.180348) (xy 32.697168 -380.194733) (xy 32.678379 -380.20252) (xy 32.66821 -380.202948)
			(xy 31.95193 -380.202948) (xy 31.941759 -380.202511) (xy 31.922962 -380.194733) (xy 31.908576 -380.180351)
			(xy 31.900792 -380.161557) (xy 31.900368 -380.151386) (xy 31.900368 -379.993398) (xy 31.899944 -379.984213)
			(xy 31.893438 -379.967029) (xy 31.887668 -379.95987) (xy 31.865925 -379.934181) (xy 31.827973 -379.878601)
			(xy 31.796936 -379.818882) (xy 31.773259 -379.755883) (xy 31.757282 -379.690505) (xy 31.749234 -379.623686)
			(xy 31.74923 -379.556384) (xy 31.75727 -379.489564) (xy 31.773239 -379.424184) (xy 31.796908 -379.361181)
			(xy 31.827937 -379.301459) (xy 31.865882 -379.245874) (xy 31.887668 -379.220222) (xy 31.893488 -379.213094)
			(xy 31.899987 -379.19589) (xy 31.900368 -379.186694) (xy 31.900368 -378.693426) (xy 31.89993 -378.684242)
			(xy 31.893434 -378.667058) (xy 31.887668 -378.659898) (xy 31.865854 -378.634267) (xy 31.827904 -378.578678)
			(xy 31.79687 -378.518952) (xy 31.773198 -378.455945) (xy 31.757226 -378.39056) (xy 31.749183 -378.323734)
			(xy 28.471145 -378.323734) (xy 28.471145 -378.323792) (xy 28.463071 -378.390728) (xy 28.447038 -378.456216)
			(xy 28.423275 -378.519312) (xy 28.392126 -378.579108) (xy 28.354039 -378.634741) (xy 28.332176 -378.660406)
			(xy 28.326392 -378.66756) (xy 28.31987 -378.684744) (xy 28.319476 -378.693934) (xy 28.319476 -379.186186)
			(xy 28.319898 -379.195372) (xy 28.326404 -379.212556) (xy 28.332176 -379.219714) (xy 28.354036 -379.245382)
			(xy 28.392125 -379.301016) (xy 28.423276 -379.360812) (xy 28.447 -379.423801) (xy 29.549058 -379.423801)
			(xy 29.549059 -379.356496) (xy 29.557103 -379.289673) (xy 29.573076 -379.224291) (xy 29.596749 -379.161286)
			(xy 29.627783 -379.101562) (xy 29.665732 -379.045976) (xy 29.68752 -379.020324) (xy 29.693334 -379.013191)
			(xy 29.699837 -378.995991) (xy 29.70022 -378.986796) (xy 29.70022 -378.828554) (xy 29.700695 -378.818396)
			(xy 29.708482 -378.799629) (xy 29.722852 -378.785266) (xy 29.741623 -378.77749) (xy 29.751782 -378.776992)
			(xy 30.468062 -378.776992) (xy 30.478212 -378.777564) (xy 30.496971 -378.785317) (xy 30.511336 -378.799658)
			(xy 30.51912 -378.818405) (xy 30.519624 -378.828554) (xy 30.519624 -378.986796) (xy 30.520031 -378.995984)
			(xy 30.526546 -379.013168) (xy 30.532324 -379.020324) (xy 30.55411 -379.045978) (xy 30.592059 -379.101564)
			(xy 30.623093 -379.161287) (xy 30.646766 -379.224291) (xy 30.662739 -379.289673) (xy 30.670784 -379.356496)
			(xy 30.670784 -379.423801) (xy 30.66274 -379.490624) (xy 30.646767 -379.556006) (xy 30.623094 -379.61901)
			(xy 30.592061 -379.678734) (xy 30.554112 -379.73432) (xy 30.532324 -379.759972) (xy 30.526517 -379.76711)
			(xy 30.520008 -379.784306) (xy 30.519624 -379.7935) (xy 30.519624 -380.286768) (xy 30.520044 -380.295954)
			(xy 30.52655 -380.313139) (xy 30.532324 -380.320296) (xy 30.554132 -380.345932) (xy 30.592083 -380.40152)
			(xy 30.623117 -380.461245) (xy 30.646791 -380.524252) (xy 30.662763 -380.589636) (xy 30.6708 -380.656404)
			(xy 33.948845 -380.656404) (xy 33.95692 -380.589467) (xy 33.972953 -380.523978) (xy 33.996716 -380.460882)
			(xy 34.027865 -380.401087) (xy 34.065953 -380.345453) (xy 34.087816 -380.319788) (xy 34.093602 -380.312635)
			(xy 34.100122 -380.29545) (xy 34.100516 -380.28626) (xy 34.100516 -379.794008) (xy 34.100098 -379.784822)
			(xy 34.093589 -379.767638) (xy 34.087816 -379.76048) (xy 34.065999 -379.734776) (xy 34.027907 -379.679148)
			(xy 33.996754 -379.619357) (xy 33.972986 -379.556265) (xy 33.956947 -379.49078) (xy 33.948867 -379.423846)
			(xy 33.948863 -379.356426) (xy 33.956934 -379.289491) (xy 33.972965 -379.224004) (xy 33.996724 -379.160909)
			(xy 34.02787 -379.101114) (xy 34.065954 -379.045481) (xy 34.087816 -379.019816) (xy 34.093633 -379.012685)
			(xy 34.100135 -378.995484) (xy 34.100516 -378.986288) (xy 34.100516 -378.828554) (xy 34.100988 -378.818427)
			(xy 34.108727 -378.79971) (xy 34.123017 -378.785356) (xy 34.1417 -378.777534) (xy 34.151824 -378.776992)
			(xy 34.868104 -378.776992) (xy 34.878257 -378.777418) (xy 34.897008 -378.785214) (xy 34.911331 -378.799609)
			(xy 34.919032 -378.818399) (xy 34.919412 -378.828554) (xy 34.919412 -378.986288) (xy 34.919825 -378.995475)
			(xy 34.926336 -379.012659) (xy 34.932112 -379.019816) (xy 34.954023 -379.045443) (xy 34.992109 -379.101083)
			(xy 35.023257 -379.160885) (xy 35.047018 -379.223986) (xy 35.06305 -379.28948) (xy 35.071122 -379.356422)
			(xy 35.071117 -379.42385) (xy 35.063037 -379.490791) (xy 35.046997 -379.556283) (xy 35.023228 -379.619381)
			(xy 34.992072 -379.679179) (xy 34.953978 -379.734815) (xy 34.932112 -379.76048) (xy 34.9263 -379.767615)
			(xy 34.919794 -379.784813) (xy 34.919412 -379.794008) (xy 34.919412 -380.28626) (xy 34.919839 -380.295446)
			(xy 34.92634 -380.31263) (xy 34.932112 -380.319788) (xy 34.953995 -380.345437) (xy 34.992083 -380.401074)
			(xy 35.023232 -380.460873) (xy 35.046994 -380.523972) (xy 35.063028 -380.589463) (xy 35.071102 -380.656403)
			(xy 35.071102 -380.656464) (xy 38.349165 -380.656464) (xy 38.357207 -380.589643) (xy 38.373176 -380.524262)
			(xy 38.396845 -380.461259) (xy 38.427874 -380.401536) (xy 38.465819 -380.345949) (xy 38.487604 -380.320296)
			(xy 38.493385 -380.31314) (xy 38.499909 -380.295958) (xy 38.500304 -380.286768) (xy 38.500304 -379.7935)
			(xy 38.499893 -379.784313) (xy 38.49338 -379.767129) (xy 38.487604 -379.759972) (xy 38.465865 -379.73428)
			(xy 38.427917 -379.678699) (xy 38.396884 -379.61898) (xy 38.37321 -379.555981) (xy 38.357234 -379.490604)
			(xy 38.349187 -379.423786) (xy 38.349183 -379.356486) (xy 38.357221 -379.289667) (xy 38.373188 -379.224288)
			(xy 38.396854 -379.161286) (xy 38.42788 -379.101563) (xy 38.465821 -379.045977) (xy 38.487604 -379.020324)
			(xy 38.493416 -379.01319) (xy 38.499921 -378.995991) (xy 38.500304 -378.986796) (xy 38.500304 -378.828554)
			(xy 38.500795 -378.818397) (xy 38.508578 -378.799634) (xy 38.522944 -378.785271) (xy 38.541709 -378.777493)
			(xy 38.551866 -378.776992) (xy 39.268146 -378.776992) (xy 39.278301 -378.777495) (xy 39.297062 -378.785276)
			(xy 39.311424 -378.799638) (xy 39.319205 -378.818399) (xy 39.319708 -378.828554) (xy 39.319708 -378.986796)
			(xy 39.320118 -378.995983) (xy 39.326632 -379.013168) (xy 39.332408 -379.020324) (xy 39.354244 -379.045937)
			(xy 39.392195 -379.101528) (xy 39.423229 -379.161256) (xy 39.446902 -379.224266) (xy 39.462873 -379.289653)
			(xy 39.470914 -379.356481) (xy 39.47091 -379.423791) (xy 39.46286 -379.490618) (xy 39.44688 -379.556003)
			(xy 39.4232 -379.61901) (xy 39.392158 -379.678735) (xy 39.3542 -379.734321) (xy 39.332408 -379.759972)
			(xy 39.326599 -379.767109) (xy 39.320092 -379.784306) (xy 39.319708 -379.7935) (xy 39.319708 -380.286768)
			(xy 39.320132 -380.295954) (xy 39.326636 -380.313138) (xy 39.332408 -380.320296) (xy 39.354217 -380.345931)
			(xy 39.392169 -380.401519) (xy 39.423204 -380.461244) (xy 39.446878 -380.524251) (xy 39.462851 -380.589636)
			(xy 39.470887 -380.656404) (xy 42.748933 -380.656404) (xy 42.757007 -380.589467) (xy 42.773041 -380.523979)
			(xy 42.796803 -380.460883) (xy 42.827951 -380.401087) (xy 42.866037 -380.345453) (xy 42.8879 -380.319788)
			(xy 42.893684 -380.312634) (xy 42.900206 -380.29545) (xy 42.9006 -380.28626) (xy 42.9006 -379.794008)
			(xy 42.900186 -379.784821) (xy 42.893675 -379.767637) (xy 42.8879 -379.76048) (xy 42.866083 -379.734776)
			(xy 42.827993 -379.679147) (xy 42.79684 -379.619356) (xy 42.773073 -379.556264) (xy 42.757035 -379.49078)
			(xy 42.748955 -379.423846) (xy 42.748951 -379.356426) (xy 42.757022 -379.289491) (xy 42.773052 -379.224005)
			(xy 42.796811 -379.16091) (xy 42.827956 -379.101115) (xy 42.866039 -379.045481) (xy 42.8879 -379.019816)
			(xy 42.893715 -379.012684) (xy 42.900219 -378.995483) (xy 42.9006 -378.986288) (xy 42.9006 -378.828554)
			(xy 42.901088 -378.818429) (xy 42.908823 -378.799715) (xy 42.923108 -378.785361) (xy 42.941786 -378.777537)
			(xy 42.951908 -378.776992) (xy 43.668188 -378.776992) (xy 43.67834 -378.777431) (xy 43.697091 -378.785221)
			(xy 43.711414 -378.799613) (xy 43.719116 -378.8184) (xy 43.719496 -378.828554) (xy 43.719496 -378.986288)
			(xy 43.719913 -378.995474) (xy 43.726422 -379.012659) (xy 43.732196 -379.019816) (xy 43.754107 -379.045442)
			(xy 43.792195 -379.101082) (xy 43.823344 -379.160884) (xy 43.847105 -379.223986) (xy 43.863138 -379.28948)
			(xy 43.87121 -379.356422) (xy 43.871205 -379.42385) (xy 43.863125 -379.490791) (xy 43.847084 -379.556283)
			(xy 43.823314 -379.619382) (xy 43.792158 -379.67918) (xy 43.754063 -379.734815) (xy 43.732196 -379.76048)
			(xy 43.726382 -379.767613) (xy 43.719878 -379.784813) (xy 43.719496 -379.794008) (xy 43.719496 -380.28626)
			(xy 43.719926 -380.295445) (xy 43.726426 -380.31263) (xy 43.732196 -380.319788) (xy 43.75408 -380.345437)
			(xy 43.792168 -380.401074) (xy 43.823318 -380.460872) (xy 43.847081 -380.523971) (xy 43.863116 -380.589462)
			(xy 43.87119 -380.656402) (xy 43.87119 -380.656463) (xy 73.548987 -380.656463) (xy 73.557029 -380.589642)
			(xy 73.572999 -380.524261) (xy 73.596669 -380.461258) (xy 73.6277 -380.401535) (xy 73.665646 -380.345948)
			(xy 73.687432 -380.320296) (xy 73.693217 -380.313143) (xy 73.699738 -380.295958) (xy 73.700132 -380.286768)
			(xy 73.700132 -379.7935) (xy 73.699715 -379.784314) (xy 73.693205 -379.76713) (xy 73.687432 -379.759972)
			(xy 73.665692 -379.734281) (xy 73.627742 -379.6787) (xy 73.596707 -379.618982) (xy 73.573032 -379.555982)
			(xy 73.557056 -379.490605) (xy 73.549008 -379.423787) (xy 73.549004 -379.356486) (xy 73.557043 -379.289666)
			(xy 73.573011 -379.224287) (xy 73.596678 -379.161285) (xy 73.627705 -379.101562) (xy 73.665648 -379.045976)
			(xy 73.687432 -379.020324) (xy 73.693247 -379.013192) (xy 73.69975 -378.995991) (xy 73.700132 -378.986796)
			(xy 73.700132 -378.828554) (xy 73.700596 -378.818394) (xy 73.708384 -378.799625) (xy 73.722759 -378.785262)
			(xy 73.741534 -378.777488) (xy 73.751694 -378.776992) (xy 74.467974 -378.776992) (xy 74.478125 -378.777553)
			(xy 74.496884 -378.785311) (xy 74.511249 -378.799655) (xy 74.519032 -378.818404) (xy 74.519536 -378.828554)
			(xy 74.519536 -378.986796) (xy 74.519962 -378.995981) (xy 74.526466 -379.013165) (xy 74.532236 -379.020324)
			(xy 74.554072 -379.045937) (xy 74.592021 -379.101528) (xy 74.623053 -379.161257) (xy 74.646725 -379.224267)
			(xy 74.662695 -379.289654) (xy 74.670736 -379.356481) (xy 74.670731 -379.423791) (xy 74.662682 -379.490617)
			(xy 74.646703 -379.556002) (xy 74.623024 -379.619009) (xy 74.591984 -379.678734) (xy 74.554028 -379.73432)
			(xy 74.532236 -379.759972) (xy 74.526419 -379.767102) (xy 74.519918 -379.784304) (xy 74.519536 -379.7935)
			(xy 74.519536 -380.286768) (xy 74.519976 -380.295952) (xy 74.52647 -380.313136) (xy 74.532236 -380.320296)
			(xy 74.554044 -380.345932) (xy 74.591994 -380.40152) (xy 74.623028 -380.461246) (xy 74.6467 -380.524252)
			(xy 74.662673 -380.589637) (xy 74.670709 -380.656404) (xy 77.948754 -380.656404) (xy 77.956829 -380.589466)
			(xy 77.972863 -380.523978) (xy 77.996626 -380.460882) (xy 78.027776 -380.401086) (xy 78.065864 -380.345453)
			(xy 78.087728 -380.319788) (xy 78.093516 -380.312637) (xy 78.100035 -380.295451) (xy 78.100428 -380.28626)
			(xy 78.100428 -379.794008) (xy 78.100008 -379.784822) (xy 78.093501 -379.767638) (xy 78.087728 -379.76048)
			(xy 78.06591 -379.734776) (xy 78.027818 -379.679148) (xy 77.996664 -379.619357) (xy 77.972896 -379.556265)
			(xy 77.956856 -379.490781) (xy 77.948776 -379.423846) (xy 77.948772 -379.356426) (xy 77.956843 -379.28949)
			(xy 77.972874 -379.224004) (xy 77.996634 -379.160909) (xy 78.027781 -379.101114) (xy 78.065866 -379.045481)
			(xy 78.087728 -379.019816) (xy 78.093546 -379.012686) (xy 78.100047 -378.995484) (xy 78.100428 -378.986288)
			(xy 78.100428 -378.828554) (xy 78.100889 -378.818426) (xy 78.108629 -378.799706) (xy 78.122923 -378.785352)
			(xy 78.14161 -378.777532) (xy 78.151736 -378.776992) (xy 78.868016 -378.776992) (xy 78.878125 -378.777472)
			(xy 78.896802 -378.785213) (xy 78.911096 -378.799512) (xy 78.918831 -378.818191) (xy 78.919324 -378.8283)
			(xy 78.919324 -378.986288) (xy 78.919734 -378.995475) (xy 78.926247 -379.01266) (xy 78.932024 -379.019816)
			(xy 78.953934 -379.045443) (xy 78.99202 -379.101083) (xy 79.023167 -379.160885) (xy 79.046928 -379.223987)
			(xy 79.062959 -379.28948) (xy 79.071031 -379.356423) (xy 79.071026 -379.42385) (xy 79.062946 -379.490791)
			(xy 79.046906 -379.556282) (xy 79.023138 -379.619381) (xy 78.991983 -379.679179) (xy 78.95389 -379.734814)
			(xy 78.932024 -379.76048) (xy 78.926214 -379.767616) (xy 78.919706 -379.784813) (xy 78.919324 -379.794008)
			(xy 78.919324 -380.28626) (xy 78.919748 -380.295446) (xy 78.926251 -380.312631) (xy 78.932024 -380.319788)
			(xy 78.953907 -380.345437) (xy 78.991993 -380.401075) (xy 79.023142 -380.460873) (xy 79.046904 -380.523972)
			(xy 79.062937 -380.589463) (xy 79.071011 -380.656403) (xy 79.071011 -380.656464) (xy 82.349074 -380.656464)
			(xy 82.357116 -380.589643) (xy 82.373086 -380.524262) (xy 82.396755 -380.461258) (xy 82.427785 -380.401535)
			(xy 82.46573 -380.345948) (xy 82.487516 -380.320296) (xy 82.493299 -380.313141) (xy 82.499821 -380.295958)
			(xy 82.500216 -380.286768) (xy 82.500216 -379.7935) (xy 82.499803 -379.784313) (xy 82.493291 -379.767129)
			(xy 82.487516 -379.759972) (xy 82.465776 -379.734281) (xy 82.427828 -379.678699) (xy 82.396794 -379.618981)
			(xy 82.373119 -379.555982) (xy 82.357144 -379.490604) (xy 82.349096 -379.423786) (xy 82.349092 -379.356486)
			(xy 82.357131 -379.289667) (xy 82.373098 -379.224288) (xy 82.396764 -379.161285) (xy 82.427791 -379.101563)
			(xy 82.465732 -379.045977) (xy 82.487516 -379.020324) (xy 82.493329 -379.013191) (xy 82.499833 -378.995991)
			(xy 82.500216 -378.986796) (xy 82.500216 -378.828554) (xy 82.500695 -378.818396) (xy 82.508481 -378.79963)
			(xy 82.52285 -378.785267) (xy 82.54162 -378.777491) (xy 82.551778 -378.776992) (xy 83.268058 -378.776992)
			(xy 83.278207 -378.777567) (xy 83.296967 -378.785319) (xy 83.311332 -378.799659) (xy 83.319116 -378.818405)
			(xy 83.31962 -378.828554) (xy 83.31962 -378.986796) (xy 83.320028 -378.995984) (xy 83.326543 -379.013168)
			(xy 83.33232 -379.020324) (xy 83.354156 -379.045937) (xy 83.392107 -379.101528) (xy 83.42314 -379.161256)
			(xy 83.446812 -379.224266) (xy 83.462783 -379.289654) (xy 83.470824 -379.356481) (xy 83.470819 -379.423791)
			(xy 83.46277 -379.490618) (xy 83.446791 -379.556003) (xy 83.423111 -379.61901) (xy 83.392069 -379.678734)
			(xy 83.354112 -379.734321) (xy 83.33232 -379.759972) (xy 83.326513 -379.76711) (xy 83.320004 -379.784306)
			(xy 83.31962 -379.7935) (xy 83.31962 -380.286768) (xy 83.320041 -380.295954) (xy 83.326547 -380.313139)
			(xy 83.33232 -380.320296) (xy 83.354129 -380.345931) (xy 83.392079 -380.401519) (xy 83.423114 -380.461245)
			(xy 83.446788 -380.524252) (xy 83.46276 -380.589636) (xy 83.470797 -380.656404) (xy 86.748842 -380.656404)
			(xy 86.756916 -380.589467) (xy 86.77295 -380.523979) (xy 86.796713 -380.460883) (xy 86.827862 -380.401087)
			(xy 86.865949 -380.345453) (xy 86.887812 -380.319788) (xy 86.893598 -380.312635) (xy 86.900118 -380.29545)
			(xy 86.900512 -380.28626) (xy 86.900512 -379.794008) (xy 86.900095 -379.784822) (xy 86.893586 -379.767637)
			(xy 86.887812 -379.76048) (xy 86.865995 -379.734776) (xy 86.827904 -379.679147) (xy 86.79675 -379.619357)
			(xy 86.772983 -379.556265) (xy 86.756944 -379.49078) (xy 86.748864 -379.423846) (xy 86.74886 -379.356426)
			(xy 86.756931 -379.289491) (xy 86.772962 -379.224004) (xy 86.796721 -379.160909) (xy 86.827867 -379.101115)
			(xy 86.86595 -379.045481) (xy 86.887812 -379.019816) (xy 86.893628 -379.012685) (xy 86.900131 -378.995483)
			(xy 86.900512 -378.986288) (xy 86.900512 -378.828554) (xy 86.900988 -378.818428) (xy 86.908726 -378.799711)
			(xy 86.923015 -378.785357) (xy 86.941696 -378.777535) (xy 86.95182 -378.776992) (xy 87.6681 -378.776992)
			(xy 87.678208 -378.777485) (xy 87.696884 -378.785221) (xy 87.711179 -378.799516) (xy 87.718915 -378.818192)
			(xy 87.719408 -378.8283) (xy 87.719408 -378.986288) (xy 87.719822 -378.995475) (xy 87.726333 -379.012659)
			(xy 87.732108 -379.019816) (xy 87.754019 -379.045442) (xy 87.792106 -379.101083) (xy 87.823254 -379.160884)
			(xy 87.847015 -379.223986) (xy 87.863047 -379.28948) (xy 87.871119 -379.356422) (xy 87.871114 -379.42385)
			(xy 87.863034 -379.490791) (xy 87.846994 -379.556283) (xy 87.823224 -379.619382) (xy 87.792068 -379.679179)
			(xy 87.753975 -379.734815) (xy 87.732108 -379.76048) (xy 87.726296 -379.767614) (xy 87.71979 -379.784813)
			(xy 87.719408 -379.794008) (xy 87.719408 -380.28626) (xy 87.719836 -380.295445) (xy 87.726337 -380.31263)
			(xy 87.732108 -380.319788) (xy 87.753991 -380.345437) (xy 87.792079 -380.401074) (xy 87.823228 -380.460873)
			(xy 87.846991 -380.523972) (xy 87.863025 -380.589463) (xy 87.871099 -380.656402) (xy 87.871097 -380.723828)
			(xy 87.863019 -380.790767) (xy 87.846982 -380.856257) (xy 87.838954 -380.877572) (xy 105.0036 -380.877572)
			(xy 105.0036 -380.013972) (xy 105.00409 -379.983988) (xy 105.011918 -379.924532) (xy 105.027439 -379.866607)
			(xy 105.050388 -379.811203) (xy 105.080372 -379.759269) (xy 105.116878 -379.711693) (xy 105.159283 -379.669288)
			(xy 105.206859 -379.632782) (xy 105.258793 -379.602798) (xy 105.314197 -379.579849) (xy 105.372122 -379.564328)
			(xy 105.431578 -379.5565) (xy 105.491546 -379.5565) (xy 105.551002 -379.564328) (xy 105.608927 -379.579849)
			(xy 105.664331 -379.602798) (xy 105.716265 -379.632782) (xy 105.763841 -379.669288) (xy 105.806246 -379.711693)
			(xy 105.842752 -379.759269) (xy 105.872736 -379.811203) (xy 105.895685 -379.866607) (xy 105.911206 -379.924532)
			(xy 105.919034 -379.983988) (xy 105.919524 -380.013972) (xy 105.919524 -380.656403) (xy 117.548873 -380.656403)
			(xy 117.556947 -380.589466) (xy 117.572982 -380.523977) (xy 117.596746 -380.460881) (xy 117.627898 -380.401085)
			(xy 117.665987 -380.345452) (xy 117.687852 -380.319788) (xy 117.693643 -380.312639) (xy 117.700159 -380.295451)
			(xy 117.700552 -380.28626) (xy 117.700552 -379.794008) (xy 117.700126 -379.784823) (xy 117.693622 -379.767639)
			(xy 117.687852 -379.76048) (xy 117.666033 -379.734777) (xy 117.62794 -379.679149) (xy 117.596784 -379.619358)
			(xy 117.573015 -379.556266) (xy 117.556975 -379.490781) (xy 117.548894 -379.423846) (xy 117.54889 -379.356426)
			(xy 117.556962 -379.28949) (xy 117.572994 -379.224003) (xy 117.596755 -379.160908) (xy 117.627903 -379.101113)
			(xy 117.665989 -379.04548) (xy 117.687852 -379.019816) (xy 117.693673 -379.012688) (xy 117.700172 -378.995484)
			(xy 117.700552 -378.986288) (xy 117.700552 -378.828554) (xy 117.700989 -378.818423) (xy 117.708734 -378.799698)
			(xy 117.723036 -378.785343) (xy 117.741731 -378.777528) (xy 117.75186 -378.776992) (xy 118.46814 -378.776992)
			(xy 118.478296 -378.777389) (xy 118.497047 -378.785196) (xy 118.511369 -378.7996) (xy 118.519069 -378.818396)
			(xy 118.519448 -378.828554) (xy 118.519448 -378.986288) (xy 118.519875 -378.995473) (xy 118.526378 -379.012657)
			(xy 118.532148 -379.019816) (xy 118.554061 -379.045441) (xy 118.592152 -379.10108) (xy 118.623303 -379.160882)
			(xy 118.647067 -379.223984) (xy 118.663101 -379.289478) (xy 118.671174 -379.356422) (xy 118.671169 -379.42385)
			(xy 118.663088 -379.490793) (xy 118.647046 -379.556285) (xy 118.623274 -379.619384) (xy 118.592115 -379.679181)
			(xy 118.554017 -379.734816) (xy 118.532148 -379.76048) (xy 118.526329 -379.767609) (xy 118.519829 -379.784812)
			(xy 118.519448 -379.794008) (xy 118.519448 -380.28626) (xy 118.519889 -380.295444) (xy 118.526382 -380.312628)
			(xy 118.532148 -380.319788) (xy 118.554033 -380.345436) (xy 118.592125 -380.401072) (xy 118.623278 -380.46087)
			(xy 118.647043 -380.523969) (xy 118.663079 -380.589461) (xy 118.671154 -380.656402) (xy 118.671154 -380.656463)
			(xy 121.949193 -380.656463) (xy 121.957235 -380.589642) (xy 121.973206 -380.524261) (xy 121.996876 -380.461257)
			(xy 122.027907 -380.401534) (xy 122.065854 -380.345948) (xy 122.08764 -380.320296) (xy 122.093426 -380.313143)
			(xy 122.099946 -380.295958) (xy 122.10034 -380.286768) (xy 122.10034 -379.7935) (xy 122.099921 -379.784314)
			(xy 122.093413 -379.76713) (xy 122.08764 -379.759972) (xy 122.0659 -379.734281) (xy 122.027949 -379.6787)
			(xy 121.996914 -379.618982) (xy 121.973238 -379.555982) (xy 121.957262 -379.490605) (xy 121.949214 -379.423787)
			(xy 121.94921 -379.356485) (xy 121.957249 -379.289666) (xy 121.973217 -379.224287) (xy 121.996884 -379.161284)
			(xy 122.027912 -379.101562) (xy 122.065855 -379.045976) (xy 122.08764 -379.020324) (xy 122.093456 -379.013193)
			(xy 122.099958 -378.995991) (xy 122.10034 -378.986796) (xy 122.10034 -378.828554) (xy 122.100796 -378.818393)
			(xy 122.108586 -378.799623) (xy 122.122963 -378.785259) (xy 122.141741 -378.777486) (xy 122.151902 -378.776992)
			(xy 122.868182 -378.776992) (xy 122.878333 -378.777547) (xy 122.897093 -378.785307) (xy 122.911457 -378.799653)
			(xy 122.919241 -378.818404) (xy 122.919744 -378.828554) (xy 122.919744 -378.986796) (xy 122.920169 -378.995981)
			(xy 122.926674 -379.013165) (xy 122.932444 -379.020324) (xy 122.95428 -379.045937) (xy 122.992228 -379.101529)
			(xy 123.02326 -379.161257) (xy 123.046931 -379.224267) (xy 123.062901 -379.289654) (xy 123.070942 -379.356482)
			(xy 123.070937 -379.423791) (xy 123.062888 -379.490617) (xy 123.04691 -379.556002) (xy 123.023231 -379.619009)
			(xy 122.992191 -379.678733) (xy 122.954235 -379.73432) (xy 122.932444 -379.759972) (xy 122.926627 -379.767103)
			(xy 122.920126 -379.784305) (xy 122.919744 -379.7935) (xy 122.919744 -380.286768) (xy 122.920182 -380.295952)
			(xy 122.926678 -380.313136) (xy 122.932444 -380.320296) (xy 122.954252 -380.345932) (xy 122.992201 -380.40152)
			(xy 123.023235 -380.461246) (xy 123.046907 -380.524252) (xy 123.062879 -380.589637) (xy 123.070915 -380.656404)
			(xy 126.34896 -380.656404) (xy 126.357035 -380.589466) (xy 126.373069 -380.523978) (xy 126.396833 -380.460881)
			(xy 126.427983 -380.401086) (xy 126.466072 -380.345453) (xy 126.487936 -380.319788) (xy 126.493725 -380.312637)
			(xy 126.500243 -380.295451) (xy 126.500636 -380.28626) (xy 126.500636 -379.794008) (xy 126.500214 -379.784822)
			(xy 126.493708 -379.767638) (xy 126.487936 -379.76048) (xy 126.466118 -379.734776) (xy 126.428025 -379.679148)
			(xy 126.396871 -379.619358) (xy 126.373102 -379.556266) (xy 126.357062 -379.490781) (xy 126.348982 -379.423846)
			(xy 126.348978 -379.356426) (xy 126.357049 -379.28949) (xy 126.373081 -379.224003) (xy 126.396841 -379.160908)
			(xy 126.427988 -379.101114) (xy 126.466074 -379.045481) (xy 126.487936 -379.019816) (xy 126.493755 -379.012687)
			(xy 126.500256 -378.995484) (xy 126.500636 -378.986288) (xy 126.500636 -378.828554) (xy 126.501089 -378.818425)
			(xy 126.508831 -378.799703) (xy 126.523127 -378.785349) (xy 126.541817 -378.777531) (xy 126.551944 -378.776992)
			(xy 127.268224 -378.776992) (xy 127.278379 -378.777402) (xy 127.29713 -378.785204) (xy 127.311452 -378.799604)
			(xy 127.319153 -378.818397) (xy 127.319532 -378.828554) (xy 127.319532 -378.986288) (xy 127.319963 -378.995473)
			(xy 127.326464 -379.012656) (xy 127.332232 -379.019816) (xy 127.354142 -379.045443) (xy 127.392227 -379.101084)
			(xy 127.423374 -379.160885) (xy 127.447134 -379.223987) (xy 127.463165 -379.289481) (xy 127.471237 -379.356423)
			(xy 127.471232 -379.423849) (xy 127.463152 -379.49079) (xy 127.447113 -379.556282) (xy 127.423345 -379.61938)
			(xy 127.39219 -379.679178) (xy 127.354098 -379.734814) (xy 127.332232 -379.76048) (xy 127.326411 -379.767607)
			(xy 127.319913 -379.784812) (xy 127.319532 -379.794008) (xy 127.319532 -380.28626) (xy 127.319977 -380.295443)
			(xy 127.326468 -380.312627) (xy 127.332232 -380.319788) (xy 127.354114 -380.345438) (xy 127.392201 -380.401075)
			(xy 127.423349 -380.460874) (xy 127.44711 -380.523973) (xy 127.463143 -380.589463) (xy 127.471217 -380.656403)
			(xy 127.471217 -380.656463) (xy 130.74928 -380.656463) (xy 130.757322 -380.589642) (xy 130.773292 -380.524262)
			(xy 130.796962 -380.461258) (xy 130.827992 -380.401535) (xy 130.865938 -380.345948) (xy 130.887724 -380.320296)
			(xy 130.893508 -380.313142) (xy 130.900029 -380.295958) (xy 130.900424 -380.286768) (xy 130.900424 -379.7935)
			(xy 130.900009 -379.784313) (xy 130.893498 -379.767129) (xy 130.887724 -379.759972) (xy 130.865984 -379.734281)
			(xy 130.828035 -379.678699) (xy 130.797 -379.618981) (xy 130.773326 -379.555982) (xy 130.75735 -379.490605)
			(xy 130.749302 -379.423787) (xy 130.749298 -379.356486) (xy 130.757337 -379.289667) (xy 130.773304 -379.224287)
			(xy 130.796971 -379.161285) (xy 130.827998 -379.101563) (xy 130.86594 -379.045977) (xy 130.887724 -379.020324)
			(xy 130.893538 -379.013191) (xy 130.900042 -378.995991) (xy 130.900424 -378.986796) (xy 130.900424 -378.828554)
			(xy 130.900895 -378.818395) (xy 130.908682 -378.799628) (xy 130.923054 -378.785264) (xy 130.941827 -378.777489)
			(xy 130.951986 -378.776992) (xy 131.668266 -378.776992) (xy 131.678416 -378.77756) (xy 131.697175 -378.785315)
			(xy 131.71154 -378.799657) (xy 131.719324 -378.818405) (xy 131.719828 -378.828554) (xy 131.719828 -378.986796)
			(xy 131.720234 -378.995984) (xy 131.72675 -379.013168) (xy 131.732528 -379.020324) (xy 131.754364 -379.045937)
			(xy 131.792314 -379.101528) (xy 131.823347 -379.161257) (xy 131.847018 -379.224267) (xy 131.862989 -379.289654)
			(xy 131.87103 -379.356481) (xy 131.871025 -379.423791) (xy 131.862976 -379.490617) (xy 131.846997 -379.556003)
			(xy 131.823317 -379.619009) (xy 131.792277 -379.678734) (xy 131.75432 -379.73432) (xy 131.732528 -379.759972)
			(xy 131.72671 -379.767101) (xy 131.72021 -379.784304) (xy 131.719828 -379.7935) (xy 131.719828 -380.286768)
			(xy 131.720247 -380.295954) (xy 131.726754 -380.313139) (xy 131.732528 -380.320296) (xy 131.754336 -380.345932)
			(xy 131.792287 -380.40152) (xy 131.823321 -380.461245) (xy 131.846994 -380.524252) (xy 131.862967 -380.589636)
			(xy 131.871003 -380.656404) (xy 161.548806 -380.656404) (xy 161.55688 -380.589468) (xy 161.572912 -380.523981)
			(xy 161.596672 -380.460885) (xy 161.627819 -380.401089) (xy 161.665902 -380.345454) (xy 161.687764 -380.319788)
			(xy 161.693556 -380.31264) (xy 161.700072 -380.295451) (xy 161.700464 -380.28626) (xy 161.700464 -379.794008)
			(xy 161.700036 -379.784823) (xy 161.693533 -379.767639) (xy 161.687764 -379.76048) (xy 161.665948 -379.734775)
			(xy 161.627861 -379.679146) (xy 161.59671 -379.619354) (xy 161.572945 -379.556263) (xy 161.556907 -379.490779)
			(xy 161.548828 -379.423846) (xy 161.548823 -379.356426) (xy 161.556894 -379.289492) (xy 161.572923 -379.224006)
			(xy 161.59668 -379.160911) (xy 161.627824 -379.101116) (xy 161.665904 -379.045482) (xy 161.687764 -379.019816)
			(xy 161.693587 -379.01269) (xy 161.700084 -378.995484) (xy 161.700464 -378.986288) (xy 161.700464 -378.828554)
			(xy 161.70089 -378.818421) (xy 161.708637 -378.799695) (xy 161.722942 -378.785339) (xy 161.741641 -378.777526)
			(xy 161.751772 -378.776992) (xy 162.468052 -378.776992) (xy 162.47817 -378.777455) (xy 162.496871 -378.785186)
			(xy 162.511187 -378.799488) (xy 162.518935 -378.818182) (xy 162.51936 -378.8283) (xy 162.51936 -378.986288)
			(xy 162.519785 -378.995473) (xy 162.526289 -379.012658) (xy 162.53206 -379.019816) (xy 162.553973 -379.045442)
			(xy 162.592062 -379.101081) (xy 162.623213 -379.160882) (xy 162.646977 -379.223984) (xy 162.66301 -379.289479)
			(xy 162.671083 -379.356422) (xy 162.671078 -379.42385) (xy 162.662997 -379.490792) (xy 162.646955 -379.556285)
			(xy 162.623184 -379.619384) (xy 162.592025 -379.679181) (xy 162.553928 -379.734815) (xy 162.53206 -379.76048)
			(xy 162.526242 -379.76761) (xy 162.519741 -379.784812) (xy 162.51936 -379.794008) (xy 162.51936 -380.28626)
			(xy 162.519799 -380.295444) (xy 162.526294 -380.312628) (xy 162.53206 -380.319788) (xy 162.553945 -380.345436)
			(xy 162.592036 -380.401072) (xy 162.623188 -380.460871) (xy 162.646953 -380.52397) (xy 162.662988 -380.589461)
			(xy 162.671063 -380.656402) (xy 162.671063 -380.656463) (xy 165.949102 -380.656463) (xy 165.957144 -380.589642)
			(xy 165.973115 -380.524261) (xy 165.996786 -380.461257) (xy 166.027818 -380.401534) (xy 166.065765 -380.345948)
			(xy 166.087552 -380.320296) (xy 166.093339 -380.313144) (xy 166.099858 -380.295959) (xy 166.100252 -380.286768)
			(xy 166.100252 -379.7935) (xy 166.09983 -379.784314) (xy 166.093323 -379.76713) (xy 166.087552 -379.759972)
			(xy 166.065811 -379.734281) (xy 166.02786 -379.678701) (xy 165.996824 -379.618982) (xy 165.973148 -379.555983)
			(xy 165.957171 -379.490605) (xy 165.949123 -379.423787) (xy 165.949119 -379.356485) (xy 165.957158 -379.289666)
			(xy 165.973127 -379.224286) (xy 165.996795 -379.161284) (xy 166.027823 -379.101562) (xy 166.065767 -379.045976)
			(xy 166.087552 -379.020324) (xy 166.09337 -379.013194) (xy 166.09987 -378.995992) (xy 166.100252 -378.986796)
			(xy 166.100252 -378.828554) (xy 166.100696 -378.818392) (xy 166.108488 -378.799619) (xy 166.122869 -378.785255)
			(xy 166.141651 -378.777484) (xy 166.151814 -378.776992) (xy 166.868094 -378.776992) (xy 166.878246 -378.777537)
			(xy 166.897006 -378.785301) (xy 166.91137 -378.79965) (xy 166.919153 -378.818403) (xy 166.919656 -378.828554)
			(xy 166.919656 -378.986796) (xy 166.920078 -378.995982) (xy 166.926584 -379.013166) (xy 166.932356 -379.020324)
			(xy 166.954191 -379.045937) (xy 166.992139 -379.101529) (xy 167.02317 -379.161258) (xy 167.046841 -379.224268)
			(xy 167.06281 -379.289655) (xy 167.070851 -379.356482) (xy 167.070847 -379.423791) (xy 167.062798 -379.490617)
			(xy 167.046819 -379.556001) (xy 167.023141 -379.619008) (xy 166.992102 -379.678733) (xy 166.954147 -379.73432)
			(xy 166.932356 -379.759972) (xy 166.926541 -379.767104) (xy 166.920038 -379.784305) (xy 166.919656 -379.7935)
			(xy 166.919656 -380.286768) (xy 166.920091 -380.295952) (xy 166.926588 -380.313137) (xy 166.932356 -380.320296)
			(xy 166.954164 -380.345932) (xy 166.992112 -380.40152) (xy 167.023145 -380.461246) (xy 167.046817 -380.524253)
			(xy 167.062789 -380.589637) (xy 167.070824 -380.656403) (xy 170.34887 -380.656403) (xy 170.356944 -380.589466)
			(xy 170.372979 -380.523977) (xy 170.396743 -380.460881) (xy 170.427894 -380.401086) (xy 170.465984 -380.345452)
			(xy 170.487848 -380.319788) (xy 170.493638 -380.312638) (xy 170.500155 -380.295451) (xy 170.500548 -380.28626)
			(xy 170.500548 -379.794008) (xy 170.500123 -379.784823) (xy 170.493619 -379.767639) (xy 170.487848 -379.76048)
			(xy 170.46603 -379.734777) (xy 170.427936 -379.679149) (xy 170.396781 -379.619358) (xy 170.373012 -379.556266)
			(xy 170.356971 -379.490781) (xy 170.348891 -379.423846) (xy 170.348887 -379.356426) (xy 170.356959 -379.28949)
			(xy 170.37299 -379.224003) (xy 170.396751 -379.160908) (xy 170.427899 -379.101113) (xy 170.465985 -379.04548)
			(xy 170.487848 -379.019816) (xy 170.493669 -379.012688) (xy 170.500168 -378.995484) (xy 170.500548 -378.986288)
			(xy 170.500548 -378.828554) (xy 170.500989 -378.818423) (xy 170.508734 -378.7997) (xy 170.523034 -378.785345)
			(xy 170.541727 -378.777529) (xy 170.551856 -378.776992) (xy 171.268136 -378.776992) (xy 171.278291 -378.777392)
			(xy 171.297043 -378.785198) (xy 171.311365 -378.799601) (xy 171.319065 -378.818396) (xy 171.319444 -378.828554)
			(xy 171.319444 -378.986288) (xy 171.319872 -378.995473) (xy 171.326375 -379.012657) (xy 171.332144 -379.019816)
			(xy 171.354057 -379.045441) (xy 171.392148 -379.10108) (xy 171.4233 -379.160881) (xy 171.447064 -379.223984)
			(xy 171.463098 -379.289478) (xy 171.47117 -379.356422) (xy 171.471166 -379.42385) (xy 171.463085 -379.490793)
			(xy 171.447042 -379.556285) (xy 171.42327 -379.619384) (xy 171.392111 -379.679182) (xy 171.354013 -379.734816)
			(xy 171.332144 -379.76048) (xy 171.326324 -379.767608) (xy 171.319825 -379.784812) (xy 171.319444 -379.794008)
			(xy 171.319444 -380.28626) (xy 171.319886 -380.295444) (xy 171.326379 -380.312628) (xy 171.332144 -380.319788)
			(xy 171.35403 -380.345436) (xy 171.392121 -380.401072) (xy 171.423274 -380.46087) (xy 171.44704 -380.523969)
			(xy 171.463076 -380.589461) (xy 171.471151 -380.656402) (xy 171.471151 -380.656463) (xy 174.74919 -380.656463)
			(xy 174.757232 -380.589642) (xy 174.773202 -380.524261) (xy 174.796873 -380.461258) (xy 174.827904 -380.401535)
			(xy 174.86585 -380.345948) (xy 174.887636 -380.320296) (xy 174.893421 -380.313143) (xy 174.899942 -380.295958)
			(xy 174.900336 -380.286768) (xy 174.900336 -379.7935) (xy 174.899918 -379.784314) (xy 174.893409 -379.76713)
			(xy 174.887636 -379.759972) (xy 174.865896 -379.734281) (xy 174.827946 -379.6787) (xy 174.796911 -379.618982)
			(xy 174.773235 -379.555982) (xy 174.757259 -379.490605) (xy 174.749211 -379.423787) (xy 174.749207 -379.356486)
			(xy 174.757246 -379.289666) (xy 174.773214 -379.224287) (xy 174.796881 -379.161284) (xy 174.827909 -379.101562)
			(xy 174.865851 -379.045976) (xy 174.887636 -379.020324) (xy 174.893452 -379.013193) (xy 174.899954 -378.995991)
			(xy 174.900336 -378.986796) (xy 174.900336 -378.828554) (xy 174.900796 -378.818394) (xy 174.908585 -378.799624)
			(xy 174.922961 -378.78526) (xy 174.941737 -378.777487) (xy 174.951898 -378.776992) (xy 175.668178 -378.776992)
			(xy 175.678329 -378.77755) (xy 175.697089 -378.785309) (xy 175.711453 -378.799654) (xy 175.719237 -378.818404)
			(xy 175.71974 -378.828554) (xy 175.71974 -378.986796) (xy 175.720166 -378.995981) (xy 175.72667 -379.013165)
			(xy 175.73244 -379.020324) (xy 175.754276 -379.045937) (xy 175.792225 -379.101529) (xy 175.823257 -379.161257)
			(xy 175.846928 -379.224267) (xy 175.862898 -379.289654) (xy 175.870939 -379.356481) (xy 175.870934 -379.423791)
			(xy 175.862885 -379.490617) (xy 175.846907 -379.556002) (xy 175.823227 -379.619009) (xy 175.792187 -379.678734)
			(xy 175.754231 -379.73432) (xy 175.73244 -379.759972) (xy 175.726623 -379.767102) (xy 175.720122 -379.784305)
			(xy 175.71974 -379.7935) (xy 175.71974 -380.286768) (xy 175.720179 -380.295952) (xy 175.726674 -380.313136)
			(xy 175.73244 -380.320296) (xy 175.754248 -380.345932) (xy 175.792198 -380.40152) (xy 175.823231 -380.461246)
			(xy 175.846904 -380.524252) (xy 175.862876 -380.589637) (xy 175.870919 -380.656462) (xy 175.870917 -380.723769)
			(xy 175.862871 -380.790593) (xy 175.846895 -380.855977) (xy 175.823219 -380.918982) (xy 175.792182 -380.978706)
			(xy 175.75423 -381.034292) (xy 175.73244 -381.059944) (xy 175.726635 -381.067083) (xy 175.720127 -381.084278)
			(xy 175.71974 -381.093472) (xy 175.71974 -381.251206) (xy 175.71934 -381.261381) (xy 175.711549 -381.28018)
			(xy 175.697156 -381.294565) (xy 175.678353 -381.302346) (xy 175.668178 -381.302768) (xy 174.951898 -381.302768)
			(xy 174.941741 -381.302268) (xy 174.922973 -381.294494) (xy 174.908608 -381.280131) (xy 174.900832 -381.261363)
			(xy 174.900336 -381.251206) (xy 174.900336 -381.093472) (xy 174.899931 -381.084284) (xy 174.893413 -381.067101)
			(xy 174.887636 -381.059944) (xy 174.865868 -381.034275) (xy 174.827919 -380.978691) (xy 174.796885 -380.91897)
			(xy 174.773211 -380.855968) (xy 174.757237 -380.790587) (xy 174.749191 -380.723767) (xy 174.74919 -380.656463)
			(xy 171.471151 -380.656463) (xy 171.471149 -380.723828) (xy 171.46307 -380.790769) (xy 171.447031 -380.85626)
			(xy 171.423262 -380.919358) (xy 171.392106 -380.979154) (xy 171.354011 -381.034788) (xy 171.332144 -381.060452)
			(xy 171.326336 -381.067589) (xy 171.31983 -381.084786) (xy 171.319444 -381.09398) (xy 171.319444 -381.251206)
			(xy 171.318978 -381.261335) (xy 171.311245 -381.280059) (xy 171.296952 -381.294416) (xy 171.278263 -381.302232)
			(xy 171.268136 -381.302768) (xy 170.551856 -381.302768) (xy 170.541695 -381.302414) (xy 170.522936 -381.294598)
			(xy 170.508613 -381.28018) (xy 170.50092 -381.26137) (xy 170.500548 -381.251206) (xy 170.500548 -381.09398)
			(xy 170.500137 -381.084793) (xy 170.493623 -381.067609) (xy 170.487848 -381.060452) (xy 170.466002 -381.034771)
			(xy 170.42791 -380.97914) (xy 170.396755 -380.919347) (xy 170.372988 -380.856252) (xy 170.35695 -380.790764)
			(xy 170.348871 -380.723827) (xy 170.34887 -380.656403) (xy 167.070824 -380.656403) (xy 167.070831 -380.656462)
			(xy 167.070829 -380.723768) (xy 167.062783 -380.790592) (xy 167.046808 -380.855976) (xy 167.023133 -380.918981)
			(xy 166.992097 -380.978705) (xy 166.954145 -381.034292) (xy 166.932356 -381.059944) (xy 166.926553 -381.067084)
			(xy 166.920043 -381.084279) (xy 166.919656 -381.093472) (xy 166.919656 -381.251206) (xy 166.919171 -381.261365)
			(xy 166.911394 -381.280135) (xy 166.897025 -381.2945) (xy 166.878253 -381.302274) (xy 166.868094 -381.302768)
			(xy 166.151814 -381.302768) (xy 166.141644 -381.302325) (xy 166.122851 -381.294546) (xy 166.108466 -381.280166)
			(xy 166.100679 -381.261376) (xy 166.100252 -381.251206) (xy 166.100252 -381.093472) (xy 166.099844 -381.084285)
			(xy 166.093327 -381.067101) (xy 166.087552 -381.059944) (xy 166.065784 -381.034276) (xy 166.027833 -380.978692)
			(xy 165.996799 -380.918971) (xy 165.973124 -380.855968) (xy 165.957149 -380.790588) (xy 165.949103 -380.723767)
			(xy 165.949102 -380.656463) (xy 162.671063 -380.656463) (xy 162.671061 -380.723828) (xy 162.662983 -380.790768)
			(xy 162.646944 -380.856259) (xy 162.623176 -380.919357) (xy 162.59202 -380.979153) (xy 162.553927 -381.034787)
			(xy 162.53206 -381.060452) (xy 162.526254 -381.06759) (xy 162.519746 -381.084786) (xy 162.51936 -381.09398)
			(xy 162.51936 -381.251206) (xy 162.518878 -381.261333) (xy 162.511148 -381.280054) (xy 162.496861 -381.29441)
			(xy 162.478177 -381.302229) (xy 162.468052 -381.302768) (xy 161.751772 -381.302768) (xy 161.741644 -381.302406)
			(xy 161.722933 -381.294643) (xy 161.708619 -381.28031) (xy 161.70088 -381.261589) (xy 161.700464 -381.25146)
			(xy 161.700464 -381.09398) (xy 161.700049 -381.084794) (xy 161.693537 -381.06761) (xy 161.687764 -381.060452)
			(xy 161.665921 -381.03477) (xy 161.627834 -380.979137) (xy 161.596684 -380.919343) (xy 161.572921 -380.856248)
			(xy 161.556885 -380.790762) (xy 161.548808 -380.723826) (xy 161.548806 -380.656404) (xy 131.871003 -380.656404)
			(xy 131.87101 -380.656461) (xy 131.871008 -380.723769) (xy 131.862961 -380.790593) (xy 131.846985 -380.855977)
			(xy 131.823309 -380.918982) (xy 131.792271 -380.978706) (xy 131.754318 -381.034292) (xy 131.732528 -381.059944)
			(xy 131.726722 -381.067082) (xy 131.720215 -381.084278) (xy 131.719828 -381.093472) (xy 131.719828 -381.251206)
			(xy 131.71944 -381.261382) (xy 131.711647 -381.280184) (xy 131.69725 -381.294569) (xy 131.678443 -381.302348)
			(xy 131.668266 -381.302768) (xy 130.951986 -381.302768) (xy 130.941828 -381.302278) (xy 130.92306 -381.2945)
			(xy 130.908695 -381.280133) (xy 130.90092 -381.261364) (xy 130.900424 -381.251206) (xy 130.900424 -381.093472)
			(xy 130.900022 -381.084284) (xy 130.893502 -381.0671) (xy 130.887724 -381.059944) (xy 130.865956 -381.034276)
			(xy 130.828008 -380.978691) (xy 130.796975 -380.91897) (xy 130.773301 -380.855967) (xy 130.757327 -380.790587)
			(xy 130.749282 -380.723767) (xy 130.74928 -380.656463) (xy 127.471217 -380.656463) (xy 127.471215 -380.723827)
			(xy 127.463138 -380.790766) (xy 127.447101 -380.856256) (xy 127.423336 -380.919354) (xy 127.392185 -380.979151)
			(xy 127.354096 -381.034786) (xy 127.332232 -381.060452) (xy 127.326423 -381.067588) (xy 127.319918 -381.084786)
			(xy 127.319532 -381.09398) (xy 127.319532 -381.251206) (xy 127.319077 -381.261337) (xy 127.311342 -381.280063)
			(xy 127.297046 -381.29442) (xy 127.278352 -381.302234) (xy 127.268224 -381.302768) (xy 126.551944 -381.302768)
			(xy 126.541789 -381.302342) (xy 126.523031 -381.294555) (xy 126.508705 -381.280159) (xy 126.50101 -381.261363)
			(xy 126.500636 -381.251206) (xy 126.500636 -381.09398) (xy 126.500227 -381.084793) (xy 126.493712 -381.067609)
			(xy 126.487936 -381.060452) (xy 126.46609 -381.034771) (xy 126.427999 -380.97914) (xy 126.396845 -380.919346)
			(xy 126.373078 -380.856251) (xy 126.35704 -380.790764) (xy 126.348962 -380.723826) (xy 126.34896 -380.656404)
			(xy 123.070915 -380.656404) (xy 123.070922 -380.656462) (xy 123.07092 -380.723769) (xy 123.062874 -380.790593)
			(xy 123.046898 -380.855976) (xy 123.023223 -380.918982) (xy 122.992186 -380.978706) (xy 122.954234 -381.034292)
			(xy 122.932444 -381.059944) (xy 122.926639 -381.067083) (xy 122.920131 -381.084279) (xy 122.919744 -381.093472)
			(xy 122.919744 -381.251206) (xy 122.919341 -381.26138) (xy 122.91155 -381.280178) (xy 122.897158 -381.294564)
			(xy 122.878356 -381.302345) (xy 122.868182 -381.302768) (xy 122.151902 -381.302768) (xy 122.141745 -381.302265)
			(xy 122.122977 -381.294492) (xy 122.108612 -381.28013) (xy 122.100836 -381.261363) (xy 122.10034 -381.251206)
			(xy 122.10034 -381.093472) (xy 122.099934 -381.084285) (xy 122.093417 -381.067101) (xy 122.08764 -381.059944)
			(xy 122.065872 -381.034276) (xy 122.027923 -380.978691) (xy 121.996888 -380.91897) (xy 121.973215 -380.855968)
			(xy 121.95724 -380.790588) (xy 121.949194 -380.723767) (xy 121.949193 -380.656463) (xy 118.671154 -380.656463)
			(xy 118.671152 -380.723828) (xy 118.663073 -380.790769) (xy 118.647034 -380.85626) (xy 118.623265 -380.919357)
			(xy 118.592109 -380.979154) (xy 118.554015 -381.034788) (xy 118.532148 -381.060452) (xy 118.52634 -381.067589)
			(xy 118.519834 -381.084786) (xy 118.519448 -381.09398) (xy 118.519448 -381.251206) (xy 118.518978 -381.261335)
			(xy 118.511246 -381.280058) (xy 118.496954 -381.294415) (xy 118.478266 -381.302231) (xy 118.46814 -381.302768)
			(xy 117.75186 -381.302768) (xy 117.741699 -381.30241) (xy 117.72294 -381.294596) (xy 117.708617 -381.280179)
			(xy 117.700924 -381.261369) (xy 117.700552 -381.251206) (xy 117.700552 -381.09398) (xy 117.70014 -381.084793)
			(xy 117.693626 -381.06761) (xy 117.687852 -381.060452) (xy 117.666006 -381.034771) (xy 117.627913 -380.97914)
			(xy 117.596759 -380.919347) (xy 117.572991 -380.856252) (xy 117.556953 -380.790764) (xy 117.548874 -380.723827)
			(xy 117.548873 -380.656403) (xy 105.919524 -380.656403) (xy 105.919524 -380.877572) (xy 105.919034 -380.907556)
			(xy 105.911206 -380.967012) (xy 105.895685 -381.024937) (xy 105.872736 -381.080341) (xy 105.842752 -381.132275)
			(xy 105.806246 -381.179851) (xy 105.763841 -381.222256) (xy 105.716265 -381.258762) (xy 105.664331 -381.288746)
			(xy 105.608927 -381.311695) (xy 105.551002 -381.327216) (xy 105.491546 -381.335044) (xy 105.431578 -381.335044)
			(xy 105.372122 -381.327216) (xy 105.314197 -381.311695) (xy 105.258793 -381.288746) (xy 105.206859 -381.258762)
			(xy 105.159283 -381.222256) (xy 105.116878 -381.179851) (xy 105.080372 -381.132275) (xy 105.050388 -381.080341)
			(xy 105.027439 -381.024937) (xy 105.011918 -380.967012) (xy 105.00409 -380.907556) (xy 105.0036 -380.877572)
			(xy 87.838954 -380.877572) (xy 87.823216 -380.919355) (xy 87.792063 -380.979152) (xy 87.753973 -381.034787)
			(xy 87.732108 -381.060452) (xy 87.726308 -381.067595) (xy 87.719795 -381.084787) (xy 87.719408 -381.09398)
			(xy 87.719408 -381.251206) (xy 87.71888 -381.261327) (xy 87.711159 -381.280039) (xy 87.696886 -381.294394)
			(xy 87.678218 -381.302221) (xy 87.6681 -381.302768) (xy 86.95182 -381.302768) (xy 86.941695 -381.302367)
			(xy 86.922985 -381.294619) (xy 86.908669 -381.280298) (xy 86.900929 -381.261585) (xy 86.900512 -381.25146)
			(xy 86.900512 -381.09398) (xy 86.900109 -381.084792) (xy 86.89359 -381.067608) (xy 86.887812 -381.060452)
			(xy 86.865967 -381.034771) (xy 86.827877 -380.979139) (xy 86.796725 -380.919345) (xy 86.772959 -380.85625)
			(xy 86.756922 -380.790763) (xy 86.748844 -380.723826) (xy 86.748842 -380.656404) (xy 83.470797 -380.656404)
			(xy 83.470804 -380.656461) (xy 83.470802 -380.723769) (xy 83.462755 -380.790593) (xy 83.446779 -380.855977)
			(xy 83.423102 -380.918983) (xy 83.392064 -380.978706) (xy 83.35411 -381.034292) (xy 83.33232 -381.059944)
			(xy 83.326525 -381.06709) (xy 83.320009 -381.08428) (xy 83.31962 -381.093472) (xy 83.31962 -381.251206)
			(xy 83.31924 -381.261383) (xy 83.311445 -381.280186) (xy 83.297046 -381.294572) (xy 83.278236 -381.302349)
			(xy 83.268058 -381.302768) (xy 82.551778 -381.302768) (xy 82.54162 -381.302285) (xy 82.522851 -381.294504)
			(xy 82.508487 -381.280136) (xy 82.500712 -381.261365) (xy 82.500216 -381.251206) (xy 82.500216 -381.093472)
			(xy 82.499816 -381.084284) (xy 82.493295 -381.0671) (xy 82.487516 -381.059944) (xy 82.465749 -381.034275)
			(xy 82.427801 -380.978691) (xy 82.396768 -380.918969) (xy 82.373095 -380.855967) (xy 82.357121 -380.790587)
			(xy 82.349076 -380.723767) (xy 82.349074 -380.656464) (xy 79.071011 -380.656464) (xy 79.071009 -380.723827)
			(xy 79.062932 -380.790767) (xy 79.046895 -380.856256) (xy 79.02313 -380.919354) (xy 78.991978 -380.979151)
			(xy 78.953888 -381.034786) (xy 78.932024 -381.060452) (xy 78.926226 -381.067596) (xy 78.919711 -381.084787)
			(xy 78.919324 -381.09398) (xy 78.919324 -381.251206) (xy 78.918877 -381.261337) (xy 78.911141 -381.280066)
			(xy 78.896842 -381.294423) (xy 78.878145 -381.302235) (xy 78.868016 -381.302768) (xy 78.151736 -381.302768)
			(xy 78.141612 -381.302354) (xy 78.122903 -381.294611) (xy 78.108586 -381.280294) (xy 78.100846 -381.261584)
			(xy 78.100428 -381.25146) (xy 78.100428 -381.09398) (xy 78.100021 -381.084793) (xy 78.093505 -381.067609)
			(xy 78.087728 -381.060452) (xy 78.065883 -381.034771) (xy 78.027792 -380.979139) (xy 77.996638 -380.919346)
			(xy 77.972872 -380.856251) (xy 77.956834 -380.790763) (xy 77.948756 -380.723826) (xy 77.948754 -380.656404)
			(xy 74.670709 -380.656404) (xy 74.670716 -380.656462) (xy 74.670714 -380.723769) (xy 74.662667 -380.790593)
			(xy 74.646691 -380.855977) (xy 74.623015 -380.918982) (xy 74.591978 -380.978706) (xy 74.554026 -381.034292)
			(xy 74.532236 -381.059944) (xy 74.52643 -381.067082) (xy 74.519923 -381.084278) (xy 74.519536 -381.093472)
			(xy 74.519536 -381.251206) (xy 74.51914 -381.261381) (xy 74.511349 -381.280181) (xy 74.496954 -381.294567)
			(xy 74.478149 -381.302347) (xy 74.467974 -381.302768) (xy 73.751694 -381.302768) (xy 73.741537 -381.302272)
			(xy 73.722769 -381.294496) (xy 73.708404 -381.280131) (xy 73.700628 -381.261363) (xy 73.700132 -381.251206)
			(xy 73.700132 -381.093472) (xy 73.699728 -381.084284) (xy 73.693209 -381.0671) (xy 73.687432 -381.059944)
			(xy 73.665664 -381.034275) (xy 73.627715 -380.978691) (xy 73.596682 -380.91897) (xy 73.573008 -380.855967)
			(xy 73.557034 -380.790587) (xy 73.548988 -380.723767) (xy 73.548987 -380.656463) (xy 43.87119 -380.656463)
			(xy 43.871188 -380.723828) (xy 43.86311 -380.790767) (xy 43.847073 -380.856258) (xy 43.823306 -380.919355)
			(xy 43.792153 -380.979152) (xy 43.754061 -381.034787) (xy 43.732196 -381.060452) (xy 43.726394 -381.067594)
			(xy 43.719883 -381.084787) (xy 43.719496 -381.09398) (xy 43.719496 -381.251206) (xy 43.718979 -381.261329)
			(xy 43.711256 -381.280043) (xy 43.69698 -381.294398) (xy 43.678308 -381.302223) (xy 43.668188 -381.302768)
			(xy 42.951908 -381.302768) (xy 42.94175 -381.302371) (xy 42.922992 -381.294572) (xy 42.908667 -381.280167)
			(xy 42.900973 -381.261366) (xy 42.9006 -381.251206) (xy 42.9006 -381.09398) (xy 42.9002 -381.084792)
			(xy 42.893679 -381.067607) (xy 42.8879 -381.060452) (xy 42.866056 -381.034771) (xy 42.827966 -380.979138)
			(xy 42.796815 -380.919344) (xy 42.773049 -380.85625) (xy 42.757013 -380.790763) (xy 42.748935 -380.723826)
			(xy 42.748933 -380.656404) (xy 39.470887 -380.656404) (xy 39.470894 -380.656461) (xy 39.470893 -380.723769)
			(xy 39.462846 -380.790594) (xy 39.446869 -380.855978) (xy 39.423192 -380.918983) (xy 39.392153 -380.978707)
			(xy 39.354199 -381.034293) (xy 39.332408 -381.059944) (xy 39.326611 -381.067089) (xy 39.320096 -381.08428)
			(xy 39.319708 -381.093472) (xy 39.319708 -381.251206) (xy 39.319173 -381.261358) (xy 39.311405 -381.280119)
			(xy 39.297052 -381.294482) (xy 39.278298 -381.302265) (xy 39.268146 -381.302768) (xy 38.551866 -381.302768)
			(xy 38.541707 -381.302295) (xy 38.522938 -381.29451) (xy 38.508574 -381.280138) (xy 38.5008 -381.261365)
			(xy 38.500304 -381.251206) (xy 38.500304 -381.093472) (xy 38.499907 -381.084283) (xy 38.493384 -381.067099)
			(xy 38.487604 -381.059944) (xy 38.465837 -381.034275) (xy 38.42789 -380.97869) (xy 38.396858 -380.918969)
			(xy 38.373185 -380.855966) (xy 38.357212 -380.790587) (xy 38.349167 -380.723766) (xy 38.349165 -380.656464)
			(xy 35.071102 -380.656464) (xy 35.0711 -380.723828) (xy 35.063023 -380.790767) (xy 35.046985 -380.856257)
			(xy 35.023219 -380.919355) (xy 34.992067 -380.979151) (xy 34.953977 -381.034787) (xy 34.932112 -381.060452)
			(xy 34.926312 -381.067595) (xy 34.919799 -381.084787) (xy 34.919412 -381.09398) (xy 34.919412 -381.251206)
			(xy 34.91888 -381.261327) (xy 34.91116 -381.280038) (xy 34.896888 -381.294392) (xy 34.878222 -381.30222)
			(xy 34.868104 -381.302768) (xy 34.151824 -381.302768) (xy 34.141667 -381.302358) (xy 34.122909 -381.294565)
			(xy 34.108584 -381.280164) (xy 34.100889 -381.261365) (xy 34.100516 -381.251206) (xy 34.100516 -381.09398)
			(xy 34.100112 -381.084792) (xy 34.093594 -381.067608) (xy 34.087816 -381.060452) (xy 34.065971 -381.034771)
			(xy 34.027881 -380.979139) (xy 33.996728 -380.919345) (xy 33.972962 -380.85625) (xy 33.956925 -380.790763)
			(xy 33.948847 -380.723826) (xy 33.948845 -380.656404) (xy 30.6708 -380.656404) (xy 30.670807 -380.656461)
			(xy 30.670805 -380.723769) (xy 30.662758 -380.790593) (xy 30.646782 -380.855977) (xy 30.623105 -380.918982)
			(xy 30.592068 -380.978706) (xy 30.554114 -381.034292) (xy 30.532324 -381.059944) (xy 30.526529 -381.067091)
			(xy 30.520013 -381.08428) (xy 30.519624 -381.093472) (xy 30.519624 -381.251206) (xy 30.51924 -381.261383)
			(xy 30.511446 -381.280185) (xy 30.497048 -381.294571) (xy 30.478239 -381.302349) (xy 30.468062 -381.302768)
			(xy 29.751782 -381.302768) (xy 29.741624 -381.302282) (xy 29.722855 -381.294502) (xy 29.708491 -381.280135)
			(xy 29.700716 -381.261364) (xy 29.70022 -381.251206) (xy 29.70022 -381.093472) (xy 29.699819 -381.084284)
			(xy 29.693298 -381.0671) (xy 29.68752 -381.059944) (xy 29.665752 -381.034276) (xy 29.627804 -380.978691)
			(xy 29.596771 -380.918969) (xy 29.573098 -380.855967) (xy 29.557124 -380.790587) (xy 29.549079 -380.723767)
			(xy 29.549077 -380.656463) (xy 29.557119 -380.589643) (xy 29.573089 -380.524262) (xy 29.596759 -380.461258)
			(xy 29.627789 -380.401535) (xy 29.665734 -380.345948) (xy 29.68752 -380.320296) (xy 29.693303 -380.313141)
			(xy 29.699825 -380.295958) (xy 29.70022 -380.286768) (xy 29.70022 -379.7935) (xy 29.699806 -379.784313)
			(xy 29.693295 -379.767129) (xy 29.68752 -379.759972) (xy 29.66573 -379.734322) (xy 29.627781 -379.678735)
			(xy 29.596748 -379.619011) (xy 29.573075 -379.556006) (xy 29.557102 -379.490624) (xy 29.549058 -379.423801)
			(xy 28.447 -379.423801) (xy 28.447041 -379.423909) (xy 28.463077 -379.489397) (xy 28.471153 -379.556335)
			(xy 28.471153 -379.623759) (xy 28.463078 -379.690697) (xy 28.447043 -379.756186) (xy 28.423279 -379.819282)
			(xy 28.392128 -379.879078) (xy 28.35404 -379.934713) (xy 28.332176 -379.960378) (xy 28.326361 -379.96751)
			(xy 28.319858 -379.984711) (xy 28.319476 -379.993906) (xy 28.319476 -380.151386) (xy 28.318962 -380.16151)
			(xy 28.311242 -380.180228) (xy 28.296964 -380.194584) (xy 28.278289 -380.202406) (xy 28.268168 -380.202948)
			(xy 27.551888 -380.202948) (xy 27.541784 -380.202426) (xy 27.523115 -380.194693) (xy 27.508823 -380.180408)
			(xy 27.50108 -380.161743) (xy 27.50058 -380.15164) (xy 27.50058 -379.993906) (xy 27.500171 -379.984719)
			(xy 27.493657 -379.967534) (xy 27.48788 -379.960378) (xy 27.466012 -379.934716) (xy 27.427923 -379.879081)
			(xy 27.396771 -379.819285) (xy 27.373007 -379.756187) (xy 27.356972 -379.690698) (xy 27.348896 -379.623759)
			(xy 27.348896 -379.556335) (xy 27.356973 -379.489396) (xy 27.373009 -379.423907) (xy 27.396774 -379.36081)
			(xy 27.427926 -379.301013) (xy 27.466015 -379.245379) (xy 27.48788 -379.219714) (xy 27.493693 -379.21258)
			(xy 27.500199 -379.195381) (xy 27.50058 -379.186186) (xy 27.50058 -378.693934) (xy 27.500158 -378.684748)
			(xy 27.493653 -378.667563) (xy 27.48788 -378.660406) (xy 27.465991 -378.634761) (xy 27.427905 -378.579124)
			(xy 27.396756 -378.519324) (xy 27.372994 -378.456225) (xy 27.356961 -378.390733) (xy 27.348888 -378.323793)
			(xy 0.508 -378.323793) (xy 0.508 -382.223705) (xy 27.348899 -382.223705) (xy 27.3489 -382.15628)
			(xy 27.356976 -382.089342) (xy 27.373012 -382.023853) (xy 27.396777 -381.960755) (xy 27.427928 -381.900959)
			(xy 27.466016 -381.845324) (xy 27.48788 -381.819658) (xy 27.493675 -381.812511) (xy 27.500191 -381.795322)
			(xy 27.50058 -381.78613) (xy 27.50058 -381.628904) (xy 27.501088 -381.618798) (xy 27.508821 -381.600124)
			(xy 27.52311 -381.58583) (xy 27.541782 -381.578091) (xy 27.551888 -381.577596) (xy 28.268168 -381.577596)
			(xy 28.278288 -381.578042) (xy 28.29699 -381.585779) (xy 28.311306 -381.600086) (xy 28.319053 -381.618784)
			(xy 28.319476 -381.628904) (xy 28.319476 -381.78613) (xy 28.319877 -381.795318) (xy 28.326398 -381.812502)
			(xy 28.332176 -381.819658) (xy 28.354031 -381.845331) (xy 28.392122 -381.900964) (xy 28.423274 -381.960759)
			(xy 28.44704 -382.023855) (xy 28.463077 -382.089343) (xy 28.471154 -382.156281) (xy 28.471155 -382.223646)
			(xy 31.749194 -382.223646) (xy 31.749195 -382.156339) (xy 31.757241 -382.089516) (xy 31.773216 -382.024132)
			(xy 31.796891 -381.961127) (xy 31.827927 -381.901404) (xy 31.865879 -381.845818) (xy 31.887668 -381.820166)
			(xy 31.89347 -381.813025) (xy 31.899979 -381.795831) (xy 31.900368 -381.786638) (xy 31.900368 -381.628904)
			(xy 31.900824 -381.618754) (xy 31.908613 -381.600008) (xy 31.922998 -381.585686) (xy 31.941778 -381.57798)
			(xy 31.95193 -381.577596) (xy 32.66821 -381.577596) (xy 32.678332 -381.578117) (xy 32.697045 -381.58584)
			(xy 32.711399 -381.600115) (xy 32.719226 -381.618785) (xy 32.719772 -381.628904) (xy 32.719772 -381.786638)
			(xy 32.72017 -381.795826) (xy 32.726693 -381.81301) (xy 32.732472 -381.820166) (xy 32.75425 -381.845826)
			(xy 32.792198 -381.901412) (xy 32.823231 -381.961134) (xy 32.846904 -382.024138) (xy 32.862877 -382.089519)
			(xy 32.870922 -382.15634) (xy 32.870923 -382.223645) (xy 32.870916 -382.223704) (xy 36.148987 -382.223704)
			(xy 36.148988 -382.156281) (xy 36.157064 -382.089342) (xy 36.1731 -382.023853) (xy 36.196863 -381.960756)
			(xy 36.228013 -381.900959) (xy 36.266101 -381.845324) (xy 36.287964 -381.819658) (xy 36.293769 -381.812519)
			(xy 36.300277 -381.795323) (xy 36.300664 -381.78613) (xy 36.300664 -381.628904) (xy 36.301188 -381.6188)
			(xy 36.308917 -381.600129) (xy 36.323202 -381.585835) (xy 36.341868 -381.578094) (xy 36.351972 -381.577596)
			(xy 37.068252 -381.577596) (xy 37.078371 -381.578055) (xy 37.097073 -381.585787) (xy 37.111388 -381.60009)
			(xy 37.119136 -381.618786) (xy 37.11956 -381.628904) (xy 37.11956 -381.78613) (xy 37.119965 -381.795318)
			(xy 37.126483 -381.812501) (xy 37.13226 -381.819658) (xy 37.154116 -381.845331) (xy 37.192207 -381.900963)
			(xy 37.223361 -381.960758) (xy 37.247127 -382.023854) (xy 37.263164 -382.089343) (xy 37.271242 -382.156281)
			(xy 37.271243 -382.223704) (xy 37.271243 -382.223705) (xy 40.548753 -382.223705) (xy 40.548754 -382.15628)
			(xy 40.556832 -382.08934) (xy 40.57287 -382.02385) (xy 40.596638 -381.960752) (xy 40.627792 -381.900956)
			(xy 40.665886 -381.845322) (xy 40.687752 -381.819658) (xy 40.693555 -381.812518) (xy 40.700065 -381.795323)
			(xy 40.700452 -381.78613) (xy 40.700452 -381.628904) (xy 40.700987 -381.618801) (xy 40.708715 -381.600133)
			(xy 40.722996 -381.585839) (xy 40.741658 -381.578096) (xy 40.75176 -381.577596) (xy 41.46804 -381.577596)
			(xy 41.478151 -381.578052) (xy 41.496829 -381.585802) (xy 41.511122 -381.600108) (xy 41.518856 -381.618793)
			(xy 41.519348 -381.628904) (xy 41.519348 -381.78613) (xy 41.519755 -381.795317) (xy 41.526272 -381.812501)
			(xy 41.532048 -381.819658) (xy 41.553904 -381.84533) (xy 41.591996 -381.900963) (xy 41.62315 -381.960757)
			(xy 41.646917 -382.023853) (xy 41.662955 -382.089342) (xy 41.671033 -382.156281) (xy 41.671034 -382.223645)
			(xy 44.949073 -382.223645) (xy 44.949074 -382.15634) (xy 44.957119 -382.089516) (xy 44.973093 -382.024133)
			(xy 44.996767 -381.961128) (xy 45.027801 -381.901405) (xy 45.065751 -381.845818) (xy 45.08754 -381.820166)
			(xy 45.093339 -381.813022) (xy 45.099851 -381.795831) (xy 45.10024 -381.786638) (xy 45.10024 -381.628904)
			(xy 45.100626 -381.618745) (xy 45.108427 -381.599985) (xy 45.122836 -381.58566) (xy 45.141641 -381.577968)
			(xy 45.151802 -381.577596) (xy 45.868082 -381.577596) (xy 45.878202 -381.57814) (xy 45.896915 -381.585854)
			(xy 45.91127 -381.600122) (xy 45.919098 -381.618787) (xy 45.919644 -381.628904) (xy 45.919644 -381.786638)
			(xy 45.920049 -381.795826) (xy 45.926568 -381.813009) (xy 45.932344 -381.820166) (xy 45.954122 -381.845826)
			(xy 45.992072 -381.901411) (xy 46.023107 -381.961133) (xy 46.046781 -382.024137) (xy 46.062755 -382.089518)
			(xy 46.070801 -382.15634) (xy 46.070801 -382.223645) (xy 46.070794 -382.223705) (xy 71.348808 -382.223705)
			(xy 71.348809 -382.15628) (xy 71.356886 -382.089342) (xy 71.372922 -382.023852) (xy 71.396687 -381.960755)
			(xy 71.427838 -381.900958) (xy 71.465928 -381.845323) (xy 71.487792 -381.819658) (xy 71.493588 -381.812512)
			(xy 71.500103 -381.795322) (xy 71.500492 -381.78613) (xy 71.500492 -381.628904) (xy 71.500919 -381.618783)
			(xy 71.508664 -381.600081) (xy 71.522977 -381.585767) (xy 71.541679 -381.57802) (xy 71.5518 -381.577596)
			(xy 72.26808 -381.577596) (xy 72.278201 -381.578032) (xy 72.296903 -381.585773) (xy 72.311218 -381.600083)
			(xy 72.318965 -381.618783) (xy 72.319388 -381.628904) (xy 72.319388 -381.78613) (xy 72.319786 -381.795318)
			(xy 72.326308 -381.812503) (xy 72.332088 -381.819658) (xy 72.353943 -381.845331) (xy 72.392032 -381.900964)
			(xy 72.423184 -381.960759) (xy 72.446949 -382.023855) (xy 72.462986 -382.089343) (xy 72.471063 -382.156281)
			(xy 72.471064 -382.223646) (xy 75.749104 -382.223646) (xy 75.749104 -382.156339) (xy 75.75715 -382.089515)
			(xy 75.773125 -382.024132) (xy 75.796801 -381.961127) (xy 75.827838 -381.901403) (xy 75.86579 -381.845818)
			(xy 75.88758 -381.820166) (xy 75.893371 -381.813017) (xy 75.89989 -381.795829) (xy 75.90028 -381.786638)
			(xy 75.90028 -381.628904) (xy 75.900725 -381.618753) (xy 75.908515 -381.600004) (xy 75.922904 -381.585681)
			(xy 75.941689 -381.577978) (xy 75.951842 -381.577596) (xy 76.668122 -381.577596) (xy 76.678245 -381.578107)
			(xy 76.696958 -381.585834) (xy 76.711312 -381.600112) (xy 76.719138 -381.618784) (xy 76.719684 -381.628904)
			(xy 76.719684 -381.786638) (xy 76.720079 -381.795827) (xy 76.726604 -381.813011) (xy 76.732384 -381.820166)
			(xy 76.754161 -381.845826) (xy 76.792109 -381.901412) (xy 76.823141 -381.961135) (xy 76.846814 -382.024138)
			(xy 76.862787 -382.089519) (xy 76.870831 -382.156341) (xy 76.870832 -382.223644) (xy 76.870825 -382.223704)
			(xy 80.148896 -382.223704) (xy 80.148897 -382.15628) (xy 80.156973 -382.089342) (xy 80.173009 -382.023853)
			(xy 80.196773 -381.960755) (xy 80.227924 -381.900959) (xy 80.266012 -381.845324) (xy 80.287876 -381.819658)
			(xy 80.29367 -381.812511) (xy 80.300187 -381.795322) (xy 80.300576 -381.78613) (xy 80.300576 -381.628904)
			(xy 80.301088 -381.618798) (xy 80.30882 -381.600125) (xy 80.323108 -381.585831) (xy 80.341779 -381.578092)
			(xy 80.351884 -381.577596) (xy 81.068164 -381.577596) (xy 81.078284 -381.578046) (xy 81.096986 -381.585781)
			(xy 81.111301 -381.600087) (xy 81.119048 -381.618785) (xy 81.119472 -381.628904) (xy 81.119472 -381.78613)
			(xy 81.119874 -381.795318) (xy 81.126394 -381.812502) (xy 81.132172 -381.819658) (xy 81.154027 -381.845331)
			(xy 81.192118 -381.900964) (xy 81.223271 -381.960759) (xy 81.247037 -382.023854) (xy 81.263074 -382.089343)
			(xy 81.271151 -382.156281) (xy 81.271152 -382.223704) (xy 84.548687 -382.223704) (xy 84.548688 -382.156281)
			(xy 84.556764 -382.089342) (xy 84.5728 -382.023853) (xy 84.596563 -381.960756) (xy 84.627713 -381.900959)
			(xy 84.665801 -381.845324) (xy 84.687664 -381.819658) (xy 84.693469 -381.812519) (xy 84.699977 -381.795323)
			(xy 84.700364 -381.78613) (xy 84.700364 -381.628904) (xy 84.700888 -381.6188) (xy 84.708617 -381.600129)
			(xy 84.722902 -381.585835) (xy 84.741568 -381.578094) (xy 84.751672 -381.577596) (xy 85.467952 -381.577596)
			(xy 85.478071 -381.578055) (xy 85.496773 -381.585787) (xy 85.511088 -381.60009) (xy 85.518836 -381.618786)
			(xy 85.51926 -381.628904) (xy 85.51926 -381.78613) (xy 85.519665 -381.795318) (xy 85.526183 -381.812501)
			(xy 85.53196 -381.819658) (xy 85.553816 -381.845331) (xy 85.591907 -381.900963) (xy 85.623061 -381.960758)
			(xy 85.646827 -382.023854) (xy 85.662864 -382.089343) (xy 85.670942 -382.156281) (xy 85.670943 -382.223646)
			(xy 88.948982 -382.223646) (xy 88.948983 -382.156339) (xy 88.957028 -382.089516) (xy 88.973003 -382.024133)
			(xy 88.996677 -381.961128) (xy 89.027712 -381.901404) (xy 89.065663 -381.845818) (xy 89.087452 -381.820166)
			(xy 89.093252 -381.813023) (xy 89.099763 -381.795831) (xy 89.100152 -381.786638) (xy 89.100152 -381.628904)
			(xy 89.100624 -381.618756) (xy 89.108409 -381.600013) (xy 89.12279 -381.585691) (xy 89.141564 -381.577983)
			(xy 89.151714 -381.577596) (xy 89.867994 -381.577596) (xy 89.878115 -381.57813) (xy 89.896828 -381.585848)
			(xy 89.911183 -381.600119) (xy 89.91901 -381.618786) (xy 89.919556 -381.628904) (xy 89.919556 -381.786638)
			(xy 89.919958 -381.795826) (xy 89.926478 -381.81301) (xy 89.932256 -381.820166) (xy 89.954034 -381.845826)
			(xy 89.991983 -381.901411) (xy 90.023017 -381.961134) (xy 90.046691 -382.024137) (xy 90.062665 -382.089519)
			(xy 90.07071 -382.15634) (xy 90.070711 -382.223645) (xy 115.349246 -382.223645) (xy 115.349247 -382.15634)
			(xy 115.357291 -382.089517) (xy 115.373264 -382.024135) (xy 115.396937 -381.96113) (xy 115.427969 -381.901406)
			(xy 115.465917 -381.845819) (xy 115.487704 -381.820166) (xy 115.493498 -381.813019) (xy 115.500014 -381.79583)
			(xy 115.500404 -381.786638) (xy 115.500404 -381.628904) (xy 115.500825 -381.61875) (xy 115.50862 -381.599997)
			(xy 115.523017 -381.585673) (xy 115.54181 -381.577974) (xy 115.551966 -381.577596) (xy 116.268246 -381.577596)
			(xy 116.27837 -381.578088) (xy 116.297084 -381.585822) (xy 116.311437 -381.600106) (xy 116.319262 -381.618782)
			(xy 116.319808 -381.628904) (xy 116.319808 -381.786638) (xy 116.320198 -381.795827) (xy 116.326725 -381.813012)
			(xy 116.332508 -381.820166) (xy 116.354288 -381.845826) (xy 116.39224 -381.90141) (xy 116.423277 -381.961132)
			(xy 116.446952 -382.024135) (xy 116.462928 -382.089517) (xy 116.470973 -382.15634) (xy 116.470974 -382.223645)
			(xy 116.470967 -382.223705) (xy 119.749014 -382.223705) (xy 119.749015 -382.15628) (xy 119.757092 -382.089341)
			(xy 119.773128 -382.023852) (xy 119.796894 -381.960754) (xy 119.828046 -381.900958) (xy 119.866135 -381.845323)
			(xy 119.888 -381.819658) (xy 119.893797 -381.812513) (xy 119.900311 -381.795322) (xy 119.9007 -381.78613)
			(xy 119.9007 -381.628904) (xy 119.901119 -381.618782) (xy 119.908866 -381.600078) (xy 119.923182 -381.585764)
			(xy 119.941886 -381.578019) (xy 119.952008 -381.577596) (xy 120.668288 -381.577596) (xy 120.678409 -381.578026)
			(xy 120.697112 -381.585769) (xy 120.711426 -381.600081) (xy 120.719173 -381.618783) (xy 120.719596 -381.628904)
			(xy 120.719596 -381.78613) (xy 120.719992 -381.795319) (xy 120.726516 -381.812503) (xy 120.732296 -381.819658)
			(xy 120.75415 -381.845331) (xy 120.79224 -381.900965) (xy 120.823391 -381.96076) (xy 120.847156 -382.023855)
			(xy 120.863192 -382.089344) (xy 120.871269 -382.156281) (xy 120.87127 -382.223646) (xy 124.14931 -382.223646)
			(xy 124.14931 -382.156339) (xy 124.157356 -382.089515) (xy 124.173332 -382.024132) (xy 124.197008 -381.961127)
			(xy 124.228045 -381.901403) (xy 124.265998 -381.845818) (xy 124.287788 -381.820166) (xy 124.29358 -381.813018)
			(xy 124.300098 -381.79583) (xy 124.300488 -381.786638) (xy 124.300488 -381.628904) (xy 124.300925 -381.618752)
			(xy 124.308717 -381.600002) (xy 124.323109 -381.585679) (xy 124.341896 -381.577977) (xy 124.35205 -381.577596)
			(xy 125.06833 -381.577596) (xy 125.078453 -381.578101) (xy 125.097167 -381.58583) (xy 125.11152 -381.60011)
			(xy 125.119346 -381.618783) (xy 125.119892 -381.628904) (xy 125.119892 -381.786638) (xy 125.120286 -381.795827)
			(xy 125.126811 -381.813011) (xy 125.132592 -381.820166) (xy 125.154369 -381.845827) (xy 125.192316 -381.901413)
			(xy 125.223348 -381.961135) (xy 125.24702 -382.024139) (xy 125.262993 -382.089519) (xy 125.271037 -382.156341)
			(xy 125.271038 -382.223644) (xy 125.271038 -382.223646) (xy 128.5491 -382.223646) (xy 128.549101 -382.156339)
			(xy 128.557147 -382.089515) (xy 128.573122 -382.024132) (xy 128.596798 -381.961127) (xy 128.627834 -381.901404)
			(xy 128.665787 -381.845818) (xy 128.687576 -381.820166) (xy 128.693367 -381.813016) (xy 128.699886 -381.795829)
			(xy 128.700276 -381.786638) (xy 128.700276 -381.628904) (xy 128.700724 -381.618753) (xy 128.708514 -381.600005)
			(xy 128.722902 -381.585683) (xy 128.741685 -381.577979) (xy 128.751838 -381.577596) (xy 129.468118 -381.577596)
			(xy 129.47824 -381.57811) (xy 129.496954 -381.585836) (xy 129.511308 -381.600113) (xy 129.519134 -381.618784)
			(xy 129.51968 -381.628904) (xy 129.51968 -381.786638) (xy 129.520076 -381.795827) (xy 129.5266 -381.813011)
			(xy 129.53238 -381.820166) (xy 129.554157 -381.845826) (xy 129.592105 -381.901412) (xy 129.623138 -381.961135)
			(xy 129.64681 -382.024138) (xy 129.662784 -382.089519) (xy 129.670828 -382.156341) (xy 129.670829 -382.223644)
			(xy 129.670829 -382.223645) (xy 159.349155 -382.223645) (xy 159.349156 -382.15634) (xy 159.3572 -382.089517)
			(xy 159.373174 -382.024134) (xy 159.396847 -381.96113) (xy 159.42788 -381.901406) (xy 159.465828 -381.845818)
			(xy 159.487616 -381.820166) (xy 159.493411 -381.81302) (xy 159.499926 -381.79583) (xy 159.500316 -381.786638)
			(xy 159.500316 -381.628904) (xy 159.50072 -381.61878) (xy 159.508469 -381.600073) (xy 159.52279 -381.585758)
			(xy 159.5415 -381.578016) (xy 159.551624 -381.577596) (xy 160.268158 -381.577596) (xy 160.278277 -381.57816)
			(xy 160.296988 -381.585866) (xy 160.311345 -381.600128) (xy 160.319173 -381.618789) (xy 160.31972 -381.628904)
			(xy 160.31972 -381.786638) (xy 160.320108 -381.795828) (xy 160.326637 -381.813012) (xy 160.33242 -381.820166)
			(xy 160.354199 -381.845826) (xy 160.392151 -381.90141) (xy 160.423187 -381.961132) (xy 160.446862 -382.024136)
			(xy 160.462837 -382.089518) (xy 160.470882 -382.15634) (xy 160.470883 -382.223645) (xy 160.470876 -382.223705)
			(xy 163.748923 -382.223705) (xy 163.748924 -382.15628) (xy 163.757001 -382.089341) (xy 163.773038 -382.023851)
			(xy 163.796804 -381.960754) (xy 163.827956 -381.900957) (xy 163.866047 -381.845323) (xy 163.887912 -381.819658)
			(xy 163.89371 -381.812514) (xy 163.900224 -381.795323) (xy 163.900612 -381.78613) (xy 163.900612 -381.628904)
			(xy 163.90102 -381.61878) (xy 163.908769 -381.600074) (xy 163.923088 -381.58576) (xy 163.941796 -381.578016)
			(xy 163.95192 -381.577596) (xy 164.6682 -381.577596) (xy 164.678322 -381.578016) (xy 164.697025 -381.585763)
			(xy 164.711339 -381.600079) (xy 164.719085 -381.618782) (xy 164.719508 -381.628904) (xy 164.719508 -381.78613)
			(xy 164.719902 -381.795319) (xy 164.726426 -381.812503) (xy 164.732208 -381.819658) (xy 164.754062 -381.845331)
			(xy 164.79215 -381.900965) (xy 164.823301 -381.96076) (xy 164.847065 -382.023856) (xy 164.863101 -382.089344)
			(xy 164.871178 -382.156281) (xy 164.871179 -382.223645) (xy 168.149243 -382.223645) (xy 168.149244 -382.15634)
			(xy 168.157288 -382.089517) (xy 168.173261 -382.024135) (xy 168.196933 -381.96113) (xy 168.227965 -381.901406)
			(xy 168.265913 -381.845819) (xy 168.2877 -381.820166) (xy 168.293494 -381.813019) (xy 168.30001 -381.79583)
			(xy 168.3004 -381.786638) (xy 168.3004 -381.628904) (xy 168.300825 -381.61875) (xy 168.308619 -381.599998)
			(xy 168.323015 -381.585674) (xy 168.341806 -381.577975) (xy 168.351962 -381.577596) (xy 169.068242 -381.577596)
			(xy 169.078366 -381.578091) (xy 169.09708 -381.585824) (xy 169.111433 -381.600107) (xy 169.119258 -381.618783)
			(xy 169.119804 -381.628904) (xy 169.119804 -381.786638) (xy 169.120195 -381.795827) (xy 169.126722 -381.813012)
			(xy 169.132504 -381.820166) (xy 169.154281 -381.845827) (xy 169.192227 -381.901413) (xy 169.223258 -381.961136)
			(xy 169.24693 -382.024139) (xy 169.262902 -382.08952) (xy 169.270946 -382.156341) (xy 169.270947 -382.223644)
			(xy 169.270947 -382.223646) (xy 172.54901 -382.223646) (xy 172.54901 -382.156339) (xy 172.557056 -382.089515)
			(xy 172.573032 -382.024132) (xy 172.596708 -381.961127) (xy 172.627745 -381.901403) (xy 172.665698 -381.845818)
			(xy 172.687488 -381.820166) (xy 172.69328 -381.813018) (xy 172.699798 -381.79583) (xy 172.700188 -381.786638)
			(xy 172.700188 -381.628904) (xy 172.700625 -381.618752) (xy 172.708417 -381.600002) (xy 172.722809 -381.585679)
			(xy 172.741596 -381.577977) (xy 172.75175 -381.577596) (xy 173.46803 -381.577596) (xy 173.478153 -381.578101)
			(xy 173.496867 -381.58583) (xy 173.51122 -381.60011) (xy 173.519046 -381.618783) (xy 173.519592 -381.628904)
			(xy 173.519592 -381.786638) (xy 173.519986 -381.795827) (xy 173.526511 -381.813011) (xy 173.532292 -381.820166)
			(xy 173.554069 -381.845827) (xy 173.592016 -381.901413) (xy 173.623048 -381.961135) (xy 173.64672 -382.024139)
			(xy 173.662693 -382.089519) (xy 173.670737 -382.156341) (xy 173.670738 -382.223644) (xy 173.662695 -382.290466)
			(xy 173.646725 -382.355847) (xy 173.623054 -382.418851) (xy 173.592024 -382.478574) (xy 173.554078 -382.534161)
			(xy 173.532292 -382.559814) (xy 173.526506 -382.566967) (xy 173.519985 -382.584151) (xy 173.519592 -382.593342)
			(xy 173.519592 -383.086864) (xy 173.520021 -383.096049) (xy 173.526522 -383.113234) (xy 173.532292 -383.120392)
			(xy 173.554094 -383.146032) (xy 173.592041 -383.201621) (xy 173.623072 -383.261346) (xy 173.646507 -383.323727)
			(xy 174.749152 -383.323727) (xy 174.749155 -383.256419) (xy 174.757202 -383.189594) (xy 174.773179 -383.12421)
			(xy 174.796856 -383.061204) (xy 174.827893 -383.001479) (xy 174.865846 -382.945892) (xy 174.887636 -382.92024)
			(xy 174.893445 -382.913104) (xy 174.899951 -382.895906) (xy 174.900336 -382.886712) (xy 174.900336 -382.728724)
			(xy 174.900742 -382.718567) (xy 174.908536 -382.699808) (xy 174.922939 -382.685482) (xy 174.941739 -382.677788)
			(xy 174.951898 -382.677416) (xy 175.668178 -382.677416) (xy 175.6783 -382.677944) (xy 175.697017 -382.68566)
			(xy 175.711373 -382.699933) (xy 175.719197 -382.718605) (xy 175.71974 -382.728724) (xy 175.71974 -382.886712)
			(xy 175.720158 -382.895898) (xy 175.726668 -382.913082) (xy 175.73244 -382.92024) (xy 175.754193 -382.945921)
			(xy 175.792144 -383.001503) (xy 175.82318 -383.061222) (xy 175.846856 -383.124223) (xy 175.862832 -383.189602)
			(xy 175.870879 -383.256422) (xy 175.870883 -383.323724) (xy 175.862842 -383.390545) (xy 175.846872 -383.455925)
			(xy 175.823202 -383.518928) (xy 175.792172 -383.578651) (xy 175.754226 -383.634236) (xy 175.73244 -383.659888)
			(xy 175.726616 -383.667014) (xy 175.720119 -383.684219) (xy 175.71974 -383.693416) (xy 175.71974 -384.186684)
			(xy 175.720171 -384.195869) (xy 175.726672 -384.213053) (xy 175.73244 -384.220212) (xy 175.754264 -384.245835)
			(xy 175.792213 -384.301425) (xy 175.823246 -384.361152) (xy 175.846918 -384.424161) (xy 175.862889 -384.489547)
			(xy 175.87093 -384.556373) (xy 175.870927 -384.623681) (xy 175.862879 -384.690507) (xy 175.846902 -384.755891)
			(xy 175.823224 -384.818897) (xy 175.792185 -384.878622) (xy 175.754231 -384.934208) (xy 175.73244 -384.95986)
			(xy 175.726628 -384.966994) (xy 175.720124 -384.984193) (xy 175.71974 -384.993388) (xy 175.71974 -385.151376)
			(xy 175.71926 -385.161524) (xy 175.71148 -385.180268) (xy 175.697101 -385.194591) (xy 175.678327 -385.202298)
			(xy 175.668178 -385.202684) (xy 174.951898 -385.202684) (xy 174.941774 -385.202176) (xy 174.923058 -385.194452)
			(xy 174.908702 -385.180172) (xy 174.900879 -385.161497) (xy 174.900336 -385.151376) (xy 174.900336 -384.993388)
			(xy 174.899924 -384.984201) (xy 174.893411 -384.967017) (xy 174.887636 -384.95986) (xy 174.865884 -384.934179)
			(xy 174.827934 -384.878596) (xy 174.7969 -384.818877) (xy 174.773225 -384.755876) (xy 174.75725 -384.690497)
			(xy 174.749203 -384.623678) (xy 174.749199 -384.556376) (xy 174.75724 -384.489556) (xy 174.773209 -384.424176)
			(xy 174.796878 -384.361173) (xy 174.827906 -384.30145) (xy 174.865851 -384.245864) (xy 174.887636 -384.220212)
			(xy 174.893457 -384.213084) (xy 174.899956 -384.19588) (xy 174.900336 -384.186684) (xy 174.900336 -383.693416)
			(xy 174.89991 -383.684231) (xy 174.893407 -383.667046) (xy 174.887636 -383.659888) (xy 174.865813 -383.634265)
			(xy 174.827865 -383.578674) (xy 174.796834 -383.518947) (xy 174.773163 -383.455938) (xy 174.757193 -383.390553)
			(xy 174.749152 -383.323727) (xy 173.646507 -383.323727) (xy 173.646742 -383.324352) (xy 173.662713 -383.389736)
			(xy 173.670756 -383.456559) (xy 173.670754 -383.523865) (xy 173.662709 -383.590688) (xy 173.646735 -383.656071)
			(xy 173.623062 -383.719076) (xy 173.592028 -383.7788) (xy 173.55408 -383.834387) (xy 173.532292 -383.86004)
			(xy 173.526495 -383.867185) (xy 173.519981 -383.884376) (xy 173.519592 -383.893568) (xy 173.519592 -384.051556)
			(xy 173.519142 -384.061708) (xy 173.51136 -384.080461) (xy 173.496971 -384.094786) (xy 173.478184 -384.102486)
			(xy 173.46803 -384.102864) (xy 172.75175 -384.102864) (xy 172.741627 -384.102333) (xy 172.722908 -384.094622)
			(xy 172.70855 -384.080349) (xy 172.700728 -384.061676) (xy 172.700188 -384.051556) (xy 172.700188 -383.893568)
			(xy 172.699796 -383.884379) (xy 172.69327 -383.867194) (xy 172.687488 -383.86004) (xy 172.665715 -383.834376)
			(xy 172.627762 -383.778792) (xy 172.596725 -383.719071) (xy 172.57305 -383.656068) (xy 172.557074 -383.590686)
			(xy 172.549028 -383.523864) (xy 172.549026 -383.45656) (xy 172.55707 -383.389737) (xy 172.573042 -383.324355)
			(xy 172.596716 -383.261351) (xy 172.62775 -383.201629) (xy 172.6657 -383.146043) (xy 172.687488 -383.120392)
			(xy 172.693269 -383.113236) (xy 172.699793 -383.096054) (xy 172.700188 -383.086864) (xy 172.700188 -382.593342)
			(xy 172.69976 -382.584157) (xy 172.693259 -382.566972) (xy 172.687488 -382.559814) (xy 172.665689 -382.534171)
			(xy 172.627737 -382.478584) (xy 172.596702 -382.41886) (xy 172.573027 -382.355854) (xy 172.557054 -382.29047)
			(xy 172.54901 -382.223646) (xy 169.270947 -382.223646) (xy 169.262905 -382.290465) (xy 169.246934 -382.355847)
			(xy 169.223264 -382.41885) (xy 169.192235 -382.478574) (xy 169.15429 -382.534161) (xy 169.132504 -382.559814)
			(xy 169.126719 -382.566968) (xy 169.120197 -382.584152) (xy 169.119804 -382.593342) (xy 169.119804 -383.086864)
			(xy 169.120231 -383.096049) (xy 169.126733 -383.113234) (xy 169.132504 -383.120392) (xy 169.154306 -383.146032)
			(xy 169.192252 -383.201621) (xy 169.223282 -383.261347) (xy 169.246739 -383.323787) (xy 170.348832 -383.323787)
			(xy 170.348835 -383.256359) (xy 170.356915 -383.189418) (xy 170.372956 -383.123926) (xy 170.396726 -383.060827)
			(xy 170.427884 -383.001031) (xy 170.46598 -382.945396) (xy 170.487848 -382.919732) (xy 170.493662 -382.912599)
			(xy 170.500165 -382.895399) (xy 170.500548 -382.886204) (xy 170.500548 -382.728724) (xy 170.501103 -382.718623)
			(xy 170.508823 -382.699955) (xy 170.523098 -382.685662) (xy 170.541756 -382.677917) (xy 170.551856 -382.677416)
			(xy 171.268136 -382.677416) (xy 171.278249 -382.677856) (xy 171.296931 -382.685608) (xy 171.311225 -382.699919)
			(xy 171.318956 -382.71861) (xy 171.319444 -382.728724) (xy 171.319444 -382.886204) (xy 171.319865 -382.89539)
			(xy 171.326372 -382.912574) (xy 171.332144 -382.919732) (xy 171.353975 -382.945425) (xy 171.392068 -383.001055)
			(xy 171.423223 -383.060846) (xy 171.446992 -383.12394) (xy 171.463032 -383.189426) (xy 171.471111 -383.256362)
			(xy 171.471115 -383.323784) (xy 171.463041 -383.390721) (xy 171.447008 -383.456209) (xy 171.423246 -383.519304)
			(xy 171.392096 -383.579099) (xy 171.354008 -383.634732) (xy 171.332144 -383.660396) (xy 171.32636 -383.66755)
			(xy 171.319839 -383.684734) (xy 171.319444 -383.693924) (xy 171.319444 -384.186176) (xy 171.319878 -384.19536)
			(xy 171.326376 -384.212544) (xy 171.332144 -384.219704) (xy 171.354045 -384.245339) (xy 171.392137 -384.300977)
			(xy 171.423289 -384.360776) (xy 171.447054 -384.423877) (xy 171.463088 -384.489371) (xy 171.471162 -384.556313)
			(xy 171.471159 -384.623741) (xy 171.463078 -384.690683) (xy 171.447037 -384.756174) (xy 171.423267 -384.819273)
			(xy 171.392109 -384.87907) (xy 171.354012 -384.934704) (xy 171.332144 -384.960368) (xy 171.326329 -384.9675)
			(xy 171.319827 -384.984701) (xy 171.319444 -384.993896) (xy 171.319444 -385.151376) (xy 171.318896 -385.161478)
			(xy 171.311175 -385.180147) (xy 171.296897 -385.194441) (xy 171.278237 -385.202185) (xy 171.268136 -385.202684)
			(xy 170.551856 -385.202684) (xy 170.541742 -385.20225) (xy 170.52306 -385.194495) (xy 170.508766 -385.180183)
			(xy 170.501036 -385.16149) (xy 170.500548 -385.151376) (xy 170.500548 -384.993896) (xy 170.500129 -384.98471)
			(xy 170.49362 -384.967526) (xy 170.487848 -384.960368) (xy 170.466018 -384.934674) (xy 170.427925 -384.879045)
			(xy 170.39677 -384.819253) (xy 170.373001 -384.75616) (xy 170.356962 -384.690674) (xy 170.348883 -384.623738)
			(xy 170.348879 -384.556316) (xy 170.356952 -384.489379) (xy 170.372985 -384.423892) (xy 170.396748 -384.360796)
			(xy 170.427897 -384.301001) (xy 170.465984 -384.245368) (xy 170.487848 -384.219704) (xy 170.493631 -384.21255)
			(xy 170.500153 -384.195366) (xy 170.500548 -384.186176) (xy 170.500548 -383.693924) (xy 170.500116 -383.684739)
			(xy 170.493616 -383.667555) (xy 170.487848 -383.660396) (xy 170.465947 -383.634761) (xy 170.427856 -383.579123)
			(xy 170.396704 -383.519323) (xy 170.37294 -383.456222) (xy 170.356906 -383.390729) (xy 170.348832 -383.323787)
			(xy 169.246739 -383.323787) (xy 169.246952 -383.324353) (xy 169.262922 -383.389736) (xy 169.270965 -383.456559)
			(xy 169.270963 -383.523865) (xy 169.262918 -383.590688) (xy 169.246945 -383.65607) (xy 169.223272 -383.719075)
			(xy 169.192239 -383.7788) (xy 169.154291 -383.834387) (xy 169.132504 -383.86004) (xy 169.126708 -383.867186)
			(xy 169.120193 -383.884376) (xy 169.119804 -383.893568) (xy 169.119804 -384.051556) (xy 169.119342 -384.061707)
			(xy 169.111562 -384.080457) (xy 169.097177 -384.094782) (xy 169.078394 -384.102484) (xy 169.068242 -384.102864)
			(xy 168.351962 -384.102864) (xy 168.341833 -384.102405) (xy 168.323112 -384.094665) (xy 168.308757 -384.080371)
			(xy 168.300939 -384.061682) (xy 168.3004 -384.051556) (xy 168.3004 -383.893568) (xy 168.300005 -383.884379)
			(xy 168.293481 -383.867195) (xy 168.2877 -383.86004) (xy 168.265929 -383.834374) (xy 168.227982 -383.778789)
			(xy 168.196951 -383.719067) (xy 168.173279 -383.656064) (xy 168.157306 -383.590684) (xy 168.149261 -383.523864)
			(xy 168.149259 -383.456561) (xy 168.157301 -383.38974) (xy 168.173272 -383.324359) (xy 168.196941 -383.261355)
			(xy 168.22797 -383.201632) (xy 168.265914 -383.146045) (xy 168.2877 -383.120392) (xy 168.293482 -383.113237)
			(xy 168.300006 -383.096054) (xy 168.3004 -383.086864) (xy 168.3004 -382.593342) (xy 168.29997 -382.584157)
			(xy 168.29347 -382.566972) (xy 168.2877 -382.559814) (xy 168.265904 -382.534169) (xy 168.227958 -382.478581)
			(xy 168.196927 -382.418856) (xy 168.173256 -382.355851) (xy 168.157285 -382.290468) (xy 168.149243 -382.223645)
			(xy 164.871179 -382.223645) (xy 164.871179 -382.223704) (xy 164.863104 -382.290641) (xy 164.84707 -382.35613)
			(xy 164.823307 -382.419226) (xy 164.792158 -382.479022) (xy 164.754071 -382.534657) (xy 164.732208 -382.560322)
			(xy 164.726421 -382.567474) (xy 164.7199 -382.584659) (xy 164.719508 -382.59385) (xy 164.719508 -383.086356)
			(xy 164.719937 -383.095541) (xy 164.726437 -383.112726) (xy 164.732208 -383.119884) (xy 164.754087 -383.145536)
			(xy 164.792175 -383.201173) (xy 164.823325 -383.260971) (xy 164.846959 -383.323727) (xy 165.949064 -383.323727)
			(xy 165.949067 -383.256419) (xy 165.957115 -383.189594) (xy 165.973092 -383.124209) (xy 165.996769 -383.061203)
			(xy 166.027808 -383.001479) (xy 166.065762 -382.945892) (xy 166.087552 -382.92024) (xy 166.093363 -382.913105)
			(xy 166.099868 -382.895907) (xy 166.100252 -382.886712) (xy 166.100252 -382.728724) (xy 166.10074 -382.718577)
			(xy 166.108519 -382.699835) (xy 166.122895 -382.685512) (xy 166.141666 -382.677803) (xy 166.151814 -382.677416)
			(xy 166.868094 -382.677416) (xy 166.878217 -382.677931) (xy 166.896934 -382.685652) (xy 166.911289 -382.699929)
			(xy 166.919113 -382.718603) (xy 166.919656 -382.728724) (xy 166.919656 -382.886712) (xy 166.92007 -382.895899)
			(xy 166.926582 -382.913082) (xy 166.932356 -382.92024) (xy 166.954108 -382.945921) (xy 166.992059 -383.001503)
			(xy 167.023094 -383.061223) (xy 167.046769 -383.124224) (xy 167.062744 -383.189602) (xy 167.070791 -383.256422)
			(xy 167.070795 -383.323724) (xy 167.062754 -383.390544) (xy 167.046785 -383.455925) (xy 167.023116 -383.518928)
			(xy 166.992086 -383.57865) (xy 166.954142 -383.634236) (xy 166.932356 -383.659888) (xy 166.926534 -383.667015)
			(xy 166.920036 -383.68422) (xy 166.919656 -383.693416) (xy 166.919656 -384.186684) (xy 166.920084 -384.195869)
			(xy 166.926586 -384.213053) (xy 166.932356 -384.220212) (xy 166.954179 -384.245835) (xy 166.992127 -384.301425)
			(xy 167.023159 -384.361153) (xy 167.04683 -384.424161) (xy 167.062801 -384.489547) (xy 167.070842 -384.556373)
			(xy 167.070839 -384.623681) (xy 167.062791 -384.690506) (xy 167.046814 -384.75589) (xy 167.023137 -384.818897)
			(xy 166.9921 -384.878621) (xy 166.954146 -384.934208) (xy 166.932356 -384.95986) (xy 166.926546 -384.966995)
			(xy 166.92004 -384.984194) (xy 166.919656 -384.993388) (xy 166.919656 -385.151376) (xy 166.91916 -385.161522)
			(xy 166.911383 -385.180263) (xy 166.89701 -385.194585) (xy 166.878241 -385.202296) (xy 166.868094 -385.202684)
			(xy 166.151814 -385.202684) (xy 166.141691 -385.202163) (xy 166.122975 -385.194444) (xy 166.108619 -385.180169)
			(xy 166.100795 -385.161496) (xy 166.100252 -385.151376) (xy 166.100252 -384.993388) (xy 166.099836 -384.984202)
			(xy 166.093325 -384.967018) (xy 166.087552 -384.95986) (xy 166.065799 -384.934179) (xy 166.027849 -384.878597)
			(xy 165.996813 -384.818877) (xy 165.973138 -384.755877) (xy 165.957162 -384.690498) (xy 165.949115 -384.623678)
			(xy 165.949111 -384.556376) (xy 165.957152 -384.489555) (xy 165.973122 -384.424175) (xy 165.996791 -384.361172)
			(xy 166.027821 -384.30145) (xy 166.065766 -384.245864) (xy 166.087552 -384.220212) (xy 166.093375 -384.213086)
			(xy 166.099872 -384.19588) (xy 166.100252 -384.186684) (xy 166.100252 -383.693416) (xy 166.099823 -383.684231)
			(xy 166.093321 -383.667047) (xy 166.087552 -383.659888) (xy 166.065728 -383.634265) (xy 166.02778 -383.578675)
			(xy 165.996747 -383.518947) (xy 165.973076 -383.455939) (xy 165.957105 -383.390553) (xy 165.949064 -383.323727)
			(xy 164.846959 -383.323727) (xy 164.847088 -383.32407) (xy 164.863122 -383.38956) (xy 164.871196 -383.4565)
			(xy 164.871195 -383.523924) (xy 164.863117 -383.590864) (xy 164.84708 -383.656353) (xy 164.823315 -383.719451)
			(xy 164.792163 -383.779248) (xy 164.754073 -383.834883) (xy 164.732208 -383.860548) (xy 164.726409 -383.867692)
			(xy 164.719896 -383.884883) (xy 164.719508 -383.894076) (xy 164.719508 -384.051556) (xy 164.719048 -384.061675)
			(xy 164.711316 -384.080376) (xy 164.697013 -384.094691) (xy 164.678318 -384.102439) (xy 164.6682 -384.102864)
			(xy 163.95192 -384.102864) (xy 163.941794 -384.102467) (xy 163.923084 -384.094719) (xy 163.908768 -384.080396)
			(xy 163.901028 -384.061682) (xy 163.900612 -384.051556) (xy 163.900612 -383.894076) (xy 163.900211 -383.884888)
			(xy 163.893691 -383.867704) (xy 163.887912 -383.860548) (xy 163.866063 -383.83487) (xy 163.827973 -383.779238)
			(xy 163.796821 -383.719443) (xy 163.773056 -383.656348) (xy 163.757019 -383.59086) (xy 163.748941 -383.523923)
			(xy 163.74894 -383.456501) (xy 163.757014 -383.389563) (xy 163.773049 -383.324075) (xy 163.796811 -383.260979)
			(xy 163.827961 -383.201183) (xy 163.866049 -383.145549) (xy 163.887912 -383.119884) (xy 163.893699 -383.112732)
			(xy 163.900219 -383.095547) (xy 163.900612 -383.086356) (xy 163.900612 -382.59385) (xy 163.900175 -382.584666)
			(xy 163.89368 -382.567481) (xy 163.887912 -382.560322) (xy 163.866038 -382.534665) (xy 163.827949 -382.47903)
			(xy 163.796798 -382.419232) (xy 163.773034 -382.356134) (xy 163.756998 -382.290644) (xy 163.748923 -382.223705)
			(xy 160.470876 -382.223705) (xy 160.46284 -382.290468) (xy 160.446866 -382.35585) (xy 160.423193 -382.418854)
			(xy 160.392159 -382.478577) (xy 160.354208 -382.534162) (xy 160.33242 -382.559814) (xy 160.326637 -382.566969)
			(xy 160.320114 -382.584152) (xy 160.31972 -382.593342) (xy 160.31972 -383.086864) (xy 160.320143 -383.09605)
			(xy 160.326647 -383.113235) (xy 160.33242 -383.120392) (xy 160.354225 -383.146031) (xy 160.392176 -383.201618)
			(xy 160.42321 -383.261343) (xy 160.446672 -383.323786) (xy 161.548769 -383.323786) (xy 161.548772 -383.25636)
			(xy 161.556851 -383.18942) (xy 161.572889 -383.123929) (xy 161.596656 -383.060831) (xy 161.627809 -383.001034)
			(xy 161.665899 -382.945398) (xy 161.687764 -382.919732) (xy 161.69358 -382.912601) (xy 161.700081 -382.895399)
			(xy 161.700464 -382.886204) (xy 161.700464 -382.728724) (xy 161.701004 -382.718621) (xy 161.708727 -382.69995)
			(xy 161.723007 -382.685656) (xy 161.74167 -382.677914) (xy 161.751772 -382.677416) (xy 162.468052 -382.677416)
			(xy 162.478173 -382.677856) (xy 162.496879 -382.685591) (xy 162.511195 -382.699901) (xy 162.51894 -382.718603)
			(xy 162.51936 -382.728724) (xy 162.51936 -382.886204) (xy 162.519777 -382.89539) (xy 162.526287 -382.912574)
			(xy 162.53206 -382.919732) (xy 162.55389 -382.945426) (xy 162.591982 -383.001055) (xy 162.623137 -383.060847)
			(xy 162.646905 -383.12394) (xy 162.662944 -383.189426) (xy 162.671023 -383.256362) (xy 162.671027 -383.323784)
			(xy 162.662954 -383.39072) (xy 162.646921 -383.456208) (xy 162.623159 -383.519303) (xy 162.59201 -383.579098)
			(xy 162.553923 -383.634731) (xy 162.53206 -383.660396) (xy 162.526278 -383.667551) (xy 162.519755 -383.684734)
			(xy 162.51936 -383.693924) (xy 162.51936 -384.186176) (xy 162.51979 -384.195361) (xy 162.526291 -384.212545)
			(xy 162.53206 -384.219704) (xy 162.553961 -384.245339) (xy 162.592051 -384.300977) (xy 162.623202 -384.360777)
			(xy 162.646966 -384.423878) (xy 162.663 -384.489371) (xy 162.671074 -384.556313) (xy 162.671071 -384.623741)
			(xy 162.662991 -384.690682) (xy 162.64695 -384.756174) (xy 162.62318 -384.819272) (xy 162.592023 -384.879069)
			(xy 162.553928 -384.934703) (xy 162.53206 -384.960368) (xy 162.526247 -384.967501) (xy 162.519743 -384.984701)
			(xy 162.51936 -384.993896) (xy 162.51936 -385.151376) (xy 162.518964 -385.161502) (xy 162.511216 -385.180213)
			(xy 162.496893 -385.194529) (xy 162.478178 -385.202268) (xy 162.468052 -385.202684) (xy 161.751772 -385.202684)
			(xy 161.741659 -385.202238) (xy 161.722978 -385.194488) (xy 161.708683 -385.180179) (xy 161.700952 -385.161489)
			(xy 161.700464 -385.151376) (xy 161.700464 -384.993896) (xy 161.700041 -384.98471) (xy 161.693535 -384.967527)
			(xy 161.687764 -384.960368) (xy 161.665937 -384.934673) (xy 161.627849 -384.879042) (xy 161.596699 -384.819249)
			(xy 161.572934 -384.756157) (xy 161.556897 -384.690671) (xy 161.548819 -384.623737) (xy 161.548816 -384.556317)
			(xy 161.556888 -384.489382) (xy 161.572918 -384.423895) (xy 161.596677 -384.3608) (xy 161.627821 -384.301005)
			(xy 161.665903 -384.24537) (xy 161.687764 -384.219704) (xy 161.693549 -384.212551) (xy 161.700069 -384.195366)
			(xy 161.700464 -384.186176) (xy 161.700464 -383.693924) (xy 161.700028 -383.68474) (xy 161.693531 -383.667556)
			(xy 161.687764 -383.660396) (xy 161.665866 -383.634759) (xy 161.627781 -383.57912) (xy 161.596634 -383.519319)
			(xy 161.572873 -383.456219) (xy 161.556841 -383.390727) (xy 161.548769 -383.323786) (xy 160.446672 -383.323786)
			(xy 160.446884 -383.32435) (xy 160.462857 -383.389734) (xy 160.470901 -383.456558) (xy 160.470899 -383.523866)
			(xy 160.462853 -383.59069) (xy 160.446877 -383.656074) (xy 160.423201 -383.719079) (xy 160.392163 -383.778803)
			(xy 160.35421 -383.834388) (xy 160.33242 -383.86004) (xy 160.326626 -383.867187) (xy 160.320109 -383.884376)
			(xy 160.31972 -383.893568) (xy 160.31972 -384.051556) (xy 160.319248 -384.061673) (xy 160.311518 -384.080372)
			(xy 160.297219 -384.094687) (xy 160.278529 -384.102437) (xy 160.268412 -384.102864) (xy 159.551878 -384.102864)
			(xy 159.54175 -384.102392) (xy 159.523029 -384.094657) (xy 159.508674 -384.080367) (xy 159.500855 -384.061681)
			(xy 159.500316 -384.051556) (xy 159.500316 -383.893568) (xy 159.499918 -383.88438) (xy 159.493395 -383.867196)
			(xy 159.487616 -383.86004) (xy 159.465845 -383.834375) (xy 159.427897 -383.77879) (xy 159.396864 -383.719068)
			(xy 159.373191 -383.656065) (xy 159.357218 -383.590684) (xy 159.349173 -383.523864) (xy 159.349172 -383.45656)
			(xy 159.357214 -383.389739) (xy 159.373184 -383.324358) (xy 159.396854 -383.261354) (xy 159.427884 -383.201631)
			(xy 159.46583 -383.146044) (xy 159.487616 -383.120392) (xy 159.4934 -383.113238) (xy 159.499922 -383.096054)
			(xy 159.500316 -383.086864) (xy 159.500316 -382.593342) (xy 159.499882 -382.584157) (xy 159.493384 -382.566973)
			(xy 159.487616 -382.559814) (xy 159.465819 -382.53417) (xy 159.427872 -382.478582) (xy 159.396841 -382.418857)
			(xy 159.373169 -382.355851) (xy 159.357198 -382.290468) (xy 159.349155 -382.223645) (xy 129.670829 -382.223645)
			(xy 129.662786 -382.290466) (xy 129.646815 -382.355847) (xy 129.623144 -382.418851) (xy 129.592113 -382.478575)
			(xy 129.554167 -382.534162) (xy 129.53238 -382.559814) (xy 129.526593 -382.566966) (xy 129.520073 -382.584151)
			(xy 129.51968 -382.593342) (xy 129.51968 -383.086864) (xy 129.520112 -383.096049) (xy 129.526611 -383.113233)
			(xy 129.53238 -383.120392) (xy 129.554183 -383.146031) (xy 129.59213 -383.20162) (xy 129.623162 -383.261346)
			(xy 129.646598 -383.323727) (xy 130.749242 -383.323727) (xy 130.749246 -383.256419) (xy 130.757293 -383.189594)
			(xy 130.77327 -383.12421) (xy 130.796946 -383.061204) (xy 130.827982 -383.00148) (xy 130.865935 -382.945892)
			(xy 130.887724 -382.92024) (xy 130.893531 -382.913103) (xy 130.900039 -382.895906) (xy 130.900424 -382.886712)
			(xy 130.900424 -382.728724) (xy 130.900842 -382.718568) (xy 130.908634 -382.699812) (xy 130.923032 -382.685487)
			(xy 130.941828 -382.67779) (xy 130.951986 -382.677416) (xy 131.668266 -382.677416) (xy 131.678388 -382.677954)
			(xy 131.697103 -382.685666) (xy 131.71146 -382.699937) (xy 131.719284 -382.718606) (xy 131.719828 -382.728724)
			(xy 131.719828 -382.886712) (xy 131.720226 -382.895901) (xy 131.726747 -382.913085) (xy 131.732528 -382.92024)
			(xy 131.754281 -382.945921) (xy 131.792233 -383.001502) (xy 131.82327 -383.061222) (xy 131.846946 -383.124223)
			(xy 131.862923 -383.189602) (xy 131.87097 -383.256422) (xy 131.870973 -383.323724) (xy 131.862932 -383.390545)
			(xy 131.846962 -383.455926) (xy 131.823292 -383.518929) (xy 131.792261 -383.578651) (xy 131.754314 -383.634236)
			(xy 131.732528 -383.659888) (xy 131.726703 -383.667013) (xy 131.720207 -383.684219) (xy 131.719828 -383.693416)
			(xy 131.719828 -384.186684) (xy 131.720239 -384.195871) (xy 131.726751 -384.213056) (xy 131.732528 -384.220212)
			(xy 131.754352 -384.245834) (xy 131.792302 -384.301424) (xy 131.823336 -384.361152) (xy 131.847008 -384.42416)
			(xy 131.86298 -384.489546) (xy 131.871021 -384.556373) (xy 131.871018 -384.623681) (xy 131.86297 -384.690507)
			(xy 131.846992 -384.755892) (xy 131.823314 -384.818898) (xy 131.792274 -384.878622) (xy 131.754319 -384.934208)
			(xy 131.732528 -384.95986) (xy 131.726715 -384.966993) (xy 131.720212 -384.984193) (xy 131.719828 -384.993388)
			(xy 131.719828 -385.151376) (xy 131.719359 -385.161525) (xy 131.711577 -385.180272) (xy 131.697195 -385.194595)
			(xy 131.678417 -385.202301) (xy 131.668266 -385.202684) (xy 130.951986 -385.202684) (xy 130.941861 -385.202185)
			(xy 130.923145 -385.194457) (xy 130.90879 -385.180175) (xy 130.900967 -385.161498) (xy 130.900424 -385.151376)
			(xy 130.900424 -384.993388) (xy 130.900014 -384.984201) (xy 130.8935 -384.967017) (xy 130.887724 -384.95986)
			(xy 130.865972 -384.934178) (xy 130.828023 -384.878596) (xy 130.796989 -384.818876) (xy 130.773315 -384.755876)
			(xy 130.75734 -384.690497) (xy 130.749294 -384.623678) (xy 130.74929 -384.556376) (xy 130.757331 -384.489556)
			(xy 130.773299 -384.424176) (xy 130.796967 -384.361173) (xy 130.827996 -384.301451) (xy 130.865939 -384.245865)
			(xy 130.887724 -384.220212) (xy 130.893543 -384.213083) (xy 130.900044 -384.19588) (xy 130.900424 -384.186684)
			(xy 130.900424 -383.693416) (xy 130.900001 -383.68423) (xy 130.893495 -383.667046) (xy 130.887724 -383.659888)
			(xy 130.865901 -383.634265) (xy 130.827955 -383.578674) (xy 130.796924 -383.518946) (xy 130.773254 -383.455938)
			(xy 130.757284 -383.390552) (xy 130.749242 -383.323727) (xy 129.646598 -383.323727) (xy 129.646833 -383.324352)
			(xy 129.662804 -383.389735) (xy 129.670846 -383.456559) (xy 129.670845 -383.523865) (xy 129.6628 -383.590688)
			(xy 129.646826 -383.656071) (xy 129.623152 -383.719076) (xy 129.592118 -383.778801) (xy 129.554168 -383.834388)
			(xy 129.53238 -383.86004) (xy 129.526582 -383.867184) (xy 129.520069 -383.884375) (xy 129.51968 -383.893568)
			(xy 129.51968 -384.051556) (xy 129.519242 -384.06171) (xy 129.511457 -384.080465) (xy 129.497065 -384.094791)
			(xy 129.478274 -384.102488) (xy 129.468118 -384.102864) (xy 128.751838 -384.102864) (xy 128.741714 -384.102342)
			(xy 128.722995 -384.094628) (xy 128.708637 -384.080352) (xy 128.700816 -384.061677) (xy 128.700276 -384.051556)
			(xy 128.700276 -383.893568) (xy 128.699886 -383.884379) (xy 128.693359 -383.867194) (xy 128.687576 -383.86004)
			(xy 128.665803 -383.834375) (xy 128.627851 -383.778792) (xy 128.596815 -383.71907) (xy 128.57314 -383.656067)
			(xy 128.557165 -383.590686) (xy 128.549119 -383.523864) (xy 128.549117 -383.45656) (xy 128.55716 -383.389738)
			(xy 128.573133 -383.324356) (xy 128.596805 -383.261352) (xy 128.627839 -383.201629) (xy 128.665788 -383.146044)
			(xy 128.687576 -383.120392) (xy 128.693356 -383.113235) (xy 128.699881 -383.096054) (xy 128.700276 -383.086864)
			(xy 128.700276 -382.593342) (xy 128.699851 -382.584156) (xy 128.693348 -382.566971) (xy 128.687576 -382.559814)
			(xy 128.665777 -382.53417) (xy 128.627826 -382.478584) (xy 128.596792 -382.418859) (xy 128.573118 -382.355853)
			(xy 128.557144 -382.29047) (xy 128.5491 -382.223646) (xy 125.271038 -382.223646) (xy 125.262995 -382.290466)
			(xy 125.247025 -382.355847) (xy 125.223354 -382.418851) (xy 125.192324 -382.478574) (xy 125.154378 -382.534161)
			(xy 125.132592 -382.559814) (xy 125.126806 -382.566967) (xy 125.120285 -382.584151) (xy 125.119892 -382.593342)
			(xy 125.119892 -383.086864) (xy 125.120321 -383.096049) (xy 125.126822 -383.113234) (xy 125.132592 -383.120392)
			(xy 125.154394 -383.146032) (xy 125.192341 -383.201621) (xy 125.223372 -383.261346) (xy 125.24683 -383.323787)
			(xy 126.348923 -383.323787) (xy 126.348926 -383.256359) (xy 126.357006 -383.189418) (xy 126.373047 -383.123926)
			(xy 126.396816 -383.060828) (xy 126.427973 -383.001031) (xy 126.466069 -382.945397) (xy 126.487936 -382.919732)
			(xy 126.493749 -382.912598) (xy 126.500253 -382.895399) (xy 126.500636 -382.886204) (xy 126.500636 -382.728724)
			(xy 126.501036 -382.718599) (xy 126.508783 -382.699889) (xy 126.523105 -382.685572) (xy 126.541818 -382.677832)
			(xy 126.551944 -382.677416) (xy 127.268224 -382.677416) (xy 127.278336 -382.677866) (xy 127.297018 -382.685614)
			(xy 127.311313 -382.699922) (xy 127.319044 -382.718611) (xy 127.319532 -382.728724) (xy 127.319532 -382.886204)
			(xy 127.319956 -382.895389) (xy 127.326462 -382.912573) (xy 127.332232 -382.919732) (xy 127.354059 -382.945427)
			(xy 127.392147 -383.001058) (xy 127.423298 -383.06085) (xy 127.447062 -383.123943) (xy 127.463099 -383.189428)
			(xy 127.471178 -383.256363) (xy 127.471181 -383.323783) (xy 127.463109 -383.390718) (xy 127.447078 -383.456205)
			(xy 127.42332 -383.5193) (xy 127.392175 -383.579096) (xy 127.354093 -383.63473) (xy 127.332232 -383.660396)
			(xy 127.326446 -383.667549) (xy 127.319927 -383.684734) (xy 127.319532 -383.693924) (xy 127.319532 -384.186176)
			(xy 127.319969 -384.19536) (xy 127.326466 -384.212544) (xy 127.332232 -384.219704) (xy 127.35413 -384.245341)
			(xy 127.392216 -384.30098) (xy 127.423363 -384.36078) (xy 127.447124 -384.423881) (xy 127.463156 -384.489373)
			(xy 127.471228 -384.556314) (xy 127.471225 -384.62374) (xy 127.463146 -384.69068) (xy 127.447108 -384.756171)
			(xy 127.423341 -384.819269) (xy 127.392188 -384.879066) (xy 127.354097 -384.934702) (xy 127.332232 -384.960368)
			(xy 127.326416 -384.967499) (xy 127.319915 -384.984701) (xy 127.319532 -384.993896) (xy 127.319532 -385.151376)
			(xy 127.318996 -385.161479) (xy 127.311272 -385.180151) (xy 127.296991 -385.194445) (xy 127.278327 -385.202187)
			(xy 127.268224 -385.202684) (xy 126.551944 -385.202684) (xy 126.541822 -385.202247) (xy 126.523117 -385.194511)
			(xy 126.5088 -385.1802) (xy 126.501056 -385.161497) (xy 126.500636 -385.151376) (xy 126.500636 -384.993896)
			(xy 126.50022 -384.98471) (xy 126.49371 -384.967526) (xy 126.487936 -384.960368) (xy 126.466106 -384.934674)
			(xy 126.428014 -384.879045) (xy 126.39686 -384.819253) (xy 126.373092 -384.756159) (xy 126.357053 -384.690673)
			(xy 126.348974 -384.623738) (xy 126.34897 -384.556316) (xy 126.357043 -384.48938) (xy 126.373076 -384.423892)
			(xy 126.396838 -384.360797) (xy 126.427986 -384.301002) (xy 126.466073 -384.245369) (xy 126.487936 -384.219704)
			(xy 126.493718 -384.212549) (xy 126.50024 -384.195366) (xy 126.500636 -384.186176) (xy 126.500636 -383.693924)
			(xy 126.500206 -383.684739) (xy 126.493705 -383.667555) (xy 126.487936 -383.660396) (xy 126.466035 -383.634761)
			(xy 126.427945 -383.579123) (xy 126.396794 -383.519323) (xy 126.373031 -383.456222) (xy 126.356996 -383.390729)
			(xy 126.348923 -383.323787) (xy 125.24683 -383.323787) (xy 125.247042 -383.324352) (xy 125.263013 -383.389736)
			(xy 125.271056 -383.456559) (xy 125.271054 -383.523865) (xy 125.263009 -383.590688) (xy 125.247035 -383.656071)
			(xy 125.223362 -383.719076) (xy 125.192328 -383.7788) (xy 125.15438 -383.834387) (xy 125.132592 -383.86004)
			(xy 125.126795 -383.867185) (xy 125.120281 -383.884376) (xy 125.119892 -383.893568) (xy 125.119892 -384.051556)
			(xy 125.119442 -384.061708) (xy 125.11166 -384.080461) (xy 125.097271 -384.094786) (xy 125.078484 -384.102486)
			(xy 125.06833 -384.102864) (xy 124.35205 -384.102864) (xy 124.341927 -384.102333) (xy 124.323208 -384.094622)
			(xy 124.30885 -384.080349) (xy 124.301028 -384.061676) (xy 124.300488 -384.051556) (xy 124.300488 -383.893568)
			(xy 124.300096 -383.884379) (xy 124.29357 -383.867194) (xy 124.287788 -383.86004) (xy 124.266015 -383.834376)
			(xy 124.228062 -383.778792) (xy 124.197025 -383.719071) (xy 124.17335 -383.656068) (xy 124.157374 -383.590686)
			(xy 124.149328 -383.523864) (xy 124.149326 -383.45656) (xy 124.15737 -383.389737) (xy 124.173342 -383.324355)
			(xy 124.197016 -383.261351) (xy 124.22805 -383.201629) (xy 124.266 -383.146043) (xy 124.287788 -383.120392)
			(xy 124.293569 -383.113236) (xy 124.300093 -383.096054) (xy 124.300488 -383.086864) (xy 124.300488 -382.593342)
			(xy 124.30006 -382.584157) (xy 124.293559 -382.566972) (xy 124.287788 -382.559814) (xy 124.265989 -382.534171)
			(xy 124.228037 -382.478584) (xy 124.197002 -382.41886) (xy 124.173327 -382.355854) (xy 124.157354 -382.29047)
			(xy 124.14931 -382.223646) (xy 120.87127 -382.223646) (xy 120.87127 -382.223704) (xy 120.863195 -382.290642)
			(xy 120.84716 -382.35613) (xy 120.823397 -382.419227) (xy 120.792247 -382.479023) (xy 120.75416 -382.534657)
			(xy 120.732296 -382.560322) (xy 120.726507 -382.567473) (xy 120.719988 -382.584659) (xy 120.719596 -382.59385)
			(xy 120.719596 -383.086356) (xy 120.720028 -383.095541) (xy 120.726527 -383.112725) (xy 120.732296 -383.119884)
			(xy 120.754176 -383.145536) (xy 120.792264 -383.201173) (xy 120.823415 -383.26097) (xy 120.847049 -383.323727)
			(xy 121.949155 -383.323727) (xy 121.949158 -383.256419) (xy 121.957206 -383.189594) (xy 121.973182 -383.12421)
			(xy 121.996859 -383.061204) (xy 122.027897 -383.001479) (xy 122.06585 -382.945892) (xy 122.08764 -382.92024)
			(xy 122.09345 -382.913104) (xy 122.099955 -382.895906) (xy 122.10034 -382.886712) (xy 122.10034 -382.728724)
			(xy 122.100742 -382.718566) (xy 122.108537 -382.699807) (xy 122.122941 -382.685481) (xy 122.141742 -382.677788)
			(xy 122.151902 -382.677416) (xy 122.868182 -382.677416) (xy 122.878305 -382.677941) (xy 122.897021 -382.685658)
			(xy 122.911377 -382.699932) (xy 122.919201 -382.718604) (xy 122.919744 -382.728724) (xy 122.919744 -382.886712)
			(xy 122.920161 -382.895898) (xy 122.926671 -382.913082) (xy 122.932444 -382.92024) (xy 122.954197 -382.945921)
			(xy 122.992148 -383.001503) (xy 123.023183 -383.061222) (xy 123.046859 -383.124223) (xy 123.062835 -383.189602)
			(xy 123.070882 -383.256422) (xy 123.070886 -383.323724) (xy 123.062845 -383.390545) (xy 123.046875 -383.455925)
			(xy 123.023206 -383.518928) (xy 122.992176 -383.57865) (xy 122.95423 -383.634236) (xy 122.932444 -383.659888)
			(xy 122.926621 -383.667014) (xy 122.920124 -383.684219) (xy 122.919744 -383.693416) (xy 122.919744 -384.186684)
			(xy 122.920174 -384.195869) (xy 122.926675 -384.213053) (xy 122.932444 -384.220212) (xy 122.954268 -384.245835)
			(xy 122.992217 -384.301425) (xy 123.023249 -384.361152) (xy 123.046921 -384.424161) (xy 123.062892 -384.489547)
			(xy 123.070933 -384.556373) (xy 123.07093 -384.623681) (xy 123.062882 -384.690507) (xy 123.046905 -384.755891)
			(xy 123.023227 -384.818897) (xy 122.992189 -384.878622) (xy 122.954235 -384.934208) (xy 122.932444 -384.95986)
			(xy 122.926633 -384.966994) (xy 122.920128 -384.984193) (xy 122.919744 -384.993388) (xy 122.919744 -385.151376)
			(xy 122.91926 -385.161523) (xy 122.91148 -385.180267) (xy 122.897103 -385.194589) (xy 122.878331 -385.202298)
			(xy 122.868182 -385.202684) (xy 122.151902 -385.202684) (xy 122.141778 -385.202172) (xy 122.123062 -385.19445)
			(xy 122.108706 -385.180171) (xy 122.100883 -385.161497) (xy 122.10034 -385.151376) (xy 122.10034 -384.993388)
			(xy 122.099927 -384.984201) (xy 122.093414 -384.967017) (xy 122.08764 -384.95986) (xy 122.065888 -384.934179)
			(xy 122.027938 -384.878596) (xy 121.996903 -384.818877) (xy 121.973228 -384.755876) (xy 121.957253 -384.690498)
			(xy 121.949206 -384.623678) (xy 121.949202 -384.556376) (xy 121.957243 -384.489556) (xy 121.973212 -384.424176)
			(xy 121.996881 -384.361173) (xy 122.02791 -384.30145) (xy 122.065855 -384.245864) (xy 122.08764 -384.220212)
			(xy 122.093461 -384.213085) (xy 122.09996 -384.19588) (xy 122.10034 -384.186684) (xy 122.10034 -383.693416)
			(xy 122.099913 -383.684231) (xy 122.09341 -383.667047) (xy 122.08764 -383.659888) (xy 122.065817 -383.634265)
			(xy 122.027869 -383.578674) (xy 121.996837 -383.518947) (xy 121.973166 -383.455939) (xy 121.957196 -383.390553)
			(xy 121.949155 -383.323727) (xy 120.847049 -383.323727) (xy 120.847178 -383.324069) (xy 120.863212 -383.38956)
			(xy 120.871287 -383.4565) (xy 120.871286 -383.523925) (xy 120.863208 -383.590864) (xy 120.847171 -383.656354)
			(xy 120.823405 -383.719452) (xy 120.792252 -383.779248) (xy 120.754161 -383.834883) (xy 120.732296 -383.860548)
			(xy 120.726496 -383.867691) (xy 120.719984 -383.884883) (xy 120.719596 -383.894076) (xy 120.719596 -384.051556)
			(xy 120.719148 -384.061676) (xy 120.711413 -384.080379) (xy 120.697106 -384.094695) (xy 120.678408 -384.102441)
			(xy 120.668288 -384.102864) (xy 119.952008 -384.102864) (xy 119.941882 -384.102477) (xy 119.923171 -384.094724)
			(xy 119.908855 -384.080399) (xy 119.901116 -384.061683) (xy 119.9007 -384.051556) (xy 119.9007 -383.894076)
			(xy 119.900302 -383.884888) (xy 119.89378 -383.867703) (xy 119.888 -383.860548) (xy 119.866152 -383.83487)
			(xy 119.828063 -383.779237) (xy 119.796911 -383.719443) (xy 119.773146 -383.656348) (xy 119.75711 -383.59086)
			(xy 119.749032 -383.523923) (xy 119.749031 -383.456501) (xy 119.757105 -383.389564) (xy 119.773139 -383.324075)
			(xy 119.796901 -383.260979) (xy 119.82805 -383.201184) (xy 119.866137 -383.145549) (xy 119.888 -383.119884)
			(xy 119.893786 -383.112731) (xy 119.900307 -383.095547) (xy 119.9007 -383.086356) (xy 119.9007 -382.59385)
			(xy 119.900266 -382.584665) (xy 119.893769 -382.567481) (xy 119.888 -382.560322) (xy 119.866126 -382.534665)
			(xy 119.828038 -382.479029) (xy 119.796888 -382.419232) (xy 119.773124 -382.356134) (xy 119.757089 -382.290644)
			(xy 119.749014 -382.223705) (xy 116.470967 -382.223705) (xy 116.46293 -382.290468) (xy 116.446957 -382.35585)
			(xy 116.423283 -382.418855) (xy 116.392248 -382.478577) (xy 116.354297 -382.534163) (xy 116.332508 -382.559814)
			(xy 116.326724 -382.566968) (xy 116.320202 -382.584152) (xy 116.319808 -382.593342) (xy 116.319808 -383.086864)
			(xy 116.320234 -383.09605) (xy 116.326736 -383.113234) (xy 116.332508 -383.120392) (xy 116.354313 -383.146031)
			(xy 116.392265 -383.201618) (xy 116.4233 -383.261343) (xy 116.446764 -383.323787) (xy 117.548835 -383.323787)
			(xy 117.548838 -383.256359) (xy 117.556918 -383.189418) (xy 117.572959 -383.123926) (xy 117.59673 -383.060827)
			(xy 117.627888 -383.00103) (xy 117.665984 -382.945396) (xy 117.687852 -382.919732) (xy 117.693666 -382.9126)
			(xy 117.700169 -382.895399) (xy 117.700552 -382.886204) (xy 117.700552 -382.728724) (xy 117.701103 -382.718623)
			(xy 117.708824 -382.699954) (xy 117.7231 -382.68566) (xy 117.741759 -382.677916) (xy 117.75186 -382.677416)
			(xy 118.46814 -382.677416) (xy 118.478253 -382.677853) (xy 118.496935 -382.685607) (xy 118.511229 -382.699918)
			(xy 118.51896 -382.71861) (xy 118.519448 -382.728724) (xy 118.519448 -382.886204) (xy 118.519868 -382.89539)
			(xy 118.526376 -382.912574) (xy 118.532148 -382.919732) (xy 118.553978 -382.945426) (xy 118.592072 -383.001055)
			(xy 118.623227 -383.060847) (xy 118.646995 -383.12394) (xy 118.663035 -383.189426) (xy 118.671114 -383.256362)
			(xy 118.671118 -383.323784) (xy 118.663045 -383.390721) (xy 118.647011 -383.456208) (xy 118.623249 -383.519304)
			(xy 118.592099 -383.579099) (xy 118.554012 -383.634732) (xy 118.532148 -383.660396) (xy 118.526364 -383.66755)
			(xy 118.519843 -383.684734) (xy 118.519448 -383.693924) (xy 118.519448 -384.186176) (xy 118.519881 -384.195361)
			(xy 118.52638 -384.212545) (xy 118.532148 -384.219704) (xy 118.554049 -384.245339) (xy 118.59214 -384.300977)
			(xy 118.623292 -384.360777) (xy 118.647057 -384.423878) (xy 118.663091 -384.489371) (xy 118.671165 -384.556313)
			(xy 118.671162 -384.623741) (xy 118.663082 -384.690682) (xy 118.647041 -384.756174) (xy 118.62327 -384.819273)
			(xy 118.592112 -384.87907) (xy 118.554016 -384.934704) (xy 118.532148 -384.960368) (xy 118.526334 -384.9675)
			(xy 118.519831 -384.984701) (xy 118.519448 -384.993896) (xy 118.519448 -385.151376) (xy 118.518897 -385.161477)
			(xy 118.511176 -385.180146) (xy 118.4969 -385.19444) (xy 118.478241 -385.202184) (xy 118.46814 -385.202684)
			(xy 117.75186 -385.202684) (xy 117.741747 -385.202247) (xy 117.723065 -385.194493) (xy 117.708771 -385.180182)
			(xy 117.70104 -385.16149) (xy 117.700552 -385.151376) (xy 117.700552 -384.993896) (xy 117.700132 -384.98471)
			(xy 117.693624 -384.967526) (xy 117.687852 -384.960368) (xy 117.666022 -384.934674) (xy 117.627928 -384.879045)
			(xy 117.596773 -384.819253) (xy 117.573005 -384.75616) (xy 117.556965 -384.690674) (xy 117.548886 -384.623738)
			(xy 117.548882 -384.556316) (xy 117.556955 -384.489379) (xy 117.572989 -384.423892) (xy 117.596751 -384.360796)
			(xy 117.627901 -384.301001) (xy 117.665988 -384.245368) (xy 117.687852 -384.219704) (xy 117.693636 -384.21255)
			(xy 117.700157 -384.195366) (xy 117.700552 -384.186176) (xy 117.700552 -383.693924) (xy 117.700119 -383.684739)
			(xy 117.69362 -383.667555) (xy 117.687852 -383.660396) (xy 117.665951 -383.634761) (xy 117.62786 -383.579123)
			(xy 117.596708 -383.519323) (xy 117.572943 -383.456222) (xy 117.556909 -383.390729) (xy 117.548835 -383.323787)
			(xy 116.446764 -383.323787) (xy 116.446975 -383.324349) (xy 116.462948 -383.389733) (xy 116.470992 -383.456558)
			(xy 116.47099 -383.523866) (xy 116.462944 -383.59069) (xy 116.446967 -383.656074) (xy 116.423291 -383.719079)
			(xy 116.392252 -383.778803) (xy 116.354298 -383.834389) (xy 116.332508 -383.86004) (xy 116.326713 -383.867186)
			(xy 116.320197 -383.884376) (xy 116.319808 -383.893568) (xy 116.319808 -384.051556) (xy 116.319342 -384.061706)
			(xy 116.311563 -384.080456) (xy 116.297179 -384.094781) (xy 116.278398 -384.102483) (xy 116.268246 -384.102864)
			(xy 115.551966 -384.102864) (xy 115.541838 -384.102401) (xy 115.523116 -384.094663) (xy 115.508761 -384.08037)
			(xy 115.500943 -384.061682) (xy 115.500404 -384.051556) (xy 115.500404 -383.893568) (xy 115.500009 -383.884379)
			(xy 115.493485 -383.867195) (xy 115.487704 -383.86004) (xy 115.465933 -383.834374) (xy 115.427986 -383.778789)
			(xy 115.396954 -383.719067) (xy 115.373282 -383.656064) (xy 115.357309 -383.590684) (xy 115.349264 -383.523864)
			(xy 115.349262 -383.45656) (xy 115.357305 -383.38974) (xy 115.373275 -383.324359) (xy 115.396944 -383.261355)
			(xy 115.427974 -383.201632) (xy 115.465918 -383.146045) (xy 115.487704 -383.120392) (xy 115.493487 -383.113237)
			(xy 115.50001 -383.096054) (xy 115.500404 -383.086864) (xy 115.500404 -382.593342) (xy 115.499973 -382.584157)
			(xy 115.493474 -382.566973) (xy 115.487704 -382.559814) (xy 115.465908 -382.534169) (xy 115.427961 -382.478581)
			(xy 115.39693 -382.418856) (xy 115.37326 -382.355851) (xy 115.357288 -382.290468) (xy 115.349246 -382.223645)
			(xy 90.070711 -382.223645) (xy 90.062667 -382.290467) (xy 90.046695 -382.355848) (xy 90.023023 -382.418852)
			(xy 89.991991 -382.478576) (xy 89.954043 -382.534162) (xy 89.932256 -382.559814) (xy 89.926465 -382.566963)
			(xy 89.919948 -382.584151) (xy 89.919556 -382.593342) (xy 89.919556 -383.086864) (xy 89.919994 -383.096048)
			(xy 89.926489 -383.113232) (xy 89.932256 -383.120392) (xy 89.95406 -383.146031) (xy 89.992008 -383.201619)
			(xy 90.023041 -383.261345) (xy 90.046478 -383.323726) (xy 91.149124 -383.323726) (xy 91.149128 -383.256419)
			(xy 91.157175 -383.189595) (xy 91.17315 -383.124211) (xy 91.196825 -383.061205) (xy 91.227861 -383.001481)
			(xy 91.265811 -382.945893) (xy 91.2876 -382.92024) (xy 91.293405 -382.9131) (xy 91.299914 -382.895906)
			(xy 91.3003 -382.886712) (xy 91.3003 -382.728724) (xy 91.300741 -382.718571) (xy 91.308529 -382.699819)
			(xy 91.32292 -382.685495) (xy 91.341708 -382.677795) (xy 91.351862 -382.677416) (xy 92.068142 -382.677416)
			(xy 92.078268 -382.677891) (xy 92.096986 -382.685629) (xy 92.11134 -382.699918) (xy 92.119162 -382.7186)
			(xy 92.119704 -382.728724) (xy 92.119704 -382.886712) (xy 92.120108 -382.8959) (xy 92.126626 -382.913084)
			(xy 92.132404 -382.92024) (xy 92.154155 -382.945922) (xy 92.192102 -383.001505) (xy 92.223135 -383.061225)
			(xy 92.246808 -383.124225) (xy 92.262782 -383.189604) (xy 92.270828 -383.256422) (xy 92.270831 -383.323724)
			(xy 92.262791 -383.390543) (xy 92.246824 -383.455923) (xy 92.223157 -383.518926) (xy 92.19213 -383.578648)
			(xy 92.154188 -383.634235) (xy 92.132404 -383.659888) (xy 92.126588 -383.66702) (xy 92.120085 -383.68422)
			(xy 92.119704 -383.693416) (xy 92.119704 -384.186684) (xy 92.120121 -384.19587) (xy 92.12663 -384.213055)
			(xy 92.132404 -384.220212) (xy 92.154226 -384.245836) (xy 92.192171 -384.301427) (xy 92.2232 -384.361155)
			(xy 92.246869 -384.424163) (xy 92.262838 -384.489548) (xy 92.270879 -384.556374) (xy 92.270875 -384.623681)
			(xy 92.262828 -384.690505) (xy 92.246853 -384.755889) (xy 92.223178 -384.818894) (xy 92.192143 -384.878619)
			(xy 92.154193 -384.934207) (xy 92.132404 -384.95986) (xy 92.1266 -384.967) (xy 92.12009 -384.984194)
			(xy 92.119704 -384.993388) (xy 92.119704 -385.151376) (xy 92.119259 -385.161528) (xy 92.111472 -385.180279)
			(xy 92.097082 -385.194603) (xy 92.078296 -385.202305) (xy 92.068142 -385.202684) (xy 91.351862 -385.202684)
			(xy 91.341736 -385.202205) (xy 91.323018 -385.194469) (xy 91.308664 -385.180181) (xy 91.300842 -385.1615)
			(xy 91.3003 -385.151376) (xy 91.3003 -384.993388) (xy 91.299895 -384.9842) (xy 91.293378 -384.967016)
			(xy 91.2876 -384.95986) (xy 91.265849 -384.934178) (xy 91.227901 -384.878595) (xy 91.196869 -384.818875)
			(xy 91.173196 -384.755875) (xy 91.157221 -384.690497) (xy 91.149175 -384.623678) (xy 91.149172 -384.556376)
			(xy 91.157212 -384.489557) (xy 91.17318 -384.424177) (xy 91.196847 -384.361174) (xy 91.227874 -384.301451)
			(xy 91.265816 -384.245865) (xy 91.2876 -384.220212) (xy 91.293416 -384.213081) (xy 91.299919 -384.19588)
			(xy 91.3003 -384.186684) (xy 91.3003 -383.693416) (xy 91.299882 -383.68423) (xy 91.293374 -383.667045)
			(xy 91.2876 -383.659888) (xy 91.265778 -383.634264) (xy 91.227833 -383.578673) (xy 91.196803 -383.518945)
			(xy 91.173134 -383.455937) (xy 91.157165 -383.390552) (xy 91.149124 -383.323726) (xy 90.046478 -383.323726)
			(xy 90.046713 -383.324351) (xy 90.062685 -383.389735) (xy 90.070728 -383.456559) (xy 90.070727 -383.523865)
			(xy 90.062681 -383.590689) (xy 90.046706 -383.656072) (xy 90.023031 -383.719077) (xy 89.991996 -383.778801)
			(xy 89.954045 -383.834388) (xy 89.932256 -383.86004) (xy 89.926454 -383.867181) (xy 89.919944 -383.884375)
			(xy 89.919556 -383.893568) (xy 89.919556 -384.051556) (xy 89.919043 -384.0617) (xy 89.911273 -384.080441)
			(xy 89.896905 -384.094764) (xy 89.87814 -384.102475) (xy 89.867994 -384.102864) (xy 89.151714 -384.102864)
			(xy 89.141589 -384.102362) (xy 89.122869 -384.09464) (xy 89.108512 -384.080358) (xy 89.100692 -384.061679)
			(xy 89.100152 -384.051556) (xy 89.100152 -383.893568) (xy 89.099745 -383.884381) (xy 89.093228 -383.867197)
			(xy 89.087452 -383.86004) (xy 89.06568 -383.834375) (xy 89.02773 -383.778791) (xy 88.996695 -383.719069)
			(xy 88.973021 -383.656066) (xy 88.957046 -383.590685) (xy 88.949001 -383.523864) (xy 88.948999 -383.45656)
			(xy 88.957042 -383.389738) (xy 88.973014 -383.324357) (xy 88.996685 -383.261353) (xy 89.027717 -383.20163)
			(xy 89.065665 -383.146044) (xy 89.087452 -383.120392) (xy 89.093241 -383.113242) (xy 89.099759 -383.096055)
			(xy 89.100152 -383.086864) (xy 89.100152 -382.593342) (xy 89.09971 -382.584158) (xy 89.093217 -382.566975)
			(xy 89.087452 -382.559814) (xy 89.065654 -382.53417) (xy 89.027704 -382.478583) (xy 88.996671 -382.418858)
			(xy 88.972998 -382.355853) (xy 88.957025 -382.290469) (xy 88.948982 -382.223646) (xy 85.670943 -382.223646)
			(xy 85.670943 -382.223704) (xy 85.662867 -382.290643) (xy 85.646832 -382.356132) (xy 85.623067 -382.419228)
			(xy 85.591915 -382.479024) (xy 85.553825 -382.534657) (xy 85.53196 -382.560322) (xy 85.526167 -382.567469)
			(xy 85.519651 -382.584658) (xy 85.51926 -382.59385) (xy 85.51926 -383.086356) (xy 85.5197 -383.09554)
			(xy 85.526194 -383.112724) (xy 85.53196 -383.119884) (xy 85.553841 -383.145536) (xy 85.591932 -383.201171)
			(xy 85.623084 -383.260969) (xy 85.646743 -383.323786) (xy 86.748805 -383.323786) (xy 86.748808 -383.25636)
			(xy 86.756888 -383.189419) (xy 86.772927 -383.123927) (xy 86.796696 -383.060829) (xy 86.827852 -383.001032)
			(xy 86.865945 -382.945397) (xy 86.887812 -382.919732) (xy 86.893621 -382.912596) (xy 86.900128 -382.895398)
			(xy 86.900512 -382.886204) (xy 86.900512 -382.728724) (xy 86.900936 -382.718602) (xy 86.908678 -382.699896)
			(xy 86.922993 -382.685581) (xy 86.941698 -382.677837) (xy 86.95182 -382.677416) (xy 87.6681 -382.677416)
			(xy 87.678224 -382.677816) (xy 87.696931 -382.685568) (xy 87.711246 -382.699889) (xy 87.718988 -382.718599)
			(xy 87.719408 -382.728724) (xy 87.719408 -382.886204) (xy 87.719815 -382.895392) (xy 87.726331 -382.912576)
			(xy 87.732108 -382.919732) (xy 87.753936 -382.945427) (xy 87.792026 -383.001057) (xy 87.823177 -383.060849)
			(xy 87.846943 -383.123942) (xy 87.862981 -383.189428) (xy 87.87106 -383.256363) (xy 87.871063 -383.323783)
			(xy 87.862991 -383.390719) (xy 87.846959 -383.456206) (xy 87.8232 -383.519301) (xy 87.792053 -383.579096)
			(xy 87.75397 -383.634731) (xy 87.732108 -383.660396) (xy 87.726332 -383.667556) (xy 87.719805 -383.684735)
			(xy 87.719408 -383.693924) (xy 87.719408 -384.186176) (xy 87.719828 -384.195362) (xy 87.726335 -384.212547)
			(xy 87.732108 -384.219704) (xy 87.754007 -384.24534) (xy 87.792094 -384.300979) (xy 87.823243 -384.360779)
			(xy 87.847005 -384.42388) (xy 87.863037 -384.489373) (xy 87.87111 -384.556314) (xy 87.871107 -384.62374)
			(xy 87.863028 -384.690681) (xy 87.846989 -384.756172) (xy 87.823221 -384.81927) (xy 87.792066 -384.879067)
			(xy 87.753974 -384.934703) (xy 87.732108 -384.960368) (xy 87.726301 -384.967506) (xy 87.719792 -384.984702)
			(xy 87.719408 -384.993896) (xy 87.719408 -385.151376) (xy 87.718965 -385.161496) (xy 87.711226 -385.180198)
			(xy 87.696918 -385.194512) (xy 87.67822 -385.20226) (xy 87.6681 -385.202684) (xy 86.95182 -385.202684)
			(xy 86.941697 -385.202267) (xy 86.922991 -385.194523) (xy 86.908675 -385.180206) (xy 86.900932 -385.161499)
			(xy 86.900512 -385.151376) (xy 86.900512 -384.993896) (xy 86.900101 -384.984709) (xy 86.893587 -384.967525)
			(xy 86.887812 -384.960368) (xy 86.865983 -384.934674) (xy 86.827892 -384.879044) (xy 86.796739 -384.819252)
			(xy 86.772973 -384.756158) (xy 86.756934 -384.690673) (xy 86.748855 -384.623738) (xy 86.748852 -384.556316)
			(xy 86.756925 -384.48938) (xy 86.772957 -384.423893) (xy 86.796717 -384.360798) (xy 86.827865 -384.301003)
			(xy 86.86595 -384.245369) (xy 86.887812 -384.219704) (xy 86.893591 -384.212546) (xy 86.900116 -384.195365)
			(xy 86.900512 -384.186176) (xy 86.900512 -383.693924) (xy 86.900088 -383.684738) (xy 86.893583 -383.667554)
			(xy 86.887812 -383.660396) (xy 86.865912 -383.63476) (xy 86.827824 -383.579122) (xy 86.796674 -383.519322)
			(xy 86.772911 -383.456221) (xy 86.756878 -383.390728) (xy 86.748805 -383.323786) (xy 85.646743 -383.323786)
			(xy 85.646849 -383.324068) (xy 85.662885 -383.389559) (xy 85.67096 -383.456499) (xy 85.670959 -383.523925)
			(xy 85.662881 -383.590865) (xy 85.646842 -383.656355) (xy 85.623074 -383.719453) (xy 85.59192 -383.77925)
			(xy 85.553826 -383.834883) (xy 85.53196 -383.860548) (xy 85.526156 -383.867687) (xy 85.519647 -383.884883)
			(xy 85.51926 -383.894076) (xy 85.51926 -384.051556) (xy 85.518847 -384.061681) (xy 85.511106 -384.080391)
			(xy 85.496787 -384.094708) (xy 85.478077 -384.102448) (xy 85.467952 -384.102864) (xy 84.751672 -384.102864)
			(xy 84.741543 -384.102506) (xy 84.722832 -384.094742) (xy 84.708517 -384.080407) (xy 84.70078 -384.061685)
			(xy 84.700364 -384.051556) (xy 84.700364 -383.894076) (xy 84.699951 -383.884889) (xy 84.693438 -383.867706)
			(xy 84.687664 -383.860548) (xy 84.665817 -383.834869) (xy 84.62773 -383.779236) (xy 84.596581 -383.719441)
			(xy 84.572817 -383.656346) (xy 84.556782 -383.590859) (xy 84.548705 -383.523923) (xy 84.548704 -383.456501)
			(xy 84.556778 -383.389565) (xy 84.57281 -383.324077) (xy 84.596571 -383.260981) (xy 84.627718 -383.201185)
			(xy 84.665802 -383.14555) (xy 84.687664 -383.119884) (xy 84.693458 -383.112737) (xy 84.699972 -383.095548)
			(xy 84.700364 -383.086356) (xy 84.700364 -382.59385) (xy 84.699916 -382.584667) (xy 84.693427 -382.567483)
			(xy 84.687664 -382.560322) (xy 84.665791 -382.534664) (xy 84.627705 -382.479028) (xy 84.596557 -382.41923)
			(xy 84.572795 -382.356132) (xy 84.556761 -382.290643) (xy 84.548687 -382.223704) (xy 81.271152 -382.223704)
			(xy 81.263076 -382.290642) (xy 81.247041 -382.356131) (xy 81.223277 -382.419228) (xy 81.192126 -382.479023)
			(xy 81.154036 -382.534657) (xy 81.132172 -382.560322) (xy 81.12638 -382.56747) (xy 81.119863 -382.584659)
			(xy 81.119472 -382.59385) (xy 81.119472 -383.086356) (xy 81.11991 -383.09554) (xy 81.126405 -383.112724)
			(xy 81.132172 -383.119884) (xy 81.154053 -383.145536) (xy 81.192143 -383.201172) (xy 81.223294 -383.260969)
			(xy 81.246931 -383.323727) (xy 82.349036 -383.323727) (xy 82.34904 -383.256419) (xy 82.357087 -383.189595)
			(xy 82.373063 -383.124211) (xy 82.396739 -383.061205) (xy 82.427775 -383.00148) (xy 82.465727 -382.945892)
			(xy 82.487516 -382.92024) (xy 82.493322 -382.913102) (xy 82.499831 -382.895906) (xy 82.500216 -382.886712)
			(xy 82.500216 -382.728724) (xy 82.500636 -382.718601) (xy 82.508379 -382.699895) (xy 82.522695 -382.685579)
			(xy 82.541401 -382.677836) (xy 82.551524 -382.677416) (xy 83.268058 -382.677416) (xy 83.278179 -382.67796)
			(xy 83.296895 -382.68567) (xy 83.311252 -382.699938) (xy 83.319076 -382.718606) (xy 83.31962 -382.728724)
			(xy 83.31962 -382.886712) (xy 83.32002 -382.8959) (xy 83.32654 -382.913085) (xy 83.33232 -382.92024)
			(xy 83.354074 -382.945921) (xy 83.392026 -383.001502) (xy 83.423063 -383.061221) (xy 83.44674 -383.124222)
			(xy 83.462717 -383.189601) (xy 83.470764 -383.256421) (xy 83.470767 -383.323724) (xy 83.462726 -383.390545)
			(xy 83.446756 -383.455926) (xy 83.423085 -383.518929) (xy 83.392054 -383.578651) (xy 83.354107 -383.634236)
			(xy 83.33232 -383.659888) (xy 83.326506 -383.667021) (xy 83.320001 -383.684221) (xy 83.31962 -383.693416)
			(xy 83.31962 -384.186684) (xy 83.320033 -384.195871) (xy 83.326544 -384.213056) (xy 83.33232 -384.220212)
			(xy 83.354144 -384.245835) (xy 83.392095 -384.301424) (xy 83.423129 -384.361152) (xy 83.446801 -384.42416)
			(xy 83.462773 -384.489546) (xy 83.470815 -384.556373) (xy 83.470812 -384.623681) (xy 83.462763 -384.690507)
			(xy 83.446785 -384.755892) (xy 83.423107 -384.818898) (xy 83.392067 -384.878622) (xy 83.354111 -384.934208)
			(xy 83.33232 -384.95986) (xy 83.326518 -384.967001) (xy 83.320006 -384.984195) (xy 83.31962 -384.993388)
			(xy 83.31962 -385.151376) (xy 83.319165 -385.161494) (xy 83.311428 -385.180194) (xy 83.297124 -385.194508)
			(xy 83.27843 -385.202258) (xy 83.268312 -385.202684) (xy 82.551778 -385.202684) (xy 82.541653 -385.202192)
			(xy 82.522936 -385.194462) (xy 82.508581 -385.180178) (xy 82.500758 -385.161499) (xy 82.500216 -385.151376)
			(xy 82.500216 -384.993388) (xy 82.499808 -384.984201) (xy 82.493293 -384.967016) (xy 82.487516 -384.95986)
			(xy 82.465765 -384.934178) (xy 82.427816 -384.878595) (xy 82.396783 -384.818876) (xy 82.373109 -384.755875)
			(xy 82.357134 -384.690497) (xy 82.349088 -384.623678) (xy 82.349084 -384.556376) (xy 82.357125 -384.489556)
			(xy 82.373093 -384.424177) (xy 82.396761 -384.361174) (xy 82.427788 -384.301451) (xy 82.465731 -384.245865)
			(xy 82.487516 -384.220212) (xy 82.493334 -384.213082) (xy 82.499835 -384.19588) (xy 82.500216 -384.186684)
			(xy 82.500216 -383.693416) (xy 82.499794 -383.68423) (xy 82.493288 -383.667046) (xy 82.487516 -383.659888)
			(xy 82.465694 -383.634265) (xy 82.427747 -383.578674) (xy 82.396717 -383.518946) (xy 82.373047 -383.455938)
			(xy 82.357077 -383.390552) (xy 82.349036 -383.323727) (xy 81.246931 -383.323727) (xy 81.247059 -383.324068)
			(xy 81.263094 -383.389559) (xy 81.271169 -383.456499) (xy 81.271168 -383.523925) (xy 81.26309 -383.590865)
			(xy 81.247052 -383.656355) (xy 81.223285 -383.719453) (xy 81.19213 -383.779249) (xy 81.154038 -383.834883)
			(xy 81.132172 -383.860548) (xy 81.126369 -383.867688) (xy 81.119859 -383.884883) (xy 81.119472 -383.894076)
			(xy 81.119472 -384.051556) (xy 81.119047 -384.061679) (xy 81.111308 -384.080387) (xy 81.096994 -384.094704)
			(xy 81.078287 -384.102446) (xy 81.068164 -384.102864) (xy 80.351884 -384.102864) (xy 80.341756 -384.102496)
			(xy 80.323045 -384.094736) (xy 80.30873 -384.080405) (xy 80.300992 -384.061685) (xy 80.300576 -384.051556)
			(xy 80.300576 -383.894076) (xy 80.300183 -383.884887) (xy 80.293658 -383.867703) (xy 80.287876 -383.860548)
			(xy 80.266029 -383.834869) (xy 80.227941 -383.779236) (xy 80.196791 -383.719442) (xy 80.173027 -383.656347)
			(xy 80.156991 -383.590859) (xy 80.148914 -383.523923) (xy 80.148913 -383.456501) (xy 80.156987 -383.389564)
			(xy 80.17302 -383.324076) (xy 80.196781 -383.26098) (xy 80.227929 -383.201184) (xy 80.266014 -383.14555)
			(xy 80.287876 -383.119884) (xy 80.293659 -383.112729) (xy 80.300183 -383.095546) (xy 80.300576 -383.086356)
			(xy 80.300576 -382.59385) (xy 80.300147 -382.584665) (xy 80.293647 -382.56748) (xy 80.287876 -382.560322)
			(xy 80.266003 -382.534664) (xy 80.227916 -382.479028) (xy 80.196767 -382.419231) (xy 80.173005 -382.356133)
			(xy 80.156971 -382.290643) (xy 80.148896 -382.223704) (xy 76.870825 -382.223704) (xy 76.862789 -382.290466)
			(xy 76.846818 -382.355847) (xy 76.823147 -382.418851) (xy 76.792117 -382.478575) (xy 76.75417 -382.534162)
			(xy 76.732384 -382.559814) (xy 76.726597 -382.566966) (xy 76.720077 -382.584151) (xy 76.719684 -382.593342)
			(xy 76.719684 -383.086864) (xy 76.720115 -383.096049) (xy 76.726615 -383.113233) (xy 76.732384 -383.120392)
			(xy 76.754187 -383.146031) (xy 76.792134 -383.20162) (xy 76.823165 -383.261346) (xy 76.846624 -383.323787)
			(xy 77.948717 -383.323787) (xy 77.94872 -383.256359) (xy 77.9568 -383.189418) (xy 77.97284 -383.123927)
			(xy 77.99661 -383.060828) (xy 78.027766 -383.001031) (xy 78.065861 -382.945397) (xy 78.087728 -382.919732)
			(xy 78.09354 -382.912598) (xy 78.100045 -382.895399) (xy 78.100428 -382.886204) (xy 78.100428 -382.728724)
			(xy 78.100836 -382.7186) (xy 78.108582 -382.699891) (xy 78.122901 -382.685575) (xy 78.141611 -382.677834)
			(xy 78.151736 -382.677416) (xy 78.868016 -382.677416) (xy 78.878142 -382.677803) (xy 78.896849 -382.685559)
			(xy 78.911163 -382.699885) (xy 78.918905 -382.718598) (xy 78.919324 -382.728724) (xy 78.919324 -382.886204)
			(xy 78.919727 -382.895392) (xy 78.926245 -382.912577) (xy 78.932024 -382.919732) (xy 78.953852 -382.945427)
			(xy 78.99194 -383.001058) (xy 79.023091 -383.06085) (xy 79.046856 -383.123943) (xy 79.062893 -383.189428)
			(xy 79.070972 -383.256363) (xy 79.070975 -383.323783) (xy 79.062903 -383.390719) (xy 79.046872 -383.456205)
			(xy 79.023113 -383.519301) (xy 78.991968 -383.579096) (xy 78.953885 -383.63473) (xy 78.932024 -383.660396)
			(xy 78.926249 -383.667557) (xy 78.919721 -383.684735) (xy 78.919324 -383.693924) (xy 78.919324 -384.186176)
			(xy 78.91974 -384.195363) (xy 78.926249 -384.212547) (xy 78.932024 -384.219704) (xy 78.953922 -384.24534)
			(xy 78.992009 -384.30098) (xy 79.023156 -384.36078) (xy 79.046917 -384.423881) (xy 79.06295 -384.489373)
			(xy 79.071022 -384.556314) (xy 79.071019 -384.62374) (xy 79.06294 -384.69068) (xy 79.046901 -384.756171)
			(xy 79.023134 -384.819269) (xy 78.991981 -384.879067) (xy 78.953889 -384.934702) (xy 78.932024 -384.960368)
			(xy 78.926219 -384.967507) (xy 78.919709 -384.984702) (xy 78.919324 -384.993896) (xy 78.919324 -385.151376)
			(xy 78.918865 -385.161494) (xy 78.911129 -385.180193) (xy 78.896826 -385.194507) (xy 78.878134 -385.202257)
			(xy 78.868016 -385.202684) (xy 78.151736 -385.202684) (xy 78.141614 -385.202254) (xy 78.122908 -385.194515)
			(xy 78.108592 -385.180202) (xy 78.100848 -385.161498) (xy 78.100428 -385.151376) (xy 78.100428 -384.993896)
			(xy 78.100014 -384.984709) (xy 78.093502 -384.967525) (xy 78.087728 -384.960368) (xy 78.065898 -384.934674)
			(xy 78.027807 -384.879044) (xy 77.996653 -384.819252) (xy 77.972886 -384.756159) (xy 77.956847 -384.690673)
			(xy 77.948768 -384.623738) (xy 77.948764 -384.556316) (xy 77.956837 -384.48938) (xy 77.972869 -384.423893)
			(xy 77.996631 -384.360797) (xy 78.027779 -384.301002) (xy 78.065865 -384.245369) (xy 78.087728 -384.219704)
			(xy 78.093509 -384.212548) (xy 78.100032 -384.195366) (xy 78.100428 -384.186176) (xy 78.100428 -383.693924)
			(xy 78.1 -383.684739) (xy 78.093498 -383.667555) (xy 78.087728 -383.660396) (xy 78.065828 -383.63476)
			(xy 78.027738 -383.579122) (xy 77.996587 -383.519322) (xy 77.972824 -383.456221) (xy 77.95679 -383.390728)
			(xy 77.948717 -383.323787) (xy 76.846624 -383.323787) (xy 76.846836 -383.324352) (xy 76.862807 -383.389735)
			(xy 76.870849 -383.456559) (xy 76.870848 -383.523865) (xy 76.862803 -383.590688) (xy 76.846829 -383.656071)
			(xy 76.823155 -383.719076) (xy 76.792121 -383.7788) (xy 76.754172 -383.834388) (xy 76.732384 -383.86004)
			(xy 76.726586 -383.867184) (xy 76.720073 -383.884376) (xy 76.719684 -383.893568) (xy 76.719684 -384.051556)
			(xy 76.719242 -384.061709) (xy 76.711458 -384.080464) (xy 76.697067 -384.094789) (xy 76.678277 -384.102488)
			(xy 76.668122 -384.102864) (xy 75.951842 -384.102864) (xy 75.941718 -384.102339) (xy 75.922999 -384.094626)
			(xy 75.908642 -384.080351) (xy 75.90082 -384.061677) (xy 75.90028 -384.051556) (xy 75.90028 -383.893568)
			(xy 75.89989 -383.884379) (xy 75.893363 -383.867194) (xy 75.88758 -383.86004) (xy 75.865807 -383.834375)
			(xy 75.827855 -383.778792) (xy 75.796819 -383.71907) (xy 75.773143 -383.656067) (xy 75.757168 -383.590686)
			(xy 75.749122 -383.523864) (xy 75.74912 -383.45656) (xy 75.757164 -383.389738) (xy 75.773136 -383.324356)
			(xy 75.796809 -383.261352) (xy 75.827842 -383.201629) (xy 75.865792 -383.146044) (xy 75.88758 -383.120392)
			(xy 75.89336 -383.113235) (xy 75.899885 -383.096054) (xy 75.90028 -383.086864) (xy 75.90028 -382.593342)
			(xy 75.899854 -382.584156) (xy 75.893352 -382.566972) (xy 75.88758 -382.559814) (xy 75.865781 -382.53417)
			(xy 75.82783 -382.478584) (xy 75.796795 -382.418859) (xy 75.773121 -382.355854) (xy 75.757147 -382.29047)
			(xy 75.749104 -382.223646) (xy 72.471064 -382.223646) (xy 72.471064 -382.223704) (xy 72.462989 -382.290642)
			(xy 72.446954 -382.356131) (xy 72.42319 -382.419227) (xy 72.39204 -382.479023) (xy 72.353952 -382.534657)
			(xy 72.332088 -382.560322) (xy 72.326298 -382.567472) (xy 72.31978 -382.584659) (xy 72.319388 -382.59385)
			(xy 72.319388 -383.086356) (xy 72.319822 -383.095541) (xy 72.326319 -383.112725) (xy 72.332088 -383.119884)
			(xy 72.353968 -383.145536) (xy 72.392057 -383.201172) (xy 72.423208 -383.26097) (xy 72.446843 -383.323727)
			(xy 73.548949 -383.323727) (xy 73.548952 -383.256419) (xy 73.556999 -383.189594) (xy 73.572976 -383.12421)
			(xy 73.596652 -383.061204) (xy 73.62769 -383.001479) (xy 73.665642 -382.945892) (xy 73.687432 -382.92024)
			(xy 73.693241 -382.913103) (xy 73.699747 -382.895906) (xy 73.700132 -382.886712) (xy 73.700132 -382.728724)
			(xy 73.700542 -382.718567) (xy 73.708335 -382.699809) (xy 73.722736 -382.685484) (xy 73.741535 -382.677789)
			(xy 73.751694 -382.677416) (xy 74.467974 -382.677416) (xy 74.478096 -382.677947) (xy 74.496812 -382.685662)
			(xy 74.511169 -382.699934) (xy 74.518993 -382.718605) (xy 74.519536 -382.728724) (xy 74.519536 -382.886712)
			(xy 74.519955 -382.895898) (xy 74.526464 -382.913082) (xy 74.532236 -382.92024) (xy 74.553989 -382.945921)
			(xy 74.591941 -383.001503) (xy 74.622977 -383.061222) (xy 74.646653 -383.124223) (xy 74.662629 -383.189602)
			(xy 74.670676 -383.256422) (xy 74.670679 -383.323724) (xy 74.662639 -383.390545) (xy 74.646669 -383.455925)
			(xy 74.622999 -383.518928) (xy 74.591968 -383.578651) (xy 74.554022 -383.634236) (xy 74.532236 -383.659888)
			(xy 74.526412 -383.667013) (xy 74.519915 -383.684219) (xy 74.519536 -383.693416) (xy 74.519536 -384.186684)
			(xy 74.519968 -384.195869) (xy 74.526468 -384.213052) (xy 74.532236 -384.220212) (xy 74.55406 -384.245835)
			(xy 74.592009 -384.301425) (xy 74.623043 -384.361152) (xy 74.646714 -384.424161) (xy 74.662686 -384.489547)
			(xy 74.670727 -384.556373) (xy 74.670724 -384.623681) (xy 74.662676 -384.690507) (xy 74.646698 -384.755891)
			(xy 74.623021 -384.818897) (xy 74.591982 -384.878622) (xy 74.554027 -384.934208) (xy 74.532236 -384.95986)
			(xy 74.526424 -384.966994) (xy 74.51992 -384.984193) (xy 74.519536 -384.993388) (xy 74.519536 -385.151376)
			(xy 74.51906 -385.161524) (xy 74.511279 -385.180269) (xy 74.496899 -385.194592) (xy 74.478124 -385.202299)
			(xy 74.467974 -385.202684) (xy 73.751694 -385.202684) (xy 73.74157 -385.202179) (xy 73.722853 -385.194454)
			(xy 73.708498 -385.180173) (xy 73.700675 -385.161497) (xy 73.700132 -385.151376) (xy 73.700132 -384.993388)
			(xy 73.699721 -384.984201) (xy 73.693207 -384.967017) (xy 73.687432 -384.95986) (xy 73.66568 -384.934178)
			(xy 73.627731 -384.878596) (xy 73.596696 -384.818877) (xy 73.573022 -384.755876) (xy 73.557047 -384.690497)
			(xy 73.549 -384.623678) (xy 73.548996 -384.556376) (xy 73.557037 -384.489556) (xy 73.573006 -384.424176)
			(xy 73.596674 -384.361173) (xy 73.627703 -384.30145) (xy 73.665647 -384.245864) (xy 73.687432 -384.220212)
			(xy 73.693253 -384.213084) (xy 73.699752 -384.19588) (xy 73.700132 -384.186684) (xy 73.700132 -383.693416)
			(xy 73.699707 -383.684231) (xy 73.693203 -383.667046) (xy 73.687432 -383.659888) (xy 73.665609 -383.634265)
			(xy 73.627662 -383.578674) (xy 73.59663 -383.518946) (xy 73.57296 -383.455938) (xy 73.55699 -383.390553)
			(xy 73.548949 -383.323727) (xy 72.446843 -383.323727) (xy 72.446972 -383.324069) (xy 72.463006 -383.38956)
			(xy 72.471081 -383.456499) (xy 72.47108 -383.523925) (xy 72.463002 -383.590864) (xy 72.446964 -383.656354)
			(xy 72.423198 -383.719452) (xy 72.392045 -383.779248) (xy 72.353953 -383.834883) (xy 72.332088 -383.860548)
			(xy 72.326287 -383.86769) (xy 72.319775 -383.884883) (xy 72.319388 -383.894076) (xy 72.319388 -384.051556)
			(xy 72.318948 -384.061677) (xy 72.311212 -384.080382) (xy 72.296902 -384.094698) (xy 72.278201 -384.102443)
			(xy 72.26808 -384.102864) (xy 71.5518 -384.102864) (xy 71.541673 -384.102483) (xy 71.522963 -384.094728)
			(xy 71.508647 -384.0804) (xy 71.500908 -384.061683) (xy 71.500492 -384.051556) (xy 71.500492 -383.894076)
			(xy 71.500095 -383.884887) (xy 71.493572 -383.867703) (xy 71.487792 -383.860548) (xy 71.465944 -383.83487)
			(xy 71.427855 -383.779237) (xy 71.396704 -383.719442) (xy 71.37294 -383.656347) (xy 71.356903 -383.59086)
			(xy 71.348826 -383.523923) (xy 71.348825 -383.456501) (xy 71.356899 -383.389564) (xy 71.372933 -383.324076)
			(xy 71.396695 -383.26098) (xy 71.427843 -383.201184) (xy 71.465929 -383.145549) (xy 71.487792 -383.119884)
			(xy 71.493577 -383.11273) (xy 71.500099 -383.095546) (xy 71.500492 -383.086356) (xy 71.500492 -382.59385)
			(xy 71.50006 -382.584665) (xy 71.493562 -382.56748) (xy 71.487792 -382.560322) (xy 71.465918 -382.534665)
			(xy 71.427831 -382.479029) (xy 71.396681 -382.419231) (xy 71.372918 -382.356134) (xy 71.356883 -382.290644)
			(xy 71.348808 -382.223705) (xy 46.070794 -382.223705) (xy 46.062758 -382.290467) (xy 46.046786 -382.355849)
			(xy 46.023113 -382.418853) (xy 45.99208 -382.478576) (xy 45.954131 -382.534162) (xy 45.932344 -382.559814)
			(xy 45.926552 -382.566962) (xy 45.920036 -382.584151) (xy 45.919644 -382.593342) (xy 45.919644 -383.086864)
			(xy 45.920084 -383.096048) (xy 45.926578 -383.113232) (xy 45.932344 -383.120392) (xy 45.954148 -383.146031)
			(xy 45.992098 -383.201619) (xy 46.023131 -383.261344) (xy 46.04657 -383.323727) (xy 47.149191 -383.323727)
			(xy 47.149195 -383.256419) (xy 47.157243 -383.189593) (xy 47.173221 -383.124208) (xy 47.1969 -383.061202)
			(xy 47.22794 -383.001477) (xy 47.265897 -382.945892) (xy 47.287688 -382.92024) (xy 47.293491 -382.913099)
			(xy 47.300002 -382.895905) (xy 47.300388 -382.886712) (xy 47.300388 -382.728724) (xy 47.300841 -382.718573)
			(xy 47.308626 -382.699823) (xy 47.323013 -382.685499) (xy 47.341797 -382.677797) (xy 47.35195 -382.677416)
			(xy 48.06823 -382.677416) (xy 48.078356 -382.677901) (xy 48.097073 -382.685634) (xy 48.111427 -382.699921)
			(xy 48.11925 -382.718601) (xy 48.119792 -382.728724) (xy 48.119792 -382.886712) (xy 48.120198 -382.8959)
			(xy 48.126715 -382.913084) (xy 48.132492 -382.92024) (xy 48.154243 -382.945922) (xy 48.192191 -383.001505)
			(xy 48.223224 -383.061224) (xy 48.246898 -383.124225) (xy 48.262872 -383.189603) (xy 48.270919 -383.256422)
			(xy 48.270922 -383.323724) (xy 48.262882 -383.390543) (xy 48.246914 -383.455923) (xy 48.223247 -383.518926)
			(xy 48.192219 -383.578649) (xy 48.154277 -383.634236) (xy 48.132492 -383.659888) (xy 48.126675 -383.667018)
			(xy 48.120173 -383.68422) (xy 48.119792 -383.693416) (xy 48.119792 -384.186684) (xy 48.120212 -384.19587)
			(xy 48.126719 -384.213054) (xy 48.132492 -384.220212) (xy 48.154314 -384.245835) (xy 48.19226 -384.301427)
			(xy 48.22329 -384.361155) (xy 48.246959 -384.424163) (xy 48.262929 -384.489548) (xy 48.27097 -384.556373)
			(xy 48.270966 -384.623681) (xy 48.262919 -384.690505) (xy 48.246943 -384.755889) (xy 48.223268 -384.818895)
			(xy 48.192232 -384.87862) (xy 48.154281 -384.934207) (xy 48.132492 -384.95986) (xy 48.126687 -384.966999)
			(xy 48.120177 -384.984194) (xy 48.119792 -384.993388) (xy 48.119792 -385.151376) (xy 48.119359 -385.16153)
			(xy 48.11157 -385.180283) (xy 48.097176 -385.194608) (xy 48.078386 -385.202307) (xy 48.06823 -385.202684)
			(xy 47.35195 -385.202684) (xy 47.341829 -385.202133) (xy 47.323114 -385.194426) (xy 47.308757 -385.18016)
			(xy 47.300932 -385.161493) (xy 47.300388 -385.151376) (xy 47.300388 -384.993388) (xy 47.299986 -384.9842)
			(xy 47.293467 -384.967016) (xy 47.287688 -384.95986) (xy 47.265934 -384.934179) (xy 47.227981 -384.878598)
			(xy 47.196944 -384.818879) (xy 47.173267 -384.755878) (xy 47.15729 -384.690499) (xy 47.149242 -384.623679)
			(xy 47.149239 -384.556376) (xy 47.15728 -384.489554) (xy 47.173251 -384.424174) (xy 47.196921 -384.361171)
			(xy 47.227953 -384.301448) (xy 47.265901 -384.245863) (xy 47.287688 -384.220212) (xy 47.293503 -384.21308)
			(xy 47.300007 -384.195879) (xy 47.300388 -384.186684) (xy 47.300388 -383.693416) (xy 47.299973 -383.684229)
			(xy 47.293463 -383.667045) (xy 47.287688 -383.659888) (xy 47.265863 -383.634266) (xy 47.227913 -383.578676)
			(xy 47.196878 -383.518949) (xy 47.173205 -383.45594) (xy 47.157233 -383.390554) (xy 47.149191 -383.323727)
			(xy 46.04657 -383.323727) (xy 46.046804 -383.32435) (xy 46.062776 -383.389734) (xy 46.070819 -383.456559)
			(xy 46.070818 -383.523865) (xy 46.062772 -383.590689) (xy 46.046797 -383.656073) (xy 46.023121 -383.719078)
			(xy 45.992085 -383.778802) (xy 45.954133 -383.834388) (xy 45.932344 -383.86004) (xy 45.926541 -383.86718)
			(xy 45.920032 -383.884375) (xy 45.919644 -383.893568) (xy 45.919644 -384.051556) (xy 45.919143 -384.061702)
			(xy 45.91137 -384.080445) (xy 45.896998 -384.094768) (xy 45.878229 -384.102477) (xy 45.868082 -384.102864)
			(xy 45.151802 -384.102864) (xy 45.141676 -384.102372) (xy 45.122956 -384.094645) (xy 45.108599 -384.080361)
			(xy 45.100779 -384.06168) (xy 45.10024 -384.051556) (xy 45.10024 -383.893568) (xy 45.099836 -383.88438)
			(xy 45.093317 -383.867197) (xy 45.08754 -383.86004) (xy 45.065768 -383.834375) (xy 45.027819 -383.77879)
			(xy 44.996785 -383.719068) (xy 44.973111 -383.656066) (xy 44.957137 -383.590685) (xy 44.949092 -383.523864)
			(xy 44.94909 -383.45656) (xy 44.957133 -383.389739) (xy 44.973104 -383.324357) (xy 44.996775 -383.261354)
			(xy 45.027806 -383.20163) (xy 45.065753 -383.146044) (xy 45.08754 -383.120392) (xy 45.093328 -383.113241)
			(xy 45.099847 -383.096055) (xy 45.10024 -383.086864) (xy 45.10024 -382.593342) (xy 45.0998 -382.584158)
			(xy 45.093306 -382.566974) (xy 45.08754 -382.559814) (xy 45.065742 -382.53417) (xy 45.027794 -382.478582)
			(xy 44.996761 -382.418858) (xy 44.973088 -382.355852) (xy 44.957116 -382.290469) (xy 44.949073 -382.223645)
			(xy 41.671034 -382.223645) (xy 41.671034 -382.223704) (xy 41.662958 -382.290643) (xy 41.646922 -382.356132)
			(xy 41.623157 -382.419229) (xy 41.592004 -382.479024) (xy 41.553913 -382.534658) (xy 41.532048 -382.560322)
			(xy 41.526253 -382.567468) (xy 41.519739 -382.584658) (xy 41.519348 -382.59385) (xy 41.519348 -383.086356)
			(xy 41.519791 -383.095539) (xy 41.526283 -383.112723) (xy 41.532048 -383.119884) (xy 41.55393 -383.145535)
			(xy 41.592021 -383.201171) (xy 41.623174 -383.260968) (xy 41.646834 -383.323786) (xy 42.748896 -383.323786)
			(xy 42.748899 -383.25636) (xy 42.756978 -383.189419) (xy 42.773018 -383.123928) (xy 42.796786 -383.06083)
			(xy 42.827941 -383.001032) (xy 42.866034 -382.945397) (xy 42.8879 -382.919732) (xy 42.893708 -382.912595)
			(xy 42.900216 -382.895398) (xy 42.9006 -382.886204) (xy 42.9006 -382.728724) (xy 42.901035 -382.718603)
			(xy 42.908776 -382.6999) (xy 42.923086 -382.685585) (xy 42.941787 -382.677839) (xy 42.951908 -382.677416)
			(xy 43.668188 -382.677416) (xy 43.678312 -382.677826) (xy 43.697018 -382.685573) (xy 43.711333 -382.699892)
			(xy 43.719076 -382.7186) (xy 43.719496 -382.728724) (xy 43.719496 -382.886204) (xy 43.719905 -382.895391)
			(xy 43.72642 -382.912575) (xy 43.732196 -382.919732) (xy 43.754025 -382.945426) (xy 43.792115 -383.001057)
			(xy 43.823267 -383.060849) (xy 43.847034 -383.123942) (xy 43.863072 -383.189427) (xy 43.871151 -383.256363)
			(xy 43.871154 -383.323783) (xy 43.863081 -383.390719) (xy 43.84705 -383.456206) (xy 43.823289 -383.519302)
			(xy 43.792143 -383.579097) (xy 43.754058 -383.634731) (xy 43.732196 -383.660396) (xy 43.726418 -383.667554)
			(xy 43.719892 -383.684735) (xy 43.719496 -383.693924) (xy 43.719496 -384.186176) (xy 43.719919 -384.195362)
			(xy 43.726424 -384.212546) (xy 43.732196 -384.219704) (xy 43.754095 -384.24534) (xy 43.792183 -384.300979)
			(xy 43.823333 -384.360779) (xy 43.847095 -384.42388) (xy 43.863128 -384.489372) (xy 43.871201 -384.556314)
			(xy 43.871198 -384.62374) (xy 43.863118 -384.690681) (xy 43.847079 -384.756172) (xy 43.823311 -384.819271)
			(xy 43.792156 -384.879068) (xy 43.754062 -384.934703) (xy 43.732196 -384.960368) (xy 43.726388 -384.967505)
			(xy 43.71988 -384.984702) (xy 43.719496 -384.993896) (xy 43.719496 -385.151376) (xy 43.719064 -385.161497)
			(xy 43.711323 -385.180201) (xy 43.697011 -385.194517) (xy 43.678309 -385.202262) (xy 43.668188 -385.202684)
			(xy 42.951908 -385.202684) (xy 42.941784 -385.202277) (xy 42.923078 -385.194529) (xy 42.908762 -385.180209)
			(xy 42.90102 -385.1615) (xy 42.9006 -385.151376) (xy 42.9006 -384.993896) (xy 42.900192 -384.984709)
			(xy 42.893677 -384.967524) (xy 42.8879 -384.960368) (xy 42.866071 -384.934674) (xy 42.827982 -384.879043)
			(xy 42.796829 -384.819251) (xy 42.773063 -384.756158) (xy 42.757025 -384.690672) (xy 42.748946 -384.623737)
			(xy 42.748943 -384.556317) (xy 42.757015 -384.489381) (xy 42.773047 -384.423894) (xy 42.796807 -384.360798)
			(xy 42.827954 -384.301003) (xy 42.866038 -384.245369) (xy 42.8879 -384.219704) (xy 42.893677 -384.212545)
			(xy 42.900204 -384.195365) (xy 42.9006 -384.186176) (xy 42.9006 -383.693924) (xy 42.900178 -383.684738)
			(xy 42.893673 -383.667554) (xy 42.8879 -383.660396) (xy 42.866001 -383.63476) (xy 42.827913 -383.579121)
			(xy 42.796764 -383.519321) (xy 42.773002 -383.45622) (xy 42.756969 -383.390728) (xy 42.748896 -383.323786)
			(xy 41.646834 -383.323786) (xy 41.64694 -383.324067) (xy 41.662976 -383.389558) (xy 41.671051 -383.456499)
			(xy 41.67105 -383.523925) (xy 41.662971 -383.590865) (xy 41.646933 -383.656356) (xy 41.623164 -383.719454)
			(xy 41.592009 -383.77925) (xy 41.553915 -383.834884) (xy 41.532048 -383.860548) (xy 41.526242 -383.867686)
			(xy 41.519734 -383.884882) (xy 41.519348 -383.894076) (xy 41.519348 -384.051556) (xy 41.518849 -384.06167)
			(xy 41.511124 -384.080363) (xy 41.496834 -384.094677) (xy 41.478153 -384.102432) (xy 41.46804 -384.102864)
			(xy 40.75176 -384.102864) (xy 40.74163 -384.102516) (xy 40.722919 -384.094748) (xy 40.708605 -384.08041)
			(xy 40.700868 -384.061686) (xy 40.700452 -384.051556) (xy 40.700452 -383.894076) (xy 40.700042 -383.884889)
			(xy 40.693527 -383.867705) (xy 40.687752 -383.860548) (xy 40.665902 -383.834871) (xy 40.627809 -383.779239)
			(xy 40.596655 -383.719445) (xy 40.572888 -383.65635) (xy 40.556849 -383.590862) (xy 40.548772 -383.523924)
			(xy 40.54877 -383.4565) (xy 40.556845 -383.389562) (xy 40.572881 -383.324073) (xy 40.596645 -383.260977)
			(xy 40.627797 -383.201182) (xy 40.665887 -383.145548) (xy 40.687752 -383.119884) (xy 40.693544 -383.112736)
			(xy 40.70006 -383.095547) (xy 40.700452 -383.086356) (xy 40.700452 -382.59385) (xy 40.700006 -382.584667)
			(xy 40.693516 -382.567483) (xy 40.687752 -382.560322) (xy 40.665876 -382.534666) (xy 40.627785 -382.479031)
			(xy 40.596631 -382.419234) (xy 40.572865 -382.356136) (xy 40.556829 -382.290645) (xy 40.548753 -382.223705)
			(xy 37.271243 -382.223705) (xy 37.263167 -382.290643) (xy 37.247132 -382.356132) (xy 37.223367 -382.419228)
			(xy 37.192215 -382.479024) (xy 37.154125 -382.534657) (xy 37.13226 -382.560322) (xy 37.126467 -382.567469)
			(xy 37.119951 -382.584658) (xy 37.11956 -382.59385) (xy 37.11956 -383.086356) (xy 37.12 -383.09554)
			(xy 37.126494 -383.112724) (xy 37.13226 -383.119884) (xy 37.154141 -383.145536) (xy 37.192232 -383.201171)
			(xy 37.223384 -383.260969) (xy 37.247021 -383.323727) (xy 38.349127 -383.323727) (xy 38.349131 -383.256419)
			(xy 38.357178 -383.189595) (xy 38.373154 -383.124211) (xy 38.396829 -383.061205) (xy 38.427864 -383.00148)
			(xy 38.465815 -382.945893) (xy 38.487604 -382.92024) (xy 38.493409 -382.913101) (xy 38.499919 -382.895906)
			(xy 38.500304 -382.886712) (xy 38.500304 -382.728724) (xy 38.500741 -382.718571) (xy 38.50853 -382.699818)
			(xy 38.522922 -382.685494) (xy 38.541711 -382.677794) (xy 38.551866 -382.677416) (xy 39.268146 -382.677416)
			(xy 39.278273 -382.677888) (xy 39.29699 -382.685627) (xy 39.311344 -382.699917) (xy 39.319166 -382.7186)
			(xy 39.319708 -382.728724) (xy 39.319708 -382.886712) (xy 39.320111 -382.8959) (xy 39.326629 -382.913084)
			(xy 39.332408 -382.92024) (xy 39.354162 -382.945921) (xy 39.392115 -383.001502) (xy 39.423153 -383.061221)
			(xy 39.44683 -383.124222) (xy 39.462807 -383.189601) (xy 39.470855 -383.256421) (xy 39.470858 -383.323725)
			(xy 39.462817 -383.390546) (xy 39.446846 -383.455926) (xy 39.423175 -383.51893) (xy 39.392143 -383.578652)
			(xy 39.354195 -383.634237) (xy 39.332408 -383.659888) (xy 39.326592 -383.66702) (xy 39.320089 -383.684221)
			(xy 39.319708 -383.693416) (xy 39.319708 -384.186684) (xy 39.320124 -384.195871) (xy 39.326633 -384.213055)
			(xy 39.332408 -384.220212) (xy 39.354233 -384.245834) (xy 39.392184 -384.301424) (xy 39.423219 -384.361151)
			(xy 39.446892 -384.42416) (xy 39.462864 -384.489546) (xy 39.470906 -384.556373) (xy 39.470902 -384.623682)
			(xy 39.462854 -384.690507) (xy 39.446876 -384.755892) (xy 39.423196 -384.818898) (xy 39.392156 -384.878623)
			(xy 39.354199 -384.934209) (xy 39.332408 -384.95986) (xy 39.326604 -384.967) (xy 39.320094 -384.984195)
			(xy 39.319708 -384.993388) (xy 39.319708 -385.151376) (xy 39.319259 -385.161528) (xy 39.311473 -385.180278)
			(xy 39.297085 -385.194602) (xy 39.278299 -385.202304) (xy 39.268146 -385.202684) (xy 38.551866 -385.202684)
			(xy 38.54174 -385.202202) (xy 38.523023 -385.194468) (xy 38.508668 -385.18018) (xy 38.500846 -385.1615)
			(xy 38.500304 -385.151376) (xy 38.500304 -384.993388) (xy 38.499899 -384.9842) (xy 38.493381 -384.967016)
			(xy 38.487604 -384.95986) (xy 38.465853 -384.934178) (xy 38.427905 -384.878595) (xy 38.396872 -384.818875)
			(xy 38.373199 -384.755875) (xy 38.357224 -384.690497) (xy 38.349178 -384.623678) (xy 38.349175 -384.556376)
			(xy 38.357215 -384.489557) (xy 38.373183 -384.424177) (xy 38.39685 -384.361174) (xy 38.427877 -384.301451)
			(xy 38.465819 -384.245865) (xy 38.487604 -384.220212) (xy 38.493421 -384.213081) (xy 38.499923 -384.19588)
			(xy 38.500304 -384.186684) (xy 38.500304 -383.693416) (xy 38.499885 -383.68423) (xy 38.493377 -383.667045)
			(xy 38.487604 -383.659888) (xy 38.465782 -383.634264) (xy 38.427837 -383.578673) (xy 38.396807 -383.518945)
			(xy 38.373138 -383.455937) (xy 38.357168 -383.390552) (xy 38.349127 -383.323727) (xy 37.247021 -383.323727)
			(xy 37.247149 -383.324068) (xy 37.263185 -383.389559) (xy 37.27126 -383.456499) (xy 37.271259 -383.523925)
			(xy 37.263181 -383.590865) (xy 37.247142 -383.656355) (xy 37.223374 -383.719453) (xy 37.19222 -383.77925)
			(xy 37.154126 -383.834883) (xy 37.13226 -383.860548) (xy 37.126456 -383.867687) (xy 37.119947 -383.884883)
			(xy 37.11956 -383.894076) (xy 37.11956 -384.051556) (xy 37.119147 -384.061681) (xy 37.111406 -384.080391)
			(xy 37.097087 -384.094708) (xy 37.078377 -384.102448) (xy 37.068252 -384.102864) (xy 36.351972 -384.102864)
			(xy 36.341843 -384.102506) (xy 36.323132 -384.094742) (xy 36.308817 -384.080407) (xy 36.30108 -384.061685)
			(xy 36.300664 -384.051556) (xy 36.300664 -383.894076) (xy 36.300251 -383.884889) (xy 36.293738 -383.867706)
			(xy 36.287964 -383.860548) (xy 36.266117 -383.834869) (xy 36.22803 -383.779236) (xy 36.196881 -383.719441)
			(xy 36.173117 -383.656346) (xy 36.157082 -383.590859) (xy 36.149005 -383.523923) (xy 36.149004 -383.456501)
			(xy 36.157078 -383.389565) (xy 36.17311 -383.324077) (xy 36.196871 -383.260981) (xy 36.228018 -383.201185)
			(xy 36.266102 -383.14555) (xy 36.287964 -383.119884) (xy 36.293758 -383.112737) (xy 36.300272 -383.095548)
			(xy 36.300664 -383.086356) (xy 36.300664 -382.59385) (xy 36.300216 -382.584667) (xy 36.293727 -382.567483)
			(xy 36.287964 -382.560322) (xy 36.266091 -382.534664) (xy 36.228005 -382.479028) (xy 36.196857 -382.41923)
			(xy 36.173095 -382.356132) (xy 36.157061 -382.290643) (xy 36.148987 -382.223704) (xy 32.870916 -382.223704)
			(xy 32.86288 -382.290466) (xy 32.846909 -382.355848) (xy 32.823237 -382.418852) (xy 32.792206 -382.478575)
			(xy 32.754259 -382.534162) (xy 32.732472 -382.559814) (xy 32.726683 -382.566965) (xy 32.720165 -382.584151)
			(xy 32.719772 -382.593342) (xy 32.719772 -383.086864) (xy 32.720206 -383.096049) (xy 32.726704 -383.113233)
			(xy 32.732472 -383.120392) (xy 32.754275 -383.146031) (xy 32.792223 -383.20162) (xy 32.823255 -383.261345)
			(xy 32.846714 -383.323786) (xy 33.948808 -383.323786) (xy 33.948811 -383.25636) (xy 33.956891 -383.189419)
			(xy 33.972931 -383.123927) (xy 33.996699 -383.060829) (xy 34.027855 -383.001032) (xy 34.065949 -382.945397)
			(xy 34.087816 -382.919732) (xy 34.093626 -382.912596) (xy 34.100132 -382.895398) (xy 34.100516 -382.886204)
			(xy 34.100516 -382.728724) (xy 34.100936 -382.718601) (xy 34.108679 -382.699895) (xy 34.122995 -382.685579)
			(xy 34.141701 -382.677836) (xy 34.151824 -382.677416) (xy 34.868104 -382.677416) (xy 34.878229 -382.677813)
			(xy 34.896935 -382.685566) (xy 34.91125 -382.699888) (xy 34.918992 -382.718599) (xy 34.919412 -382.728724)
			(xy 34.919412 -382.886204) (xy 34.919818 -382.895392) (xy 34.926334 -382.912576) (xy 34.932112 -382.919732)
			(xy 34.95394 -382.945427) (xy 34.992029 -383.001057) (xy 35.023181 -383.060849) (xy 35.046946 -383.123942)
			(xy 35.062984 -383.189428) (xy 35.071063 -383.256363) (xy 35.071066 -383.323783) (xy 35.062994 -383.390719)
			(xy 35.046962 -383.456206) (xy 35.023203 -383.519301) (xy 34.992057 -383.579096) (xy 34.953973 -383.634731)
			(xy 34.932112 -383.660396) (xy 34.926336 -383.667556) (xy 34.919809 -383.684735) (xy 34.919412 -383.693924)
			(xy 34.919412 -384.186176) (xy 34.919831 -384.195362) (xy 34.926338 -384.212547) (xy 34.932112 -384.219704)
			(xy 34.954011 -384.24534) (xy 34.992098 -384.300979) (xy 35.023246 -384.36078) (xy 35.047008 -384.42388)
			(xy 35.06304 -384.489373) (xy 35.071113 -384.556314) (xy 35.07111 -384.62374) (xy 35.063031 -384.690681)
			(xy 35.046992 -384.756172) (xy 35.023224 -384.81927) (xy 34.99207 -384.879067) (xy 34.953978 -384.934703)
			(xy 34.932112 -384.960368) (xy 34.926305 -384.967506) (xy 34.919796 -384.984702) (xy 34.919412 -384.993896)
			(xy 34.919412 -385.151376) (xy 34.918965 -385.161495) (xy 34.911227 -385.180196) (xy 34.89692 -385.194511)
			(xy 34.878223 -385.202259) (xy 34.868104 -385.202684) (xy 34.151824 -385.202684) (xy 34.141701 -385.202264)
			(xy 34.122995 -385.194521) (xy 34.108679 -385.180205) (xy 34.100936 -385.161499) (xy 34.100516 -385.151376)
			(xy 34.100516 -384.993896) (xy 34.100104 -384.984709) (xy 34.093591 -384.967525) (xy 34.087816 -384.960368)
			(xy 34.065987 -384.934674) (xy 34.027896 -384.879044) (xy 33.996743 -384.819252) (xy 33.972976 -384.756159)
			(xy 33.956937 -384.690673) (xy 33.948858 -384.623738) (xy 33.948855 -384.556316) (xy 33.956928 -384.48938)
			(xy 33.97296 -384.423893) (xy 33.996721 -384.360798) (xy 34.027868 -384.301003) (xy 34.065954 -384.245369)
			(xy 34.087816 -384.219704) (xy 34.093595 -384.212547) (xy 34.10012 -384.195365) (xy 34.100516 -384.186176)
			(xy 34.100516 -383.693924) (xy 34.100091 -383.684739) (xy 34.093587 -383.667554) (xy 34.087816 -383.660396)
			(xy 34.065916 -383.63476) (xy 34.027827 -383.579122) (xy 33.996677 -383.519322) (xy 33.972915 -383.456221)
			(xy 33.956881 -383.390728) (xy 33.948808 -383.323786) (xy 32.846714 -383.323786) (xy 32.846926 -383.324351)
			(xy 32.862898 -383.389735) (xy 32.87094 -383.456559) (xy 32.870939 -383.523865) (xy 32.862893 -383.590689)
			(xy 32.846919 -383.656072) (xy 32.823245 -383.719077) (xy 32.79221 -383.778801) (xy 32.75426 -383.834388)
			(xy 32.732472 -383.86004) (xy 32.726672 -383.867183) (xy 32.72016 -383.884375) (xy 32.719772 -383.893568)
			(xy 32.719772 -384.051556) (xy 32.719342 -384.061711) (xy 32.711555 -384.080468) (xy 32.697161 -384.094793)
			(xy 32.678367 -384.10249) (xy 32.66821 -384.102864) (xy 31.95193 -384.102864) (xy 31.941806 -384.102349)
			(xy 31.923086 -384.094632) (xy 31.908729 -384.080354) (xy 31.900908 -384.061678) (xy 31.900368 -384.051556)
			(xy 31.900368 -383.893568) (xy 31.899958 -383.884381) (xy 31.893443 -383.867197) (xy 31.887668 -383.86004)
			(xy 31.865895 -383.834375) (xy 31.827944 -383.778791) (xy 31.796908 -383.71907) (xy 31.773234 -383.656067)
			(xy 31.757259 -383.590686) (xy 31.749213 -383.523864) (xy 31.749211 -383.45656) (xy 31.757254 -383.389738)
			(xy 31.773226 -383.324356) (xy 31.796899 -383.261352) (xy 31.827932 -383.201629) (xy 31.86588 -383.146044)
			(xy 31.887668 -383.120392) (xy 31.893459 -383.113243) (xy 31.899975 -383.096055) (xy 31.900368 -383.086864)
			(xy 31.900368 -382.593342) (xy 31.899923 -382.584159) (xy 31.893432 -382.566975) (xy 31.887668 -382.559814)
			(xy 31.86587 -382.53417) (xy 31.827919 -382.478583) (xy 31.796885 -382.418859) (xy 31.773211 -382.355853)
			(xy 31.757238 -382.29047) (xy 31.749194 -382.223646) (xy 28.471155 -382.223646) (xy 28.471155 -382.223704)
			(xy 28.463079 -382.290642) (xy 28.447044 -382.356131) (xy 28.42328 -382.419228) (xy 28.392129 -382.479023)
			(xy 28.35404 -382.534657) (xy 28.332176 -382.560322) (xy 28.326385 -382.567471) (xy 28.319868 -382.584659)
			(xy 28.319476 -382.59385) (xy 28.319476 -383.086356) (xy 28.319913 -383.09554) (xy 28.326409 -383.112725)
			(xy 28.332176 -383.119884) (xy 28.354057 -383.145536) (xy 28.392146 -383.201172) (xy 28.423298 -383.26097)
			(xy 28.446934 -383.323727) (xy 29.549039 -383.323727) (xy 29.549043 -383.256419) (xy 29.55709 -383.189594)
			(xy 29.573066 -383.12421) (xy 29.596742 -383.061205) (xy 29.627779 -383.00148) (xy 29.665731 -382.945892)
			(xy 29.68752 -382.92024) (xy 29.693327 -382.913102) (xy 29.699835 -382.895906) (xy 29.70022 -382.886712)
			(xy 29.70022 -382.728724) (xy 29.700636 -382.718601) (xy 29.70838 -382.699894) (xy 29.722697 -382.685578)
			(xy 29.741405 -382.677835) (xy 29.751528 -382.677416) (xy 30.468062 -382.677416) (xy 30.478183 -382.677957)
			(xy 30.496899 -382.685668) (xy 30.511256 -382.699938) (xy 30.51908 -382.718606) (xy 30.519624 -382.728724)
			(xy 30.519624 -382.886712) (xy 30.520023 -382.8959) (xy 30.526544 -382.913085) (xy 30.532324 -382.92024)
			(xy 30.554077 -382.945921) (xy 30.59203 -383.001502) (xy 30.623067 -383.061222) (xy 30.646743 -383.124222)
			(xy 30.66272 -383.189601) (xy 30.670767 -383.256421) (xy 30.67077 -383.323724) (xy 30.662729 -383.390545)
			(xy 30.646759 -383.455926) (xy 30.623089 -383.518929) (xy 30.592058 -383.578651) (xy 30.554111 -383.634236)
			(xy 30.532324 -383.659888) (xy 30.52651 -383.667021) (xy 30.520005 -383.684221) (xy 30.519624 -383.693416)
			(xy 30.519624 -384.186684) (xy 30.520036 -384.195871) (xy 30.526548 -384.213056) (xy 30.532324 -384.220212)
			(xy 30.554149 -384.245834) (xy 30.592099 -384.301424) (xy 30.623132 -384.361152) (xy 30.646805 -384.42416)
			(xy 30.662776 -384.489546) (xy 30.670818 -384.556373) (xy 30.670815 -384.623681) (xy 30.662767 -384.690507)
			(xy 30.646789 -384.755892) (xy 30.62311 -384.818898) (xy 30.592071 -384.878622) (xy 30.554115 -384.934209)
			(xy 30.532324 -384.95986) (xy 30.526522 -384.967002) (xy 30.52001 -384.984195) (xy 30.519624 -384.993388)
			(xy 30.519624 -385.151376) (xy 30.519165 -385.161494) (xy 30.511429 -385.180193) (xy 30.497126 -385.194507)
			(xy 30.478434 -385.202257) (xy 30.468316 -385.202684) (xy 29.751782 -385.202684) (xy 29.741657 -385.202189)
			(xy 29.72294 -385.19446) (xy 29.708585 -385.180177) (xy 29.700762 -385.161498) (xy 29.70022 -385.151376)
			(xy 29.70022 -384.993388) (xy 29.699811 -384.984201) (xy 29.693296 -384.967017) (xy 29.68752 -384.95986)
			(xy 29.665769 -384.934178) (xy 29.62782 -384.878596) (xy 29.596786 -384.818876) (xy 29.573112 -384.755875)
			(xy 29.557137 -384.690497) (xy 29.549091 -384.623678) (xy 29.549087 -384.556376) (xy 29.557128 -384.489556)
			(xy 29.573096 -384.424176) (xy 29.596764 -384.361174) (xy 29.627792 -384.301451) (xy 29.665735 -384.245865)
			(xy 29.68752 -384.220212) (xy 29.693339 -384.213083) (xy 29.69984 -384.19588) (xy 29.70022 -384.186684)
			(xy 29.70022 -383.693416) (xy 29.699797 -383.68423) (xy 29.693292 -383.667046) (xy 29.68752 -383.659888)
			(xy 29.665697 -383.634265) (xy 29.627751 -383.578674) (xy 29.59672 -383.518946) (xy 29.57305 -383.455938)
			(xy 29.55708 -383.390552) (xy 29.549039 -383.323727) (xy 28.446934 -383.323727) (xy 28.447062 -383.324068)
			(xy 28.463097 -383.389559) (xy 28.471172 -383.456499) (xy 28.471171 -383.523925) (xy 28.463093 -383.590865)
			(xy 28.447055 -383.656355) (xy 28.423288 -383.719452) (xy 28.392134 -383.779249) (xy 28.354042 -383.834883)
			(xy 28.332176 -383.860548) (xy 28.326374 -383.867689) (xy 28.319863 -383.884883) (xy 28.319476 -383.894076)
			(xy 28.319476 -384.051556) (xy 28.319047 -384.061679) (xy 28.311309 -384.080386) (xy 28.296996 -384.094702)
			(xy 28.27829 -384.102445) (xy 28.268168 -384.102864) (xy 27.551888 -384.102864) (xy 27.54176 -384.102493)
			(xy 27.523049 -384.094734) (xy 27.508734 -384.080404) (xy 27.500996 -384.061684) (xy 27.50058 -384.051556)
			(xy 27.50058 -383.894076) (xy 27.500186 -383.884887) (xy 27.493661 -383.867703) (xy 27.48788 -383.860548)
			(xy 27.466032 -383.834869) (xy 27.427945 -383.779236) (xy 27.396794 -383.719442) (xy 27.37303 -383.656347)
			(xy 27.356994 -383.59086) (xy 27.348917 -383.523923) (xy 27.348916 -383.456501) (xy 27.35699 -383.389564)
			(xy 27.373023 -383.324076) (xy 27.396784 -383.26098) (xy 27.427932 -383.201184) (xy 27.466018 -383.14555)
			(xy 27.48788 -383.119884) (xy 27.493664 -383.112729) (xy 27.500187 -383.095546) (xy 27.50058 -383.086356)
			(xy 27.50058 -382.59385) (xy 27.50015 -382.584665) (xy 27.49365 -382.56748) (xy 27.48788 -382.560322)
			(xy 27.466007 -382.534665) (xy 27.42792 -382.479028) (xy 27.396771 -382.419231) (xy 27.373008 -382.356133)
			(xy 27.356974 -382.290643) (xy 27.348899 -382.223705) (xy 0.508 -382.223705) (xy 0.508 -385.583938)
			(xy 100.447856 -385.583938) (xy 100.447856 -384.720338) (xy 100.448346 -384.690354) (xy 100.456174 -384.630898)
			(xy 100.471695 -384.572973) (xy 100.494644 -384.517569) (xy 100.524628 -384.465635) (xy 100.561134 -384.418059)
			(xy 100.603539 -384.375654) (xy 100.651115 -384.339148) (xy 100.703049 -384.309164) (xy 100.758453 -384.286215)
			(xy 100.816378 -384.270694) (xy 100.875834 -384.262866) (xy 100.935802 -384.262866) (xy 100.995258 -384.270694)
			(xy 101.053183 -384.286215) (xy 101.108587 -384.309164) (xy 101.160521 -384.339148) (xy 101.208097 -384.375654)
			(xy 101.250502 -384.418059) (xy 101.287008 -384.465635) (xy 101.316992 -384.517569) (xy 101.339941 -384.572973)
			(xy 101.355462 -384.630898) (xy 101.36329 -384.690354) (xy 101.36378 -384.720338) (xy 101.36378 -385.319283)
			(xy 104.635826 -385.319283) (xy 104.635826 -385.259317) (xy 104.643653 -385.199864) (xy 104.659172 -385.141942)
			(xy 104.682119 -385.08654) (xy 104.7121 -385.034608) (xy 104.748603 -384.987032) (xy 104.791004 -384.944628)
			(xy 104.838576 -384.908121) (xy 104.890506 -384.878136) (xy 104.945906 -384.855184) (xy 105.003827 -384.83966)
			(xy 105.063279 -384.831828) (xy 105.093262 -384.831336) (xy 105.956862 -384.831336) (xy 105.986849 -384.831807)
			(xy 106.046311 -384.83963) (xy 106.104243 -384.855149) (xy 106.159653 -384.878097) (xy 106.211594 -384.908081)
			(xy 106.259176 -384.944589) (xy 106.301586 -384.986995) (xy 106.338098 -385.034574) (xy 106.368087 -385.086513)
			(xy 106.391039 -385.141921) (xy 106.406562 -385.199852) (xy 106.414391 -385.259313) (xy 106.414391 -385.319287)
			(xy 106.406562 -385.378748) (xy 106.391039 -385.436679) (xy 106.368087 -385.492087) (xy 106.338098 -385.544026)
			(xy 106.301586 -385.591605) (xy 106.259176 -385.634011) (xy 106.211594 -385.670519) (xy 106.159653 -385.700503)
			(xy 106.104243 -385.723451) (xy 106.046311 -385.73897) (xy 105.986849 -385.746793) (xy 105.956862 -385.74726)
			(xy 105.093262 -385.74726) (xy 105.063279 -385.746772) (xy 105.003827 -385.73894) (xy 104.945906 -385.723416)
			(xy 104.890506 -385.700464) (xy 104.838576 -385.670479) (xy 104.791004 -385.633972) (xy 104.748603 -385.591568)
			(xy 104.7121 -385.543992) (xy 104.682119 -385.49206) (xy 104.659172 -385.436658) (xy 104.643653 -385.378736)
			(xy 104.635826 -385.319283) (xy 101.36378 -385.319283) (xy 101.36378 -385.583938) (xy 101.36329 -385.613922)
			(xy 101.355462 -385.673378) (xy 101.339941 -385.731303) (xy 101.316992 -385.786707) (xy 101.287008 -385.838641)
			(xy 101.250502 -385.886217) (xy 101.208097 -385.928622) (xy 101.160521 -385.965128) (xy 101.108587 -385.995112)
			(xy 101.053183 -386.018061) (xy 100.995258 -386.033582) (xy 100.935802 -386.04141) (xy 100.875834 -386.04141)
			(xy 100.816378 -386.033582) (xy 100.758453 -386.018061) (xy 100.703049 -385.995112) (xy 100.651115 -385.965128)
			(xy 100.603539 -385.928622) (xy 100.561134 -385.886217) (xy 100.524628 -385.838641) (xy 100.494644 -385.786707)
			(xy 100.471695 -385.731303) (xy 100.456174 -385.673378) (xy 100.448346 -385.613922) (xy 100.447856 -385.583938)
			(xy 0.508 -385.583938) (xy 0.508 -388.37489) (xy 1.56972 -388.37489) (xy 1.56972 -387.51129) (xy 1.57021 -387.481322)
			(xy 1.578033 -387.4219) (xy 1.593546 -387.364007) (xy 1.616482 -387.308634) (xy 1.646449 -387.256728)
			(xy 1.682936 -387.209178) (xy 1.725316 -387.166798) (xy 1.772866 -387.130311) (xy 1.824772 -387.100344)
			(xy 1.880145 -387.077408) (xy 1.938038 -387.061895) (xy 1.99746 -387.054072) (xy 2.057396 -387.054072)
			(xy 2.116818 -387.061895) (xy 2.174711 -387.077408) (xy 2.230084 -387.100344) (xy 2.28199 -387.130311)
			(xy 2.32954 -387.166798) (xy 2.37192 -387.209178) (xy 2.408407 -387.256728) (xy 2.438374 -387.308634)
			(xy 2.46131 -387.364007) (xy 2.476823 -387.4219) (xy 2.484646 -387.481322) (xy 2.485136 -387.51129)
			(xy 2.485136 -388.37489) (xy 2.484646 -388.404858) (xy 2.476823 -388.46428) (xy 2.46131 -388.522173)
			(xy 2.438374 -388.577546) (xy 2.408407 -388.629452) (xy 2.37192 -388.677002) (xy 2.32954 -388.719382)
			(xy 2.28199 -388.755869) (xy 2.230084 -388.785836) (xy 2.174711 -388.808772) (xy 2.116818 -388.824285)
			(xy 2.057396 -388.832108) (xy 1.99746 -388.832108) (xy 1.938038 -388.824285) (xy 1.880145 -388.808772)
			(xy 1.824772 -388.785836) (xy 1.772866 -388.755869) (xy 1.725316 -388.719382) (xy 1.682936 -388.677002)
			(xy 1.646449 -388.629452) (xy 1.616482 -388.577546) (xy 1.593546 -388.522173) (xy 1.578033 -388.46428)
			(xy 1.57021 -388.404858) (xy 1.56972 -388.37489) (xy 0.508 -388.37489) (xy 0.508 -398.164722) (xy 3.141726 -398.164722)
			(xy 3.141726 -398.035362) (xy 3.149849 -397.906256) (xy 3.166062 -397.777916) (xy 3.190302 -397.650846)
			(xy 3.222472 -397.52555) (xy 3.262447 -397.40252) (xy 3.310068 -397.282244) (xy 3.365147 -397.165195)
			(xy 3.427467 -397.051835) (xy 3.496782 -396.942612) (xy 3.572818 -396.837957) (xy 3.655276 -396.738283)
			(xy 3.743829 -396.643983) (xy 3.838129 -396.55543) (xy 3.937803 -396.472972) (xy 4.042458 -396.396936)
			(xy 4.151681 -396.327621) (xy 4.265041 -396.265301) (xy 4.38209 -396.210222) (xy 4.502366 -396.162601)
			(xy 4.625396 -396.122626) (xy 4.750692 -396.090456) (xy 4.877762 -396.066216) (xy 5.006102 -396.050003)
			(xy 5.135208 -396.04188) (xy 5.199888 -396.041372) (xy 6.800088 -396.041372) (xy 6.864769 -396.041866)
			(xy 6.993875 -396.049988) (xy 7.122217 -396.066201) (xy 7.249287 -396.090441) (xy 7.374584 -396.122612)
			(xy 7.497614 -396.162587) (xy 7.617892 -396.210208) (xy 7.734942 -396.265287) (xy 7.848302 -396.327608)
			(xy 7.957526 -396.396923) (xy 8.062181 -396.47296) (xy 8.161856 -396.555418) (xy 8.256157 -396.643972)
			(xy 8.344711 -396.738272) (xy 8.427169 -396.837947) (xy 8.503206 -396.942603) (xy 8.572521 -397.051826)
			(xy 8.634842 -397.165187) (xy 8.689921 -397.282236) (xy 8.737543 -397.402514) (xy 8.777518 -397.525544)
			(xy 8.809688 -397.650841) (xy 8.833928 -397.777911) (xy 8.839736 -397.823885) (xy 27.348879 -397.823885)
			(xy 27.348883 -397.756458) (xy 27.356962 -397.689518) (xy 27.373001 -397.624027) (xy 27.396769 -397.560929)
			(xy 27.427923 -397.501131) (xy 27.466014 -397.445496) (xy 27.48788 -397.41983) (xy 27.493686 -397.412692)
			(xy 27.500196 -397.395496) (xy 27.50058 -397.386302) (xy 27.50058 -396.89405) (xy 27.50015 -396.884865)
			(xy 27.49365 -396.86768) (xy 27.48788 -396.860522) (xy 27.466007 -396.834865) (xy 27.42792 -396.779228)
			(xy 27.396771 -396.719431) (xy 27.373008 -396.656333) (xy 27.356974 -396.590843) (xy 27.348899 -396.523905)
			(xy 27.3489 -396.45648) (xy 27.356976 -396.389542) (xy 27.373012 -396.324053) (xy 27.396777 -396.260955)
			(xy 27.427928 -396.201159) (xy 27.466016 -396.145524) (xy 27.48788 -396.119858) (xy 27.493675 -396.112711)
			(xy 27.500191 -396.095522) (xy 27.50058 -396.08633) (xy 27.50058 -395.92885) (xy 27.501069 -395.918722)
			(xy 27.508787 -395.899994) (xy 27.523074 -395.885635) (xy 27.541762 -395.877821) (xy 27.551888 -395.877288)
			(xy 28.268168 -395.877288) (xy 28.278319 -395.877747) (xy 28.297068 -395.88553) (xy 28.311392 -395.899915)
			(xy 28.319095 -395.918698) (xy 28.319476 -395.92885) (xy 28.319476 -396.08633) (xy 28.319877 -396.095518)
			(xy 28.326398 -396.112702) (xy 28.332176 -396.119858) (xy 28.354031 -396.145531) (xy 28.392122 -396.201164)
			(xy 28.423274 -396.260959) (xy 28.44704 -396.324055) (xy 28.463077 -396.389543) (xy 28.471154 -396.456481)
			(xy 28.471155 -396.523904) (xy 28.463079 -396.590842) (xy 28.447044 -396.656331) (xy 28.42328 -396.719428)
			(xy 28.392129 -396.779223) (xy 28.35404 -396.834857) (xy 28.332176 -396.860522) (xy 28.326385 -396.867671)
			(xy 28.319868 -396.884859) (xy 28.319476 -396.89405) (xy 28.319476 -397.386302) (xy 28.31989 -397.395489)
			(xy 28.326402 -397.412673) (xy 28.332176 -397.41983) (xy 28.354003 -397.445526) (xy 28.392095 -397.501155)
			(xy 28.420857 -397.556356) (xy 29.549071 -397.556356) (xy 29.557114 -397.489534) (xy 29.573085 -397.424153)
			(xy 29.596756 -397.361149) (xy 29.627787 -397.301425) (xy 29.665733 -397.245838) (xy 29.68752 -397.220186)
			(xy 29.693307 -397.213034) (xy 29.699827 -397.195849) (xy 29.70022 -397.186658) (xy 29.70022 -397.028924)
			(xy 29.700641 -397.018769) (xy 29.708433 -397.000013) (xy 29.72283 -396.985688) (xy 29.741625 -396.977991)
			(xy 29.751782 -396.977616) (xy 30.468062 -396.977616) (xy 30.478183 -396.978157) (xy 30.496899 -396.985868)
			(xy 30.511256 -397.000138) (xy 30.51908 -397.018806) (xy 30.519624 -397.028924) (xy 30.519624 -397.186658)
			(xy 30.520049 -397.195844) (xy 30.526552 -397.213029) (xy 30.532324 -397.220186) (xy 30.554123 -397.24583)
			(xy 30.592074 -397.301416) (xy 30.623108 -397.361141) (xy 30.646782 -397.424147) (xy 30.662756 -397.48953)
			(xy 30.6708 -397.556354) (xy 30.670799 -397.623661) (xy 30.662753 -397.690485) (xy 30.646778 -397.755868)
			(xy 30.623102 -397.818873) (xy 30.620528 -397.823826) (xy 31.749174 -397.823826) (xy 31.749178 -397.756517)
			(xy 31.757226 -397.689691) (xy 31.773204 -397.624307) (xy 31.796882 -397.5613) (xy 31.827922 -397.501576)
			(xy 31.865877 -397.44599) (xy 31.887668 -397.420338) (xy 31.893482 -397.413205) (xy 31.899984 -397.396005)
			(xy 31.900368 -397.38681) (xy 31.900368 -396.893542) (xy 31.899923 -396.884359) (xy 31.893432 -396.867175)
			(xy 31.887668 -396.860014) (xy 31.86587 -396.83437) (xy 31.827919 -396.778783) (xy 31.796885 -396.719059)
			(xy 31.773211 -396.656053) (xy 31.757238 -396.59067) (xy 31.749194 -396.523846) (xy 31.749195 -396.456539)
			(xy 31.757241 -396.389716) (xy 31.773216 -396.324332) (xy 31.796891 -396.261327) (xy 31.827927 -396.201604)
			(xy 31.865879 -396.146018) (xy 31.887668 -396.120366) (xy 31.89347 -396.113225) (xy 31.899979 -396.096031)
			(xy 31.900368 -396.086838) (xy 31.900368 -395.92885) (xy 31.900805 -395.918678) (xy 31.90858 -395.899879)
			(xy 31.922962 -395.885491) (xy 31.941758 -395.877709) (xy 31.95193 -395.877288) (xy 32.66821 -395.877288)
			(xy 32.678388 -395.877657) (xy 32.697193 -395.885455) (xy 32.711579 -395.899858) (xy 32.719355 -395.918671)
			(xy 32.719772 -395.92885) (xy 32.719772 -396.086838) (xy 32.72017 -396.096026) (xy 32.726693 -396.11321)
			(xy 32.732472 -396.120366) (xy 32.75425 -396.146026) (xy 32.792198 -396.201612) (xy 32.823231 -396.261334)
			(xy 32.846904 -396.324338) (xy 32.862877 -396.389719) (xy 32.870922 -396.45654) (xy 32.870923 -396.523845)
			(xy 32.86288 -396.590666) (xy 32.846909 -396.656048) (xy 32.823237 -396.719052) (xy 32.792206 -396.778775)
			(xy 32.754259 -396.834362) (xy 32.732472 -396.860014) (xy 32.726683 -396.867165) (xy 32.720165 -396.884351)
			(xy 32.719772 -396.893542) (xy 32.719772 -397.38681) (xy 32.720183 -397.395997) (xy 32.726697 -397.413181)
			(xy 32.732472 -397.420338) (xy 32.754222 -397.446021) (xy 32.792171 -397.501603) (xy 32.820593 -397.556296)
			(xy 33.948839 -397.556296) (xy 33.956914 -397.489358) (xy 33.972949 -397.423869) (xy 33.996713 -397.360773)
			(xy 34.027863 -397.300977) (xy 34.065952 -397.245343) (xy 34.087816 -397.219678) (xy 34.093606 -397.212528)
			(xy 34.100124 -397.195341) (xy 34.100516 -397.18615) (xy 34.100516 -397.028924) (xy 34.100936 -397.018801)
			(xy 34.108679 -397.000095) (xy 34.122995 -396.985779) (xy 34.141701 -396.978036) (xy 34.151824 -396.977616)
			(xy 34.868104 -396.977616) (xy 34.878229 -396.978013) (xy 34.896935 -396.985766) (xy 34.91125 -397.000088)
			(xy 34.918992 -397.018799) (xy 34.919412 -397.028924) (xy 34.919412 -397.18615) (xy 34.919843 -397.195335)
			(xy 34.926342 -397.21252) (xy 34.932112 -397.219678) (xy 34.953985 -397.245335) (xy 34.992073 -397.300971)
			(xy 35.023223 -397.360769) (xy 35.046986 -397.423867) (xy 35.06302 -397.489356) (xy 35.071095 -397.556295)
			(xy 35.071094 -397.62372) (xy 35.063017 -397.690658) (xy 35.046981 -397.756148) (xy 35.023216 -397.819245)
			(xy 35.020799 -397.823884) (xy 36.148967 -397.823884) (xy 36.148971 -397.756458) (xy 36.15705 -397.689518)
			(xy 36.173088 -397.624028) (xy 36.196855 -397.560929) (xy 36.228008 -397.501132) (xy 36.266099 -397.445496)
			(xy 36.287964 -397.41983) (xy 36.293781 -397.412699) (xy 36.300282 -397.395497) (xy 36.300664 -397.386302)
			(xy 36.300664 -396.89405) (xy 36.300216 -396.884867) (xy 36.293727 -396.867683) (xy 36.287964 -396.860522)
			(xy 36.266091 -396.834864) (xy 36.228005 -396.779228) (xy 36.196857 -396.71943) (xy 36.173095 -396.656332)
			(xy 36.157061 -396.590843) (xy 36.148987 -396.523904) (xy 36.148988 -396.456481) (xy 36.157064 -396.389542)
			(xy 36.1731 -396.324053) (xy 36.196863 -396.260956) (xy 36.228013 -396.201159) (xy 36.266101 -396.145524)
			(xy 36.287964 -396.119858) (xy 36.293769 -396.112719) (xy 36.300277 -396.095523) (xy 36.300664 -396.08633)
			(xy 36.300664 -395.92885) (xy 36.301168 -395.918724) (xy 36.308884 -395.899999) (xy 36.323166 -395.88564)
			(xy 36.341848 -395.877823) (xy 36.351972 -395.877288) (xy 37.068252 -395.877288) (xy 37.078402 -395.877761)
			(xy 37.097151 -395.885538) (xy 37.111475 -395.899919) (xy 37.119179 -395.918699) (xy 37.11956 -395.92885)
			(xy 37.11956 -396.08633) (xy 37.119965 -396.095518) (xy 37.126483 -396.112701) (xy 37.13226 -396.119858)
			(xy 37.154116 -396.145531) (xy 37.192207 -396.201163) (xy 37.223361 -396.260958) (xy 37.247127 -396.324054)
			(xy 37.263164 -396.389543) (xy 37.271242 -396.456481) (xy 37.271243 -396.523904) (xy 37.263167 -396.590843)
			(xy 37.247132 -396.656332) (xy 37.223367 -396.719428) (xy 37.192215 -396.779224) (xy 37.154125 -396.834857)
			(xy 37.13226 -396.860522) (xy 37.126467 -396.867669) (xy 37.119951 -396.884858) (xy 37.11956 -396.89405)
			(xy 37.11956 -397.386302) (xy 37.119978 -397.395488) (xy 37.126487 -397.412672) (xy 37.13226 -397.41983)
			(xy 37.154088 -397.445525) (xy 37.192181 -397.501155) (xy 37.220943 -397.556356) (xy 38.349159 -397.556356)
			(xy 38.357201 -397.489534) (xy 38.373172 -397.424153) (xy 38.396842 -397.361149) (xy 38.427873 -397.301426)
			(xy 38.465818 -397.245839) (xy 38.487604 -397.220186) (xy 38.493389 -397.213033) (xy 38.499911 -397.195848)
			(xy 38.500304 -397.186658) (xy 38.500304 -397.028924) (xy 38.500741 -397.018771) (xy 38.50853 -397.000018)
			(xy 38.522922 -396.985694) (xy 38.541711 -396.977994) (xy 38.551866 -396.977616) (xy 39.268146 -396.977616)
			(xy 39.278273 -396.978088) (xy 39.29699 -396.985827) (xy 39.311344 -397.000117) (xy 39.319166 -397.0188)
			(xy 39.319708 -397.028924) (xy 39.319708 -397.186658) (xy 39.320136 -397.195843) (xy 39.326637 -397.213028)
			(xy 39.332408 -397.220186) (xy 39.354207 -397.245829) (xy 39.392159 -397.301416) (xy 39.423195 -397.36114)
			(xy 39.446869 -397.424146) (xy 39.462843 -397.48953) (xy 39.470887 -397.556354) (xy 39.470887 -397.623661)
			(xy 39.462841 -397.690485) (xy 39.446865 -397.755869) (xy 39.423189 -397.818874) (xy 39.420585 -397.823885)
			(xy 40.548734 -397.823885) (xy 40.548737 -397.756458) (xy 40.556817 -397.689516) (xy 40.572859 -397.624024)
			(xy 40.596629 -397.560925) (xy 40.627787 -397.501128) (xy 40.665884 -397.445494) (xy 40.687752 -397.41983)
			(xy 40.693567 -397.412698) (xy 40.700069 -397.395497) (xy 40.700452 -397.386302) (xy 40.700452 -396.89405)
			(xy 40.700006 -396.884867) (xy 40.693516 -396.867683) (xy 40.687752 -396.860522) (xy 40.665876 -396.834866)
			(xy 40.627785 -396.779231) (xy 40.596631 -396.719434) (xy 40.572865 -396.656336) (xy 40.556829 -396.590845)
			(xy 40.548753 -396.523905) (xy 40.548754 -396.45648) (xy 40.556832 -396.38954) (xy 40.57287 -396.32405)
			(xy 40.596638 -396.260952) (xy 40.627792 -396.201156) (xy 40.665886 -396.145522) (xy 40.687752 -396.119858)
			(xy 40.693555 -396.112718) (xy 40.700065 -396.095523) (xy 40.700452 -396.08633) (xy 40.700452 -395.92885)
			(xy 40.700968 -395.918725) (xy 40.708682 -395.900003) (xy 40.722959 -395.885644) (xy 40.741638 -395.877825)
			(xy 40.75176 -395.877288) (xy 41.46804 -395.877288) (xy 41.478195 -395.877689) (xy 41.496946 -395.885495)
			(xy 41.511268 -395.899898) (xy 41.518968 -395.918693) (xy 41.519348 -395.92885) (xy 41.519348 -396.08633)
			(xy 41.519755 -396.095517) (xy 41.526272 -396.112701) (xy 41.532048 -396.119858) (xy 41.553904 -396.14553)
			(xy 41.591996 -396.201163) (xy 41.62315 -396.260957) (xy 41.646917 -396.324053) (xy 41.662955 -396.389542)
			(xy 41.671033 -396.456481) (xy 41.671034 -396.523904) (xy 41.662958 -396.590843) (xy 41.646922 -396.656332)
			(xy 41.623157 -396.719429) (xy 41.592004 -396.779224) (xy 41.553913 -396.834858) (xy 41.532048 -396.860522)
			(xy 41.526253 -396.867668) (xy 41.519739 -396.884858) (xy 41.519348 -396.89405) (xy 41.519348 -397.386302)
			(xy 41.519769 -397.395488) (xy 41.526276 -397.412672) (xy 41.532048 -397.41983) (xy 41.553876 -397.445525)
			(xy 41.59197 -397.501154) (xy 41.620702 -397.556296) (xy 42.748927 -397.556296) (xy 42.757002 -397.489358)
			(xy 42.773037 -397.42387) (xy 42.7968 -397.360774) (xy 42.827949 -397.300978) (xy 42.866037 -397.245343)
			(xy 42.8879 -397.219678) (xy 42.893688 -397.212527) (xy 42.900208 -397.195341) (xy 42.9006 -397.18615)
			(xy 42.9006 -397.028924) (xy 42.901035 -397.018803) (xy 42.908776 -397.0001) (xy 42.923086 -396.985785)
			(xy 42.941787 -396.978039) (xy 42.951908 -396.977616) (xy 43.668188 -396.977616) (xy 43.678312 -396.978026)
			(xy 43.697018 -396.985773) (xy 43.711333 -397.000092) (xy 43.719076 -397.0188) (xy 43.719496 -397.028924)
			(xy 43.719496 -397.18615) (xy 43.719931 -397.195335) (xy 43.726427 -397.212519) (xy 43.732196 -397.219678)
			(xy 43.75407 -397.245335) (xy 43.792159 -397.300971) (xy 43.823309 -397.360768) (xy 43.847073 -397.423866)
			(xy 43.863108 -397.489356) (xy 43.871183 -397.556295) (xy 43.871182 -397.62372) (xy 43.863105 -397.690659)
			(xy 43.847068 -397.756148) (xy 43.823303 -397.819246) (xy 43.820917 -397.823825) (xy 44.949053 -397.823825)
			(xy 44.949057 -397.756517) (xy 44.957105 -397.689692) (xy 44.973082 -397.624308) (xy 44.996759 -397.561302)
			(xy 45.027796 -397.501577) (xy 45.06575 -397.44599) (xy 45.08754 -397.420338) (xy 45.09335 -397.413203)
			(xy 45.099856 -397.396004) (xy 45.10024 -397.38681) (xy 45.10024 -396.893542) (xy 45.0998 -396.884358)
			(xy 45.093306 -396.867174) (xy 45.08754 -396.860014) (xy 45.065742 -396.83437) (xy 45.027794 -396.778782)
			(xy 44.996761 -396.719058) (xy 44.973088 -396.656052) (xy 44.957116 -396.590669) (xy 44.949073 -396.523845)
			(xy 44.949074 -396.45654) (xy 44.957119 -396.389716) (xy 44.973093 -396.324333) (xy 44.996767 -396.261328)
			(xy 45.027801 -396.201605) (xy 45.065751 -396.146018) (xy 45.08754 -396.120366) (xy 45.093339 -396.113222)
			(xy 45.099851 -396.096031) (xy 45.10024 -396.086838) (xy 45.10024 -395.92885) (xy 45.100705 -395.918681)
			(xy 45.108474 -395.899887) (xy 45.122847 -395.885501) (xy 45.141634 -395.877714) (xy 45.151802 -395.877288)
			(xy 45.868082 -395.877288) (xy 45.878259 -395.87768) (xy 45.897063 -395.885468) (xy 45.91145 -395.899864)
			(xy 45.919227 -395.918673) (xy 45.919644 -395.92885) (xy 45.919644 -396.086838) (xy 45.920049 -396.096026)
			(xy 45.926568 -396.113209) (xy 45.932344 -396.120366) (xy 45.954122 -396.146026) (xy 45.992072 -396.201611)
			(xy 46.023107 -396.261333) (xy 46.046781 -396.324337) (xy 46.062755 -396.389718) (xy 46.070801 -396.45654)
			(xy 46.070801 -396.523845) (xy 46.062758 -396.590667) (xy 46.046786 -396.656049) (xy 46.023113 -396.719053)
			(xy 45.99208 -396.778776) (xy 45.954131 -396.834362) (xy 45.932344 -396.860014) (xy 45.926552 -396.867162)
			(xy 45.920036 -396.884351) (xy 45.919644 -396.893542) (xy 45.919644 -397.38681) (xy 45.920062 -397.395996)
			(xy 45.926572 -397.41318) (xy 45.932344 -397.420338) (xy 45.954095 -397.446021) (xy 45.992046 -397.501602)
			(xy 46.020501 -397.556355) (xy 47.149223 -397.556355) (xy 47.157267 -397.489532) (xy 47.17324 -397.42415)
			(xy 47.196914 -397.361146) (xy 47.227949 -397.301423) (xy 47.265899 -397.245837) (xy 47.287688 -397.220186)
			(xy 47.293472 -397.213032) (xy 47.299994 -397.195848) (xy 47.300388 -397.186658) (xy 47.300388 -397.028924)
			(xy 47.300841 -397.018773) (xy 47.308626 -397.000023) (xy 47.323013 -396.985699) (xy 47.341797 -396.977997)
			(xy 47.35195 -396.977616) (xy 48.06823 -396.977616) (xy 48.078356 -396.978101) (xy 48.097073 -396.985834)
			(xy 48.111427 -397.000121) (xy 48.11925 -397.018801) (xy 48.119792 -397.028924) (xy 48.119792 -397.186658)
			(xy 48.120224 -397.195843) (xy 48.126723 -397.213027) (xy 48.132492 -397.220186) (xy 48.154289 -397.24583)
			(xy 48.192235 -397.301419) (xy 48.223266 -397.361144) (xy 48.246937 -397.424149) (xy 48.262908 -397.489532)
			(xy 48.270951 -397.556355) (xy 48.27095 -397.62366) (xy 48.262906 -397.690483) (xy 48.246933 -397.755865)
			(xy 48.22326 -397.81887) (xy 48.192227 -397.878594) (xy 48.154279 -397.934181) (xy 48.132492 -397.959834)
			(xy 48.126698 -397.966981) (xy 48.120182 -397.98417) (xy 48.119792 -397.993362) (xy 48.119792 -398.486884)
			(xy 48.120212 -398.49607) (xy 48.126719 -398.513254) (xy 48.132492 -398.520412) (xy 48.154314 -398.546035)
			(xy 48.19226 -398.601627) (xy 48.22329 -398.661355) (xy 48.246959 -398.724363) (xy 48.262929 -398.789748)
			(xy 48.27097 -398.856573) (xy 48.270966 -398.923881) (xy 48.262919 -398.990705) (xy 48.246943 -399.056089)
			(xy 48.223268 -399.119095) (xy 48.192232 -399.17882) (xy 48.154281 -399.234407) (xy 48.132492 -399.26006)
			(xy 48.126687 -399.267199) (xy 48.120177 -399.284394) (xy 48.119792 -399.293588) (xy 48.119792 -399.451576)
			(xy 48.119359 -399.46173) (xy 48.11157 -399.480483) (xy 48.097176 -399.494808) (xy 48.078386 -399.502507)
			(xy 48.06823 -399.502884) (xy 47.35195 -399.502884) (xy 47.341829 -399.502333) (xy 47.323114 -399.494626)
			(xy 47.308757 -399.48036) (xy 47.300932 -399.461693) (xy 47.300388 -399.451576) (xy 47.300388 -399.293588)
			(xy 47.299986 -399.2844) (xy 47.293467 -399.267216) (xy 47.287688 -399.26006) (xy 47.265934 -399.234379)
			(xy 47.227981 -399.178798) (xy 47.196944 -399.119079) (xy 47.173267 -399.056078) (xy 47.15729 -398.990699)
			(xy 47.149242 -398.923879) (xy 47.149239 -398.856576) (xy 47.15728 -398.789754) (xy 47.173251 -398.724374)
			(xy 47.196921 -398.661371) (xy 47.227953 -398.601648) (xy 47.265901 -398.546063) (xy 47.287688 -398.520412)
			(xy 47.293503 -398.51328) (xy 47.300007 -398.496079) (xy 47.300388 -398.486884) (xy 47.300388 -397.993362)
			(xy 47.299999 -397.984172) (xy 47.293471 -397.966988) (xy 47.287688 -397.959834) (xy 47.265909 -397.934174)
			(xy 47.227956 -397.87859) (xy 47.19692 -397.818868) (xy 47.173244 -397.755864) (xy 47.157269 -397.690483)
			(xy 47.149224 -397.62366) (xy 47.149223 -397.556355) (xy 46.020501 -397.556355) (xy 46.023082 -397.561322)
			(xy 46.046757 -397.624322) (xy 46.062733 -397.689701) (xy 46.070781 -397.75652) (xy 46.070784 -397.823823)
			(xy 46.062744 -397.890643) (xy 46.046774 -397.956023) (xy 46.023105 -398.019026) (xy 45.992075 -398.078748)
			(xy 45.95413 -398.134334) (xy 45.932344 -398.159986) (xy 45.926522 -398.167113) (xy 45.920024 -398.184318)
			(xy 45.919644 -398.193514) (xy 45.919644 -398.351502) (xy 45.919237 -398.361676) (xy 45.911448 -398.380474)
			(xy 45.897057 -398.39486) (xy 45.878256 -398.402641) (xy 45.868082 -398.403064) (xy 45.151802 -398.403064)
			(xy 45.141645 -398.402565) (xy 45.122876 -398.394792) (xy 45.108511 -398.380427) (xy 45.100736 -398.361659)
			(xy 45.10024 -398.351502) (xy 45.10024 -398.193514) (xy 45.099814 -398.184329) (xy 45.093311 -398.167145)
			(xy 45.08754 -398.159986) (xy 45.065715 -398.134365) (xy 45.027767 -398.078774) (xy 44.996735 -398.019046)
			(xy 44.973065 -397.956037) (xy 44.957094 -397.890651) (xy 44.949053 -397.823825) (xy 43.820917 -397.823825)
			(xy 43.792151 -397.879042) (xy 43.754061 -397.934677) (xy 43.732196 -397.960342) (xy 43.726399 -397.967487)
			(xy 43.719885 -397.984678) (xy 43.719496 -397.99387) (xy 43.719496 -398.486376) (xy 43.719919 -398.495562)
			(xy 43.726424 -398.512746) (xy 43.732196 -398.519904) (xy 43.754095 -398.54554) (xy 43.792183 -398.601179)
			(xy 43.823333 -398.660979) (xy 43.847095 -398.72408) (xy 43.863128 -398.789572) (xy 43.871201 -398.856514)
			(xy 43.871198 -398.92394) (xy 43.863118 -398.990881) (xy 43.847079 -399.056372) (xy 43.823311 -399.119471)
			(xy 43.792156 -399.179268) (xy 43.754062 -399.234903) (xy 43.732196 -399.260568) (xy 43.726388 -399.267705)
			(xy 43.71988 -399.284902) (xy 43.719496 -399.294096) (xy 43.719496 -399.451576) (xy 43.719064 -399.461697)
			(xy 43.711323 -399.480401) (xy 43.697011 -399.494717) (xy 43.678309 -399.502462) (xy 43.668188 -399.502884)
			(xy 42.951908 -399.502884) (xy 42.941784 -399.502477) (xy 42.923078 -399.494729) (xy 42.908762 -399.480409)
			(xy 42.90102 -399.4617) (xy 42.9006 -399.451576) (xy 42.9006 -399.294096) (xy 42.900192 -399.284909)
			(xy 42.893677 -399.267724) (xy 42.8879 -399.260568) (xy 42.866071 -399.234874) (xy 42.827982 -399.179243)
			(xy 42.796829 -399.119451) (xy 42.773063 -399.056358) (xy 42.757025 -398.990872) (xy 42.748946 -398.923937)
			(xy 42.748943 -398.856517) (xy 42.757015 -398.789581) (xy 42.773047 -398.724094) (xy 42.796807 -398.660998)
			(xy 42.827954 -398.601203) (xy 42.866038 -398.545569) (xy 42.8879 -398.519904) (xy 42.893677 -398.512745)
			(xy 42.900204 -398.495565) (xy 42.9006 -398.486376) (xy 42.9006 -397.99387) (xy 42.900204 -397.984681)
			(xy 42.893681 -397.967497) (xy 42.8879 -397.960342) (xy 42.866046 -397.934669) (xy 42.827957 -397.879035)
			(xy 42.796806 -397.81924) (xy 42.773041 -397.756144) (xy 42.757005 -397.690656) (xy 42.748928 -397.623719)
			(xy 42.748927 -397.556296) (xy 41.620702 -397.556296) (xy 41.623125 -397.560946) (xy 41.646894 -397.624039)
			(xy 41.662933 -397.689525) (xy 41.671013 -397.756461) (xy 41.671016 -397.823882) (xy 41.662944 -397.890819)
			(xy 41.646911 -397.956307) (xy 41.623148 -398.019402) (xy 41.591999 -398.079197) (xy 41.553912 -398.13483)
			(xy 41.532048 -398.160494) (xy 41.526265 -398.167649) (xy 41.519744 -398.184832) (xy 41.519348 -398.194022)
			(xy 41.519348 -398.351502) (xy 41.518875 -398.36163) (xy 41.511144 -398.380354) (xy 41.496853 -398.39471)
			(xy 41.478166 -398.402527) (xy 41.46804 -398.403064) (xy 40.75176 -398.403064) (xy 40.741599 -398.40271)
			(xy 40.722839 -398.394895) (xy 40.708515 -398.380477) (xy 40.700824 -398.361666) (xy 40.700452 -398.351502)
			(xy 40.700452 -398.194022) (xy 40.70002 -398.184837) (xy 40.69352 -398.167653) (xy 40.687752 -398.160494)
			(xy 40.665849 -398.13486) (xy 40.627758 -398.079223) (xy 40.596606 -398.019423) (xy 40.572842 -397.956321)
			(xy 40.556807 -397.890828) (xy 40.548734 -397.823885) (xy 39.420585 -397.823885) (xy 39.392151 -397.878597)
			(xy 39.354198 -397.934183) (xy 39.332408 -397.959834) (xy 39.326615 -397.966982) (xy 39.320098 -397.98417)
			(xy 39.319708 -397.993362) (xy 39.319708 -398.486884) (xy 39.320124 -398.496071) (xy 39.326633 -398.513255)
			(xy 39.332408 -398.520412) (xy 39.354233 -398.546034) (xy 39.392184 -398.601624) (xy 39.423219 -398.661351)
			(xy 39.446892 -398.72436) (xy 39.462864 -398.789746) (xy 39.470906 -398.856573) (xy 39.470902 -398.923882)
			(xy 39.462854 -398.990707) (xy 39.446876 -399.056092) (xy 39.423196 -399.119098) (xy 39.392156 -399.178823)
			(xy 39.354199 -399.234409) (xy 39.332408 -399.26006) (xy 39.326604 -399.2672) (xy 39.320094 -399.284395)
			(xy 39.319708 -399.293588) (xy 39.319708 -399.451576) (xy 39.319259 -399.461728) (xy 39.311473 -399.480478)
			(xy 39.297085 -399.494802) (xy 39.278299 -399.502504) (xy 39.268146 -399.502884) (xy 38.551866 -399.502884)
			(xy 38.54174 -399.502402) (xy 38.523023 -399.494668) (xy 38.508668 -399.48038) (xy 38.500846 -399.4617)
			(xy 38.500304 -399.451576) (xy 38.500304 -399.293588) (xy 38.499899 -399.2844) (xy 38.493381 -399.267216)
			(xy 38.487604 -399.26006) (xy 38.465853 -399.234378) (xy 38.427905 -399.178795) (xy 38.396872 -399.119075)
			(xy 38.373199 -399.056075) (xy 38.357224 -398.990697) (xy 38.349178 -398.923878) (xy 38.349175 -398.856576)
			(xy 38.357215 -398.789757) (xy 38.373183 -398.724377) (xy 38.39685 -398.661374) (xy 38.427877 -398.601651)
			(xy 38.465819 -398.546065) (xy 38.487604 -398.520412) (xy 38.493421 -398.513281) (xy 38.499923 -398.49608)
			(xy 38.500304 -398.486884) (xy 38.500304 -397.993362) (xy 38.499911 -397.984173) (xy 38.493385 -397.966989)
			(xy 38.487604 -397.959834) (xy 38.465827 -397.934173) (xy 38.42788 -397.878587) (xy 38.396849 -397.818865)
			(xy 38.373177 -397.755861) (xy 38.357204 -397.69048) (xy 38.34916 -397.623659) (xy 38.349159 -397.556356)
			(xy 37.220943 -397.556356) (xy 37.223335 -397.560946) (xy 37.247103 -397.624039) (xy 37.263142 -397.689525)
			(xy 37.271222 -397.756461) (xy 37.271225 -397.823882) (xy 37.263153 -397.890819) (xy 37.24712 -397.956306)
			(xy 37.223358 -398.019402) (xy 37.19221 -398.079196) (xy 37.154123 -398.134829) (xy 37.13226 -398.160494)
			(xy 37.126478 -398.16765) (xy 37.119956 -398.184832) (xy 37.11956 -398.194022) (xy 37.11956 -398.351502)
			(xy 37.119075 -398.361629) (xy 37.111347 -398.38035) (xy 37.09706 -398.394706) (xy 37.078376 -398.402525)
			(xy 37.068252 -398.403064) (xy 36.351972 -398.403064) (xy 36.341812 -398.402701) (xy 36.323052 -398.394889)
			(xy 36.308728 -398.380474) (xy 36.301036 -398.361665) (xy 36.300664 -398.351502) (xy 36.300664 -398.194022)
			(xy 36.300229 -398.184838) (xy 36.293731 -398.167654) (xy 36.287964 -398.160494) (xy 36.266064 -398.134859)
			(xy 36.227979 -398.079219) (xy 36.196832 -398.019419) (xy 36.173071 -397.956318) (xy 36.15704 -397.890825)
			(xy 36.148967 -397.823884) (xy 35.020799 -397.823884) (xy 34.992065 -397.879042) (xy 34.953976 -397.934677)
			(xy 34.932112 -397.960342) (xy 34.926316 -397.967488) (xy 34.919801 -397.984678) (xy 34.919412 -397.99387)
			(xy 34.919412 -398.486376) (xy 34.919831 -398.495562) (xy 34.926338 -398.512747) (xy 34.932112 -398.519904)
			(xy 34.954011 -398.54554) (xy 34.992098 -398.601179) (xy 35.023246 -398.66098) (xy 35.047008 -398.72408)
			(xy 35.06304 -398.789573) (xy 35.071113 -398.856514) (xy 35.07111 -398.92394) (xy 35.063031 -398.990881)
			(xy 35.046992 -399.056372) (xy 35.023224 -399.11947) (xy 34.99207 -399.179267) (xy 34.953978 -399.234903)
			(xy 34.932112 -399.260568) (xy 34.926305 -399.267706) (xy 34.919796 -399.284902) (xy 34.919412 -399.294096)
			(xy 34.919412 -399.451576) (xy 34.918965 -399.461695) (xy 34.911227 -399.480396) (xy 34.89692 -399.494711)
			(xy 34.878223 -399.502459) (xy 34.868104 -399.502884) (xy 34.151824 -399.502884) (xy 34.141701 -399.502464)
			(xy 34.122995 -399.494721) (xy 34.108679 -399.480405) (xy 34.100936 -399.461699) (xy 34.100516 -399.451576)
			(xy 34.100516 -399.294096) (xy 34.100104 -399.284909) (xy 34.093591 -399.267725) (xy 34.087816 -399.260568)
			(xy 34.065987 -399.234874) (xy 34.027896 -399.179244) (xy 33.996743 -399.119452) (xy 33.972976 -399.056359)
			(xy 33.956937 -398.990873) (xy 33.948858 -398.923938) (xy 33.948855 -398.856516) (xy 33.956928 -398.78958)
			(xy 33.97296 -398.724093) (xy 33.996721 -398.660998) (xy 34.027868 -398.601203) (xy 34.065954 -398.545569)
			(xy 34.087816 -398.519904) (xy 34.093595 -398.512747) (xy 34.10012 -398.495565) (xy 34.100516 -398.486376)
			(xy 34.100516 -397.99387) (xy 34.100117 -397.984682) (xy 34.093595 -397.967498) (xy 34.087816 -397.960342)
			(xy 34.065961 -397.934669) (xy 34.027871 -397.879036) (xy 33.996719 -397.819241) (xy 33.972954 -397.756145)
			(xy 33.956917 -397.690657) (xy 33.94884 -397.623719) (xy 33.948839 -397.556296) (xy 32.820593 -397.556296)
			(xy 32.823205 -397.561323) (xy 32.84688 -397.624323) (xy 32.862855 -397.689702) (xy 32.870902 -397.756521)
			(xy 32.870905 -397.823822) (xy 32.862865 -397.890642) (xy 32.846897 -397.956022) (xy 32.823229 -398.019025)
			(xy 32.7922 -398.078747) (xy 32.754257 -398.134334) (xy 32.732472 -398.159986) (xy 32.726653 -398.167115)
			(xy 32.720152 -398.184318) (xy 32.719772 -398.193514) (xy 32.719772 -398.351502) (xy 32.719268 -398.361659)
			(xy 32.711495 -398.380426) (xy 32.697133 -398.394791) (xy 32.678367 -398.402567) (xy 32.66821 -398.403064)
			(xy 31.95193 -398.403064) (xy 31.941761 -398.402611) (xy 31.922967 -398.394837) (xy 31.908581 -398.38046)
			(xy 31.900795 -398.361671) (xy 31.900368 -398.351502) (xy 31.900368 -398.193514) (xy 31.899936 -398.184329)
			(xy 31.893436 -398.167146) (xy 31.887668 -398.159986) (xy 31.865842 -398.134365) (xy 31.827892 -398.078775)
			(xy 31.796859 -398.019047) (xy 31.773187 -397.956039) (xy 31.757216 -397.890652) (xy 31.749174 -397.823826)
			(xy 30.620528 -397.823826) (xy 30.592066 -397.878596) (xy 30.554113 -397.934182) (xy 30.532324 -397.959834)
			(xy 30.526533 -397.966984) (xy 30.520014 -397.984171) (xy 30.519624 -397.993362) (xy 30.519624 -398.486884)
			(xy 30.520036 -398.496071) (xy 30.526548 -398.513256) (xy 30.532324 -398.520412) (xy 30.554149 -398.546034)
			(xy 30.592099 -398.601624) (xy 30.623132 -398.661352) (xy 30.646805 -398.72436) (xy 30.662776 -398.789746)
			(xy 30.670818 -398.856573) (xy 30.670815 -398.923881) (xy 30.662767 -398.990707) (xy 30.646789 -399.056092)
			(xy 30.62311 -399.119098) (xy 30.592071 -399.178822) (xy 30.554115 -399.234409) (xy 30.532324 -399.26006)
			(xy 30.526522 -399.267202) (xy 30.52001 -399.284395) (xy 30.519624 -399.293588) (xy 30.519624 -399.451576)
			(xy 30.519159 -399.461726) (xy 30.511376 -399.480473) (xy 30.496993 -399.494796) (xy 30.478213 -399.502501)
			(xy 30.468062 -399.502884) (xy 29.751782 -399.502884) (xy 29.741657 -399.502389) (xy 29.72294 -399.49466)
			(xy 29.708585 -399.480377) (xy 29.700762 -399.461698) (xy 29.70022 -399.451576) (xy 29.70022 -399.293588)
			(xy 29.699811 -399.284401) (xy 29.693296 -399.267217) (xy 29.68752 -399.26006) (xy 29.665769 -399.234378)
			(xy 29.62782 -399.178796) (xy 29.596786 -399.119076) (xy 29.573112 -399.056075) (xy 29.557137 -398.990697)
			(xy 29.549091 -398.923878) (xy 29.549087 -398.856576) (xy 29.557128 -398.789756) (xy 29.573096 -398.724376)
			(xy 29.596764 -398.661374) (xy 29.627792 -398.601651) (xy 29.665735 -398.546065) (xy 29.68752 -398.520412)
			(xy 29.693339 -398.513283) (xy 29.69984 -398.49608) (xy 29.70022 -398.486884) (xy 29.70022 -397.993362)
			(xy 29.699824 -397.984173) (xy 29.6933 -397.966989) (xy 29.68752 -397.959834) (xy 29.665743 -397.934174)
			(xy 29.627795 -397.878588) (xy 29.596762 -397.818865) (xy 29.57309 -397.755862) (xy 29.557116 -397.690481)
			(xy 29.549072 -397.623659) (xy 29.549071 -397.556356) (xy 28.420857 -397.556356) (xy 28.423249 -397.560947)
			(xy 28.447016 -397.62404) (xy 28.463055 -397.689526) (xy 28.471134 -397.756461) (xy 28.471138 -397.823882)
			(xy 28.463065 -397.890818) (xy 28.447033 -397.956305) (xy 28.423272 -398.019401) (xy 28.392124 -398.079196)
			(xy 28.354039 -398.134829) (xy 28.332176 -398.160494) (xy 28.326397 -398.167651) (xy 28.319873 -398.184833)
			(xy 28.319476 -398.194022) (xy 28.319476 -398.351502) (xy 28.318975 -398.361627) (xy 28.31125 -398.380345)
			(xy 28.296968 -398.394701) (xy 28.27829 -398.402523) (xy 28.268168 -398.403064) (xy 27.551888 -398.403064)
			(xy 27.541729 -398.402688) (xy 27.522969 -398.394881) (xy 27.508645 -398.38047) (xy 27.500952 -398.361664)
			(xy 27.50058 -398.351502) (xy 27.50058 -398.194022) (xy 27.500164 -398.184835) (xy 27.493655 -398.167651)
			(xy 27.48788 -398.160494) (xy 27.465979 -398.134859) (xy 27.427893 -398.07922) (xy 27.396745 -398.019419)
			(xy 27.372984 -397.956318) (xy 27.356952 -397.890826) (xy 27.348879 -397.823885) (xy 8.839736 -397.823885)
			(xy 8.850142 -397.906253) (xy 8.858264 -398.035359) (xy 8.858264 -398.164721) (xy 8.850142 -398.293827)
			(xy 8.833928 -398.422169) (xy 8.809688 -398.549239) (xy 8.777518 -398.674536) (xy 8.737543 -398.797566)
			(xy 8.689921 -398.917844) (xy 8.634842 -399.034893) (xy 8.572521 -399.148254) (xy 8.503206 -399.257477)
			(xy 8.427169 -399.362133) (xy 8.344711 -399.461808) (xy 8.256157 -399.556108) (xy 8.161856 -399.644662)
			(xy 8.062181 -399.72712) (xy 7.957526 -399.803157) (xy 7.848302 -399.872472) (xy 7.734942 -399.934793)
			(xy 7.617892 -399.989872) (xy 7.497614 -400.037493) (xy 7.374584 -400.077468) (xy 7.249287 -400.109639)
			(xy 7.122217 -400.133879) (xy 6.993875 -400.150092) (xy 6.864769 -400.158214) (xy 6.800088 -400.158712)
			(xy 5.199888 -400.158712) (xy 5.135208 -400.158204) (xy 5.006102 -400.150081) (xy 4.877762 -400.133868)
			(xy 4.750692 -400.109628) (xy 4.625396 -400.077458) (xy 4.502366 -400.037483) (xy 4.38209 -399.989862)
			(xy 4.265041 -399.934783) (xy 4.151681 -399.872463) (xy 4.042458 -399.803148) (xy 3.937803 -399.727112)
			(xy 3.838129 -399.644654) (xy 3.743829 -399.556101) (xy 3.655276 -399.461801) (xy 3.572818 -399.362127)
			(xy 3.496782 -399.257472) (xy 3.427467 -399.148249) (xy 3.365147 -399.034889) (xy 3.310068 -398.91784)
			(xy 3.262447 -398.797564) (xy 3.222472 -398.674534) (xy 3.190302 -398.549238) (xy 3.166062 -398.422168)
			(xy 3.149849 -398.293828) (xy 3.141726 -398.164722) (xy 0.508 -398.164722) (xy 0.508 -401.723796)
			(xy 27.348891 -401.723796) (xy 27.348893 -401.656371) (xy 27.35697 -401.589432) (xy 27.373007 -401.523942)
			(xy 27.396773 -401.460844) (xy 27.427925 -401.401047) (xy 27.466015 -401.345412) (xy 27.48788 -401.319746)
			(xy 27.49368 -401.312603) (xy 27.500193 -401.295411) (xy 27.50058 -401.286218) (xy 27.50058 -400.793966)
			(xy 27.500191 -400.784777) (xy 27.493663 -400.767592) (xy 27.48788 -400.760438) (xy 27.466023 -400.734768)
			(xy 27.427935 -400.679133) (xy 27.396785 -400.619338) (xy 27.373022 -400.556241) (xy 27.356986 -400.490753)
			(xy 27.34891 -400.423816) (xy 27.34891 -400.356393) (xy 27.356985 -400.289456) (xy 27.373019 -400.223967)
			(xy 27.396782 -400.160871) (xy 27.42793 -400.101074) (xy 27.466017 -400.04544) (xy 27.48788 -400.019774)
			(xy 27.493668 -400.012622) (xy 27.500188 -399.995437) (xy 27.50058 -399.986246) (xy 27.50058 -399.828766)
			(xy 27.501 -399.818632) (xy 27.508746 -399.799903) (xy 27.523053 -399.785546) (xy 27.541756 -399.777735)
			(xy 27.551888 -399.777204) (xy 28.268168 -399.777204) (xy 28.278321 -399.777648) (xy 28.297073 -399.785433)
			(xy 28.311398 -399.799824) (xy 28.319098 -399.818612) (xy 28.319476 -399.828766) (xy 28.319476 -399.986246)
			(xy 28.319918 -399.99543) (xy 28.32641 -400.012614) (xy 28.332176 -400.019774) (xy 28.354047 -400.045434)
			(xy 28.392137 -400.101069) (xy 28.423289 -400.160865) (xy 28.447053 -400.223963) (xy 28.463089 -400.289453)
			(xy 28.471165 -400.356392) (xy 28.471165 -400.423817) (xy 28.463088 -400.490756) (xy 28.447051 -400.556246)
			(xy 28.423285 -400.619343) (xy 28.392132 -400.679139) (xy 28.354041 -400.734773) (xy 28.332176 -400.760438)
			(xy 28.326378 -400.767582) (xy 28.319865 -400.784774) (xy 28.319476 -400.793966) (xy 28.319476 -401.286218)
			(xy 28.319883 -401.295405) (xy 28.326399 -401.31259) (xy 28.332176 -401.319746) (xy 28.354019 -401.345429)
			(xy 28.39211 -401.40106) (xy 28.423263 -401.460854) (xy 28.446989 -401.523838) (xy 29.549051 -401.523838)
			(xy 29.549053 -401.456532) (xy 29.557098 -401.389708) (xy 29.573073 -401.324325) (xy 29.596747 -401.26132)
			(xy 29.627782 -401.201596) (xy 29.665732 -401.146008) (xy 29.68752 -401.120356) (xy 29.69332 -401.113213)
			(xy 29.699832 -401.096021) (xy 29.70022 -401.086828) (xy 29.70022 -400.92884) (xy 29.700655 -400.918686)
			(xy 29.708441 -400.899931) (xy 29.722834 -400.885605) (xy 29.741626 -400.877908) (xy 29.751782 -400.877532)
			(xy 30.468062 -400.877532) (xy 30.478185 -400.878058) (xy 30.496904 -400.885771) (xy 30.511261 -400.900046)
			(xy 30.519083 -400.91872) (xy 30.519624 -400.92884) (xy 30.519624 -401.086828) (xy 30.520015 -401.096017)
			(xy 30.526542 -401.113202) (xy 30.532324 -401.120356) (xy 30.554093 -401.146024) (xy 30.592045 -401.201607)
			(xy 30.623081 -401.261328) (xy 30.646757 -401.324331) (xy 30.662732 -401.389711) (xy 30.670778 -401.456533)
			(xy 30.67078 -401.523837) (xy 30.662738 -401.590659) (xy 30.646766 -401.65604) (xy 30.623093 -401.719044)
			(xy 30.620654 -401.723737) (xy 31.749186 -401.723737) (xy 31.749188 -401.65643) (xy 31.757235 -401.589605)
			(xy 31.773211 -401.524221) (xy 31.796887 -401.461216) (xy 31.827925 -401.401492) (xy 31.865878 -401.345906)
			(xy 31.887668 -401.320254) (xy 31.893475 -401.313116) (xy 31.899981 -401.29592) (xy 31.900368 -401.286726)
			(xy 31.900368 -400.793458) (xy 31.899963 -400.784271) (xy 31.893444 -400.767087) (xy 31.887668 -400.75993)
			(xy 31.865885 -400.734273) (xy 31.827935 -400.678688) (xy 31.796899 -400.618966) (xy 31.773225 -400.555962)
			(xy 31.757251 -400.49058) (xy 31.749206 -400.423757) (xy 31.749205 -400.356452) (xy 31.757249 -400.289629)
			(xy 31.773222 -400.224247) (xy 31.796896 -400.161243) (xy 31.82793 -400.10152) (xy 31.86588 -400.045934)
			(xy 31.887668 -400.020282) (xy 31.893463 -400.013136) (xy 31.899977 -399.995946) (xy 31.900368 -399.986754)
			(xy 31.900368 -399.828766) (xy 31.900806 -399.818602) (xy 31.908597 -399.799827) (xy 31.92298 -399.785462)
			(xy 31.941766 -399.777694) (xy 31.95193 -399.777204) (xy 32.66821 -399.777204) (xy 32.678364 -399.777725)
			(xy 32.697127 -399.785496) (xy 32.711491 -399.799853) (xy 32.719271 -399.818612) (xy 32.719772 -399.828766)
			(xy 32.719772 -399.986754) (xy 32.720211 -399.995938) (xy 32.726705 -400.013122) (xy 32.732472 -400.020282)
			(xy 32.754265 -400.045929) (xy 32.792213 -400.101517) (xy 32.823246 -400.161241) (xy 32.846918 -400.224246)
			(xy 32.86289 -400.289629) (xy 32.870933 -400.356452) (xy 32.870933 -400.423757) (xy 32.862888 -400.49058)
			(xy 32.846915 -400.555962) (xy 32.823242 -400.618967) (xy 32.792209 -400.678691) (xy 32.75426 -400.734278)
			(xy 32.732472 -400.75993) (xy 32.726677 -400.767076) (xy 32.720162 -400.784266) (xy 32.719772 -400.793458)
			(xy 32.719772 -401.286726) (xy 32.720176 -401.295914) (xy 32.726695 -401.313098) (xy 32.732472 -401.320254)
			(xy 32.754237 -401.345924) (xy 32.792186 -401.401508) (xy 32.82322 -401.46123) (xy 32.846893 -401.524232)
			(xy 32.862868 -401.589612) (xy 32.870913 -401.656432) (xy 32.870915 -401.723735) (xy 32.862873 -401.790556)
			(xy 32.846903 -401.855937) (xy 32.823233 -401.91894) (xy 32.792203 -401.978663) (xy 32.754258 -402.03425)
			(xy 32.732472 -402.059902) (xy 32.726688 -402.067056) (xy 32.720167 -402.08424) (xy 32.719772 -402.09343)
			(xy 32.719772 -402.251418) (xy 32.719282 -402.261576) (xy 32.711503 -402.280343) (xy 32.697137 -402.294708)
			(xy 32.678368 -402.302483) (xy 32.66821 -402.30298) (xy 31.95193 -402.30298) (xy 31.941763 -402.302512)
			(xy 31.922972 -402.29474) (xy 31.908587 -402.280368) (xy 31.900798 -402.261585) (xy 31.900368 -402.251418)
			(xy 31.900368 -402.09343) (xy 31.899928 -402.084246) (xy 31.893434 -402.067062) (xy 31.887668 -402.059902)
			(xy 31.865858 -402.034268) (xy 31.827908 -401.97868) (xy 31.796874 -401.918954) (xy 31.773201 -401.855947)
			(xy 31.757229 -401.790562) (xy 31.749186 -401.723737) (xy 30.620654 -401.723737) (xy 30.59206 -401.778767)
			(xy 30.554112 -401.834352) (xy 30.532324 -401.860004) (xy 30.526546 -401.867163) (xy 30.520019 -401.884343)
			(xy 30.519624 -401.893532) (xy 30.519624 -402.3868) (xy 30.520029 -402.395988) (xy 30.526546 -402.413172)
			(xy 30.532324 -402.420328) (xy 30.554114 -402.445978) (xy 30.592063 -402.501565) (xy 30.623097 -402.561289)
			(xy 30.64677 -402.624293) (xy 30.662743 -402.689676) (xy 30.670787 -402.756499) (xy 30.670787 -402.823804)
			(xy 30.670778 -402.823878) (xy 33.948799 -402.823878) (xy 33.948804 -402.75645) (xy 33.956885 -402.689508)
			(xy 33.972926 -402.624016) (xy 33.996696 -402.560917) (xy 34.027853 -402.50112) (xy 34.065949 -402.445485)
			(xy 34.087816 -402.41982) (xy 34.093631 -402.412688) (xy 34.100134 -402.395487) (xy 34.100516 -402.386292)
			(xy 34.100516 -401.89404) (xy 34.100083 -401.884855) (xy 34.093585 -401.867671) (xy 34.087816 -401.860512)
			(xy 34.065932 -401.834863) (xy 34.027843 -401.779227) (xy 33.996692 -401.719428) (xy 33.972928 -401.656329)
			(xy 33.956894 -401.590838) (xy 33.948819 -401.523898) (xy 33.948821 -401.456472) (xy 33.956899 -401.389532)
			(xy 33.972937 -401.324042) (xy 33.996704 -401.260944) (xy 34.027858 -401.201147) (xy 34.06595 -401.145513)
			(xy 34.087816 -401.119848) (xy 34.093619 -401.112707) (xy 34.100129 -401.095513) (xy 34.100516 -401.08632)
			(xy 34.100516 -400.92884) (xy 34.100949 -400.918718) (xy 34.108687 -400.900012) (xy 34.122999 -400.885696)
			(xy 34.141702 -400.877952) (xy 34.151824 -400.877532) (xy 34.868104 -400.877532) (xy 34.878231 -400.877914)
			(xy 34.89694 -400.885669) (xy 34.911256 -400.899997) (xy 34.918995 -400.918713) (xy 34.919412 -400.92884)
			(xy 34.919412 -401.08632) (xy 34.91981 -401.095509) (xy 34.926332 -401.112693) (xy 34.932112 -401.119848)
			(xy 34.953956 -401.14553) (xy 34.992044 -401.201162) (xy 35.023195 -401.260956) (xy 35.04696 -401.324051)
			(xy 35.062997 -401.389538) (xy 35.071074 -401.456474) (xy 35.071076 -401.523896) (xy 35.063002 -401.590833)
			(xy 35.046969 -401.65632) (xy 35.023208 -401.719416) (xy 35.020926 -401.723796) (xy 36.148978 -401.723796)
			(xy 36.14898 -401.656371) (xy 36.157058 -401.589432) (xy 36.173095 -401.523942) (xy 36.19686 -401.460845)
			(xy 36.228011 -401.401047) (xy 36.2661 -401.345412) (xy 36.287964 -401.319746) (xy 36.293774 -401.312611)
			(xy 36.300279 -401.295412) (xy 36.300664 -401.286218) (xy 36.300664 -400.793966) (xy 36.300256 -400.784779)
			(xy 36.293739 -400.767595) (xy 36.287964 -400.760438) (xy 36.266107 -400.734767) (xy 36.228021 -400.679133)
			(xy 36.196872 -400.619337) (xy 36.173109 -400.556241) (xy 36.157074 -400.490753) (xy 36.148998 -400.423816)
			(xy 36.148998 -400.356393) (xy 36.157072 -400.289456) (xy 36.173106 -400.223968) (xy 36.196868 -400.160871)
			(xy 36.228016 -400.101075) (xy 36.266102 -400.04544) (xy 36.287964 -400.019774) (xy 36.293762 -400.01263)
			(xy 36.300274 -399.995438) (xy 36.300664 -399.986246) (xy 36.300664 -399.828766) (xy 36.301099 -399.818634)
			(xy 36.308843 -399.799908) (xy 36.323145 -399.785552) (xy 36.341842 -399.777738) (xy 36.351972 -399.777204)
			(xy 37.068252 -399.777204) (xy 37.078404 -399.777661) (xy 37.097156 -399.785442) (xy 37.111481 -399.799828)
			(xy 37.119181 -399.818613) (xy 37.11956 -399.828766) (xy 37.11956 -399.986246) (xy 37.120005 -399.995429)
			(xy 37.126496 -400.012613) (xy 37.13226 -400.019774) (xy 37.154131 -400.045434) (xy 37.192222 -400.101068)
			(xy 37.223375 -400.160865) (xy 37.247141 -400.223962) (xy 37.263177 -400.289453) (xy 37.271253 -400.356392)
			(xy 37.271252 -400.423817) (xy 37.263175 -400.490756) (xy 37.247138 -400.556246) (xy 37.223371 -400.619344)
			(xy 37.192218 -400.67914) (xy 37.154126 -400.734773) (xy 37.13226 -400.760438) (xy 37.12646 -400.76758)
			(xy 37.119948 -400.784773) (xy 37.11956 -400.793966) (xy 37.11956 -401.286218) (xy 37.11997 -401.295405)
			(xy 37.126485 -401.312589) (xy 37.13226 -401.319746) (xy 37.154104 -401.345428) (xy 37.192196 -401.40106)
			(xy 37.22335 -401.460853) (xy 37.247117 -401.523948) (xy 37.263155 -401.589435) (xy 37.271233 -401.656372)
			(xy 37.271235 -401.723795) (xy 37.263161 -401.790732) (xy 37.247127 -401.856221) (xy 37.223363 -401.919317)
			(xy 37.192213 -401.979112) (xy 37.154124 -402.034745) (xy 37.13226 -402.06041) (xy 37.126472 -402.067561)
			(xy 37.119953 -402.084747) (xy 37.11956 -402.093938) (xy 37.11956 -402.251418) (xy 37.119088 -402.261546)
			(xy 37.111355 -402.280268) (xy 37.097064 -402.294623) (xy 37.078378 -402.302442) (xy 37.068252 -402.30298)
			(xy 36.351972 -402.30298) (xy 36.341814 -402.302601) (xy 36.323057 -402.294792) (xy 36.308734 -402.280383)
			(xy 36.301038 -402.261579) (xy 36.300664 -402.251418) (xy 36.300664 -402.093938) (xy 36.300221 -402.084755)
			(xy 36.293729 -402.067571) (xy 36.287964 -402.06041) (xy 36.26608 -402.034762) (xy 36.227994 -401.979124)
			(xy 36.196846 -401.919325) (xy 36.173085 -401.856226) (xy 36.157052 -401.790735) (xy 36.148978 -401.723796)
			(xy 35.020926 -401.723796) (xy 34.99206 -401.779212) (xy 34.953974 -401.834847) (xy 34.932112 -401.860512)
			(xy 34.926329 -401.867667) (xy 34.919806 -401.88485) (xy 34.919412 -401.89404) (xy 34.919412 -402.386292)
			(xy 34.919823 -402.395479) (xy 34.926336 -402.412664) (xy 34.932112 -402.41982) (xy 34.953928 -402.445524)
			(xy 34.992018 -402.501154) (xy 35.02317 -402.560944) (xy 35.046936 -402.624036) (xy 35.062975 -402.68952)
			(xy 35.071054 -402.756454) (xy 35.071059 -402.823818) (xy 38.349119 -402.823818) (xy 38.349123 -402.75651)
			(xy 38.357172 -402.689685) (xy 38.373149 -402.6243) (xy 38.396825 -402.561294) (xy 38.427862 -402.501569)
			(xy 38.465814 -402.445981) (xy 38.487604 -402.420328) (xy 38.493414 -402.413192) (xy 38.499921 -402.395995)
			(xy 38.500304 -402.3868) (xy 38.500304 -401.893532) (xy 38.499878 -401.884347) (xy 38.493375 -401.867162)
			(xy 38.487604 -401.860004) (xy 38.465798 -401.834368) (xy 38.427852 -401.778778) (xy 38.396821 -401.719052)
			(xy 38.373151 -401.656045) (xy 38.357181 -401.590662) (xy 38.349139 -401.523838) (xy 38.34914 -401.456532)
			(xy 38.357186 -401.389709) (xy 38.37316 -401.324326) (xy 38.396834 -401.261321) (xy 38.427867 -401.201596)
			(xy 38.465816 -401.146009) (xy 38.487604 -401.120356) (xy 38.493402 -401.113212) (xy 38.499916 -401.096021)
			(xy 38.500304 -401.086828) (xy 38.500304 -400.92884) (xy 38.500755 -400.918688) (xy 38.508538 -400.899936)
			(xy 38.522926 -400.885611) (xy 38.541712 -400.87791) (xy 38.551866 -400.877532) (xy 39.268146 -400.877532)
			(xy 39.278275 -400.877989) (xy 39.296995 -400.88573) (xy 39.31135 -400.900025) (xy 39.319169 -400.918714)
			(xy 39.319708 -400.92884) (xy 39.319708 -401.086828) (xy 39.320103 -401.096017) (xy 39.326627 -401.113201)
			(xy 39.332408 -401.120356) (xy 39.354178 -401.146024) (xy 39.392131 -401.201607) (xy 39.423168 -401.261328)
			(xy 39.446844 -401.32433) (xy 39.46282 -401.389711) (xy 39.470866 -401.456533) (xy 39.470868 -401.523837)
			(xy 39.462825 -401.590659) (xy 39.446853 -401.656041) (xy 39.42318 -401.719045) (xy 39.420711 -401.723797)
			(xy 40.548745 -401.723797) (xy 40.548747 -401.65637) (xy 40.556826 -401.58943) (xy 40.572865 -401.523939)
			(xy 40.596634 -401.460841) (xy 40.62779 -401.401044) (xy 40.665885 -401.34541) (xy 40.687752 -401.319746)
			(xy 40.69356 -401.312609) (xy 40.700067 -401.295412) (xy 40.700452 -401.286218) (xy 40.700452 -400.793966)
			(xy 40.700046 -400.784779) (xy 40.693528 -400.767595) (xy 40.687752 -400.760438) (xy 40.665892 -400.734769)
			(xy 40.6278 -400.679136) (xy 40.596646 -400.619341) (xy 40.572879 -400.556244) (xy 40.556842 -400.490755)
			(xy 40.548764 -400.423817) (xy 40.548764 -400.356392) (xy 40.55684 -400.289454) (xy 40.572876 -400.223964)
			(xy 40.596642 -400.160867) (xy 40.627795 -400.101072) (xy 40.665887 -400.045438) (xy 40.687752 -400.019774)
			(xy 40.693549 -400.012629) (xy 40.700062 -399.995438) (xy 40.700452 -399.986246) (xy 40.700452 -399.828766)
			(xy 40.700899 -399.818636) (xy 40.70864 -399.799911) (xy 40.722939 -399.785556) (xy 40.741632 -399.77774)
			(xy 40.75176 -399.777204) (xy 41.46804 -399.777204) (xy 41.478197 -399.777589) (xy 41.496951 -399.785399)
			(xy 41.511273 -399.799806) (xy 41.518971 -399.818606) (xy 41.519348 -399.828766) (xy 41.519348 -399.986246)
			(xy 41.519796 -399.995429) (xy 41.526285 -400.012613) (xy 41.532048 -400.019774) (xy 41.55392 -400.045433)
			(xy 41.592012 -400.101068) (xy 41.623165 -400.160864) (xy 41.646931 -400.223962) (xy 41.662968 -400.289452)
			(xy 41.671044 -400.356392) (xy 41.671043 -400.423817) (xy 41.662966 -400.490757) (xy 41.646928 -400.556247)
			(xy 41.623161 -400.619344) (xy 41.592007 -400.67914) (xy 41.553914 -400.734774) (xy 41.532048 -400.760438)
			(xy 41.526246 -400.767579) (xy 41.519736 -400.784773) (xy 41.519348 -400.793966) (xy 41.519348 -401.286218)
			(xy 41.519761 -401.295405) (xy 41.526274 -401.312588) (xy 41.532048 -401.319746) (xy 41.553892 -401.345428)
			(xy 41.591985 -401.401059) (xy 41.62314 -401.460852) (xy 41.646907 -401.523947) (xy 41.662946 -401.589435)
			(xy 41.671024 -401.656372) (xy 41.671026 -401.723795) (xy 41.662952 -401.790733) (xy 41.646917 -401.856221)
			(xy 41.623153 -401.919317) (xy 41.592002 -401.979113) (xy 41.553912 -402.034746) (xy 41.532048 -402.06041)
			(xy 41.526258 -402.06756) (xy 41.519741 -402.084747) (xy 41.519348 -402.093938) (xy 41.519348 -402.251418)
			(xy 41.518888 -402.261547) (xy 41.511152 -402.280271) (xy 41.496858 -402.294627) (xy 41.478167 -402.302444)
			(xy 41.46804 -402.30298) (xy 40.75176 -402.30298) (xy 40.741601 -402.302611) (xy 40.722844 -402.294798)
			(xy 40.708521 -402.280385) (xy 40.700826 -402.26158) (xy 40.700452 -402.251418) (xy 40.700452 -402.093938)
			(xy 40.700012 -402.084754) (xy 40.693518 -402.06757) (xy 40.687752 -402.06041) (xy 40.665865 -402.034763)
			(xy 40.627773 -401.979127) (xy 40.59662 -401.919329) (xy 40.572855 -401.85623) (xy 40.55682 -401.790738)
			(xy 40.548745 -401.723797) (xy 39.420711 -401.723797) (xy 39.392146 -401.778768) (xy 39.354196 -401.834353)
			(xy 39.332408 -401.860004) (xy 39.326628 -401.867161) (xy 39.320103 -401.884342) (xy 39.319708 -401.893532)
			(xy 39.319708 -402.3868) (xy 39.320116 -402.395987) (xy 39.326631 -402.413172) (xy 39.332408 -402.420328)
			(xy 39.35415 -402.446018) (xy 39.392104 -402.501598) (xy 39.423142 -402.561316) (xy 39.44682 -402.624315)
			(xy 39.462798 -402.689694) (xy 39.470847 -402.756513) (xy 39.470851 -402.823815) (xy 39.470843 -402.823878)
			(xy 42.748887 -402.823878) (xy 42.748892 -402.75645) (xy 42.756972 -402.689509) (xy 42.773013 -402.624017)
			(xy 42.796782 -402.560918) (xy 42.827939 -402.501121) (xy 42.866033 -402.445485) (xy 42.8879 -402.41982)
			(xy 42.893713 -402.412686) (xy 42.900218 -402.395487) (xy 42.9006 -402.386292) (xy 42.9006 -401.89404)
			(xy 42.900171 -401.884855) (xy 42.89367 -401.86767) (xy 42.8879 -401.860512) (xy 42.866016 -401.834863)
			(xy 42.827928 -401.779226) (xy 42.796778 -401.719428) (xy 42.773015 -401.656329) (xy 42.756981 -401.590838)
			(xy 42.748907 -401.523898) (xy 42.748909 -401.456472) (xy 42.756987 -401.389533) (xy 42.773024 -401.324043)
			(xy 42.796791 -401.260945) (xy 42.827944 -401.201148) (xy 42.866035 -401.145513) (xy 42.8879 -401.119848)
			(xy 42.893701 -401.112706) (xy 42.900213 -401.095513) (xy 42.9006 -401.08632) (xy 42.9006 -400.92884)
			(xy 42.901049 -400.91872) (xy 42.908784 -400.900017) (xy 42.923091 -400.885702) (xy 42.941788 -400.877955)
			(xy 42.951908 -400.877532) (xy 43.668188 -400.877532) (xy 43.678314 -400.877927) (xy 43.697023 -400.885677)
			(xy 43.711339 -400.9) (xy 43.719079 -400.918714) (xy 43.719496 -400.92884) (xy 43.719496 -401.08632)
			(xy 43.719897 -401.095508) (xy 43.726417 -401.112692) (xy 43.732196 -401.119848) (xy 43.75404 -401.145529)
			(xy 43.79213 -401.201162) (xy 43.823282 -401.260955) (xy 43.847047 -401.32405) (xy 43.863084 -401.389537)
			(xy 43.871162 -401.456474) (xy 43.871164 -401.523896) (xy 43.86309 -401.590833) (xy 43.847056 -401.656321)
			(xy 43.823294 -401.719417) (xy 43.821044 -401.723737) (xy 44.949064 -401.723737) (xy 44.949066 -401.65643)
			(xy 44.957113 -401.589606) (xy 44.973088 -401.524222) (xy 44.996763 -401.461217) (xy 45.027799 -401.401493)
			(xy 45.065751 -401.345906) (xy 45.08754 -401.320254) (xy 45.093344 -401.313114) (xy 45.099853 -401.295919)
			(xy 45.10024 -401.286726) (xy 45.10024 -400.793458) (xy 45.099841 -400.78427) (xy 45.093319 -400.767086)
			(xy 45.08754 -400.75993) (xy 45.065758 -400.734273) (xy 45.027809 -400.678687) (xy 44.996776 -400.618964)
			(xy 44.973103 -400.55596) (xy 44.957129 -400.490579) (xy 44.949085 -400.423757) (xy 44.949084 -400.356452)
			(xy 44.957128 -400.28963) (xy 44.9731 -400.224248) (xy 44.996772 -400.161244) (xy 45.027805 -400.101521)
			(xy 45.065753 -400.045934) (xy 45.08754 -400.020282) (xy 45.093332 -400.013134) (xy 45.099848 -399.995945)
			(xy 45.10024 -399.986754) (xy 45.10024 -399.828766) (xy 45.100706 -399.818606) (xy 45.108492 -399.799835)
			(xy 45.122866 -399.785471) (xy 45.141641 -399.777698) (xy 45.151802 -399.777204) (xy 45.868082 -399.777204)
			(xy 45.878234 -399.777747) (xy 45.896997 -399.785509) (xy 45.911361 -399.79986) (xy 45.919143 -399.818614)
			(xy 45.919644 -399.828766) (xy 45.919644 -399.986754) (xy 45.920089 -399.995937) (xy 45.92658 -400.013121)
			(xy 45.932344 -400.020282) (xy 45.954138 -400.045929) (xy 45.992088 -400.101516) (xy 46.023122 -400.16124)
			(xy 46.046795 -400.224245) (xy 46.062768 -400.289628) (xy 46.070812 -400.356452) (xy 46.070811 -400.423757)
			(xy 46.062766 -400.490581) (xy 46.046792 -400.555963) (xy 46.023118 -400.618968) (xy 45.992083 -400.678692)
			(xy 45.954132 -400.734278) (xy 45.932344 -400.75993) (xy 45.926545 -400.767073) (xy 45.920033 -400.784266)
			(xy 45.919644 -400.793458) (xy 45.919644 -401.286726) (xy 45.920054 -401.295913) (xy 45.926569 -401.313097)
			(xy 45.932344 -401.320254) (xy 45.95411 -401.345924) (xy 45.992061 -401.401507) (xy 46.023096 -401.461228)
			(xy 46.046771 -401.524231) (xy 46.062746 -401.589611) (xy 46.070792 -401.656432) (xy 46.070794 -401.723735)
			(xy 46.062752 -401.790557) (xy 46.046781 -401.855938) (xy 46.02311 -401.918941) (xy 45.992078 -401.978664)
			(xy 45.954131 -402.03425) (xy 45.932344 -402.059902) (xy 45.926557 -402.067054) (xy 45.920038 -402.084239)
			(xy 45.919644 -402.09343) (xy 45.919644 -402.251418) (xy 45.919181 -402.261579) (xy 45.911397 -402.280352)
			(xy 45.897022 -402.294718) (xy 45.878244 -402.302488) (xy 45.868082 -402.30298) (xy 45.151802 -402.30298)
			(xy 45.141647 -402.302465) (xy 45.122881 -402.294695) (xy 45.108516 -402.280336) (xy 45.100739 -402.261573)
			(xy 45.10024 -402.251418) (xy 45.10024 -402.09343) (xy 45.099806 -402.084246) (xy 45.093308 -402.067061)
			(xy 45.08754 -402.059902) (xy 45.06573 -402.034268) (xy 45.027782 -401.978679) (xy 44.99675 -401.918953)
			(xy 44.973078 -401.855946) (xy 44.957107 -401.790561) (xy 44.949064 -401.723737) (xy 43.821044 -401.723737)
			(xy 43.792146 -401.779213) (xy 43.754059 -401.834847) (xy 43.732196 -401.860512) (xy 43.726411 -401.867666)
			(xy 43.71989 -401.88485) (xy 43.719496 -401.89404) (xy 43.719496 -402.386292) (xy 43.719911 -402.395479)
			(xy 43.726421 -402.412663) (xy 43.732196 -402.41982) (xy 43.754013 -402.445524) (xy 43.792103 -402.501153)
			(xy 43.823256 -402.560944) (xy 43.847023 -402.624036) (xy 43.863062 -402.68952) (xy 43.871142 -402.756454)
			(xy 43.871146 -402.823874) (xy 43.863075 -402.890809) (xy 43.847045 -402.956295) (xy 43.823286 -403.01939)
			(xy 43.792141 -403.079185) (xy 43.754057 -403.134819) (xy 43.732196 -403.160484) (xy 43.726381 -403.167616)
			(xy 43.719877 -403.184817) (xy 43.719496 -403.194012) (xy 43.719496 -403.351492) (xy 43.719077 -403.361614)
			(xy 43.711331 -403.380319) (xy 43.697015 -403.394633) (xy 43.67831 -403.402378) (xy 43.668188 -403.4028)
			(xy 42.951908 -403.4028) (xy 42.941786 -403.402377) (xy 42.923083 -403.394632) (xy 42.908768 -403.380317)
			(xy 42.901023 -403.361614) (xy 42.9006 -403.351492) (xy 42.9006 -403.194012) (xy 42.900184 -403.184825)
			(xy 42.893674 -403.167641) (xy 42.8879 -403.160484) (xy 42.865989 -403.134858) (xy 42.827902 -403.079218)
			(xy 42.796753 -403.019416) (xy 42.772992 -402.956314) (xy 42.756959 -402.89082) (xy 42.748887 -402.823878)
			(xy 39.470843 -402.823878) (xy 39.462811 -402.890635) (xy 39.446841 -402.956016) (xy 39.423172 -403.019018)
			(xy 39.392141 -403.07874) (xy 39.354194 -403.134325) (xy 39.332408 -403.159976) (xy 39.326598 -403.167111)
			(xy 39.320091 -403.184309) (xy 39.319708 -403.193504) (xy 39.319708 -403.351492) (xy 39.319272 -403.361645)
			(xy 39.311481 -403.380395) (xy 39.297088 -403.394719) (xy 39.278301 -403.40242) (xy 39.268146 -403.4028)
			(xy 38.551866 -403.4028) (xy 38.541742 -403.402303) (xy 38.523028 -403.394571) (xy 38.508674 -403.380289)
			(xy 38.500849 -403.361613) (xy 38.500304 -403.351492) (xy 38.500304 -403.193504) (xy 38.499891 -403.184317)
			(xy 38.493379 -403.167133) (xy 38.487604 -403.159976) (xy 38.46577 -403.134362) (xy 38.427825 -403.078769)
			(xy 38.396796 -403.01904) (xy 38.373127 -402.956031) (xy 38.357159 -402.890644) (xy 38.349119 -402.823818)
			(xy 35.071059 -402.823818) (xy 35.071059 -402.823874) (xy 35.062988 -402.890809) (xy 35.046958 -402.956295)
			(xy 35.023199 -403.01939) (xy 34.992055 -403.079185) (xy 34.953973 -403.134819) (xy 34.932112 -403.160484)
			(xy 34.926299 -403.167617) (xy 34.919794 -403.184817) (xy 34.919412 -403.194012) (xy 34.919412 -403.351492)
			(xy 34.918978 -403.361612) (xy 34.911234 -403.380314) (xy 34.896924 -403.394628) (xy 34.878224 -403.402375)
			(xy 34.868104 -403.4028) (xy 34.151824 -403.4028) (xy 34.141703 -403.402365) (xy 34.123 -403.394624)
			(xy 34.108685 -403.380314) (xy 34.100939 -403.361613) (xy 34.100516 -403.351492) (xy 34.100516 -403.194012)
			(xy 34.100096 -403.184826) (xy 34.093589 -403.167642) (xy 34.087816 -403.160484) (xy 34.065904 -403.134858)
			(xy 34.027816 -403.079218) (xy 33.996666 -403.019417) (xy 33.972904 -402.956315) (xy 33.956872 -402.890821)
			(xy 33.948799 -402.823878) (xy 30.670778 -402.823878) (xy 30.662742 -402.890627) (xy 30.646769 -402.956009)
			(xy 30.623096 -403.019014) (xy 30.592062 -403.078738) (xy 30.554112 -403.134324) (xy 30.532324 -403.159976)
			(xy 30.526515 -403.167113) (xy 30.520007 -403.18431) (xy 30.519624 -403.193504) (xy 30.519624 -403.351492)
			(xy 30.519172 -403.361643) (xy 30.511384 -403.38039) (xy 30.496997 -403.394713) (xy 30.478214 -403.402417)
			(xy 30.468062 -403.4028) (xy 29.751782 -403.4028) (xy 29.741659 -403.40229) (xy 29.722945 -403.394563)
			(xy 29.708591 -403.380285) (xy 29.700765 -403.361612) (xy 29.70022 -403.351492) (xy 29.70022 -403.193504)
			(xy 29.699804 -403.184318) (xy 29.693294 -403.167133) (xy 29.68752 -403.159976) (xy 29.665734 -403.134322)
			(xy 29.627785 -403.078736) (xy 29.596752 -403.019013) (xy 29.573079 -402.956008) (xy 29.557106 -402.890626)
			(xy 29.549061 -402.823804) (xy 29.549061 -402.756499) (xy 29.557105 -402.689677) (xy 29.573078 -402.624294)
			(xy 29.59675 -402.56129) (xy 29.627784 -402.501566) (xy 29.665732 -402.44598) (xy 29.68752 -402.420328)
			(xy 29.693332 -402.413194) (xy 29.699837 -402.395995) (xy 29.70022 -402.3868) (xy 29.70022 -401.893532)
			(xy 29.69979 -401.884347) (xy 29.69329 -401.867163) (xy 29.68752 -401.860004) (xy 29.665713 -401.834368)
			(xy 29.627766 -401.778779) (xy 29.596735 -401.719053) (xy 29.573064 -401.656046) (xy 29.557093 -401.590662)
			(xy 29.549051 -401.523838) (xy 28.446989 -401.523838) (xy 28.44703 -401.523948) (xy 28.463067 -401.589436)
			(xy 28.471145 -401.656372) (xy 28.471147 -401.723795) (xy 28.463073 -401.790732) (xy 28.447039 -401.85622)
			(xy 28.423277 -401.919316) (xy 28.392127 -401.979111) (xy 28.354039 -402.034745) (xy 28.332176 -402.06041)
			(xy 28.32639 -402.067562) (xy 28.31987 -402.084748) (xy 28.319476 -402.093938) (xy 28.319476 -402.251418)
			(xy 28.318989 -402.261544) (xy 28.311258 -402.280263) (xy 28.296972 -402.294618) (xy 28.278291 -402.302439)
			(xy 28.268168 -402.30298) (xy 27.551888 -402.30298) (xy 27.541731 -402.302588) (xy 27.522974 -402.294785)
			(xy 27.50865 -402.280379) (xy 27.500954 -402.261578) (xy 27.50058 -402.251418) (xy 27.50058 -402.093938)
			(xy 27.500156 -402.084752) (xy 27.493653 -402.067567) (xy 27.48788 -402.06041) (xy 27.465995 -402.034762)
			(xy 27.427908 -401.979125) (xy 27.39676 -401.919326) (xy 27.372998 -401.856227) (xy 27.356964 -401.790736)
			(xy 27.348891 -401.723796) (xy 0.508 -401.723796) (xy 0.508 -405.623707) (xy 27.348902 -405.623707)
			(xy 27.348902 -405.556284) (xy 27.356979 -405.489345) (xy 27.373014 -405.423856) (xy 27.396778 -405.360759)
			(xy 27.427928 -405.300963) (xy 27.466016 -405.245328) (xy 27.48788 -405.219662) (xy 27.493673 -405.212514)
			(xy 27.50019 -405.195326) (xy 27.50058 -405.186134) (xy 27.50058 -404.693882) (xy 27.500183 -404.684693)
			(xy 27.493661 -404.667509) (xy 27.48788 -404.660354) (xy 27.466038 -404.634671) (xy 27.42795 -404.579038)
			(xy 27.3968 -404.519244) (xy 27.373035 -404.45615) (xy 27.356999 -404.390663) (xy 27.348922 -404.323727)
			(xy 27.34892 -404.256306) (xy 27.356993 -404.189369) (xy 27.373025 -404.123882) (xy 27.396786 -404.060786)
			(xy 27.427933 -404.00099) (xy 27.466018 -403.945356) (xy 27.48788 -403.91969) (xy 27.493661 -403.912534)
			(xy 27.500186 -403.895352) (xy 27.50058 -403.886162) (xy 27.50058 -403.728682) (xy 27.501013 -403.718549)
			(xy 27.508754 -403.69982) (xy 27.523057 -403.685463) (xy 27.541757 -403.677651) (xy 27.551888 -403.67712)
			(xy 28.268168 -403.67712) (xy 28.278323 -403.677548) (xy 28.297078 -403.685337) (xy 28.311404 -403.699732)
			(xy 28.319101 -403.718525) (xy 28.319476 -403.728682) (xy 28.319476 -403.886162) (xy 28.31991 -403.895347)
			(xy 28.326408 -403.912531) (xy 28.332176 -403.91969) (xy 28.354062 -403.945337) (xy 28.392152 -404.000974)
			(xy 28.423303 -404.060772) (xy 28.447067 -404.123871) (xy 28.463102 -404.189363) (xy 28.471176 -404.256304)
			(xy 28.471174 -404.323729) (xy 28.463096 -404.39067) (xy 28.447057 -404.45616) (xy 28.42329 -404.519258)
			(xy 28.392135 -404.579055) (xy 28.354042 -404.634689) (xy 28.332176 -404.660354) (xy 28.326371 -404.667493)
			(xy 28.319862 -404.684688) (xy 28.319476 -404.693882) (xy 28.319476 -405.186134) (xy 28.319875 -405.195322)
			(xy 28.326397 -405.212506) (xy 28.332176 -405.219662) (xy 28.354035 -405.245332) (xy 28.392125 -405.300965)
			(xy 28.423278 -405.36076) (xy 28.447043 -405.423857) (xy 28.46308 -405.489345) (xy 28.471157 -405.556284)
			(xy 28.471157 -405.623707) (xy 28.463081 -405.690646) (xy 28.447046 -405.756135) (xy 28.423281 -405.819231)
			(xy 28.39213 -405.879027) (xy 28.35404 -405.934661) (xy 28.332176 -405.960326) (xy 28.326383 -405.967474)
			(xy 28.319867 -405.984662) (xy 28.319476 -405.993854) (xy 28.319476 -406.151334) (xy 28.319002 -406.161461)
			(xy 28.311266 -406.18018) (xy 28.296976 -406.194534) (xy 28.278293 -406.202355) (xy 28.268168 -406.202896)
			(xy 27.551888 -406.202896) (xy 27.541733 -406.202488) (xy 27.522979 -406.194688) (xy 27.508656 -406.180287)
			(xy 27.500957 -406.161492) (xy 27.50058 -406.151334) (xy 27.50058 -405.993854) (xy 27.500148 -405.984669)
			(xy 27.49365 -405.967484) (xy 27.48788 -405.960326) (xy 27.466011 -405.934665) (xy 27.427924 -405.87903)
			(xy 27.396774 -405.819233) (xy 27.373011 -405.756135) (xy 27.356977 -405.690646) (xy 27.348902 -405.623707)
			(xy 0.508 -405.623707) (xy 0.508 -406.72373) (xy 29.549042 -406.72373) (xy 29.549045 -406.656422)
			(xy 29.557092 -406.589598) (xy 29.573068 -406.524214) (xy 29.596744 -406.461208) (xy 29.627779 -406.401484)
			(xy 29.665731 -406.345896) (xy 29.68752 -406.320244) (xy 29.693325 -406.313105) (xy 29.699834 -406.29591)
			(xy 29.70022 -406.286716) (xy 29.70022 -405.793448) (xy 29.699782 -405.784264) (xy 29.693287 -405.767079)
			(xy 29.68752 -405.75992) (xy 29.665729 -405.734271) (xy 29.627781 -405.678684) (xy 29.596749 -405.618959)
			(xy 29.573078 -405.555955) (xy 29.557105 -405.490572) (xy 29.549062 -405.423749) (xy 29.549062 -405.356444)
			(xy 29.557107 -405.289622) (xy 29.573079 -405.22424) (xy 29.596752 -405.161235) (xy 29.627784 -405.101511)
			(xy 29.665733 -405.045924) (xy 29.68752 -405.020272) (xy 29.693313 -405.013125) (xy 29.699829 -404.995936)
			(xy 29.70022 -404.986744) (xy 29.70022 -404.828756) (xy 29.700586 -404.818597) (xy 29.7084 -404.799839)
			(xy 29.722814 -404.785517) (xy 29.74162 -404.777822) (xy 29.751782 -404.777448) (xy 30.468062 -404.777448)
			(xy 30.478187 -404.777958) (xy 30.496909 -404.785675) (xy 30.511267 -404.799954) (xy 30.519086 -404.818634)
			(xy 30.519624 -404.828756) (xy 30.519624 -404.986744) (xy 30.520008 -404.995934) (xy 30.526539 -405.013118)
			(xy 30.532324 -405.020272) (xy 30.554109 -405.045927) (xy 30.59206 -405.101512) (xy 30.623096 -405.161235)
			(xy 30.64677 -405.224239) (xy 30.662745 -405.289621) (xy 30.67079 -405.356444) (xy 30.67079 -405.42375)
			(xy 30.662746 -405.490573) (xy 30.646772 -405.555955) (xy 30.623098 -405.61896) (xy 30.620661 -405.623649)
			(xy 31.749197 -405.623649) (xy 31.749198 -405.556342) (xy 31.757243 -405.489519) (xy 31.773217 -405.424136)
			(xy 31.796892 -405.361131) (xy 31.827928 -405.301408) (xy 31.865879 -405.245822) (xy 31.887668 -405.22017)
			(xy 31.893468 -405.213028) (xy 31.899979 -405.195835) (xy 31.900368 -405.186642) (xy 31.900368 -404.693374)
			(xy 31.899955 -404.684187) (xy 31.893441 -404.667004) (xy 31.887668 -404.659846) (xy 31.865901 -404.634176)
			(xy 31.82795 -404.578593) (xy 31.796914 -404.518872) (xy 31.773239 -404.45587) (xy 31.757263 -404.39049)
			(xy 31.749217 -404.323668) (xy 31.749215 -404.256365) (xy 31.757257 -404.189543) (xy 31.773229 -404.124162)
			(xy 31.7969 -404.061158) (xy 31.827933 -404.001435) (xy 31.865881 -403.94585) (xy 31.887668 -403.920198)
			(xy 31.893456 -403.913047) (xy 31.899974 -403.895861) (xy 31.900368 -403.88667) (xy 31.900368 -403.728682)
			(xy 31.90075 -403.718506) (xy 31.908547 -403.699705) (xy 31.922945 -403.68532) (xy 31.941753 -403.677541)
			(xy 31.95193 -403.67712) (xy 32.66821 -403.67712) (xy 32.678366 -403.677625) (xy 32.697132 -403.685399)
			(xy 32.711496 -403.699761) (xy 32.719273 -403.718526) (xy 32.719772 -403.728682) (xy 32.719772 -403.88667)
			(xy 32.720203 -403.895855) (xy 32.726703 -403.913039) (xy 32.732472 -403.920198) (xy 32.754281 -403.945832)
			(xy 32.792229 -404.001422) (xy 32.82326 -404.061148) (xy 32.846931 -404.124155) (xy 32.862902 -404.189539)
			(xy 32.870945 -404.256363) (xy 32.870943 -404.32367) (xy 32.862897 -404.390494) (xy 32.846922 -404.455877)
			(xy 32.823247 -404.518882) (xy 32.792212 -404.578607) (xy 32.754261 -404.634194) (xy 32.732472 -404.659846)
			(xy 32.72667 -404.666987) (xy 32.720159 -404.684181) (xy 32.719772 -404.693374) (xy 32.719772 -405.186642)
			(xy 32.720168 -405.195831) (xy 32.726692 -405.213014) (xy 32.732472 -405.22017) (xy 32.754254 -405.245827)
			(xy 32.792202 -405.301413) (xy 32.823235 -405.361136) (xy 32.846907 -405.42414) (xy 32.862881 -405.489521)
			(xy 32.870925 -405.556343) (xy 32.870926 -405.623648) (xy 32.862882 -405.69047) (xy 32.84691 -405.755851)
			(xy 32.823239 -405.818856) (xy 32.792207 -405.878579) (xy 32.754259 -405.934166) (xy 32.732472 -405.959818)
			(xy 32.726682 -405.966967) (xy 32.720164 -405.984155) (xy 32.719772 -405.993346) (xy 32.719772 -406.151334)
			(xy 32.719295 -406.161493) (xy 32.711511 -406.180261) (xy 32.697141 -406.194624) (xy 32.678369 -406.202399)
			(xy 32.66821 -406.202896) (xy 31.95193 -406.202896) (xy 31.941778 -406.202343) (xy 31.923016 -406.194585)
			(xy 31.908651 -406.180237) (xy 31.900869 -406.161485) (xy 31.900368 -406.151334) (xy 31.900368 -405.993346)
			(xy 31.899921 -405.984163) (xy 31.893431 -405.966979) (xy 31.887668 -405.959818) (xy 31.865874 -405.934171)
			(xy 31.827923 -405.878584) (xy 31.796888 -405.81886) (xy 31.773215 -405.755855) (xy 31.757241 -405.690472)
			(xy 31.749197 -405.623649) (xy 30.620661 -405.623649) (xy 30.592063 -405.678683) (xy 30.554113 -405.734268)
			(xy 30.532324 -405.75992) (xy 30.526539 -405.767074) (xy 30.520017 -405.784258) (xy 30.519624 -405.793448)
			(xy 30.519624 -406.286716) (xy 30.520021 -406.295905) (xy 30.526543 -406.313089) (xy 30.532324 -406.320244)
			(xy 30.554081 -406.345922) (xy 30.592034 -406.401503) (xy 30.62307 -406.461223) (xy 30.646746 -406.524224)
			(xy 30.662723 -406.589604) (xy 30.67077 -406.656424) (xy 30.670773 -406.723728) (xy 30.670766 -406.723789)
			(xy 33.948811 -406.723789) (xy 33.948814 -406.656363) (xy 33.956893 -406.589422) (xy 33.972932 -406.523931)
			(xy 33.996701 -406.460833) (xy 34.027856 -406.401036) (xy 34.06595 -406.345401) (xy 34.087816 -406.319736)
			(xy 34.093624 -406.312599) (xy 34.100131 -406.295402) (xy 34.100516 -406.286208) (xy 34.100516 -405.793956)
			(xy 34.100123 -405.784767) (xy 34.093597 -405.767583) (xy 34.087816 -405.760428) (xy 34.065948 -405.734766)
			(xy 34.027858 -405.679132) (xy 33.996706 -405.619335) (xy 33.972942 -405.556238) (xy 33.956906 -405.490748)
			(xy 33.94883 -405.423809) (xy 33.948831 -405.356385) (xy 33.956907 -405.289446) (xy 33.972944 -405.223957)
			(xy 33.996709 -405.160859) (xy 34.027861 -405.101063) (xy 34.065951 -405.045429) (xy 34.087816 -405.019764)
			(xy 34.093612 -405.012619) (xy 34.100127 -404.995428) (xy 34.100516 -404.986236) (xy 34.100516 -404.828756)
			(xy 34.10095 -404.818642) (xy 34.108705 -404.79996) (xy 34.123017 -404.785666) (xy 34.14171 -404.777936)
			(xy 34.151824 -404.777448) (xy 34.868104 -404.777448) (xy 34.878207 -404.777981) (xy 34.896875 -404.78571)
			(xy 34.911168 -404.799992) (xy 34.918911 -404.818654) (xy 34.919412 -404.828756) (xy 34.919412 -404.986236)
			(xy 34.919802 -404.995425) (xy 34.926329 -405.01261) (xy 34.932112 -405.019764) (xy 34.953972 -405.045433)
			(xy 34.99206 -405.101067) (xy 35.02321 -405.160863) (xy 35.046974 -405.223959) (xy 35.063009 -405.289448)
			(xy 35.071085 -405.356385) (xy 35.071085 -405.423809) (xy 35.06301 -405.490746) (xy 35.046976 -405.556235)
			(xy 35.023212 -405.619332) (xy 35.020933 -405.623707) (xy 36.14899 -405.623707) (xy 36.14899 -405.556284)
			(xy 36.157066 -405.489346) (xy 36.173101 -405.423857) (xy 36.196864 -405.36076) (xy 36.228014 -405.300963)
			(xy 36.266101 -405.245328) (xy 36.287964 -405.219662) (xy 36.293767 -405.212522) (xy 36.300276 -405.195327)
			(xy 36.300664 -405.186134) (xy 36.300664 -404.693882) (xy 36.300248 -404.684696) (xy 36.293737 -404.667512)
			(xy 36.287964 -404.660354) (xy 36.266123 -404.63467) (xy 36.228036 -404.579038) (xy 36.196886 -404.519244)
			(xy 36.173122 -404.456149) (xy 36.157087 -404.390663) (xy 36.149009 -404.323727) (xy 36.149007 -404.256306)
			(xy 36.157081 -404.18937) (xy 36.173113 -404.123882) (xy 36.196873 -404.060787) (xy 36.228019 -404.000991)
			(xy 36.266103 -403.945356) (xy 36.287964 -403.91969) (xy 36.293755 -403.912541) (xy 36.300271 -403.895353)
			(xy 36.300664 -403.886162) (xy 36.300664 -403.728682) (xy 36.301112 -403.718551) (xy 36.30885 -403.699825)
			(xy 36.323149 -403.685468) (xy 36.341843 -403.677654) (xy 36.351972 -403.67712) (xy 37.068252 -403.67712)
			(xy 37.078405 -403.677561) (xy 37.097161 -403.685345) (xy 37.111486 -403.699736) (xy 37.119184 -403.718527)
			(xy 37.11956 -403.728682) (xy 37.11956 -403.886162) (xy 37.119998 -403.895346) (xy 37.126493 -403.91253)
			(xy 37.13226 -403.91969) (xy 37.154147 -403.945337) (xy 37.192238 -404.000973) (xy 37.22339 -404.060771)
			(xy 37.247154 -404.123871) (xy 37.26319 -404.189362) (xy 37.271264 -404.256303) (xy 37.271262 -404.32373)
			(xy 37.263184 -404.39067) (xy 37.247145 -404.456161) (xy 37.223376 -404.519259) (xy 37.192221 -404.579055)
			(xy 37.154127 -404.634689) (xy 37.13226 -404.660354) (xy 37.126453 -404.667492) (xy 37.119946 -404.684688)
			(xy 37.11956 -404.693882) (xy 37.11956 -405.186134) (xy 37.119963 -405.195322) (xy 37.126483 -405.212506)
			(xy 37.13226 -405.219662) (xy 37.154119 -405.245331) (xy 37.192211 -405.300964) (xy 37.223364 -405.36076)
			(xy 37.24713 -405.423856) (xy 37.263168 -405.489345) (xy 37.271245 -405.556284) (xy 37.271245 -405.623707)
			(xy 37.263169 -405.690646) (xy 37.247133 -405.756135) (xy 37.223368 -405.819232) (xy 37.192216 -405.879028)
			(xy 37.154125 -405.934661) (xy 37.13226 -405.960326) (xy 37.126465 -405.967472) (xy 37.11995 -405.984662)
			(xy 37.11956 -405.993854) (xy 37.11956 -406.151334) (xy 37.119101 -406.161463) (xy 37.111362 -406.180185)
			(xy 37.097068 -406.19454) (xy 37.078379 -406.202358) (xy 37.068252 -406.202896) (xy 36.351972 -406.202896)
			(xy 36.341816 -406.202501) (xy 36.323062 -406.194696) (xy 36.308739 -406.180291) (xy 36.301041 -406.161493)
			(xy 36.300664 -406.151334) (xy 36.300664 -405.993854) (xy 36.300214 -405.984671) (xy 36.293726 -405.967487)
			(xy 36.287964 -405.960326) (xy 36.266095 -405.934665) (xy 36.228009 -405.879029) (xy 36.196861 -405.819232)
			(xy 36.173099 -405.756135) (xy 36.157065 -405.690645) (xy 36.14899 -405.623707) (xy 35.020933 -405.623707)
			(xy 34.992063 -405.679128) (xy 34.953975 -405.734763) (xy 34.932112 -405.760428) (xy 34.926322 -405.767578)
			(xy 34.919803 -405.784765) (xy 34.919412 -405.793956) (xy 34.919412 -406.286208) (xy 34.919816 -406.295396)
			(xy 34.926334 -406.31258) (xy 34.932112 -406.319736) (xy 34.953944 -406.345427) (xy 34.992033 -406.401058)
			(xy 35.023184 -406.460851) (xy 35.04695 -406.523945) (xy 35.062987 -406.58943) (xy 35.071065 -406.656366)
			(xy 35.071068 -406.723729) (xy 38.34913 -406.723729) (xy 38.349133 -406.656422) (xy 38.35718 -406.589598)
			(xy 38.373155 -406.524215) (xy 38.39683 -406.461209) (xy 38.427865 -406.401484) (xy 38.465815 -406.345897)
			(xy 38.487604 -406.320244) (xy 38.493407 -406.313104) (xy 38.499918 -406.295909) (xy 38.500304 -406.286716)
			(xy 38.500304 -405.793448) (xy 38.49987 -405.784263) (xy 38.493373 -405.767079) (xy 38.487604 -405.75992)
			(xy 38.465813 -405.734271) (xy 38.427867 -405.678683) (xy 38.396836 -405.618959) (xy 38.373165 -405.555954)
			(xy 38.357193 -405.490572) (xy 38.34915 -405.423749) (xy 38.34915 -405.356445) (xy 38.357194 -405.289622)
			(xy 38.373167 -405.22424) (xy 38.396838 -405.161236) (xy 38.42787 -405.101512) (xy 38.465817 -405.045925)
			(xy 38.487604 -405.020272) (xy 38.493395 -405.013123) (xy 38.499913 -404.995935) (xy 38.500304 -404.986744)
			(xy 38.500304 -404.828756) (xy 38.500686 -404.818599) (xy 38.508497 -404.799844) (xy 38.522905 -404.785523)
			(xy 38.541706 -404.777825) (xy 38.551866 -404.777448) (xy 39.268146 -404.777448) (xy 39.278277 -404.777889)
			(xy 39.297 -404.785634) (xy 39.311355 -404.799934) (xy 39.319171 -404.818627) (xy 39.319708 -404.828756)
			(xy 39.319708 -404.986744) (xy 39.320095 -404.995934) (xy 39.326624 -405.013118) (xy 39.332408 -405.020272)
			(xy 39.354193 -405.045927) (xy 39.392146 -405.101512) (xy 39.423182 -405.161234) (xy 39.446858 -405.224239)
			(xy 39.462832 -405.289621) (xy 39.470878 -405.356444) (xy 39.470878 -405.42375) (xy 39.462833 -405.490573)
			(xy 39.446859 -405.555956) (xy 39.423185 -405.61896) (xy 39.420718 -405.623708) (xy 40.548756 -405.623708)
			(xy 40.548757 -405.556283) (xy 40.556834 -405.489343) (xy 40.572872 -405.423853) (xy 40.596639 -405.360756)
			(xy 40.627793 -405.30096) (xy 40.665886 -405.245326) (xy 40.687752 -405.219662) (xy 40.693554 -405.212521)
			(xy 40.700064 -405.195327) (xy 40.700452 -405.186134) (xy 40.700452 -404.693882) (xy 40.700039 -404.684695)
			(xy 40.693526 -404.667512) (xy 40.687752 -404.660354) (xy 40.665908 -404.634672) (xy 40.627815 -404.579041)
			(xy 40.59666 -404.519248) (xy 40.572893 -404.456153) (xy 40.556854 -404.390665) (xy 40.548776 -404.323728)
			(xy 40.548774 -404.256305) (xy 40.556848 -404.189367) (xy 40.572883 -404.123879) (xy 40.596647 -404.060783)
			(xy 40.627798 -404.000987) (xy 40.665888 -403.945354) (xy 40.687752 -403.91969) (xy 40.693542 -403.91254)
			(xy 40.700059 -403.895353) (xy 40.700452 -403.886162) (xy 40.700452 -403.728682) (xy 40.700912 -403.718553)
			(xy 40.708648 -403.699829) (xy 40.722942 -403.685473) (xy 40.741633 -403.677656) (xy 40.75176 -403.67712)
			(xy 41.46804 -403.67712) (xy 41.478199 -403.677489) (xy 41.496956 -403.685302) (xy 41.511279 -403.699715)
			(xy 41.518974 -403.71852) (xy 41.519348 -403.728682) (xy 41.519348 -403.886162) (xy 41.519788 -403.895346)
			(xy 41.526282 -403.91253) (xy 41.532048 -403.91969) (xy 41.553935 -403.945337) (xy 41.592027 -404.000973)
			(xy 41.62318 -404.060771) (xy 41.646945 -404.12387) (xy 41.66298 -404.189362) (xy 41.671055 -404.256303)
			(xy 41.671053 -404.32373) (xy 41.662974 -404.39067) (xy 41.646935 -404.456161) (xy 41.623166 -404.519259)
			(xy 41.59201 -404.579056) (xy 41.553915 -404.63469) (xy 41.532048 -404.660354) (xy 41.52624 -404.667491)
			(xy 41.519733 -404.684688) (xy 41.519348 -404.693882) (xy 41.519348 -405.186134) (xy 41.519754 -405.195321)
			(xy 41.526272 -405.212505) (xy 41.532048 -405.219662) (xy 41.553908 -405.245331) (xy 41.592 -405.300964)
			(xy 41.623154 -405.360759) (xy 41.646921 -405.423856) (xy 41.662958 -405.489345) (xy 41.671036 -405.556283)
			(xy 41.671036 -405.623708) (xy 41.66296 -405.690646) (xy 41.646924 -405.756136) (xy 41.623158 -405.819233)
			(xy 41.592005 -405.879028) (xy 41.553913 -405.934662) (xy 41.532048 -405.960326) (xy 41.526251 -405.967471)
			(xy 41.519738 -405.984662) (xy 41.519348 -405.993854) (xy 41.519348 -406.151334) (xy 41.518901 -406.161464)
			(xy 41.51116 -406.180189) (xy 41.496861 -406.194544) (xy 41.478168 -406.20236) (xy 41.46804 -406.202896)
			(xy 40.75176 -406.202896) (xy 40.741603 -406.202511) (xy 40.722849 -406.194701) (xy 40.708527 -406.180294)
			(xy 40.700829 -406.161494) (xy 40.700452 -406.151334) (xy 40.700452 -405.993854) (xy 40.700004 -405.984671)
			(xy 40.693515 -405.967487) (xy 40.687752 -405.960326) (xy 40.66588 -405.934667) (xy 40.627788 -405.879032)
			(xy 40.596635 -405.819236) (xy 40.572869 -405.756138) (xy 40.556832 -405.690648) (xy 40.548756 -405.623708)
			(xy 39.420718 -405.623708) (xy 39.392149 -405.678683) (xy 39.354197 -405.734269) (xy 39.332408 -405.75992)
			(xy 39.326621 -405.767072) (xy 39.3201 -405.784257) (xy 39.319708 -405.793448) (xy 39.319708 -406.286716)
			(xy 39.320109 -406.295904) (xy 39.326629 -406.313088) (xy 39.332408 -406.320244) (xy 39.354166 -406.345921)
			(xy 39.392119 -406.401503) (xy 39.423157 -406.461222) (xy 39.446834 -406.524224) (xy 39.46281 -406.589604)
			(xy 39.470858 -406.656424) (xy 39.470861 -406.723728) (xy 39.470854 -406.723789) (xy 42.748899 -406.723789)
			(xy 42.748901 -406.656363) (xy 42.756981 -406.589422) (xy 42.773019 -406.523932) (xy 42.796787 -406.460833)
			(xy 42.827942 -406.401036) (xy 42.866034 -406.345401) (xy 42.8879 -406.319736) (xy 42.893706 -406.312598)
			(xy 42.900215 -406.295402) (xy 42.9006 -406.286208) (xy 42.9006 -405.793956) (xy 42.900211 -405.784767)
			(xy 42.893683 -405.767582) (xy 42.8879 -405.760428) (xy 42.866032 -405.734766) (xy 42.827944 -405.679131)
			(xy 42.796793 -405.619334) (xy 42.773029 -405.556237) (xy 42.756994 -405.490748) (xy 42.748918 -405.423809)
			(xy 42.748919 -405.356385) (xy 42.756995 -405.289446) (xy 42.773031 -405.223957) (xy 42.796795 -405.16086)
			(xy 42.827947 -405.101064) (xy 42.866036 -405.045429) (xy 42.8879 -405.019764) (xy 42.893694 -405.012617)
			(xy 42.90021 -404.995428) (xy 42.9006 -404.986236) (xy 42.9006 -404.828756) (xy 42.901049 -404.818644)
			(xy 42.908801 -404.799965) (xy 42.923109 -404.785672) (xy 42.941796 -404.777939) (xy 42.951908 -404.777448)
			(xy 43.668188 -404.777448) (xy 43.67829 -404.777994) (xy 43.696958 -404.785718) (xy 43.711251 -404.799995)
			(xy 43.718995 -404.818655) (xy 43.719496 -404.828756) (xy 43.719496 -404.986236) (xy 43.71989 -404.995425)
			(xy 43.726415 -405.012609) (xy 43.732196 -405.019764) (xy 43.754056 -405.045432) (xy 43.792145 -405.101066)
			(xy 43.823296 -405.160862) (xy 43.847061 -405.223959) (xy 43.863097 -405.289447) (xy 43.871173 -405.356385)
			(xy 43.871173 -405.423809) (xy 43.863098 -405.490747) (xy 43.847063 -405.556236) (xy 43.823299 -405.619332)
			(xy 43.792148 -405.679128) (xy 43.75406 -405.734763) (xy 43.732196 -405.760428) (xy 43.726405 -405.767577)
			(xy 43.719887 -405.784765) (xy 43.719496 -405.793956) (xy 43.719496 -406.286208) (xy 43.719903 -406.295395)
			(xy 43.726419 -406.31258) (xy 43.732196 -406.319736) (xy 43.754029 -406.345427) (xy 43.792119 -406.401058)
			(xy 43.823271 -406.46085) (xy 43.847037 -406.523944) (xy 43.863075 -406.58943) (xy 43.871153 -406.656365)
			(xy 43.871156 -406.72373) (xy 47.149194 -406.72373) (xy 47.149197 -406.656422) (xy 47.157245 -406.589596)
			(xy 47.173223 -406.524212) (xy 47.196901 -406.461206) (xy 47.227941 -406.401481) (xy 47.265897 -406.345896)
			(xy 47.287688 -406.320244) (xy 47.293489 -406.313102) (xy 47.300002 -406.295909) (xy 47.300388 -406.286716)
			(xy 47.300388 -405.793448) (xy 47.299958 -405.784263) (xy 47.293458 -405.767078) (xy 47.287688 -405.75992)
			(xy 47.265895 -405.734272) (xy 47.227943 -405.678686) (xy 47.196907 -405.618962) (xy 47.173232 -405.555957)
			(xy 47.157258 -405.490574) (xy 47.149214 -405.42375) (xy 47.149214 -405.356444) (xy 47.157259 -405.28962)
			(xy 47.173234 -405.224237) (xy 47.19691 -405.161232) (xy 47.227946 -405.101509) (xy 47.265899 -405.045924)
			(xy 47.287688 -405.020272) (xy 47.293478 -405.013122) (xy 47.299997 -404.995935) (xy 47.300388 -404.986744)
			(xy 47.300388 -404.828756) (xy 47.300785 -404.818601) (xy 47.308593 -404.79985) (xy 47.322997 -404.785528)
			(xy 47.341792 -404.777828) (xy 47.35195 -404.777448) (xy 48.06823 -404.777448) (xy 48.07836 -404.777902)
			(xy 48.097083 -404.785641) (xy 48.111439 -404.799937) (xy 48.119255 -404.818629) (xy 48.119792 -404.828756)
			(xy 48.119792 -404.986744) (xy 48.120183 -404.995933) (xy 48.12671 -405.013117) (xy 48.132492 -405.020272)
			(xy 48.154275 -405.045928) (xy 48.192222 -405.101514) (xy 48.223254 -405.161238) (xy 48.246925 -405.224242)
			(xy 48.262897 -405.289623) (xy 48.270941 -405.356445) (xy 48.270942 -405.423749) (xy 48.262899 -405.490571)
			(xy 48.246927 -405.555952) (xy 48.223256 -405.618957) (xy 48.192225 -405.67868) (xy 48.154279 -405.734267)
			(xy 48.132492 -405.75992) (xy 48.126704 -405.767071) (xy 48.120184 -405.784257) (xy 48.119792 -405.793448)
			(xy 48.119792 -406.286716) (xy 48.120196 -406.295904) (xy 48.126714 -406.313088) (xy 48.132492 -406.320244)
			(xy 48.154247 -406.345922) (xy 48.192195 -406.401506) (xy 48.223228 -406.461226) (xy 48.246901 -406.524227)
			(xy 48.262876 -406.589606) (xy 48.270922 -406.656425) (xy 48.270925 -406.723727) (xy 48.262884 -406.790547)
			(xy 48.246916 -406.855927) (xy 48.223248 -406.91893) (xy 48.19222 -406.978653) (xy 48.154277 -407.034239)
			(xy 48.132492 -407.059892) (xy 48.126715 -407.067051) (xy 48.120189 -407.084231) (xy 48.119792 -407.09342)
			(xy 48.119792 -407.251408) (xy 48.119385 -407.261564) (xy 48.111585 -407.280318) (xy 48.097184 -407.294641)
			(xy 48.078388 -407.302339) (xy 48.06823 -407.302716) (xy 47.35195 -407.302716) (xy 47.341821 -407.302231)
			(xy 47.323093 -407.294512) (xy 47.308733 -407.280224) (xy 47.30092 -407.261534) (xy 47.300388 -407.251408)
			(xy 47.300388 -407.09342) (xy 47.299971 -407.084233) (xy 47.293462 -407.067049) (xy 47.287688 -407.059892)
			(xy 47.265867 -407.034266) (xy 47.227916 -406.978677) (xy 47.196882 -406.91895) (xy 47.173209 -406.855942)
			(xy 47.157236 -406.790556) (xy 47.149194 -406.72373) (xy 43.871156 -406.72373) (xy 43.871156 -406.723787)
			(xy 43.863084 -406.790723) (xy 43.847051 -406.85621) (xy 43.823291 -406.919306) (xy 43.792143 -406.979101)
			(xy 43.754058 -407.034735) (xy 43.732196 -407.0604) (xy 43.726416 -407.067557) (xy 43.719892 -407.084739)
			(xy 43.719496 -407.093928) (xy 43.719496 -407.251408) (xy 43.71909 -407.261531) (xy 43.711339 -407.280236)
			(xy 43.697019 -407.29455) (xy 43.678312 -407.302294) (xy 43.668188 -407.302716) (xy 42.951908 -407.302716)
			(xy 42.941802 -407.302209) (xy 42.923127 -407.294477) (xy 42.908832 -407.280187) (xy 42.901094 -407.261514)
			(xy 42.9006 -407.251408) (xy 42.9006 -407.093928) (xy 42.900176 -407.084742) (xy 42.893672 -407.067558)
			(xy 42.8879 -407.0604) (xy 42.866005 -407.034761) (xy 42.827917 -406.979122) (xy 42.796768 -406.919323)
			(xy 42.773005 -406.856222) (xy 42.756972 -406.79073) (xy 42.748899 -406.723789) (xy 39.470854 -406.723789)
			(xy 39.462819 -406.790549) (xy 39.446848 -406.85593) (xy 39.423176 -406.918933) (xy 39.392144 -406.978656)
			(xy 39.354195 -407.034241) (xy 39.332408 -407.059892) (xy 39.326633 -407.067053) (xy 39.320105 -407.084231)
			(xy 39.319708 -407.09342) (xy 39.319708 -407.251408) (xy 39.319285 -407.261562) (xy 39.311488 -407.280313)
			(xy 39.297092 -407.294635) (xy 39.278302 -407.302336) (xy 39.268146 -407.302716) (xy 38.551866 -407.302716)
			(xy 38.541732 -407.3023) (xy 38.523001 -407.294553) (xy 38.508645 -407.280245) (xy 38.500835 -407.261541)
			(xy 38.500304 -407.251408) (xy 38.500304 -407.09342) (xy 38.499883 -407.084234) (xy 38.493377 -407.06705)
			(xy 38.487604 -407.059892) (xy 38.465786 -407.034265) (xy 38.42784 -406.978674) (xy 38.39681 -406.918947)
			(xy 38.373141 -406.855939) (xy 38.357171 -406.790554) (xy 38.34913 -406.723729) (xy 35.071068 -406.723729)
			(xy 35.071068 -406.723786) (xy 35.062996 -406.790722) (xy 35.046964 -406.856209) (xy 35.023204 -406.919305)
			(xy 34.992058 -406.9791) (xy 34.953974 -407.034735) (xy 34.932112 -407.0604) (xy 34.926334 -407.067559)
			(xy 34.919808 -407.084739) (xy 34.919412 -407.093928) (xy 34.919412 -407.251408) (xy 34.918922 -407.261516)
			(xy 34.911184 -407.280192) (xy 34.896888 -407.294486) (xy 34.878212 -407.302222) (xy 34.868104 -407.302716)
			(xy 34.151824 -407.302716) (xy 34.141705 -407.302265) (xy 34.123005 -407.294528) (xy 34.10869 -407.280222)
			(xy 34.100941 -407.261527) (xy 34.100516 -407.251408) (xy 34.100516 -407.093928) (xy 34.100089 -407.084743)
			(xy 34.093586 -407.067558) (xy 34.087816 -407.0604) (xy 34.06592 -407.034761) (xy 34.027831 -406.979123)
			(xy 33.996681 -406.919323) (xy 33.972918 -406.856223) (xy 33.956884 -406.790731) (xy 33.948811 -406.723789)
			(xy 30.670766 -406.723789) (xy 30.662731 -406.790549) (xy 30.646761 -406.855929) (xy 30.62309 -406.918933)
			(xy 30.592058 -406.978655) (xy 30.554111 -407.03424) (xy 30.532324 -407.059892) (xy 30.526551 -407.067054)
			(xy 30.520022 -407.084232) (xy 30.519624 -407.09342) (xy 30.519624 -407.251408) (xy 30.519185 -407.26156)
			(xy 30.511392 -407.280307) (xy 30.497001 -407.29463) (xy 30.478216 -407.302333) (xy 30.468062 -407.302716)
			(xy 29.751782 -407.302716) (xy 29.741649 -407.302287) (xy 29.722919 -407.294545) (xy 29.708561 -407.280241)
			(xy 29.700751 -407.261539) (xy 29.70022 -407.251408) (xy 29.70022 -407.09342) (xy 29.699796 -407.084234)
			(xy 29.693291 -407.06705) (xy 29.68752 -407.059892) (xy 29.665701 -407.034265) (xy 29.627755 -406.978675)
			(xy 29.596724 -406.918948) (xy 29.573054 -406.85594) (xy 29.557084 -406.790555) (xy 29.549042 -406.72373)
			(xy 0.508 -406.72373) (xy 0.508 -409.523886) (xy 27.348881 -409.523886) (xy 27.348884 -409.45646)
			(xy 27.356963 -409.38952) (xy 27.373002 -409.324029) (xy 27.396769 -409.26093) (xy 27.427923 -409.201133)
			(xy 27.466015 -409.145498) (xy 27.48788 -409.119832) (xy 27.493686 -409.112693) (xy 27.500196 -409.095498)
			(xy 27.50058 -409.086304) (xy 27.50058 -408.594052) (xy 27.500149 -408.584867) (xy 27.49365 -408.567682)
			(xy 27.48788 -408.560524) (xy 27.466009 -408.534865) (xy 27.427922 -408.479229) (xy 27.396772 -408.419432)
			(xy 27.37301 -408.356334) (xy 27.356975 -408.290845) (xy 27.3489 -408.223906) (xy 27.348901 -408.156482)
			(xy 27.356977 -408.089544) (xy 27.373013 -408.024054) (xy 27.396777 -407.960957) (xy 27.427928 -407.901161)
			(xy 27.466016 -407.845526) (xy 27.48788 -407.81986) (xy 27.493674 -407.812713) (xy 27.500191 -407.795524)
			(xy 27.50058 -407.786332) (xy 27.50058 -407.628852) (xy 27.501045 -407.618743) (xy 27.508795 -407.600067)
			(xy 27.523098 -407.585775) (xy 27.541778 -407.578038) (xy 27.551888 -407.577544) (xy 28.268168 -407.577544)
			(xy 28.278268 -407.57811) (xy 28.296935 -407.585826) (xy 28.311229 -407.600098) (xy 28.318975 -407.618753)
			(xy 28.319476 -407.628852) (xy 28.319476 -407.786332) (xy 28.319876 -407.79552) (xy 28.326397 -407.812704)
			(xy 28.332176 -407.81986) (xy 28.354033 -407.845531) (xy 28.392123 -407.901164) (xy 28.423276 -407.96096)
			(xy 28.447042 -408.024056) (xy 28.463078 -408.089544) (xy 28.471155 -408.156482) (xy 28.471156 -408.223906)
			(xy 28.46308 -408.290844) (xy 28.447045 -408.356333) (xy 28.423281 -408.419429) (xy 28.39213 -408.479225)
			(xy 28.35404 -408.534859) (xy 28.332176 -408.560524) (xy 28.326384 -408.567672) (xy 28.319867 -408.584861)
			(xy 28.319476 -408.594052) (xy 28.319476 -409.086304) (xy 28.319889 -409.095491) (xy 28.326401 -409.112675)
			(xy 28.332176 -409.119832) (xy 28.354005 -409.145526) (xy 28.392097 -409.201156) (xy 28.42325 -409.260948)
			(xy 28.447018 -409.324041) (xy 28.463056 -409.389527) (xy 28.471135 -409.456462) (xy 28.471139 -409.523884)
			(xy 28.463066 -409.59082) (xy 28.447034 -409.656307) (xy 28.423273 -409.719403) (xy 28.392125 -409.779198)
			(xy 28.354039 -409.834831) (xy 28.332176 -409.860496) (xy 28.326396 -409.867653) (xy 28.319872 -409.884835)
			(xy 28.319476 -409.894024) (xy 28.319476 -410.051504) (xy 28.319087 -410.06163) (xy 28.311333 -410.080338)
			(xy 28.297008 -410.094653) (xy 28.278294 -410.102394) (xy 28.268168 -410.102812) (xy 27.551888 -410.102812)
			(xy 27.54178 -410.102325) (xy 27.523104 -410.094585) (xy 27.50881 -410.080289) (xy 27.501074 -410.061612)
			(xy 27.50058 -410.051504) (xy 27.50058 -409.894024) (xy 27.500163 -409.884837) (xy 27.493655 -409.867653)
			(xy 27.48788 -409.860496) (xy 27.465981 -409.83486) (xy 27.427895 -409.77922) (xy 27.396747 -409.71942)
			(xy 27.372986 -409.656319) (xy 27.356953 -409.590827) (xy 27.348881 -409.523886) (xy 0.508 -409.523886)
			(xy 0.508 -410.623641) (xy 29.549054 -410.623641) (xy 29.549055 -410.556335) (xy 29.5571 -410.489512)
			(xy 29.573074 -410.424129) (xy 29.596748 -410.361124) (xy 29.627782 -410.301399) (xy 29.665732 -410.245812)
			(xy 29.68752 -410.22016) (xy 29.693318 -410.213016) (xy 29.699831 -410.195825) (xy 29.70022 -410.186632)
			(xy 29.70022 -409.693364) (xy 29.699823 -409.684176) (xy 29.6933 -409.666992) (xy 29.68752 -409.659836)
			(xy 29.665745 -409.634174) (xy 29.627797 -409.578588) (xy 29.596764 -409.518866) (xy 29.573091 -409.455863)
			(xy 29.557118 -409.390482) (xy 29.549073 -409.323661) (xy 29.549072 -409.256357) (xy 29.557115 -409.189536)
			(xy 29.573086 -409.124154) (xy 29.596757 -409.06115) (xy 29.627787 -409.001427) (xy 29.665734 -408.94584)
			(xy 29.68752 -408.920188) (xy 29.693306 -408.913036) (xy 29.699827 -408.895851) (xy 29.70022 -408.88666)
			(xy 29.70022 -408.728672) (xy 29.700599 -408.718514) (xy 29.708408 -408.699757) (xy 29.722817 -408.685434)
			(xy 29.741621 -408.677738) (xy 29.751782 -408.677364) (xy 30.468062 -408.677364) (xy 30.478189 -408.677859)
			(xy 30.496914 -408.685578) (xy 30.511272 -408.699863) (xy 30.519089 -408.718547) (xy 30.519624 -408.728672)
			(xy 30.519624 -408.88666) (xy 30.520048 -408.895846) (xy 30.526551 -408.913031) (xy 30.532324 -408.920188)
			(xy 30.554125 -408.94583) (xy 30.592075 -409.001417) (xy 30.62311 -409.061142) (xy 30.646784 -409.124148)
			(xy 30.662757 -409.189531) (xy 30.670801 -409.256356) (xy 30.6708 -409.323662) (xy 30.662754 -409.390486)
			(xy 30.646779 -409.45587) (xy 30.623103 -409.518875) (xy 30.62053 -409.523827) (xy 31.749176 -409.523827)
			(xy 31.749179 -409.456519) (xy 31.757227 -409.389693) (xy 31.773205 -409.324309) (xy 31.796883 -409.261302)
			(xy 31.827922 -409.201578) (xy 31.865877 -409.145992) (xy 31.887668 -409.12034) (xy 31.893481 -409.113207)
			(xy 31.899984 -409.096007) (xy 31.900368 -409.086812) (xy 31.900368 -408.593544) (xy 31.899922 -408.584361)
			(xy 31.893432 -408.567177) (xy 31.887668 -408.560016) (xy 31.865872 -408.534371) (xy 31.827921 -408.478784)
			(xy 31.796887 -408.41906) (xy 31.773213 -408.356054) (xy 31.75724 -408.290671) (xy 31.749196 -408.223847)
			(xy 31.749197 -408.156541) (xy 31.757242 -408.089717) (xy 31.773217 -408.024334) (xy 31.796892 -407.961329)
			(xy 31.827927 -407.901606) (xy 31.865879 -407.84602) (xy 31.887668 -407.820368) (xy 31.893469 -407.813226)
			(xy 31.899979 -407.796033) (xy 31.900368 -407.78684) (xy 31.900368 -407.628852) (xy 31.900782 -407.618699)
			(xy 31.908587 -407.599952) (xy 31.922985 -407.585631) (xy 31.941775 -407.577927) (xy 31.95193 -407.577544)
			(xy 32.66821 -407.577544) (xy 32.678338 -407.578019) (xy 32.69706 -407.58575) (xy 32.711416 -407.60004)
			(xy 32.719234 -407.618727) (xy 32.719772 -407.628852) (xy 32.719772 -407.78684) (xy 32.720169 -407.796028)
			(xy 32.726693 -407.813212) (xy 32.732472 -407.820368) (xy 32.754252 -407.846027) (xy 32.7922 -407.901612)
			(xy 32.823233 -407.961335) (xy 32.846906 -408.024339) (xy 32.862879 -408.08972) (xy 32.870924 -408.156542)
			(xy 32.870924 -408.223846) (xy 32.862881 -408.290668) (xy 32.846909 -408.35605) (xy 32.823238 -408.419054)
			(xy 32.792206 -408.478777) (xy 32.754259 -408.534364) (xy 32.732472 -408.560016) (xy 32.726682 -408.567166)
			(xy 32.720164 -408.584353) (xy 32.719772 -408.593544) (xy 32.719772 -409.086812) (xy 32.720183 -409.095999)
			(xy 32.726697 -409.113183) (xy 32.732472 -409.12034) (xy 32.754224 -409.146022) (xy 32.792173 -409.201604)
			(xy 32.823207 -409.261324) (xy 32.846881 -409.324324) (xy 32.862857 -409.389703) (xy 32.870903 -409.456522)
			(xy 32.870907 -409.523824) (xy 32.862866 -409.590644) (xy 32.846897 -409.656024) (xy 32.823229 -409.719027)
			(xy 32.792201 -409.778749) (xy 32.754257 -409.834336) (xy 32.732472 -409.859988) (xy 32.726652 -409.867116)
			(xy 32.720152 -409.88432) (xy 32.719772 -409.893516) (xy 32.719772 -410.051504) (xy 32.719381 -410.061662)
			(xy 32.711579 -410.08042) (xy 32.697172 -410.094744) (xy 32.67837 -410.102438) (xy 32.66821 -410.102812)
			(xy 31.95193 -410.102812) (xy 31.941812 -410.102251) (xy 31.923101 -410.094542) (xy 31.908745 -410.080279)
			(xy 31.900916 -410.061619) (xy 31.900368 -410.051504) (xy 31.900368 -409.893516) (xy 31.899935 -409.884332)
			(xy 31.893436 -409.867148) (xy 31.887668 -409.859988) (xy 31.865844 -409.834366) (xy 31.827894 -409.778775)
			(xy 31.796861 -409.719048) (xy 31.773189 -409.65604) (xy 31.757217 -409.590654) (xy 31.749176 -409.523827)
			(xy 30.62053 -409.523827) (xy 30.592066 -409.578598) (xy 30.554113 -409.634184) (xy 30.532324 -409.659836)
			(xy 30.526532 -409.666985) (xy 30.520014 -409.684172) (xy 30.519624 -409.693364) (xy 30.519624 -410.186632)
			(xy 30.520014 -410.195821) (xy 30.526541 -410.213006) (xy 30.532324 -410.22016) (xy 30.554097 -410.245825)
			(xy 30.592049 -410.301408) (xy 30.623085 -410.36113) (xy 30.64676 -410.424133) (xy 30.662735 -410.489514)
			(xy 30.670781 -410.556336) (xy 30.670783 -410.62364) (xy 30.670776 -410.623701) (xy 33.948822 -410.623701)
			(xy 33.948823 -410.556275) (xy 33.956901 -410.489336) (xy 33.972939 -410.423846) (xy 33.996705 -410.360748)
			(xy 34.027859 -410.300951) (xy 34.065951 -410.245317) (xy 34.087816 -410.219652) (xy 34.093617 -410.21251)
			(xy 34.100129 -410.195317) (xy 34.100516 -410.186124) (xy 34.100516 -409.693872) (xy 34.100116 -409.684684)
			(xy 34.093595 -409.6675) (xy 34.087816 -409.660344) (xy 34.065963 -409.634669) (xy 34.027873 -409.579037)
			(xy 33.996721 -409.519242) (xy 33.972955 -409.456146) (xy 33.956919 -409.390658) (xy 33.948842 -409.323721)
			(xy 33.948841 -409.256297) (xy 33.956915 -409.18936) (xy 33.97295 -409.123871) (xy 33.996714 -409.060775)
			(xy 34.027864 -409.000979) (xy 34.065952 -408.945345) (xy 34.087816 -408.91968) (xy 34.093605 -408.91253)
			(xy 34.100124 -408.895343) (xy 34.100516 -408.886152) (xy 34.100516 -408.728672) (xy 34.100962 -408.718559)
			(xy 34.108712 -408.699878) (xy 34.123021 -408.685583) (xy 34.141711 -408.677852) (xy 34.151824 -408.677364)
			(xy 34.868104 -408.677364) (xy 34.878209 -408.677881) (xy 34.89688 -408.685613) (xy 34.911173 -408.6999)
			(xy 34.918914 -408.718568) (xy 34.919412 -408.728672) (xy 34.919412 -408.886152) (xy 34.919842 -408.895337)
			(xy 34.926342 -408.912522) (xy 34.932112 -408.91968) (xy 34.953987 -408.945336) (xy 34.992075 -409.000972)
			(xy 35.023224 -409.06077) (xy 35.046987 -409.123868) (xy 35.063022 -409.189358) (xy 35.071096 -409.256297)
			(xy 35.071095 -409.323721) (xy 35.063018 -409.39066) (xy 35.046982 -409.45615) (xy 35.023217 -409.519247)
			(xy 35.0208 -409.523886) (xy 36.148969 -409.523886) (xy 36.148972 -409.45646) (xy 36.157051 -409.38952)
			(xy 36.173089 -409.324029) (xy 36.196856 -409.260931) (xy 36.228009 -409.201134) (xy 36.266099 -409.145498)
			(xy 36.287964 -409.119832) (xy 36.29378 -409.112701) (xy 36.300281 -409.095499) (xy 36.300664 -409.086304)
			(xy 36.300664 -408.594052) (xy 36.300215 -408.584869) (xy 36.293727 -408.567685) (xy 36.287964 -408.560524)
			(xy 36.266093 -408.534865) (xy 36.228007 -408.479228) (xy 36.196859 -408.419431) (xy 36.173097 -408.356334)
			(xy 36.157063 -408.290844) (xy 36.148988 -408.223906) (xy 36.148989 -408.156482) (xy 36.157065 -408.089544)
			(xy 36.1731 -408.024055) (xy 36.196864 -407.960958) (xy 36.228014 -407.901161) (xy 36.266101 -407.845526)
			(xy 36.287964 -407.81986) (xy 36.293768 -407.81272) (xy 36.300276 -407.795525) (xy 36.300664 -407.786332)
			(xy 36.300664 -407.628852) (xy 36.301145 -407.618745) (xy 36.308892 -407.600072) (xy 36.323189 -407.585781)
			(xy 36.341864 -407.578041) (xy 36.351972 -407.577544) (xy 37.068252 -407.577544) (xy 37.078351 -407.578123)
			(xy 37.097017 -407.585835) (xy 37.111312 -407.600102) (xy 37.119058 -407.618754) (xy 37.11956 -407.628852)
			(xy 37.11956 -407.786332) (xy 37.119964 -407.79552) (xy 37.126483 -407.812703) (xy 37.13226 -407.81986)
			(xy 37.154118 -407.845531) (xy 37.192209 -407.901164) (xy 37.223362 -407.960959) (xy 37.247129 -408.024055)
			(xy 37.263166 -408.089544) (xy 37.271243 -408.156482) (xy 37.271244 -408.223906) (xy 37.263168 -408.290844)
			(xy 37.247132 -408.356333) (xy 37.223367 -408.41943) (xy 37.192215 -408.479226) (xy 37.154125 -408.534859)
			(xy 37.13226 -408.560524) (xy 37.126466 -408.567671) (xy 37.119951 -408.58486) (xy 37.11956 -408.594052)
			(xy 37.11956 -409.086304) (xy 37.119977 -409.09549) (xy 37.126487 -409.112674) (xy 37.13226 -409.119832)
			(xy 37.15409 -409.145526) (xy 37.192182 -409.201155) (xy 37.223337 -409.260947) (xy 37.247105 -409.32404)
			(xy 37.263144 -409.389526) (xy 37.271223 -409.456462) (xy 37.271227 -409.523884) (xy 37.263154 -409.59082)
			(xy 37.247121 -409.656308) (xy 37.223359 -409.719403) (xy 37.19221 -409.779198) (xy 37.154123 -409.834831)
			(xy 37.13226 -409.860496) (xy 37.126478 -409.867651) (xy 37.119955 -409.884834) (xy 37.11956 -409.894024)
			(xy 37.11956 -410.051504) (xy 37.119186 -410.061632) (xy 37.111429 -410.080343) (xy 37.097099 -410.094659)
			(xy 37.07838 -410.102396) (xy 37.068252 -410.102812) (xy 36.351972 -410.102812) (xy 36.341863 -410.102338)
			(xy 36.323186 -410.094594) (xy 36.308893 -410.080293) (xy 36.301157 -410.061613) (xy 36.300664 -410.051504)
			(xy 36.300664 -409.894024) (xy 36.300228 -409.88484) (xy 36.293731 -409.867656) (xy 36.287964 -409.860496)
			(xy 36.266066 -409.834859) (xy 36.227981 -409.77922) (xy 36.196834 -409.719419) (xy 36.173073 -409.656319)
			(xy 36.157041 -409.590827) (xy 36.148969 -409.523886) (xy 35.0208 -409.523886) (xy 34.992066 -409.579044)
			(xy 34.953976 -409.634679) (xy 34.932112 -409.660344) (xy 34.926316 -409.667489) (xy 34.9198 -409.68468)
			(xy 34.919412 -409.693872) (xy 34.919412 -410.186124) (xy 34.919808 -410.195313) (xy 34.926331 -410.212497)
			(xy 34.932112 -410.219652) (xy 34.95396 -410.24533) (xy 34.992048 -410.300963) (xy 35.023199 -410.360758)
			(xy 35.046964 -410.423853) (xy 35.063 -410.48934) (xy 35.071077 -410.556277) (xy 35.071078 -410.623641)
			(xy 38.349141 -410.623641) (xy 38.349143 -410.556335) (xy 38.357188 -410.489512) (xy 38.373162 -410.424129)
			(xy 38.396835 -410.361124) (xy 38.427868 -410.3014) (xy 38.465816 -410.245813) (xy 38.487604 -410.22016)
			(xy 38.493401 -410.213015) (xy 38.499915 -410.195824) (xy 38.500304 -410.186632) (xy 38.500304 -409.693364)
			(xy 38.49991 -409.684175) (xy 38.493385 -409.666991) (xy 38.487604 -409.659836) (xy 38.465829 -409.634174)
			(xy 38.427882 -409.578588) (xy 38.39685 -409.518865) (xy 38.373178 -409.455862) (xy 38.357206 -409.390482)
			(xy 38.349161 -409.323661) (xy 38.34916 -409.256357) (xy 38.357202 -409.189536) (xy 38.373173 -409.124155)
			(xy 38.396843 -409.061151) (xy 38.427873 -409.001428) (xy 38.465818 -408.945841) (xy 38.487604 -408.920188)
			(xy 38.493389 -408.913034) (xy 38.49991 -408.89585) (xy 38.500304 -408.88666) (xy 38.500304 -408.728672)
			(xy 38.500699 -408.718516) (xy 38.508504 -408.699762) (xy 38.522909 -408.685439) (xy 38.541707 -408.677741)
			(xy 38.551866 -408.677364) (xy 39.268146 -408.677364) (xy 39.278279 -408.67779) (xy 39.297005 -408.685537)
			(xy 39.311361 -408.699842) (xy 39.319174 -408.718541) (xy 39.319708 -408.728672) (xy 39.319708 -408.88666)
			(xy 39.320136 -408.895845) (xy 39.326637 -408.91303) (xy 39.332408 -408.920188) (xy 39.354209 -408.94583)
			(xy 39.392161 -409.001416) (xy 39.423197 -409.061141) (xy 39.446871 -409.124147) (xy 39.462845 -409.189531)
			(xy 39.470889 -409.256356) (xy 39.470888 -409.323663) (xy 39.462842 -409.390487) (xy 39.446866 -409.45587)
			(xy 39.423189 -409.518876) (xy 39.420585 -409.523887) (xy 40.548735 -409.523887) (xy 40.548738 -409.456459)
			(xy 40.556818 -409.389518) (xy 40.572859 -409.324026) (xy 40.59663 -409.260927) (xy 40.627788 -409.20113)
			(xy 40.665884 -409.145496) (xy 40.687752 -409.119832) (xy 40.693566 -409.1127) (xy 40.700069 -409.095499)
			(xy 40.700452 -409.086304) (xy 40.700452 -408.594052) (xy 40.700005 -408.584869) (xy 40.693516 -408.567685)
			(xy 40.687752 -408.560524) (xy 40.665878 -408.534866) (xy 40.627786 -408.479232) (xy 40.596633 -408.419435)
			(xy 40.572867 -408.356337) (xy 40.556831 -408.290847) (xy 40.548755 -408.223907) (xy 40.548755 -408.156481)
			(xy 40.556833 -408.089542) (xy 40.572871 -408.024051) (xy 40.596638 -407.960954) (xy 40.627793 -407.901158)
			(xy 40.665886 -407.845524) (xy 40.687752 -407.81986) (xy 40.693554 -407.812719) (xy 40.700064 -407.795525)
			(xy 40.700452 -407.786332) (xy 40.700452 -407.628852) (xy 40.700945 -407.618746) (xy 40.708689 -407.600076)
			(xy 40.722983 -407.585785) (xy 40.741654 -407.578043) (xy 40.75176 -407.577544) (xy 41.46804 -407.577544)
			(xy 41.478144 -407.578051) (xy 41.496813 -407.585791) (xy 41.511104 -407.600081) (xy 41.518847 -407.618748)
			(xy 41.519348 -407.628852) (xy 41.519348 -407.786332) (xy 41.519755 -407.795519) (xy 41.526272 -407.812703)
			(xy 41.532048 -407.81986) (xy 41.553906 -407.845531) (xy 41.591998 -407.901163) (xy 41.623152 -407.960958)
			(xy 41.646919 -408.024055) (xy 41.662957 -408.089543) (xy 41.671034 -408.156482) (xy 41.671035 -408.223906)
			(xy 41.662959 -408.290845) (xy 41.646923 -408.356334) (xy 41.623157 -408.419431) (xy 41.592004 -408.479226)
			(xy 41.553913 -408.53486) (xy 41.532048 -408.560524) (xy 41.526252 -408.56767) (xy 41.519739 -408.58486)
			(xy 41.519348 -408.594052) (xy 41.519348 -409.086304) (xy 41.519768 -409.09549) (xy 41.526276 -409.112674)
			(xy 41.532048 -409.119832) (xy 41.553878 -409.145526) (xy 41.591972 -409.201155) (xy 41.623127 -409.260947)
			(xy 41.646895 -409.32404) (xy 41.662935 -409.389526) (xy 41.671014 -409.456462) (xy 41.671018 -409.523884)
			(xy 41.662945 -409.590821) (xy 41.646911 -409.656308) (xy 41.623149 -409.719404) (xy 41.591999 -409.779199)
			(xy 41.553912 -409.834832) (xy 41.532048 -409.860496) (xy 41.526264 -409.86765) (xy 41.519743 -409.884834)
			(xy 41.519348 -409.894024) (xy 41.519348 -410.051504) (xy 41.518819 -410.061607) (xy 41.511089 -410.080276)
			(xy 41.496806 -410.094569) (xy 41.478143 -410.102312) (xy 41.46804 -410.102812) (xy 40.75176 -410.102812)
			(xy 40.74165 -410.102348) (xy 40.722973 -410.094599) (xy 40.70868 -410.080296) (xy 40.700945 -410.061614)
			(xy 40.700452 -410.051504) (xy 40.700452 -409.894024) (xy 40.700019 -409.884839) (xy 40.69352 -409.867655)
			(xy 40.687752 -409.860496) (xy 40.665851 -409.834861) (xy 40.62776 -409.779223) (xy 40.596608 -409.719423)
			(xy 40.572843 -409.656322) (xy 40.556809 -409.590829) (xy 40.548735 -409.523887) (xy 39.420585 -409.523887)
			(xy 39.392152 -409.578599) (xy 39.354198 -409.634185) (xy 39.332408 -409.659836) (xy 39.326615 -409.666984)
			(xy 39.320098 -409.684172) (xy 39.319708 -409.693364) (xy 39.319708 -410.186632) (xy 39.320101 -410.195821)
			(xy 39.326626 -410.213005) (xy 39.332408 -410.22016) (xy 39.354182 -410.245824) (xy 39.392134 -410.301408)
			(xy 39.423171 -410.361129) (xy 39.446847 -410.424132) (xy 39.462823 -410.489513) (xy 39.470869 -410.556336)
			(xy 39.470871 -410.62364) (xy 39.470864 -410.6237) (xy 42.74891 -410.6237) (xy 42.748911 -410.556276)
			(xy 42.756989 -410.489336) (xy 42.773026 -410.423846) (xy 42.796792 -410.360749) (xy 42.827944 -410.300952)
			(xy 42.866035 -410.245317) (xy 42.8879 -410.219652) (xy 42.893699 -410.212509) (xy 42.900212 -410.195317)
			(xy 42.9006 -410.186124) (xy 42.9006 -409.693872) (xy 42.900204 -409.684683) (xy 42.89368 -409.667499)
			(xy 42.8879 -409.660344) (xy 42.866048 -409.634669) (xy 42.827959 -409.579036) (xy 42.796808 -409.519241)
			(xy 42.773043 -409.456145) (xy 42.757006 -409.390658) (xy 42.74893 -409.32372) (xy 42.748928 -409.256298)
			(xy 42.757003 -409.18936) (xy 42.773037 -409.123872) (xy 42.7968 -409.060775) (xy 42.827949 -409.00098)
			(xy 42.866037 -408.945345) (xy 42.8879 -408.91968) (xy 42.893688 -408.912528) (xy 42.900208 -408.895343)
			(xy 42.9006 -408.886152) (xy 42.9006 -408.728672) (xy 42.901062 -408.718561) (xy 42.908809 -408.699883)
			(xy 42.923113 -408.685589) (xy 42.941797 -408.677855) (xy 42.951908 -408.677364) (xy 43.668188 -408.677364)
			(xy 43.678292 -408.677894) (xy 43.696963 -408.685621) (xy 43.711257 -408.699904) (xy 43.718998 -408.718569)
			(xy 43.719496 -408.728672) (xy 43.719496 -408.886152) (xy 43.71993 -408.895337) (xy 43.726427 -408.912521)
			(xy 43.732196 -408.91968) (xy 43.754072 -408.945335) (xy 43.792161 -409.000971) (xy 43.823311 -409.060769)
			(xy 43.847075 -409.123867) (xy 43.863109 -409.189357) (xy 43.871184 -409.256297) (xy 43.871183 -409.323721)
			(xy 43.863106 -409.390661) (xy 43.847069 -409.45615) (xy 43.823304 -409.519248) (xy 43.792151 -409.579044)
			(xy 43.754061 -409.634679) (xy 43.732196 -409.660344) (xy 43.726398 -409.667488) (xy 43.719884 -409.684679)
			(xy 43.719496 -409.693872) (xy 43.719496 -410.186124) (xy 43.719895 -410.195312) (xy 43.726417 -410.212497)
			(xy 43.732196 -410.219652) (xy 43.754044 -410.24533) (xy 43.792134 -410.300963) (xy 43.823285 -410.360757)
			(xy 43.847051 -410.423852) (xy 43.863087 -410.48934) (xy 43.871165 -410.556277) (xy 43.871166 -410.623642)
			(xy 47.149205 -410.623642) (xy 47.149207 -410.556334) (xy 47.157253 -410.48951) (xy 47.173229 -410.424126)
			(xy 47.196906 -410.361121) (xy 47.227944 -410.301397) (xy 47.265898 -410.245812) (xy 47.287688 -410.22016)
			(xy 47.293483 -410.213013) (xy 47.299999 -410.195824) (xy 47.300388 -410.186632) (xy 47.300388 -409.693364)
			(xy 47.299998 -409.684175) (xy 47.293471 -409.66699) (xy 47.287688 -409.659836) (xy 47.265911 -409.634175)
			(xy 47.227958 -409.578591) (xy 47.196922 -409.518869) (xy 47.173246 -409.455866) (xy 47.157271 -409.390484)
			(xy 47.149225 -409.323662) (xy 47.149224 -409.256357) (xy 47.157268 -409.189534) (xy 47.173241 -409.124152)
			(xy 47.196914 -409.061148) (xy 47.227949 -409.001425) (xy 47.2659 -408.945839) (xy 47.287688 -408.920188)
			(xy 47.293471 -408.913033) (xy 47.299994 -408.89585) (xy 47.300388 -408.88666) (xy 47.300388 -408.728672)
			(xy 47.300798 -408.718518) (xy 47.308601 -408.699767) (xy 47.323001 -408.685445) (xy 47.341793 -408.677744)
			(xy 47.35195 -408.677364) (xy 48.06823 -408.677364) (xy 48.078362 -408.677803) (xy 48.097088 -408.685545)
			(xy 48.111444 -408.699846) (xy 48.119258 -408.718542) (xy 48.119792 -408.728672) (xy 48.119792 -408.88666)
			(xy 48.120223 -408.895845) (xy 48.126722 -408.913029) (xy 48.132492 -408.920188) (xy 48.154291 -408.945831)
			(xy 48.192237 -409.001419) (xy 48.223268 -409.061145) (xy 48.246939 -409.12415) (xy 48.26291 -409.189533)
			(xy 48.270953 -409.256356) (xy 48.270952 -409.323662) (xy 48.262907 -409.390485) (xy 48.246933 -409.455867)
			(xy 48.223261 -409.518872) (xy 48.192228 -409.578596) (xy 48.15428 -409.634183) (xy 48.132492 -409.659836)
			(xy 48.126697 -409.666982) (xy 48.120182 -409.684172) (xy 48.119792 -409.693364) (xy 48.119792 -410.186632)
			(xy 48.120188 -410.195821) (xy 48.126712 -410.213005) (xy 48.132492 -410.22016) (xy 48.154263 -410.245825)
			(xy 48.19221 -410.301411) (xy 48.223243 -410.361133) (xy 48.246915 -410.424135) (xy 48.262888 -410.489516)
			(xy 48.270933 -410.556336) (xy 48.270934 -410.62364) (xy 48.262892 -410.690461) (xy 48.246922 -410.755842)
			(xy 48.223252 -410.818845) (xy 48.192223 -410.878569) (xy 48.154278 -410.934155) (xy 48.132492 -410.959808)
			(xy 48.126709 -410.966963) (xy 48.120186 -410.984146) (xy 48.119792 -410.993336) (xy 48.119792 -411.151324)
			(xy 48.119398 -411.161481) (xy 48.111593 -411.180235) (xy 48.097188 -411.194558) (xy 48.078389 -411.202255)
			(xy 48.06823 -411.202632) (xy 47.35195 -411.202632) (xy 47.341823 -411.202132) (xy 47.323098 -411.194415)
			(xy 47.308739 -411.180132) (xy 47.300923 -411.161448) (xy 47.300388 -411.151324) (xy 47.300388 -410.993336)
			(xy 47.299963 -410.98415) (xy 47.29346 -410.966966) (xy 47.287688 -410.959808) (xy 47.265883 -410.934169)
			(xy 47.227932 -410.878582) (xy 47.196896 -410.818857) (xy 47.173222 -410.755851) (xy 47.157249 -410.690466)
			(xy 47.149205 -410.623642) (xy 43.871166 -410.623642) (xy 43.871166 -410.623699) (xy 43.863092 -410.690636)
			(xy 43.847058 -410.756125) (xy 43.823295 -410.819221) (xy 43.792146 -410.879017) (xy 43.754059 -410.934651)
			(xy 43.732196 -410.960316) (xy 43.72641 -410.967468) (xy 43.719889 -410.984653) (xy 43.719496 -410.993844)
			(xy 43.719496 -411.151324) (xy 43.719035 -411.161435) (xy 43.711288 -411.180114) (xy 43.696984 -411.194408)
			(xy 43.678299 -411.202142) (xy 43.668188 -411.202632) (xy 42.951908 -411.202632) (xy 42.941804 -411.202109)
			(xy 42.923132 -411.19438) (xy 42.908838 -411.180095) (xy 42.901097 -411.161428) (xy 42.9006 -411.151324)
			(xy 42.9006 -410.993844) (xy 42.900169 -410.984659) (xy 42.89367 -410.967474) (xy 42.8879 -410.960316)
			(xy 42.86602 -410.934664) (xy 42.827932 -410.879027) (xy 42.796782 -410.819229) (xy 42.773019 -410.756131)
			(xy 42.756984 -410.69064) (xy 42.74891 -410.6237) (xy 39.470864 -410.6237) (xy 39.462827 -410.690463)
			(xy 39.446854 -410.755845) (xy 39.423181 -410.818849) (xy 39.392147 -410.878572) (xy 39.354196 -410.934157)
			(xy 39.332408 -410.959808) (xy 39.326626 -410.966964) (xy 39.320103 -410.984146) (xy 39.319708 -410.993336)
			(xy 39.319708 -411.151324) (xy 39.319298 -411.161479) (xy 39.311496 -411.18023) (xy 39.297096 -411.194552)
			(xy 39.278303 -411.202253) (xy 39.268146 -411.202632) (xy 38.551866 -411.202632) (xy 38.541734 -411.202201)
			(xy 38.523006 -411.194456) (xy 38.50865 -411.180153) (xy 38.500837 -411.161454) (xy 38.500304 -411.151324)
			(xy 38.500304 -410.993336) (xy 38.499876 -410.984151) (xy 38.493375 -410.966966) (xy 38.487604 -410.959808)
			(xy 38.465802 -410.934168) (xy 38.427856 -410.878579) (xy 38.396825 -410.818854) (xy 38.373155 -410.755848)
			(xy 38.357184 -410.690464) (xy 38.349141 -410.623641) (xy 35.071078 -410.623641) (xy 35.071078 -410.623699)
			(xy 35.063004 -410.690636) (xy 35.046971 -410.756124) (xy 35.023209 -410.81922) (xy 34.992061 -410.879016)
			(xy 34.953975 -410.934651) (xy 34.932112 -410.960316) (xy 34.926328 -410.96747) (xy 34.919805 -410.984654)
			(xy 34.919412 -410.993844) (xy 34.919412 -411.151324) (xy 34.918935 -411.161433) (xy 34.911192 -411.180109)
			(xy 34.896893 -411.194403) (xy 34.878213 -411.202139) (xy 34.868104 -411.202632) (xy 34.151824 -411.202632)
			(xy 34.141721 -411.202096) (xy 34.123049 -411.194372) (xy 34.108755 -411.180091) (xy 34.101013 -411.161427)
			(xy 34.100516 -411.151324) (xy 34.100516 -410.993844) (xy 34.100081 -410.98466) (xy 34.093584 -410.967475)
			(xy 34.087816 -410.960316) (xy 34.065936 -410.934664) (xy 34.027846 -410.879028) (xy 33.996696 -410.81923)
			(xy 33.972932 -410.756131) (xy 33.956897 -410.690641) (xy 33.948822 -410.623701) (xy 30.670776 -410.623701)
			(xy 30.66274 -410.690462) (xy 30.646767 -410.755844) (xy 30.623095 -410.818848) (xy 30.592061 -410.878571)
			(xy 30.554112 -410.934156) (xy 30.532324 -410.959808) (xy 30.526544 -410.966965) (xy 30.520019 -410.984146)
			(xy 30.519624 -410.993336) (xy 30.519624 -411.151324) (xy 30.519199 -411.161477) (xy 30.5114 -411.180225)
			(xy 30.497005 -411.194547) (xy 30.478217 -411.20225) (xy 30.468062 -411.202632) (xy 29.751782 -411.202632)
			(xy 29.741651 -411.202188) (xy 29.722924 -411.194449) (xy 29.708567 -411.180149) (xy 29.700753 -411.161453)
			(xy 29.70022 -411.151324) (xy 29.70022 -410.993336) (xy 29.699788 -410.984151) (xy 29.693289 -410.966967)
			(xy 29.68752 -410.959808) (xy 29.665717 -410.934169) (xy 29.62777 -410.87858) (xy 29.596738 -410.818854)
			(xy 29.573067 -410.755848) (xy 29.557096 -410.690465) (xy 29.549054 -410.623641) (xy 0.508 -410.623641)
			(xy 0.508 -416.589972) (xy 0.508522 -416.645779) (xy 0.516863 -416.757081) (xy 0.533498 -416.867448)
			(xy 0.558335 -416.976264) (xy 0.591234 -417.082919) (xy 0.632011 -417.186818) (xy 0.680438 -417.287379)
			(xy 0.681656 -417.289488) (xy 53.073808 -417.289488) (xy 53.073808 -394.27912) (xy 66.477388 -394.27912)
			(xy 66.525648 -394.32738) (xy 66.525648 -397.823885) (xy 71.348788 -397.823885) (xy 71.348792 -397.756458)
			(xy 71.356871 -397.689518) (xy 71.372911 -397.624026) (xy 71.396679 -397.560928) (xy 71.427833 -397.501131)
			(xy 71.465926 -397.445495) (xy 71.487792 -397.41983) (xy 71.4936 -397.412693) (xy 71.500108 -397.395496)
			(xy 71.500492 -397.386302) (xy 71.500492 -396.89405) (xy 71.50006 -396.884865) (xy 71.493562 -396.86768)
			(xy 71.487792 -396.860522) (xy 71.465918 -396.834865) (xy 71.427831 -396.779229) (xy 71.396681 -396.719431)
			(xy 71.372918 -396.656334) (xy 71.356883 -396.590844) (xy 71.348808 -396.523905) (xy 71.348809 -396.45648)
			(xy 71.356886 -396.389542) (xy 71.372922 -396.324052) (xy 71.396687 -396.260955) (xy 71.427838 -396.201158)
			(xy 71.465928 -396.145523) (xy 71.487792 -396.119858) (xy 71.493588 -396.112712) (xy 71.500103 -396.095522)
			(xy 71.500492 -396.08633) (xy 71.500492 -395.92885) (xy 71.501066 -395.918732) (xy 71.508769 -395.900021)
			(xy 71.523028 -395.885665) (xy 71.541686 -395.877836) (xy 71.5518 -395.877288) (xy 72.26808 -395.877288)
			(xy 72.278231 -395.877738) (xy 72.296981 -395.885524) (xy 72.311305 -395.899912) (xy 72.319007 -395.918697)
			(xy 72.319388 -395.92885) (xy 72.319388 -396.08633) (xy 72.319786 -396.095518) (xy 72.326308 -396.112703)
			(xy 72.332088 -396.119858) (xy 72.353943 -396.145531) (xy 72.392032 -396.201164) (xy 72.423184 -396.260959)
			(xy 72.446949 -396.324055) (xy 72.462986 -396.389543) (xy 72.471063 -396.456481) (xy 72.471064 -396.523904)
			(xy 72.462989 -396.590842) (xy 72.446954 -396.656331) (xy 72.42319 -396.719427) (xy 72.39204 -396.779223)
			(xy 72.353952 -396.834857) (xy 72.332088 -396.860522) (xy 72.326298 -396.867672) (xy 72.31978 -396.884859)
			(xy 72.319388 -396.89405) (xy 72.319388 -397.386302) (xy 72.3198 -397.395489) (xy 72.326313 -397.412673)
			(xy 72.332088 -397.41983) (xy 72.353915 -397.445526) (xy 72.392006 -397.501156) (xy 72.420766 -397.556355)
			(xy 73.54898 -397.556355) (xy 73.557023 -397.489534) (xy 73.572995 -397.424152) (xy 73.596666 -397.361148)
			(xy 73.627698 -397.301425) (xy 73.665645 -397.245838) (xy 73.687432 -397.220186) (xy 73.693221 -397.213036)
			(xy 73.69974 -397.195849) (xy 73.700132 -397.186658) (xy 73.700132 -397.028924) (xy 73.700542 -397.018767)
			(xy 73.708335 -397.000009) (xy 73.722736 -396.985684) (xy 73.741535 -396.977989) (xy 73.751694 -396.977616)
			(xy 74.467974 -396.977616) (xy 74.478096 -396.978147) (xy 74.496812 -396.985862) (xy 74.511169 -397.000134)
			(xy 74.518993 -397.018805) (xy 74.519536 -397.028924) (xy 74.519536 -397.186658) (xy 74.519981 -397.195841)
			(xy 74.526472 -397.213025) (xy 74.532236 -397.220186) (xy 74.554034 -397.24583) (xy 74.591984 -397.301417)
			(xy 74.623019 -397.361141) (xy 74.646692 -397.424147) (xy 74.662665 -397.48953) (xy 74.670709 -397.556354)
			(xy 74.670708 -397.623661) (xy 74.662662 -397.690484) (xy 74.646687 -397.755867) (xy 74.623012 -397.818872)
			(xy 74.620438 -397.823826) (xy 75.749084 -397.823826) (xy 75.749087 -397.756517) (xy 75.757136 -397.689691)
			(xy 75.773114 -397.624306) (xy 75.796793 -397.5613) (xy 75.827833 -397.501576) (xy 75.865789 -397.44599)
			(xy 75.88758 -397.420338) (xy 75.893383 -397.413197) (xy 75.899895 -397.396003) (xy 75.90028 -397.38681)
			(xy 75.90028 -396.893542) (xy 75.899854 -396.884356) (xy 75.893352 -396.867172) (xy 75.88758 -396.860014)
			(xy 75.865781 -396.83437) (xy 75.82783 -396.778784) (xy 75.796795 -396.719059) (xy 75.773121 -396.656054)
			(xy 75.757147 -396.59067) (xy 75.749104 -396.523846) (xy 75.749104 -396.456539) (xy 75.75715 -396.389715)
			(xy 75.773125 -396.324332) (xy 75.796801 -396.261327) (xy 75.827838 -396.201603) (xy 75.86579 -396.146018)
			(xy 75.88758 -396.120366) (xy 75.893371 -396.113217) (xy 75.89989 -396.096029) (xy 75.90028 -396.086838)
			(xy 75.90028 -395.92885) (xy 75.900706 -395.918676) (xy 75.908482 -395.899875) (xy 75.922868 -395.885487)
			(xy 75.941668 -395.877707) (xy 75.951842 -395.877288) (xy 76.668122 -395.877288) (xy 76.678301 -395.877647)
			(xy 76.697106 -395.885449) (xy 76.711492 -395.899855) (xy 76.719267 -395.91867) (xy 76.719684 -395.92885)
			(xy 76.719684 -396.086838) (xy 76.720079 -396.096027) (xy 76.726604 -396.113211) (xy 76.732384 -396.120366)
			(xy 76.754161 -396.146026) (xy 76.792109 -396.201612) (xy 76.823141 -396.261335) (xy 76.846814 -396.324338)
			(xy 76.862787 -396.389719) (xy 76.870831 -396.456541) (xy 76.870832 -396.523844) (xy 76.862789 -396.590666)
			(xy 76.846818 -396.656047) (xy 76.823147 -396.719051) (xy 76.792117 -396.778775) (xy 76.75417 -396.834362)
			(xy 76.732384 -396.860014) (xy 76.726597 -396.867166) (xy 76.720077 -396.884351) (xy 76.719684 -396.893542)
			(xy 76.719684 -397.38681) (xy 76.720093 -397.395997) (xy 76.726608 -397.413181) (xy 76.732384 -397.420338)
			(xy 76.754133 -397.446021) (xy 76.792082 -397.501604) (xy 76.820503 -397.556296) (xy 77.948748 -397.556296)
			(xy 77.956824 -397.489358) (xy 77.972859 -397.423869) (xy 77.996623 -397.360772) (xy 78.027774 -397.300977)
			(xy 78.065864 -397.245343) (xy 78.087728 -397.219678) (xy 78.09352 -397.21253) (xy 78.100037 -397.195341)
			(xy 78.100428 -397.18615) (xy 78.100428 -397.028924) (xy 78.100836 -397.0188) (xy 78.108582 -397.000091)
			(xy 78.122901 -396.985775) (xy 78.141611 -396.978034) (xy 78.151736 -396.977616) (xy 78.868016 -396.977616)
			(xy 78.878142 -396.978003) (xy 78.896849 -396.985759) (xy 78.911163 -397.000085) (xy 78.918905 -397.018798)
			(xy 78.919324 -397.028924) (xy 78.919324 -397.18615) (xy 78.919753 -397.195335) (xy 78.926253 -397.21252)
			(xy 78.932024 -397.219678) (xy 78.953897 -397.245336) (xy 78.991984 -397.300972) (xy 79.023133 -397.360769)
			(xy 79.046895 -397.423867) (xy 79.062929 -397.489357) (xy 79.071004 -397.556296) (xy 79.071003 -397.62372)
			(xy 79.062927 -397.690658) (xy 79.046891 -397.756147) (xy 79.023127 -397.819245) (xy 79.02071 -397.823885)
			(xy 80.148876 -397.823885) (xy 80.14888 -397.756458) (xy 80.156959 -397.689518) (xy 80.172998 -397.624027)
			(xy 80.196765 -397.560929) (xy 80.227919 -397.501131) (xy 80.266011 -397.445496) (xy 80.287876 -397.41983)
			(xy 80.293682 -397.412691) (xy 80.300192 -397.395496) (xy 80.300576 -397.386302) (xy 80.300576 -396.89405)
			(xy 80.300147 -396.884865) (xy 80.293647 -396.86768) (xy 80.287876 -396.860522) (xy 80.266003 -396.834864)
			(xy 80.227916 -396.779228) (xy 80.196767 -396.719431) (xy 80.173005 -396.656333) (xy 80.156971 -396.590843)
			(xy 80.148896 -396.523904) (xy 80.148897 -396.45648) (xy 80.156973 -396.389542) (xy 80.173009 -396.324053)
			(xy 80.196773 -396.260955) (xy 80.227924 -396.201159) (xy 80.266012 -396.145524) (xy 80.287876 -396.119858)
			(xy 80.29367 -396.112711) (xy 80.300187 -396.095522) (xy 80.300576 -396.08633) (xy 80.300576 -395.92885)
			(xy 80.301069 -395.918722) (xy 80.308787 -395.899995) (xy 80.323072 -395.885636) (xy 80.341759 -395.877821)
			(xy 80.351884 -395.877288) (xy 81.068164 -395.877288) (xy 81.078314 -395.877751) (xy 81.097063 -395.885532)
			(xy 81.111388 -395.899917) (xy 81.119091 -395.918698) (xy 81.119472 -395.92885) (xy 81.119472 -396.08633)
			(xy 81.119874 -396.095518) (xy 81.126394 -396.112702) (xy 81.132172 -396.119858) (xy 81.154027 -396.145531)
			(xy 81.192118 -396.201164) (xy 81.223271 -396.260959) (xy 81.247037 -396.324054) (xy 81.263074 -396.389543)
			(xy 81.271151 -396.456481) (xy 81.271152 -396.523904) (xy 81.263076 -396.590842) (xy 81.247041 -396.656331)
			(xy 81.223277 -396.719428) (xy 81.192126 -396.779223) (xy 81.154036 -396.834857) (xy 81.132172 -396.860522)
			(xy 81.12638 -396.86767) (xy 81.119863 -396.884859) (xy 81.119472 -396.89405) (xy 81.119472 -397.386302)
			(xy 81.119887 -397.395489) (xy 81.126398 -397.412673) (xy 81.132172 -397.41983) (xy 81.154 -397.445526)
			(xy 81.192091 -397.501155) (xy 81.220853 -397.556356) (xy 82.349068 -397.556356) (xy 82.357111 -397.489534)
			(xy 82.373082 -397.424153) (xy 82.396753 -397.361149) (xy 82.427783 -397.301425) (xy 82.46573 -397.245838)
			(xy 82.487516 -397.220186) (xy 82.493303 -397.213034) (xy 82.499823 -397.195849) (xy 82.500216 -397.186658)
			(xy 82.500216 -397.028924) (xy 82.500641 -397.018769) (xy 82.508432 -397.000014) (xy 82.522828 -396.98569)
			(xy 82.541621 -396.977992) (xy 82.551778 -396.977616) (xy 83.268058 -396.977616) (xy 83.278179 -396.97816)
			(xy 83.296895 -396.98587) (xy 83.311252 -397.000138) (xy 83.319076 -397.018806) (xy 83.31962 -397.028924)
			(xy 83.31962 -397.186658) (xy 83.320046 -397.195844) (xy 83.326548 -397.213028) (xy 83.33232 -397.220186)
			(xy 83.354119 -397.24583) (xy 83.39207 -397.301416) (xy 83.423105 -397.361141) (xy 83.446779 -397.424146)
			(xy 83.462753 -397.48953) (xy 83.470796 -397.556354) (xy 83.470796 -397.623661) (xy 83.46275 -397.690485)
			(xy 83.446775 -397.755868) (xy 83.423099 -397.818873) (xy 83.420495 -397.823884) (xy 84.548667 -397.823884)
			(xy 84.548671 -397.756458) (xy 84.55675 -397.689518) (xy 84.572788 -397.624028) (xy 84.596555 -397.560929)
			(xy 84.627708 -397.501132) (xy 84.665799 -397.445496) (xy 84.687664 -397.41983) (xy 84.693481 -397.412699)
			(xy 84.699982 -397.395497) (xy 84.700364 -397.386302) (xy 84.700364 -396.89405) (xy 84.699916 -396.884867)
			(xy 84.693427 -396.867683) (xy 84.687664 -396.860522) (xy 84.665791 -396.834864) (xy 84.627705 -396.779228)
			(xy 84.596557 -396.71943) (xy 84.572795 -396.656332) (xy 84.556761 -396.590843) (xy 84.548687 -396.523904)
			(xy 84.548688 -396.456481) (xy 84.556764 -396.389542) (xy 84.5728 -396.324053) (xy 84.596563 -396.260956)
			(xy 84.627713 -396.201159) (xy 84.665801 -396.145524) (xy 84.687664 -396.119858) (xy 84.693469 -396.112719)
			(xy 84.699977 -396.095523) (xy 84.700364 -396.08633) (xy 84.700364 -395.92885) (xy 84.700868 -395.918724)
			(xy 84.708584 -395.899999) (xy 84.722866 -395.88564) (xy 84.741548 -395.877823) (xy 84.751672 -395.877288)
			(xy 85.467952 -395.877288) (xy 85.478102 -395.877761) (xy 85.496851 -395.885538) (xy 85.511175 -395.899919)
			(xy 85.518879 -395.918699) (xy 85.51926 -395.92885) (xy 85.51926 -396.08633) (xy 85.519665 -396.095518)
			(xy 85.526183 -396.112701) (xy 85.53196 -396.119858) (xy 85.553816 -396.145531) (xy 85.591907 -396.201163)
			(xy 85.623061 -396.260958) (xy 85.646827 -396.324054) (xy 85.662864 -396.389543) (xy 85.670942 -396.456481)
			(xy 85.670943 -396.523904) (xy 85.662867 -396.590843) (xy 85.646832 -396.656332) (xy 85.623067 -396.719428)
			(xy 85.591915 -396.779224) (xy 85.553825 -396.834857) (xy 85.53196 -396.860522) (xy 85.526167 -396.867669)
			(xy 85.519651 -396.884858) (xy 85.51926 -396.89405) (xy 85.51926 -397.386302) (xy 85.519678 -397.395488)
			(xy 85.526187 -397.412672) (xy 85.53196 -397.41983) (xy 85.553788 -397.445525) (xy 85.591881 -397.501155)
			(xy 85.620612 -397.556296) (xy 86.748836 -397.556296) (xy 86.756911 -397.489358) (xy 86.772946 -397.423869)
			(xy 86.79671 -397.360773) (xy 86.82786 -397.300977) (xy 86.865948 -397.245343) (xy 86.887812 -397.219678)
			(xy 86.893602 -397.212528) (xy 86.90012 -397.195341) (xy 86.900512 -397.18615) (xy 86.900512 -397.028924)
			(xy 86.900936 -397.018802) (xy 86.908678 -397.000096) (xy 86.922993 -396.985781) (xy 86.941698 -396.978037)
			(xy 86.95182 -396.977616) (xy 87.6681 -396.977616) (xy 87.678224 -396.978016) (xy 87.696931 -396.985768)
			(xy 87.711246 -397.000089) (xy 87.718988 -397.018799) (xy 87.719408 -397.028924) (xy 87.719408 -397.18615)
			(xy 87.71984 -397.195335) (xy 87.726338 -397.21252) (xy 87.732108 -397.219678) (xy 87.753982 -397.245335)
			(xy 87.792069 -397.300971) (xy 87.823219 -397.360769) (xy 87.846982 -397.423866) (xy 87.863017 -397.489356)
			(xy 87.871092 -397.556295) (xy 87.871091 -397.62372) (xy 87.863014 -397.690658) (xy 87.846978 -397.756148)
			(xy 87.823213 -397.819245) (xy 87.820827 -397.823826) (xy 88.948962 -397.823826) (xy 88.948966 -397.756517)
			(xy 88.957014 -397.689692) (xy 88.972991 -397.624307) (xy 88.996669 -397.561301) (xy 89.027707 -397.501577)
			(xy 89.065661 -397.44599) (xy 89.087452 -397.420338) (xy 89.093264 -397.413204) (xy 89.099768 -397.396005)
			(xy 89.100152 -397.38681) (xy 89.100152 -396.893542) (xy 89.09971 -396.884358) (xy 89.093217 -396.867175)
			(xy 89.087452 -396.860014) (xy 89.065654 -396.83437) (xy 89.027704 -396.778783) (xy 88.996671 -396.719058)
			(xy 88.972998 -396.656053) (xy 88.957025 -396.590669) (xy 88.948982 -396.523846) (xy 88.948983 -396.456539)
			(xy 88.957028 -396.389716) (xy 88.973003 -396.324333) (xy 88.996677 -396.261328) (xy 89.027712 -396.201604)
			(xy 89.065663 -396.146018) (xy 89.087452 -396.120366) (xy 89.093252 -396.113223) (xy 89.099763 -396.096031)
			(xy 89.100152 -396.086838) (xy 89.100152 -395.92885) (xy 89.100605 -395.91868) (xy 89.108376 -395.899884)
			(xy 89.122753 -395.885496) (xy 89.141544 -395.877712) (xy 89.151714 -395.877288) (xy 89.867994 -395.877288)
			(xy 89.878171 -395.87767) (xy 89.896976 -395.885462) (xy 89.911362 -395.899861) (xy 89.919139 -395.918672)
			(xy 89.919556 -395.92885) (xy 89.919556 -396.086838) (xy 89.919958 -396.096026) (xy 89.926478 -396.11321)
			(xy 89.932256 -396.120366) (xy 89.954034 -396.146026) (xy 89.991983 -396.201611) (xy 90.023017 -396.261334)
			(xy 90.046691 -396.324337) (xy 90.062665 -396.389719) (xy 90.07071 -396.45654) (xy 90.070711 -396.523845)
			(xy 90.062667 -396.590667) (xy 90.046695 -396.656048) (xy 90.023023 -396.719052) (xy 89.991991 -396.778776)
			(xy 89.954043 -396.834362) (xy 89.932256 -396.860014) (xy 89.926465 -396.867163) (xy 89.919948 -396.884351)
			(xy 89.919556 -396.893542) (xy 89.919556 -397.38681) (xy 89.919971 -397.395996) (xy 89.926482 -397.41318)
			(xy 89.932256 -397.420338) (xy 89.954006 -397.446021) (xy 89.991957 -397.501603) (xy 90.020411 -397.556356)
			(xy 91.149156 -397.556356) (xy 91.157198 -397.489535) (xy 91.173169 -397.424153) (xy 91.196839 -397.361149)
			(xy 91.227869 -397.301426) (xy 91.265814 -397.245839) (xy 91.2876 -397.220186) (xy 91.293385 -397.213033)
			(xy 91.299907 -397.195848) (xy 91.3003 -397.186658) (xy 91.3003 -397.028924) (xy 91.300741 -397.018771)
			(xy 91.308529 -397.000019) (xy 91.32292 -396.985695) (xy 91.341708 -396.977995) (xy 91.351862 -396.977616)
			(xy 92.068142 -396.977616) (xy 92.078268 -396.978091) (xy 92.096986 -396.985829) (xy 92.11134 -397.000118)
			(xy 92.119162 -397.0188) (xy 92.119704 -397.028924) (xy 92.119704 -397.186658) (xy 92.120133 -397.195843)
			(xy 92.126634 -397.213028) (xy 92.132404 -397.220186) (xy 92.1542 -397.245831) (xy 92.192146 -397.301419)
			(xy 92.223176 -397.361144) (xy 92.246847 -397.42415) (xy 92.262818 -397.489532) (xy 92.27086 -397.556355)
			(xy 92.270859 -397.62366) (xy 92.262815 -397.690483) (xy 92.246842 -397.755865) (xy 92.22317 -397.81887)
			(xy 92.220595 -397.823825) (xy 115.349226 -397.823825) (xy 115.349229 -397.756518) (xy 115.357277 -397.689693)
			(xy 115.373253 -397.624309) (xy 115.396928 -397.561303) (xy 115.427964 -397.501578) (xy 115.465915 -397.445991)
			(xy 115.487704 -397.420338) (xy 115.49351 -397.413199) (xy 115.500019 -397.396004) (xy 115.500404 -397.38681)
			(xy 115.500404 -396.893542) (xy 115.499973 -396.884357) (xy 115.493474 -396.867173) (xy 115.487704 -396.860014)
			(xy 115.465908 -396.834369) (xy 115.427961 -396.778781) (xy 115.39693 -396.719056) (xy 115.37326 -396.656051)
			(xy 115.357288 -396.590668) (xy 115.349246 -396.523845) (xy 115.349247 -396.45654) (xy 115.357291 -396.389717)
			(xy 115.373264 -396.324335) (xy 115.396937 -396.26133) (xy 115.427969 -396.201606) (xy 115.465917 -396.146019)
			(xy 115.487704 -396.120366) (xy 115.493498 -396.113219) (xy 115.500014 -396.09603) (xy 115.500404 -396.086838)
			(xy 115.500404 -395.92885) (xy 115.500904 -395.918686) (xy 115.508666 -395.899899) (xy 115.523028 -395.885513)
			(xy 115.541803 -395.87772) (xy 115.551966 -395.877288) (xy 116.268246 -395.877288) (xy 116.278427 -395.877627)
			(xy 116.297232 -395.885437) (xy 116.311617 -395.899849) (xy 116.319392 -395.918668) (xy 116.319808 -395.92885)
			(xy 116.319808 -396.086838) (xy 116.320198 -396.096027) (xy 116.326725 -396.113212) (xy 116.332508 -396.120366)
			(xy 116.354288 -396.146026) (xy 116.39224 -396.20161) (xy 116.423277 -396.261332) (xy 116.446952 -396.324335)
			(xy 116.462928 -396.389717) (xy 116.470973 -396.45654) (xy 116.470974 -396.523845) (xy 116.46293 -396.590668)
			(xy 116.446957 -396.65605) (xy 116.423283 -396.719055) (xy 116.392248 -396.778777) (xy 116.354297 -396.834363)
			(xy 116.332508 -396.860014) (xy 116.326724 -396.867168) (xy 116.320202 -396.884352) (xy 116.319808 -396.893542)
			(xy 116.319808 -397.38681) (xy 116.320212 -397.395998) (xy 116.32673 -397.413182) (xy 116.332508 -397.420338)
			(xy 116.35426 -397.44602) (xy 116.392213 -397.501601) (xy 116.42064 -397.556296) (xy 117.548866 -397.556296)
			(xy 117.556942 -397.489357) (xy 117.572978 -397.423868) (xy 117.596743 -397.360771) (xy 117.627896 -397.300976)
			(xy 117.665987 -397.245342) (xy 117.687852 -397.219678) (xy 117.693647 -397.212532) (xy 117.700161 -397.195342)
			(xy 117.700552 -397.18615) (xy 117.700552 -397.028924) (xy 117.701103 -397.018823) (xy 117.708824 -397.000154)
			(xy 117.7231 -396.98586) (xy 117.741759 -396.978116) (xy 117.75186 -396.977616) (xy 118.46814 -396.977616)
			(xy 118.478253 -396.978053) (xy 118.496935 -396.985807) (xy 118.511229 -397.000118) (xy 118.51896 -397.01881)
			(xy 118.519448 -397.028924) (xy 118.519448 -397.18615) (xy 118.519894 -397.195333) (xy 118.526384 -397.212517)
			(xy 118.532148 -397.219678) (xy 118.554024 -397.245334) (xy 118.592115 -397.300969) (xy 118.623269 -397.360766)
			(xy 118.647035 -397.423864) (xy 118.663071 -397.489355) (xy 118.671147 -397.556295) (xy 118.671146 -397.62372)
			(xy 118.663068 -397.69066) (xy 118.64703 -397.75615) (xy 118.623262 -397.819248) (xy 118.620846 -397.823885)
			(xy 119.748994 -397.823885) (xy 119.748998 -397.756458) (xy 119.757077 -397.689517) (xy 119.773117 -397.624026)
			(xy 119.796885 -397.560928) (xy 119.828041 -397.50113) (xy 119.866134 -397.445495) (xy 119.888 -397.41983)
			(xy 119.893809 -397.412693) (xy 119.900316 -397.395496) (xy 119.9007 -397.386302) (xy 119.9007 -396.89405)
			(xy 119.900266 -396.884865) (xy 119.893769 -396.867681) (xy 119.888 -396.860522) (xy 119.866126 -396.834865)
			(xy 119.828038 -396.779229) (xy 119.796888 -396.719432) (xy 119.773124 -396.656334) (xy 119.757089 -396.590844)
			(xy 119.749014 -396.523905) (xy 119.749015 -396.45648) (xy 119.757092 -396.389541) (xy 119.773128 -396.324052)
			(xy 119.796894 -396.260954) (xy 119.828046 -396.201158) (xy 119.866135 -396.145523) (xy 119.888 -396.119858)
			(xy 119.893797 -396.112713) (xy 119.900311 -396.095522) (xy 119.9007 -396.08633) (xy 119.9007 -395.92885)
			(xy 119.901266 -395.918731) (xy 119.90897 -395.900019) (xy 119.923232 -395.885662) (xy 119.941893 -395.877834)
			(xy 119.952008 -395.877288) (xy 120.668288 -395.877288) (xy 120.678408 -395.877725) (xy 120.697109 -395.885467)
			(xy 120.711424 -395.899777) (xy 120.719171 -395.918476) (xy 120.719596 -395.928596) (xy 120.719596 -396.08633)
			(xy 120.719992 -396.095519) (xy 120.726516 -396.112703) (xy 120.732296 -396.119858) (xy 120.75415 -396.145531)
			(xy 120.79224 -396.201165) (xy 120.823391 -396.26096) (xy 120.847156 -396.324055) (xy 120.863192 -396.389544)
			(xy 120.871269 -396.456481) (xy 120.87127 -396.523904) (xy 120.863195 -396.590842) (xy 120.84716 -396.65633)
			(xy 120.823397 -396.719427) (xy 120.792247 -396.779223) (xy 120.75416 -396.834857) (xy 120.732296 -396.860522)
			(xy 120.726507 -396.867673) (xy 120.719988 -396.884859) (xy 120.719596 -396.89405) (xy 120.719596 -397.386302)
			(xy 120.720006 -397.395489) (xy 120.72652 -397.412673) (xy 120.732296 -397.41983) (xy 120.754123 -397.445526)
			(xy 120.792213 -397.501156) (xy 120.820972 -397.556355) (xy 121.949186 -397.556355) (xy 121.95723 -397.489533)
			(xy 121.973202 -397.424152) (xy 121.996873 -397.361148) (xy 122.027905 -397.301425) (xy 122.065853 -397.245838)
			(xy 122.08764 -397.220186) (xy 122.09343 -397.213036) (xy 122.099948 -397.195849) (xy 122.10034 -397.186658)
			(xy 122.10034 -397.028924) (xy 122.100736 -397.018798) (xy 122.108484 -397.000087) (xy 122.122807 -396.985771)
			(xy 122.141522 -396.978032) (xy 122.151648 -396.977616) (xy 122.868182 -396.977616) (xy 122.878305 -396.978141)
			(xy 122.897021 -396.985858) (xy 122.911377 -397.000132) (xy 122.919201 -397.018804) (xy 122.919744 -397.028924)
			(xy 122.919744 -397.186658) (xy 122.920187 -397.195841) (xy 122.926679 -397.213026) (xy 122.932444 -397.220186)
			(xy 122.954242 -397.24583) (xy 122.992192 -397.301417) (xy 123.023225 -397.361142) (xy 123.046898 -397.424147)
			(xy 123.062871 -397.489531) (xy 123.070915 -397.556354) (xy 123.070914 -397.623661) (xy 123.062868 -397.690484)
			(xy 123.046894 -397.755867) (xy 123.023219 -397.818872) (xy 123.020645 -397.823826) (xy 124.14929 -397.823826)
			(xy 124.149293 -397.756517) (xy 124.157342 -397.689691) (xy 124.17332 -397.624306) (xy 124.197 -397.5613)
			(xy 124.22804 -397.501575) (xy 124.265997 -397.44599) (xy 124.287788 -397.420338) (xy 124.293592 -397.413198)
			(xy 124.300103 -397.396004) (xy 124.300488 -397.38681) (xy 124.300488 -396.893542) (xy 124.30006 -396.884357)
			(xy 124.293559 -396.867172) (xy 124.287788 -396.860014) (xy 124.265989 -396.834371) (xy 124.228037 -396.778784)
			(xy 124.197002 -396.71906) (xy 124.173327 -396.656054) (xy 124.157354 -396.59067) (xy 124.14931 -396.523846)
			(xy 124.14931 -396.456539) (xy 124.157356 -396.389715) (xy 124.173332 -396.324332) (xy 124.197008 -396.261327)
			(xy 124.228045 -396.201603) (xy 124.265998 -396.146018) (xy 124.287788 -396.120366) (xy 124.29358 -396.113218)
			(xy 124.300098 -396.09603) (xy 124.300488 -396.086838) (xy 124.300488 -395.92885) (xy 124.300906 -395.918675)
			(xy 124.308684 -395.899872) (xy 124.323072 -395.885484) (xy 124.341875 -395.877706) (xy 124.35205 -395.877288)
			(xy 125.06833 -395.877288) (xy 125.07851 -395.87764) (xy 125.097315 -395.885445) (xy 125.1117 -395.899852)
			(xy 125.119475 -395.91867) (xy 125.119892 -395.92885) (xy 125.119892 -396.086838) (xy 125.120286 -396.096027)
			(xy 125.126811 -396.113211) (xy 125.132592 -396.120366) (xy 125.154369 -396.146027) (xy 125.192316 -396.201613)
			(xy 125.223348 -396.261335) (xy 125.24702 -396.324339) (xy 125.262993 -396.389719) (xy 125.271037 -396.456541)
			(xy 125.271038 -396.523844) (xy 125.262995 -396.590666) (xy 125.247025 -396.656047) (xy 125.223354 -396.719051)
			(xy 125.192324 -396.778774) (xy 125.154378 -396.834361) (xy 125.132592 -396.860014) (xy 125.126806 -396.867167)
			(xy 125.120285 -396.884351) (xy 125.119892 -396.893542) (xy 125.119892 -397.38681) (xy 125.120299 -397.395998)
			(xy 125.126815 -397.413182) (xy 125.132592 -397.420338) (xy 125.154341 -397.446021) (xy 125.192289 -397.501604)
			(xy 125.22071 -397.556296) (xy 126.348954 -397.556296) (xy 126.35703 -397.489357) (xy 126.373065 -397.423869)
			(xy 126.39683 -397.360772) (xy 126.427981 -397.300976) (xy 126.466071 -397.245343) (xy 126.487936 -397.219678)
			(xy 126.493729 -397.21253) (xy 126.500245 -397.195342) (xy 126.500636 -397.18615) (xy 126.500636 -397.028924)
			(xy 126.501036 -397.018799) (xy 126.508783 -397.000089) (xy 126.523105 -396.985772) (xy 126.541818 -396.978032)
			(xy 126.551944 -396.977616) (xy 127.268224 -396.977616) (xy 127.278336 -396.978066) (xy 127.297018 -396.985814)
			(xy 127.311313 -397.000122) (xy 127.319044 -397.018811) (xy 127.319532 -397.028924) (xy 127.319532 -397.18615)
			(xy 127.319981 -397.195333) (xy 127.326469 -397.212517) (xy 127.332232 -397.219678) (xy 127.354105 -397.245336)
			(xy 127.392191 -397.300972) (xy 127.423339 -397.36077) (xy 127.447102 -397.423867) (xy 127.463135 -397.489357)
			(xy 127.47121 -397.556296) (xy 127.471209 -397.623719) (xy 127.463133 -397.690658) (xy 127.447097 -397.756147)
			(xy 127.423333 -397.819244) (xy 127.420946 -397.823826) (xy 128.54908 -397.823826) (xy 128.549084 -397.756517)
			(xy 128.557132 -397.689691) (xy 128.57311 -397.624306) (xy 128.596789 -397.5613) (xy 128.627829 -397.501576)
			(xy 128.665785 -397.445989) (xy 128.687576 -397.420338) (xy 128.693379 -397.413197) (xy 128.69989 -397.396003)
			(xy 128.700276 -397.38681) (xy 128.700276 -396.893542) (xy 128.699851 -396.884356) (xy 128.693348 -396.867171)
			(xy 128.687576 -396.860014) (xy 128.665777 -396.83437) (xy 128.627826 -396.778784) (xy 128.596792 -396.719059)
			(xy 128.573118 -396.656053) (xy 128.557144 -396.59067) (xy 128.5491 -396.523846) (xy 128.549101 -396.456539)
			(xy 128.557147 -396.389715) (xy 128.573122 -396.324332) (xy 128.596798 -396.261327) (xy 128.627834 -396.201604)
			(xy 128.665787 -396.146018) (xy 128.687576 -396.120366) (xy 128.693367 -396.113216) (xy 128.699886 -396.096029)
			(xy 128.700276 -396.086838) (xy 128.700276 -395.92885) (xy 128.700706 -395.918677) (xy 128.708481 -395.899876)
			(xy 128.722866 -395.885488) (xy 128.741665 -395.877708) (xy 128.751838 -395.877288) (xy 129.468118 -395.877288)
			(xy 129.478297 -395.87765) (xy 129.497102 -395.885451) (xy 129.511487 -395.899856) (xy 129.519263 -395.91867)
			(xy 129.51968 -395.92885) (xy 129.51968 -396.086838) (xy 129.520076 -396.096027) (xy 129.5266 -396.113211)
			(xy 129.53238 -396.120366) (xy 129.554157 -396.146026) (xy 129.592105 -396.201612) (xy 129.623138 -396.261335)
			(xy 129.64681 -396.324338) (xy 129.662784 -396.389719) (xy 129.670828 -396.456541) (xy 129.670829 -396.523844)
			(xy 129.662786 -396.590666) (xy 129.646815 -396.656047) (xy 129.623144 -396.719051) (xy 129.592113 -396.778775)
			(xy 129.554167 -396.834362) (xy 129.53238 -396.860014) (xy 129.526593 -396.867166) (xy 129.520073 -396.884351)
			(xy 129.51968 -396.893542) (xy 129.51968 -397.38681) (xy 129.52009 -397.395997) (xy 129.526604 -397.413181)
			(xy 129.53238 -397.420338) (xy 129.55413 -397.446021) (xy 129.592078 -397.501604) (xy 129.620531 -397.556356)
			(xy 130.749274 -397.556356) (xy 130.757317 -397.489534) (xy 130.773288 -397.424152) (xy 130.796959 -397.361148)
			(xy 130.827991 -397.301425) (xy 130.865937 -397.245838) (xy 130.887724 -397.220186) (xy 130.893512 -397.213035)
			(xy 130.900031 -397.195849) (xy 130.900424 -397.186658) (xy 130.900424 -397.028924) (xy 130.900842 -397.018768)
			(xy 130.908634 -397.000012) (xy 130.923032 -396.985687) (xy 130.941828 -396.97799) (xy 130.951986 -396.977616)
			(xy 131.668266 -396.977616) (xy 131.678388 -396.978154) (xy 131.697103 -396.985866) (xy 131.71146 -397.000137)
			(xy 131.719284 -397.018806) (xy 131.719828 -397.028924) (xy 131.719828 -397.186658) (xy 131.720252 -397.195844)
			(xy 131.726756 -397.213029) (xy 131.732528 -397.220186) (xy 131.754326 -397.24583) (xy 131.792277 -397.301417)
			(xy 131.823312 -397.361141) (xy 131.846985 -397.424147) (xy 131.862959 -397.48953) (xy 131.871003 -397.556354)
			(xy 131.871002 -397.623661) (xy 131.862956 -397.690485) (xy 131.846981 -397.755868) (xy 131.823306 -397.818873)
			(xy 131.792269 -397.878596) (xy 131.754317 -397.934182) (xy 131.732528 -397.959834) (xy 131.726726 -397.966975)
			(xy 131.720217 -397.984169) (xy 131.719828 -397.993362) (xy 131.719828 -398.486884) (xy 131.720239 -398.496071)
			(xy 131.726751 -398.513256) (xy 131.732528 -398.520412) (xy 131.754352 -398.546034) (xy 131.792302 -398.601624)
			(xy 131.823336 -398.661352) (xy 131.847008 -398.72436) (xy 131.86298 -398.789746) (xy 131.871021 -398.856573)
			(xy 131.871018 -398.923881) (xy 131.86297 -398.990707) (xy 131.846992 -399.056092) (xy 131.823314 -399.119098)
			(xy 131.792274 -399.178822) (xy 131.754319 -399.234408) (xy 131.732528 -399.26006) (xy 131.726715 -399.267193)
			(xy 131.720212 -399.284393) (xy 131.719828 -399.293588) (xy 131.719828 -399.451576) (xy 131.719359 -399.461725)
			(xy 131.711577 -399.480472) (xy 131.697195 -399.494795) (xy 131.678417 -399.502501) (xy 131.668266 -399.502884)
			(xy 130.951986 -399.502884) (xy 130.941861 -399.502385) (xy 130.923145 -399.494657) (xy 130.90879 -399.480375)
			(xy 130.900967 -399.461698) (xy 130.900424 -399.451576) (xy 130.900424 -399.293588) (xy 130.900014 -399.284401)
			(xy 130.8935 -399.267217) (xy 130.887724 -399.26006) (xy 130.865972 -399.234378) (xy 130.828023 -399.178796)
			(xy 130.796989 -399.119076) (xy 130.773315 -399.056076) (xy 130.75734 -398.990697) (xy 130.749294 -398.923878)
			(xy 130.74929 -398.856576) (xy 130.757331 -398.789756) (xy 130.773299 -398.724376) (xy 130.796967 -398.661373)
			(xy 130.827996 -398.601651) (xy 130.865939 -398.546065) (xy 130.887724 -398.520412) (xy 130.893543 -398.513283)
			(xy 130.900044 -398.49608) (xy 130.900424 -398.486884) (xy 130.900424 -397.993362) (xy 130.900027 -397.984174)
			(xy 130.893504 -397.96699) (xy 130.887724 -397.959834) (xy 130.865946 -397.934174) (xy 130.827998 -397.878588)
			(xy 130.796965 -397.818865) (xy 130.773293 -397.755862) (xy 130.75732 -397.690481) (xy 130.749275 -397.62366)
			(xy 130.749274 -397.556356) (xy 129.620531 -397.556356) (xy 129.623112 -397.561323) (xy 129.646786 -397.624324)
			(xy 129.662761 -397.689702) (xy 129.670808 -397.756521) (xy 129.670811 -397.823822) (xy 129.662771 -397.890642)
			(xy 129.646803 -397.956022) (xy 129.623135 -398.019025) (xy 129.592108 -398.078747) (xy 129.554165 -398.134333)
			(xy 129.53238 -398.159986) (xy 129.526562 -398.167116) (xy 129.520061 -398.184318) (xy 129.51968 -398.193514)
			(xy 129.51968 -398.351502) (xy 129.519169 -398.361658) (xy 129.511397 -398.380423) (xy 129.497037 -398.394788)
			(xy 129.478274 -398.402565) (xy 129.468118 -398.403064) (xy 128.751838 -398.403064) (xy 128.741669 -398.402605)
			(xy 128.722876 -398.394833) (xy 128.70849 -398.380458) (xy 128.700703 -398.361671) (xy 128.700276 -398.351502)
			(xy 128.700276 -398.193514) (xy 128.699865 -398.184327) (xy 128.693352 -398.167142) (xy 128.687576 -398.159986)
			(xy 128.66575 -398.134365) (xy 128.627799 -398.078775) (xy 128.596766 -398.019048) (xy 128.573093 -397.956039)
			(xy 128.557122 -397.890652) (xy 128.54908 -397.823826) (xy 127.420946 -397.823826) (xy 127.392183 -397.879041)
			(xy 127.354095 -397.934676) (xy 127.332232 -397.960342) (xy 127.326427 -397.967481) (xy 127.319919 -397.984676)
			(xy 127.319532 -397.99387) (xy 127.319532 -398.486376) (xy 127.319969 -398.49556) (xy 127.326466 -398.512744)
			(xy 127.332232 -398.519904) (xy 127.35413 -398.545541) (xy 127.392216 -398.60118) (xy 127.423363 -398.66098)
			(xy 127.447124 -398.724081) (xy 127.463156 -398.789573) (xy 127.471228 -398.856514) (xy 127.471225 -398.92394)
			(xy 127.463146 -398.99088) (xy 127.447108 -399.056371) (xy 127.423341 -399.119469) (xy 127.392188 -399.179266)
			(xy 127.354097 -399.234902) (xy 127.332232 -399.260568) (xy 127.326416 -399.267699) (xy 127.319915 -399.284901)
			(xy 127.319532 -399.294096) (xy 127.319532 -399.451576) (xy 127.318996 -399.461679) (xy 127.311272 -399.480351)
			(xy 127.296991 -399.494645) (xy 127.278327 -399.502387) (xy 127.268224 -399.502884) (xy 126.551944 -399.502884)
			(xy 126.541822 -399.502447) (xy 126.523117 -399.494711) (xy 126.5088 -399.4804) (xy 126.501056 -399.461697)
			(xy 126.500636 -399.451576) (xy 126.500636 -399.294096) (xy 126.50022 -399.28491) (xy 126.49371 -399.267726)
			(xy 126.487936 -399.260568) (xy 126.466106 -399.234874) (xy 126.428014 -399.179245) (xy 126.39686 -399.119453)
			(xy 126.373092 -399.056359) (xy 126.357053 -398.990873) (xy 126.348974 -398.923938) (xy 126.34897 -398.856516)
			(xy 126.357043 -398.78958) (xy 126.373076 -398.724092) (xy 126.396838 -398.660997) (xy 126.427986 -398.601202)
			(xy 126.466073 -398.545569) (xy 126.487936 -398.519904) (xy 126.493718 -398.512749) (xy 126.50024 -398.495566)
			(xy 126.500636 -398.486376) (xy 126.500636 -397.99387) (xy 126.500232 -397.984682) (xy 126.493713 -397.967498)
			(xy 126.487936 -397.960342) (xy 126.466081 -397.934669) (xy 126.427989 -397.879037) (xy 126.396836 -397.819242)
			(xy 126.37307 -397.756146) (xy 126.357032 -397.690657) (xy 126.348955 -397.623719) (xy 126.348954 -397.556296)
			(xy 125.22071 -397.556296) (xy 125.223323 -397.561324) (xy 125.246996 -397.624324) (xy 125.262971 -397.689702)
			(xy 125.271018 -397.756521) (xy 125.271021 -397.823822) (xy 125.262981 -397.890642) (xy 125.247013 -397.956021)
			(xy 125.223346 -398.019024) (xy 125.192319 -398.078747) (xy 125.154377 -398.134334) (xy 125.132592 -398.159986)
			(xy 125.126775 -398.167117) (xy 125.120273 -398.184318) (xy 125.119892 -398.193514) (xy 125.119892 -398.351502)
			(xy 125.119369 -398.361656) (xy 125.111599 -398.38042) (xy 125.097243 -398.394784) (xy 125.078484 -398.402563)
			(xy 125.06833 -398.403064) (xy 124.35205 -398.403064) (xy 124.341882 -398.402595) (xy 124.323089 -398.394827)
			(xy 124.308702 -398.380455) (xy 124.300915 -398.36167) (xy 124.300488 -398.351502) (xy 124.300488 -398.193514)
			(xy 124.300074 -398.184327) (xy 124.293563 -398.167143) (xy 124.287788 -398.159986) (xy 124.265961 -398.134365)
			(xy 124.228011 -398.078775) (xy 124.196976 -398.019048) (xy 124.173304 -397.956039) (xy 124.157332 -397.890653)
			(xy 124.14929 -397.823826) (xy 123.020645 -397.823826) (xy 122.992184 -397.878596) (xy 122.954233 -397.934182)
			(xy 122.932444 -397.959834) (xy 122.926644 -397.966976) (xy 122.920133 -397.984169) (xy 122.919744 -397.993362)
			(xy 122.919744 -398.486884) (xy 122.920174 -398.496069) (xy 122.926675 -398.513253) (xy 122.932444 -398.520412)
			(xy 122.954268 -398.546035) (xy 122.992217 -398.601625) (xy 123.023249 -398.661352) (xy 123.046921 -398.724361)
			(xy 123.062892 -398.789747) (xy 123.070933 -398.856573) (xy 123.07093 -398.923881) (xy 123.062882 -398.990707)
			(xy 123.046905 -399.056091) (xy 123.023227 -399.119097) (xy 122.992189 -399.178822) (xy 122.954235 -399.234408)
			(xy 122.932444 -399.26006) (xy 122.926633 -399.267194) (xy 122.920128 -399.284393) (xy 122.919744 -399.293588)
			(xy 122.919744 -399.451576) (xy 122.919196 -399.461678) (xy 122.911475 -399.480347) (xy 122.897197 -399.494641)
			(xy 122.878537 -399.502385) (xy 122.868436 -399.502884) (xy 122.151902 -399.502884) (xy 122.141778 -399.502372)
			(xy 122.123062 -399.49465) (xy 122.108706 -399.480371) (xy 122.100883 -399.461697) (xy 122.10034 -399.451576)
			(xy 122.10034 -399.293588) (xy 122.099927 -399.284401) (xy 122.093414 -399.267217) (xy 122.08764 -399.26006)
			(xy 122.065888 -399.234379) (xy 122.027938 -399.178796) (xy 121.996903 -399.119077) (xy 121.973228 -399.056076)
			(xy 121.957253 -398.990698) (xy 121.949206 -398.923878) (xy 121.949202 -398.856576) (xy 121.957243 -398.789756)
			(xy 121.973212 -398.724376) (xy 121.996881 -398.661373) (xy 122.02791 -398.60165) (xy 122.065855 -398.546064)
			(xy 122.08764 -398.520412) (xy 122.093461 -398.513285) (xy 122.09996 -398.49608) (xy 122.10034 -398.486884)
			(xy 122.10034 -397.993362) (xy 122.099939 -397.984174) (xy 122.093418 -397.96699) (xy 122.08764 -397.959834)
			(xy 122.065862 -397.934174) (xy 122.027913 -397.878588) (xy 121.996879 -397.818866) (xy 121.973206 -397.755863)
			(xy 121.957232 -397.690481) (xy 121.949187 -397.62366) (xy 121.949186 -397.556355) (xy 120.820972 -397.556355)
			(xy 120.823365 -397.560948) (xy 120.847132 -397.624041) (xy 120.86317 -397.689526) (xy 120.871249 -397.756461)
			(xy 120.871253 -397.823882) (xy 120.86318 -397.890818) (xy 120.847149 -397.956305) (xy 120.823389 -398.0194)
			(xy 120.792242 -398.079195) (xy 120.754158 -398.134829) (xy 120.732296 -398.160494) (xy 120.726519 -398.167653)
			(xy 120.719993 -398.184833) (xy 120.719596 -398.194022) (xy 120.719596 -398.351502) (xy 120.719076 -398.361624)
			(xy 120.711354 -398.380339) (xy 120.697079 -398.394694) (xy 120.678408 -398.402519) (xy 120.668288 -398.403064)
			(xy 119.952008 -398.403064) (xy 119.941882 -398.402677) (xy 119.923171 -398.394924) (xy 119.908855 -398.380599)
			(xy 119.901116 -398.361883) (xy 119.9007 -398.351756) (xy 119.9007 -398.194022) (xy 119.900279 -398.184836)
			(xy 119.893773 -398.167651) (xy 119.888 -398.160494) (xy 119.866099 -398.13486) (xy 119.828011 -398.079221)
			(xy 119.796862 -398.01942) (xy 119.7731 -397.956319) (xy 119.757067 -397.890826) (xy 119.748994 -397.823885)
			(xy 118.620846 -397.823885) (xy 118.592108 -397.879044) (xy 118.554014 -397.934678) (xy 118.532148 -397.960342)
			(xy 118.526345 -397.967482) (xy 118.519835 -397.984677) (xy 118.519448 -397.99387) (xy 118.519448 -398.486376)
			(xy 118.519881 -398.495561) (xy 118.52638 -398.512745) (xy 118.532148 -398.519904) (xy 118.554049 -398.545539)
			(xy 118.59214 -398.601177) (xy 118.623292 -398.660977) (xy 118.647057 -398.724078) (xy 118.663091 -398.789571)
			(xy 118.671165 -398.856513) (xy 118.671162 -398.923941) (xy 118.663082 -398.990882) (xy 118.647041 -399.056374)
			(xy 118.62327 -399.119473) (xy 118.592112 -399.17927) (xy 118.554016 -399.234904) (xy 118.532148 -399.260568)
			(xy 118.526334 -399.2677) (xy 118.519831 -399.284901) (xy 118.519448 -399.294096) (xy 118.519448 -399.451576)
			(xy 118.518897 -399.461677) (xy 118.511176 -399.480346) (xy 118.4969 -399.49464) (xy 118.478241 -399.502384)
			(xy 118.46814 -399.502884) (xy 117.75186 -399.502884) (xy 117.741747 -399.502447) (xy 117.723065 -399.494693)
			(xy 117.708771 -399.480382) (xy 117.70104 -399.46169) (xy 117.700552 -399.451576) (xy 117.700552 -399.294096)
			(xy 117.700132 -399.28491) (xy 117.693624 -399.267726) (xy 117.687852 -399.260568) (xy 117.666022 -399.234874)
			(xy 117.627928 -399.179245) (xy 117.596773 -399.119453) (xy 117.573005 -399.05636) (xy 117.556965 -398.990874)
			(xy 117.548886 -398.923938) (xy 117.548882 -398.856516) (xy 117.556955 -398.789579) (xy 117.572989 -398.724092)
			(xy 117.596751 -398.660996) (xy 117.627901 -398.601201) (xy 117.665988 -398.545568) (xy 117.687852 -398.519904)
			(xy 117.693636 -398.51275) (xy 117.700157 -398.495566) (xy 117.700552 -398.486376) (xy 117.700552 -397.99387)
			(xy 117.700145 -397.984683) (xy 117.693628 -397.967499) (xy 117.687852 -397.960342) (xy 117.665996 -397.93467)
			(xy 117.627904 -397.879037) (xy 117.59675 -397.819243) (xy 117.572983 -397.756147) (xy 117.556945 -397.690658)
			(xy 117.548867 -397.623719) (xy 117.548866 -397.556296) (xy 116.42064 -397.556296) (xy 116.423251 -397.56132)
			(xy 116.446929 -397.624321) (xy 116.462906 -397.6897) (xy 116.470954 -397.75652) (xy 116.470957 -397.823823)
			(xy 116.462916 -397.890644) (xy 116.446945 -397.956025) (xy 116.423275 -398.019028) (xy 116.392243 -398.07875)
			(xy 116.354295 -398.134335) (xy 116.332508 -398.159986) (xy 116.326693 -398.167118) (xy 116.320189 -398.184319)
			(xy 116.319808 -398.193514) (xy 116.319808 -398.351502) (xy 116.319269 -398.361654) (xy 116.311503 -398.380415)
			(xy 116.297152 -398.394778) (xy 116.278398 -398.402561) (xy 116.268246 -398.403064) (xy 115.551966 -398.403064)
			(xy 115.541806 -398.402595) (xy 115.523037 -398.394809) (xy 115.508673 -398.380436) (xy 115.500899 -398.361662)
			(xy 115.500404 -398.351502) (xy 115.500404 -398.193514) (xy 115.499986 -398.184328) (xy 115.493478 -398.167143)
			(xy 115.487704 -398.159986) (xy 115.46588 -398.134364) (xy 115.427935 -398.078772) (xy 115.396905 -398.019044)
			(xy 115.373236 -397.956036) (xy 115.357267 -397.89065) (xy 115.349226 -397.823825) (xy 92.220595 -397.823825)
			(xy 92.192138 -397.878594) (xy 92.154191 -397.934181) (xy 92.132404 -397.959834) (xy 92.126611 -397.966982)
			(xy 92.120094 -397.98417) (xy 92.119704 -397.993362) (xy 92.119704 -398.486884) (xy 92.120121 -398.49607)
			(xy 92.12663 -398.513255) (xy 92.132404 -398.520412) (xy 92.154226 -398.546036) (xy 92.192171 -398.601627)
			(xy 92.2232 -398.661355) (xy 92.246869 -398.724363) (xy 92.262838 -398.789748) (xy 92.270879 -398.856574)
			(xy 92.270875 -398.923881) (xy 92.262828 -398.990705) (xy 92.246853 -399.056089) (xy 92.223178 -399.119094)
			(xy 92.192143 -399.178819) (xy 92.154193 -399.234407) (xy 92.132404 -399.26006) (xy 92.1266 -399.2672)
			(xy 92.12009 -399.284394) (xy 92.119704 -399.293588) (xy 92.119704 -399.451576) (xy 92.119259 -399.461728)
			(xy 92.111472 -399.480479) (xy 92.097082 -399.494803) (xy 92.078296 -399.502505) (xy 92.068142 -399.502884)
			(xy 91.351862 -399.502884) (xy 91.341736 -399.502405) (xy 91.323018 -399.494669) (xy 91.308664 -399.480381)
			(xy 91.300842 -399.4617) (xy 91.3003 -399.451576) (xy 91.3003 -399.293588) (xy 91.299895 -399.2844)
			(xy 91.293378 -399.267216) (xy 91.2876 -399.26006) (xy 91.265849 -399.234378) (xy 91.227901 -399.178795)
			(xy 91.196869 -399.119075) (xy 91.173196 -399.056075) (xy 91.157221 -398.990697) (xy 91.149175 -398.923878)
			(xy 91.149172 -398.856576) (xy 91.157212 -398.789757) (xy 91.17318 -398.724377) (xy 91.196847 -398.661374)
			(xy 91.227874 -398.601651) (xy 91.265816 -398.546065) (xy 91.2876 -398.520412) (xy 91.293416 -398.513281)
			(xy 91.299919 -398.49608) (xy 91.3003 -398.486884) (xy 91.3003 -397.993362) (xy 91.299908 -397.984173)
			(xy 91.293382 -397.966989) (xy 91.2876 -397.959834) (xy 91.265823 -397.934173) (xy 91.227877 -397.878587)
			(xy 91.196845 -397.818864) (xy 91.173174 -397.755861) (xy 91.157201 -397.69048) (xy 91.149157 -397.623659)
			(xy 91.149156 -397.556356) (xy 90.020411 -397.556356) (xy 90.022992 -397.561322) (xy 90.046667 -397.624323)
			(xy 90.062643 -397.689701) (xy 90.07069 -397.75652) (xy 90.070693 -397.823822) (xy 90.062653 -397.890643)
			(xy 90.046684 -397.956023) (xy 90.023015 -398.019026) (xy 89.991986 -398.078748) (xy 89.954041 -398.134334)
			(xy 89.932256 -398.159986) (xy 89.926435 -398.167114) (xy 89.919936 -398.184318) (xy 89.919556 -398.193514)
			(xy 89.919556 -398.351502) (xy 89.919138 -398.361674) (xy 89.911351 -398.38047) (xy 89.896964 -398.394855)
			(xy 89.878167 -398.402639) (xy 89.867994 -398.403064) (xy 89.151714 -398.403064) (xy 89.141544 -398.402625)
			(xy 89.122749 -398.394845) (xy 89.108364 -398.380464) (xy 89.100578 -398.361672) (xy 89.100152 -398.351502)
			(xy 89.100152 -398.193514) (xy 89.099724 -398.184329) (xy 89.093221 -398.167145) (xy 89.087452 -398.159986)
			(xy 89.065626 -398.134365) (xy 89.027678 -398.078774) (xy 88.996645 -398.019047) (xy 88.972974 -397.956038)
			(xy 88.957004 -397.890652) (xy 88.948962 -397.823826) (xy 87.820827 -397.823826) (xy 87.792062 -397.879042)
			(xy 87.753972 -397.934677) (xy 87.732108 -397.960342) (xy 87.726312 -397.967488) (xy 87.719797 -397.984678)
			(xy 87.719408 -397.99387) (xy 87.719408 -398.486376) (xy 87.719828 -398.495562) (xy 87.726335 -398.512747)
			(xy 87.732108 -398.519904) (xy 87.754007 -398.54554) (xy 87.792094 -398.601179) (xy 87.823243 -398.660979)
			(xy 87.847005 -398.72408) (xy 87.863037 -398.789573) (xy 87.87111 -398.856514) (xy 87.871107 -398.92394)
			(xy 87.863028 -398.990881) (xy 87.846989 -399.056372) (xy 87.823221 -399.11947) (xy 87.792066 -399.179267)
			(xy 87.753974 -399.234903) (xy 87.732108 -399.260568) (xy 87.726301 -399.267706) (xy 87.719792 -399.284902)
			(xy 87.719408 -399.294096) (xy 87.719408 -399.451576) (xy 87.718965 -399.461696) (xy 87.711226 -399.480398)
			(xy 87.696918 -399.494712) (xy 87.67822 -399.50246) (xy 87.6681 -399.502884) (xy 86.95182 -399.502884)
			(xy 86.941697 -399.502467) (xy 86.922991 -399.494723) (xy 86.908675 -399.480406) (xy 86.900932 -399.461699)
			(xy 86.900512 -399.451576) (xy 86.900512 -399.294096) (xy 86.900101 -399.284909) (xy 86.893587 -399.267725)
			(xy 86.887812 -399.260568) (xy 86.865983 -399.234874) (xy 86.827892 -399.179244) (xy 86.796739 -399.119452)
			(xy 86.772973 -399.056358) (xy 86.756934 -398.990873) (xy 86.748855 -398.923938) (xy 86.748852 -398.856516)
			(xy 86.756925 -398.78958) (xy 86.772957 -398.724093) (xy 86.796717 -398.660998) (xy 86.827865 -398.601203)
			(xy 86.86595 -398.545569) (xy 86.887812 -398.519904) (xy 86.893591 -398.512746) (xy 86.900116 -398.495565)
			(xy 86.900512 -398.486376) (xy 86.900512 -397.99387) (xy 86.900114 -397.984682) (xy 86.893592 -397.967497)
			(xy 86.887812 -397.960342) (xy 86.865957 -397.934669) (xy 86.827868 -397.879036) (xy 86.796716 -397.819241)
			(xy 86.772951 -397.756145) (xy 86.756914 -397.690657) (xy 86.748837 -397.623719) (xy 86.748836 -397.556296)
			(xy 85.620612 -397.556296) (xy 85.623035 -397.560946) (xy 85.646803 -397.624039) (xy 85.662842 -397.689525)
			(xy 85.670922 -397.756461) (xy 85.670925 -397.823882) (xy 85.662853 -397.890819) (xy 85.64682 -397.956306)
			(xy 85.623058 -398.019402) (xy 85.59191 -398.079196) (xy 85.553823 -398.134829) (xy 85.53196 -398.160494)
			(xy 85.526178 -398.16765) (xy 85.519656 -398.184832) (xy 85.51926 -398.194022) (xy 85.51926 -398.351502)
			(xy 85.518775 -398.361629) (xy 85.511047 -398.38035) (xy 85.49676 -398.394706) (xy 85.478076 -398.402525)
			(xy 85.467952 -398.403064) (xy 84.751672 -398.403064) (xy 84.741512 -398.402701) (xy 84.722752 -398.394889)
			(xy 84.708428 -398.380474) (xy 84.700736 -398.361665) (xy 84.700364 -398.351502) (xy 84.700364 -398.194022)
			(xy 84.699929 -398.184838) (xy 84.693431 -398.167654) (xy 84.687664 -398.160494) (xy 84.665764 -398.134859)
			(xy 84.627679 -398.079219) (xy 84.596532 -398.019419) (xy 84.572771 -397.956318) (xy 84.55674 -397.890825)
			(xy 84.548667 -397.823884) (xy 83.420495 -397.823884) (xy 83.392062 -397.878597) (xy 83.35411 -397.934182)
			(xy 83.33232 -397.959834) (xy 83.326529 -397.966983) (xy 83.32001 -397.984171) (xy 83.31962 -397.993362)
			(xy 83.31962 -398.486884) (xy 83.320033 -398.496071) (xy 83.326544 -398.513256) (xy 83.33232 -398.520412)
			(xy 83.354144 -398.546035) (xy 83.392095 -398.601624) (xy 83.423129 -398.661352) (xy 83.446801 -398.72436)
			(xy 83.462773 -398.789746) (xy 83.470815 -398.856573) (xy 83.470812 -398.923881) (xy 83.462763 -398.990707)
			(xy 83.446785 -399.056092) (xy 83.423107 -399.119098) (xy 83.392067 -399.178822) (xy 83.354111 -399.234408)
			(xy 83.33232 -399.26006) (xy 83.326518 -399.267201) (xy 83.320006 -399.284395) (xy 83.31962 -399.293588)
			(xy 83.31962 -399.451576) (xy 83.319159 -399.461726) (xy 83.311375 -399.480474) (xy 83.296991 -399.494798)
			(xy 83.27821 -399.502502) (xy 83.268058 -399.502884) (xy 82.551778 -399.502884) (xy 82.541653 -399.502392)
			(xy 82.522936 -399.494662) (xy 82.508581 -399.480378) (xy 82.500758 -399.461699) (xy 82.500216 -399.451576)
			(xy 82.500216 -399.293588) (xy 82.499808 -399.284401) (xy 82.493293 -399.267216) (xy 82.487516 -399.26006)
			(xy 82.465765 -399.234378) (xy 82.427816 -399.178795) (xy 82.396783 -399.119076) (xy 82.373109 -399.056075)
			(xy 82.357134 -398.990697) (xy 82.349088 -398.923878) (xy 82.349084 -398.856576) (xy 82.357125 -398.789756)
			(xy 82.373093 -398.724377) (xy 82.396761 -398.661374) (xy 82.427788 -398.601651) (xy 82.465731 -398.546065)
			(xy 82.487516 -398.520412) (xy 82.493334 -398.513282) (xy 82.499835 -398.49608) (xy 82.500216 -398.486884)
			(xy 82.500216 -397.993362) (xy 82.499821 -397.984173) (xy 82.493296 -397.966989) (xy 82.487516 -397.959834)
			(xy 82.465739 -397.934174) (xy 82.427791 -397.878588) (xy 82.396759 -397.818865) (xy 82.373086 -397.755862)
			(xy 82.357113 -397.690481) (xy 82.349069 -397.623659) (xy 82.349068 -397.556356) (xy 81.220853 -397.556356)
			(xy 81.223245 -397.560947) (xy 81.247013 -397.62404) (xy 81.263052 -397.689525) (xy 81.271131 -397.756461)
			(xy 81.271135 -397.823882) (xy 81.263062 -397.890818) (xy 81.24703 -397.956306) (xy 81.223269 -398.019401)
			(xy 81.192121 -398.079196) (xy 81.154035 -398.134829) (xy 81.132172 -398.160494) (xy 81.126392 -398.167651)
			(xy 81.119868 -398.184832) (xy 81.119472 -398.194022) (xy 81.119472 -398.351502) (xy 81.118975 -398.361627)
			(xy 81.111249 -398.380346) (xy 81.096966 -398.394702) (xy 81.078287 -398.402523) (xy 81.068164 -398.403064)
			(xy 80.351884 -398.403064) (xy 80.341724 -398.402691) (xy 80.322965 -398.394883) (xy 80.30864 -398.380471)
			(xy 80.300948 -398.361664) (xy 80.300576 -398.351502) (xy 80.300576 -398.194022) (xy 80.300161 -398.184835)
			(xy 80.293651 -398.16765) (xy 80.287876 -398.160494) (xy 80.265976 -398.134859) (xy 80.22789 -398.07922)
			(xy 80.196742 -398.019419) (xy 80.172981 -397.956318) (xy 80.156949 -397.890826) (xy 80.148876 -397.823885)
			(xy 79.02071 -397.823885) (xy 78.991976 -397.879041) (xy 78.953888 -397.934676) (xy 78.932024 -397.960342)
			(xy 78.92623 -397.967489) (xy 78.919713 -397.984678) (xy 78.919324 -397.99387) (xy 78.919324 -398.486376)
			(xy 78.91974 -398.495563) (xy 78.926249 -398.512747) (xy 78.932024 -398.519904) (xy 78.953922 -398.54554)
			(xy 78.992009 -398.60118) (xy 79.023156 -398.66098) (xy 79.046917 -398.724081) (xy 79.06295 -398.789573)
			(xy 79.071022 -398.856514) (xy 79.071019 -398.92394) (xy 79.06294 -398.99088) (xy 79.046901 -399.056371)
			(xy 79.023134 -399.119469) (xy 78.991981 -399.179267) (xy 78.953889 -399.234902) (xy 78.932024 -399.260568)
			(xy 78.926219 -399.267707) (xy 78.919709 -399.284902) (xy 78.919324 -399.294096) (xy 78.919324 -399.451576)
			(xy 78.918865 -399.461694) (xy 78.911129 -399.480393) (xy 78.896826 -399.494707) (xy 78.878134 -399.502457)
			(xy 78.868016 -399.502884) (xy 78.151736 -399.502884) (xy 78.141614 -399.502454) (xy 78.122908 -399.494715)
			(xy 78.108592 -399.480402) (xy 78.100848 -399.461698) (xy 78.100428 -399.451576) (xy 78.100428 -399.294096)
			(xy 78.100014 -399.284909) (xy 78.093502 -399.267725) (xy 78.087728 -399.260568) (xy 78.065898 -399.234874)
			(xy 78.027807 -399.179244) (xy 77.996653 -399.119452) (xy 77.972886 -399.056359) (xy 77.956847 -398.990873)
			(xy 77.948768 -398.923938) (xy 77.948764 -398.856516) (xy 77.956837 -398.78958) (xy 77.972869 -398.724093)
			(xy 77.996631 -398.660997) (xy 78.027779 -398.601202) (xy 78.065865 -398.545569) (xy 78.087728 -398.519904)
			(xy 78.093509 -398.512748) (xy 78.100032 -398.495566) (xy 78.100428 -398.486376) (xy 78.100428 -397.99387)
			(xy 78.100026 -397.984682) (xy 78.093506 -397.967498) (xy 78.087728 -397.960342) (xy 78.065873 -397.934669)
			(xy 78.027782 -397.879036) (xy 77.996629 -397.819241) (xy 77.972863 -397.756146) (xy 77.956826 -397.690657)
			(xy 77.948749 -397.623719) (xy 77.948748 -397.556296) (xy 76.820503 -397.556296) (xy 76.823115 -397.561323)
			(xy 76.846789 -397.624324) (xy 76.862764 -397.689702) (xy 76.870811 -397.756521) (xy 76.870814 -397.823822)
			(xy 76.862774 -397.890642) (xy 76.846806 -397.956022) (xy 76.823139 -398.019024) (xy 76.792111 -398.078747)
			(xy 76.754168 -398.134333) (xy 76.732384 -398.159986) (xy 76.726567 -398.167116) (xy 76.720065 -398.184318)
			(xy 76.719684 -398.193514) (xy 76.719684 -398.351502) (xy 76.719169 -398.361657) (xy 76.711398 -398.380422)
			(xy 76.697039 -398.394787) (xy 76.678277 -398.402565) (xy 76.668122 -398.403064) (xy 75.951842 -398.403064)
			(xy 75.941673 -398.402602) (xy 75.92288 -398.394831) (xy 75.908494 -398.380457) (xy 75.900707 -398.36167)
			(xy 75.90028 -398.351502) (xy 75.90028 -398.193514) (xy 75.899868 -398.184327) (xy 75.893356 -398.167142)
			(xy 75.88758 -398.159986) (xy 75.865754 -398.134365) (xy 75.827803 -398.078775) (xy 75.79677 -398.019048)
			(xy 75.773097 -397.956039) (xy 75.757126 -397.890653) (xy 75.749084 -397.823826) (xy 74.620438 -397.823826)
			(xy 74.591977 -397.878596) (xy 74.554025 -397.934182) (xy 74.532236 -397.959834) (xy 74.526435 -397.966975)
			(xy 74.519925 -397.984169) (xy 74.519536 -397.993362) (xy 74.519536 -398.486884) (xy 74.519968 -398.496069)
			(xy 74.526468 -398.513252) (xy 74.532236 -398.520412) (xy 74.55406 -398.546035) (xy 74.592009 -398.601625)
			(xy 74.623043 -398.661352) (xy 74.646714 -398.724361) (xy 74.662686 -398.789747) (xy 74.670727 -398.856573)
			(xy 74.670724 -398.923881) (xy 74.662676 -398.990707) (xy 74.646698 -399.056091) (xy 74.623021 -399.119097)
			(xy 74.591982 -399.178822) (xy 74.554027 -399.234408) (xy 74.532236 -399.26006) (xy 74.526424 -399.267194)
			(xy 74.51992 -399.284393) (xy 74.519536 -399.293588) (xy 74.519536 -399.451576) (xy 74.51906 -399.461724)
			(xy 74.511279 -399.480469) (xy 74.496899 -399.494792) (xy 74.478124 -399.502499) (xy 74.467974 -399.502884)
			(xy 73.751694 -399.502884) (xy 73.74157 -399.502379) (xy 73.722853 -399.494654) (xy 73.708498 -399.480373)
			(xy 73.700675 -399.461697) (xy 73.700132 -399.451576) (xy 73.700132 -399.293588) (xy 73.699721 -399.284401)
			(xy 73.693207 -399.267217) (xy 73.687432 -399.26006) (xy 73.66568 -399.234378) (xy 73.627731 -399.178796)
			(xy 73.596696 -399.119077) (xy 73.573022 -399.056076) (xy 73.557047 -398.990697) (xy 73.549 -398.923878)
			(xy 73.548996 -398.856576) (xy 73.557037 -398.789756) (xy 73.573006 -398.724376) (xy 73.596674 -398.661373)
			(xy 73.627703 -398.60165) (xy 73.665647 -398.546064) (xy 73.687432 -398.520412) (xy 73.693253 -398.513284)
			(xy 73.699752 -398.49608) (xy 73.700132 -398.486884) (xy 73.700132 -397.993362) (xy 73.699733 -397.984174)
			(xy 73.693211 -397.96699) (xy 73.687432 -397.959834) (xy 73.665654 -397.934174) (xy 73.627705 -397.878588)
			(xy 73.596672 -397.818866) (xy 73.572999 -397.755862) (xy 73.557026 -397.690481) (xy 73.548981 -397.62366)
			(xy 73.54898 -397.556355) (xy 72.420766 -397.556355) (xy 72.423159 -397.560948) (xy 72.446926 -397.62404)
			(xy 72.462964 -397.689526) (xy 72.471043 -397.756461) (xy 72.471047 -397.823882) (xy 72.462974 -397.890818)
			(xy 72.446942 -397.956305) (xy 72.423182 -398.0194) (xy 72.392035 -398.079195) (xy 72.35395 -398.134829)
			(xy 72.332088 -398.160494) (xy 72.32631 -398.167652) (xy 72.319785 -398.184833) (xy 72.319388 -398.194022)
			(xy 72.319388 -398.351502) (xy 72.318876 -398.361625) (xy 72.311153 -398.380341) (xy 72.296875 -398.394696)
			(xy 72.278201 -398.40252) (xy 72.26808 -398.403064) (xy 71.5518 -398.403064) (xy 71.541641 -398.402678)
			(xy 71.522882 -398.394875) (xy 71.508557 -398.380467) (xy 71.500864 -398.361663) (xy 71.500492 -398.351502)
			(xy 71.500492 -398.194022) (xy 71.500073 -398.184836) (xy 71.493566 -398.167651) (xy 71.487792 -398.160494)
			(xy 71.465891 -398.134859) (xy 71.427804 -398.07922) (xy 71.396655 -398.01942) (xy 71.372894 -397.956319)
			(xy 71.356861 -397.890826) (xy 71.348788 -397.823885) (xy 66.525648 -397.823885) (xy 66.525648 -401.723796)
			(xy 71.3488 -401.723796) (xy 71.348802 -401.656371) (xy 71.35688 -401.589431) (xy 71.372917 -401.523941)
			(xy 71.396683 -401.460843) (xy 71.427836 -401.401046) (xy 71.465927 -401.345411) (xy 71.487792 -401.319746)
			(xy 71.493593 -401.312604) (xy 71.500105 -401.295411) (xy 71.500492 -401.286218) (xy 71.500492 -400.793966)
			(xy 71.5001 -400.784777) (xy 71.493574 -400.767592) (xy 71.487792 -400.760438) (xy 71.465934 -400.734768)
			(xy 71.427846 -400.679134) (xy 71.396695 -400.619338) (xy 71.372931 -400.556242) (xy 71.356896 -400.490754)
			(xy 71.348819 -400.423816) (xy 71.348819 -400.356393) (xy 71.356894 -400.289455) (xy 71.372928 -400.223967)
			(xy 71.396692 -400.16087) (xy 71.427841 -400.101074) (xy 71.465929 -400.045439) (xy 71.487792 -400.019774)
			(xy 71.493581 -400.012623) (xy 71.500101 -399.995437) (xy 71.500492 -399.986246) (xy 71.500492 -399.828766)
			(xy 71.500997 -399.818643) (xy 71.508727 -399.79993) (xy 71.523007 -399.785577) (xy 71.54168 -399.77775)
			(xy 71.5518 -399.777204) (xy 72.26808 -399.777204) (xy 72.278233 -399.777638) (xy 72.296986 -399.785428)
			(xy 72.31131 -399.799821) (xy 72.31901 -399.818611) (xy 72.319388 -399.828766) (xy 72.319388 -399.986246)
			(xy 72.319827 -399.99543) (xy 72.326321 -400.012615) (xy 72.332088 -400.019774) (xy 72.353958 -400.045434)
			(xy 72.392048 -400.101069) (xy 72.423199 -400.160866) (xy 72.446963 -400.223963) (xy 72.462999 -400.289453)
			(xy 72.471074 -400.356392) (xy 72.471074 -400.423817) (xy 72.462997 -400.490756) (xy 72.44696 -400.556245)
			(xy 72.423195 -400.619342) (xy 72.392043 -400.679139) (xy 72.353953 -400.734773) (xy 72.332088 -400.760438)
			(xy 72.326291 -400.767583) (xy 72.319777 -400.784774) (xy 72.319388 -400.793966) (xy 72.319388 -401.286218)
			(xy 72.319792 -401.295406) (xy 72.32631 -401.31259) (xy 72.332088 -401.319746) (xy 72.353931 -401.345429)
			(xy 72.392021 -401.401061) (xy 72.423173 -401.460854) (xy 72.446939 -401.523949) (xy 72.462977 -401.589436)
			(xy 72.471054 -401.656372) (xy 72.471056 -401.723795) (xy 72.462982 -401.790732) (xy 72.446949 -401.85622)
			(xy 72.423187 -401.919316) (xy 72.392038 -401.979111) (xy 72.353951 -402.034745) (xy 72.332088 -402.06041)
			(xy 72.326303 -402.067564) (xy 72.319782 -402.084748) (xy 72.319388 -402.093938) (xy 72.319388 -402.251418)
			(xy 72.318889 -402.261542) (xy 72.311161 -402.280259) (xy 72.296879 -402.294614) (xy 72.278202 -402.302437)
			(xy 72.26808 -402.30298) (xy 71.5518 -402.30298) (xy 71.541643 -402.302578) (xy 71.522887 -402.294779)
			(xy 71.508563 -402.280376) (xy 71.500867 -402.261577) (xy 71.500492 -402.251418) (xy 71.500492 -402.093938)
			(xy 71.500065 -402.084753) (xy 71.493563 -402.067568) (xy 71.487792 -402.06041) (xy 71.465907 -402.034762)
			(xy 71.427819 -401.979125) (xy 71.39667 -401.919326) (xy 71.372907 -401.856227) (xy 71.356874 -401.790736)
			(xy 71.3488 -401.723796) (xy 66.525648 -401.723796) (xy 66.525648 -402.823818) (xy 73.54894 -402.823818)
			(xy 73.548944 -402.75651) (xy 73.556993 -402.689684) (xy 73.572971 -402.624299) (xy 73.596649 -402.561293)
			(xy 73.627687 -402.501568) (xy 73.665642 -402.44598) (xy 73.687432 -402.420328) (xy 73.693246 -402.413195)
			(xy 73.699749 -402.395995) (xy 73.700132 -402.3868) (xy 73.700132 -401.893532) (xy 73.699699 -401.884347)
			(xy 73.6932 -401.867163) (xy 73.687432 -401.860004) (xy 73.665625 -401.834368) (xy 73.627677 -401.778779)
			(xy 73.596645 -401.719053) (xy 73.572974 -401.656047) (xy 73.557002 -401.590662) (xy 73.54896 -401.523838)
			(xy 73.548962 -401.456532) (xy 73.557008 -401.389708) (xy 73.572982 -401.324325) (xy 73.596657 -401.261319)
			(xy 73.627692 -401.201595) (xy 73.665643 -401.146008) (xy 73.687432 -401.120356) (xy 73.693234 -401.113215)
			(xy 73.699745 -401.096021) (xy 73.700132 -401.086828) (xy 73.700132 -400.92884) (xy 73.700555 -400.918685)
			(xy 73.708343 -400.899927) (xy 73.722741 -400.885601) (xy 73.741537 -400.877906) (xy 73.751694 -400.877532)
			(xy 74.467974 -400.877532) (xy 74.478098 -400.878047) (xy 74.496817 -400.885765) (xy 74.511174 -400.900043)
			(xy 74.518996 -400.918719) (xy 74.519536 -400.92884) (xy 74.519536 -401.086828) (xy 74.519947 -401.096015)
			(xy 74.526462 -401.113198) (xy 74.532236 -401.120356) (xy 74.554005 -401.146024) (xy 74.591956 -401.201608)
			(xy 74.622991 -401.261329) (xy 74.646666 -401.324331) (xy 74.662641 -401.389712) (xy 74.670687 -401.456533)
			(xy 74.670689 -401.523837) (xy 74.662647 -401.590659) (xy 74.646675 -401.65604) (xy 74.623004 -401.719044)
			(xy 74.620565 -401.723737) (xy 75.749095 -401.723737) (xy 75.749097 -401.65643) (xy 75.757144 -401.589605)
			(xy 75.773121 -401.524221) (xy 75.796798 -401.461215) (xy 75.827836 -401.401492) (xy 75.86579 -401.345906)
			(xy 75.88758 -401.320254) (xy 75.893376 -401.313108) (xy 75.899892 -401.295918) (xy 75.90028 -401.286726)
			(xy 75.90028 -400.793458) (xy 75.899895 -400.784268) (xy 75.893364 -400.767084) (xy 75.88758 -400.75993)
			(xy 75.865797 -400.734274) (xy 75.827845 -400.678689) (xy 75.79681 -400.618966) (xy 75.773135 -400.555962)
			(xy 75.75716 -400.49058) (xy 75.749115 -400.423757) (xy 75.749114 -400.356452) (xy 75.757158 -400.289629)
			(xy 75.773132 -400.224247) (xy 75.796806 -400.161242) (xy 75.827841 -400.101519) (xy 75.865791 -400.045934)
			(xy 75.88758 -400.020282) (xy 75.893364 -400.013128) (xy 75.899887 -399.995944) (xy 75.90028 -399.986754)
			(xy 75.90028 -399.828766) (xy 75.900637 -399.818587) (xy 75.908441 -399.799783) (xy 75.922847 -399.785398)
			(xy 75.941662 -399.777622) (xy 75.951842 -399.777204) (xy 76.668122 -399.777204) (xy 76.678277 -399.777714)
			(xy 76.69704 -399.78549) (xy 76.711404 -399.79985) (xy 76.719183 -399.818611) (xy 76.719684 -399.828766)
			(xy 76.719684 -399.986754) (xy 76.72012 -399.995938) (xy 76.726616 -400.013123) (xy 76.732384 -400.020282)
			(xy 76.754177 -400.04593) (xy 76.792124 -400.101517) (xy 76.823156 -400.161242) (xy 76.846827 -400.224247)
			(xy 76.862799 -400.289629) (xy 76.870842 -400.356452) (xy 76.870842 -400.423757) (xy 76.862798 -400.49058)
			(xy 76.846825 -400.555962) (xy 76.823152 -400.618967) (xy 76.792119 -400.678691) (xy 76.754171 -400.734278)
			(xy 76.732384 -400.75993) (xy 76.72659 -400.767077) (xy 76.720074 -400.784266) (xy 76.719684 -400.793458)
			(xy 76.719684 -401.286726) (xy 76.720085 -401.295914) (xy 76.726605 -401.313098) (xy 76.732384 -401.320254)
			(xy 76.754149 -401.345924) (xy 76.792097 -401.401509) (xy 76.82313 -401.46123) (xy 76.846803 -401.524232)
			(xy 76.862777 -401.589612) (xy 76.870823 -401.656432) (xy 76.870825 -401.723735) (xy 76.862783 -401.790556)
			(xy 76.846813 -401.855936) (xy 76.823144 -401.91894) (xy 76.792114 -401.978663) (xy 76.75417 -402.03425)
			(xy 76.732384 -402.059902) (xy 76.726602 -402.067058) (xy 76.720079 -402.08424) (xy 76.719684 -402.09343)
			(xy 76.719684 -402.251418) (xy 76.719182 -402.261574) (xy 76.711406 -402.28034) (xy 76.697043 -402.294704)
			(xy 76.678278 -402.302481) (xy 76.668122 -402.30298) (xy 75.951842 -402.30298) (xy 75.941675 -402.302502)
			(xy 75.922885 -402.294734) (xy 75.908499 -402.280365) (xy 75.90071 -402.261584) (xy 75.90028 -402.251418)
			(xy 75.90028 -402.09343) (xy 75.89986 -402.084244) (xy 75.893354 -402.067059) (xy 75.88758 -402.059902)
			(xy 75.865769 -402.034268) (xy 75.827819 -401.97868) (xy 75.796784 -401.918954) (xy 75.773111 -401.855947)
			(xy 75.757138 -401.790562) (xy 75.749095 -401.723737) (xy 74.620565 -401.723737) (xy 74.591971 -401.778767)
			(xy 74.554023 -401.834352) (xy 74.532236 -401.860004) (xy 74.526447 -401.867155) (xy 74.51993 -401.884341)
			(xy 74.519536 -401.893532) (xy 74.519536 -402.3868) (xy 74.519961 -402.395985) (xy 74.526466 -402.413169)
			(xy 74.532236 -402.420328) (xy 74.553977 -402.446019) (xy 74.591929 -402.501599) (xy 74.622966 -402.561317)
			(xy 74.646642 -402.624317) (xy 74.662619 -402.689694) (xy 74.670668 -402.756513) (xy 74.670672 -402.823815)
			(xy 74.670664 -402.823878) (xy 77.948708 -402.823878) (xy 77.948713 -402.75645) (xy 77.956794 -402.689508)
			(xy 77.972835 -402.624016) (xy 77.996606 -402.560917) (xy 78.027764 -402.501119) (xy 78.06586 -402.445485)
			(xy 78.087728 -402.41982) (xy 78.093545 -402.412689) (xy 78.100047 -402.395488) (xy 78.100428 -402.386292)
			(xy 78.100428 -401.89404) (xy 78.099992 -401.884856) (xy 78.093496 -401.867671) (xy 78.087728 -401.860512)
			(xy 78.065843 -401.834863) (xy 78.027753 -401.779227) (xy 77.996602 -401.719429) (xy 77.972838 -401.65633)
			(xy 77.956803 -401.590838) (xy 77.948728 -401.523898) (xy 77.94873 -401.456472) (xy 77.956808 -401.389532)
			(xy 77.972847 -401.324041) (xy 77.996614 -401.260944) (xy 78.027769 -401.201147) (xy 78.065862 -401.145513)
			(xy 78.087728 -401.119848) (xy 78.093533 -401.112709) (xy 78.100042 -401.095514) (xy 78.100428 -401.08632)
			(xy 78.100428 -400.92884) (xy 78.10085 -400.918717) (xy 78.10859 -400.900009) (xy 78.122905 -400.885692)
			(xy 78.141613 -400.87795) (xy 78.151736 -400.877532) (xy 78.868016 -400.877532) (xy 78.878144 -400.877903)
			(xy 78.896854 -400.885663) (xy 78.911169 -400.899993) (xy 78.918908 -400.918712) (xy 78.919324 -400.92884)
			(xy 78.919324 -401.08632) (xy 78.919719 -401.095509) (xy 78.926243 -401.112693) (xy 78.932024 -401.119848)
			(xy 78.953867 -401.14553) (xy 78.991955 -401.201163) (xy 79.023105 -401.260957) (xy 79.04687 -401.324051)
			(xy 79.062906 -401.389538) (xy 79.070983 -401.456474) (xy 79.070985 -401.523896) (xy 79.062911 -401.590832)
			(xy 79.046879 -401.65632) (xy 79.023118 -401.719416) (xy 79.020837 -401.723796) (xy 80.148888 -401.723796)
			(xy 80.14889 -401.656371) (xy 80.156967 -401.589432) (xy 80.173004 -401.523942) (xy 80.19677 -401.460844)
			(xy 80.227922 -401.401047) (xy 80.266012 -401.345412) (xy 80.287876 -401.319746) (xy 80.293675 -401.312603)
			(xy 80.300189 -401.295411) (xy 80.300576 -401.286218) (xy 80.300576 -400.793966) (xy 80.300187 -400.784776)
			(xy 80.293659 -400.767592) (xy 80.287876 -400.760438) (xy 80.266019 -400.734767) (xy 80.227931 -400.679133)
			(xy 80.196782 -400.619337) (xy 80.173018 -400.556241) (xy 80.156983 -400.490753) (xy 80.148907 -400.423816)
			(xy 80.148907 -400.356393) (xy 80.156982 -400.289456) (xy 80.173016 -400.223967) (xy 80.196778 -400.160871)
			(xy 80.227927 -400.101075) (xy 80.266013 -400.04544) (xy 80.287876 -400.019774) (xy 80.293663 -400.012622)
			(xy 80.300184 -399.995437) (xy 80.300576 -399.986246) (xy 80.300576 -399.828766) (xy 80.301 -399.818633)
			(xy 80.308745 -399.799904) (xy 80.323051 -399.785548) (xy 80.341753 -399.777736) (xy 80.351884 -399.777204)
			(xy 81.068164 -399.777204) (xy 81.078316 -399.777651) (xy 81.097069 -399.785436) (xy 81.111393 -399.799825)
			(xy 81.119094 -399.818612) (xy 81.119472 -399.828766) (xy 81.119472 -399.986246) (xy 81.119914 -399.99543)
			(xy 81.126406 -400.012614) (xy 81.132172 -400.019774) (xy 81.154043 -400.045434) (xy 81.192133 -400.101069)
			(xy 81.223285 -400.160865) (xy 81.24705 -400.223963) (xy 81.263086 -400.289453) (xy 81.271162 -400.356392)
			(xy 81.271161 -400.423817) (xy 81.263085 -400.490756) (xy 81.247048 -400.556246) (xy 81.223282 -400.619343)
			(xy 81.192129 -400.679139) (xy 81.154037 -400.734773) (xy 81.132172 -400.760438) (xy 81.126373 -400.767581)
			(xy 81.11986 -400.784773) (xy 81.119472 -400.793966) (xy 81.119472 -401.286218) (xy 81.11988 -401.295405)
			(xy 81.126396 -401.312589) (xy 81.132172 -401.319746) (xy 81.154015 -401.345429) (xy 81.192107 -401.40106)
			(xy 81.22326 -401.460854) (xy 81.247026 -401.523948) (xy 81.263064 -401.589435) (xy 81.271142 -401.656372)
			(xy 81.271144 -401.723795) (xy 81.26307 -401.790732) (xy 81.247036 -401.85622) (xy 81.223273 -401.919316)
			(xy 81.192124 -401.979112) (xy 81.154036 -402.034745) (xy 81.132172 -402.06041) (xy 81.126385 -402.067562)
			(xy 81.119865 -402.084747) (xy 81.119472 -402.093938) (xy 81.119472 -402.251418) (xy 81.118989 -402.261544)
			(xy 81.111257 -402.280264) (xy 81.09697 -402.294619) (xy 81.078288 -402.30244) (xy 81.068164 -402.30298)
			(xy 80.351884 -402.30298) (xy 80.341726 -402.302591) (xy 80.32297 -402.294787) (xy 80.308646 -402.28038)
			(xy 80.30095 -402.261578) (xy 80.300576 -402.251418) (xy 80.300576 -402.093938) (xy 80.300153 -402.084752)
			(xy 80.293649 -402.067567) (xy 80.287876 -402.06041) (xy 80.265991 -402.034762) (xy 80.227905 -401.979125)
			(xy 80.196756 -401.919326) (xy 80.172994 -401.856227) (xy 80.156961 -401.790736) (xy 80.148888 -401.723796)
			(xy 79.020837 -401.723796) (xy 78.991971 -401.779212) (xy 78.953886 -401.834846) (xy 78.932024 -401.860512)
			(xy 78.926243 -401.867668) (xy 78.919718 -401.88485) (xy 78.919324 -401.89404) (xy 78.919324 -402.386292)
			(xy 78.919733 -402.395479) (xy 78.926247 -402.412664) (xy 78.932024 -402.41982) (xy 78.95384 -402.445525)
			(xy 78.991929 -402.501154) (xy 79.02308 -402.560945) (xy 79.046846 -402.624037) (xy 79.062884 -402.689521)
			(xy 79.070963 -402.756454) (xy 79.070968 -402.823818) (xy 82.349028 -402.823818) (xy 82.349032 -402.75651)
			(xy 82.357081 -402.689684) (xy 82.373058 -402.6243) (xy 82.396735 -402.561293) (xy 82.427773 -402.501568)
			(xy 82.465726 -402.44598) (xy 82.487516 -402.420328) (xy 82.493327 -402.413193) (xy 82.499833 -402.395995)
			(xy 82.500216 -402.3868) (xy 82.500216 -401.893532) (xy 82.499787 -401.884347) (xy 82.493286 -401.867163)
			(xy 82.487516 -401.860004) (xy 82.465709 -401.834368) (xy 82.427763 -401.778778) (xy 82.396731 -401.719052)
			(xy 82.373061 -401.656046) (xy 82.35709 -401.590662) (xy 82.349048 -401.523838) (xy 82.34905 -401.456532)
			(xy 82.357095 -401.389708) (xy 82.37307 -401.324325) (xy 82.396744 -401.26132) (xy 82.427778 -401.201596)
			(xy 82.465728 -401.146008) (xy 82.487516 -401.120356) (xy 82.493316 -401.113213) (xy 82.499828 -401.096021)
			(xy 82.500216 -401.086828) (xy 82.500216 -400.92884) (xy 82.500655 -400.918687) (xy 82.50844 -400.899932)
			(xy 82.522832 -400.885607) (xy 82.541623 -400.877908) (xy 82.551778 -400.877532) (xy 83.268058 -400.877532)
			(xy 83.278181 -400.878061) (xy 83.2969 -400.885773) (xy 83.311257 -400.900047) (xy 83.319079 -400.91872)
			(xy 83.31962 -400.92884) (xy 83.31962 -401.086828) (xy 83.320012 -401.096017) (xy 83.326538 -401.113202)
			(xy 83.33232 -401.120356) (xy 83.354089 -401.146024) (xy 83.392041 -401.201607) (xy 83.423078 -401.261328)
			(xy 83.446753 -401.324331) (xy 83.462729 -401.389711) (xy 83.470775 -401.456533) (xy 83.470777 -401.523837)
			(xy 83.462734 -401.590659) (xy 83.446762 -401.656041) (xy 83.42309 -401.719044) (xy 83.420621 -401.723796)
			(xy 84.548678 -401.723796) (xy 84.54868 -401.656371) (xy 84.556758 -401.589432) (xy 84.572795 -401.523942)
			(xy 84.59656 -401.460845) (xy 84.627711 -401.401047) (xy 84.6658 -401.345412) (xy 84.687664 -401.319746)
			(xy 84.693474 -401.312611) (xy 84.699979 -401.295412) (xy 84.700364 -401.286218) (xy 84.700364 -400.793966)
			(xy 84.699956 -400.784779) (xy 84.693439 -400.767595) (xy 84.687664 -400.760438) (xy 84.665807 -400.734767)
			(xy 84.627721 -400.679133) (xy 84.596572 -400.619337) (xy 84.572809 -400.556241) (xy 84.556774 -400.490753)
			(xy 84.548698 -400.423816) (xy 84.548698 -400.356393) (xy 84.556772 -400.289456) (xy 84.572806 -400.223968)
			(xy 84.596568 -400.160871) (xy 84.627716 -400.101075) (xy 84.665802 -400.04544) (xy 84.687664 -400.019774)
			(xy 84.693462 -400.01263) (xy 84.699974 -399.995438) (xy 84.700364 -399.986246) (xy 84.700364 -399.828766)
			(xy 84.700799 -399.818634) (xy 84.708543 -399.799908) (xy 84.722845 -399.785552) (xy 84.741542 -399.777738)
			(xy 84.751672 -399.777204) (xy 85.467952 -399.777204) (xy 85.478104 -399.777661) (xy 85.496856 -399.785442)
			(xy 85.511181 -399.799828) (xy 85.518881 -399.818613) (xy 85.51926 -399.828766) (xy 85.51926 -399.986246)
			(xy 85.519705 -399.995429) (xy 85.526196 -400.012613) (xy 85.53196 -400.019774) (xy 85.553831 -400.045434)
			(xy 85.591922 -400.101068) (xy 85.623075 -400.160865) (xy 85.646841 -400.223962) (xy 85.662877 -400.289453)
			(xy 85.670953 -400.356392) (xy 85.670952 -400.423817) (xy 85.662875 -400.490756) (xy 85.646838 -400.556246)
			(xy 85.623071 -400.619344) (xy 85.591918 -400.67914) (xy 85.553826 -400.734773) (xy 85.53196 -400.760438)
			(xy 85.52616 -400.76758) (xy 85.519648 -400.784773) (xy 85.51926 -400.793966) (xy 85.51926 -401.286218)
			(xy 85.51967 -401.295405) (xy 85.526185 -401.312589) (xy 85.53196 -401.319746) (xy 85.553804 -401.345428)
			(xy 85.591896 -401.40106) (xy 85.62305 -401.460853) (xy 85.646817 -401.523948) (xy 85.662855 -401.589435)
			(xy 85.670933 -401.656372) (xy 85.670935 -401.723795) (xy 85.662861 -401.790732) (xy 85.646827 -401.856221)
			(xy 85.623063 -401.919317) (xy 85.591913 -401.979112) (xy 85.553824 -402.034745) (xy 85.53196 -402.06041)
			(xy 85.526172 -402.067561) (xy 85.519653 -402.084747) (xy 85.51926 -402.093938) (xy 85.51926 -402.251418)
			(xy 85.518788 -402.261546) (xy 85.511055 -402.280268) (xy 85.496764 -402.294623) (xy 85.478078 -402.302442)
			(xy 85.467952 -402.30298) (xy 84.751672 -402.30298) (xy 84.741514 -402.302601) (xy 84.722757 -402.294792)
			(xy 84.708434 -402.280383) (xy 84.700738 -402.261579) (xy 84.700364 -402.251418) (xy 84.700364 -402.093938)
			(xy 84.699921 -402.084755) (xy 84.693429 -402.067571) (xy 84.687664 -402.06041) (xy 84.66578 -402.034762)
			(xy 84.627694 -401.979124) (xy 84.596546 -401.919325) (xy 84.572785 -401.856226) (xy 84.556752 -401.790735)
			(xy 84.548678 -401.723796) (xy 83.420621 -401.723796) (xy 83.392057 -401.778767) (xy 83.354108 -401.834352)
			(xy 83.33232 -401.860004) (xy 83.326542 -401.867162) (xy 83.320015 -401.884343) (xy 83.31962 -401.893532)
			(xy 83.31962 -402.3868) (xy 83.320026 -402.395988) (xy 83.326542 -402.413172) (xy 83.33232 -402.420328)
			(xy 83.354062 -402.446018) (xy 83.392015 -402.501598) (xy 83.423052 -402.561316) (xy 83.44673 -402.624316)
			(xy 83.462707 -402.689694) (xy 83.470756 -402.756513) (xy 83.47076 -402.823815) (xy 83.470752 -402.823878)
			(xy 86.748796 -402.823878) (xy 86.748801 -402.75645) (xy 86.756882 -402.689508) (xy 86.772922 -402.624016)
			(xy 86.796693 -402.560918) (xy 86.82785 -402.50112) (xy 86.865945 -402.445485) (xy 86.887812 -402.41982)
			(xy 86.893626 -402.412687) (xy 86.90013 -402.395487) (xy 86.900512 -402.386292) (xy 86.900512 -401.89404)
			(xy 86.90008 -401.884855) (xy 86.893581 -401.867671) (xy 86.887812 -401.860512) (xy 86.865928 -401.834863)
			(xy 86.827839 -401.779227) (xy 86.796689 -401.719428) (xy 86.772925 -401.656329) (xy 86.756891 -401.590838)
			(xy 86.748816 -401.523898) (xy 86.748818 -401.456472) (xy 86.756896 -401.389532) (xy 86.772934 -401.324042)
			(xy 86.796701 -401.260944) (xy 86.827855 -401.201148) (xy 86.865946 -401.145513) (xy 86.887812 -401.119848)
			(xy 86.893615 -401.112707) (xy 86.900125 -401.095513) (xy 86.900512 -401.08632) (xy 86.900512 -400.92884)
			(xy 86.900949 -400.918719) (xy 86.908686 -400.900014) (xy 86.922997 -400.885698) (xy 86.941699 -400.877953)
			(xy 86.95182 -400.877532) (xy 87.6681 -400.877532) (xy 87.678226 -400.877917) (xy 87.696936 -400.885671)
			(xy 87.711252 -400.899997) (xy 87.718991 -400.918713) (xy 87.719408 -400.92884) (xy 87.719408 -401.08632)
			(xy 87.719807 -401.095508) (xy 87.726328 -401.112693) (xy 87.732108 -401.119848) (xy 87.753952 -401.14553)
			(xy 87.792041 -401.201162) (xy 87.823192 -401.260956) (xy 87.846957 -401.324051) (xy 87.862994 -401.389538)
			(xy 87.871071 -401.456474) (xy 87.871073 -401.523896) (xy 87.862999 -401.590833) (xy 87.846966 -401.656321)
			(xy 87.823204 -401.719417) (xy 87.820954 -401.723737) (xy 115.349237 -401.723737) (xy 115.349239 -401.65643)
			(xy 115.357285 -401.589607) (xy 115.373259 -401.524224) (xy 115.396933 -401.461219) (xy 115.427967 -401.401494)
			(xy 115.465916 -401.345907) (xy 115.487704 -401.320254) (xy 115.493503 -401.313111) (xy 115.500016 -401.295919)
			(xy 115.500404 -401.286726) (xy 115.500404 -400.793458) (xy 115.500013 -400.784269) (xy 115.493486 -400.767085)
			(xy 115.487704 -400.75993) (xy 115.465923 -400.734273) (xy 115.427977 -400.678686) (xy 115.396945 -400.618963)
			(xy 115.373273 -400.555959) (xy 115.357301 -400.490578) (xy 115.349257 -400.423756) (xy 115.349256 -400.356453)
			(xy 115.357299 -400.289631) (xy 115.373271 -400.22425) (xy 115.396941 -400.161245) (xy 115.427972 -400.101522)
			(xy 115.465918 -400.045935) (xy 115.487704 -400.020282) (xy 115.493491 -400.01313) (xy 115.500011 -399.995945)
			(xy 115.500404 -399.986754) (xy 115.500404 -399.828766) (xy 115.500905 -399.81861) (xy 115.508684 -399.799847)
			(xy 115.523047 -399.785484) (xy 115.54181 -399.777705) (xy 115.551966 -399.777204) (xy 116.268246 -399.777204)
			(xy 116.278403 -399.777695) (xy 116.297166 -399.785478) (xy 116.311529 -399.799844) (xy 116.319307 -399.818609)
			(xy 116.319808 -399.828766) (xy 116.319808 -399.986754) (xy 116.320238 -399.995939) (xy 116.326738 -400.013124)
			(xy 116.332508 -400.020282) (xy 116.354303 -400.045929) (xy 116.392255 -400.101515) (xy 116.423291 -400.161238)
			(xy 116.446966 -400.224244) (xy 116.46294 -400.289627) (xy 116.470985 -400.356451) (xy 116.470984 -400.423758)
			(xy 116.462939 -400.490582) (xy 116.446963 -400.555965) (xy 116.423288 -400.61897) (xy 116.392251 -400.678693)
			(xy 116.354298 -400.734279) (xy 116.332508 -400.75993) (xy 116.326717 -400.767079) (xy 116.320199 -400.784267)
			(xy 116.319808 -400.793458) (xy 116.319808 -401.286726) (xy 116.320204 -401.295915) (xy 116.326727 -401.313099)
			(xy 116.332508 -401.320254) (xy 116.354276 -401.345923) (xy 116.392229 -401.401506) (xy 116.423266 -401.461227)
			(xy 116.446942 -401.524229) (xy 116.462918 -401.58961) (xy 116.470965 -401.656431) (xy 116.470967 -401.723736)
			(xy 116.462924 -401.790558) (xy 116.446952 -401.855939) (xy 116.423279 -401.918943) (xy 116.392246 -401.978666)
			(xy 116.354296 -402.034251) (xy 116.332508 -402.059902) (xy 116.326729 -402.06706) (xy 116.320204 -402.084241)
			(xy 116.319808 -402.09343) (xy 116.319808 -402.251418) (xy 116.319283 -402.261571) (xy 116.311511 -402.280332)
			(xy 116.297156 -402.294695) (xy 116.278399 -402.302477) (xy 116.268246 -402.30298) (xy 115.551966 -402.30298)
			(xy 115.541808 -402.302495) (xy 115.523042 -402.294713) (xy 115.508678 -402.280345) (xy 115.500902 -402.261576)
			(xy 115.500404 -402.251418) (xy 115.500404 -402.09343) (xy 115.499978 -402.084244) (xy 115.493475 -402.06706)
			(xy 115.487704 -402.059902) (xy 115.465896 -402.034267) (xy 115.42795 -401.978677) (xy 115.396919 -401.918951)
			(xy 115.373249 -401.855944) (xy 115.357279 -401.79056) (xy 115.349237 -401.723737) (xy 87.820954 -401.723737)
			(xy 87.792056 -401.779212) (xy 87.75397 -401.834847) (xy 87.732108 -401.860512) (xy 87.726325 -401.867667)
			(xy 87.719802 -401.88485) (xy 87.719408 -401.89404) (xy 87.719408 -402.386292) (xy 87.71982 -402.395479)
			(xy 87.726332 -402.412663) (xy 87.732108 -402.41982) (xy 87.753925 -402.445524) (xy 87.792014 -402.501153)
			(xy 87.823166 -402.560944) (xy 87.846933 -402.624036) (xy 87.862972 -402.68952) (xy 87.871051 -402.756454)
			(xy 87.871055 -402.823874) (xy 87.871055 -402.823878) (xy 117.548826 -402.823878) (xy 117.548831 -402.75645)
			(xy 117.556912 -402.689507) (xy 117.572954 -402.624015) (xy 117.596726 -402.560916) (xy 117.627885 -402.501119)
			(xy 117.665983 -402.445484) (xy 117.687852 -402.41982) (xy 117.693671 -402.412691) (xy 117.700171 -402.395488)
			(xy 117.700552 -402.386292) (xy 117.700552 -401.89404) (xy 117.700111 -401.884856) (xy 117.693618 -401.867672)
			(xy 117.687852 -401.860512) (xy 117.665967 -401.834864) (xy 117.627875 -401.779228) (xy 117.596722 -401.71943)
			(xy 117.572957 -401.656331) (xy 117.556921 -401.590839) (xy 117.548846 -401.523898) (xy 117.548848 -401.456472)
			(xy 117.556927 -401.389531) (xy 117.572966 -401.32404) (xy 117.596735 -401.260943) (xy 117.627891 -401.201146)
			(xy 117.665985 -401.145512) (xy 117.687852 -401.119848) (xy 117.69366 -401.112711) (xy 117.700166 -401.095514)
			(xy 117.700552 -401.08632) (xy 117.700552 -400.92884) (xy 117.701117 -400.91874) (xy 117.708832 -400.900072)
			(xy 117.723105 -400.885777) (xy 117.741761 -400.878033) (xy 117.75186 -400.877532) (xy 118.46814 -400.877532)
			(xy 118.478255 -400.877953) (xy 118.49694 -400.88571) (xy 118.511235 -400.900027) (xy 118.518963 -400.918724)
			(xy 118.519448 -400.92884) (xy 118.519448 -401.08632) (xy 118.51986 -401.095507) (xy 118.526374 -401.11269)
			(xy 118.532148 -401.119848) (xy 118.553994 -401.145529) (xy 118.592087 -401.20116) (xy 118.623241 -401.260953)
			(xy 118.647009 -401.324048) (xy 118.663047 -401.389536) (xy 118.671126 -401.456473) (xy 118.671127 -401.523897)
			(xy 118.663053 -401.590834) (xy 118.647018 -401.656323) (xy 118.623254 -401.719419) (xy 118.620974 -401.723796)
			(xy 119.749006 -401.723796) (xy 119.749008 -401.656371) (xy 119.757086 -401.589431) (xy 119.773123 -401.523941)
			(xy 119.79689 -401.460843) (xy 119.828043 -401.401046) (xy 119.866135 -401.345411) (xy 119.888 -401.319746)
			(xy 119.893802 -401.312605) (xy 119.900313 -401.295411) (xy 119.9007 -401.286218) (xy 119.9007 -400.793966)
			(xy 119.900306 -400.784777) (xy 119.893781 -400.767593) (xy 119.888 -400.760438) (xy 119.866142 -400.734768)
			(xy 119.828053 -400.679134) (xy 119.796902 -400.619339) (xy 119.773138 -400.556242) (xy 119.757102 -400.490754)
			(xy 119.749025 -400.423816) (xy 119.749025 -400.356393) (xy 119.7571 -400.289455) (xy 119.773135 -400.223966)
			(xy 119.796898 -400.16087) (xy 119.828048 -400.101074) (xy 119.866136 -400.045439) (xy 119.888 -400.019774)
			(xy 119.89379 -400.012624) (xy 119.900309 -399.995437) (xy 119.9007 -399.986246) (xy 119.9007 -399.828766)
			(xy 119.901197 -399.818642) (xy 119.908929 -399.799928) (xy 119.923211 -399.785574) (xy 119.941887 -399.777749)
			(xy 119.952008 -399.777204) (xy 120.668288 -399.777204) (xy 120.67841 -399.777626) (xy 120.697114 -399.785371)
			(xy 120.711429 -399.799686) (xy 120.719174 -399.81839) (xy 120.719596 -399.828512) (xy 120.719596 -399.986246)
			(xy 120.720033 -399.99543) (xy 120.726528 -400.012615) (xy 120.732296 -400.019774) (xy 120.754166 -400.045434)
			(xy 120.792255 -400.101069) (xy 120.823405 -400.160866) (xy 120.847169 -400.223964) (xy 120.863205 -400.289454)
			(xy 120.87128 -400.356392) (xy 120.87128 -400.423817) (xy 120.863203 -400.490755) (xy 120.847167 -400.556245)
			(xy 120.823402 -400.619342) (xy 120.79225 -400.679138) (xy 120.75416 -400.734773) (xy 120.732296 -400.760438)
			(xy 120.7265 -400.767584) (xy 120.719985 -400.784774) (xy 120.719596 -400.793966) (xy 120.719596 -401.286218)
			(xy 120.719998 -401.295406) (xy 120.726517 -401.31259) (xy 120.732296 -401.319746) (xy 120.754138 -401.345429)
			(xy 120.792228 -401.401061) (xy 120.82338 -401.460855) (xy 120.847146 -401.523949) (xy 120.863183 -401.589436)
			(xy 120.87126 -401.656372) (xy 120.871262 -401.723794) (xy 120.863189 -401.790731) (xy 120.847155 -401.856219)
			(xy 120.823394 -401.919315) (xy 120.792245 -401.979111) (xy 120.754159 -402.034745) (xy 120.732296 -402.06041)
			(xy 120.726512 -402.067564) (xy 120.71999 -402.084748) (xy 120.719596 -402.093938) (xy 120.719596 -402.251418)
			(xy 120.719089 -402.261541) (xy 120.711362 -402.280256) (xy 120.697083 -402.294611) (xy 120.678409 -402.302436)
			(xy 120.668288 -402.30298) (xy 119.952008 -402.30298) (xy 119.941884 -402.302577) (xy 119.923176 -402.294828)
			(xy 119.908861 -402.280507) (xy 119.901119 -402.261797) (xy 119.9007 -402.251672) (xy 119.9007 -402.093938)
			(xy 119.900272 -402.084753) (xy 119.893771 -402.067568) (xy 119.888 -402.06041) (xy 119.866114 -402.034763)
			(xy 119.828026 -401.979126) (xy 119.796877 -401.919327) (xy 119.773114 -401.856228) (xy 119.75708 -401.790736)
			(xy 119.749006 -401.723796) (xy 118.620974 -401.723796) (xy 118.592102 -401.779215) (xy 118.554013 -401.834848)
			(xy 118.532148 -401.860512) (xy 118.526357 -401.867661) (xy 118.519841 -401.884849) (xy 118.519448 -401.89404)
			(xy 118.519448 -402.386292) (xy 118.519874 -402.395477) (xy 118.526378 -402.412661) (xy 118.532148 -402.41982)
			(xy 118.553967 -402.445523) (xy 118.59206 -402.501151) (xy 118.623216 -402.560942) (xy 118.646985 -402.624034)
			(xy 118.663025 -402.689519) (xy 118.671106 -402.756454) (xy 118.67111 -402.823818) (xy 121.949146 -402.823818)
			(xy 121.94915 -402.756509) (xy 121.957199 -402.689684) (xy 121.973177 -402.624299) (xy 121.996856 -402.561292)
			(xy 122.027895 -402.501567) (xy 122.065849 -402.44598) (xy 122.08764 -402.420328) (xy 122.093455 -402.413196)
			(xy 122.099958 -402.395995) (xy 122.10034 -402.3868) (xy 122.10034 -401.893532) (xy 122.099905 -401.884348)
			(xy 122.093408 -401.867164) (xy 122.08764 -401.860004) (xy 122.065832 -401.834368) (xy 122.027884 -401.778779)
			(xy 121.996852 -401.719054) (xy 121.97318 -401.656047) (xy 121.957208 -401.590663) (xy 121.949166 -401.523838)
			(xy 121.949168 -401.456532) (xy 121.957214 -401.389708) (xy 121.973189 -401.324324) (xy 121.996864 -401.261319)
			(xy 122.0279 -401.201595) (xy 122.065851 -401.146008) (xy 122.08764 -401.120356) (xy 122.093443 -401.113215)
			(xy 122.099953 -401.096021) (xy 122.10034 -401.086828) (xy 122.10034 -400.92884) (xy 122.10075 -400.918715)
			(xy 122.108492 -400.900005) (xy 122.122812 -400.885688) (xy 122.141523 -400.877948) (xy 122.151648 -400.877532)
			(xy 122.868182 -400.877532) (xy 122.878307 -400.878041) (xy 122.897026 -400.885761) (xy 122.911383 -400.900041)
			(xy 122.919204 -400.918718) (xy 122.919744 -400.92884) (xy 122.919744 -401.086828) (xy 122.920153 -401.096015)
			(xy 122.926669 -401.113199) (xy 122.932444 -401.120356) (xy 122.954212 -401.146024) (xy 122.992163 -401.201608)
			(xy 123.023198 -401.261329) (xy 123.046873 -401.324332) (xy 123.062848 -401.389712) (xy 123.070894 -401.456533)
			(xy 123.070895 -401.523837) (xy 123.062853 -401.590658) (xy 123.046882 -401.65604) (xy 123.02321 -401.719043)
			(xy 123.020771 -401.723737) (xy 124.149301 -401.723737) (xy 124.149303 -401.65643) (xy 124.15735 -401.589605)
			(xy 124.173327 -401.524221) (xy 124.197004 -401.461215) (xy 124.228043 -401.401491) (xy 124.265997 -401.345906)
			(xy 124.287788 -401.320254) (xy 124.293585 -401.313109) (xy 124.3001 -401.295918) (xy 124.300488 -401.286726)
			(xy 124.300488 -400.793458) (xy 124.300101 -400.784268) (xy 124.293572 -400.767084) (xy 124.287788 -400.75993)
			(xy 124.266005 -400.734274) (xy 124.228052 -400.678689) (xy 124.197016 -400.618966) (xy 124.173341 -400.555962)
			(xy 124.157366 -400.49058) (xy 124.149321 -400.423757) (xy 124.14932 -400.356452) (xy 124.157365 -400.289629)
			(xy 124.173338 -400.224246) (xy 124.197013 -400.161242) (xy 124.228048 -400.101519) (xy 124.265999 -400.045933)
			(xy 124.287788 -400.020282) (xy 124.293573 -400.013129) (xy 124.300095 -399.995944) (xy 124.300488 -399.986754)
			(xy 124.300488 -399.828766) (xy 124.300837 -399.818586) (xy 124.308643 -399.799781) (xy 124.323052 -399.785395)
			(xy 124.341869 -399.777621) (xy 124.35205 -399.777204) (xy 125.06833 -399.777204) (xy 125.078486 -399.777708)
			(xy 125.097249 -399.785486) (xy 125.111612 -399.799848) (xy 125.119391 -399.818611) (xy 125.119892 -399.828766)
			(xy 125.119892 -399.986754) (xy 125.120326 -399.995939) (xy 125.126823 -400.013123) (xy 125.132592 -400.020282)
			(xy 125.154385 -400.04593) (xy 125.192331 -400.101518) (xy 125.223363 -400.161242) (xy 125.247034 -400.224247)
			(xy 125.263005 -400.289629) (xy 125.271049 -400.356452) (xy 125.271048 -400.423757) (xy 125.263004 -400.490579)
			(xy 125.247031 -400.555962) (xy 125.223359 -400.618966) (xy 125.192327 -400.67869) (xy 125.154379 -400.734277)
			(xy 125.132592 -400.75993) (xy 125.126799 -400.767078) (xy 125.120283 -400.784266) (xy 125.119892 -400.793458)
			(xy 125.119892 -401.286726) (xy 125.120291 -401.295914) (xy 125.126813 -401.313099) (xy 125.132592 -401.320254)
			(xy 125.154357 -401.345924) (xy 125.192305 -401.401509) (xy 125.223337 -401.46123) (xy 125.24701 -401.524232)
			(xy 125.262983 -401.589612) (xy 125.271029 -401.656432) (xy 125.271031 -401.723735) (xy 125.262989 -401.790555)
			(xy 125.24702 -401.855936) (xy 125.223351 -401.918939) (xy 125.192322 -401.978663) (xy 125.154377 -402.034249)
			(xy 125.132592 -402.059902) (xy 125.126811 -402.067058) (xy 125.120287 -402.08424) (xy 125.119892 -402.09343)
			(xy 125.119892 -402.251418) (xy 125.119382 -402.261573) (xy 125.111608 -402.280337) (xy 125.097247 -402.294701)
			(xy 125.078485 -402.30248) (xy 125.06833 -402.30298) (xy 124.35205 -402.30298) (xy 124.341884 -402.302496)
			(xy 124.323094 -402.29473) (xy 124.308708 -402.280363) (xy 124.300918 -402.261584) (xy 124.300488 -402.251418)
			(xy 124.300488 -402.09343) (xy 124.300066 -402.084244) (xy 124.293561 -402.067059) (xy 124.287788 -402.059902)
			(xy 124.265977 -402.034268) (xy 124.228026 -401.97868) (xy 124.196991 -401.918955) (xy 124.173317 -401.855948)
			(xy 124.157344 -401.790563) (xy 124.149301 -401.723737) (xy 123.020771 -401.723737) (xy 122.992178 -401.778766)
			(xy 122.954231 -401.834352) (xy 122.932444 -401.860004) (xy 122.926656 -401.867155) (xy 122.920138 -401.884341)
			(xy 122.919744 -401.893532) (xy 122.919744 -402.3868) (xy 122.920167 -402.395986) (xy 122.926673 -402.413169)
			(xy 122.932444 -402.420328) (xy 122.954185 -402.446019) (xy 122.992136 -402.501599) (xy 123.023173 -402.561317)
			(xy 123.046849 -402.624317) (xy 123.062826 -402.689695) (xy 123.070874 -402.756513) (xy 123.070878 -402.823815)
			(xy 123.07087 -402.823878) (xy 126.348914 -402.823878) (xy 126.348919 -402.75645) (xy 126.357 -402.689508)
			(xy 126.373042 -402.624016) (xy 126.396813 -402.560916) (xy 126.427971 -402.501119) (xy 126.466068 -402.445485)
			(xy 126.487936 -402.41982) (xy 126.493754 -402.41269) (xy 126.500255 -402.395488) (xy 126.500636 -402.386292)
			(xy 126.500636 -401.89404) (xy 126.500198 -401.884856) (xy 126.493703 -401.867672) (xy 126.487936 -401.860512)
			(xy 126.466051 -401.834864) (xy 126.427961 -401.779227) (xy 126.396809 -401.719429) (xy 126.373044 -401.65633)
			(xy 126.357009 -401.590839) (xy 126.348934 -401.523898) (xy 126.348936 -401.456472) (xy 126.357014 -401.389532)
			(xy 126.373053 -401.324041) (xy 126.396821 -401.260943) (xy 126.427976 -401.201147) (xy 126.46607 -401.145513)
			(xy 126.487936 -401.119848) (xy 126.493742 -401.112709) (xy 126.50025 -401.095514) (xy 126.500636 -401.08632)
			(xy 126.500636 -400.92884) (xy 126.50105 -400.918716) (xy 126.508791 -400.900006) (xy 126.523109 -400.885689)
			(xy 126.54182 -400.877949) (xy 126.551944 -400.877532) (xy 127.268224 -400.877532) (xy 127.278352 -400.877897)
			(xy 127.297062 -400.885659) (xy 127.311377 -400.899991) (xy 127.319116 -400.918711) (xy 127.319532 -400.92884)
			(xy 127.319532 -401.08632) (xy 127.319948 -401.095506) (xy 127.326459 -401.11269) (xy 127.332232 -401.119848)
			(xy 127.354075 -401.14553) (xy 127.392162 -401.201163) (xy 127.423312 -401.260957) (xy 127.447076 -401.324052)
			(xy 127.463112 -401.389538) (xy 127.471189 -401.456474) (xy 127.471191 -401.523896) (xy 127.463117 -401.590832)
			(xy 127.447085 -401.65632) (xy 127.423324 -401.719415) (xy 127.421073 -401.723737) (xy 128.549092 -401.723737)
			(xy 128.549094 -401.65643) (xy 128.557141 -401.589605) (xy 128.573117 -401.524221) (xy 128.596794 -401.461216)
			(xy 128.627832 -401.401492) (xy 128.665786 -401.345906) (xy 128.687576 -401.320254) (xy 128.693372 -401.313108)
			(xy 128.699888 -401.295918) (xy 128.700276 -401.286726) (xy 128.700276 -400.793458) (xy 128.699891 -400.784268)
			(xy 128.69336 -400.767084) (xy 128.687576 -400.75993) (xy 128.665793 -400.734273) (xy 128.627842 -400.678688)
			(xy 128.596806 -400.618966) (xy 128.573131 -400.555962) (xy 128.557157 -400.49058) (xy 128.549112 -400.423757)
			(xy 128.549111 -400.356452) (xy 128.557155 -400.289629) (xy 128.573129 -400.224247) (xy 128.596802 -400.161242)
			(xy 128.627837 -400.101519) (xy 128.665788 -400.045934) (xy 128.687576 -400.020282) (xy 128.69336 -400.013128)
			(xy 128.699883 -399.995944) (xy 128.700276 -399.986754) (xy 128.700276 -399.828766) (xy 128.700637 -399.818587)
			(xy 128.70844 -399.799785) (xy 128.722845 -399.7854) (xy 128.741659 -399.777623) (xy 128.751838 -399.777204)
			(xy 129.468118 -399.777204) (xy 129.478273 -399.777718) (xy 129.497036 -399.785492) (xy 129.511399 -399.799851)
			(xy 129.519179 -399.818611) (xy 129.51968 -399.828766) (xy 129.51968 -399.986754) (xy 129.520117 -399.995938)
			(xy 129.526612 -400.013123) (xy 129.53238 -400.020282) (xy 129.554173 -400.045929) (xy 129.592121 -400.101517)
			(xy 129.623152 -400.161241) (xy 129.646824 -400.224247) (xy 129.662796 -400.289629) (xy 129.670839 -400.356452)
			(xy 129.670839 -400.423757) (xy 129.662794 -400.49058) (xy 129.646821 -400.555962) (xy 129.623149 -400.618967)
			(xy 129.592116 -400.678691) (xy 129.554168 -400.734278) (xy 129.53238 -400.75993) (xy 129.526586 -400.767077)
			(xy 129.52007 -400.784266) (xy 129.51968 -400.793458) (xy 129.51968 -401.286726) (xy 129.520082 -401.295914)
			(xy 129.526602 -401.313098) (xy 129.53238 -401.320254) (xy 129.554146 -401.345924) (xy 129.592094 -401.401508)
			(xy 129.623127 -401.46123) (xy 129.6468 -401.524232) (xy 129.662774 -401.589612) (xy 129.67082 -401.656432)
			(xy 129.670822 -401.723735) (xy 129.66278 -401.790556) (xy 129.64681 -401.855937) (xy 129.623141 -401.91894)
			(xy 129.592111 -401.978663) (xy 129.554166 -402.03425) (xy 129.53238 -402.059902) (xy 129.526598 -402.067057)
			(xy 129.520075 -402.08424) (xy 129.51968 -402.09343) (xy 129.51968 -402.251418) (xy 129.519182 -402.261575)
			(xy 129.511405 -402.280341) (xy 129.497041 -402.294705) (xy 129.478275 -402.302482) (xy 129.468118 -402.30298)
			(xy 128.751838 -402.30298) (xy 128.741671 -402.302505) (xy 128.722881 -402.294736) (xy 128.708495 -402.280366)
			(xy 128.700706 -402.261584) (xy 128.700276 -402.251418) (xy 128.700276 -402.09343) (xy 128.699857 -402.084244)
			(xy 128.69335 -402.067059) (xy 128.687576 -402.059902) (xy 128.665766 -402.034268) (xy 128.627815 -401.97868)
			(xy 128.596781 -401.918954) (xy 128.573108 -401.855947) (xy 128.557135 -401.790562) (xy 128.549092 -401.723737)
			(xy 127.421073 -401.723737) (xy 127.392178 -401.779211) (xy 127.354094 -401.834846) (xy 127.332232 -401.860512)
			(xy 127.32644 -401.86766) (xy 127.319924 -401.884849) (xy 127.319532 -401.89404) (xy 127.319532 -402.386292)
			(xy 127.319961 -402.395477) (xy 127.326463 -402.412661) (xy 127.332232 -402.41982) (xy 127.354048 -402.445525)
			(xy 127.392136 -402.501154) (xy 127.423287 -402.560945) (xy 127.447052 -402.624037) (xy 127.46309 -402.689521)
			(xy 127.471169 -402.756454) (xy 127.471174 -402.823818) (xy 130.749234 -402.823818) (xy 130.749238 -402.75651)
			(xy 130.757287 -402.689684) (xy 130.773265 -402.624299) (xy 130.796942 -402.561293) (xy 130.82798 -402.501568)
			(xy 130.865934 -402.44598) (xy 130.887724 -402.420328) (xy 130.893536 -402.413194) (xy 130.900041 -402.395995)
			(xy 130.900424 -402.3868) (xy 130.900424 -401.893532) (xy 130.899993 -401.884347) (xy 130.893493 -401.867163)
			(xy 130.887724 -401.860004) (xy 130.865917 -401.834368) (xy 130.82797 -401.778779) (xy 130.796938 -401.719053)
			(xy 130.773267 -401.656046) (xy 130.757296 -401.590662) (xy 130.749254 -401.523838) (xy 130.749256 -401.456532)
			(xy 130.757301 -401.389708) (xy 130.773276 -401.324325) (xy 130.79695 -401.26132) (xy 130.827985 -401.201595)
			(xy 130.865935 -401.146008) (xy 130.887724 -401.120356) (xy 130.893525 -401.113214) (xy 130.900036 -401.096021)
			(xy 130.900424 -401.086828) (xy 130.900424 -400.92884) (xy 130.900855 -400.918686) (xy 130.908642 -400.899929)
			(xy 130.923036 -400.885604) (xy 130.94183 -400.877907) (xy 130.951986 -400.877532) (xy 131.668266 -400.877532)
			(xy 131.67839 -400.878054) (xy 131.697108 -400.88577) (xy 131.711465 -400.900045) (xy 131.719287 -400.918719)
			(xy 131.719828 -400.92884) (xy 131.719828 -401.086828) (xy 131.720218 -401.096017) (xy 131.726745 -401.113202)
			(xy 131.732528 -401.120356) (xy 131.754297 -401.146024) (xy 131.792249 -401.201607) (xy 131.823285 -401.261328)
			(xy 131.84696 -401.324331) (xy 131.862935 -401.389712) (xy 131.870981 -401.456533) (xy 131.870983 -401.523837)
			(xy 131.862941 -401.590659) (xy 131.846969 -401.65604) (xy 131.823297 -401.719044) (xy 131.792264 -401.778767)
			(xy 131.754315 -401.834352) (xy 131.732528 -401.860004) (xy 131.726738 -401.867154) (xy 131.720222 -401.884341)
			(xy 131.719828 -401.893532) (xy 131.719828 -402.3868) (xy 131.720232 -402.395988) (xy 131.726749 -402.413173)
			(xy 131.732528 -402.420328) (xy 131.75427 -402.446019) (xy 131.792222 -402.501599) (xy 131.823259 -402.561317)
			(xy 131.846936 -402.624316) (xy 131.862913 -402.689694) (xy 131.870962 -402.756513) (xy 131.870966 -402.823815)
			(xy 131.862926 -402.890635) (xy 131.846957 -402.956015) (xy 131.823289 -403.019017) (xy 131.792259 -403.078739)
			(xy 131.754314 -403.134324) (xy 131.732528 -403.159976) (xy 131.726708 -403.167104) (xy 131.720209 -403.184308)
			(xy 131.719828 -403.193504) (xy 131.719828 -403.351492) (xy 131.719372 -403.361642) (xy 131.711585 -403.380389)
			(xy 131.697199 -403.394712) (xy 131.678418 -403.402417) (xy 131.668266 -403.4028) (xy 130.951986 -403.4028)
			(xy 130.941863 -403.402286) (xy 130.92315 -403.394561) (xy 130.908795 -403.380284) (xy 130.90097 -403.361612)
			(xy 130.900424 -403.351492) (xy 130.900424 -403.193504) (xy 130.900007 -403.184318) (xy 130.893498 -403.167133)
			(xy 130.887724 -403.159976) (xy 130.86589 -403.134362) (xy 130.827943 -403.07877) (xy 130.796913 -403.019041)
			(xy 130.773243 -402.956032) (xy 130.757274 -402.890645) (xy 130.749234 -402.823818) (xy 127.471174 -402.823818)
			(xy 127.471174 -402.823874) (xy 127.463103 -402.890808) (xy 127.447074 -402.956294) (xy 127.423316 -403.019389)
			(xy 127.392173 -403.079184) (xy 127.354092 -403.134818) (xy 127.332232 -403.160484) (xy 127.326409 -403.16761)
			(xy 127.319912 -403.184816) (xy 127.319532 -403.194012) (xy 127.319532 -403.351492) (xy 127.319009 -403.361596)
			(xy 127.31128 -403.380268) (xy 127.296995 -403.394562) (xy 127.278328 -403.402303) (xy 127.268224 -403.4028)
			(xy 126.551944 -403.4028) (xy 126.541824 -403.402348) (xy 126.523122 -403.394614) (xy 126.508806 -403.380308)
			(xy 126.501059 -403.361611) (xy 126.500636 -403.351492) (xy 126.500636 -403.194012) (xy 126.500212 -403.184826)
			(xy 126.493707 -403.167642) (xy 126.487936 -403.160484) (xy 126.466024 -403.134858) (xy 126.427934 -403.079219)
			(xy 126.396783 -403.019418) (xy 126.37302 -402.956315) (xy 126.356987 -402.890821) (xy 126.348914 -402.823878)
			(xy 123.07087 -402.823878) (xy 123.062839 -402.890634) (xy 123.04687 -402.956014) (xy 123.023202 -403.019017)
			(xy 122.992173 -403.078739) (xy 122.954229 -403.134324) (xy 122.932444 -403.159976) (xy 122.926626 -403.167106)
			(xy 122.920126 -403.184308) (xy 122.919744 -403.193504) (xy 122.919744 -403.351492) (xy 122.919209 -403.361595)
			(xy 122.911483 -403.380264) (xy 122.897201 -403.394558) (xy 122.878538 -403.402301) (xy 122.868436 -403.4028)
			(xy 122.151902 -403.4028) (xy 122.14178 -403.402273) (xy 122.123067 -403.394553) (xy 122.108712 -403.38028)
			(xy 122.100886 -403.361611) (xy 122.10034 -403.351492) (xy 122.10034 -403.193504) (xy 122.099919 -403.184318)
			(xy 122.093412 -403.167134) (xy 122.08764 -403.159976) (xy 122.065805 -403.134363) (xy 122.027857 -403.078771)
			(xy 121.996826 -403.019042) (xy 121.973156 -402.956032) (xy 121.957186 -402.890645) (xy 121.949146 -402.823818)
			(xy 118.67111 -402.823818) (xy 118.67111 -402.823874) (xy 118.663038 -402.89081) (xy 118.647006 -402.956297)
			(xy 118.623245 -403.019392) (xy 118.592097 -403.079187) (xy 118.554011 -403.13482) (xy 118.532148 -403.160484)
			(xy 118.526327 -403.167612) (xy 118.519828 -403.184816) (xy 118.519448 -403.194012) (xy 118.519448 -403.351492)
			(xy 118.51891 -403.361594) (xy 118.511183 -403.380263) (xy 118.496903 -403.394557) (xy 118.478242 -403.4023)
			(xy 118.46814 -403.4028) (xy 117.75186 -403.4028) (xy 117.741749 -403.402348) (xy 117.72307 -403.394597)
			(xy 117.708776 -403.38029) (xy 117.701043 -403.361604) (xy 117.700552 -403.351492) (xy 117.700552 -403.194012)
			(xy 117.700125 -403.184827) (xy 117.693622 -403.167643) (xy 117.687852 -403.160484) (xy 117.665939 -403.134859)
			(xy 117.627848 -403.07922) (xy 117.596697 -403.019418) (xy 117.572933 -402.956316) (xy 117.556899 -402.890822)
			(xy 117.548826 -402.823878) (xy 87.871055 -402.823878) (xy 87.862984 -402.890809) (xy 87.846954 -402.956295)
			(xy 87.823196 -403.01939) (xy 87.792051 -403.079185) (xy 87.753969 -403.134819) (xy 87.732108 -403.160484)
			(xy 87.726294 -403.167617) (xy 87.71979 -403.184817) (xy 87.719408 -403.194012) (xy 87.719408 -403.351492)
			(xy 87.718978 -403.361613) (xy 87.711234 -403.380315) (xy 87.696922 -403.394629) (xy 87.678221 -403.402376)
			(xy 87.6681 -403.4028) (xy 86.95182 -403.4028) (xy 86.941699 -403.402368) (xy 86.922996 -403.394626)
			(xy 86.908681 -403.380315) (xy 86.900935 -403.361613) (xy 86.900512 -403.351492) (xy 86.900512 -403.194012)
			(xy 86.900093 -403.184826) (xy 86.893585 -403.167642) (xy 86.887812 -403.160484) (xy 86.8659 -403.134858)
			(xy 86.827812 -403.079218) (xy 86.796663 -403.019417) (xy 86.772901 -402.956315) (xy 86.756869 -402.890821)
			(xy 86.748796 -402.823878) (xy 83.470752 -402.823878) (xy 83.46272 -402.890635) (xy 83.446751 -402.956015)
			(xy 83.423082 -403.019018) (xy 83.392052 -403.07874) (xy 83.354106 -403.134324) (xy 83.33232 -403.159976)
			(xy 83.326511 -403.167113) (xy 83.320003 -403.18431) (xy 83.31962 -403.193504) (xy 83.31962 -403.351492)
			(xy 83.319172 -403.361643) (xy 83.311383 -403.380391) (xy 83.296995 -403.394714) (xy 83.278211 -403.402418)
			(xy 83.268058 -403.4028) (xy 82.551778 -403.4028) (xy 82.541655 -403.402293) (xy 82.522941 -403.394565)
			(xy 82.508586 -403.380286) (xy 82.500761 -403.361613) (xy 82.500216 -403.351492) (xy 82.500216 -403.193504)
			(xy 82.4998 -403.184318) (xy 82.49329 -403.167133) (xy 82.487516 -403.159976) (xy 82.465682 -403.134362)
			(xy 82.427736 -403.07877) (xy 82.396706 -403.019041) (xy 82.373037 -402.956031) (xy 82.357068 -402.890645)
			(xy 82.349028 -402.823818) (xy 79.070968 -402.823818) (xy 79.070968 -402.823874) (xy 79.062897 -402.890808)
			(xy 79.046867 -402.956294) (xy 79.023109 -403.019389) (xy 78.991966 -403.079184) (xy 78.953884 -403.134818)
			(xy 78.932024 -403.160484) (xy 78.926212 -403.167618) (xy 78.919706 -403.184817) (xy 78.919324 -403.194012)
			(xy 78.919324 -403.351492) (xy 78.918809 -403.361597) (xy 78.911078 -403.380271) (xy 78.896791 -403.394565)
			(xy 78.878121 -403.402304) (xy 78.868016 -403.4028) (xy 78.151736 -403.4028) (xy 78.141616 -403.402354)
			(xy 78.122913 -403.394618) (xy 78.108598 -403.38031) (xy 78.100851 -403.361612) (xy 78.100428 -403.351492)
			(xy 78.100428 -403.194012) (xy 78.100006 -403.184826) (xy 78.0935 -403.167642) (xy 78.087728 -403.160484)
			(xy 78.065816 -403.134858) (xy 78.027727 -403.079219) (xy 77.996577 -403.019417) (xy 77.972814 -402.956315)
			(xy 77.956781 -402.890821) (xy 77.948708 -402.823878) (xy 74.670664 -402.823878) (xy 74.662632 -402.890635)
			(xy 74.646664 -402.956014) (xy 74.622995 -403.019017) (xy 74.591966 -403.078739) (xy 74.554022 -403.134324)
			(xy 74.532236 -403.159976) (xy 74.526417 -403.167105) (xy 74.519917 -403.184308) (xy 74.519536 -403.193504)
			(xy 74.519536 -403.351492) (xy 74.519073 -403.361641) (xy 74.511286 -403.380386) (xy 74.496903 -403.394709)
			(xy 74.478125 -403.402415) (xy 74.467974 -403.4028) (xy 73.751694 -403.4028) (xy 73.741572 -403.402279)
			(xy 73.722858 -403.394557) (xy 73.708504 -403.380282) (xy 73.700678 -403.361611) (xy 73.700132 -403.351492)
			(xy 73.700132 -403.193504) (xy 73.699713 -403.184318) (xy 73.693205 -403.167134) (xy 73.687432 -403.159976)
			(xy 73.665597 -403.134363) (xy 73.62765 -403.07877) (xy 73.59662 -403.019041) (xy 73.57295 -402.956032)
			(xy 73.55698 -402.890645) (xy 73.54894 -402.823818) (xy 66.525648 -402.823818) (xy 66.525648 -405.623707)
			(xy 71.348811 -405.623707) (xy 71.348811 -405.556283) (xy 71.356888 -405.489345) (xy 71.372924 -405.423856)
			(xy 71.396688 -405.360759) (xy 71.427839 -405.300962) (xy 71.465928 -405.245327) (xy 71.487792 -405.219662)
			(xy 71.493586 -405.212515) (xy 71.500103 -405.195326) (xy 71.500492 -405.186134) (xy 71.500492 -404.693882)
			(xy 71.500092 -404.684694) (xy 71.493571 -404.667509) (xy 71.487792 -404.660354) (xy 71.46595 -404.634671)
			(xy 71.427861 -404.579039) (xy 71.39671 -404.519245) (xy 71.372945 -404.45615) (xy 71.356908 -404.390664)
			(xy 71.348831 -404.323727) (xy 71.348829 -404.256306) (xy 71.356902 -404.189369) (xy 71.372935 -404.123881)
			(xy 71.396696 -404.060785) (xy 71.427844 -404.00099) (xy 71.46593 -403.945355) (xy 71.487792 -403.91969)
			(xy 71.493574 -403.912535) (xy 71.500098 -403.895352) (xy 71.500492 -403.886162) (xy 71.500492 -403.728682)
			(xy 71.50101 -403.71856) (xy 71.508735 -403.699847) (xy 71.523011 -403.685493) (xy 71.541681 -403.677666)
			(xy 71.5518 -403.67712) (xy 72.26808 -403.67712) (xy 72.278235 -403.677538) (xy 72.296991 -403.685331)
			(xy 72.311316 -403.699729) (xy 72.319013 -403.718525) (xy 72.319388 -403.728682) (xy 72.319388 -403.886162)
			(xy 72.319819 -403.895347) (xy 72.326319 -403.912531) (xy 72.332088 -403.91969) (xy 72.353974 -403.945337)
			(xy 72.392063 -404.000974) (xy 72.423213 -404.060773) (xy 72.446977 -404.123872) (xy 72.463011 -404.189363)
			(xy 72.471085 -404.256304) (xy 72.471083 -404.323729) (xy 72.463005 -404.390669) (xy 72.446967 -404.45616)
			(xy 72.4232 -404.519258) (xy 72.392046 -404.579054) (xy 72.353954 -404.634689) (xy 72.332088 -404.660354)
			(xy 72.326285 -404.667494) (xy 72.319774 -404.684689) (xy 72.319388 -404.693882) (xy 72.319388 -405.186134)
			(xy 72.319784 -405.195323) (xy 72.326308 -405.212507) (xy 72.332088 -405.219662) (xy 72.353946 -405.245332)
			(xy 72.392036 -405.300965) (xy 72.423188 -405.360761) (xy 72.446953 -405.423857) (xy 72.462989 -405.489346)
			(xy 72.471066 -405.556284) (xy 72.471066 -405.623707) (xy 72.462991 -405.690645) (xy 72.446956 -405.756134)
			(xy 72.423191 -405.819231) (xy 72.392041 -405.879027) (xy 72.353952 -405.934661) (xy 72.332088 -405.960326)
			(xy 72.326297 -405.967475) (xy 72.319779 -405.984663) (xy 72.319388 -405.993854) (xy 72.319388 -406.151334)
			(xy 72.318902 -406.161459) (xy 72.311168 -406.180176) (xy 72.296883 -406.19453) (xy 72.278203 -406.202353)
			(xy 72.26808 -406.202896) (xy 71.5518 -406.202896) (xy 71.541645 -406.202478) (xy 71.522892 -406.194682)
			(xy 71.508569 -406.180284) (xy 71.50087 -406.161491) (xy 71.500492 -406.151334) (xy 71.500492 -405.993854)
			(xy 71.500058 -405.984669) (xy 71.493561 -405.967485) (xy 71.487792 -405.960326) (xy 71.465922 -405.934665)
			(xy 71.427834 -405.87903) (xy 71.396684 -405.819233) (xy 71.372921 -405.756136) (xy 71.356886 -405.690646)
			(xy 71.348811 -405.623707) (xy 66.525648 -405.623707) (xy 66.525648 -406.72373) (xy 73.548951 -406.72373)
			(xy 73.548954 -406.656422) (xy 73.557001 -406.589598) (xy 73.572978 -406.524214) (xy 73.596654 -406.461208)
			(xy 73.62769 -406.401483) (xy 73.665642 -406.345896) (xy 73.687432 -406.320244) (xy 73.693239 -406.313106)
			(xy 73.699747 -406.29591) (xy 73.700132 -406.286716) (xy 73.700132 -405.793448) (xy 73.699691 -405.784264)
			(xy 73.693198 -405.76708) (xy 73.687432 -405.75992) (xy 73.66564 -405.734271) (xy 73.627692 -405.678684)
			(xy 73.596659 -405.61896) (xy 73.572987 -405.555955) (xy 73.557015 -405.490572) (xy 73.548971 -405.42375)
			(xy 73.548971 -405.356444) (xy 73.557016 -405.289622) (xy 73.572989 -405.224239) (xy 73.596662 -405.161235)
			(xy 73.627695 -405.101511) (xy 73.665644 -405.045924) (xy 73.687432 -405.020272) (xy 73.693227 -405.013126)
			(xy 73.699742 -404.995936) (xy 73.700132 -404.986744) (xy 73.700132 -404.828756) (xy 73.700486 -404.818595)
			(xy 73.708302 -404.799836) (xy 73.72272 -404.785513) (xy 73.74153 -404.77782) (xy 73.751694 -404.777448)
			(xy 74.467974 -404.777448) (xy 74.4781 -404.777948) (xy 74.496822 -404.785669) (xy 74.51118 -404.799951)
			(xy 74.518998 -404.818633) (xy 74.519536 -404.828756) (xy 74.519536 -404.986744) (xy 74.519939 -404.995932)
			(xy 74.526459 -405.013115) (xy 74.532236 -405.020272) (xy 74.55402 -405.045927) (xy 74.591971 -405.101513)
			(xy 74.623006 -405.161235) (xy 74.64668 -405.22424) (xy 74.662654 -405.289622) (xy 74.670699 -405.356444)
			(xy 74.670699 -405.42375) (xy 74.662655 -405.490572) (xy 74.646682 -405.555955) (xy 74.623008 -405.618959)
			(xy 74.620571 -405.623649) (xy 75.749106 -405.623649) (xy 75.749107 -405.556342) (xy 75.757152 -405.489519)
			(xy 75.773127 -405.424136) (xy 75.796802 -405.361131) (xy 75.827839 -405.301407) (xy 75.865791 -405.245822)
			(xy 75.88758 -405.22017) (xy 75.893369 -405.21302) (xy 75.899889 -405.195833) (xy 75.90028 -405.186642)
			(xy 75.90028 -404.693374) (xy 75.899887 -404.684185) (xy 75.893362 -404.667001) (xy 75.88758 -404.659846)
			(xy 75.865813 -404.634177) (xy 75.827861 -404.578594) (xy 75.796824 -404.518873) (xy 75.773148 -404.45587)
			(xy 75.757173 -404.39049) (xy 75.749126 -404.323669) (xy 75.749124 -404.256365) (xy 75.757167 -404.189543)
			(xy 75.773138 -404.124161) (xy 75.796811 -404.061157) (xy 75.827844 -404.001435) (xy 75.865792 -403.94585)
			(xy 75.88758 -403.920198) (xy 75.893358 -403.913039) (xy 75.899884 -403.895859) (xy 75.90028 -403.88667)
			(xy 75.90028 -403.728682) (xy 75.90065 -403.718504) (xy 75.908449 -403.699701) (xy 75.922851 -403.685315)
			(xy 75.941664 -403.677538) (xy 75.951842 -403.67712) (xy 76.668122 -403.67712) (xy 76.678279 -403.677615)
			(xy 76.697045 -403.685393) (xy 76.711409 -403.699758) (xy 76.719186 -403.718525) (xy 76.719684 -403.728682)
			(xy 76.719684 -403.88667) (xy 76.720112 -403.895855) (xy 76.726614 -403.91304) (xy 76.732384 -403.920198)
			(xy 76.754193 -403.945833) (xy 76.792139 -404.001422) (xy 76.82317 -404.061148) (xy 76.846841 -404.124155)
			(xy 76.862812 -404.189539) (xy 76.870854 -404.256363) (xy 76.870852 -404.32367) (xy 76.862806 -404.390493)
			(xy 76.846831 -404.455877) (xy 76.823157 -404.518882) (xy 76.792122 -404.578606) (xy 76.754172 -404.634194)
			(xy 76.732384 -404.659846) (xy 76.726584 -404.666988) (xy 76.720072 -404.684181) (xy 76.719684 -404.693374)
			(xy 76.719684 -405.186642) (xy 76.720077 -405.195831) (xy 76.726603 -405.213015) (xy 76.732384 -405.22017)
			(xy 76.754165 -405.245827) (xy 76.792113 -405.301414) (xy 76.823145 -405.361137) (xy 76.846817 -405.42414)
			(xy 76.86279 -405.489522) (xy 76.870834 -405.556343) (xy 76.870835 -405.623648) (xy 76.862791 -405.690469)
			(xy 76.84682 -405.755851) (xy 76.823149 -405.818855) (xy 76.792117 -405.878579) (xy 76.754171 -405.934166)
			(xy 76.732384 -405.959818) (xy 76.726595 -405.966969) (xy 76.720077 -405.984155) (xy 76.719684 -405.993346)
			(xy 76.719684 -406.151334) (xy 76.719195 -406.161491) (xy 76.711414 -406.180257) (xy 76.697047 -406.19462)
			(xy 76.678279 -406.202397) (xy 76.668122 -406.202896) (xy 75.951842 -406.202896) (xy 75.941677 -406.202403)
			(xy 75.92289 -406.194638) (xy 75.908505 -406.180274) (xy 75.900712 -406.161498) (xy 75.90028 -406.151334)
			(xy 75.90028 -405.993346) (xy 75.899852 -405.984161) (xy 75.893351 -405.966976) (xy 75.88758 -405.959818)
			(xy 75.865785 -405.934171) (xy 75.827834 -405.878585) (xy 75.796799 -405.818861) (xy 75.773124 -405.755856)
			(xy 75.757151 -405.690472) (xy 75.749106 -405.623649) (xy 74.620571 -405.623649) (xy 74.591974 -405.678682)
			(xy 74.554024 -405.734268) (xy 74.532236 -405.75992) (xy 74.526441 -405.767066) (xy 74.519927 -405.784256)
			(xy 74.519536 -405.793448) (xy 74.519536 -406.286716) (xy 74.519953 -406.295902) (xy 74.526464 -406.313086)
			(xy 74.532236 -406.320244) (xy 74.553993 -406.345922) (xy 74.591944 -406.401504) (xy 74.62298 -406.461224)
			(xy 74.646656 -406.524225) (xy 74.662632 -406.589604) (xy 74.670679 -406.656424) (xy 74.670682 -406.723727)
			(xy 74.670675 -406.723789) (xy 77.94872 -406.723789) (xy 77.948723 -406.656363) (xy 77.956802 -406.589422)
			(xy 77.972842 -406.52393) (xy 77.996611 -406.460832) (xy 78.027767 -406.401035) (xy 78.065861 -406.345401)
			(xy 78.087728 -406.319736) (xy 78.093538 -406.3126) (xy 78.100044 -406.295402) (xy 78.100428 -406.286208)
			(xy 78.100428 -405.793956) (xy 78.100033 -405.784767) (xy 78.093508 -405.767584) (xy 78.087728 -405.760428)
			(xy 78.065859 -405.734766) (xy 78.027769 -405.679132) (xy 77.996617 -405.619336) (xy 77.972851 -405.556238)
			(xy 77.956815 -405.490748) (xy 77.948739 -405.423809) (xy 77.94874 -405.356385) (xy 77.956816 -405.289446)
			(xy 77.972853 -405.223956) (xy 77.996619 -405.160859) (xy 78.027772 -405.101063) (xy 78.065863 -405.045429)
			(xy 78.087728 -405.019764) (xy 78.093526 -405.01262) (xy 78.100039 -404.995428) (xy 78.100428 -404.986236)
			(xy 78.100428 -404.828756) (xy 78.10085 -404.818641) (xy 78.108607 -404.799956) (xy 78.122924 -404.785662)
			(xy 78.14162 -404.777934) (xy 78.151736 -404.777448) (xy 78.868016 -404.777448) (xy 78.878119 -404.777971)
			(xy 78.896788 -404.785704) (xy 78.91108 -404.799989) (xy 78.918823 -404.818653) (xy 78.919324 -404.828756)
			(xy 78.919324 -404.986236) (xy 78.919712 -404.995426) (xy 78.92624 -405.01261) (xy 78.932024 -405.019764)
			(xy 78.953883 -405.045433) (xy 78.99197 -405.101067) (xy 79.02312 -405.160863) (xy 79.046883 -405.22396)
			(xy 79.062918 -405.289448) (xy 79.070994 -405.356386) (xy 79.070995 -405.423808) (xy 79.062919 -405.490746)
			(xy 79.046885 -405.556235) (xy 79.023122 -405.619331) (xy 79.020843 -405.623707) (xy 80.148899 -405.623707)
			(xy 80.148899 -405.556284) (xy 80.156975 -405.489345) (xy 80.173011 -405.423856) (xy 80.196775 -405.360759)
			(xy 80.227925 -405.300963) (xy 80.266013 -405.245328) (xy 80.287876 -405.219662) (xy 80.293668 -405.212514)
			(xy 80.300186 -405.195326) (xy 80.300576 -405.186134) (xy 80.300576 -404.693882) (xy 80.30018 -404.684693)
			(xy 80.293657 -404.667509) (xy 80.287876 -404.660354) (xy 80.266034 -404.634671) (xy 80.227947 -404.579038)
			(xy 80.196796 -404.519244) (xy 80.173032 -404.45615) (xy 80.156996 -404.390663) (xy 80.148918 -404.323727)
			(xy 80.148917 -404.256306) (xy 80.15699 -404.189369) (xy 80.173022 -404.123882) (xy 80.196783 -404.060786)
			(xy 80.22793 -404.00099) (xy 80.266014 -403.945356) (xy 80.287876 -403.91969) (xy 80.293657 -403.912533)
			(xy 80.300182 -403.895352) (xy 80.300576 -403.886162) (xy 80.300576 -403.728682) (xy 80.301013 -403.71855)
			(xy 80.308753 -403.699821) (xy 80.323055 -403.685464) (xy 80.341754 -403.677652) (xy 80.351884 -403.67712)
			(xy 81.068164 -403.67712) (xy 81.078318 -403.677552) (xy 81.097074 -403.685339) (xy 81.111399 -403.699733)
			(xy 81.119096 -403.718526) (xy 81.119472 -403.728682) (xy 81.119472 -403.886162) (xy 81.119907 -403.895346)
			(xy 81.126404 -403.912531) (xy 81.132172 -403.91969) (xy 81.154059 -403.945337) (xy 81.192148 -404.000973)
			(xy 81.2233 -404.060772) (xy 81.247064 -404.123871) (xy 81.263099 -404.189363) (xy 81.271173 -404.256304)
			(xy 81.271171 -404.32373) (xy 81.263093 -404.39067) (xy 81.247054 -404.45616) (xy 81.223286 -404.519258)
			(xy 81.192131 -404.579055) (xy 81.154038 -404.634689) (xy 81.132172 -404.660354) (xy 81.126366 -404.667493)
			(xy 81.119858 -404.684688) (xy 81.119472 -404.693882) (xy 81.119472 -405.186134) (xy 81.119872 -405.195322)
			(xy 81.126393 -405.212506) (xy 81.132172 -405.219662) (xy 81.154031 -405.245332) (xy 81.192122 -405.300965)
			(xy 81.223274 -405.36076) (xy 81.24704 -405.423857) (xy 81.263077 -405.489345) (xy 81.271154 -405.556284)
			(xy 81.271154 -405.623707) (xy 81.263078 -405.690646) (xy 81.247043 -405.756135) (xy 81.223278 -405.819232)
			(xy 81.192126 -405.879027) (xy 81.154037 -405.934661) (xy 81.132172 -405.960326) (xy 81.126378 -405.967473)
			(xy 81.119862 -405.984662) (xy 81.119472 -405.993854) (xy 81.119472 -406.151334) (xy 81.119002 -406.161461)
			(xy 81.111265 -406.180181) (xy 81.096974 -406.194536) (xy 81.078289 -406.202356) (xy 81.068164 -406.202896)
			(xy 80.351884 -406.202896) (xy 80.341728 -406.202492) (xy 80.322975 -406.19469) (xy 80.308652 -406.180288)
			(xy 80.300953 -406.161492) (xy 80.300576 -406.151334) (xy 80.300576 -405.993854) (xy 80.300145 -405.984669)
			(xy 80.293646 -405.967484) (xy 80.287876 -405.960326) (xy 80.266007 -405.934665) (xy 80.22792 -405.879029)
			(xy 80.196771 -405.819232) (xy 80.173008 -405.756135) (xy 80.156974 -405.690646) (xy 80.148899 -405.623707)
			(xy 79.020843 -405.623707) (xy 78.991974 -405.679127) (xy 78.953887 -405.734762) (xy 78.932024 -405.760428)
			(xy 78.926236 -405.767579) (xy 78.919715 -405.784765) (xy 78.919324 -405.793956) (xy 78.919324 -406.286208)
			(xy 78.919725 -406.295396) (xy 78.926244 -406.312581) (xy 78.932024 -406.319736) (xy 78.953856 -406.345428)
			(xy 78.991944 -406.401059) (xy 79.023095 -406.460852) (xy 79.046859 -406.523945) (xy 79.062896 -406.589431)
			(xy 79.070974 -406.656366) (xy 79.070977 -406.72373) (xy 82.349039 -406.72373) (xy 82.349042 -406.656422)
			(xy 82.357089 -406.589598) (xy 82.373065 -406.524214) (xy 82.39674 -406.461209) (xy 82.427776 -406.401484)
			(xy 82.465727 -406.345896) (xy 82.487516 -406.320244) (xy 82.493321 -406.313105) (xy 82.49983 -406.29591)
			(xy 82.500216 -406.286716) (xy 82.500216 -405.793448) (xy 82.499779 -405.784264) (xy 82.493284 -405.767079)
			(xy 82.487516 -405.75992) (xy 82.465725 -405.734271) (xy 82.427778 -405.678683) (xy 82.396746 -405.618959)
			(xy 82.373074 -405.555954) (xy 82.357102 -405.490572) (xy 82.349059 -405.423749) (xy 82.349059 -405.356445)
			(xy 82.357103 -405.289622) (xy 82.373076 -405.22424) (xy 82.396748 -405.161235) (xy 82.427781 -405.101511)
			(xy 82.465729 -405.045924) (xy 82.487516 -405.020272) (xy 82.493309 -405.013124) (xy 82.499825 -404.995936)
			(xy 82.500216 -404.986744) (xy 82.500216 -404.828756) (xy 82.500586 -404.818597) (xy 82.508399 -404.799841)
			(xy 82.522811 -404.785518) (xy 82.541617 -404.777823) (xy 82.551778 -404.777448) (xy 83.268058 -404.777448)
			(xy 83.278183 -404.777961) (xy 83.296905 -404.785677) (xy 83.311263 -404.799955) (xy 83.319082 -404.818634)
			(xy 83.31962 -404.828756) (xy 83.31962 -404.986744) (xy 83.320004 -404.995934) (xy 83.326535 -405.013118)
			(xy 83.33232 -405.020272) (xy 83.354105 -405.045927) (xy 83.392057 -405.101512) (xy 83.423092 -405.161235)
			(xy 83.446767 -405.224239) (xy 83.462742 -405.289621) (xy 83.470787 -405.356444) (xy 83.470787 -405.42375)
			(xy 83.462743 -405.490573) (xy 83.446769 -405.555955) (xy 83.423095 -405.61896) (xy 83.420628 -405.623707)
			(xy 84.54869 -405.623707) (xy 84.54869 -405.556284) (xy 84.556766 -405.489346) (xy 84.572801 -405.423857)
			(xy 84.596564 -405.36076) (xy 84.627714 -405.300963) (xy 84.665801 -405.245328) (xy 84.687664 -405.219662)
			(xy 84.693467 -405.212522) (xy 84.699976 -405.195327) (xy 84.700364 -405.186134) (xy 84.700364 -404.693882)
			(xy 84.699948 -404.684696) (xy 84.693437 -404.667512) (xy 84.687664 -404.660354) (xy 84.665823 -404.63467)
			(xy 84.627736 -404.579038) (xy 84.596586 -404.519244) (xy 84.572822 -404.456149) (xy 84.556787 -404.390663)
			(xy 84.548709 -404.323727) (xy 84.548707 -404.256306) (xy 84.556781 -404.18937) (xy 84.572813 -404.123882)
			(xy 84.596573 -404.060787) (xy 84.627719 -404.000991) (xy 84.665803 -403.945356) (xy 84.687664 -403.91969)
			(xy 84.693455 -403.912541) (xy 84.699971 -403.895353) (xy 84.700364 -403.886162) (xy 84.700364 -403.728682)
			(xy 84.700812 -403.718551) (xy 84.70855 -403.699825) (xy 84.722849 -403.685468) (xy 84.741543 -403.677654)
			(xy 84.751672 -403.67712) (xy 85.467952 -403.67712) (xy 85.478105 -403.677561) (xy 85.496861 -403.685345)
			(xy 85.511186 -403.699736) (xy 85.518884 -403.718527) (xy 85.51926 -403.728682) (xy 85.51926 -403.886162)
			(xy 85.519698 -403.895346) (xy 85.526193 -403.91253) (xy 85.53196 -403.91969) (xy 85.553847 -403.945337)
			(xy 85.591938 -404.000973) (xy 85.62309 -404.060771) (xy 85.646854 -404.123871) (xy 85.66289 -404.189362)
			(xy 85.670964 -404.256303) (xy 85.670962 -404.32373) (xy 85.662884 -404.39067) (xy 85.646845 -404.456161)
			(xy 85.623076 -404.519259) (xy 85.591921 -404.579055) (xy 85.553827 -404.634689) (xy 85.53196 -404.660354)
			(xy 85.526153 -404.667492) (xy 85.519646 -404.684688) (xy 85.51926 -404.693882) (xy 85.51926 -405.186134)
			(xy 85.519663 -405.195322) (xy 85.526183 -405.212506) (xy 85.53196 -405.219662) (xy 85.553819 -405.245331)
			(xy 85.591911 -405.300964) (xy 85.623064 -405.36076) (xy 85.64683 -405.423856) (xy 85.662868 -405.489345)
			(xy 85.670945 -405.556284) (xy 85.670945 -405.623707) (xy 85.662869 -405.690646) (xy 85.646833 -405.756135)
			(xy 85.623068 -405.819232) (xy 85.591916 -405.879028) (xy 85.553825 -405.934661) (xy 85.53196 -405.960326)
			(xy 85.526165 -405.967472) (xy 85.51965 -405.984662) (xy 85.51926 -405.993854) (xy 85.51926 -406.151334)
			(xy 85.518801 -406.161463) (xy 85.511062 -406.180185) (xy 85.496768 -406.19454) (xy 85.478079 -406.202358)
			(xy 85.467952 -406.202896) (xy 84.751672 -406.202896) (xy 84.741516 -406.202501) (xy 84.722762 -406.194696)
			(xy 84.708439 -406.180291) (xy 84.700741 -406.161493) (xy 84.700364 -406.151334) (xy 84.700364 -405.993854)
			(xy 84.699914 -405.984671) (xy 84.693426 -405.967487) (xy 84.687664 -405.960326) (xy 84.665795 -405.934665)
			(xy 84.627709 -405.879029) (xy 84.596561 -405.819232) (xy 84.572799 -405.756135) (xy 84.556765 -405.690645)
			(xy 84.54869 -405.623707) (xy 83.420628 -405.623707) (xy 83.39206 -405.678683) (xy 83.354109 -405.734268)
			(xy 83.33232 -405.75992) (xy 83.326535 -405.767073) (xy 83.320013 -405.784258) (xy 83.31962 -405.793448)
			(xy 83.31962 -406.286716) (xy 83.320018 -406.295905) (xy 83.32654 -406.313089) (xy 83.33232 -406.320244)
			(xy 83.354077 -406.345921) (xy 83.39203 -406.401503) (xy 83.423067 -406.461223) (xy 83.446743 -406.524224)
			(xy 83.46272 -406.589604) (xy 83.470767 -406.656424) (xy 83.47077 -406.723728) (xy 83.470763 -406.723789)
			(xy 86.748808 -406.723789) (xy 86.748811 -406.656363) (xy 86.75689 -406.589422) (xy 86.772929 -406.523931)
			(xy 86.796697 -406.460833) (xy 86.827852 -406.401036) (xy 86.865946 -406.345401) (xy 86.887812 -406.319736)
			(xy 86.89362 -406.312599) (xy 86.900127 -406.295402) (xy 86.900512 -406.286208) (xy 86.900512 -405.793956)
			(xy 86.90012 -405.784767) (xy 86.893594 -405.767583) (xy 86.887812 -405.760428) (xy 86.865944 -405.734766)
			(xy 86.827854 -405.679131) (xy 86.796703 -405.619335) (xy 86.772939 -405.556238) (xy 86.756903 -405.490748)
			(xy 86.748827 -405.423809) (xy 86.748828 -405.356385) (xy 86.756904 -405.289446) (xy 86.77294 -405.223957)
			(xy 86.796706 -405.16086) (xy 86.827857 -405.101063) (xy 86.865947 -405.045429) (xy 86.887812 -405.019764)
			(xy 86.893608 -405.012618) (xy 86.900123 -404.995428) (xy 86.900512 -404.986236) (xy 86.900512 -404.828756)
			(xy 86.900949 -404.818643) (xy 86.908704 -404.799961) (xy 86.923015 -404.785668) (xy 86.941706 -404.777937)
			(xy 86.95182 -404.777448) (xy 87.6681 -404.777448) (xy 87.678202 -404.777984) (xy 87.696871 -404.785712)
			(xy 87.711163 -404.799993) (xy 87.718907 -404.818654) (xy 87.719408 -404.828756) (xy 87.719408 -404.986236)
			(xy 87.719799 -404.995425) (xy 87.726326 -405.01261) (xy 87.732108 -405.019764) (xy 87.753968 -405.045433)
			(xy 87.792056 -405.101067) (xy 87.823206 -405.160863) (xy 87.846971 -405.223959) (xy 87.863006 -405.289448)
			(xy 87.871082 -405.356385) (xy 87.871082 -405.423809) (xy 87.863007 -405.490746) (xy 87.846972 -405.556235)
			(xy 87.823209 -405.619332) (xy 87.792059 -405.679128) (xy 87.753971 -405.734763) (xy 87.732108 -405.760428)
			(xy 87.726318 -405.767578) (xy 87.719799 -405.784765) (xy 87.719408 -405.793956) (xy 87.719408 -406.286208)
			(xy 87.719813 -406.295396) (xy 87.72633 -406.31258) (xy 87.732108 -406.319736) (xy 87.75394 -406.345427)
			(xy 87.792029 -406.401058) (xy 87.823181 -406.460851) (xy 87.846947 -406.523944) (xy 87.862984 -406.58943)
			(xy 87.871062 -406.656365) (xy 87.871065 -406.723729) (xy 91.149127 -406.723729) (xy 91.14913 -406.656423)
			(xy 91.157177 -406.589598) (xy 91.173152 -406.524215) (xy 91.196827 -406.461209) (xy 91.227861 -406.401484)
			(xy 91.265812 -406.345897) (xy 91.2876 -406.320244) (xy 91.293403 -406.313103) (xy 91.299914 -406.295909)
			(xy 91.3003 -406.286716) (xy 91.3003 -405.793448) (xy 91.299867 -405.784263) (xy 91.293369 -405.767079)
			(xy 91.2876 -405.75992) (xy 91.26581 -405.734271) (xy 91.227863 -405.678683) (xy 91.196832 -405.618958)
			(xy 91.173162 -405.555954) (xy 91.15719 -405.490572) (xy 91.149147 -405.423749) (xy 91.149147 -405.356445)
			(xy 91.157191 -405.289622) (xy 91.173163 -405.224241) (xy 91.196835 -405.161236) (xy 91.227866 -405.101512)
			(xy 91.265813 -405.045925) (xy 91.2876 -405.020272) (xy 91.293391 -405.013123) (xy 91.299909 -404.995935)
			(xy 91.3003 -404.986744) (xy 91.3003 -404.828756) (xy 91.300686 -404.818599) (xy 91.308496 -404.799846)
			(xy 91.322903 -404.785524) (xy 91.341703 -404.777826) (xy 91.351862 -404.777448) (xy 92.068142 -404.777448)
			(xy 92.078272 -404.777892) (xy 92.096996 -404.785635) (xy 92.111351 -404.799934) (xy 92.119167 -404.818628)
			(xy 92.119704 -404.828756) (xy 92.119704 -404.986744) (xy 92.120092 -404.995934) (xy 92.126621 -405.013118)
			(xy 92.132404 -405.020272) (xy 92.154186 -405.045928) (xy 92.192133 -405.101515) (xy 92.223164 -405.161238)
			(xy 92.246835 -405.224242) (xy 92.262807 -405.289624) (xy 92.270851 -405.356445) (xy 92.270851 -405.423749)
			(xy 92.262808 -405.490571) (xy 92.246837 -405.555952) (xy 92.223166 -405.618956) (xy 92.220728 -405.623648)
			(xy 115.349248 -405.623648) (xy 115.349249 -405.556343) (xy 115.357293 -405.489521) (xy 115.373266 -405.424139)
			(xy 115.396938 -405.361134) (xy 115.42797 -405.30141) (xy 115.465917 -405.245823) (xy 115.487704 -405.22017)
			(xy 115.493496 -405.213022) (xy 115.500013 -405.195834) (xy 115.500404 -405.186642) (xy 115.500404 -404.693374)
			(xy 115.500006 -404.684186) (xy 115.493484 -404.667001) (xy 115.487704 -404.659846) (xy 115.465939 -404.634176)
			(xy 115.427992 -404.578591) (xy 115.396959 -404.51887) (xy 115.373287 -404.455868) (xy 115.357314 -404.390488)
			(xy 115.349268 -404.323668) (xy 115.349266 -404.256365) (xy 115.357308 -404.189545) (xy 115.373277 -404.124164)
			(xy 115.396946 -404.061161) (xy 115.427975 -404.001437) (xy 115.465919 -403.945851) (xy 115.487704 -403.920198)
			(xy 115.493484 -403.913041) (xy 115.500009 -403.89586) (xy 115.500404 -403.88667) (xy 115.500404 -403.728682)
			(xy 115.500918 -403.718527) (xy 115.508692 -403.699764) (xy 115.523051 -403.685401) (xy 115.541811 -403.677621)
			(xy 115.551966 -403.67712) (xy 116.268246 -403.67712) (xy 116.278404 -403.677595) (xy 116.297171 -403.685382)
			(xy 116.311534 -403.699752) (xy 116.31931 -403.718523) (xy 116.319808 -403.728682) (xy 116.319808 -403.88667)
			(xy 116.320231 -403.895856) (xy 116.326735 -403.91304) (xy 116.332508 -403.920198) (xy 116.354319 -403.945832)
			(xy 116.392271 -404.00142) (xy 116.423306 -404.061145) (xy 116.44698 -404.124152) (xy 116.462953 -404.189537)
			(xy 116.470996 -404.256363) (xy 116.470994 -404.32367) (xy 116.462947 -404.390495) (xy 116.44697 -404.455879)
			(xy 116.423292 -404.518885) (xy 116.392254 -404.578609) (xy 116.354299 -404.634195) (xy 116.332508 -404.659846)
			(xy 116.32671 -404.66699) (xy 116.320196 -404.684181) (xy 116.319808 -404.693374) (xy 116.319808 -405.186642)
			(xy 116.320196 -405.195832) (xy 116.326725 -405.213016) (xy 116.332508 -405.22017) (xy 116.354291 -405.245826)
			(xy 116.392244 -405.301411) (xy 116.42328 -405.361133) (xy 116.446956 -405.424137) (xy 116.462931 -405.48952)
			(xy 116.470976 -405.556343) (xy 116.470977 -405.623648) (xy 116.462932 -405.690471) (xy 116.446958 -405.755854)
			(xy 116.423284 -405.818858) (xy 116.392249 -405.878581) (xy 116.354297 -405.934167) (xy 116.332508 -405.959818)
			(xy 116.326722 -405.966971) (xy 116.320201 -405.984155) (xy 116.319808 -405.993346) (xy 116.319808 -406.151334)
			(xy 116.319296 -406.161488) (xy 116.311519 -406.180249) (xy 116.297159 -406.194612) (xy 116.2784 -406.202393)
			(xy 116.268246 -406.202896) (xy 115.551966 -406.202896) (xy 115.54181 -406.202395) (xy 115.523047 -406.194616)
			(xy 115.508684 -406.180253) (xy 115.500905 -406.16149) (xy 115.500404 -406.151334) (xy 115.500404 -405.993346)
			(xy 115.499971 -405.984161) (xy 115.493473 -405.966977) (xy 115.487704 -405.959818) (xy 115.465911 -405.93417)
			(xy 115.427965 -405.878582) (xy 115.396934 -405.818858) (xy 115.373263 -405.755853) (xy 115.357292 -405.69047)
			(xy 115.349248 -405.623648) (xy 92.220728 -405.623648) (xy 92.192136 -405.67868) (xy 92.15419 -405.734267)
			(xy 92.132404 -405.75992) (xy 92.126617 -405.767072) (xy 92.120096 -405.784257) (xy 92.119704 -405.793448)
			(xy 92.119704 -406.286716) (xy 92.120106 -406.295904) (xy 92.126625 -406.313088) (xy 92.132404 -406.320244)
			(xy 92.154159 -406.345923) (xy 92.192106 -406.401506) (xy 92.223138 -406.461227) (xy 92.246811 -406.524228)
			(xy 92.262785 -406.589606) (xy 92.270831 -406.656425) (xy 92.270834 -406.723727) (xy 92.270826 -406.72379)
			(xy 117.548838 -406.72379) (xy 117.548841 -406.656362) (xy 117.55692 -406.589421) (xy 117.572961 -406.523929)
			(xy 117.596731 -406.460831) (xy 117.627888 -406.401034) (xy 117.665984 -406.3454) (xy 117.687852 -406.319736)
			(xy 117.693665 -406.312602) (xy 117.700168 -406.295403) (xy 117.700552 -406.286208) (xy 117.700552 -405.793956)
			(xy 117.700151 -405.784768) (xy 117.69363 -405.767585) (xy 117.687852 -405.760428) (xy 117.665982 -405.734767)
			(xy 117.62789 -405.679133) (xy 117.596737 -405.619337) (xy 117.572971 -405.556239) (xy 117.556934 -405.490749)
			(xy 117.548857 -405.42381) (xy 117.548858 -405.356384) (xy 117.556935 -405.289445) (xy 117.572972 -405.223955)
			(xy 117.596739 -405.160858) (xy 117.627893 -405.101062) (xy 117.665986 -405.045428) (xy 117.687852 -405.019764)
			(xy 117.693653 -405.012622) (xy 117.700164 -404.995429) (xy 117.700552 -404.986236) (xy 117.700552 -404.828756)
			(xy 117.701048 -404.81865) (xy 117.708791 -404.79998) (xy 117.723084 -404.785689) (xy 117.741754 -404.777947)
			(xy 117.75186 -404.777448) (xy 118.46814 -404.777448) (xy 118.478245 -404.777951) (xy 118.496914 -404.785692)
			(xy 118.511206 -404.799983) (xy 118.518948 -404.818651) (xy 118.519448 -404.828756) (xy 118.519448 -404.986236)
			(xy 118.519853 -404.995424) (xy 118.526372 -405.012607) (xy 118.532148 -405.019764) (xy 118.55401 -405.045432)
			(xy 118.592102 -405.101065) (xy 118.623256 -405.16086) (xy 118.647023 -405.223957) (xy 118.66306 -405.289446)
			(xy 118.671137 -405.356385) (xy 118.671137 -405.423809) (xy 118.663061 -405.490748) (xy 118.647024 -405.556238)
			(xy 118.623258 -405.619335) (xy 118.62098 -405.623708) (xy 119.749017 -405.623708) (xy 119.749017 -405.556283)
			(xy 119.757094 -405.489345) (xy 119.77313 -405.423855) (xy 119.796895 -405.360758) (xy 119.828046 -405.300962)
			(xy 119.866136 -405.245327) (xy 119.888 -405.219662) (xy 119.893795 -405.212516) (xy 119.900311 -405.195326)
			(xy 119.9007 -405.186134) (xy 119.9007 -404.693882) (xy 119.900298 -404.684694) (xy 119.893779 -404.66751)
			(xy 119.888 -404.660354) (xy 119.866158 -404.634671) (xy 119.828068 -404.579039) (xy 119.796917 -404.519245)
			(xy 119.773151 -404.456151) (xy 119.757114 -404.390664) (xy 119.749037 -404.323727) (xy 119.749035 -404.256306)
			(xy 119.757108 -404.189369) (xy 119.773141 -404.123881) (xy 119.796903 -404.060785) (xy 119.828051 -404.000989)
			(xy 119.866137 -403.945355) (xy 119.888 -403.91969) (xy 119.893783 -403.912535) (xy 119.900306 -403.895352)
			(xy 119.9007 -403.886162) (xy 119.9007 -403.728682) (xy 119.90121 -403.718559) (xy 119.908937 -403.699845)
			(xy 119.923215 -403.685491) (xy 119.941888 -403.677665) (xy 119.952008 -403.67712) (xy 120.668288 -403.67712)
			(xy 120.678412 -403.677526) (xy 120.697119 -403.685274) (xy 120.711435 -403.699594) (xy 120.719177 -403.718304)
			(xy 120.719596 -403.728428) (xy 120.719596 -403.886162) (xy 120.720025 -403.895347) (xy 120.726526 -403.912532)
			(xy 120.732296 -403.91969) (xy 120.754182 -403.945337) (xy 120.79227 -404.000974) (xy 120.82342 -404.060773)
			(xy 120.847183 -404.123872) (xy 120.863217 -404.189363) (xy 120.871291 -404.256304) (xy 120.871289 -404.323729)
			(xy 120.863211 -404.390669) (xy 120.847173 -404.456159) (xy 120.823407 -404.519257) (xy 120.792253 -404.579054)
			(xy 120.754161 -404.634689) (xy 120.732296 -404.660354) (xy 120.726494 -404.667495) (xy 120.719983 -404.684689)
			(xy 120.719596 -404.693882) (xy 120.719596 -405.186134) (xy 120.719991 -405.195323) (xy 120.726515 -405.212507)
			(xy 120.732296 -405.219662) (xy 120.754154 -405.245332) (xy 120.792243 -405.300966) (xy 120.823395 -405.360761)
			(xy 120.847159 -405.423858) (xy 120.863195 -405.489346) (xy 120.871272 -405.556284) (xy 120.871272 -405.623707)
			(xy 120.863197 -405.690645) (xy 120.847162 -405.756134) (xy 120.823398 -405.81923) (xy 120.792248 -405.879026)
			(xy 120.75416 -405.934661) (xy 120.732296 -405.960326) (xy 120.726505 -405.967475) (xy 120.719987 -405.984663)
			(xy 120.719596 -405.993854) (xy 120.719596 -406.151334) (xy 120.719102 -406.161458) (xy 120.71137 -406.180174)
			(xy 120.697087 -406.194527) (xy 120.67841 -406.202352) (xy 120.668288 -406.202896) (xy 119.952008 -406.202896)
			(xy 119.941886 -406.202477) (xy 119.923181 -406.194731) (xy 119.908867 -406.180415) (xy 119.901122 -406.16171)
			(xy 119.9007 -406.151588) (xy 119.9007 -405.993854) (xy 119.900264 -405.98467) (xy 119.893768 -405.967485)
			(xy 119.888 -405.960326) (xy 119.86613 -405.934666) (xy 119.828042 -405.87903) (xy 119.796891 -405.819234)
			(xy 119.773127 -405.756136) (xy 119.757092 -405.690646) (xy 119.749017 -405.623708) (xy 118.62098 -405.623708)
			(xy 118.592105 -405.67913) (xy 118.554014 -405.734764) (xy 118.532148 -405.760428) (xy 118.526351 -405.767572)
			(xy 118.519838 -405.784764) (xy 118.519448 -405.793956) (xy 118.519448 -406.286208) (xy 118.519866 -406.295394)
			(xy 118.526375 -406.312578) (xy 118.532148 -406.319736) (xy 118.553982 -406.345426) (xy 118.592075 -406.401056)
			(xy 118.62323 -406.460848) (xy 118.646999 -406.523942) (xy 118.663038 -406.589429) (xy 118.671117 -406.656365)
			(xy 118.67112 -406.72373) (xy 121.949157 -406.72373) (xy 121.94916 -406.656422) (xy 121.957208 -406.589597)
			(xy 121.973184 -406.524213) (xy 121.99686 -406.461207) (xy 122.027897 -406.401483) (xy 122.06585 -406.345896)
			(xy 122.08764 -406.320244) (xy 122.093448 -406.313107) (xy 122.099955 -406.29591) (xy 122.10034 -406.286716)
			(xy 122.10034 -405.793448) (xy 122.099898 -405.784264) (xy 122.093405 -405.76708) (xy 122.08764 -405.75992)
			(xy 122.065848 -405.734271) (xy 122.027899 -405.678684) (xy 121.996866 -405.61896) (xy 121.973194 -405.555955)
			(xy 121.957221 -405.490573) (xy 121.949177 -405.42375) (xy 121.949177 -405.356444) (xy 121.957222 -405.289621)
			(xy 121.973195 -405.224239) (xy 121.996869 -405.161234) (xy 122.027902 -405.101511) (xy 122.065852 -405.045924)
			(xy 122.08764 -405.020272) (xy 122.093436 -405.013127) (xy 122.09995 -404.995936) (xy 122.10034 -404.986744)
			(xy 122.10034 -404.828756) (xy 122.100681 -404.818626) (xy 122.108451 -404.799913) (xy 122.122791 -404.785599)
			(xy 122.141517 -404.777863) (xy 122.151648 -404.777448) (xy 122.868182 -404.777448) (xy 122.878309 -404.777941)
			(xy 122.897031 -404.785665) (xy 122.911388 -404.799949) (xy 122.919207 -404.818632) (xy 122.919744 -404.828756)
			(xy 122.919744 -404.986744) (xy 122.920145 -404.995932) (xy 122.926666 -405.013116) (xy 122.932444 -405.020272)
			(xy 122.954228 -405.045927) (xy 122.992178 -405.101513) (xy 123.023213 -405.161236) (xy 123.046886 -405.22424)
			(xy 123.06286 -405.289622) (xy 123.070905 -405.356444) (xy 123.070905 -405.42375) (xy 123.062861 -405.490572)
			(xy 123.046888 -405.555954) (xy 123.023215 -405.618959) (xy 123.020778 -405.623649) (xy 124.149312 -405.623649)
			(xy 124.149313 -405.556342) (xy 124.157358 -405.489518) (xy 124.173333 -405.424135) (xy 124.197009 -405.36113)
			(xy 124.228046 -405.301407) (xy 124.265998 -405.245822) (xy 124.287788 -405.22017) (xy 124.293578 -405.21302)
			(xy 124.300097 -405.195833) (xy 124.300488 -405.186642) (xy 124.300488 -404.693374) (xy 124.300093 -404.684185)
			(xy 124.293569 -404.667001) (xy 124.287788 -404.659846) (xy 124.26602 -404.634177) (xy 124.228068 -404.578594)
			(xy 124.197031 -404.518873) (xy 124.173355 -404.455871) (xy 124.157379 -404.39049) (xy 124.149332 -404.323669)
			(xy 124.14933 -404.256364) (xy 124.157373 -404.189542) (xy 124.173345 -404.124161) (xy 124.197017 -404.061157)
			(xy 124.228051 -404.001435) (xy 124.266 -403.945849) (xy 124.287788 -403.920198) (xy 124.293567 -403.91304)
			(xy 124.300092 -403.895859) (xy 124.300488 -403.88667) (xy 124.300488 -403.728682) (xy 124.30085 -403.718503)
			(xy 124.308651 -403.699698) (xy 124.323056 -403.685313) (xy 124.34187 -403.677537) (xy 124.35205 -403.67712)
			(xy 125.06833 -403.67712) (xy 125.078487 -403.677608) (xy 125.097254 -403.685389) (xy 125.111617 -403.699756)
			(xy 125.119394 -403.718524) (xy 125.119892 -403.728682) (xy 125.119892 -403.88667) (xy 125.120318 -403.895855)
			(xy 125.126821 -403.91304) (xy 125.132592 -403.920198) (xy 125.1544 -403.945833) (xy 125.192347 -404.001422)
			(xy 125.223377 -404.061149) (xy 125.247047 -404.124155) (xy 125.263018 -404.189539) (xy 125.27106 -404.256363)
			(xy 125.271058 -404.32367) (xy 125.263012 -404.390493) (xy 125.247038 -404.455876) (xy 125.223364 -404.518882)
			(xy 125.19233 -404.578606) (xy 125.15438 -404.634193) (xy 125.132592 -404.659846) (xy 125.126792 -404.666989)
			(xy 125.12028 -404.684181) (xy 125.119892 -404.693374) (xy 125.119892 -405.186642) (xy 125.120284 -405.195831)
			(xy 125.12681 -405.213015) (xy 125.132592 -405.22017) (xy 125.154373 -405.245827) (xy 125.19232 -405.301414)
			(xy 125.223352 -405.361137) (xy 125.247023 -405.424141) (xy 125.262996 -405.489522) (xy 125.27104 -405.556343)
			(xy 125.271041 -405.623647) (xy 125.262998 -405.690469) (xy 125.247026 -405.755851) (xy 125.223355 -405.818855)
			(xy 125.192325 -405.878578) (xy 125.154378 -405.934165) (xy 125.132592 -405.959818) (xy 125.126804 -405.96697)
			(xy 125.120285 -405.984155) (xy 125.119892 -405.993346) (xy 125.119892 -406.151334) (xy 125.119395 -406.16149)
			(xy 125.111615 -406.180254) (xy 125.097251 -406.194617) (xy 125.078486 -406.202396) (xy 125.06833 -406.202896)
			(xy 124.35205 -406.202896) (xy 124.341886 -406.202396) (xy 124.323099 -406.194634) (xy 124.308713 -406.180272)
			(xy 124.30092 -406.161497) (xy 124.300488 -406.151334) (xy 124.300488 -405.993346) (xy 124.300059 -405.984161)
			(xy 124.293559 -405.966976) (xy 124.287788 -405.959818) (xy 124.265993 -405.934171) (xy 124.228041 -405.878585)
			(xy 124.197005 -405.818861) (xy 124.173331 -405.755856) (xy 124.157357 -405.690473) (xy 124.149312 -405.623649)
			(xy 123.020778 -405.623649) (xy 122.992181 -405.678682) (xy 122.954232 -405.734268) (xy 122.932444 -405.75992)
			(xy 122.92665 -405.767066) (xy 122.920135 -405.784256) (xy 122.919744 -405.793448) (xy 122.919744 -406.286716)
			(xy 122.920159 -406.295902) (xy 122.926671 -406.313086) (xy 122.932444 -406.320244) (xy 122.954201 -406.345922)
			(xy 122.992152 -406.401504) (xy 123.023187 -406.461224) (xy 123.046862 -406.524225) (xy 123.062838 -406.589605)
			(xy 123.070885 -406.656425) (xy 123.070888 -406.723727) (xy 123.070881 -406.723789) (xy 126.348926 -406.723789)
			(xy 126.348929 -406.656363) (xy 126.357008 -406.589421) (xy 126.373048 -406.52393) (xy 126.396818 -406.460832)
			(xy 126.427974 -406.401035) (xy 126.466069 -406.345401) (xy 126.487936 -406.319736) (xy 126.493747 -406.312601)
			(xy 126.500252 -406.295403) (xy 126.500636 -406.286208) (xy 126.500636 -405.793956) (xy 126.500239 -405.784768)
			(xy 126.493715 -405.767584) (xy 126.487936 -405.760428) (xy 126.466067 -405.734767) (xy 126.427976 -405.679132)
			(xy 126.396823 -405.619336) (xy 126.373058 -405.556239) (xy 126.357022 -405.490749) (xy 126.348945 -405.423809)
			(xy 126.348946 -405.356385) (xy 126.357023 -405.289445) (xy 126.37306 -405.223956) (xy 126.396826 -405.160859)
			(xy 126.427979 -405.101062) (xy 126.466071 -405.045429) (xy 126.487936 -405.019764) (xy 126.493735 -405.012621)
			(xy 126.500247 -404.995429) (xy 126.500636 -404.986236) (xy 126.500636 -404.828756) (xy 126.50105 -404.81864)
			(xy 126.508809 -404.799954) (xy 126.523128 -404.785659) (xy 126.541827 -404.777933) (xy 126.551944 -404.777448)
			(xy 127.268224 -404.777448) (xy 127.278328 -404.777964) (xy 127.296997 -404.7857) (xy 127.311289 -404.799986)
			(xy 127.319032 -404.818652) (xy 127.319532 -404.828756) (xy 127.319532 -404.986236) (xy 127.31994 -404.995423)
			(xy 127.326457 -405.012607) (xy 127.332232 -405.019764) (xy 127.354091 -405.045433) (xy 127.392178 -405.101068)
			(xy 127.423327 -405.160864) (xy 127.44709 -405.22396) (xy 127.463125 -405.289448) (xy 127.4712 -405.356386)
			(xy 127.471201 -405.423808) (xy 127.463126 -405.490746) (xy 127.447092 -405.556234) (xy 127.423329 -405.619331)
			(xy 127.42108 -405.623649) (xy 128.549103 -405.623649) (xy 128.549104 -405.556342) (xy 128.557149 -405.489519)
			(xy 128.573124 -405.424136) (xy 128.596799 -405.361131) (xy 128.627835 -405.301407) (xy 128.665787 -405.245822)
			(xy 128.687576 -405.22017) (xy 128.693365 -405.213019) (xy 128.699885 -405.195833) (xy 128.700276 -405.186642)
			(xy 128.700276 -404.693374) (xy 128.699884 -404.684185) (xy 128.693358 -404.667) (xy 128.687576 -404.659846)
			(xy 128.665809 -404.634177) (xy 128.627857 -404.578593) (xy 128.596821 -404.518873) (xy 128.573145 -404.45587)
			(xy 128.557169 -404.39049) (xy 128.549123 -404.323669) (xy 128.549121 -404.256365) (xy 128.557164 -404.189543)
			(xy 128.573135 -404.124161) (xy 128.596807 -404.061158) (xy 128.62784 -404.001435) (xy 128.665789 -403.94585)
			(xy 128.687576 -403.920198) (xy 128.693353 -403.913039) (xy 128.69988 -403.895859) (xy 128.700276 -403.88667)
			(xy 128.700276 -403.728682) (xy 128.70065 -403.718505) (xy 128.708448 -403.699702) (xy 128.722849 -403.685317)
			(xy 128.74166 -403.677539) (xy 128.751838 -403.67712) (xy 129.468118 -403.67712) (xy 129.478275 -403.677618)
			(xy 129.497041 -403.685395) (xy 129.511405 -403.699759) (xy 129.519182 -403.718525) (xy 129.51968 -403.728682)
			(xy 129.51968 -403.88667) (xy 129.520109 -403.895855) (xy 129.52661 -403.913039) (xy 129.53238 -403.920198)
			(xy 129.554189 -403.945833) (xy 129.592136 -404.001422) (xy 129.623167 -404.061148) (xy 129.646838 -404.124155)
			(xy 129.662809 -404.189539) (xy 129.670851 -404.256363) (xy 129.670849 -404.32367) (xy 129.662803 -404.390494)
			(xy 129.646828 -404.455877) (xy 129.623154 -404.518882) (xy 129.592119 -404.578606) (xy 129.554169 -404.634194)
			(xy 129.53238 -404.659846) (xy 129.526579 -404.666988) (xy 129.520068 -404.684181) (xy 129.51968 -404.693374)
			(xy 129.51968 -405.186642) (xy 129.520074 -405.195831) (xy 129.5266 -405.213015) (xy 129.53238 -405.22017)
			(xy 129.554161 -405.245827) (xy 129.592109 -405.301413) (xy 129.623142 -405.361136) (xy 129.646814 -405.42414)
			(xy 129.662787 -405.489522) (xy 129.670831 -405.556343) (xy 129.670832 -405.623648) (xy 129.662788 -405.690469)
			(xy 129.646817 -405.755851) (xy 129.623145 -405.818855) (xy 129.592114 -405.878579) (xy 129.554167 -405.934166)
			(xy 129.53238 -405.959818) (xy 129.526591 -405.966968) (xy 129.520072 -405.984155) (xy 129.51968 -405.993346)
			(xy 129.51968 -406.151334) (xy 129.519195 -406.161492) (xy 129.511413 -406.180258) (xy 129.497045 -406.194622)
			(xy 129.478276 -406.202398) (xy 129.468118 -406.202896) (xy 128.751838 -406.202896) (xy 128.741673 -406.202406)
			(xy 128.722886 -406.19464) (xy 128.708501 -406.180275) (xy 128.700708 -406.161498) (xy 128.700276 -406.151334)
			(xy 128.700276 -405.993346) (xy 128.699849 -405.984161) (xy 128.693347 -405.966976) (xy 128.687576 -405.959818)
			(xy 128.665781 -405.934171) (xy 128.62783 -405.878585) (xy 128.596795 -405.818861) (xy 128.573121 -405.755856)
			(xy 128.557148 -405.690472) (xy 128.549103 -405.623649) (xy 127.42108 -405.623649) (xy 127.392181 -405.679127)
			(xy 127.354095 -405.734762) (xy 127.332232 -405.760428) (xy 127.326433 -405.767571) (xy 127.319922 -405.784763)
			(xy 127.319532 -405.793956) (xy 127.319532 -406.286208) (xy 127.319954 -406.295394) (xy 127.326461 -406.312577)
			(xy 127.332232 -406.319736) (xy 127.354063 -406.345428) (xy 127.392151 -406.401059) (xy 127.423301 -406.460852)
			(xy 127.447066 -406.523945) (xy 127.463103 -406.589431) (xy 127.471181 -406.656366) (xy 127.471183 -406.72373)
			(xy 130.749245 -406.72373) (xy 130.749248 -406.656422) (xy 130.757295 -406.589598) (xy 130.773271 -406.524214)
			(xy 130.796947 -406.461208) (xy 130.827983 -406.401484) (xy 130.865935 -406.345896) (xy 130.887724 -406.320244)
			(xy 130.89353 -406.313105) (xy 130.900038 -406.29591) (xy 130.900424 -406.286716) (xy 130.900424 -405.793448)
			(xy 130.899985 -405.784264) (xy 130.893491 -405.76708) (xy 130.887724 -405.75992) (xy 130.865933 -405.734271)
			(xy 130.827985 -405.678684) (xy 130.796953 -405.61896) (xy 130.773281 -405.555955) (xy 130.757309 -405.490572)
			(xy 130.749265 -405.42375) (xy 130.749265 -405.356444) (xy 130.75731 -405.289622) (xy 130.773283 -405.22424)
			(xy 130.796955 -405.161235) (xy 130.827988 -405.101511) (xy 130.865936 -405.045924) (xy 130.887724 -405.020272)
			(xy 130.893518 -405.013125) (xy 130.900033 -404.995936) (xy 130.900424 -404.986744) (xy 130.900424 -404.828756)
			(xy 130.900786 -404.818596) (xy 130.908601 -404.799838) (xy 130.923016 -404.785515) (xy 130.941823 -404.777822)
			(xy 130.951986 -404.777448) (xy 131.668266 -404.777448) (xy 131.678391 -404.777955) (xy 131.697113 -404.785673)
			(xy 131.711471 -404.799953) (xy 131.71929 -404.818633) (xy 131.719828 -404.828756) (xy 131.719828 -404.986744)
			(xy 131.720211 -404.995934) (xy 131.726743 -405.013119) (xy 131.732528 -405.020272) (xy 131.754313 -405.045927)
			(xy 131.792264 -405.101512) (xy 131.823299 -405.161235) (xy 131.846974 -405.224239) (xy 131.862948 -405.289622)
			(xy 131.870993 -405.356444) (xy 131.870993 -405.42375) (xy 131.862949 -405.490573) (xy 131.846975 -405.555955)
			(xy 131.823302 -405.618959) (xy 131.792267 -405.678683) (xy 131.754316 -405.734268) (xy 131.732528 -405.75992)
			(xy 131.726732 -405.767065) (xy 131.720219 -405.784256) (xy 131.719828 -405.793448) (xy 131.719828 -406.286716)
			(xy 131.720224 -406.295905) (xy 131.726747 -406.313089) (xy 131.732528 -406.320244) (xy 131.754285 -406.345922)
			(xy 131.792237 -406.401504) (xy 131.823274 -406.461223) (xy 131.84695 -406.524225) (xy 131.862926 -406.589604)
			(xy 131.870973 -406.656424) (xy 131.870976 -406.723728) (xy 131.862934 -406.790548) (xy 131.846964 -406.855929)
			(xy 131.823293 -406.918933) (xy 131.792262 -406.978655) (xy 131.754315 -407.03424) (xy 131.732528 -407.059892)
			(xy 131.726744 -407.067045) (xy 131.720224 -407.08423) (xy 131.719828 -407.09342) (xy 131.719828 -407.251408)
			(xy 131.719385 -407.261559) (xy 131.711592 -407.280306) (xy 131.697203 -407.294628) (xy 131.678419 -407.302333)
			(xy 131.668266 -407.302716) (xy 130.951986 -407.302716) (xy 130.941853 -407.302283) (xy 130.923123 -407.294543)
			(xy 130.908766 -407.28024) (xy 130.900955 -407.261539) (xy 130.900424 -407.251408) (xy 130.900424 -407.09342)
			(xy 130.899999 -407.084235) (xy 130.893495 -407.06705) (xy 130.887724 -407.059892) (xy 130.865905 -407.034266)
			(xy 130.827958 -406.978675) (xy 130.796927 -406.918948) (xy 130.773257 -406.85594) (xy 130.757287 -406.790555)
			(xy 130.749245 -406.72373) (xy 127.471183 -406.72373) (xy 127.471183 -406.723786) (xy 127.463111 -406.790722)
			(xy 127.44708 -406.856209) (xy 127.423321 -406.919304) (xy 127.392176 -406.9791) (xy 127.354093 -407.034734)
			(xy 127.332232 -407.0604) (xy 127.326445 -407.067551) (xy 127.319926 -407.084737) (xy 127.319532 -407.093928)
			(xy 127.319532 -407.251408) (xy 127.319022 -407.261513) (xy 127.311288 -407.280185) (xy 127.296999 -407.294479)
			(xy 127.278329 -407.302219) (xy 127.268224 -407.302716) (xy 126.551944 -407.302716) (xy 126.541826 -407.302248)
			(xy 126.523127 -407.294518) (xy 126.508812 -407.280217) (xy 126.501062 -407.261525) (xy 126.500636 -407.251408)
			(xy 126.500636 -407.093928) (xy 126.500204 -407.084743) (xy 126.493705 -407.067559) (xy 126.487936 -407.0604)
			(xy 126.466039 -407.034761) (xy 126.427949 -406.979124) (xy 126.396798 -406.919324) (xy 126.373034 -406.856224)
			(xy 126.357 -406.790731) (xy 126.348926 -406.723789) (xy 123.070881 -406.723789) (xy 123.062847 -406.790548)
			(xy 123.046877 -406.855929) (xy 123.023207 -406.918932) (xy 122.992176 -406.978654) (xy 122.95423 -407.03424)
			(xy 122.932444 -407.059892) (xy 122.926661 -407.067047) (xy 122.92014 -407.08423) (xy 122.919744 -407.09342)
			(xy 122.919744 -407.251408) (xy 122.919222 -407.261512) (xy 122.91149 -407.280182) (xy 122.897205 -407.294475)
			(xy 122.878539 -407.302217) (xy 122.868436 -407.302716) (xy 122.151902 -407.302716) (xy 122.14177 -407.30227)
			(xy 122.123041 -407.294535) (xy 122.108683 -407.280236) (xy 122.100871 -407.261538) (xy 122.10034 -407.251408)
			(xy 122.10034 -407.09342) (xy 122.099911 -407.084235) (xy 122.09341 -407.067051) (xy 122.08764 -407.059892)
			(xy 122.065821 -407.034266) (xy 122.027873 -406.978676) (xy 121.996841 -406.918949) (xy 121.97317 -406.855941)
			(xy 121.957199 -406.790555) (xy 121.949157 -406.72373) (xy 118.67112 -406.72373) (xy 118.67112 -406.723787)
			(xy 118.663047 -406.790724) (xy 118.647013 -406.856212) (xy 118.62325 -406.919308) (xy 118.5921 -406.979103)
			(xy 118.554012 -407.034736) (xy 118.532148 -407.0604) (xy 118.526362 -407.067553) (xy 118.519843 -407.084738)
			(xy 118.519448 -407.093928) (xy 118.519448 -407.251408) (xy 118.518922 -407.261511) (xy 118.511191 -407.28018)
			(xy 118.496907 -407.294473) (xy 118.478243 -407.302216) (xy 118.46814 -407.302716) (xy 117.75186 -407.302716)
			(xy 117.741751 -407.302248) (xy 117.723075 -407.2945) (xy 117.708782 -407.280198) (xy 117.701046 -407.261518)
			(xy 117.700552 -407.251408) (xy 117.700552 -407.093928) (xy 117.700117 -407.084744) (xy 117.693619 -407.06756)
			(xy 117.687852 -407.0604) (xy 117.665955 -407.034762) (xy 117.627864 -406.979124) (xy 117.596711 -406.919325)
			(xy 117.572947 -406.856225) (xy 117.556912 -406.790732) (xy 117.548838 -406.72379) (xy 92.270826 -406.72379)
			(xy 92.262793 -406.790546) (xy 92.246825 -406.855926) (xy 92.223158 -406.918929) (xy 92.192131 -406.978652)
			(xy 92.154188 -407.034239) (xy 92.132404 -407.059892) (xy 92.126629 -407.067052) (xy 92.120101 -407.084231)
			(xy 92.119704 -407.09342) (xy 92.119704 -407.251408) (xy 92.119285 -407.261562) (xy 92.111487 -407.280314)
			(xy 92.09709 -407.294637) (xy 92.078298 -407.302337) (xy 92.068142 -407.302716) (xy 91.351862 -407.302716)
			(xy 91.341727 -407.302303) (xy 91.322997 -407.294555) (xy 91.308641 -407.280246) (xy 91.30083 -407.261541)
			(xy 91.3003 -407.251408) (xy 91.3003 -407.09342) (xy 91.29988 -407.084234) (xy 91.293373 -407.067049)
			(xy 91.2876 -407.059892) (xy 91.265782 -407.034265) (xy 91.227837 -406.978674) (xy 91.196807 -406.918947)
			(xy 91.173138 -406.855939) (xy 91.157168 -406.790554) (xy 91.149127 -406.723729) (xy 87.871065 -406.723729)
			(xy 87.871065 -406.723786) (xy 87.862993 -406.790722) (xy 87.846961 -406.85621) (xy 87.823201 -406.919305)
			(xy 87.792054 -406.9791) (xy 87.75397 -407.034735) (xy 87.732108 -407.0604) (xy 87.72633 -407.067558)
			(xy 87.719804 -407.084739) (xy 87.719408 -407.093928) (xy 87.719408 -407.251408) (xy 87.718921 -407.261516)
			(xy 87.711183 -407.280193) (xy 87.696886 -407.294487) (xy 87.678208 -407.302223) (xy 87.6681 -407.302716)
			(xy 86.95182 -407.302716) (xy 86.941701 -407.302268) (xy 86.923001 -407.29453) (xy 86.908686 -407.280223)
			(xy 86.900937 -407.261527) (xy 86.900512 -407.251408) (xy 86.900512 -407.093928) (xy 86.900086 -407.084743)
			(xy 86.893583 -407.067558) (xy 86.887812 -407.0604) (xy 86.865916 -407.034761) (xy 86.827828 -406.979123)
			(xy 86.796678 -406.919323) (xy 86.772915 -406.856223) (xy 86.756881 -406.790731) (xy 86.748808 -406.723789)
			(xy 83.470763 -406.723789) (xy 83.462728 -406.790549) (xy 83.446757 -406.85593) (xy 83.423086 -406.918933)
			(xy 83.392055 -406.978655) (xy 83.354107 -407.03424) (xy 83.33232 -407.059892) (xy 83.326547 -407.067054)
			(xy 83.320017 -407.084231) (xy 83.31962 -407.09342) (xy 83.31962 -407.251408) (xy 83.319185 -407.26156)
			(xy 83.311391 -407.280309) (xy 83.296998 -407.294631) (xy 83.278212 -407.302334) (xy 83.268058 -407.302716)
			(xy 82.551778 -407.302716) (xy 82.541644 -407.30229) (xy 82.522914 -407.294547) (xy 82.508557 -407.280242)
			(xy 82.500747 -407.26154) (xy 82.500216 -407.251408) (xy 82.500216 -407.09342) (xy 82.499792 -407.084234)
			(xy 82.493288 -407.06705) (xy 82.487516 -407.059892) (xy 82.465698 -407.034265) (xy 82.427751 -406.978675)
			(xy 82.396721 -406.918947) (xy 82.373051 -406.85594) (xy 82.35708 -406.790555) (xy 82.349039 -406.72373)
			(xy 79.070977 -406.72373) (xy 79.070977 -406.723786) (xy 79.062905 -406.790722) (xy 79.046874 -406.856209)
			(xy 79.023114 -406.919304) (xy 78.991969 -406.9791) (xy 78.953885 -407.034734) (xy 78.932024 -407.0604)
			(xy 78.926248 -407.06756) (xy 78.91972 -407.084739) (xy 78.919324 -407.093928) (xy 78.919324 -407.251408)
			(xy 78.918822 -407.261514) (xy 78.911086 -407.280188) (xy 78.896795 -407.294482) (xy 78.878122 -407.30222)
			(xy 78.868016 -407.302716) (xy 78.151736 -407.302716) (xy 78.141618 -407.302255) (xy 78.122918 -407.294521)
			(xy 78.108603 -407.280219) (xy 78.100854 -407.261526) (xy 78.100428 -407.251408) (xy 78.100428 -407.093928)
			(xy 78.099998 -407.084743) (xy 78.093497 -407.067559) (xy 78.087728 -407.0604) (xy 78.065832 -407.034761)
			(xy 78.027742 -406.979124) (xy 77.996591 -406.919324) (xy 77.972828 -406.856224) (xy 77.956793 -406.790731)
			(xy 77.94872 -406.723789) (xy 74.670675 -406.723789) (xy 74.662641 -406.790548) (xy 74.64667 -406.855929)
			(xy 74.623 -406.918932) (xy 74.591969 -406.978655) (xy 74.554022 -407.03424) (xy 74.532236 -407.059892)
			(xy 74.526453 -407.067046) (xy 74.519932 -407.08423) (xy 74.519536 -407.09342) (xy 74.519536 -407.251408)
			(xy 74.519085 -407.261558) (xy 74.511294 -407.280304) (xy 74.496907 -407.294625) (xy 74.478126 -407.302331)
			(xy 74.467974 -407.302716) (xy 73.751694 -407.302716) (xy 73.741562 -407.302277) (xy 73.722832 -407.294539)
			(xy 73.708474 -407.280238) (xy 73.700663 -407.261538) (xy 73.700132 -407.251408) (xy 73.700132 -407.09342)
			(xy 73.699705 -407.084235) (xy 73.693202 -407.067051) (xy 73.687432 -407.059892) (xy 73.665613 -407.034266)
			(xy 73.627666 -406.978675) (xy 73.596634 -406.918948) (xy 73.572963 -406.85594) (xy 73.556993 -406.790555)
			(xy 73.548951 -406.72373) (xy 66.525648 -406.72373) (xy 66.525648 -409.523886) (xy 71.34879 -409.523886)
			(xy 71.348793 -409.45646) (xy 71.356872 -409.389519) (xy 71.372911 -409.324028) (xy 71.396679 -409.26093)
			(xy 71.427834 -409.201133) (xy 71.465926 -409.145497) (xy 71.487792 -409.119832) (xy 71.493599 -409.112694)
			(xy 71.500108 -409.095498) (xy 71.500492 -409.086304) (xy 71.500492 -408.594052) (xy 71.500059 -408.584867)
			(xy 71.493561 -408.567682) (xy 71.487792 -408.560524) (xy 71.46592 -408.534865) (xy 71.427833 -408.479229)
			(xy 71.396683 -408.419432) (xy 71.372919 -408.356335) (xy 71.356885 -408.290845) (xy 71.348809 -408.223906)
			(xy 71.34881 -408.156482) (xy 71.356887 -408.089543) (xy 71.372923 -408.024054) (xy 71.396688 -407.960957)
			(xy 71.427839 -407.90116) (xy 71.465928 -407.845525) (xy 71.487792 -407.81986) (xy 71.493587 -407.812714)
			(xy 71.500103 -407.795524) (xy 71.500492 -407.786332) (xy 71.500492 -407.628852) (xy 71.500946 -407.618741)
			(xy 71.508698 -407.600063) (xy 71.523004 -407.585771) (xy 71.541689 -407.578036) (xy 71.5518 -407.577544)
			(xy 72.26808 -407.577544) (xy 72.278181 -407.5781) (xy 72.296848 -407.585821) (xy 72.311141 -407.600095)
			(xy 72.318887 -407.618752) (xy 72.319388 -407.628852) (xy 72.319388 -407.786332) (xy 72.319785 -407.795521)
			(xy 72.326308 -407.812705) (xy 72.332088 -407.81986) (xy 72.353945 -407.845532) (xy 72.392034 -407.901165)
			(xy 72.423186 -407.96096) (xy 72.446951 -408.024056) (xy 72.462988 -408.089545) (xy 72.471064 -408.156482)
			(xy 72.471065 -408.223906) (xy 72.46299 -408.290844) (xy 72.446955 -408.356332) (xy 72.423191 -408.419429)
			(xy 72.39204 -408.479225) (xy 72.353952 -408.534859) (xy 72.332088 -408.560524) (xy 72.326297 -408.567673)
			(xy 72.31978 -408.584861) (xy 72.319388 -408.594052) (xy 72.319388 -409.086304) (xy 72.319799 -409.095491)
			(xy 72.326313 -409.112675) (xy 72.332088 -409.119832) (xy 72.353917 -409.145526) (xy 72.392008 -409.201156)
			(xy 72.423161 -409.260948) (xy 72.446927 -409.324042) (xy 72.462966 -409.389527) (xy 72.471045 -409.456462)
			(xy 72.471048 -409.523884) (xy 72.462975 -409.59082) (xy 72.446943 -409.656307) (xy 72.423183 -409.719402)
			(xy 72.392035 -409.779197) (xy 72.35395 -409.834831) (xy 72.332088 -409.860496) (xy 72.326309 -409.867654)
			(xy 72.319784 -409.884835) (xy 72.319388 -409.894024) (xy 72.319388 -410.051504) (xy 72.318987 -410.061628)
			(xy 72.311235 -410.080334) (xy 72.296914 -410.094649) (xy 72.278204 -410.102392) (xy 72.26808 -410.102812)
			(xy 71.5518 -410.102812) (xy 71.541693 -410.102315) (xy 71.523017 -410.09458) (xy 71.508723 -410.080286)
			(xy 71.500986 -410.061611) (xy 71.500492 -410.051504) (xy 71.500492 -409.894024) (xy 71.500072 -409.884838)
			(xy 71.493565 -409.867653) (xy 71.487792 -409.860496) (xy 71.465893 -409.83486) (xy 71.427806 -409.779221)
			(xy 71.396657 -409.719421) (xy 71.372895 -409.65632) (xy 71.356863 -409.590827) (xy 71.34879 -409.523886)
			(xy 66.525648 -409.523886) (xy 66.525648 -410.623641) (xy 73.548963 -410.623641) (xy 73.548964 -410.556335)
			(xy 73.55701 -410.489511) (xy 73.572984 -410.424128) (xy 73.596658 -410.361123) (xy 73.627693 -410.301399)
			(xy 73.665643 -410.245812) (xy 73.687432 -410.22016) (xy 73.693232 -410.213017) (xy 73.699744 -410.195825)
			(xy 73.700132 -410.186632) (xy 73.700132 -409.693364) (xy 73.699732 -409.684176) (xy 73.69321 -409.666992)
			(xy 73.687432 -409.659836) (xy 73.665656 -409.634174) (xy 73.627707 -409.578589) (xy 73.596674 -409.518867)
			(xy 73.573001 -409.455863) (xy 73.557027 -409.390482) (xy 73.548982 -409.323661) (xy 73.548981 -409.256357)
			(xy 73.557024 -409.189535) (xy 73.572995 -409.124154) (xy 73.596667 -409.06115) (xy 73.627698 -409.001427)
			(xy 73.665645 -408.94584) (xy 73.687432 -408.920188) (xy 73.69322 -408.913037) (xy 73.699739 -408.895851)
			(xy 73.700132 -408.88666) (xy 73.700132 -408.728672) (xy 73.700499 -408.718512) (xy 73.70831 -408.699753)
			(xy 73.722724 -408.685429) (xy 73.741532 -408.677736) (xy 73.751694 -408.677364) (xy 74.467974 -408.677364)
			(xy 74.478102 -408.677848) (xy 74.496827 -408.685572) (xy 74.511185 -408.69986) (xy 74.519001 -408.718546)
			(xy 74.519536 -408.728672) (xy 74.519536 -408.88666) (xy 74.51998 -408.895843) (xy 74.526472 -408.913027)
			(xy 74.532236 -408.920188) (xy 74.554036 -408.94583) (xy 74.591986 -409.001418) (xy 74.62302 -409.061142)
			(xy 74.646694 -409.124148) (xy 74.662666 -409.189532) (xy 74.67071 -409.256356) (xy 74.670709 -409.323662)
			(xy 74.662663 -409.390486) (xy 74.646688 -409.455869) (xy 74.623013 -409.518874) (xy 74.620439 -409.523827)
			(xy 75.749085 -409.523827) (xy 75.749088 -409.456519) (xy 75.757137 -409.389693) (xy 75.773115 -409.324308)
			(xy 75.796793 -409.261302) (xy 75.827833 -409.201578) (xy 75.865789 -409.145992) (xy 75.88758 -409.12034)
			(xy 75.893382 -409.113199) (xy 75.899894 -409.096005) (xy 75.90028 -409.086812) (xy 75.90028 -408.593544)
			(xy 75.899853 -408.584358) (xy 75.893352 -408.567174) (xy 75.88758 -408.560016) (xy 75.865783 -408.534371)
			(xy 75.827832 -408.478784) (xy 75.796797 -408.41906) (xy 75.773123 -408.356055) (xy 75.757149 -408.290671)
			(xy 75.749105 -408.223847) (xy 75.749106 -408.156541) (xy 75.757151 -408.089717) (xy 75.773126 -408.024334)
			(xy 75.796802 -407.961329) (xy 75.827838 -407.901605) (xy 75.865791 -407.84602) (xy 75.88758 -407.820368)
			(xy 75.89337 -407.813218) (xy 75.899889 -407.796031) (xy 75.90028 -407.78684) (xy 75.90028 -407.628852)
			(xy 75.900682 -407.618697) (xy 75.90849 -407.599948) (xy 75.922892 -407.585627) (xy 75.941685 -407.577925)
			(xy 75.951842 -407.577544) (xy 76.668122 -407.577544) (xy 76.678251 -407.578008) (xy 76.696973 -407.585744)
			(xy 76.711329 -407.600037) (xy 76.719147 -407.618726) (xy 76.719684 -407.628852) (xy 76.719684 -407.78684)
			(xy 76.720078 -407.796029) (xy 76.726603 -407.813213) (xy 76.732384 -407.820368) (xy 76.754163 -407.846027)
			(xy 76.792111 -407.901613) (xy 76.823143 -407.961336) (xy 76.846815 -408.024339) (xy 76.862788 -408.08972)
			(xy 76.870833 -408.156542) (xy 76.870833 -408.223846) (xy 76.86279 -408.290668) (xy 76.846819 -408.356049)
			(xy 76.823148 -408.419053) (xy 76.792117 -408.478777) (xy 76.754171 -408.534364) (xy 76.732384 -408.560016)
			(xy 76.726596 -408.567167) (xy 76.720077 -408.584353) (xy 76.719684 -408.593544) (xy 76.719684 -409.086812)
			(xy 76.720092 -409.095999) (xy 76.726607 -409.113184) (xy 76.732384 -409.12034) (xy 76.754135 -409.146022)
			(xy 76.792084 -409.201605) (xy 76.823117 -409.261324) (xy 76.846791 -409.324325) (xy 76.862766 -409.389703)
			(xy 76.870812 -409.456522) (xy 76.870816 -409.523824) (xy 76.862775 -409.590644) (xy 76.846807 -409.656023)
			(xy 76.823139 -409.719026) (xy 76.792112 -409.778749) (xy 76.754169 -409.834335) (xy 76.732384 -409.859988)
			(xy 76.726566 -409.867118) (xy 76.720065 -409.88432) (xy 76.719684 -409.893516) (xy 76.719684 -410.051504)
			(xy 76.719281 -410.06166) (xy 76.711481 -410.080416) (xy 76.697079 -410.09474) (xy 76.678281 -410.102436)
			(xy 76.668122 -410.102812) (xy 75.951842 -410.102812) (xy 75.941724 -410.10224) (xy 75.923014 -410.094536)
			(xy 75.908658 -410.080276) (xy 75.900828 -410.061618) (xy 75.90028 -410.051504) (xy 75.90028 -409.893516)
			(xy 75.899867 -409.884329) (xy 75.893356 -409.867144) (xy 75.88758 -409.859988) (xy 75.865756 -409.834365)
			(xy 75.827805 -409.778776) (xy 75.796771 -409.719048) (xy 75.773099 -409.65604) (xy 75.757127 -409.590654)
			(xy 75.749085 -409.523827) (xy 74.620439 -409.523827) (xy 74.591977 -409.578598) (xy 74.554025 -409.634184)
			(xy 74.532236 -409.659836) (xy 74.526434 -409.666977) (xy 74.519924 -409.684171) (xy 74.519536 -409.693364)
			(xy 74.519536 -410.186632) (xy 74.519945 -410.195819) (xy 74.526461 -410.213002) (xy 74.532236 -410.22016)
			(xy 74.554009 -410.245825) (xy 74.59196 -410.301409) (xy 74.622995 -410.36113) (xy 74.64667 -410.424133)
			(xy 74.662644 -410.489514) (xy 74.67069 -410.556336) (xy 74.670692 -410.62364) (xy 74.670685 -410.623701)
			(xy 77.948731 -410.623701) (xy 77.948732 -410.556275) (xy 77.95681 -410.489335) (xy 77.972848 -410.423845)
			(xy 77.996615 -410.360747) (xy 78.02777 -410.300951) (xy 78.065862 -410.245317) (xy 78.087728 -410.219652)
			(xy 78.093531 -410.212512) (xy 78.100041 -410.195317) (xy 78.100428 -410.186124) (xy 78.100428 -409.693872)
			(xy 78.100025 -409.684684) (xy 78.093506 -409.6675) (xy 78.087728 -409.660344) (xy 78.065875 -409.63467)
			(xy 78.027784 -409.579037) (xy 77.996631 -409.519242) (xy 77.972865 -409.456147) (xy 77.956828 -409.390658)
			(xy 77.948751 -409.323721) (xy 77.94875 -409.256297) (xy 77.956825 -409.189359) (xy 77.97286 -409.123871)
			(xy 77.996624 -409.060774) (xy 78.027775 -409.000979) (xy 78.065864 -408.945345) (xy 78.087728 -408.91968)
			(xy 78.093519 -408.912531) (xy 78.100036 -408.895343) (xy 78.100428 -408.886152) (xy 78.100428 -408.728672)
			(xy 78.100794 -408.718544) (xy 78.108556 -408.699835) (xy 78.122888 -408.68552) (xy 78.141608 -408.677781)
			(xy 78.151736 -408.677364) (xy 78.868016 -408.677364) (xy 78.878121 -408.677871) (xy 78.896793 -408.685608)
			(xy 78.911086 -408.699897) (xy 78.918826 -408.718567) (xy 78.919324 -408.728672) (xy 78.919324 -408.886152)
			(xy 78.919752 -408.895337) (xy 78.926253 -408.912522) (xy 78.932024 -408.91968) (xy 78.953899 -408.945336)
			(xy 78.991986 -409.000972) (xy 79.023135 -409.06077) (xy 79.046897 -409.123868) (xy 79.062931 -409.189358)
			(xy 79.071005 -409.256297) (xy 79.071004 -409.323721) (xy 79.062928 -409.39066) (xy 79.046892 -409.456149)
			(xy 79.023127 -409.519246) (xy 79.02071 -409.523886) (xy 80.148878 -409.523886) (xy 80.148881 -409.45646)
			(xy 80.15696 -409.38952) (xy 80.172999 -409.324029) (xy 80.196766 -409.260931) (xy 80.227919 -409.201133)
			(xy 80.266011 -409.145498) (xy 80.287876 -409.119832) (xy 80.293681 -409.112693) (xy 80.300191 -409.095498)
			(xy 80.300576 -409.086304) (xy 80.300576 -408.594052) (xy 80.300146 -408.584867) (xy 80.293647 -408.567682)
			(xy 80.287876 -408.560524) (xy 80.266005 -408.534865) (xy 80.227918 -408.479229) (xy 80.196769 -408.419432)
			(xy 80.173006 -408.356334) (xy 80.156972 -408.290844) (xy 80.148897 -408.223906) (xy 80.148898 -408.156482)
			(xy 80.156974 -408.089544) (xy 80.17301 -408.024055) (xy 80.196774 -407.960957) (xy 80.227924 -407.901161)
			(xy 80.266012 -407.845526) (xy 80.287876 -407.81986) (xy 80.293669 -407.812712) (xy 80.300187 -407.795524)
			(xy 80.300576 -407.786332) (xy 80.300576 -407.628852) (xy 80.301045 -407.618743) (xy 80.308794 -407.600069)
			(xy 80.323095 -407.585776) (xy 80.341775 -407.578039) (xy 80.351884 -407.577544) (xy 81.068164 -407.577544)
			(xy 81.078264 -407.578113) (xy 81.09693 -407.585829) (xy 81.111224 -407.600099) (xy 81.11897 -407.618753)
			(xy 81.119472 -407.628852) (xy 81.119472 -407.786332) (xy 81.119873 -407.79552) (xy 81.126394 -407.812704)
			(xy 81.132172 -407.81986) (xy 81.154029 -407.845531) (xy 81.19212 -407.901164) (xy 81.223273 -407.960959)
			(xy 81.247038 -408.024056) (xy 81.263075 -408.089544) (xy 81.271152 -408.156482) (xy 81.271153 -408.223906)
			(xy 81.263077 -408.290844) (xy 81.247042 -408.356333) (xy 81.223277 -408.41943) (xy 81.192126 -408.479225)
			(xy 81.154036 -408.534859) (xy 81.132172 -408.560524) (xy 81.126379 -408.567672) (xy 81.119863 -408.58486)
			(xy 81.119472 -408.594052) (xy 81.119472 -409.086304) (xy 81.119886 -409.095491) (xy 81.126398 -409.112675)
			(xy 81.132172 -409.119832) (xy 81.154002 -409.145526) (xy 81.192093 -409.201156) (xy 81.223247 -409.260948)
			(xy 81.247014 -409.324041) (xy 81.263053 -409.389527) (xy 81.271132 -409.456462) (xy 81.271136 -409.523884)
			(xy 81.263063 -409.59082) (xy 81.247031 -409.656307) (xy 81.223269 -409.719403) (xy 81.192121 -409.779198)
			(xy 81.154035 -409.834831) (xy 81.132172 -409.860496) (xy 81.126391 -409.867652) (xy 81.119868 -409.884834)
			(xy 81.119472 -409.894024) (xy 81.119472 -410.051504) (xy 81.119086 -410.06163) (xy 81.111332 -410.080339)
			(xy 81.097006 -410.094654) (xy 81.078291 -410.102394) (xy 81.068164 -410.102812) (xy 80.351884 -410.102812)
			(xy 80.341776 -410.102328) (xy 80.3231 -410.094587) (xy 80.308806 -410.08029) (xy 80.30107 -410.061612)
			(xy 80.300576 -410.051504) (xy 80.300576 -409.894024) (xy 80.30016 -409.884837) (xy 80.293651 -409.867653)
			(xy 80.287876 -409.860496) (xy 80.265978 -409.83486) (xy 80.227891 -409.77922) (xy 80.196744 -409.71942)
			(xy 80.172983 -409.656319) (xy 80.15695 -409.590827) (xy 80.148878 -409.523886) (xy 79.02071 -409.523886)
			(xy 78.991976 -409.579043) (xy 78.953888 -409.634678) (xy 78.932024 -409.660344) (xy 78.926229 -409.667491)
			(xy 78.919713 -409.68468) (xy 78.919324 -409.693872) (xy 78.919324 -410.186124) (xy 78.919717 -410.195313)
			(xy 78.926242 -410.212497) (xy 78.932024 -410.219652) (xy 78.953871 -410.245331) (xy 78.991959 -410.300964)
			(xy 79.023109 -410.360758) (xy 79.046873 -410.423853) (xy 79.062909 -410.489341) (xy 79.070986 -410.556277)
			(xy 79.070987 -410.623641) (xy 82.349051 -410.623641) (xy 82.349052 -410.556335) (xy 82.357097 -410.489512)
			(xy 82.373071 -410.424129) (xy 82.396745 -410.361124) (xy 82.427779 -410.3014) (xy 82.465728 -410.245812)
			(xy 82.487516 -410.22016) (xy 82.493314 -410.213016) (xy 82.499827 -410.195824) (xy 82.500216 -410.186632)
			(xy 82.500216 -409.693364) (xy 82.49982 -409.684175) (xy 82.493296 -409.666991) (xy 82.487516 -409.659836)
			(xy 82.465741 -409.634174) (xy 82.427793 -409.578588) (xy 82.39676 -409.518866) (xy 82.373088 -409.455863)
			(xy 82.357115 -409.390482) (xy 82.34907 -409.323661) (xy 82.349069 -409.256357) (xy 82.357112 -409.189536)
			(xy 82.373083 -409.124155) (xy 82.396753 -409.061151) (xy 82.427784 -409.001427) (xy 82.46573 -408.94584)
			(xy 82.487516 -408.920188) (xy 82.493302 -408.913035) (xy 82.499822 -408.89585) (xy 82.500216 -408.88666)
			(xy 82.500216 -408.728672) (xy 82.500599 -408.718514) (xy 82.508407 -408.699758) (xy 82.522815 -408.685435)
			(xy 82.541618 -408.677739) (xy 82.551778 -408.677364) (xy 83.268058 -408.677364) (xy 83.278185 -408.677862)
			(xy 83.29691 -408.68558) (xy 83.311268 -408.699864) (xy 83.319085 -408.718548) (xy 83.31962 -408.728672)
			(xy 83.31962 -408.88666) (xy 83.320045 -408.895846) (xy 83.326548 -408.913031) (xy 83.33232 -408.920188)
			(xy 83.354121 -408.94583) (xy 83.392072 -409.001417) (xy 83.423107 -409.061141) (xy 83.446781 -409.124147)
			(xy 83.462754 -409.189531) (xy 83.470798 -409.256356) (xy 83.470797 -409.323662) (xy 83.462751 -409.390487)
			(xy 83.446775 -409.45587) (xy 83.423099 -409.518875) (xy 83.420495 -409.523886) (xy 84.548669 -409.523886)
			(xy 84.548672 -409.45646) (xy 84.556751 -409.38952) (xy 84.572789 -409.324029) (xy 84.596556 -409.260931)
			(xy 84.627709 -409.201134) (xy 84.665799 -409.145498) (xy 84.687664 -409.119832) (xy 84.69348 -409.112701)
			(xy 84.699981 -409.095499) (xy 84.700364 -409.086304) (xy 84.700364 -408.594052) (xy 84.699915 -408.584869)
			(xy 84.693427 -408.567685) (xy 84.687664 -408.560524) (xy 84.665793 -408.534865) (xy 84.627707 -408.479228)
			(xy 84.596559 -408.419431) (xy 84.572797 -408.356334) (xy 84.556763 -408.290844) (xy 84.548688 -408.223906)
			(xy 84.548689 -408.156482) (xy 84.556765 -408.089544) (xy 84.5728 -408.024055) (xy 84.596564 -407.960958)
			(xy 84.627714 -407.901161) (xy 84.665801 -407.845526) (xy 84.687664 -407.81986) (xy 84.693468 -407.81272)
			(xy 84.699976 -407.795525) (xy 84.700364 -407.786332) (xy 84.700364 -407.628852) (xy 84.700845 -407.618745)
			(xy 84.708592 -407.600072) (xy 84.722889 -407.585781) (xy 84.741564 -407.578041) (xy 84.751672 -407.577544)
			(xy 85.467952 -407.577544) (xy 85.478051 -407.578123) (xy 85.496717 -407.585835) (xy 85.511012 -407.600102)
			(xy 85.518758 -407.618754) (xy 85.51926 -407.628852) (xy 85.51926 -407.786332) (xy 85.519664 -407.79552)
			(xy 85.526183 -407.812703) (xy 85.53196 -407.81986) (xy 85.553818 -407.845531) (xy 85.591909 -407.901164)
			(xy 85.623062 -407.960959) (xy 85.646829 -408.024055) (xy 85.662866 -408.089544) (xy 85.670943 -408.156482)
			(xy 85.670944 -408.223906) (xy 85.662868 -408.290844) (xy 85.646832 -408.356333) (xy 85.623067 -408.41943)
			(xy 85.591915 -408.479226) (xy 85.553825 -408.534859) (xy 85.53196 -408.560524) (xy 85.526166 -408.567671)
			(xy 85.519651 -408.58486) (xy 85.51926 -408.594052) (xy 85.51926 -409.086304) (xy 85.519677 -409.09549)
			(xy 85.526187 -409.112674) (xy 85.53196 -409.119832) (xy 85.55379 -409.145526) (xy 85.591882 -409.201155)
			(xy 85.623037 -409.260947) (xy 85.646805 -409.32404) (xy 85.662844 -409.389526) (xy 85.670923 -409.456462)
			(xy 85.670927 -409.523884) (xy 85.662854 -409.59082) (xy 85.646821 -409.656308) (xy 85.623059 -409.719403)
			(xy 85.59191 -409.779198) (xy 85.553823 -409.834831) (xy 85.53196 -409.860496) (xy 85.526178 -409.867651)
			(xy 85.519655 -409.884834) (xy 85.51926 -409.894024) (xy 85.51926 -410.051504) (xy 85.518886 -410.061632)
			(xy 85.511129 -410.080343) (xy 85.496799 -410.094659) (xy 85.47808 -410.102396) (xy 85.467952 -410.102812)
			(xy 84.751672 -410.102812) (xy 84.741563 -410.102338) (xy 84.722886 -410.094594) (xy 84.708593 -410.080293)
			(xy 84.700857 -410.061613) (xy 84.700364 -410.051504) (xy 84.700364 -409.894024) (xy 84.699928 -409.88484)
			(xy 84.693431 -409.867656) (xy 84.687664 -409.860496) (xy 84.665766 -409.834859) (xy 84.627681 -409.77922)
			(xy 84.596534 -409.719419) (xy 84.572773 -409.656319) (xy 84.556741 -409.590827) (xy 84.548669 -409.523886)
			(xy 83.420495 -409.523886) (xy 83.392063 -409.578599) (xy 83.35411 -409.634184) (xy 83.33232 -409.659836)
			(xy 83.326528 -409.666985) (xy 83.32001 -409.684172) (xy 83.31962 -409.693364) (xy 83.31962 -410.186632)
			(xy 83.32001 -410.195821) (xy 83.326537 -410.213006) (xy 83.33232 -410.22016) (xy 83.354093 -410.245825)
			(xy 83.392045 -410.301408) (xy 83.423081 -410.36113) (xy 83.446757 -410.424133) (xy 83.462732 -410.489514)
			(xy 83.470778 -410.556336) (xy 83.47078 -410.62364) (xy 83.470773 -410.623701) (xy 86.748819 -410.623701)
			(xy 86.74882 -410.556275) (xy 86.756898 -410.489336) (xy 86.772936 -410.423846) (xy 86.796702 -410.360748)
			(xy 86.827855 -410.300952) (xy 86.865947 -410.245317) (xy 86.887812 -410.219652) (xy 86.893613 -410.21251)
			(xy 86.900125 -410.195317) (xy 86.900512 -410.186124) (xy 86.900512 -409.693872) (xy 86.900113 -409.684684)
			(xy 86.893591 -409.6675) (xy 86.887812 -409.660344) (xy 86.865959 -409.634669) (xy 86.82787 -409.579036)
			(xy 86.796718 -409.519242) (xy 86.772952 -409.456146) (xy 86.756916 -409.390658) (xy 86.748839 -409.32372)
			(xy 86.748837 -409.256298) (xy 86.756912 -409.18936) (xy 86.772947 -409.123871) (xy 86.79671 -409.060775)
			(xy 86.82786 -409.000979) (xy 86.865948 -408.945345) (xy 86.887812 -408.91968) (xy 86.893601 -408.912529)
			(xy 86.90012 -408.895343) (xy 86.900512 -408.886152) (xy 86.900512 -408.728672) (xy 86.900962 -408.71856)
			(xy 86.908711 -408.699879) (xy 86.923019 -408.685585) (xy 86.941708 -408.677853) (xy 86.95182 -408.677364)
			(xy 87.6681 -408.677364) (xy 87.678204 -408.677884) (xy 87.696876 -408.685615) (xy 87.711169 -408.699901)
			(xy 87.71891 -408.718568) (xy 87.719408 -408.728672) (xy 87.719408 -408.886152) (xy 87.719839 -408.895337)
			(xy 87.726338 -408.912522) (xy 87.732108 -408.91968) (xy 87.753983 -408.945336) (xy 87.792071 -409.000972)
			(xy 87.823221 -409.060769) (xy 87.846984 -409.123867) (xy 87.863019 -409.189358) (xy 87.871093 -409.256297)
			(xy 87.871092 -409.323721) (xy 87.863015 -409.39066) (xy 87.846979 -409.45615) (xy 87.823214 -409.519247)
			(xy 87.792062 -409.579044) (xy 87.753972 -409.634679) (xy 87.732108 -409.660344) (xy 87.726311 -409.667489)
			(xy 87.719796 -409.68468) (xy 87.719408 -409.693872) (xy 87.719408 -410.186124) (xy 87.719805 -410.195313)
			(xy 87.726328 -410.212497) (xy 87.732108 -410.219652) (xy 87.753956 -410.24533) (xy 87.792045 -410.300963)
			(xy 87.823196 -410.360758) (xy 87.84696 -410.423853) (xy 87.862997 -410.48934) (xy 87.871074 -410.556277)
			(xy 87.871075 -410.623641) (xy 91.149138 -410.623641) (xy 91.14914 -410.556335) (xy 91.157185 -410.489512)
			(xy 91.173158 -410.42413) (xy 91.196831 -410.361125) (xy 91.227864 -410.3014) (xy 91.265813 -410.245813)
			(xy 91.2876 -410.22016) (xy 91.293396 -410.213014) (xy 91.299911 -410.195824) (xy 91.3003 -410.186632)
			(xy 91.3003 -409.693364) (xy 91.299907 -409.684175) (xy 91.293382 -409.666991) (xy 91.2876 -409.659836)
			(xy 91.265825 -409.634174) (xy 91.227879 -409.578588) (xy 91.196847 -409.518865) (xy 91.173175 -409.455862)
			(xy 91.157203 -409.390482) (xy 91.149158 -409.323661) (xy 91.149157 -409.256357) (xy 91.157199 -409.189536)
			(xy 91.17317 -409.124155) (xy 91.19684 -409.061151) (xy 91.227869 -409.001428) (xy 91.265814 -408.945841)
			(xy 91.2876 -408.920188) (xy 91.293384 -408.913034) (xy 91.299906 -408.89585) (xy 91.3003 -408.88666)
			(xy 91.3003 -408.728672) (xy 91.300699 -408.718516) (xy 91.308503 -408.699763) (xy 91.322907 -408.685441)
			(xy 91.341704 -408.677742) (xy 91.351862 -408.677364) (xy 92.068142 -408.677364) (xy 92.078274 -408.677793)
			(xy 92.097001 -408.685539) (xy 92.111357 -408.699843) (xy 92.11917 -408.718542) (xy 92.119704 -408.728672)
			(xy 92.119704 -408.88666) (xy 92.120132 -408.895845) (xy 92.126633 -408.91303) (xy 92.132404 -408.920188)
			(xy 92.154202 -408.945831) (xy 92.192148 -409.00142) (xy 92.223178 -409.061145) (xy 92.246848 -409.124151)
			(xy 92.262819 -409.189534) (xy 92.270862 -409.256356) (xy 92.270861 -409.323662) (xy 92.262816 -409.390484)
			(xy 92.246843 -409.455867) (xy 92.223171 -409.518871) (xy 92.220596 -409.523827) (xy 115.349227 -409.523827)
			(xy 115.349231 -409.456519) (xy 115.357278 -409.389695) (xy 115.373254 -409.324311) (xy 115.396929 -409.261305)
			(xy 115.427964 -409.20158) (xy 115.465915 -409.145993) (xy 115.487704 -409.12034) (xy 115.493509 -409.113201)
			(xy 115.500019 -409.096006) (xy 115.500404 -409.086812) (xy 115.500404 -408.593544) (xy 115.499972 -408.584359)
			(xy 115.493473 -408.567175) (xy 115.487704 -408.560016) (xy 115.465909 -408.53437) (xy 115.427963 -408.478782)
			(xy 115.396932 -408.419057) (xy 115.373261 -408.356052) (xy 115.35729 -408.290669) (xy 115.349247 -408.223846)
			(xy 115.349248 -408.156541) (xy 115.357292 -408.089719) (xy 115.373265 -408.024337) (xy 115.396937 -407.961332)
			(xy 115.427969 -407.901608) (xy 115.465917 -407.846021) (xy 115.487704 -407.820368) (xy 115.493497 -407.81322)
			(xy 115.500014 -407.796032) (xy 115.500404 -407.78684) (xy 115.500404 -407.628852) (xy 115.500846 -407.61874)
			(xy 115.5086 -407.60006) (xy 115.52291 -407.585767) (xy 115.541599 -407.578034) (xy 115.551712 -407.577544)
			(xy 116.268246 -407.577544) (xy 116.278376 -407.577989) (xy 116.297099 -407.585733) (xy 116.311454 -407.600031)
			(xy 116.319271 -407.618724) (xy 116.319808 -407.628852) (xy 116.319808 -407.78684) (xy 116.320197 -407.79603)
			(xy 116.326725 -407.813214) (xy 116.332508 -407.820368) (xy 116.354289 -407.846026) (xy 116.392242 -407.90161)
			(xy 116.423279 -407.961333) (xy 116.446954 -408.024336) (xy 116.462929 -408.089718) (xy 116.470975 -408.156541)
			(xy 116.470976 -408.223847) (xy 116.462931 -408.29067) (xy 116.446958 -408.356052) (xy 116.423283 -408.419056)
			(xy 116.392248 -408.478779) (xy 116.354297 -408.534365) (xy 116.332508 -408.560016) (xy 116.326723 -408.56717)
			(xy 116.320201 -408.584354) (xy 116.319808 -408.593544) (xy 116.319808 -409.086812) (xy 116.320211 -409.096)
			(xy 116.326729 -409.113184) (xy 116.332508 -409.12034) (xy 116.354262 -409.146021) (xy 116.392215 -409.201602)
			(xy 116.423253 -409.261321) (xy 116.44693 -409.324322) (xy 116.462907 -409.389701) (xy 116.470955 -409.456521)
			(xy 116.470958 -409.523825) (xy 116.462917 -409.590646) (xy 116.446946 -409.656026) (xy 116.423275 -409.71903)
			(xy 116.392243 -409.778752) (xy 116.354295 -409.834337) (xy 116.332508 -409.859988) (xy 116.326692 -409.86712)
			(xy 116.320189 -409.884321) (xy 116.319808 -409.893516) (xy 116.319808 -410.051504) (xy 116.319318 -410.061612)
			(xy 116.311581 -410.080289) (xy 116.297285 -410.094583) (xy 116.278608 -410.102319) (xy 116.2685 -410.102812)
			(xy 115.551966 -410.102812) (xy 115.541844 -410.102303) (xy 115.523131 -410.094574) (xy 115.508778 -410.080295)
			(xy 115.500951 -410.061624) (xy 115.500404 -410.051504) (xy 115.500404 -409.893516) (xy 115.499985 -409.88433)
			(xy 115.493477 -409.867145) (xy 115.487704 -409.859988) (xy 115.465882 -409.834364) (xy 115.427937 -409.778773)
			(xy 115.396907 -409.719045) (xy 115.373238 -409.656037) (xy 115.357268 -409.590652) (xy 115.349227 -409.523827)
			(xy 92.220596 -409.523827) (xy 92.192139 -409.578596) (xy 92.154191 -409.634183) (xy 92.132404 -409.659836)
			(xy 92.12661 -409.666983) (xy 92.120094 -409.684172) (xy 92.119704 -409.693364) (xy 92.119704 -410.186632)
			(xy 92.120098 -410.195821) (xy 92.126623 -410.213005) (xy 92.132404 -410.22016) (xy 92.154175 -410.245826)
			(xy 92.192121 -410.301411) (xy 92.223153 -410.361133) (xy 92.246825 -410.424136) (xy 92.262797 -410.489516)
			(xy 92.270842 -410.556336) (xy 92.270844 -410.623639) (xy 92.270837 -410.623701) (xy 117.548849 -410.623701)
			(xy 117.54885 -410.556275) (xy 117.556929 -410.489335) (xy 117.572967 -410.423844) (xy 117.596736 -410.360746)
			(xy 117.627891 -410.30095) (xy 117.665985 -410.245316) (xy 117.687852 -410.219652) (xy 117.693658 -410.212514)
			(xy 117.700166 -410.195318) (xy 117.700552 -410.186124) (xy 117.700552 -409.693872) (xy 117.700144 -409.684685)
			(xy 117.693627 -409.667501) (xy 117.687852 -409.660344) (xy 117.665998 -409.63467) (xy 117.627906 -409.579038)
			(xy 117.596751 -409.519243) (xy 117.572984 -409.456148) (xy 117.556946 -409.390659) (xy 117.548869 -409.323721)
			(xy 117.548868 -409.256297) (xy 117.556943 -409.189359) (xy 117.572979 -409.12387) (xy 117.596744 -409.060773)
			(xy 117.627896 -409.000978) (xy 117.665987 -408.945344) (xy 117.687852 -408.91968) (xy 117.693646 -408.912533)
			(xy 117.700161 -408.895344) (xy 117.700552 -408.886152) (xy 117.700552 -408.728672) (xy 117.701061 -408.718567)
			(xy 117.708799 -408.699898) (xy 117.723088 -408.685606) (xy 117.741756 -408.677863) (xy 117.75186 -408.677364)
			(xy 118.46814 -408.677364) (xy 118.478247 -408.677852) (xy 118.496919 -408.685596) (xy 118.511211 -408.699891)
			(xy 118.518951 -408.718565) (xy 118.519448 -408.728672) (xy 118.519448 -408.886152) (xy 118.519893 -408.895335)
			(xy 118.526384 -408.912519) (xy 118.532148 -408.91968) (xy 118.554026 -408.945335) (xy 118.592117 -409.000969)
			(xy 118.62327 -409.060767) (xy 118.647036 -409.123865) (xy 118.663072 -409.189356) (xy 118.671148 -409.256296)
			(xy 118.671147 -409.323722) (xy 118.663069 -409.390662) (xy 118.647031 -409.456152) (xy 118.623263 -409.51925)
			(xy 118.620848 -409.523886) (xy 119.748996 -409.523886) (xy 119.748999 -409.45646) (xy 119.757078 -409.389519)
			(xy 119.773118 -409.324028) (xy 119.796886 -409.26093) (xy 119.828041 -409.201132) (xy 119.866134 -409.145497)
			(xy 119.888 -409.119832) (xy 119.893808 -409.112695) (xy 119.900316 -409.095498) (xy 119.9007 -409.086304)
			(xy 119.9007 -408.594052) (xy 119.900265 -408.584867) (xy 119.893769 -408.567683) (xy 119.888 -408.560524)
			(xy 119.866128 -408.534865) (xy 119.82804 -408.47923) (xy 119.796889 -408.419433) (xy 119.773126 -408.356335)
			(xy 119.757091 -408.290845) (xy 119.749015 -408.223906) (xy 119.749016 -408.156482) (xy 119.757093 -408.089543)
			(xy 119.773129 -408.024054) (xy 119.796894 -407.960956) (xy 119.828046 -407.90116) (xy 119.866136 -407.845525)
			(xy 119.888 -407.81986) (xy 119.893796 -407.812714) (xy 119.900311 -407.795524) (xy 119.9007 -407.786332)
			(xy 119.9007 -407.628852) (xy 119.901146 -407.61874) (xy 119.908899 -407.600061) (xy 119.923208 -407.585768)
			(xy 119.941896 -407.578035) (xy 119.952008 -407.577544) (xy 120.668288 -407.577544) (xy 120.678389 -407.578094)
			(xy 120.697056 -407.585817) (xy 120.71135 -407.600093) (xy 120.719095 -407.618752) (xy 120.719596 -407.628852)
			(xy 120.719596 -407.786332) (xy 120.719991 -407.795521) (xy 120.726515 -407.812705) (xy 120.732296 -407.81986)
			(xy 120.754152 -407.845532) (xy 120.792241 -407.901165) (xy 120.823393 -407.96096) (xy 120.847158 -408.024056)
			(xy 120.863194 -408.089545) (xy 120.87127 -408.156482) (xy 120.871271 -408.223906) (xy 120.863196 -408.290843)
			(xy 120.847161 -408.356332) (xy 120.823398 -408.419429) (xy 120.792248 -408.479225) (xy 120.75416 -408.534859)
			(xy 120.732296 -408.560524) (xy 120.726506 -408.567674) (xy 120.719988 -408.584861) (xy 120.719596 -408.594052)
			(xy 120.719596 -409.086304) (xy 120.720005 -409.095491) (xy 120.72652 -409.112675) (xy 120.732296 -409.119832)
			(xy 120.754125 -409.145526) (xy 120.792215 -409.201157) (xy 120.823367 -409.260949) (xy 120.847134 -409.324042)
			(xy 120.863172 -409.389527) (xy 120.871251 -409.456463) (xy 120.871254 -409.523883) (xy 120.863181 -409.590819)
			(xy 120.84715 -409.656306) (xy 120.823389 -409.719402) (xy 120.792243 -409.779197) (xy 120.754158 -409.834831)
			(xy 120.732296 -409.860496) (xy 120.726518 -409.867654) (xy 120.719992 -409.884835) (xy 120.719596 -409.894024)
			(xy 120.719596 -410.051504) (xy 120.719187 -410.061627) (xy 120.711437 -410.080332) (xy 120.697118 -410.094646)
			(xy 120.678411 -410.10239) (xy 120.668288 -410.102812) (xy 119.952008 -410.102812) (xy 119.941888 -410.102378)
			(xy 119.923186 -410.094634) (xy 119.908872 -410.080324) (xy 119.901125 -410.061624) (xy 119.9007 -410.051504)
			(xy 119.9007 -409.894024) (xy 119.900278 -409.884838) (xy 119.893773 -409.867654) (xy 119.888 -409.860496)
			(xy 119.866101 -409.83486) (xy 119.828013 -409.779221) (xy 119.796864 -409.719421) (xy 119.773102 -409.65632)
			(xy 119.757069 -409.590828) (xy 119.748996 -409.523886) (xy 118.620848 -409.523886) (xy 118.592108 -409.579046)
			(xy 118.554015 -409.63468) (xy 118.532148 -409.660344) (xy 118.526344 -409.667484) (xy 118.519835 -409.684679)
			(xy 118.519448 -409.693872) (xy 118.519448 -410.186124) (xy 118.519858 -410.195311) (xy 118.526373 -410.212495)
			(xy 118.532148 -410.219652) (xy 118.553998 -410.245329) (xy 118.592091 -410.300961) (xy 118.623245 -410.360755)
			(xy 118.647012 -410.42385) (xy 118.663051 -410.489338) (xy 118.671128 -410.556276) (xy 118.67113 -410.623641)
			(xy 121.949169 -410.623641) (xy 121.94917 -410.556335) (xy 121.957216 -410.489511) (xy 121.97319 -410.424128)
			(xy 121.996865 -410.361123) (xy 122.0279 -410.301399) (xy 122.065851 -410.245812) (xy 122.08764 -410.22016)
			(xy 122.093441 -410.213018) (xy 122.099952 -410.195825) (xy 122.10034 -410.186632) (xy 122.10034 -409.693364)
			(xy 122.099938 -409.684176) (xy 122.093418 -409.666992) (xy 122.08764 -409.659836) (xy 122.065864 -409.634174)
			(xy 122.027915 -409.578589) (xy 121.996881 -409.518867) (xy 121.973208 -409.455864) (xy 121.957234 -409.390483)
			(xy 121.949189 -409.323661) (xy 121.949188 -409.256357) (xy 121.957231 -409.189535) (xy 121.973202 -409.124154)
			(xy 121.996874 -409.06115) (xy 122.027906 -409.001427) (xy 122.065853 -408.94584) (xy 122.08764 -408.920188)
			(xy 122.093429 -408.913038) (xy 122.099947 -408.895851) (xy 122.10034 -408.88666) (xy 122.10034 -408.728672)
			(xy 122.100694 -408.718543) (xy 122.108459 -408.699831) (xy 122.122795 -408.685516) (xy 122.141518 -408.677779)
			(xy 122.151648 -408.677364) (xy 122.868182 -408.677364) (xy 122.878311 -408.677842) (xy 122.897036 -408.685568)
			(xy 122.911394 -408.699858) (xy 122.919209 -408.718546) (xy 122.919744 -408.728672) (xy 122.919744 -408.88666)
			(xy 122.920186 -408.895844) (xy 122.926679 -408.913028) (xy 122.932444 -408.920188) (xy 122.954244 -408.94583)
			(xy 122.992193 -409.001418) (xy 123.023227 -409.061143) (xy 123.0469 -409.124148) (xy 123.062873 -409.189532)
			(xy 123.070916 -409.256356) (xy 123.070915 -409.323662) (xy 123.062869 -409.390486) (xy 123.046895 -409.455869)
			(xy 123.02322 -409.518874) (xy 123.020646 -409.523827) (xy 124.149291 -409.523827) (xy 124.149295 -409.456519)
			(xy 124.157343 -409.389693) (xy 124.173321 -409.324308) (xy 124.197 -409.261302) (xy 124.22804 -409.201577)
			(xy 124.265997 -409.145992) (xy 124.287788 -409.12034) (xy 124.293591 -409.113199) (xy 124.300102 -409.096005)
			(xy 124.300488 -409.086812) (xy 124.300488 -408.593544) (xy 124.300059 -408.584359) (xy 124.293559 -408.567174)
			(xy 124.287788 -408.560016) (xy 124.265991 -408.534371) (xy 124.228039 -408.478785) (xy 124.197004 -408.419061)
			(xy 124.173329 -408.356055) (xy 124.157355 -408.290671) (xy 124.149311 -408.223847) (xy 124.149312 -408.156541)
			(xy 124.157357 -408.089717) (xy 124.173333 -408.024333) (xy 124.197008 -407.961328) (xy 124.228045 -407.901605)
			(xy 124.265998 -407.84602) (xy 124.287788 -407.820368) (xy 124.293579 -407.813219) (xy 124.300097 -407.796031)
			(xy 124.300488 -407.78684) (xy 124.300488 -407.628852) (xy 124.300946 -407.618742) (xy 124.308697 -407.600065)
			(xy 124.323002 -407.585772) (xy 124.341685 -407.578037) (xy 124.351796 -407.577544) (xy 125.06833 -407.577544)
			(xy 125.078459 -407.578002) (xy 125.097182 -407.58574) (xy 125.111537 -407.600035) (xy 125.119355 -407.618725)
			(xy 125.119892 -407.628852) (xy 125.119892 -407.78684) (xy 125.120285 -407.796029) (xy 125.126811 -407.813213)
			(xy 125.132592 -407.820368) (xy 125.154371 -407.846027) (xy 125.192318 -407.901613) (xy 125.22335 -407.961336)
			(xy 125.247022 -408.02434) (xy 125.262994 -408.089721) (xy 125.271039 -408.156542) (xy 125.271039 -408.223846)
			(xy 125.262997 -408.290667) (xy 125.247025 -408.356049) (xy 125.223355 -408.419053) (xy 125.192324 -408.478776)
			(xy 125.154378 -408.534363) (xy 125.132592 -408.560016) (xy 125.126805 -408.567168) (xy 125.120285 -408.584353)
			(xy 125.119892 -408.593544) (xy 125.119892 -409.086812) (xy 125.120298 -409.096) (xy 125.126815 -409.113184)
			(xy 125.132592 -409.12034) (xy 125.154343 -409.146022) (xy 125.192291 -409.201605) (xy 125.223324 -409.261324)
			(xy 125.246998 -409.324325) (xy 125.262972 -409.389703) (xy 125.271019 -409.456522) (xy 125.271022 -409.523824)
			(xy 125.262982 -409.590643) (xy 125.247014 -409.656023) (xy 125.223347 -409.719026) (xy 125.192319 -409.778749)
			(xy 125.154377 -409.834336) (xy 125.132592 -409.859988) (xy 125.126775 -409.867118) (xy 125.120273 -409.88432)
			(xy 125.119892 -409.893516) (xy 125.119892 -410.051504) (xy 125.119487 -410.061628) (xy 125.111736 -410.080333)
			(xy 125.097416 -410.094647) (xy 125.078708 -410.102391) (xy 125.068584 -410.102812) (xy 124.35205 -410.102812)
			(xy 124.341933 -410.102234) (xy 124.323223 -410.094532) (xy 124.308867 -410.080274) (xy 124.301036 -410.061618)
			(xy 124.300488 -410.051504) (xy 124.300488 -409.893516) (xy 124.300073 -409.884329) (xy 124.293563 -409.867145)
			(xy 124.287788 -409.859988) (xy 124.265963 -409.834366) (xy 124.228013 -409.778776) (xy 124.196978 -409.719049)
			(xy 124.173305 -409.65604) (xy 124.157333 -409.590654) (xy 124.149291 -409.523827) (xy 123.020646 -409.523827)
			(xy 122.992184 -409.578598) (xy 122.954233 -409.634184) (xy 122.932444 -409.659836) (xy 122.926643 -409.666978)
			(xy 122.920132 -409.684171) (xy 122.919744 -409.693364) (xy 122.919744 -410.186632) (xy 122.920151 -410.195819)
			(xy 122.926668 -410.213003) (xy 122.932444 -410.22016) (xy 122.954216 -410.245825) (xy 122.992167 -410.301409)
			(xy 123.023202 -410.361131) (xy 123.046876 -410.424134) (xy 123.062851 -410.489514) (xy 123.070896 -410.556336)
			(xy 123.070898 -410.62364) (xy 123.070891 -410.623701) (xy 126.348937 -410.623701) (xy 126.348938 -410.556275)
			(xy 126.357016 -410.489335) (xy 126.373055 -410.423845) (xy 126.396822 -410.360747) (xy 126.427977 -410.300951)
			(xy 126.46607 -410.245317) (xy 126.487936 -410.219652) (xy 126.49374 -410.212512) (xy 126.500249 -410.195317)
			(xy 126.500636 -410.186124) (xy 126.500636 -409.693872) (xy 126.500231 -409.684684) (xy 126.493713 -409.667501)
			(xy 126.487936 -409.660344) (xy 126.466083 -409.63467) (xy 126.427991 -409.579037) (xy 126.396838 -409.519243)
			(xy 126.373071 -409.456147) (xy 126.357034 -409.390659) (xy 126.348957 -409.323721) (xy 126.348956 -409.256297)
			(xy 126.357031 -409.189359) (xy 126.373066 -409.12387) (xy 126.396831 -409.060774) (xy 126.427982 -409.000978)
			(xy 126.466071 -408.945345) (xy 126.487936 -408.91968) (xy 126.493728 -408.912532) (xy 126.500245 -408.895343)
			(xy 126.500636 -408.886152) (xy 126.500636 -408.728672) (xy 126.500994 -408.718543) (xy 126.508758 -408.699832)
			(xy 126.523093 -408.685517) (xy 126.541815 -408.67778) (xy 126.551944 -408.677364) (xy 127.268224 -408.677364)
			(xy 127.27833 -408.677864) (xy 127.297002 -408.685603) (xy 127.311294 -408.699895) (xy 127.319035 -408.718566)
			(xy 127.319532 -408.728672) (xy 127.319532 -408.886152) (xy 127.31998 -408.895335) (xy 127.326469 -408.912519)
			(xy 127.332232 -408.91968) (xy 127.354107 -408.945336) (xy 127.392193 -409.000973) (xy 127.423341 -409.06077)
			(xy 127.447103 -409.123868) (xy 127.463137 -409.189358) (xy 127.471211 -409.256297) (xy 127.47121 -409.323721)
			(xy 127.463134 -409.39066) (xy 127.447098 -409.456149) (xy 127.423334 -409.519246) (xy 127.420948 -409.523827)
			(xy 128.549082 -409.523827) (xy 128.549085 -409.456519) (xy 128.557133 -409.389693) (xy 128.573111 -409.324308)
			(xy 128.59679 -409.261302) (xy 128.627829 -409.201578) (xy 128.665785 -409.145991) (xy 128.687576 -409.12034)
			(xy 128.693378 -409.113198) (xy 128.69989 -409.096005) (xy 128.700276 -409.086812) (xy 128.700276 -408.593544)
			(xy 128.69985 -408.584358) (xy 128.693348 -408.567174) (xy 128.687576 -408.560016) (xy 128.665779 -408.534371)
			(xy 128.627828 -408.478784) (xy 128.596793 -408.41906) (xy 128.573119 -408.356055) (xy 128.557146 -408.290671)
			(xy 128.549102 -408.223847) (xy 128.549103 -408.156541) (xy 128.557148 -408.089717) (xy 128.573123 -408.024334)
			(xy 128.596798 -407.961329) (xy 128.627835 -407.901605) (xy 128.665787 -407.84602) (xy 128.687576 -407.820368)
			(xy 128.693366 -407.813218) (xy 128.699885 -407.796031) (xy 128.700276 -407.78684) (xy 128.700276 -407.628852)
			(xy 128.700745 -407.618743) (xy 128.708494 -407.600069) (xy 128.722795 -407.585776) (xy 128.741475 -407.578039)
			(xy 128.751584 -407.577544) (xy 129.468118 -407.577544) (xy 129.478246 -407.578012) (xy 129.496969 -407.585746)
			(xy 129.511325 -407.600038) (xy 129.519143 -407.618726) (xy 129.51968 -407.628852) (xy 129.51968 -407.78684)
			(xy 129.520075 -407.796029) (xy 129.5266 -407.813213) (xy 129.53238 -407.820368) (xy 129.554159 -407.846027)
			(xy 129.592107 -407.901613) (xy 129.62314 -407.961336) (xy 129.646812 -408.024339) (xy 129.662785 -408.08972)
			(xy 129.67083 -408.156542) (xy 129.67083 -408.223846) (xy 129.662787 -408.290668) (xy 129.646816 -408.356049)
			(xy 129.623145 -408.419053) (xy 129.592113 -408.478777) (xy 129.554167 -408.534364) (xy 129.53238 -408.560016)
			(xy 129.526592 -408.567167) (xy 129.520073 -408.584353) (xy 129.51968 -408.593544) (xy 129.51968 -409.086812)
			(xy 129.520089 -409.095999) (xy 129.526604 -409.113183) (xy 129.53238 -409.12034) (xy 129.554131 -409.146022)
			(xy 129.59208 -409.201604) (xy 129.623114 -409.261324) (xy 129.646788 -409.324325) (xy 129.662763 -409.389703)
			(xy 129.670809 -409.456522) (xy 129.670813 -409.523824) (xy 129.662772 -409.590644) (xy 129.646804 -409.656024)
			(xy 129.623136 -409.719026) (xy 129.592108 -409.778749) (xy 129.554165 -409.834335) (xy 129.53238 -409.859988)
			(xy 129.526561 -409.867117) (xy 129.52006 -409.88432) (xy 129.51968 -409.893516) (xy 129.51968 -410.051504)
			(xy 129.519287 -410.061629) (xy 129.511534 -410.080337) (xy 129.49721 -410.094651) (xy 129.478497 -410.102393)
			(xy 129.468372 -410.102812) (xy 128.751838 -410.102812) (xy 128.74172 -410.102244) (xy 128.72301 -410.094538)
			(xy 128.708654 -410.080277) (xy 128.700824 -410.061618) (xy 128.700276 -410.051504) (xy 128.700276 -409.893516)
			(xy 128.699864 -409.884329) (xy 128.693352 -409.867144) (xy 128.687576 -409.859988) (xy 128.665751 -409.834366)
			(xy 128.627801 -409.778776) (xy 128.596768 -409.719048) (xy 128.573095 -409.65604) (xy 128.557124 -409.590654)
			(xy 128.549082 -409.523827) (xy 127.420948 -409.523827) (xy 127.392184 -409.579043) (xy 127.354096 -409.634678)
			(xy 127.332232 -409.660344) (xy 127.326426 -409.667482) (xy 127.319919 -409.684678) (xy 127.319532 -409.693872)
			(xy 127.319532 -410.186124) (xy 127.319946 -410.19531) (xy 127.326459 -410.212494) (xy 127.332232 -410.219652)
			(xy 127.354079 -410.245331) (xy 127.392166 -410.300964) (xy 127.423316 -410.360759) (xy 127.44708 -410.423854)
			(xy 127.463115 -410.489341) (xy 127.471192 -410.556277) (xy 127.471193 -410.623641) (xy 130.749257 -410.623641)
			(xy 130.749258 -410.556335) (xy 130.757303 -410.489512) (xy 130.773278 -410.424129) (xy 130.796952 -410.361123)
			(xy 130.827986 -410.301399) (xy 130.865936 -410.245812) (xy 130.887724 -410.22016) (xy 130.893523 -410.213017)
			(xy 130.900035 -410.195825) (xy 130.900424 -410.186632) (xy 130.900424 -409.693364) (xy 130.900026 -409.684176)
			(xy 130.893503 -409.666992) (xy 130.887724 -409.659836) (xy 130.865948 -409.634174) (xy 130.828 -409.578589)
			(xy 130.796967 -409.518866) (xy 130.773294 -409.455863) (xy 130.757321 -409.390482) (xy 130.749276 -409.323661)
			(xy 130.749275 -409.256357) (xy 130.757318 -409.189536) (xy 130.773289 -409.124154) (xy 130.79696 -409.06115)
			(xy 130.827991 -409.001427) (xy 130.865937 -408.94584) (xy 130.887724 -408.920188) (xy 130.893511 -408.913036)
			(xy 130.900031 -408.895851) (xy 130.900424 -408.88666) (xy 130.900424 -408.728672) (xy 130.900799 -408.718513)
			(xy 130.908608 -408.699755) (xy 130.92302 -408.685432) (xy 130.941825 -408.677738) (xy 130.951986 -408.677364)
			(xy 131.668266 -408.677364) (xy 131.678393 -408.677855) (xy 131.697118 -408.685576) (xy 131.711477 -408.699862)
			(xy 131.719293 -408.718547) (xy 131.719828 -408.728672) (xy 131.719828 -408.88666) (xy 131.720251 -408.895846)
			(xy 131.726755 -408.913031) (xy 131.732528 -408.920188) (xy 131.754328 -408.94583) (xy 131.792279 -409.001417)
			(xy 131.823314 -409.061142) (xy 131.846987 -409.124148) (xy 131.86296 -409.189532) (xy 131.871004 -409.256356)
			(xy 131.871003 -409.323662) (xy 131.862957 -409.390486) (xy 131.846982 -409.45587) (xy 131.823306 -409.518875)
			(xy 131.79227 -409.578598) (xy 131.754317 -409.634184) (xy 131.732528 -409.659836) (xy 131.726725 -409.666976)
			(xy 131.720216 -409.684171) (xy 131.719828 -409.693364) (xy 131.719828 -410.186632) (xy 131.720217 -410.195822)
			(xy 131.726745 -410.213006) (xy 131.732528 -410.22016) (xy 131.754301 -410.245825) (xy 131.792252 -410.301409)
			(xy 131.823288 -410.36113) (xy 131.846963 -410.424133) (xy 131.862938 -410.489514) (xy 131.870984 -410.556336)
			(xy 131.870986 -410.62364) (xy 131.862943 -410.690462) (xy 131.84697 -410.755844) (xy 131.823298 -410.818848)
			(xy 131.792265 -410.878571) (xy 131.754316 -410.934156) (xy 131.732528 -410.959808) (xy 131.726737 -410.966957)
			(xy 131.720221 -410.984145) (xy 131.719828 -410.993336) (xy 131.719828 -411.151324) (xy 131.719399 -411.161476)
			(xy 131.7116 -411.180224) (xy 131.697207 -411.194545) (xy 131.67842 -411.202249) (xy 131.668266 -411.202632)
			(xy 130.951986 -411.202632) (xy 130.941855 -411.202184) (xy 130.923128 -411.194446) (xy 130.908772 -411.180148)
			(xy 130.900958 -411.161453) (xy 130.900424 -411.151324) (xy 130.900424 -410.993336) (xy 130.899991 -410.984151)
			(xy 130.893493 -410.966967) (xy 130.887724 -410.959808) (xy 130.865921 -410.934169) (xy 130.827974 -410.87858)
			(xy 130.796942 -410.818855) (xy 130.773271 -410.755848) (xy 130.757299 -410.690465) (xy 130.749257 -410.623641)
			(xy 127.471193 -410.623641) (xy 127.471193 -410.623699) (xy 127.463119 -410.690635) (xy 127.447087 -410.756123)
			(xy 127.423326 -410.819219) (xy 127.392179 -410.879015) (xy 127.354094 -410.93465) (xy 127.332232 -410.960316)
			(xy 127.326438 -410.967463) (xy 127.319924 -410.984652) (xy 127.319532 -410.993844) (xy 127.319532 -411.151324)
			(xy 127.319035 -411.16143) (xy 127.311296 -411.180103) (xy 127.297003 -411.194396) (xy 127.27833 -411.202135)
			(xy 127.268224 -411.202632) (xy 126.551944 -411.202632) (xy 126.541828 -411.202149) (xy 126.523132 -411.194421)
			(xy 126.508817 -411.180125) (xy 126.501065 -411.161439) (xy 126.500636 -411.151324) (xy 126.500636 -410.993844)
			(xy 126.500196 -410.98466) (xy 126.493702 -410.967476) (xy 126.487936 -410.960316) (xy 126.466055 -410.934664)
			(xy 126.427964 -410.879029) (xy 126.396812 -410.819231) (xy 126.373048 -410.756132) (xy 126.357012 -410.690641)
			(xy 126.348937 -410.623701) (xy 123.070891 -410.623701) (xy 123.062855 -410.690462) (xy 123.046883 -410.755843)
			(xy 123.023211 -410.818847) (xy 122.992179 -410.87857) (xy 122.954231 -410.934156) (xy 122.932444 -410.959808)
			(xy 122.926655 -410.966958) (xy 122.920137 -410.984145) (xy 122.919744 -410.993336) (xy 122.919744 -411.151324)
			(xy 122.919236 -411.161429) (xy 122.911498 -411.180099) (xy 122.897209 -411.194392) (xy 122.878541 -411.202133)
			(xy 122.868436 -411.202632) (xy 122.151902 -411.202632) (xy 122.141772 -411.202171) (xy 122.123046 -411.194439)
			(xy 122.108688 -411.180144) (xy 122.100874 -411.161452) (xy 122.10034 -411.151324) (xy 122.10034 -410.993336)
			(xy 122.099903 -410.984152) (xy 122.093407 -410.966968) (xy 122.08764 -410.959808) (xy 122.065836 -410.934169)
			(xy 122.027888 -410.878581) (xy 121.996855 -410.818855) (xy 121.973183 -410.755849) (xy 121.957211 -410.690465)
			(xy 121.949169 -410.623641) (xy 118.67113 -410.623641) (xy 118.67113 -410.6237) (xy 118.663055 -410.690638)
			(xy 118.647019 -410.756127) (xy 118.623255 -410.819223) (xy 118.592103 -410.879018) (xy 118.554013 -410.934652)
			(xy 118.532148 -410.960316) (xy 118.526356 -410.967464) (xy 118.51984 -410.984653) (xy 118.519448 -410.993844)
			(xy 118.519448 -411.151324) (xy 118.518936 -411.161428) (xy 118.511199 -411.180098) (xy 118.496911 -411.19439)
			(xy 118.478244 -411.202133) (xy 118.46814 -411.202632) (xy 117.75186 -411.202632) (xy 117.741753 -411.202148)
			(xy 117.72308 -411.194404) (xy 117.708787 -411.180107) (xy 117.701048 -411.161431) (xy 117.700552 -411.151324)
			(xy 117.700552 -410.993844) (xy 117.700109 -410.984661) (xy 117.693617 -410.967477) (xy 117.687852 -410.960316)
			(xy 117.66597 -410.934665) (xy 117.627879 -410.879029) (xy 117.596726 -410.819232) (xy 117.57296 -410.756133)
			(xy 117.556924 -410.690642) (xy 117.548849 -410.623701) (xy 92.270837 -410.623701) (xy 92.262802 -410.69046)
			(xy 92.246832 -410.755841) (xy 92.223163 -410.818845) (xy 92.192134 -410.878568) (xy 92.154189 -410.934155)
			(xy 92.132404 -410.959808) (xy 92.126622 -410.966964) (xy 92.120098 -410.984146) (xy 92.119704 -410.993336)
			(xy 92.119704 -411.151324) (xy 92.119298 -411.161479) (xy 92.111495 -411.180231) (xy 92.097094 -411.194554)
			(xy 92.078299 -411.202253) (xy 92.068142 -411.202632) (xy 91.351862 -411.202632) (xy 91.341729 -411.202204)
			(xy 91.323002 -411.194458) (xy 91.308646 -411.180154) (xy 91.300833 -411.161455) (xy 91.3003 -411.151324)
			(xy 91.3003 -410.993336) (xy 91.299873 -410.984151) (xy 91.293371 -410.966966) (xy 91.2876 -410.959808)
			(xy 91.265798 -410.934168) (xy 91.227852 -410.878579) (xy 91.196822 -410.818853) (xy 91.173151 -410.755847)
			(xy 91.157181 -410.690464) (xy 91.149138 -410.623641) (xy 87.871075 -410.623641) (xy 87.871075 -410.623699)
			(xy 87.863001 -410.690636) (xy 87.846967 -410.756124) (xy 87.823205 -410.81922) (xy 87.792057 -410.879016)
			(xy 87.753971 -410.934651) (xy 87.732108 -410.960316) (xy 87.726323 -410.96747) (xy 87.719801 -410.984654)
			(xy 87.719408 -410.993844) (xy 87.719408 -411.151324) (xy 87.718935 -411.161433) (xy 87.711191 -411.180111)
			(xy 87.69689 -411.194404) (xy 87.67821 -411.20214) (xy 87.6681 -411.202632) (xy 86.95182 -411.202632)
			(xy 86.941716 -411.202099) (xy 86.923045 -411.194374) (xy 86.90875 -411.180092) (xy 86.901009 -411.161427)
			(xy 86.900512 -411.151324) (xy 86.900512 -410.993844) (xy 86.900078 -410.984659) (xy 86.893581 -410.967475)
			(xy 86.887812 -410.960316) (xy 86.865932 -410.934664) (xy 86.827843 -410.879028) (xy 86.796692 -410.81923)
			(xy 86.772928 -410.756131) (xy 86.756894 -410.69064) (xy 86.748819 -410.623701) (xy 83.470773 -410.623701)
			(xy 83.462736 -410.690462) (xy 83.446764 -410.755844) (xy 83.423091 -410.818848) (xy 83.392058 -410.878571)
			(xy 83.354108 -410.934156) (xy 83.33232 -410.959808) (xy 83.32654 -410.966965) (xy 83.320015 -410.984146)
			(xy 83.31962 -410.993336) (xy 83.31962 -411.151324) (xy 83.319199 -411.161477) (xy 83.311399 -411.180226)
			(xy 83.297003 -411.194548) (xy 83.278213 -411.202251) (xy 83.268058 -411.202632) (xy 82.551778 -411.202632)
			(xy 82.541646 -411.202191) (xy 82.522919 -411.194451) (xy 82.508563 -411.18015) (xy 82.500749 -411.161454)
			(xy 82.500216 -411.151324) (xy 82.500216 -410.993336) (xy 82.499785 -410.984151) (xy 82.493285 -410.966967)
			(xy 82.487516 -410.959808) (xy 82.465713 -410.934169) (xy 82.427766 -410.87858) (xy 82.396735 -410.818854)
			(xy 82.373064 -410.755848) (xy 82.357093 -410.690465) (xy 82.349051 -410.623641) (xy 79.070987 -410.623641)
			(xy 79.070987 -410.623699) (xy 79.062913 -410.690636) (xy 79.04688 -410.756124) (xy 79.023119 -410.81922)
			(xy 78.991971 -410.879016) (xy 78.953886 -410.93465) (xy 78.932024 -410.960316) (xy 78.926241 -410.967471)
			(xy 78.919717 -410.984654) (xy 78.919324 -410.993844) (xy 78.919324 -411.151324) (xy 78.918835 -411.161431)
			(xy 78.911094 -411.180106) (xy 78.896799 -411.194399) (xy 78.878123 -411.202137) (xy 78.868016 -411.202632)
			(xy 78.151736 -411.202632) (xy 78.14162 -411.202155) (xy 78.122923 -411.194425) (xy 78.108609 -411.180127)
			(xy 78.100857 -411.16144) (xy 78.100428 -411.151324) (xy 78.100428 -410.993844) (xy 78.09999 -410.98466)
			(xy 78.093495 -410.967476) (xy 78.087728 -410.960316) (xy 78.065847 -410.934664) (xy 78.027757 -410.879028)
			(xy 77.996606 -410.819231) (xy 77.972841 -410.756132) (xy 77.956806 -410.690641) (xy 77.948731 -410.623701)
			(xy 74.670685 -410.623701) (xy 74.662649 -410.690462) (xy 74.646677 -410.755844) (xy 74.623005 -410.818848)
			(xy 74.591972 -410.87857) (xy 74.554023 -410.934156) (xy 74.532236 -410.959808) (xy 74.526446 -410.966957)
			(xy 74.519929 -410.984145) (xy 74.519536 -410.993336) (xy 74.519536 -411.151324) (xy 74.519099 -411.161475)
			(xy 74.511302 -411.180221) (xy 74.496911 -411.194542) (xy 74.478127 -411.202248) (xy 74.467974 -411.202632)
			(xy 73.751694 -411.202632) (xy 73.741563 -411.202177) (xy 73.722837 -411.194442) (xy 73.70848 -411.180146)
			(xy 73.700666 -411.161452) (xy 73.700132 -411.151324) (xy 73.700132 -410.993336) (xy 73.699697 -410.984152)
			(xy 73.6932 -410.966967) (xy 73.687432 -410.959808) (xy 73.665629 -410.934169) (xy 73.627681 -410.87858)
			(xy 73.596649 -410.818855) (xy 73.572977 -410.755849) (xy 73.557005 -410.690465) (xy 73.548963 -410.623641)
			(xy 66.525648 -410.623641) (xy 66.525648 -417.289488) (xy 66.525648 -417.371276) (xy 141.02334 -417.371276)
			(xy 141.02334 -394.305282) (xy 141.023796 -394.293166) (xy 141.031289 -394.270122) (xy 141.045535 -394.25052)
			(xy 141.06514 -394.23628) (xy 141.088186 -394.228793) (xy 141.100302 -394.22832) (xy 154.426158 -394.22832)
			(xy 154.57678 -394.378688) (xy 154.57678 -397.823825) (xy 159.349135 -397.823825) (xy 159.349138 -397.756518)
			(xy 159.357186 -397.689693) (xy 159.373162 -397.624309) (xy 159.396838 -397.561303) (xy 159.427875 -397.501578)
			(xy 159.465827 -397.44599) (xy 159.487616 -397.420338) (xy 159.493423 -397.4132) (xy 159.499931 -397.396004)
			(xy 159.500316 -397.38681) (xy 159.500316 -396.893542) (xy 159.499882 -396.884357) (xy 159.493384 -396.867173)
			(xy 159.487616 -396.860014) (xy 159.465819 -396.83437) (xy 159.427872 -396.778782) (xy 159.396841 -396.719057)
			(xy 159.373169 -396.656051) (xy 159.357198 -396.590668) (xy 159.349155 -396.523845) (xy 159.349156 -396.45654)
			(xy 159.3572 -396.389717) (xy 159.373174 -396.324334) (xy 159.396847 -396.26133) (xy 159.42788 -396.201606)
			(xy 159.465828 -396.146018) (xy 159.487616 -396.120366) (xy 159.493411 -396.11322) (xy 159.499926 -396.09603)
			(xy 159.500316 -396.086838) (xy 159.500316 -395.92885) (xy 159.500804 -395.918684) (xy 159.508569 -395.899895)
			(xy 159.522934 -395.885509) (xy 159.541713 -395.877718) (xy 159.551878 -395.877288) (xy 160.268158 -395.877288)
			(xy 160.278333 -395.877699) (xy 160.297136 -395.88548) (xy 160.311525 -395.89987) (xy 160.319302 -395.918675)
			(xy 160.31972 -395.92885) (xy 160.31972 -396.086838) (xy 160.320108 -396.096028) (xy 160.326637 -396.113212)
			(xy 160.33242 -396.120366) (xy 160.354199 -396.146026) (xy 160.392151 -396.20161) (xy 160.423187 -396.261332)
			(xy 160.446862 -396.324336) (xy 160.462837 -396.389718) (xy 160.470882 -396.45654) (xy 160.470883 -396.523845)
			(xy 160.46284 -396.590668) (xy 160.446866 -396.65605) (xy 160.423193 -396.719054) (xy 160.392159 -396.778777)
			(xy 160.354208 -396.834362) (xy 160.33242 -396.860014) (xy 160.326637 -396.867169) (xy 160.320114 -396.884352)
			(xy 160.31972 -396.893542) (xy 160.31972 -397.38681) (xy 160.320121 -397.395998) (xy 160.326641 -397.413183)
			(xy 160.33242 -397.420338) (xy 160.354172 -397.44602) (xy 160.392124 -397.501601) (xy 160.420549 -397.556296)
			(xy 161.5488 -397.556296) (xy 161.556874 -397.489359) (xy 161.572908 -397.423871) (xy 161.596669 -397.360775)
			(xy 161.627817 -397.300979) (xy 161.665902 -397.245344) (xy 161.687764 -397.219678) (xy 161.69356 -397.212533)
			(xy 161.700073 -397.195342) (xy 161.700464 -397.18615) (xy 161.700464 -397.028924) (xy 161.701004 -397.018821)
			(xy 161.708727 -397.00015) (xy 161.723007 -396.985856) (xy 161.74167 -396.978114) (xy 161.751772 -396.977616)
			(xy 162.468052 -396.977616) (xy 162.478173 -396.978056) (xy 162.496879 -396.985791) (xy 162.511195 -397.000101)
			(xy 162.51894 -397.018803) (xy 162.51936 -397.028924) (xy 162.51936 -397.18615) (xy 162.519803 -397.195333)
			(xy 162.526295 -397.212518) (xy 162.53206 -397.219678) (xy 162.553935 -397.245334) (xy 162.592026 -397.300969)
			(xy 162.623179 -397.360766) (xy 162.646944 -397.423864) (xy 162.66298 -397.489355) (xy 162.671056 -397.556295)
			(xy 162.671055 -397.62372) (xy 162.662977 -397.69066) (xy 162.64694 -397.75615) (xy 162.623173 -397.819247)
			(xy 162.620757 -397.823885) (xy 163.748903 -397.823885) (xy 163.748907 -397.756458) (xy 163.756987 -397.689517)
			(xy 163.773027 -397.624026) (xy 163.796796 -397.560927) (xy 163.827951 -397.50113) (xy 163.866045 -397.445495)
			(xy 163.887912 -397.41983) (xy 163.893722 -397.412694) (xy 163.900228 -397.395497) (xy 163.900612 -397.386302)
			(xy 163.900612 -396.89405) (xy 163.900175 -396.884866) (xy 163.89368 -396.867681) (xy 163.887912 -396.860522)
			(xy 163.866038 -396.834865) (xy 163.827949 -396.77923) (xy 163.796798 -396.719432) (xy 163.773034 -396.656334)
			(xy 163.756998 -396.590844) (xy 163.748923 -396.523905) (xy 163.748924 -396.45648) (xy 163.757001 -396.389541)
			(xy 163.773038 -396.324051) (xy 163.796804 -396.260954) (xy 163.827956 -396.201157) (xy 163.866047 -396.145523)
			(xy 163.887912 -396.119858) (xy 163.89371 -396.112714) (xy 163.900224 -396.095523) (xy 163.900612 -396.08633)
			(xy 163.900612 -395.92885) (xy 163.901167 -395.91873) (xy 163.908873 -395.900015) (xy 163.923138 -395.885658)
			(xy 163.941803 -395.877832) (xy 163.95192 -395.877288) (xy 164.6682 -395.877288) (xy 164.678353 -395.877721)
			(xy 164.697103 -395.885515) (xy 164.711426 -395.899908) (xy 164.719127 -395.918695) (xy 164.719508 -395.92885)
			(xy 164.719508 -396.08633) (xy 164.719902 -396.095519) (xy 164.726426 -396.112703) (xy 164.732208 -396.119858)
			(xy 164.754062 -396.145531) (xy 164.79215 -396.201165) (xy 164.823301 -396.26096) (xy 164.847065 -396.324056)
			(xy 164.863101 -396.389544) (xy 164.871178 -396.456481) (xy 164.871179 -396.523904) (xy 164.863104 -396.590841)
			(xy 164.84707 -396.65633) (xy 164.823307 -396.719426) (xy 164.792158 -396.779222) (xy 164.754071 -396.834857)
			(xy 164.732208 -396.860522) (xy 164.726421 -396.867674) (xy 164.7199 -396.884859) (xy 164.719508 -396.89405)
			(xy 164.719508 -397.386302) (xy 164.719915 -397.395489) (xy 164.726431 -397.412674) (xy 164.732208 -397.41983)
			(xy 164.754034 -397.445526) (xy 164.792124 -397.501156) (xy 164.823276 -397.560948) (xy 164.846898 -397.62366)
			(xy 165.949096 -397.62366) (xy 165.949096 -397.556355) (xy 165.957139 -397.489533) (xy 165.973111 -397.424151)
			(xy 165.996783 -397.361147) (xy 166.027816 -397.301424) (xy 166.065765 -397.245838) (xy 166.087552 -397.220186)
			(xy 166.093343 -397.213037) (xy 166.09986 -397.195849) (xy 166.100252 -397.186658) (xy 166.100252 -397.028924)
			(xy 166.10074 -397.018777) (xy 166.108519 -397.000035) (xy 166.122895 -396.985712) (xy 166.141666 -396.978003)
			(xy 166.151814 -396.977616) (xy 166.868094 -396.977616) (xy 166.878217 -396.978131) (xy 166.896934 -396.985852)
			(xy 166.911289 -397.000129) (xy 166.919113 -397.018803) (xy 166.919656 -397.028924) (xy 166.919656 -397.186658)
			(xy 166.920096 -397.195842) (xy 166.92659 -397.213026) (xy 166.932356 -397.220186) (xy 166.954154 -397.24583)
			(xy 166.992103 -397.301417) (xy 167.023136 -397.361142) (xy 167.046808 -397.424148) (xy 167.062781 -397.489531)
			(xy 167.070824 -397.556355) (xy 167.070823 -397.62366) (xy 167.062778 -397.690484) (xy 167.046804 -397.755867)
			(xy 167.02313 -397.818872) (xy 167.020556 -397.823825) (xy 168.149223 -397.823825) (xy 168.149226 -397.756518)
			(xy 168.157274 -397.689693) (xy 168.17325 -397.624309) (xy 168.196925 -397.561304) (xy 168.22796 -397.501579)
			(xy 168.265911 -397.445991) (xy 168.2877 -397.420338) (xy 168.293505 -397.413199) (xy 168.300015 -397.396004)
			(xy 168.3004 -397.38681) (xy 168.3004 -396.893542) (xy 168.29997 -396.884357) (xy 168.29347 -396.867172)
			(xy 168.2877 -396.860014) (xy 168.265904 -396.834369) (xy 168.227958 -396.778781) (xy 168.196927 -396.719056)
			(xy 168.173256 -396.656051) (xy 168.157285 -396.590668) (xy 168.149243 -396.523845) (xy 168.149244 -396.45654)
			(xy 168.157288 -396.389717) (xy 168.173261 -396.324335) (xy 168.196933 -396.26133) (xy 168.227965 -396.201606)
			(xy 168.265913 -396.146019) (xy 168.2877 -396.120366) (xy 168.293494 -396.113219) (xy 168.30001 -396.09603)
			(xy 168.3004 -396.086838) (xy 168.3004 -395.92885) (xy 168.300904 -395.918686) (xy 168.308665 -395.8999)
			(xy 168.323026 -395.885515) (xy 168.341799 -395.877721) (xy 168.351962 -395.877288) (xy 169.068242 -395.877288)
			(xy 169.078423 -395.877631) (xy 169.097228 -395.885439) (xy 169.111613 -395.89985) (xy 169.119388 -395.918669)
			(xy 169.119804 -395.92885) (xy 169.119804 -396.086838) (xy 169.120195 -396.096027) (xy 169.126722 -396.113212)
			(xy 169.132504 -396.120366) (xy 169.154281 -396.146027) (xy 169.192227 -396.201613) (xy 169.223258 -396.261336)
			(xy 169.24693 -396.324339) (xy 169.262902 -396.38972) (xy 169.270946 -396.456541) (xy 169.270947 -396.523844)
			(xy 169.262905 -396.590665) (xy 169.246934 -396.656047) (xy 169.223264 -396.71905) (xy 169.192235 -396.778774)
			(xy 169.15429 -396.834361) (xy 169.132504 -396.860014) (xy 169.126719 -396.867168) (xy 169.120197 -396.884352)
			(xy 169.119804 -396.893542) (xy 169.119804 -397.38681) (xy 169.120209 -397.395998) (xy 169.126726 -397.413182)
			(xy 169.132504 -397.420338) (xy 169.154253 -397.446021) (xy 169.1922 -397.501604) (xy 169.22062 -397.556296)
			(xy 170.348863 -397.556296) (xy 170.356939 -397.489357) (xy 170.372975 -397.423868) (xy 170.39674 -397.360771)
			(xy 170.427892 -397.300976) (xy 170.465983 -397.245342) (xy 170.487848 -397.219678) (xy 170.493642 -397.212531)
			(xy 170.500157 -397.195342) (xy 170.500548 -397.18615) (xy 170.500548 -397.028924) (xy 170.501103 -397.018823)
			(xy 170.508823 -397.000155) (xy 170.523098 -396.985862) (xy 170.541756 -396.978117) (xy 170.551856 -396.977616)
			(xy 171.268136 -396.977616) (xy 171.278249 -396.978056) (xy 171.296931 -396.985808) (xy 171.311225 -397.000119)
			(xy 171.318956 -397.01881) (xy 171.319444 -397.028924) (xy 171.319444 -397.18615) (xy 171.319891 -397.195333)
			(xy 171.326381 -397.212517) (xy 171.332144 -397.219678) (xy 171.35402 -397.245334) (xy 171.392112 -397.300969)
			(xy 171.423265 -397.360766) (xy 171.447031 -397.423864) (xy 171.463068 -397.489355) (xy 171.471144 -397.556295)
			(xy 171.471143 -397.62372) (xy 171.463065 -397.69066) (xy 171.447027 -397.756151) (xy 171.423259 -397.819248)
			(xy 171.420874 -397.823826) (xy 172.54899 -397.823826) (xy 172.548993 -397.756517) (xy 172.557042 -397.689691)
			(xy 172.57302 -397.624306) (xy 172.5967 -397.5613) (xy 172.62774 -397.501575) (xy 172.665697 -397.44599)
			(xy 172.687488 -397.420338) (xy 172.693292 -397.413198) (xy 172.699803 -397.396004) (xy 172.700188 -397.38681)
			(xy 172.700188 -396.893542) (xy 172.69976 -396.884357) (xy 172.693259 -396.867172) (xy 172.687488 -396.860014)
			(xy 172.665689 -396.834371) (xy 172.627737 -396.778784) (xy 172.596702 -396.71906) (xy 172.573027 -396.656054)
			(xy 172.557054 -396.59067) (xy 172.54901 -396.523846) (xy 172.54901 -396.456539) (xy 172.557056 -396.389715)
			(xy 172.573032 -396.324332) (xy 172.596708 -396.261327) (xy 172.627745 -396.201603) (xy 172.665698 -396.146018)
			(xy 172.687488 -396.120366) (xy 172.69328 -396.113218) (xy 172.699798 -396.09603) (xy 172.700188 -396.086838)
			(xy 172.700188 -395.92885) (xy 172.700606 -395.918675) (xy 172.708384 -395.899872) (xy 172.722772 -395.885484)
			(xy 172.741575 -395.877706) (xy 172.75175 -395.877288) (xy 173.46803 -395.877288) (xy 173.47821 -395.87764)
			(xy 173.497015 -395.885445) (xy 173.5114 -395.899852) (xy 173.519175 -395.91867) (xy 173.519592 -395.92885)
			(xy 173.519592 -396.086838) (xy 173.519986 -396.096027) (xy 173.526511 -396.113211) (xy 173.532292 -396.120366)
			(xy 173.554069 -396.146027) (xy 173.592016 -396.201613) (xy 173.623048 -396.261335) (xy 173.64672 -396.324339)
			(xy 173.662693 -396.389719) (xy 173.670737 -396.456541) (xy 173.670738 -396.523844) (xy 173.662695 -396.590666)
			(xy 173.646725 -396.656047) (xy 173.623054 -396.719051) (xy 173.592024 -396.778774) (xy 173.554078 -396.834361)
			(xy 173.532292 -396.860014) (xy 173.526506 -396.867167) (xy 173.519985 -396.884351) (xy 173.519592 -396.893542)
			(xy 173.519592 -397.38681) (xy 173.519999 -397.395998) (xy 173.526515 -397.413182) (xy 173.532292 -397.420338)
			(xy 173.554041 -397.446021) (xy 173.591989 -397.501604) (xy 173.620441 -397.556355) (xy 174.749183 -397.556355)
			(xy 174.757226 -397.489534) (xy 174.773198 -397.424152) (xy 174.796869 -397.361148) (xy 174.827901 -397.301424)
			(xy 174.865849 -397.245838) (xy 174.887636 -397.220186) (xy 174.893426 -397.213036) (xy 174.899944 -397.195849)
			(xy 174.900336 -397.186658) (xy 174.900336 -397.028924) (xy 174.900742 -397.018767) (xy 174.908536 -397.000008)
			(xy 174.922939 -396.985682) (xy 174.941739 -396.977988) (xy 174.951898 -396.977616) (xy 175.668178 -396.977616)
			(xy 175.6783 -396.978144) (xy 175.697017 -396.98586) (xy 175.711373 -397.000133) (xy 175.719197 -397.018805)
			(xy 175.71974 -397.028924) (xy 175.71974 -397.186658) (xy 175.720184 -397.195841) (xy 175.726675 -397.213025)
			(xy 175.73244 -397.220186) (xy 175.754238 -397.24583) (xy 175.792188 -397.301417) (xy 175.823222 -397.361142)
			(xy 175.846895 -397.424147) (xy 175.862868 -397.489531) (xy 175.870912 -397.556354) (xy 175.870911 -397.623661)
			(xy 175.862865 -397.690484) (xy 175.846891 -397.755867) (xy 175.823216 -397.818872) (xy 175.79218 -397.878596)
			(xy 175.754229 -397.934182) (xy 175.73244 -397.959834) (xy 175.726639 -397.966976) (xy 175.720129 -397.984169)
			(xy 175.71974 -397.993362) (xy 175.71974 -398.486884) (xy 175.720171 -398.496069) (xy 175.726672 -398.513253)
			(xy 175.73244 -398.520412) (xy 175.754264 -398.546035) (xy 175.792213 -398.601625) (xy 175.823246 -398.661352)
			(xy 175.846918 -398.724361) (xy 175.862889 -398.789747) (xy 175.87093 -398.856573) (xy 175.870927 -398.923881)
			(xy 175.862879 -398.990707) (xy 175.846902 -399.056091) (xy 175.823224 -399.119097) (xy 175.792185 -399.178822)
			(xy 175.754231 -399.234408) (xy 175.73244 -399.26006) (xy 175.726628 -399.267194) (xy 175.720124 -399.284393)
			(xy 175.71974 -399.293588) (xy 175.71974 -399.451576) (xy 175.71926 -399.461724) (xy 175.71148 -399.480468)
			(xy 175.697101 -399.494791) (xy 175.678327 -399.502498) (xy 175.668178 -399.502884) (xy 174.951898 -399.502884)
			(xy 174.941774 -399.502376) (xy 174.923058 -399.494652) (xy 174.908702 -399.480372) (xy 174.900879 -399.461697)
			(xy 174.900336 -399.451576) (xy 174.900336 -399.293588) (xy 174.899924 -399.284401) (xy 174.893411 -399.267217)
			(xy 174.887636 -399.26006) (xy 174.865884 -399.234379) (xy 174.827934 -399.178796) (xy 174.7969 -399.119077)
			(xy 174.773225 -399.056076) (xy 174.75725 -398.990697) (xy 174.749203 -398.923878) (xy 174.749199 -398.856576)
			(xy 174.75724 -398.789756) (xy 174.773209 -398.724376) (xy 174.796878 -398.661373) (xy 174.827906 -398.60165)
			(xy 174.865851 -398.546064) (xy 174.887636 -398.520412) (xy 174.893457 -398.513284) (xy 174.899956 -398.49608)
			(xy 174.900336 -398.486884) (xy 174.900336 -397.993362) (xy 174.899936 -397.984174) (xy 174.893414 -397.96699)
			(xy 174.887636 -397.959834) (xy 174.865858 -397.934174) (xy 174.827909 -397.878588) (xy 174.796876 -397.818866)
			(xy 174.773202 -397.755863) (xy 174.757229 -397.690481) (xy 174.749184 -397.62366) (xy 174.749183 -397.556355)
			(xy 173.620441 -397.556355) (xy 173.623023 -397.561324) (xy 173.646696 -397.624324) (xy 173.662671 -397.689702)
			(xy 173.670718 -397.756521) (xy 173.670721 -397.823822) (xy 173.662681 -397.890642) (xy 173.646713 -397.956021)
			(xy 173.623046 -398.019024) (xy 173.592019 -398.078747) (xy 173.554077 -398.134334) (xy 173.532292 -398.159986)
			(xy 173.526475 -398.167117) (xy 173.519973 -398.184318) (xy 173.519592 -398.193514) (xy 173.519592 -398.351502)
			(xy 173.519069 -398.361656) (xy 173.511299 -398.38042) (xy 173.496943 -398.394784) (xy 173.478184 -398.402563)
			(xy 173.46803 -398.403064) (xy 172.75175 -398.403064) (xy 172.741582 -398.402595) (xy 172.722789 -398.394827)
			(xy 172.708402 -398.380455) (xy 172.700615 -398.36167) (xy 172.700188 -398.351502) (xy 172.700188 -398.193514)
			(xy 172.699774 -398.184327) (xy 172.693263 -398.167143) (xy 172.687488 -398.159986) (xy 172.665661 -398.134365)
			(xy 172.627711 -398.078775) (xy 172.596676 -398.019048) (xy 172.573004 -397.956039) (xy 172.557032 -397.890653)
			(xy 172.54899 -397.823826) (xy 171.420874 -397.823826) (xy 171.392104 -397.879044) (xy 171.354011 -397.934678)
			(xy 171.332144 -397.960342) (xy 171.32634 -397.967482) (xy 171.319831 -397.984677) (xy 171.319444 -397.99387)
			(xy 171.319444 -398.486376) (xy 171.319878 -398.49556) (xy 171.326376 -398.512744) (xy 171.332144 -398.519904)
			(xy 171.354045 -398.545539) (xy 171.392137 -398.601177) (xy 171.423289 -398.660976) (xy 171.447054 -398.724077)
			(xy 171.463088 -398.789571) (xy 171.471162 -398.856513) (xy 171.471159 -398.923941) (xy 171.463078 -398.990883)
			(xy 171.447037 -399.056374) (xy 171.423267 -399.119473) (xy 171.392109 -399.17927) (xy 171.354012 -399.234904)
			(xy 171.332144 -399.260568) (xy 171.326329 -399.2677) (xy 171.319827 -399.284901) (xy 171.319444 -399.294096)
			(xy 171.319444 -399.451576) (xy 171.318896 -399.461678) (xy 171.311175 -399.480347) (xy 171.296897 -399.494641)
			(xy 171.278237 -399.502385) (xy 171.268136 -399.502884) (xy 170.551856 -399.502884) (xy 170.541742 -399.50245)
			(xy 170.52306 -399.494695) (xy 170.508766 -399.480383) (xy 170.501036 -399.46169) (xy 170.500548 -399.451576)
			(xy 170.500548 -399.294096) (xy 170.500129 -399.28491) (xy 170.49362 -399.267726) (xy 170.487848 -399.260568)
			(xy 170.466018 -399.234874) (xy 170.427925 -399.179245) (xy 170.39677 -399.119453) (xy 170.373001 -399.05636)
			(xy 170.356962 -398.990874) (xy 170.348883 -398.923938) (xy 170.348879 -398.856516) (xy 170.356952 -398.789579)
			(xy 170.372985 -398.724092) (xy 170.396748 -398.660996) (xy 170.427897 -398.601201) (xy 170.465984 -398.545568)
			(xy 170.487848 -398.519904) (xy 170.493631 -398.51275) (xy 170.500153 -398.495566) (xy 170.500548 -398.486376)
			(xy 170.500548 -397.99387) (xy 170.500141 -397.984683) (xy 170.493624 -397.967499) (xy 170.487848 -397.960342)
			(xy 170.465992 -397.934669) (xy 170.4279 -397.879037) (xy 170.396746 -397.819242) (xy 170.372979 -397.756146)
			(xy 170.356942 -397.690658) (xy 170.348864 -397.623719) (xy 170.348863 -397.556296) (xy 169.22062 -397.556296)
			(xy 169.223233 -397.561324) (xy 169.246906 -397.624324) (xy 169.26288 -397.689702) (xy 169.270927 -397.756521)
			(xy 169.27093 -397.823822) (xy 169.26289 -397.890641) (xy 169.246923 -397.956021) (xy 169.223256 -398.019024)
			(xy 169.19223 -398.078746) (xy 169.154288 -398.134333) (xy 169.132504 -398.159986) (xy 169.126689 -398.167118)
			(xy 169.120185 -398.184319) (xy 169.119804 -398.193514) (xy 169.119804 -398.351502) (xy 169.119269 -398.361655)
			(xy 169.111502 -398.380416) (xy 169.097149 -398.394779) (xy 169.078394 -398.402561) (xy 169.068242 -398.403064)
			(xy 168.351962 -398.403064) (xy 168.341802 -398.402598) (xy 168.323032 -398.394811) (xy 168.308669 -398.380437)
			(xy 168.300895 -398.361662) (xy 168.3004 -398.351502) (xy 168.3004 -398.193514) (xy 168.299983 -398.184328)
			(xy 168.293474 -398.167143) (xy 168.2877 -398.159986) (xy 168.265876 -398.134364) (xy 168.227931 -398.078772)
			(xy 168.196902 -398.019044) (xy 168.173233 -397.956036) (xy 168.157263 -397.89065) (xy 168.149223 -397.823825)
			(xy 167.020556 -397.823825) (xy 166.992095 -397.878596) (xy 166.954145 -397.934182) (xy 166.932356 -397.959834)
			(xy 166.926557 -397.966977) (xy 166.920045 -397.984169) (xy 166.919656 -397.993362) (xy 166.919656 -398.486884)
			(xy 166.920084 -398.496069) (xy 166.926586 -398.513253) (xy 166.932356 -398.520412) (xy 166.954179 -398.546035)
			(xy 166.992127 -398.601625) (xy 167.023159 -398.661353) (xy 167.04683 -398.724361) (xy 167.062801 -398.789747)
			(xy 167.070842 -398.856573) (xy 167.070839 -398.923881) (xy 167.062791 -398.990706) (xy 167.046814 -399.05609)
			(xy 167.023137 -399.119097) (xy 166.9921 -399.178821) (xy 166.954146 -399.234408) (xy 166.932356 -399.26006)
			(xy 166.926546 -399.267195) (xy 166.92004 -399.284394) (xy 166.919656 -399.293588) (xy 166.919656 -399.451576)
			(xy 166.91916 -399.461722) (xy 166.911383 -399.480463) (xy 166.89701 -399.494785) (xy 166.878241 -399.502496)
			(xy 166.868094 -399.502884) (xy 166.151814 -399.502884) (xy 166.141691 -399.502363) (xy 166.122975 -399.494644)
			(xy 166.108619 -399.480369) (xy 166.100795 -399.461696) (xy 166.100252 -399.451576) (xy 166.100252 -399.293588)
			(xy 166.099836 -399.284402) (xy 166.093325 -399.267218) (xy 166.087552 -399.26006) (xy 166.065799 -399.234379)
			(xy 166.027849 -399.178797) (xy 165.996813 -399.119077) (xy 165.973138 -399.056077) (xy 165.957162 -398.990698)
			(xy 165.949115 -398.923878) (xy 165.949111 -398.856576) (xy 165.957152 -398.789755) (xy 165.973122 -398.724375)
			(xy 165.996791 -398.661372) (xy 166.027821 -398.60165) (xy 166.065766 -398.546064) (xy 166.087552 -398.520412)
			(xy 166.093375 -398.513286) (xy 166.099872 -398.49608) (xy 166.100252 -398.486884) (xy 166.100252 -397.993362)
			(xy 166.099848 -397.984174) (xy 166.093329 -397.966991) (xy 166.087552 -397.959834) (xy 166.065774 -397.934174)
			(xy 166.027824 -397.878589) (xy 165.99679 -397.818866) (xy 165.973116 -397.755863) (xy 165.957142 -397.690482)
			(xy 165.949096 -397.62366) (xy 164.846898 -397.62366) (xy 164.847042 -397.624041) (xy 164.863079 -397.689526)
			(xy 164.871158 -397.756461) (xy 164.871162 -397.823882) (xy 164.86309 -397.890817) (xy 164.847058 -397.956304)
			(xy 164.823299 -398.019399) (xy 164.792153 -398.079195) (xy 164.754069 -398.134829) (xy 164.732208 -398.160494)
			(xy 164.726432 -398.167654) (xy 164.719905 -398.184833) (xy 164.719508 -398.194022) (xy 164.719508 -398.351502)
			(xy 164.718976 -398.361623) (xy 164.711257 -398.380335) (xy 164.696985 -398.394689) (xy 164.678318 -398.402517)
			(xy 164.6682 -398.403064) (xy 163.95192 -398.403064) (xy 163.941763 -398.402661) (xy 163.923004 -398.394866)
			(xy 163.908678 -398.380462) (xy 163.900984 -398.361662) (xy 163.900612 -398.351502) (xy 163.900612 -398.194022)
			(xy 163.900188 -398.184836) (xy 163.893684 -398.167652) (xy 163.887912 -398.160494) (xy 163.86601 -398.13486)
			(xy 163.827922 -398.079221) (xy 163.796772 -398.019421) (xy 163.77301 -397.95632) (xy 163.756976 -397.890827)
			(xy 163.748903 -397.823885) (xy 162.620757 -397.823885) (xy 162.592019 -397.879044) (xy 162.553926 -397.934677)
			(xy 162.53206 -397.960342) (xy 162.526258 -397.967483) (xy 162.519748 -397.984677) (xy 162.51936 -397.99387)
			(xy 162.51936 -398.486376) (xy 162.51979 -398.495561) (xy 162.526291 -398.512745) (xy 162.53206 -398.519904)
			(xy 162.553961 -398.545539) (xy 162.592051 -398.601177) (xy 162.623202 -398.660977) (xy 162.646966 -398.724078)
			(xy 162.663 -398.789571) (xy 162.671074 -398.856513) (xy 162.671071 -398.923941) (xy 162.662991 -398.990882)
			(xy 162.64695 -399.056374) (xy 162.62318 -399.119472) (xy 162.592023 -399.179269) (xy 162.553928 -399.234903)
			(xy 162.53206 -399.260568) (xy 162.526247 -399.267701) (xy 162.519743 -399.284901) (xy 162.51936 -399.294096)
			(xy 162.51936 -399.451576) (xy 162.518964 -399.461702) (xy 162.511216 -399.480413) (xy 162.496893 -399.494729)
			(xy 162.478178 -399.502468) (xy 162.468052 -399.502884) (xy 161.751772 -399.502884) (xy 161.741659 -399.502438)
			(xy 161.722978 -399.494688) (xy 161.708683 -399.480379) (xy 161.700952 -399.461689) (xy 161.700464 -399.451576)
			(xy 161.700464 -399.294096) (xy 161.700041 -399.28491) (xy 161.693535 -399.267727) (xy 161.687764 -399.260568)
			(xy 161.665937 -399.234873) (xy 161.627849 -399.179242) (xy 161.596699 -399.119449) (xy 161.572934 -399.056357)
			(xy 161.556897 -398.990871) (xy 161.548819 -398.923937) (xy 161.548816 -398.856517) (xy 161.556888 -398.789582)
			(xy 161.572918 -398.724095) (xy 161.596677 -398.661) (xy 161.627821 -398.601205) (xy 161.665903 -398.54557)
			(xy 161.687764 -398.519904) (xy 161.693549 -398.512751) (xy 161.700069 -398.495566) (xy 161.700464 -398.486376)
			(xy 161.700464 -397.99387) (xy 161.700054 -397.984683) (xy 161.693538 -397.9675) (xy 161.687764 -397.960342)
			(xy 161.665911 -397.934668) (xy 161.627824 -397.879034) (xy 161.596675 -397.819239) (xy 161.572912 -397.756143)
			(xy 161.556877 -397.690655) (xy 161.548801 -397.623719) (xy 161.5488 -397.556296) (xy 160.420549 -397.556296)
			(xy 160.423161 -397.561321) (xy 160.446838 -397.624321) (xy 160.462815 -397.6897) (xy 160.470863 -397.75652)
			(xy 160.470866 -397.823823) (xy 160.462825 -397.890644) (xy 160.446855 -397.956024) (xy 160.423185 -398.019027)
			(xy 160.392154 -398.078749) (xy 160.354207 -398.134334) (xy 160.33242 -398.159986) (xy 160.326607 -398.16712)
			(xy 160.320101 -398.184319) (xy 160.31972 -398.193514) (xy 160.31972 -398.351502) (xy 160.319337 -398.361679)
			(xy 160.311543 -398.380482) (xy 160.297145 -398.394868) (xy 160.278335 -398.402645) (xy 160.268158 -398.403064)
			(xy 159.551878 -398.403064) (xy 159.541719 -398.402585) (xy 159.52295 -398.394804) (xy 159.508585 -398.380433)
			(xy 159.500811 -398.361661) (xy 159.500316 -398.351502) (xy 159.500316 -398.193514) (xy 159.499895 -398.184328)
			(xy 159.493388 -398.167144) (xy 159.487616 -398.159986) (xy 159.465792 -398.134364) (xy 159.427845 -398.078773)
			(xy 159.396815 -398.019045) (xy 159.373145 -397.956036) (xy 159.357176 -397.890651) (xy 159.349135 -397.823825)
			(xy 154.57678 -397.823825) (xy 154.57678 -401.723737) (xy 159.349146 -401.723737) (xy 159.349148 -401.65643)
			(xy 159.357194 -401.589607) (xy 159.373169 -401.524223) (xy 159.396843 -401.461218) (xy 159.427878 -401.401494)
			(xy 159.465828 -401.345906) (xy 159.487616 -401.320254) (xy 159.493416 -401.313112) (xy 159.499928 -401.295919)
			(xy 159.500316 -401.286726) (xy 159.500316 -400.793458) (xy 159.499923 -400.784269) (xy 159.493397 -400.767085)
			(xy 159.487616 -400.75993) (xy 159.465835 -400.734273) (xy 159.427887 -400.678686) (xy 159.396855 -400.618963)
			(xy 159.373183 -400.55596) (xy 159.35721 -400.490578) (xy 159.349166 -400.423757) (xy 159.349165 -400.356452)
			(xy 159.357209 -400.289631) (xy 159.37318 -400.224249) (xy 159.396851 -400.161245) (xy 159.427883 -400.101521)
			(xy 159.465829 -400.045934) (xy 159.487616 -400.020282) (xy 159.493405 -400.013131) (xy 159.499923 -399.995945)
			(xy 159.500316 -399.986754) (xy 159.500316 -399.828766) (xy 159.500805 -399.818609) (xy 159.508586 -399.799843)
			(xy 159.522953 -399.78548) (xy 159.541721 -399.777703) (xy 159.551878 -399.777204) (xy 160.268158 -399.777204)
			(xy 160.278323 -399.777697) (xy 160.29711 -399.785462) (xy 160.311495 -399.799826) (xy 160.319288 -399.818602)
			(xy 160.31972 -399.828766) (xy 160.31972 -399.986754) (xy 160.320148 -399.995939) (xy 160.326649 -400.013124)
			(xy 160.33242 -400.020282) (xy 160.354215 -400.045929) (xy 160.392166 -400.101515) (xy 160.423201 -400.161239)
			(xy 160.446876 -400.224244) (xy 160.462849 -400.289628) (xy 160.470894 -400.356451) (xy 160.470893 -400.423758)
			(xy 160.462848 -400.490581) (xy 160.446873 -400.555964) (xy 160.423198 -400.618969) (xy 160.392161 -400.678693)
			(xy 160.354209 -400.734278) (xy 160.33242 -400.75993) (xy 160.326631 -400.76708) (xy 160.320111 -400.784267)
			(xy 160.31972 -400.793458) (xy 160.31972 -401.286726) (xy 160.320113 -401.295915) (xy 160.326638 -401.313099)
			(xy 160.33242 -401.320254) (xy 160.354187 -401.345923) (xy 160.392139 -401.401506) (xy 160.423176 -401.461227)
			(xy 160.446852 -401.52423) (xy 160.462827 -401.58961) (xy 160.470874 -401.656431) (xy 160.470876 -401.723735)
			(xy 160.462833 -401.790557) (xy 160.446862 -401.855939) (xy 160.423189 -401.918943) (xy 160.392156 -401.978665)
			(xy 160.354208 -402.03425) (xy 160.33242 -402.059902) (xy 160.326642 -402.067061) (xy 160.320116 -402.084241)
			(xy 160.31972 -402.09343) (xy 160.31972 -402.251418) (xy 160.31935 -402.261596) (xy 160.311551 -402.280399)
			(xy 160.297149 -402.294785) (xy 160.278336 -402.302562) (xy 160.268158 -402.30298) (xy 159.551878 -402.30298)
			(xy 159.541721 -402.302485) (xy 159.522955 -402.294707) (xy 159.508591 -402.280342) (xy 159.500814 -402.261575)
			(xy 159.500316 -402.251418) (xy 159.500316 -402.09343) (xy 159.499888 -402.084245) (xy 159.493386 -402.06706)
			(xy 159.487616 -402.059902) (xy 159.465807 -402.034267) (xy 159.427861 -401.978678) (xy 159.39683 -401.918952)
			(xy 159.373159 -401.855945) (xy 159.357188 -401.790561) (xy 159.349146 -401.723737) (xy 154.57678 -401.723737)
			(xy 154.57678 -402.823877) (xy 161.54876 -402.823877) (xy 161.548765 -402.756451) (xy 161.556845 -402.68951)
			(xy 161.572884 -402.624018) (xy 161.596652 -402.56092) (xy 161.627806 -402.501122) (xy 161.665898 -402.445486)
			(xy 161.687764 -402.41982) (xy 161.693585 -402.412692) (xy 161.700083 -402.395488) (xy 161.700464 -402.386292)
			(xy 161.700464 -401.89404) (xy 161.70002 -401.884857) (xy 161.693528 -401.867673) (xy 161.687764 -401.860512)
			(xy 161.665882 -401.834862) (xy 161.627796 -401.779225) (xy 161.596648 -401.719426) (xy 161.572887 -401.656327)
			(xy 161.556854 -401.590837) (xy 161.54878 -401.523897) (xy 161.548782 -401.456473) (xy 161.556859 -401.389534)
			(xy 161.572896 -401.324044) (xy 161.59666 -401.260946) (xy 161.627811 -401.201149) (xy 161.6659 -401.145514)
			(xy 161.687764 -401.119848) (xy 161.693573 -401.112712) (xy 161.700078 -401.095514) (xy 161.700464 -401.08632)
			(xy 161.700464 -400.92884) (xy 161.700948 -400.918725) (xy 161.708676 -400.900029) (xy 161.722972 -400.885714)
			(xy 161.741657 -400.877961) (xy 161.751772 -400.877532) (xy 162.468052 -400.877532) (xy 162.478175 -400.877956)
			(xy 162.496884 -400.885694) (xy 162.511201 -400.900009) (xy 162.518942 -400.918717) (xy 162.51936 -400.92884)
			(xy 162.51936 -401.08632) (xy 162.519769 -401.095507) (xy 162.526285 -401.112691) (xy 162.53206 -401.119848)
			(xy 162.553906 -401.145529) (xy 162.591998 -401.20116) (xy 162.623151 -401.260954) (xy 162.646919 -401.324049)
			(xy 162.662957 -401.389536) (xy 162.671035 -401.456474) (xy 162.671037 -401.523896) (xy 162.662962 -401.590834)
			(xy 162.646927 -401.656323) (xy 162.623164 -401.719419) (xy 162.620884 -401.723796) (xy 163.748915 -401.723796)
			(xy 163.748917 -401.656371) (xy 163.756995 -401.589431) (xy 163.773033 -401.52394) (xy 163.7968 -401.460842)
			(xy 163.827954 -401.401046) (xy 163.866046 -401.345411) (xy 163.887912 -401.319746) (xy 163.893715 -401.312606)
			(xy 163.900226 -401.295411) (xy 163.900612 -401.286218) (xy 163.900612 -400.793966) (xy 163.900216 -400.784777)
			(xy 163.893692 -400.767593) (xy 163.887912 -400.760438) (xy 163.866054 -400.734768) (xy 163.827964 -400.679135)
			(xy 163.796812 -400.619339) (xy 163.773047 -400.556243) (xy 163.757011 -400.490754) (xy 163.748934 -400.423816)
			(xy 163.748934 -400.356393) (xy 163.757009 -400.289455) (xy 163.773044 -400.223966) (xy 163.796809 -400.160869)
			(xy 163.827959 -400.101073) (xy 163.866048 -400.045439) (xy 163.887912 -400.019774) (xy 163.893703 -400.012625)
			(xy 163.900221 -399.995437) (xy 163.900612 -399.986246) (xy 163.900612 -399.828766) (xy 163.901098 -399.818641)
			(xy 163.908832 -399.799924) (xy 163.923117 -399.78557) (xy 163.941797 -399.777747) (xy 163.95192 -399.777204)
			(xy 164.6682 -399.777204) (xy 164.678355 -399.777622) (xy 164.697108 -399.785418) (xy 164.711431 -399.799816)
			(xy 164.71913 -399.818609) (xy 164.719508 -399.828766) (xy 164.719508 -399.986246) (xy 164.719942 -399.995431)
			(xy 164.726439 -400.012615) (xy 164.732208 -400.019774) (xy 164.754078 -400.045435) (xy 164.792166 -400.10107)
			(xy 164.823316 -400.160867) (xy 164.847079 -400.223964) (xy 164.863114 -400.289454) (xy 164.871189 -400.356393)
			(xy 164.871189 -400.423817) (xy 164.863112 -400.490755) (xy 164.847076 -400.556244) (xy 164.823312 -400.619341)
			(xy 164.792161 -400.679138) (xy 164.754072 -400.734773) (xy 164.732208 -400.760438) (xy 164.726414 -400.767585)
			(xy 164.719897 -400.784774) (xy 164.719508 -400.793966) (xy 164.719508 -401.286218) (xy 164.719908 -401.295406)
			(xy 164.726429 -401.312591) (xy 164.732208 -401.319746) (xy 164.75405 -401.345429) (xy 164.792139 -401.401061)
			(xy 164.82329 -401.460855) (xy 164.847055 -401.52395) (xy 164.863092 -401.589436) (xy 164.871169 -401.656373)
			(xy 164.871171 -401.723794) (xy 164.863098 -401.790731) (xy 164.847065 -401.856219) (xy 164.823304 -401.919315)
			(xy 164.792156 -401.97911) (xy 164.75407 -402.034745) (xy 164.732208 -402.06041) (xy 164.726426 -402.067565)
			(xy 164.719902 -402.084748) (xy 164.719508 -402.093938) (xy 164.719508 -402.251418) (xy 164.71899 -402.26154)
			(xy 164.711265 -402.280253) (xy 164.696989 -402.294607) (xy 164.678319 -402.302434) (xy 164.6682 -402.30298)
			(xy 163.95192 -402.30298) (xy 163.941765 -402.302562) (xy 163.923009 -402.294769) (xy 163.908684 -402.280371)
			(xy 163.900987 -402.261575) (xy 163.900612 -402.251418) (xy 163.900612 -402.093938) (xy 163.900181 -402.084753)
			(xy 163.893681 -402.067569) (xy 163.887912 -402.06041) (xy 163.866026 -402.034763) (xy 163.827937 -401.979126)
			(xy 163.796787 -401.919327) (xy 163.773023 -401.856228) (xy 163.756989 -401.790737) (xy 163.748915 -401.723796)
			(xy 162.620884 -401.723796) (xy 162.592013 -401.779214) (xy 162.553924 -401.834847) (xy 162.53206 -401.860512)
			(xy 162.526271 -401.867662) (xy 162.519753 -401.884849) (xy 162.51936 -401.89404) (xy 162.51936 -402.386292)
			(xy 162.519783 -402.395478) (xy 162.526289 -402.412662) (xy 162.53206 -402.41982) (xy 162.553878 -402.445523)
			(xy 162.591971 -402.501152) (xy 162.623126 -402.560942) (xy 162.646895 -402.624034) (xy 162.662935 -402.689519)
			(xy 162.671015 -402.756454) (xy 162.671019 -402.823818) (xy 165.949055 -402.823818) (xy 165.94906 -402.756509)
			(xy 165.957109 -402.689683) (xy 165.973087 -402.624298) (xy 165.996766 -402.561292) (xy 166.027805 -402.501567)
			(xy 166.065761 -402.44598) (xy 166.087552 -402.420328) (xy 166.093368 -402.413197) (xy 166.09987 -402.395995)
			(xy 166.100252 -402.3868) (xy 166.100252 -401.893532) (xy 166.099815 -401.884348) (xy 166.093319 -401.867164)
			(xy 166.087552 -401.860004) (xy 166.065744 -401.834368) (xy 166.027795 -401.77878) (xy 165.996762 -401.719054)
			(xy 165.97309 -401.656047) (xy 165.957118 -401.590663) (xy 165.949075 -401.523838) (xy 165.949077 -401.456532)
			(xy 165.957123 -401.389707) (xy 165.973098 -401.324324) (xy 165.996774 -401.261318) (xy 166.02781 -401.201594)
			(xy 166.065762 -401.146008) (xy 166.087552 -401.120356) (xy 166.093356 -401.113216) (xy 166.099865 -401.096021)
			(xy 166.100252 -401.086828) (xy 166.100252 -400.92884) (xy 166.100754 -400.918694) (xy 166.108527 -400.899952)
			(xy 166.122899 -400.885629) (xy 166.141667 -400.87792) (xy 166.151814 -400.877532) (xy 166.868094 -400.877532)
			(xy 166.878219 -400.878031) (xy 166.896939 -400.885756) (xy 166.911295 -400.900038) (xy 166.919116 -400.918717)
			(xy 166.919656 -400.92884) (xy 166.919656 -401.086828) (xy 166.920063 -401.096015) (xy 166.92658 -401.113199)
			(xy 166.932356 -401.120356) (xy 166.954124 -401.146024) (xy 166.992074 -401.201608) (xy 167.023108 -401.26133)
			(xy 167.046782 -401.324332) (xy 167.062757 -401.389712) (xy 167.070803 -401.456533) (xy 167.070804 -401.523837)
			(xy 167.062762 -401.590658) (xy 167.046791 -401.656039) (xy 167.02312 -401.719043) (xy 167.020682 -401.723736)
			(xy 168.149234 -401.723736) (xy 168.149236 -401.65643) (xy 168.157282 -401.589607) (xy 168.173256 -401.524224)
			(xy 168.19693 -401.461219) (xy 168.227963 -401.401494) (xy 168.265912 -401.345907) (xy 168.2877 -401.320254)
			(xy 168.293499 -401.31311) (xy 168.300012 -401.295919) (xy 168.3004 -401.286726) (xy 168.3004 -400.793458)
			(xy 168.30001 -400.784269) (xy 168.293482 -400.767084) (xy 168.2877 -400.75993) (xy 168.265919 -400.734272)
			(xy 168.227973 -400.678686) (xy 168.196942 -400.618963) (xy 168.17327 -400.555959) (xy 168.157298 -400.490578)
			(xy 168.149254 -400.423756) (xy 168.149253 -400.356453) (xy 168.157296 -400.289631) (xy 168.173267 -400.22425)
			(xy 168.196938 -400.161246) (xy 168.227968 -400.101522) (xy 168.265914 -400.045935) (xy 168.2877 -400.020282)
			(xy 168.293487 -400.01313) (xy 168.300007 -399.995945) (xy 168.3004 -399.986754) (xy 168.3004 -399.828766)
			(xy 168.300905 -399.818611) (xy 168.308683 -399.799848) (xy 168.323045 -399.785485) (xy 168.341807 -399.777705)
			(xy 168.351962 -399.777204) (xy 169.068242 -399.777204) (xy 169.078398 -399.777698) (xy 169.097162 -399.78548)
			(xy 169.111524 -399.799845) (xy 169.119303 -399.81861) (xy 169.119804 -399.828766) (xy 169.119804 -399.986754)
			(xy 169.120235 -399.995939) (xy 169.126734 -400.013124) (xy 169.132504 -400.020282) (xy 169.154296 -400.04593)
			(xy 169.192242 -400.101518) (xy 169.223273 -400.161243) (xy 169.246943 -400.224248) (xy 169.262915 -400.28963)
			(xy 169.270958 -400.356452) (xy 169.270957 -400.423757) (xy 169.262913 -400.490579) (xy 169.246941 -400.555961)
			(xy 169.223269 -400.618966) (xy 169.192237 -400.67869) (xy 169.154291 -400.734277) (xy 169.132504 -400.75993)
			(xy 169.126713 -400.767079) (xy 169.120195 -400.784267) (xy 169.119804 -400.793458) (xy 169.119804 -401.286726)
			(xy 169.1202 -401.295915) (xy 169.126723 -401.313099) (xy 169.132504 -401.320254) (xy 169.154269 -401.345925)
			(xy 169.192215 -401.401509) (xy 169.223247 -401.461231) (xy 169.246919 -401.524233) (xy 169.262893 -401.589612)
			(xy 169.270938 -401.656432) (xy 169.27094 -401.723735) (xy 169.262899 -401.790555) (xy 169.246929 -401.855936)
			(xy 169.223261 -401.918939) (xy 169.192232 -401.978662) (xy 169.154289 -402.034249) (xy 169.132504 -402.059902)
			(xy 169.126725 -402.067059) (xy 169.1202 -402.084241) (xy 169.119804 -402.09343) (xy 169.119804 -402.251418)
			(xy 169.119283 -402.261572) (xy 169.11151 -402.280333) (xy 169.097154 -402.294697) (xy 169.078396 -402.302478)
			(xy 169.068242 -402.30298) (xy 168.351962 -402.30298) (xy 168.341804 -402.302498) (xy 168.323037 -402.294715)
			(xy 168.308674 -402.280346) (xy 168.300898 -402.261576) (xy 168.3004 -402.251418) (xy 168.3004 -402.09343)
			(xy 168.299975 -402.084244) (xy 168.293472 -402.06706) (xy 168.2877 -402.059902) (xy 168.265892 -402.034267)
			(xy 168.227946 -401.978677) (xy 168.196916 -401.918951) (xy 168.173246 -401.855944) (xy 168.157276 -401.79056)
			(xy 168.149234 -401.723736) (xy 167.020682 -401.723736) (xy 166.992089 -401.778766) (xy 166.954142 -401.834352)
			(xy 166.932356 -401.860004) (xy 166.92657 -401.867156) (xy 166.92005 -401.884342) (xy 166.919656 -401.893532)
			(xy 166.919656 -402.3868) (xy 166.920076 -402.395986) (xy 166.926584 -402.41317) (xy 166.932356 -402.420328)
			(xy 166.954097 -402.446019) (xy 166.992047 -402.5016) (xy 167.023083 -402.561318) (xy 167.046758 -402.624317)
			(xy 167.062735 -402.689695) (xy 167.070783 -402.756513) (xy 167.070787 -402.823815) (xy 167.070779 -402.823878)
			(xy 170.348823 -402.823878) (xy 170.348828 -402.75645) (xy 170.356909 -402.689507) (xy 170.372951 -402.624015)
			(xy 170.396723 -402.560916) (xy 170.427882 -402.501119) (xy 170.465979 -402.445484) (xy 170.487848 -402.41982)
			(xy 170.493667 -402.412691) (xy 170.500167 -402.395488) (xy 170.500548 -402.386292) (xy 170.500548 -401.89404)
			(xy 170.500108 -401.884856) (xy 170.493614 -401.867672) (xy 170.487848 -401.860512) (xy 170.465963 -401.834864)
			(xy 170.427871 -401.779228) (xy 170.396719 -401.71943) (xy 170.372954 -401.656331) (xy 170.356918 -401.590839)
			(xy 170.348843 -401.523898) (xy 170.348845 -401.456472) (xy 170.356924 -401.389531) (xy 170.372963 -401.324041)
			(xy 170.396731 -401.260943) (xy 170.427887 -401.201146) (xy 170.465981 -401.145512) (xy 170.487848 -401.119848)
			(xy 170.493655 -401.112711) (xy 170.500162 -401.095514) (xy 170.500548 -401.08632) (xy 170.500548 -400.92884)
			(xy 170.501117 -400.91874) (xy 170.508832 -400.900073) (xy 170.523102 -400.885779) (xy 170.541757 -400.878033)
			(xy 170.551856 -400.877532) (xy 171.268136 -400.877532) (xy 171.278265 -400.877887) (xy 171.296975 -400.885653)
			(xy 171.311289 -400.899989) (xy 171.319028 -400.918711) (xy 171.319444 -400.92884) (xy 171.319444 -401.08632)
			(xy 171.319857 -401.095507) (xy 171.32637 -401.11269) (xy 171.332144 -401.119848) (xy 171.35399 -401.145528)
			(xy 171.392083 -401.20116) (xy 171.423238 -401.260953) (xy 171.447006 -401.324048) (xy 171.463044 -401.389536)
			(xy 171.471123 -401.456473) (xy 171.471124 -401.523897) (xy 171.46305 -401.590834) (xy 171.447015 -401.656323)
			(xy 171.42325 -401.719419) (xy 171.421001 -401.723737) (xy 172.549001 -401.723737) (xy 172.549003 -401.65643)
			(xy 172.55705 -401.589605) (xy 172.573027 -401.524221) (xy 172.596704 -401.461215) (xy 172.627743 -401.401491)
			(xy 172.665697 -401.345906) (xy 172.687488 -401.320254) (xy 172.693285 -401.313109) (xy 172.6998 -401.295918)
			(xy 172.700188 -401.286726) (xy 172.700188 -400.793458) (xy 172.699801 -400.784268) (xy 172.693272 -400.767084)
			(xy 172.687488 -400.75993) (xy 172.665705 -400.734274) (xy 172.627752 -400.678689) (xy 172.596716 -400.618966)
			(xy 172.573041 -400.555962) (xy 172.557066 -400.49058) (xy 172.549021 -400.423757) (xy 172.54902 -400.356452)
			(xy 172.557065 -400.289629) (xy 172.573038 -400.224246) (xy 172.596713 -400.161242) (xy 172.627748 -400.101519)
			(xy 172.665699 -400.045933) (xy 172.687488 -400.020282) (xy 172.693273 -400.013129) (xy 172.699795 -399.995944)
			(xy 172.700188 -399.986754) (xy 172.700188 -399.828766) (xy 172.700537 -399.818586) (xy 172.708343 -399.799781)
			(xy 172.722752 -399.785395) (xy 172.741569 -399.777621) (xy 172.75175 -399.777204) (xy 173.46803 -399.777204)
			(xy 173.478186 -399.777708) (xy 173.496949 -399.785486) (xy 173.511312 -399.799848) (xy 173.519091 -399.818611)
			(xy 173.519592 -399.828766) (xy 173.519592 -399.986754) (xy 173.520026 -399.995939) (xy 173.526523 -400.013123)
			(xy 173.532292 -400.020282) (xy 173.554085 -400.04593) (xy 173.592031 -400.101518) (xy 173.623063 -400.161242)
			(xy 173.646734 -400.224247) (xy 173.662705 -400.289629) (xy 173.670749 -400.356452) (xy 173.670748 -400.423757)
			(xy 173.662704 -400.490579) (xy 173.646731 -400.555962) (xy 173.623059 -400.618966) (xy 173.592027 -400.67869)
			(xy 173.554079 -400.734277) (xy 173.532292 -400.75993) (xy 173.526499 -400.767078) (xy 173.519983 -400.784266)
			(xy 173.519592 -400.793458) (xy 173.519592 -401.286726) (xy 173.519991 -401.295914) (xy 173.526513 -401.313099)
			(xy 173.532292 -401.320254) (xy 173.554057 -401.345924) (xy 173.592005 -401.401509) (xy 173.623037 -401.46123)
			(xy 173.64671 -401.524232) (xy 173.662683 -401.589612) (xy 173.670729 -401.656432) (xy 173.670731 -401.723735)
			(xy 173.662689 -401.790555) (xy 173.64672 -401.855936) (xy 173.623051 -401.918939) (xy 173.592022 -401.978663)
			(xy 173.554077 -402.034249) (xy 173.532292 -402.059902) (xy 173.526511 -402.067058) (xy 173.519987 -402.08424)
			(xy 173.519592 -402.09343) (xy 173.519592 -402.251418) (xy 173.519082 -402.261573) (xy 173.511308 -402.280337)
			(xy 173.496947 -402.294701) (xy 173.478185 -402.30248) (xy 173.46803 -402.30298) (xy 172.75175 -402.30298)
			(xy 172.741584 -402.302496) (xy 172.722794 -402.29473) (xy 172.708408 -402.280363) (xy 172.700618 -402.261584)
			(xy 172.700188 -402.251418) (xy 172.700188 -402.09343) (xy 172.699766 -402.084244) (xy 172.693261 -402.067059)
			(xy 172.687488 -402.059902) (xy 172.665677 -402.034268) (xy 172.627726 -401.97868) (xy 172.596691 -401.918955)
			(xy 172.573017 -401.855948) (xy 172.557044 -401.790563) (xy 172.549001 -401.723737) (xy 171.421001 -401.723737)
			(xy 171.392099 -401.779215) (xy 171.354009 -401.834848) (xy 171.332144 -401.860512) (xy 171.326353 -401.867661)
			(xy 171.319836 -401.884849) (xy 171.319444 -401.89404) (xy 171.319444 -402.386292) (xy 171.31987 -402.395477)
			(xy 171.326374 -402.412661) (xy 171.332144 -402.41982) (xy 171.353963 -402.445523) (xy 171.392057 -402.501151)
			(xy 171.423213 -402.560941) (xy 171.446982 -402.624033) (xy 171.463022 -402.689518) (xy 171.471103 -402.756453)
			(xy 171.471107 -402.823818) (xy 174.749143 -402.823818) (xy 174.749147 -402.75651) (xy 174.757196 -402.689684)
			(xy 174.773174 -402.624299) (xy 174.796852 -402.561292) (xy 174.827891 -402.501567) (xy 174.865845 -402.44598)
			(xy 174.887636 -402.420328) (xy 174.89345 -402.413195) (xy 174.899953 -402.395995) (xy 174.900336 -402.3868)
			(xy 174.900336 -401.893532) (xy 174.899902 -401.884348) (xy 174.893404 -401.867163) (xy 174.887636 -401.860004)
			(xy 174.865829 -401.834368) (xy 174.827881 -401.778779) (xy 174.796848 -401.719053) (xy 174.773177 -401.656047)
			(xy 174.757205 -401.590663) (xy 174.749163 -401.523838) (xy 174.749165 -401.456532) (xy 174.757211 -401.389708)
			(xy 174.773186 -401.324324) (xy 174.796861 -401.261319) (xy 174.827896 -401.201595) (xy 174.865847 -401.146008)
			(xy 174.887636 -401.120356) (xy 174.893438 -401.113215) (xy 174.899949 -401.096021) (xy 174.900336 -401.086828)
			(xy 174.900336 -400.92884) (xy 174.900755 -400.918684) (xy 174.908544 -400.899926) (xy 174.922943 -400.8856)
			(xy 174.94174 -400.877905) (xy 174.951898 -400.877532) (xy 175.668178 -400.877532) (xy 175.678302 -400.878044)
			(xy 175.697022 -400.885763) (xy 175.711378 -400.900042) (xy 175.7192 -400.918718) (xy 175.71974 -400.92884)
			(xy 175.71974 -401.086828) (xy 175.72015 -401.096015) (xy 175.726665 -401.113198) (xy 175.73244 -401.120356)
			(xy 175.754209 -401.146024) (xy 175.792159 -401.201608) (xy 175.823195 -401.261329) (xy 175.846869 -401.324331)
			(xy 175.862844 -401.389712) (xy 175.870891 -401.456533) (xy 175.870892 -401.523837) (xy 175.86285 -401.590658)
			(xy 175.846878 -401.65604) (xy 175.823207 -401.719044) (xy 175.792175 -401.778766) (xy 175.754227 -401.834352)
			(xy 175.73244 -401.860004) (xy 175.726652 -401.867155) (xy 175.720134 -401.884341) (xy 175.71974 -401.893532)
			(xy 175.71974 -402.3868) (xy 175.720164 -402.395985) (xy 175.726669 -402.413169) (xy 175.73244 -402.420328)
			(xy 175.754181 -402.446019) (xy 175.792133 -402.501599) (xy 175.823169 -402.561317) (xy 175.846846 -402.624317)
			(xy 175.862823 -402.689694) (xy 175.870871 -402.756513) (xy 175.870875 -402.823815) (xy 175.862835 -402.890634)
			(xy 175.846867 -402.956014) (xy 175.823199 -403.019017) (xy 175.79217 -403.078739) (xy 175.754225 -403.134324)
			(xy 175.73244 -403.159976) (xy 175.726621 -403.167105) (xy 175.720122 -403.184308) (xy 175.71974 -403.193504)
			(xy 175.71974 -403.351492) (xy 175.719273 -403.361641) (xy 175.711487 -403.380385) (xy 175.697105 -403.394707)
			(xy 175.678328 -403.402415) (xy 175.668178 -403.4028) (xy 174.951898 -403.4028) (xy 174.941776 -403.402276)
			(xy 174.923063 -403.394555) (xy 174.908708 -403.380281) (xy 174.900882 -403.361611) (xy 174.900336 -403.351492)
			(xy 174.900336 -403.193504) (xy 174.899916 -403.184318) (xy 174.893408 -403.167134) (xy 174.887636 -403.159976)
			(xy 174.865801 -403.134363) (xy 174.827854 -403.078771) (xy 174.796823 -403.019042) (xy 174.773153 -402.956032)
			(xy 174.757183 -402.890645) (xy 174.749143 -402.823818) (xy 171.471107 -402.823818) (xy 171.471107 -402.823874)
			(xy 171.463035 -402.89081) (xy 171.447003 -402.956298) (xy 171.423242 -403.019393) (xy 171.392094 -403.079187)
			(xy 171.354007 -403.13482) (xy 171.332144 -403.160484) (xy 171.326322 -403.167611) (xy 171.319824 -403.184816)
			(xy 171.319444 -403.194012) (xy 171.319444 -403.351492) (xy 171.318909 -403.361595) (xy 171.311183 -403.380264)
			(xy 171.296901 -403.394558) (xy 171.278238 -403.402301) (xy 171.268136 -403.4028) (xy 170.551856 -403.4028)
			(xy 170.541744 -403.402351) (xy 170.523065 -403.394599) (xy 170.508772 -403.380291) (xy 170.501039 -403.361604)
			(xy 170.500548 -403.351492) (xy 170.500548 -403.194012) (xy 170.500121 -403.184827) (xy 170.493618 -403.167643)
			(xy 170.487848 -403.160484) (xy 170.465935 -403.134858) (xy 170.427845 -403.079219) (xy 170.396693 -403.019418)
			(xy 170.37293 -402.956316) (xy 170.356896 -402.890822) (xy 170.348823 -402.823878) (xy 167.070779 -402.823878)
			(xy 167.062748 -402.890634) (xy 167.04678 -402.956014) (xy 167.023112 -403.019016) (xy 166.992084 -403.078738)
			(xy 166.954141 -403.134324) (xy 166.932356 -403.159976) (xy 166.926539 -403.167107) (xy 166.920038 -403.184308)
			(xy 166.919656 -403.193504) (xy 166.919656 -403.351492) (xy 166.919173 -403.361639) (xy 166.911391 -403.38038)
			(xy 166.897014 -403.394702) (xy 166.878242 -403.402412) (xy 166.868094 -403.4028) (xy 166.151814 -403.4028)
			(xy 166.141693 -403.402263) (xy 166.12298 -403.394547) (xy 166.108624 -403.380277) (xy 166.100798 -403.36161)
			(xy 166.100252 -403.351492) (xy 166.100252 -403.193504) (xy 166.099828 -403.184318) (xy 166.093323 -403.167135)
			(xy 166.087552 -403.159976) (xy 166.065717 -403.134363) (xy 166.027768 -403.078771) (xy 165.996736 -403.019042)
			(xy 165.973066 -402.956033) (xy 165.957096 -402.890646) (xy 165.949055 -402.823818) (xy 162.671019 -402.823818)
			(xy 162.671019 -402.823874) (xy 162.662948 -402.89081) (xy 162.646916 -402.956297) (xy 162.623155 -403.019392)
			(xy 162.592008 -403.079187) (xy 162.553923 -403.13482) (xy 162.53206 -403.160484) (xy 162.52624 -403.167613)
			(xy 162.51974 -403.184816) (xy 162.51936 -403.194012) (xy 162.51936 -403.351492) (xy 162.518976 -403.361619)
			(xy 162.511224 -403.38033) (xy 162.496896 -403.394646) (xy 162.478179 -403.402384) (xy 162.468052 -403.4028)
			(xy 161.751772 -403.4028) (xy 161.741661 -403.402338) (xy 161.722983 -403.394591) (xy 161.708689 -403.380287)
			(xy 161.700955 -403.361603) (xy 161.700464 -403.351492) (xy 161.700464 -403.194012) (xy 161.700034 -403.184827)
			(xy 161.693532 -403.167643) (xy 161.687764 -403.160484) (xy 161.665854 -403.134857) (xy 161.627769 -403.079216)
			(xy 161.596623 -403.019414) (xy 161.572863 -402.956313) (xy 161.556832 -402.890819) (xy 161.54876 -402.823877)
			(xy 154.57678 -402.823877) (xy 154.57678 -405.623648) (xy 159.349158 -405.623648) (xy 159.349158 -405.556343)
			(xy 159.357202 -405.48952) (xy 159.373175 -405.424138) (xy 159.396848 -405.361133) (xy 159.427881 -405.301409)
			(xy 159.465829 -405.245822) (xy 159.487616 -405.22017) (xy 159.49341 -405.213023) (xy 159.499926 -405.195834)
			(xy 159.500316 -405.186642) (xy 159.500316 -404.693374) (xy 159.499915 -404.684186) (xy 159.493395 -404.667002)
			(xy 159.487616 -404.659846) (xy 159.465851 -404.634176) (xy 159.427903 -404.578591) (xy 159.39687 -404.51887)
			(xy 159.373197 -404.455868) (xy 159.357223 -404.390488) (xy 159.349177 -404.323668) (xy 159.349175 -404.256365)
			(xy 159.357217 -404.189544) (xy 159.373187 -404.124164) (xy 159.396856 -404.06116) (xy 159.427886 -404.001437)
			(xy 159.46583 -403.94585) (xy 159.487616 -403.920198) (xy 159.493398 -403.913042) (xy 159.499921 -403.89586)
			(xy 159.500316 -403.88667) (xy 159.500316 -403.728682) (xy 159.500818 -403.718526) (xy 159.508594 -403.69976)
			(xy 159.522957 -403.685396) (xy 159.541722 -403.677619) (xy 159.551878 -403.67712) (xy 160.268158 -403.67712)
			(xy 160.278325 -403.677598) (xy 160.297115 -403.685366) (xy 160.311501 -403.699735) (xy 160.31929 -403.718516)
			(xy 160.31972 -403.728682) (xy 160.31972 -403.88667) (xy 160.32014 -403.895856) (xy 160.326646 -403.913041)
			(xy 160.33242 -403.920198) (xy 160.354231 -403.945832) (xy 160.392181 -404.00142) (xy 160.423216 -404.061146)
			(xy 160.446889 -404.124153) (xy 160.462862 -404.189538) (xy 160.470905 -404.256363) (xy 160.470903 -404.32367)
			(xy 160.462856 -404.390495) (xy 160.446879 -404.455879) (xy 160.423202 -404.518885) (xy 160.392164 -404.578608)
			(xy 160.35421 -404.634194) (xy 160.33242 -404.659846) (xy 160.326624 -404.666992) (xy 160.320108 -404.684182)
			(xy 160.31972 -404.693374) (xy 160.31972 -405.186642) (xy 160.320105 -405.195832) (xy 160.326636 -405.213016)
			(xy 160.33242 -405.22017) (xy 160.354203 -405.245826) (xy 160.392155 -405.301411) (xy 160.42319 -405.361134)
			(xy 160.446865 -405.424138) (xy 160.46284 -405.48952) (xy 160.470885 -405.556343) (xy 160.470886 -405.623648)
			(xy 160.462842 -405.690471) (xy 160.446868 -405.755853) (xy 160.423194 -405.818858) (xy 160.392159 -405.878581)
			(xy 160.354209 -405.934166) (xy 160.33242 -405.959818) (xy 160.326636 -405.966972) (xy 160.320113 -405.984156)
			(xy 160.31972 -405.993346) (xy 160.31972 -406.151334) (xy 160.319363 -406.161513) (xy 160.311559 -406.180317)
			(xy 160.297153 -406.194702) (xy 160.278338 -406.202478) (xy 160.268158 -406.202896) (xy 159.551878 -406.202896)
			(xy 159.541723 -406.202386) (xy 159.52296 -406.19461) (xy 159.508596 -406.18025) (xy 159.500817 -406.161489)
			(xy 159.500316 -406.151334) (xy 159.500316 -405.993346) (xy 159.49988 -405.984162) (xy 159.493384 -405.966977)
			(xy 159.487616 -405.959818) (xy 159.465823 -405.93417) (xy 159.427876 -405.878583) (xy 159.396844 -405.818858)
			(xy 159.373173 -405.755853) (xy 159.357201 -405.690471) (xy 159.349158 -405.623648) (xy 154.57678 -405.623648)
			(xy 154.57678 -406.723789) (xy 161.548771 -406.723789) (xy 161.548774 -406.656363) (xy 161.556853 -406.589423)
			(xy 161.572891 -406.523933) (xy 161.596657 -406.460835) (xy 161.627809 -406.401038) (xy 161.665899 -406.345402)
			(xy 161.687764 -406.319736) (xy 161.693578 -406.312604) (xy 161.70008 -406.295403) (xy 161.700464 -406.286208)
			(xy 161.700464 -405.793956) (xy 161.700061 -405.784768) (xy 161.693541 -405.767585) (xy 161.687764 -405.760428)
			(xy 161.665897 -405.734765) (xy 161.627811 -405.67913) (xy 161.596663 -405.619333) (xy 161.5729 -405.556236)
			(xy 161.556866 -405.490747) (xy 161.548791 -405.423809) (xy 161.548792 -405.356385) (xy 161.556867 -405.289447)
			(xy 161.572902 -405.223959) (xy 161.596665 -405.160862) (xy 161.627814 -405.101065) (xy 161.665901 -405.04543)
			(xy 161.687764 -405.019764) (xy 161.693566 -405.012623) (xy 161.700076 -404.995429) (xy 161.700464 -404.986236)
			(xy 161.700464 -404.828756) (xy 161.700948 -404.818649) (xy 161.708694 -404.799977) (xy 161.72299 -404.785685)
			(xy 161.741665 -404.777945) (xy 161.751772 -404.777448) (xy 162.468052 -404.777448) (xy 162.478165 -404.777954)
			(xy 162.496858 -404.785677) (xy 162.511172 -404.799965) (xy 162.518928 -404.818644) (xy 162.51936 -404.828756)
			(xy 162.51936 -404.986236) (xy 162.519762 -404.995424) (xy 162.526282 -405.012608) (xy 162.53206 -405.019764)
			(xy 162.553921 -405.045432) (xy 162.592013 -405.101065) (xy 162.623166 -405.16086) (xy 162.646932 -405.223957)
			(xy 162.662969 -405.289446) (xy 162.671046 -405.356385) (xy 162.671046 -405.423809) (xy 162.66297 -405.490748)
			(xy 162.646934 -405.556237) (xy 162.623168 -405.619334) (xy 162.620889 -405.623708) (xy 163.748926 -405.623708)
			(xy 163.748926 -405.556283) (xy 163.757003 -405.489344) (xy 163.77304 -405.423855) (xy 163.796805 -405.360758)
			(xy 163.827957 -405.300961) (xy 163.866047 -405.245327) (xy 163.887912 -405.219662) (xy 163.893709 -405.212517)
			(xy 163.900223 -405.195326) (xy 163.900612 -405.186134) (xy 163.900612 -404.693882) (xy 163.900208 -404.684694)
			(xy 163.89369 -404.66751) (xy 163.887912 -404.660354) (xy 163.866069 -404.634671) (xy 163.827979 -404.579039)
			(xy 163.796827 -404.519246) (xy 163.773061 -404.456151) (xy 163.757023 -404.390664) (xy 163.748946 -404.323728)
			(xy 163.748944 -404.256305) (xy 163.757018 -404.189368) (xy 163.773051 -404.12388) (xy 163.796813 -404.060784)
			(xy 163.827962 -404.000989) (xy 163.866049 -403.945355) (xy 163.887912 -403.91969) (xy 163.893697 -403.912536)
			(xy 163.900218 -403.895352) (xy 163.900612 -403.886162) (xy 163.900612 -403.728682) (xy 163.901111 -403.718558)
			(xy 163.908839 -403.699841) (xy 163.923121 -403.685486) (xy 163.941798 -403.677663) (xy 163.95192 -403.67712)
			(xy 164.6682 -403.67712) (xy 164.678357 -403.677522) (xy 164.697113 -403.685321) (xy 164.711437 -403.699724)
			(xy 164.719133 -403.718523) (xy 164.719508 -403.728682) (xy 164.719508 -403.886162) (xy 164.719935 -403.895347)
			(xy 164.726437 -403.912532) (xy 164.732208 -403.91969) (xy 164.754093 -403.945338) (xy 164.792181 -404.000975)
			(xy 164.82333 -404.060774) (xy 164.847093 -404.123873) (xy 164.863126 -404.189364) (xy 164.8712 -404.256304)
			(xy 164.871198 -404.323729) (xy 164.86312 -404.390669) (xy 164.847083 -404.456159) (xy 164.823317 -404.519257)
			(xy 164.792164 -404.579054) (xy 164.754073 -404.634689) (xy 164.732208 -404.660354) (xy 164.726407 -404.667496)
			(xy 164.719895 -404.684689) (xy 164.719508 -404.693882) (xy 164.719508 -405.186134) (xy 164.7199 -405.195323)
			(xy 164.726426 -405.212508) (xy 164.732208 -405.219662) (xy 164.754066 -405.245332) (xy 164.792154 -405.300966)
			(xy 164.823305 -405.360762) (xy 164.847069 -405.423858) (xy 164.863104 -405.489346) (xy 164.871181 -405.556284)
			(xy 164.871181 -405.623707) (xy 164.863106 -405.690645) (xy 164.847072 -405.756133) (xy 164.823308 -405.81923)
			(xy 164.792159 -405.879026) (xy 164.754071 -405.934661) (xy 164.732208 -405.960326) (xy 164.726419 -405.967477)
			(xy 164.719899 -405.984663) (xy 164.719508 -405.993854) (xy 164.719508 -406.151334) (xy 164.719003 -406.161457)
			(xy 164.711273 -406.18017) (xy 164.696993 -406.194523) (xy 164.67832 -406.20235) (xy 164.6682 -406.202896)
			(xy 163.95192 -406.202896) (xy 163.941767 -406.202462) (xy 163.923014 -406.194672) (xy 163.90869 -406.180279)
			(xy 163.90099 -406.161489) (xy 163.900612 -406.151334) (xy 163.900612 -405.993854) (xy 163.900173 -405.98467)
			(xy 163.893679 -405.967485) (xy 163.887912 -405.960326) (xy 163.866042 -405.934666) (xy 163.827952 -405.879031)
			(xy 163.796801 -405.819234) (xy 163.773037 -405.756137) (xy 163.757001 -405.690647) (xy 163.748926 -405.623708)
			(xy 162.620889 -405.623708) (xy 162.592016 -405.67913) (xy 162.553925 -405.734763) (xy 162.53206 -405.760428)
			(xy 162.526264 -405.767573) (xy 162.51975 -405.784764) (xy 162.51936 -405.793956) (xy 162.51936 -406.286208)
			(xy 162.519775 -406.295394) (xy 162.526286 -406.312578) (xy 162.53206 -406.319736) (xy 162.553894 -406.345426)
			(xy 162.591986 -406.401056) (xy 162.623141 -406.460849) (xy 162.646908 -406.523942) (xy 162.662947 -406.589429)
			(xy 162.671026 -406.656365) (xy 162.671029 -406.72373) (xy 165.949066 -406.72373) (xy 165.949069 -406.656422)
			(xy 165.957117 -406.589597) (xy 165.973094 -406.524213) (xy 165.996771 -406.461207) (xy 166.027808 -406.401483)
			(xy 166.065762 -406.345896) (xy 166.087552 -406.320244) (xy 166.093361 -406.313108) (xy 166.099867 -406.29591)
			(xy 166.100252 -406.286716) (xy 166.100252 -405.793448) (xy 166.099807 -405.784265) (xy 166.093316 -405.767081)
			(xy 166.087552 -405.75992) (xy 166.06576 -405.734271) (xy 166.027811 -405.678685) (xy 165.996777 -405.618961)
			(xy 165.973104 -405.555956) (xy 165.957131 -405.490573) (xy 165.949087 -405.42375) (xy 165.949087 -405.356444)
			(xy 165.957132 -405.289621) (xy 165.973105 -405.224239) (xy 165.996779 -405.161234) (xy 166.027814 -405.10151)
			(xy 166.065764 -405.045924) (xy 166.087552 -405.020272) (xy 166.093349 -405.013128) (xy 166.099862 -404.995936)
			(xy 166.100252 -404.986744) (xy 166.100252 -404.828756) (xy 166.100685 -404.818605) (xy 166.108486 -404.799861)
			(xy 166.122878 -404.785541) (xy 166.141661 -404.777834) (xy 166.151814 -404.777448) (xy 166.868094 -404.777448)
			(xy 166.878221 -404.777932) (xy 166.896944 -404.785659) (xy 166.911301 -404.799946) (xy 166.919119 -404.818631)
			(xy 166.919656 -404.828756) (xy 166.919656 -404.986744) (xy 166.920055 -404.995932) (xy 166.926578 -405.013116)
			(xy 166.932356 -405.020272) (xy 166.95414 -405.045927) (xy 166.992089 -405.101513) (xy 167.023123 -405.161236)
			(xy 167.046796 -405.22424) (xy 167.062769 -405.289622) (xy 167.070814 -405.356445) (xy 167.070814 -405.423749)
			(xy 167.06277 -405.490572) (xy 167.046798 -405.555954) (xy 167.023125 -405.618958) (xy 167.020688 -405.623648)
			(xy 168.149245 -405.623648) (xy 168.149246 -405.556343) (xy 168.15729 -405.489521) (xy 168.173263 -405.424139)
			(xy 168.196934 -405.361134) (xy 168.227966 -405.30141) (xy 168.265913 -405.245823) (xy 168.2877 -405.22017)
			(xy 168.293492 -405.213021) (xy 168.300009 -405.195834) (xy 168.3004 -405.186642) (xy 168.3004 -404.693374)
			(xy 168.300003 -404.684185) (xy 168.29348 -404.667001) (xy 168.2877 -404.659846) (xy 168.265935 -404.634176)
			(xy 168.227988 -404.578591) (xy 168.196956 -404.518869) (xy 168.173284 -404.455867) (xy 168.15731 -404.390488)
			(xy 168.149265 -404.323668) (xy 168.149263 -404.256365) (xy 168.157305 -404.189545) (xy 168.173274 -404.124164)
			(xy 168.196943 -404.061161) (xy 168.227971 -404.001438) (xy 168.265915 -403.945851) (xy 168.2877 -403.920198)
			(xy 168.29348 -403.913041) (xy 168.300005 -403.89586) (xy 168.3004 -403.88667) (xy 168.3004 -403.728682)
			(xy 168.300917 -403.718528) (xy 168.308691 -403.699765) (xy 168.323049 -403.685402) (xy 168.341808 -403.677621)
			(xy 168.351962 -403.67712) (xy 169.068242 -403.67712) (xy 169.0784 -403.677599) (xy 169.097167 -403.685383)
			(xy 169.11153 -403.699753) (xy 169.119306 -403.718524) (xy 169.119804 -403.728682) (xy 169.119804 -403.88667)
			(xy 169.120228 -403.895856) (xy 169.126732 -403.91304) (xy 169.132504 -403.920198) (xy 169.154312 -403.945833)
			(xy 169.192257 -404.001423) (xy 169.223287 -404.061149) (xy 169.246957 -404.124156) (xy 169.262927 -404.18954)
			(xy 169.270969 -404.256364) (xy 169.270967 -404.32367) (xy 169.262921 -404.390493) (xy 169.246947 -404.455876)
			(xy 169.223274 -404.518881) (xy 169.19224 -404.578606) (xy 169.154292 -404.634193) (xy 169.132504 -404.659846)
			(xy 169.126706 -404.66699) (xy 169.120192 -404.684181) (xy 169.119804 -404.693374) (xy 169.119804 -405.186642)
			(xy 169.120193 -405.195832) (xy 169.126721 -405.213016) (xy 169.132504 -405.22017) (xy 169.154284 -405.245828)
			(xy 169.192231 -405.301414) (xy 169.223262 -405.361137) (xy 169.246933 -405.424141) (xy 169.262905 -405.489522)
			(xy 169.270949 -405.556344) (xy 169.27095 -405.623647) (xy 169.262907 -405.690469) (xy 169.246936 -405.75585)
			(xy 169.223266 -405.818854) (xy 169.192235 -405.878578) (xy 169.15429 -405.934165) (xy 169.132504 -405.959818)
			(xy 169.126718 -405.966971) (xy 169.120197 -405.984155) (xy 169.119804 -405.993346) (xy 169.119804 -406.151334)
			(xy 169.119296 -406.161489) (xy 169.111518 -406.180251) (xy 169.097157 -406.194613) (xy 169.078397 -406.202394)
			(xy 169.068242 -406.202896) (xy 168.351962 -406.202896) (xy 168.341806 -406.202399) (xy 168.323042 -406.194618)
			(xy 168.30868 -406.180254) (xy 168.300901 -406.16149) (xy 168.3004 -406.151334) (xy 168.3004 -405.993346)
			(xy 168.299968 -405.984161) (xy 168.293469 -405.966977) (xy 168.2877 -405.959818) (xy 168.265908 -405.93417)
			(xy 168.227961 -405.878582) (xy 168.196931 -405.818858) (xy 168.17326 -405.755853) (xy 168.157289 -405.69047)
			(xy 168.149245 -405.623648) (xy 167.020688 -405.623648) (xy 166.992092 -405.678681) (xy 166.954143 -405.734268)
			(xy 166.932356 -405.75992) (xy 166.926563 -405.767067) (xy 166.920047 -405.784256) (xy 166.919656 -405.793448)
			(xy 166.919656 -406.286716) (xy 166.920068 -406.295903) (xy 166.926582 -406.313087) (xy 166.932356 -406.320244)
			(xy 166.954112 -406.345922) (xy 166.992062 -406.401505) (xy 167.023097 -406.461225) (xy 167.046772 -406.524226)
			(xy 167.062747 -406.589605) (xy 167.070794 -406.656425) (xy 167.070797 -406.723727) (xy 167.070789 -406.72379)
			(xy 170.348835 -406.72379) (xy 170.348838 -406.656362) (xy 170.356917 -406.589421) (xy 170.372958 -406.52393)
			(xy 170.396728 -406.460831) (xy 170.427885 -406.401034) (xy 170.46598 -406.3454) (xy 170.487848 -406.319736)
			(xy 170.49366 -406.312602) (xy 170.500164 -406.295403) (xy 170.500548 -406.286208) (xy 170.500548 -405.793956)
			(xy 170.500148 -405.784768) (xy 170.493626 -405.767584) (xy 170.487848 -405.760428) (xy 170.465978 -405.734767)
			(xy 170.427887 -405.679133) (xy 170.396733 -405.619337) (xy 170.372967 -405.556239) (xy 170.356931 -405.490749)
			(xy 170.348854 -405.423809) (xy 170.348855 -405.356385) (xy 170.356932 -405.289445) (xy 170.372969 -405.223955)
			(xy 170.396736 -405.160858) (xy 170.42789 -405.101062) (xy 170.465982 -405.045428) (xy 170.487848 -405.019764)
			(xy 170.493648 -405.012622) (xy 170.500159 -404.995429) (xy 170.500548 -404.986236) (xy 170.500548 -404.828756)
			(xy 170.501048 -404.818651) (xy 170.50879 -404.799982) (xy 170.523082 -404.78569) (xy 170.541751 -404.777948)
			(xy 170.551856 -404.777448) (xy 171.268136 -404.777448) (xy 171.278241 -404.777954) (xy 171.29691 -404.785694)
			(xy 171.311201 -404.799984) (xy 171.318944 -404.818651) (xy 171.319444 -404.828756) (xy 171.319444 -404.986236)
			(xy 171.31985 -404.995423) (xy 171.326368 -405.012607) (xy 171.332144 -405.019764) (xy 171.354006 -405.045432)
			(xy 171.392099 -405.101064) (xy 171.423253 -405.16086) (xy 171.447019 -405.223956) (xy 171.463057 -405.289446)
			(xy 171.471134 -405.356385) (xy 171.471134 -405.423809) (xy 171.463058 -405.490748) (xy 171.447021 -405.556238)
			(xy 171.423255 -405.619335) (xy 171.421007 -405.623649) (xy 172.549012 -405.623649) (xy 172.549013 -405.556342)
			(xy 172.557058 -405.489518) (xy 172.573033 -405.424135) (xy 172.596709 -405.36113) (xy 172.627746 -405.301407)
			(xy 172.665698 -405.245822) (xy 172.687488 -405.22017) (xy 172.693278 -405.21302) (xy 172.699797 -405.195833)
			(xy 172.700188 -405.186642) (xy 172.700188 -404.693374) (xy 172.699793 -404.684185) (xy 172.693269 -404.667001)
			(xy 172.687488 -404.659846) (xy 172.66572 -404.634177) (xy 172.627768 -404.578594) (xy 172.596731 -404.518873)
			(xy 172.573055 -404.455871) (xy 172.557079 -404.39049) (xy 172.549032 -404.323669) (xy 172.54903 -404.256364)
			(xy 172.557073 -404.189542) (xy 172.573045 -404.124161) (xy 172.596717 -404.061157) (xy 172.627751 -404.001435)
			(xy 172.6657 -403.945849) (xy 172.687488 -403.920198) (xy 172.693267 -403.91304) (xy 172.699792 -403.895859)
			(xy 172.700188 -403.88667) (xy 172.700188 -403.728682) (xy 172.70055 -403.718503) (xy 172.708351 -403.699698)
			(xy 172.722756 -403.685313) (xy 172.74157 -403.677537) (xy 172.75175 -403.67712) (xy 173.46803 -403.67712)
			(xy 173.478187 -403.677608) (xy 173.496954 -403.685389) (xy 173.511317 -403.699756) (xy 173.519094 -403.718524)
			(xy 173.519592 -403.728682) (xy 173.519592 -403.88667) (xy 173.520018 -403.895855) (xy 173.526521 -403.91304)
			(xy 173.532292 -403.920198) (xy 173.5541 -403.945833) (xy 173.592047 -404.001422) (xy 173.623077 -404.061149)
			(xy 173.646747 -404.124155) (xy 173.662718 -404.189539) (xy 173.67076 -404.256363) (xy 173.670758 -404.32367)
			(xy 173.662712 -404.390493) (xy 173.646738 -404.455876) (xy 173.623064 -404.518882) (xy 173.59203 -404.578606)
			(xy 173.55408 -404.634193) (xy 173.532292 -404.659846) (xy 173.526492 -404.666989) (xy 173.51998 -404.684181)
			(xy 173.519592 -404.693374) (xy 173.519592 -405.186642) (xy 173.519984 -405.195831) (xy 173.52651 -405.213015)
			(xy 173.532292 -405.22017) (xy 173.554073 -405.245827) (xy 173.59202 -405.301414) (xy 173.623052 -405.361137)
			(xy 173.646723 -405.424141) (xy 173.662696 -405.489522) (xy 173.67074 -405.556343) (xy 173.670741 -405.623647)
			(xy 173.662698 -405.690469) (xy 173.646726 -405.755851) (xy 173.623055 -405.818855) (xy 173.592025 -405.878578)
			(xy 173.554078 -405.934165) (xy 173.532292 -405.959818) (xy 173.526504 -405.96697) (xy 173.519985 -405.984155)
			(xy 173.519592 -405.993346) (xy 173.519592 -406.151334) (xy 173.519095 -406.16149) (xy 173.511315 -406.180254)
			(xy 173.496951 -406.194617) (xy 173.478186 -406.202396) (xy 173.46803 -406.202896) (xy 172.75175 -406.202896)
			(xy 172.741586 -406.202396) (xy 172.722799 -406.194634) (xy 172.708413 -406.180272) (xy 172.70062 -406.161497)
			(xy 172.700188 -406.151334) (xy 172.700188 -405.993346) (xy 172.699759 -405.984161) (xy 172.693259 -405.966976)
			(xy 172.687488 -405.959818) (xy 172.665693 -405.934171) (xy 172.627741 -405.878585) (xy 172.596705 -405.818861)
			(xy 172.573031 -405.755856) (xy 172.557057 -405.690473) (xy 172.549012 -405.623649) (xy 171.421007 -405.623649)
			(xy 171.392102 -405.67913) (xy 171.35401 -405.734764) (xy 171.332144 -405.760428) (xy 171.326346 -405.767572)
			(xy 171.319834 -405.784764) (xy 171.319444 -405.793956) (xy 171.319444 -406.286208) (xy 171.319863 -406.295394)
			(xy 171.326372 -406.312578) (xy 171.332144 -406.319736) (xy 171.353978 -406.345426) (xy 171.392072 -406.401056)
			(xy 171.423227 -406.460848) (xy 171.446996 -406.523942) (xy 171.463035 -406.589428) (xy 171.471114 -406.656365)
			(xy 171.471117 -406.72373) (xy 174.749154 -406.72373) (xy 174.749157 -406.656422) (xy 174.757205 -406.589597)
			(xy 174.773181 -406.524213) (xy 174.796857 -406.461208) (xy 174.827894 -406.401483) (xy 174.865846 -406.345896)
			(xy 174.887636 -406.320244) (xy 174.893443 -406.313107) (xy 174.899951 -406.29591) (xy 174.900336 -406.286716)
			(xy 174.900336 -405.793448) (xy 174.899895 -405.784264) (xy 174.893402 -405.76708) (xy 174.887636 -405.75992)
			(xy 174.865844 -405.734271) (xy 174.827896 -405.678684) (xy 174.796863 -405.61896) (xy 174.77319 -405.555955)
			(xy 174.757218 -405.490573) (xy 174.749174 -405.42375) (xy 174.749174 -405.356444) (xy 174.757219 -405.289621)
			(xy 174.773192 -405.224239) (xy 174.796865 -405.161234) (xy 174.827899 -405.101511) (xy 174.865848 -405.045924)
			(xy 174.887636 -405.020272) (xy 174.893432 -405.013126) (xy 174.899946 -404.995936) (xy 174.900336 -404.986744)
			(xy 174.900336 -404.828756) (xy 174.900686 -404.818594) (xy 174.908503 -404.799834) (xy 174.922922 -404.785511)
			(xy 174.941734 -404.77782) (xy 174.951898 -404.777448) (xy 175.668178 -404.777448) (xy 175.678304 -404.777945)
			(xy 175.697027 -404.785667) (xy 175.711384 -404.79995) (xy 175.719202 -404.818632) (xy 175.71974 -404.828756)
			(xy 175.71974 -404.986744) (xy 175.720142 -404.995932) (xy 175.726663 -405.013115) (xy 175.73244 -405.020272)
			(xy 175.754224 -405.045927) (xy 175.792175 -405.101513) (xy 175.823209 -405.161236) (xy 175.846883 -405.22424)
			(xy 175.862857 -405.289622) (xy 175.870902 -405.356444) (xy 175.870902 -405.42375) (xy 175.862858 -405.490572)
			(xy 175.846885 -405.555954) (xy 175.823212 -405.618959) (xy 175.792178 -405.678682) (xy 175.754228 -405.734268)
			(xy 175.73244 -405.75992) (xy 175.726645 -405.767066) (xy 175.720131 -405.784256) (xy 175.71974 -405.793448)
			(xy 175.71974 -406.286716) (xy 175.720156 -406.295902) (xy 175.726667 -406.313086) (xy 175.73244 -406.320244)
			(xy 175.754197 -406.345922) (xy 175.792148 -406.401504) (xy 175.823184 -406.461224) (xy 175.846859 -406.524225)
			(xy 175.862835 -406.589604) (xy 175.870882 -406.656424) (xy 175.870885 -406.723727) (xy 175.862844 -406.790548)
			(xy 175.846873 -406.855929) (xy 175.823203 -406.918932) (xy 175.792173 -406.978655) (xy 175.754226 -407.03424)
			(xy 175.73244 -407.059892) (xy 175.726657 -407.067046) (xy 175.720136 -407.08423) (xy 175.71974 -407.09342)
			(xy 175.71974 -407.251408) (xy 175.719286 -407.261558) (xy 175.711495 -407.280302) (xy 175.697109 -407.294624)
			(xy 175.678329 -407.302331) (xy 175.668178 -407.302716) (xy 174.951898 -407.302716) (xy 174.941766 -407.302274)
			(xy 174.923036 -407.294537) (xy 174.908679 -407.280237) (xy 174.900867 -407.261538) (xy 174.900336 -407.251408)
			(xy 174.900336 -407.09342) (xy 174.899908 -407.084235) (xy 174.893406 -407.067051) (xy 174.887636 -407.059892)
			(xy 174.865817 -407.034266) (xy 174.827869 -406.978676) (xy 174.796837 -406.918948) (xy 174.773167 -406.85594)
			(xy 174.757196 -406.790555) (xy 174.749154 -406.72373) (xy 171.471117 -406.72373) (xy 171.471117 -406.723787)
			(xy 171.463044 -406.790724) (xy 171.44701 -406.856212) (xy 171.423247 -406.919308) (xy 171.392097 -406.979103)
			(xy 171.354008 -407.034736) (xy 171.332144 -407.0604) (xy 171.326358 -407.067552) (xy 171.319839 -407.084738)
			(xy 171.319444 -407.093928) (xy 171.319444 -407.251408) (xy 171.318922 -407.261512) (xy 171.31119 -407.280182)
			(xy 171.296905 -407.294475) (xy 171.278239 -407.302217) (xy 171.268136 -407.302716) (xy 170.551856 -407.302716)
			(xy 170.541746 -407.302251) (xy 170.52307 -407.294502) (xy 170.508778 -407.280199) (xy 170.501042 -407.261518)
			(xy 170.500548 -407.251408) (xy 170.500548 -407.093928) (xy 170.500114 -407.084744) (xy 170.493616 -407.067559)
			(xy 170.487848 -407.0604) (xy 170.465951 -407.034762) (xy 170.42786 -406.979124) (xy 170.396708 -406.919325)
			(xy 170.372944 -406.856224) (xy 170.356909 -406.790732) (xy 170.348835 -406.72379) (xy 167.070789 -406.72379)
			(xy 167.062756 -406.790548) (xy 167.046786 -406.855928) (xy 167.023117 -406.918931) (xy 166.992087 -406.978654)
			(xy 166.954142 -407.03424) (xy 166.932356 -407.059892) (xy 166.926575 -407.067048) (xy 166.920052 -407.08423)
			(xy 166.919656 -407.09342) (xy 166.919656 -407.251408) (xy 166.919186 -407.261556) (xy 166.911398 -407.280297)
			(xy 166.897017 -407.294618) (xy 166.878243 -407.302328) (xy 166.868094 -407.302716) (xy 166.151814 -407.302716)
			(xy 166.141683 -407.302261) (xy 166.122954 -407.294529) (xy 166.108595 -407.280233) (xy 166.100783 -407.261537)
			(xy 166.100252 -407.251408) (xy 166.100252 -407.09342) (xy 166.099821 -407.084235) (xy 166.093321 -407.067051)
			(xy 166.087552 -407.059892) (xy 166.065732 -407.034266) (xy 166.027784 -406.978676) (xy 165.996751 -406.918949)
			(xy 165.973079 -406.855941) (xy 165.957108 -406.790556) (xy 165.949066 -406.72373) (xy 162.671029 -406.72373)
			(xy 162.671029 -406.723787) (xy 162.662956 -406.790724) (xy 162.646923 -406.856212) (xy 162.62316 -406.919307)
			(xy 162.592011 -406.979102) (xy 162.553923 -407.034735) (xy 162.53206 -407.0604) (xy 162.526276 -407.067554)
			(xy 162.519755 -407.084738) (xy 162.51936 -407.093928) (xy 162.51936 -407.251408) (xy 162.518989 -407.261536)
			(xy 162.511231 -407.280247) (xy 162.4969 -407.294563) (xy 162.47818 -407.3023) (xy 162.468052 -407.302716)
			(xy 161.751772 -407.302716) (xy 161.741663 -407.302238) (xy 161.722988 -407.294494) (xy 161.708694 -407.280196)
			(xy 161.700958 -407.261517) (xy 161.700464 -407.251408) (xy 161.700464 -407.093928) (xy 161.700026 -407.084744)
			(xy 161.69353 -407.06756) (xy 161.687764 -407.0604) (xy 161.66587 -407.03476) (xy 161.627784 -406.979121)
			(xy 161.596637 -406.919321) (xy 161.572876 -406.856221) (xy 161.556844 -406.790729) (xy 161.548771 -406.723789)
			(xy 154.57678 -406.723789) (xy 154.57678 -409.523827) (xy 159.349136 -409.523827) (xy 159.34914 -409.456519)
			(xy 159.357187 -409.389695) (xy 159.373163 -409.324311) (xy 159.396839 -409.261305) (xy 159.427875 -409.20158)
			(xy 159.465827 -409.145992) (xy 159.487616 -409.12034) (xy 159.493422 -409.113202) (xy 159.499931 -409.096006)
			(xy 159.500316 -409.086812) (xy 159.500316 -408.593544) (xy 159.499881 -408.58436) (xy 159.493384 -408.567175)
			(xy 159.487616 -408.560016) (xy 159.465821 -408.53437) (xy 159.427874 -408.478782) (xy 159.396842 -408.419058)
			(xy 159.373171 -408.356052) (xy 159.357199 -408.29067) (xy 159.349156 -408.223847) (xy 159.349157 -408.156541)
			(xy 159.357201 -408.089719) (xy 159.373175 -408.024336) (xy 159.396847 -407.961331) (xy 159.42788 -407.901607)
			(xy 159.465828 -407.84602) (xy 159.487616 -407.820368) (xy 159.49341 -407.813221) (xy 159.499926 -407.796032)
			(xy 159.500316 -407.78684) (xy 159.500316 -407.628852) (xy 159.500683 -407.618693) (xy 159.508497 -407.599936)
			(xy 159.522911 -407.585614) (xy 159.541716 -407.577919) (xy 159.551878 -407.577544) (xy 160.268158 -407.577544)
			(xy 160.278283 -407.578061) (xy 160.297003 -407.585776) (xy 160.311361 -407.600053) (xy 160.319181 -407.61873)
			(xy 160.31972 -407.628852) (xy 160.31972 -407.78684) (xy 160.320107 -407.79603) (xy 160.326636 -407.813214)
			(xy 160.33242 -407.820368) (xy 160.354201 -407.846026) (xy 160.392153 -407.901611) (xy 160.423189 -407.961333)
			(xy 160.446864 -408.024337) (xy 160.462838 -408.089719) (xy 160.470884 -408.156541) (xy 160.470885 -408.223847)
			(xy 160.462841 -408.290669) (xy 160.446867 -408.356052) (xy 160.423194 -408.419056) (xy 160.392159 -408.478779)
			(xy 160.354208 -408.534364) (xy 160.33242 -408.560016) (xy 160.326636 -408.567171) (xy 160.320113 -408.584354)
			(xy 160.31972 -408.593544) (xy 160.31972 -409.086812) (xy 160.32012 -409.096) (xy 160.32664 -409.113185)
			(xy 160.33242 -409.12034) (xy 160.354174 -409.146021) (xy 160.392126 -409.201602) (xy 160.423163 -409.261321)
			(xy 160.44684 -409.324322) (xy 160.462817 -409.389701) (xy 160.470864 -409.456521) (xy 160.470867 -409.523824)
			(xy 160.462826 -409.590645) (xy 160.446856 -409.656026) (xy 160.423185 -409.719029) (xy 160.392154 -409.778751)
			(xy 160.354207 -409.834336) (xy 160.33242 -409.859988) (xy 160.326606 -409.867121) (xy 160.320101 -409.884321)
			(xy 160.31972 -409.893516) (xy 160.31972 -410.051504) (xy 160.319282 -410.061656) (xy 160.311489 -410.080404)
			(xy 160.297098 -410.094727) (xy 160.278312 -410.10243) (xy 160.268158 -410.102812) (xy 159.551878 -410.102812)
			(xy 159.541756 -410.102293) (xy 159.523044 -410.094568) (xy 159.508691 -410.080292) (xy 159.500863 -410.061623)
			(xy 159.500316 -410.051504) (xy 159.500316 -409.893516) (xy 159.499894 -409.88433) (xy 159.493388 -409.867146)
			(xy 159.487616 -409.859988) (xy 159.465794 -409.834365) (xy 159.427847 -409.778774) (xy 159.396817 -409.719046)
			(xy 159.373147 -409.656038) (xy 159.357177 -409.590652) (xy 159.349136 -409.523827) (xy 154.57678 -409.523827)
			(xy 154.57678 -410.6237) (xy 161.548783 -410.6237) (xy 161.548784 -410.556276) (xy 161.556861 -410.489337)
			(xy 161.572897 -410.423848) (xy 161.596662 -410.36075) (xy 161.627812 -410.300953) (xy 161.6659 -410.245318)
			(xy 161.687764 -410.219652) (xy 161.693571 -410.212515) (xy 161.700078 -410.195318) (xy 161.700464 -410.186124)
			(xy 161.700464 -409.693872) (xy 161.700053 -409.684685) (xy 161.693538 -409.667502) (xy 161.687764 -409.660344)
			(xy 161.665913 -409.634668) (xy 161.627826 -409.579035) (xy 161.596677 -409.519239) (xy 161.572914 -409.456144)
			(xy 161.556879 -409.390657) (xy 161.548802 -409.32372) (xy 161.548801 -409.256298) (xy 161.556875 -409.189361)
			(xy 161.572909 -409.123873) (xy 161.59667 -409.060777) (xy 161.627817 -409.000981) (xy 161.665902 -408.945346)
			(xy 161.687764 -408.91968) (xy 161.693559 -408.912534) (xy 161.700073 -408.895344) (xy 161.700464 -408.886152)
			(xy 161.700464 -408.728672) (xy 161.700961 -408.718566) (xy 161.708701 -408.699894) (xy 161.722994 -408.685601)
			(xy 161.741666 -408.677861) (xy 161.751772 -408.677364) (xy 162.468052 -408.677364) (xy 162.478167 -408.677854)
			(xy 162.496863 -408.68558) (xy 162.511177 -408.699874) (xy 162.518931 -408.718558) (xy 162.51936 -408.728672)
			(xy 162.51936 -408.886152) (xy 162.519802 -408.895336) (xy 162.526295 -408.91252) (xy 162.53206 -408.91968)
			(xy 162.553937 -408.945335) (xy 162.592028 -409.00097) (xy 162.623181 -409.060767) (xy 162.646946 -409.123866)
			(xy 162.662982 -409.189356) (xy 162.671057 -409.256296) (xy 162.671056 -409.323722) (xy 162.662978 -409.390662)
			(xy 162.64694 -409.456152) (xy 162.623173 -409.519249) (xy 162.620757 -409.523886) (xy 163.748905 -409.523886)
			(xy 163.748908 -409.45646) (xy 163.756988 -409.389519) (xy 163.773027 -409.324027) (xy 163.796796 -409.260929)
			(xy 163.827952 -409.201132) (xy 163.866045 -409.145497) (xy 163.887912 -409.119832) (xy 163.893721 -409.112696)
			(xy 163.900228 -409.095498) (xy 163.900612 -409.086304) (xy 163.900612 -408.594052) (xy 163.900174 -408.584868)
			(xy 163.893679 -408.567683) (xy 163.887912 -408.560524) (xy 163.86604 -408.534865) (xy 163.82795 -408.47923)
			(xy 163.796799 -408.419433) (xy 163.773035 -408.356335) (xy 163.757 -408.290845) (xy 163.748925 -408.223906)
			(xy 163.748925 -408.156482) (xy 163.757002 -408.089543) (xy 163.773039 -408.024053) (xy 163.796804 -407.960956)
			(xy 163.827957 -407.901159) (xy 163.866047 -407.845525) (xy 163.887912 -407.81986) (xy 163.893709 -407.812715)
			(xy 163.900223 -407.795524) (xy 163.900612 -407.786332) (xy 163.900612 -407.628852) (xy 163.901046 -407.618739)
			(xy 163.908802 -407.600057) (xy 163.923114 -407.585764) (xy 163.941806 -407.578033) (xy 163.95192 -407.577544)
			(xy 164.6682 -407.577544) (xy 164.678302 -407.578084) (xy 164.696969 -407.585811) (xy 164.711262 -407.60009)
			(xy 164.719007 -407.618751) (xy 164.719508 -407.628852) (xy 164.719508 -407.786332) (xy 164.719901 -407.795521)
			(xy 164.726426 -407.812705) (xy 164.732208 -407.81986) (xy 164.754064 -407.845532) (xy 164.792152 -407.901166)
			(xy 164.823303 -407.960961) (xy 164.847067 -408.024057) (xy 164.863103 -408.089545) (xy 164.871179 -408.156483)
			(xy 164.87118 -408.223905) (xy 164.863105 -408.290843) (xy 164.847071 -408.356332) (xy 164.823308 -408.419428)
			(xy 164.792158 -408.479224) (xy 164.754071 -408.534859) (xy 164.732208 -408.560524) (xy 164.72642 -408.567675)
			(xy 164.7199 -408.584861) (xy 164.719508 -408.594052) (xy 164.719508 -409.086304) (xy 164.719915 -409.095492)
			(xy 164.726431 -409.112676) (xy 164.732208 -409.119832) (xy 164.754036 -409.145527) (xy 164.792126 -409.201157)
			(xy 164.823277 -409.260949) (xy 164.847043 -409.324042) (xy 164.863081 -409.389528) (xy 164.87116 -409.456463)
			(xy 164.871163 -409.523883) (xy 164.863091 -409.590819) (xy 164.847059 -409.656306) (xy 164.8233 -409.719401)
			(xy 164.792153 -409.779196) (xy 164.75407 -409.834831) (xy 164.732208 -409.860496) (xy 164.726432 -409.867656)
			(xy 164.719905 -409.884835) (xy 164.719508 -409.894024) (xy 164.719508 -410.051504) (xy 164.719018 -410.061612)
			(xy 164.711281 -410.080289) (xy 164.696985 -410.094583) (xy 164.678308 -410.102319) (xy 164.6682 -410.102812)
			(xy 163.95192 -410.102812) (xy 163.9418 -410.102368) (xy 163.923099 -410.094629) (xy 163.908785 -410.080321)
			(xy 163.901037 -410.061624) (xy 163.900612 -410.051504) (xy 163.900612 -409.894024) (xy 163.900188 -409.884838)
			(xy 163.893683 -409.867654) (xy 163.887912 -409.860496) (xy 163.866012 -409.83486) (xy 163.827924 -409.779222)
			(xy 163.796774 -409.719422) (xy 163.773011 -409.656321) (xy 163.756978 -409.590828) (xy 163.748905 -409.523886)
			(xy 162.620757 -409.523886) (xy 162.592019 -409.579046) (xy 162.553926 -409.634679) (xy 162.53206 -409.660344)
			(xy 162.526257 -409.667485) (xy 162.519747 -409.684679) (xy 162.51936 -409.693872) (xy 162.51936 -410.186124)
			(xy 162.519768 -410.195311) (xy 162.526284 -410.212495) (xy 162.53206 -410.219652) (xy 162.55391 -410.24533)
			(xy 162.592001 -410.300961) (xy 162.623155 -410.360755) (xy 162.646922 -410.423851) (xy 162.66296 -410.489339)
			(xy 162.671038 -410.556276) (xy 162.671039 -410.623641) (xy 165.949078 -410.623641) (xy 165.949079 -410.556335)
			(xy 165.957125 -410.489511) (xy 165.9731 -410.424127) (xy 165.996775 -410.361122) (xy 166.027811 -410.301398)
			(xy 166.065763 -410.245812) (xy 166.087552 -410.22016) (xy 166.093354 -410.213019) (xy 166.099864 -410.195825)
			(xy 166.100252 -410.186632) (xy 166.100252 -409.693364) (xy 166.099847 -409.684176) (xy 166.093328 -409.666993)
			(xy 166.087552 -409.659836) (xy 166.065776 -409.634174) (xy 166.027826 -409.578589) (xy 165.996791 -409.518867)
			(xy 165.973117 -409.455864) (xy 165.957143 -409.390483) (xy 165.949098 -409.323661) (xy 165.949097 -409.256357)
			(xy 165.95714 -409.189535) (xy 165.973112 -409.124153) (xy 165.996784 -409.061149) (xy 166.027817 -409.001426)
			(xy 166.065765 -408.94584) (xy 166.087552 -408.920188) (xy 166.093343 -408.913039) (xy 166.099859 -408.895851)
			(xy 166.100252 -408.88666) (xy 166.100252 -408.728672) (xy 166.100698 -408.718522) (xy 166.108493 -408.699778)
			(xy 166.122882 -408.685458) (xy 166.141662 -408.67775) (xy 166.151814 -408.677364) (xy 166.868094 -408.677364)
			(xy 166.878223 -408.677832) (xy 166.896949 -408.685562) (xy 166.911306 -408.699855) (xy 166.919121 -408.718545)
			(xy 166.919656 -408.728672) (xy 166.919656 -408.88666) (xy 166.920095 -408.895844) (xy 166.92659 -408.913028)
			(xy 166.932356 -408.920188) (xy 166.954156 -408.94583) (xy 166.992105 -409.001418) (xy 167.023138 -409.061143)
			(xy 167.04681 -409.124149) (xy 167.062782 -409.189532) (xy 167.070826 -409.256356) (xy 167.070824 -409.323662)
			(xy 167.062779 -409.390486) (xy 167.046805 -409.455869) (xy 167.02313 -409.518874) (xy 167.020557 -409.523826)
			(xy 168.149224 -409.523826) (xy 168.149228 -409.456519) (xy 168.157275 -409.389695) (xy 168.17325 -409.324311)
			(xy 168.196925 -409.261305) (xy 168.227961 -409.201581) (xy 168.265911 -409.145993) (xy 168.2877 -409.12034)
			(xy 168.293505 -409.1132) (xy 168.300014 -409.096006) (xy 168.3004 -409.086812) (xy 168.3004 -408.593544)
			(xy 168.299969 -408.584359) (xy 168.29347 -408.567174) (xy 168.2877 -408.560016) (xy 168.265906 -408.53437)
			(xy 168.22796 -408.478782) (xy 168.196929 -408.419057) (xy 168.173258 -408.356052) (xy 168.157287 -408.290669)
			(xy 168.149244 -408.223846) (xy 168.149245 -408.156542) (xy 168.157289 -408.089719) (xy 168.173262 -408.024337)
			(xy 168.196934 -407.961332) (xy 168.227966 -407.901608) (xy 168.265913 -407.846021) (xy 168.2877 -407.820368)
			(xy 168.293493 -407.81322) (xy 168.30001 -407.796032) (xy 168.3004 -407.78684) (xy 168.3004 -407.628852)
			(xy 168.300782 -407.618695) (xy 168.308594 -407.599941) (xy 168.323002 -407.58562) (xy 168.341802 -407.577922)
			(xy 168.351962 -407.577544) (xy 169.068242 -407.577544) (xy 169.078372 -407.577992) (xy 169.097095 -407.585735)
			(xy 169.11145 -407.600032) (xy 169.119267 -407.618724) (xy 169.119804 -407.628852) (xy 169.119804 -407.78684)
			(xy 169.120194 -407.796029) (xy 169.126721 -407.813214) (xy 169.132504 -407.820368) (xy 169.154283 -407.846027)
			(xy 169.192229 -407.901614) (xy 169.22326 -407.961337) (xy 169.246931 -408.02434) (xy 169.262904 -408.089721)
			(xy 169.270948 -408.156542) (xy 169.270948 -408.223846) (xy 169.262906 -408.290667) (xy 169.246935 -408.356048)
			(xy 169.223265 -408.419052) (xy 169.192235 -408.478776) (xy 169.15429 -408.534363) (xy 169.132504 -408.560016)
			(xy 169.126719 -408.567169) (xy 169.120197 -408.584354) (xy 169.119804 -408.593544) (xy 169.119804 -409.086812)
			(xy 169.120208 -409.096) (xy 169.126726 -409.113184) (xy 169.132504 -409.12034) (xy 169.154255 -409.146022)
			(xy 169.192202 -409.201605) (xy 169.223235 -409.261325) (xy 169.246908 -409.324325) (xy 169.262882 -409.389704)
			(xy 169.270928 -409.456522) (xy 169.270931 -409.523824) (xy 169.262891 -409.590643) (xy 169.246924 -409.656023)
			(xy 169.223257 -409.719026) (xy 169.19223 -409.778748) (xy 169.154288 -409.834335) (xy 169.132504 -409.859988)
			(xy 169.126688 -409.86712) (xy 169.120185 -409.88432) (xy 169.119804 -409.893516) (xy 169.119804 -410.051504)
			(xy 169.119382 -410.061658) (xy 169.111586 -410.08041) (xy 169.097189 -410.094733) (xy 169.078398 -410.102433)
			(xy 169.068242 -410.102812) (xy 168.351962 -410.102812) (xy 168.341839 -410.102306) (xy 168.323127 -410.094575)
			(xy 168.308774 -410.080296) (xy 168.300947 -410.061624) (xy 168.3004 -410.051504) (xy 168.3004 -409.893516)
			(xy 168.299982 -409.88433) (xy 168.293474 -409.867145) (xy 168.2877 -409.859988) (xy 168.265878 -409.834364)
			(xy 168.227933 -409.778773) (xy 168.196903 -409.719045) (xy 168.173234 -409.656037) (xy 168.157265 -409.590652)
			(xy 168.149224 -409.523826) (xy 167.020557 -409.523826) (xy 166.992095 -409.578598) (xy 166.954145 -409.634184)
			(xy 166.932356 -409.659836) (xy 166.926556 -409.666979) (xy 166.920045 -409.684171) (xy 166.919656 -409.693364)
			(xy 166.919656 -410.186632) (xy 166.920061 -410.19582) (xy 166.926579 -410.213003) (xy 166.932356 -410.22016)
			(xy 166.954128 -410.245825) (xy 166.992078 -410.30141) (xy 167.023112 -410.361131) (xy 167.046786 -410.424134)
			(xy 167.06276 -410.489515) (xy 167.070805 -410.556336) (xy 167.070807 -410.62364) (xy 167.0708 -410.623701)
			(xy 170.348846 -410.623701) (xy 170.348847 -410.556275) (xy 170.356926 -410.489335) (xy 170.372964 -410.423844)
			(xy 170.396732 -410.360747) (xy 170.427888 -410.30095) (xy 170.465981 -410.245316) (xy 170.487848 -410.219652)
			(xy 170.493653 -410.212513) (xy 170.500162 -410.195318) (xy 170.500548 -410.186124) (xy 170.500548 -409.693872)
			(xy 170.50014 -409.684685) (xy 170.493624 -409.667501) (xy 170.487848 -409.660344) (xy 170.465994 -409.63467)
			(xy 170.427902 -409.579038) (xy 170.396748 -409.519243) (xy 170.372981 -409.456147) (xy 170.356943 -409.390659)
			(xy 170.348866 -409.323721) (xy 170.348865 -409.256297) (xy 170.35694 -409.189359) (xy 170.372976 -409.12387)
			(xy 170.396741 -409.060773) (xy 170.427893 -409.000978) (xy 170.465983 -408.945344) (xy 170.487848 -408.91968)
			(xy 170.493642 -408.912533) (xy 170.500157 -408.895344) (xy 170.500548 -408.886152) (xy 170.500548 -408.728672)
			(xy 170.501061 -408.718568) (xy 170.508798 -408.699899) (xy 170.523086 -408.685607) (xy 170.541752 -408.677864)
			(xy 170.551856 -408.677364) (xy 171.268136 -408.677364) (xy 171.278243 -408.677855) (xy 171.296915 -408.685598)
			(xy 171.311207 -408.699892) (xy 171.318947 -408.718565) (xy 171.319444 -408.728672) (xy 171.319444 -408.886152)
			(xy 171.31989 -408.895335) (xy 171.32638 -408.912519) (xy 171.332144 -408.91968) (xy 171.354022 -408.945335)
			(xy 171.392114 -409.000969) (xy 171.423267 -409.060766) (xy 171.447033 -409.123865) (xy 171.463069 -409.189356)
			(xy 171.471145 -409.256296) (xy 171.471144 -409.323722) (xy 171.463066 -409.390662) (xy 171.447028 -409.456152)
			(xy 171.42326 -409.51925) (xy 171.420875 -409.523827) (xy 172.548991 -409.523827) (xy 172.548995 -409.456519)
			(xy 172.557043 -409.389693) (xy 172.573021 -409.324308) (xy 172.5967 -409.261302) (xy 172.62774 -409.201577)
			(xy 172.665697 -409.145992) (xy 172.687488 -409.12034) (xy 172.693291 -409.113199) (xy 172.699802 -409.096005)
			(xy 172.700188 -409.086812) (xy 172.700188 -408.593544) (xy 172.699759 -408.584359) (xy 172.693259 -408.567174)
			(xy 172.687488 -408.560016) (xy 172.665691 -408.534371) (xy 172.627739 -408.478785) (xy 172.596704 -408.419061)
			(xy 172.573029 -408.356055) (xy 172.557055 -408.290671) (xy 172.549011 -408.223847) (xy 172.549012 -408.156541)
			(xy 172.557057 -408.089717) (xy 172.573033 -408.024333) (xy 172.596708 -407.961328) (xy 172.627745 -407.901605)
			(xy 172.665698 -407.84602) (xy 172.687488 -407.820368) (xy 172.693279 -407.813219) (xy 172.699797 -407.796031)
			(xy 172.700188 -407.78684) (xy 172.700188 -407.628852) (xy 172.700582 -407.618696) (xy 172.708391 -407.599945)
			(xy 172.722796 -407.585624) (xy 172.741592 -407.577924) (xy 172.75175 -407.577544) (xy 173.46803 -407.577544)
			(xy 173.478159 -407.578002) (xy 173.496882 -407.58574) (xy 173.511237 -407.600035) (xy 173.519055 -407.618725)
			(xy 173.519592 -407.628852) (xy 173.519592 -407.78684) (xy 173.519985 -407.796029) (xy 173.526511 -407.813213)
			(xy 173.532292 -407.820368) (xy 173.554071 -407.846027) (xy 173.592018 -407.901613) (xy 173.62305 -407.961336)
			(xy 173.646722 -408.02434) (xy 173.662694 -408.089721) (xy 173.670739 -408.156542) (xy 173.670739 -408.223846)
			(xy 173.662697 -408.290667) (xy 173.646725 -408.356049) (xy 173.623055 -408.419053) (xy 173.592024 -408.478776)
			(xy 173.554078 -408.534363) (xy 173.532292 -408.560016) (xy 173.526505 -408.567168) (xy 173.519985 -408.584353)
			(xy 173.519592 -408.593544) (xy 173.519592 -409.086812) (xy 173.519998 -409.096) (xy 173.526515 -409.113184)
			(xy 173.532292 -409.12034) (xy 173.554043 -409.146022) (xy 173.591991 -409.201605) (xy 173.623024 -409.261324)
			(xy 173.646698 -409.324325) (xy 173.662672 -409.389703) (xy 173.670719 -409.456522) (xy 173.670722 -409.523824)
			(xy 173.662682 -409.590643) (xy 173.646714 -409.656023) (xy 173.623047 -409.719026) (xy 173.592019 -409.778749)
			(xy 173.554077 -409.834336) (xy 173.532292 -409.859988) (xy 173.526475 -409.867118) (xy 173.519973 -409.88432)
			(xy 173.519592 -409.893516) (xy 173.519592 -410.051504) (xy 173.519181 -410.061659) (xy 173.511383 -410.080413)
			(xy 173.496983 -410.094737) (xy 173.478187 -410.102435) (xy 173.46803 -410.102812) (xy 172.75175 -410.102812)
			(xy 172.741633 -410.102234) (xy 172.722923 -410.094532) (xy 172.708567 -410.080274) (xy 172.700736 -410.061618)
			(xy 172.700188 -410.051504) (xy 172.700188 -409.893516) (xy 172.699773 -409.884329) (xy 172.693263 -409.867145)
			(xy 172.687488 -409.859988) (xy 172.665663 -409.834366) (xy 172.627713 -409.778776) (xy 172.596678 -409.719049)
			(xy 172.573005 -409.65604) (xy 172.557033 -409.590654) (xy 172.548991 -409.523827) (xy 171.420875 -409.523827)
			(xy 171.392104 -409.579046) (xy 171.354011 -409.63468) (xy 171.332144 -409.660344) (xy 171.326339 -409.667483)
			(xy 171.319831 -409.684679) (xy 171.319444 -409.693872) (xy 171.319444 -410.186124) (xy 171.319855 -410.195311)
			(xy 171.32637 -410.212494) (xy 171.332144 -410.219652) (xy 171.353994 -410.245329) (xy 171.392087 -410.300961)
			(xy 171.423242 -410.360755) (xy 171.447009 -410.42385) (xy 171.463047 -410.489338) (xy 171.471125 -410.556276)
			(xy 171.471127 -410.623641) (xy 174.749166 -410.623641) (xy 174.749167 -410.556335) (xy 174.757213 -410.489511)
			(xy 174.773187 -410.424128) (xy 174.796862 -410.361123) (xy 174.827897 -410.301399) (xy 174.865847 -410.245812)
			(xy 174.887636 -410.22016) (xy 174.893437 -410.213018) (xy 174.899948 -410.195825) (xy 174.900336 -410.186632)
			(xy 174.900336 -409.693364) (xy 174.899935 -409.684176) (xy 174.893414 -409.666992) (xy 174.887636 -409.659836)
			(xy 174.86586 -409.634174) (xy 174.827911 -409.578589) (xy 174.796878 -409.518867) (xy 174.773205 -409.455863)
			(xy 174.757231 -409.390482) (xy 174.749186 -409.323661) (xy 174.749185 -409.256357) (xy 174.757228 -409.189535)
			(xy 174.773199 -409.124154) (xy 174.79687 -409.06115) (xy 174.827902 -409.001427) (xy 174.865849 -408.94584)
			(xy 174.887636 -408.920188) (xy 174.893425 -408.913037) (xy 174.899943 -408.895851) (xy 174.900336 -408.88666)
			(xy 174.900336 -408.728672) (xy 174.900699 -408.718512) (xy 174.908511 -408.699752) (xy 174.922926 -408.685428)
			(xy 174.941735 -408.677736) (xy 174.951898 -408.677364) (xy 175.668178 -408.677364) (xy 175.678306 -408.677845)
			(xy 175.697032 -408.68557) (xy 175.711389 -408.699859) (xy 175.719205 -408.718546) (xy 175.71974 -408.728672)
			(xy 175.71974 -408.88666) (xy 175.720183 -408.895843) (xy 175.726675 -408.913028) (xy 175.73244 -408.920188)
			(xy 175.75424 -408.94583) (xy 175.79219 -409.001418) (xy 175.823224 -409.061142) (xy 175.846897 -409.124148)
			(xy 175.862869 -409.189532) (xy 175.870913 -409.256356) (xy 175.870912 -409.323662) (xy 175.862866 -409.390486)
			(xy 175.846891 -409.455869) (xy 175.823216 -409.518874) (xy 175.792181 -409.578598) (xy 175.754229 -409.634184)
			(xy 175.73244 -409.659836) (xy 175.726638 -409.666977) (xy 175.720128 -409.684171) (xy 175.71974 -409.693364)
			(xy 175.71974 -410.186632) (xy 175.720148 -410.195819) (xy 175.726665 -410.213003) (xy 175.73244 -410.22016)
			(xy 175.754213 -410.245825) (xy 175.792163 -410.301409) (xy 175.823198 -410.361131) (xy 175.846873 -410.424134)
			(xy 175.862848 -410.489514) (xy 175.870893 -410.556336) (xy 175.870895 -410.62364) (xy 175.862852 -410.690462)
			(xy 175.84688 -410.755843) (xy 175.823208 -410.818847) (xy 175.792176 -410.87857) (xy 175.754227 -410.934156)
			(xy 175.73244 -410.959808) (xy 175.72665 -410.966958) (xy 175.720133 -410.984145) (xy 175.71974 -410.993336)
			(xy 175.71974 -411.151324) (xy 175.719299 -411.161475) (xy 175.711503 -411.18022) (xy 175.697113 -411.194541)
			(xy 175.678331 -411.202247) (xy 175.668178 -411.202632) (xy 174.951898 -411.202632) (xy 174.941768 -411.202174)
			(xy 174.923041 -411.194441) (xy 174.908684 -411.180145) (xy 174.90087 -411.161452) (xy 174.900336 -411.151324)
			(xy 174.900336 -410.993336) (xy 174.8999 -410.984152) (xy 174.893403 -410.966968) (xy 174.887636 -410.959808)
			(xy 174.865833 -410.934169) (xy 174.827884 -410.87858) (xy 174.796852 -410.818855) (xy 174.77318 -410.755849)
			(xy 174.757208 -410.690465) (xy 174.749166 -410.623641) (xy 171.471127 -410.623641) (xy 171.471127 -410.6237)
			(xy 171.463052 -410.690638) (xy 171.447016 -410.756127) (xy 171.423251 -410.819223) (xy 171.392099 -410.879019)
			(xy 171.354009 -410.934652) (xy 171.332144 -410.960316) (xy 171.326351 -410.967464) (xy 171.319836 -410.984653)
			(xy 171.319444 -410.993844) (xy 171.319444 -411.151324) (xy 171.318936 -411.161429) (xy 171.311198 -411.180099)
			(xy 171.296909 -411.194392) (xy 171.278241 -411.202133) (xy 171.268136 -411.202632) (xy 170.551856 -411.202632)
			(xy 170.541748 -411.202152) (xy 170.523075 -411.194405) (xy 170.508783 -411.180108) (xy 170.501044 -411.161432)
			(xy 170.500548 -411.151324) (xy 170.500548 -410.993844) (xy 170.500106 -410.98466) (xy 170.493613 -410.967476)
			(xy 170.487848 -410.960316) (xy 170.465967 -410.934665) (xy 170.427875 -410.879029) (xy 170.396723 -410.819232)
			(xy 170.372957 -410.756133) (xy 170.356921 -410.690641) (xy 170.348846 -410.623701) (xy 167.0708 -410.623701)
			(xy 167.062764 -410.690461) (xy 167.046793 -410.755843) (xy 167.023122 -410.818847) (xy 166.99209 -410.87857)
			(xy 166.954143 -410.934156) (xy 166.932356 -410.959808) (xy 166.926568 -410.966959) (xy 166.920049 -410.984145)
			(xy 166.919656 -410.993336) (xy 166.919656 -411.151324) (xy 166.919199 -411.161473) (xy 166.911406 -411.180215)
			(xy 166.897021 -411.194535) (xy 166.878245 -411.202244) (xy 166.868094 -411.202632) (xy 166.151814 -411.202632)
			(xy 166.141685 -411.202161) (xy 166.122959 -411.194433) (xy 166.108601 -411.180141) (xy 166.100786 -411.161451)
			(xy 166.100252 -411.151324) (xy 166.100252 -410.993336) (xy 166.099813 -410.984152) (xy 166.093318 -410.966968)
			(xy 166.087552 -410.959808) (xy 166.065748 -410.934169) (xy 166.027799 -410.878581) (xy 165.996765 -410.818856)
			(xy 165.973093 -410.75585) (xy 165.957121 -410.690466) (xy 165.949078 -410.623641) (xy 162.671039 -410.623641)
			(xy 162.671039 -410.6237) (xy 162.662964 -410.690637) (xy 162.646929 -410.756126) (xy 162.623165 -410.819223)
			(xy 162.592014 -410.879018) (xy 162.553924 -410.934651) (xy 162.53206 -410.960316) (xy 162.526269 -410.967465)
			(xy 162.519752 -410.984653) (xy 162.51936 -410.993844) (xy 162.51936 -411.151324) (xy 162.519003 -411.161453)
			(xy 162.511239 -411.180165) (xy 162.496904 -411.19448) (xy 162.478182 -411.202217) (xy 162.468052 -411.202632)
			(xy 161.751772 -411.202632) (xy 161.741665 -411.202139) (xy 161.722993 -411.194398) (xy 161.7087 -411.180104)
			(xy 161.700961 -411.161431) (xy 161.700464 -411.151324) (xy 161.700464 -410.993844) (xy 161.700019 -410.984661)
			(xy 161.693528 -410.967477) (xy 161.687764 -410.960316) (xy 161.665886 -410.934663) (xy 161.6278 -410.879026)
			(xy 161.596652 -410.819228) (xy 161.57289 -410.756129) (xy 161.556857 -410.690639) (xy 161.548783 -410.6237)
			(xy 154.57678 -410.6237) (xy 154.57678 -417.371276) (xy 154.576371 -417.383441) (xy 154.568857 -417.406581)
			(xy 154.554556 -417.426265) (xy 154.53487 -417.440562) (xy 154.511729 -417.448073) (xy 154.499564 -417.448492)
			(xy 141.100302 -417.448492) (xy 141.088157 -417.448035) (xy 141.06506 -417.440516) (xy 141.045426 -417.426216)
			(xy 141.031183 -417.406541) (xy 141.02373 -417.383422) (xy 141.02334 -417.371276) (xy 66.525648 -417.371276)
			(xy 66.525648 -417.533836) (xy 66.525172 -417.545883) (xy 66.517735 -417.568802) (xy 66.503597 -417.588313)
			(xy 66.484133 -417.602517) (xy 66.46124 -417.610031) (xy 66.449194 -417.610544) (xy 53.151024 -417.610544)
			(xy 53.138954 -417.610016) (xy 53.115994 -417.602564) (xy 53.09646 -417.588383) (xy 53.082263 -417.56886)
			(xy 53.074793 -417.545905) (xy 53.074316 -417.533836) (xy 53.074316 -417.289488) (xy 53.073808 -417.289488)
			(xy 0.681656 -417.289488) (xy 0.736245 -417.384039) (xy 0.79912 -417.476259) (xy 0.86871 -417.563523)
			(xy 0.944627 -417.645342) (xy 1.026446 -417.721259) (xy 1.113709 -417.790849) (xy 1.205929 -417.853724)
			(xy 1.302589 -417.909531) (xy 1.40315 -417.957958) (xy 1.507049 -417.998736) (xy 1.613704 -418.031635)
			(xy 1.72252 -418.056471) (xy 1.832887 -418.073107) (xy 1.944189 -418.081448) (xy 1.999996 -418.081968)
		)
		(stroke
			(width 0)
			(type solid)
		)
		(fill yes)
		(layer "In12.Cu")
		(net "GND")
	)
	(gr_line
		(start 30.927802 -45.074586)
		(end 32.387286 -46.665642)
		(stroke
			(width 0.1016)
			(type default)
		)
		(layer "In12.Cu")
	)
	(gr_line
		(start 31.500064 -44.549314)
		(end 30.927802 -45.074586)
		(stroke
			(width 0.1016)
			(type default)
		)
		(layer "In12.Cu")
	)
	(gr_line
		(start 31.500572 -44.54906)
		(end 32.959802 -46.140116)
		(stroke
			(width 0.1016)
			(type default)
		)
		(layer "In12.Cu")
	)
	(gr_line
		(start 32.68853 -44.205398)
		(end 33.2613 -43.679872)
		(stroke
			(width 0.1016)
			(type default)
		)
		(layer "In12.Cu")
	)
	(gr_line
		(start 32.68853 -44.205398)
		(end 34.148014 -45.796454)
		(stroke
			(width 0.1016)
			(type default)
		)
		(layer "In12.Cu")
	)
	(gr_line
		(start 33.2613 -43.679872)
		(end 34.72053 -45.270928)
		(stroke
			(width 0.1016)
			(type default)
		)
		(layer "In12.Cu")
	)
	(gr_line
		(start 34.148014 -45.796454)
		(end 32.68853 -44.205398)
		(stroke
			(width 0.1016)
			(type default)
		)
		(layer "In12.Cu")
	)
	(gr_line
		(start 36.240212 -51.197764)
		(end 36.375594 -53.352446)
		(stroke
			(width 0.1016)
			(type default)
		)
		(layer "In12.Cu")
	)
	(gr_line
		(start 37.01542 -51.148742)
		(end 36.240212 -51.197764)
		(stroke
			(width 0.1016)
			(type default)
		)
		(layer "In12.Cu")
	)
	(gr_line
		(start 37.01542 -51.148742)
		(end 37.150802 -53.303424)
		(stroke
			(width 0.1016)
			(type default)
		)
		(layer "In12.Cu")
	)
	(gr_line
		(start 38.105334 -50.819304)
		(end 38.240716 -52.973986)
		(stroke
			(width 0.1016)
			(type default)
		)
		(layer "In12.Cu")
	)
	(gr_line
		(start 38.880542 -50.770282)
		(end 38.105334 -50.819304)
		(stroke
			(width 0.1016)
			(type default)
		)
		(layer "In12.Cu")
	)
	(gr_line
		(start 38.880542 -50.770282)
		(end 39.015924 -52.924964)
		(stroke
			(width 0.1016)
			(type default)
		)
		(layer "In12.Cu")
	)
	(gr_circle
		(center 43.499786 -312.049922)
		(end 43.753786 -312.049922)
		(stroke
			(width 0.1016)
			(type default)
		)
		(fill no)
		(layer "In12.Cu")
	)
	(gr_circle
		(center 43.499786 -311.099962)
		(end 43.753786 -311.099962)
		(stroke
			(width 0.1016)
			(type default)
		)
		(fill no)
		(layer "In12.Cu")
	)
	(gr_circle
		(center 44.449746 -313.949842)
		(end 44.703746 -313.949842)
		(stroke
			(width 0.1016)
			(type default)
		)
		(fill no)
		(layer "In12.Cu")
	)
	(gr_circle
		(center 44.449746 -312.999882)
		(end 44.703746 -312.999882)
		(stroke
			(width 0.1016)
			(type default)
		)
		(fill no)
		(layer "In12.Cu")
	)
	(gr_circle
		(center 45.39996 -312.049922)
		(end 45.65396 -312.049922)
		(stroke
			(width 0.1016)
			(type default)
		)
		(fill no)
		(layer "In12.Cu")
	)
	(gr_circle
		(center 45.39996 -311.099962)
		(end 45.65396 -311.099962)
		(stroke
			(width 0.1016)
			(type default)
		)
		(fill no)
		(layer "In12.Cu")
	)
	(gr_circle
		(center 46.34992 -313.949842)
		(end 46.60392 -313.949842)
		(stroke
			(width 0.1016)
			(type default)
		)
		(fill no)
		(layer "In12.Cu")
	)
	(gr_circle
		(center 46.34992 -312.999882)
		(end 46.60392 -312.999882)
		(stroke
			(width 0.1016)
			(type default)
		)
		(fill no)
		(layer "In12.Cu")
	)
	(gr_circle
		(center 47.29988 -312.049922)
		(end 47.55388 -312.049922)
		(stroke
			(width 0.1016)
			(type default)
		)
		(fill no)
		(layer "In12.Cu")
	)
	(gr_circle
		(center 47.29988 -311.099962)
		(end 47.55388 -311.099962)
		(stroke
			(width 0.1016)
			(type default)
		)
		(fill no)
		(layer "In12.Cu")
	)
	(gr_circle
		(center 48.24984 -313.949842)
		(end 48.50384 -313.949842)
		(stroke
			(width 0.1016)
			(type default)
		)
		(fill no)
		(layer "In12.Cu")
	)
	(gr_circle
		(center 48.24984 -312.999882)
		(end 48.50384 -312.999882)
		(stroke
			(width 0.1016)
			(type default)
		)
		(fill no)
		(layer "In12.Cu")
	)
	(gr_circle
		(center 49.1998 -312.049922)
		(end 49.4538 -312.049922)
		(stroke
			(width 0.1016)
			(type default)
		)
		(fill no)
		(layer "In12.Cu")
	)
	(gr_circle
		(center 49.1998 -311.099962)
		(end 49.4538 -311.099962)
		(stroke
			(width 0.1016)
			(type default)
		)
		(fill no)
		(layer "In12.Cu")
	)
	(gr_circle
		(center 50.14976 -313.949842)
		(end 50.40376 -313.949842)
		(stroke
			(width 0.1016)
			(type default)
		)
		(fill no)
		(layer "In12.Cu")
	)
	(gr_circle
		(center 50.14976 -312.999882)
		(end 50.40376 -312.999882)
		(stroke
			(width 0.1016)
			(type default)
		)
		(fill no)
		(layer "In12.Cu")
	)
	(gr_circle
		(center 51.099974 -312.049922)
		(end 51.353974 -312.049922)
		(stroke
			(width 0.1016)
			(type default)
		)
		(fill no)
		(layer "In12.Cu")
	)
	(gr_circle
		(center 51.099974 -311.099962)
		(end 51.353974 -311.099962)
		(stroke
			(width 0.1016)
			(type default)
		)
		(fill no)
		(layer "In12.Cu")
	)
	(gr_circle
		(center 52.049934 -313.949842)
		(end 52.303934 -313.949842)
		(stroke
			(width 0.1016)
			(type default)
		)
		(fill no)
		(layer "In12.Cu")
	)
	(gr_circle
		(center 52.049934 -312.999882)
		(end 52.303934 -312.999882)
		(stroke
			(width 0.1016)
			(type default)
		)
		(fill no)
		(layer "In12.Cu")
	)
	(gr_circle
		(center 52.999894 -312.049922)
		(end 53.253894 -312.049922)
		(stroke
			(width 0.1016)
			(type default)
		)
		(fill no)
		(layer "In12.Cu")
	)
	(gr_circle
		(center 52.999894 -311.099962)
		(end 53.253894 -311.099962)
		(stroke
			(width 0.1016)
			(type default)
		)
		(fill no)
		(layer "In12.Cu")
	)
	(gr_circle
		(center 53.949854 -313.949842)
		(end 54.203854 -313.949842)
		(stroke
			(width 0.1016)
			(type default)
		)
		(fill no)
		(layer "In12.Cu")
	)
	(gr_circle
		(center 53.949854 -312.999882)
		(end 54.203854 -312.999882)
		(stroke
			(width 0.1016)
			(type default)
		)
		(fill no)
		(layer "In12.Cu")
	)
	(gr_circle
		(center 54.899814 -312.049922)
		(end 55.153814 -312.049922)
		(stroke
			(width 0.1016)
			(type default)
		)
		(fill no)
		(layer "In12.Cu")
	)
	(gr_circle
		(center 54.899814 -311.099962)
		(end 55.153814 -311.099962)
		(stroke
			(width 0.1016)
			(type default)
		)
		(fill no)
		(layer "In12.Cu")
	)
	(gr_circle
		(center 55.849774 -313.949842)
		(end 56.103774 -313.949842)
		(stroke
			(width 0.1016)
			(type default)
		)
		(fill no)
		(layer "In12.Cu")
	)
	(gr_circle
		(center 55.849774 -312.999882)
		(end 56.103774 -312.999882)
		(stroke
			(width 0.1016)
			(type default)
		)
		(fill no)
		(layer "In12.Cu")
	)
	(gr_line
		(start 56.75249 -44.884086)
		(end 58.211974 -46.475142)
		(stroke
			(width 0.1016)
			(type default)
		)
		(layer "In12.Cu")
	)
	(gr_circle
		(center 56.799988 -312.049922)
		(end 57.053988 -312.049922)
		(stroke
			(width 0.1016)
			(type default)
		)
		(fill no)
		(layer "In12.Cu")
	)
	(gr_circle
		(center 56.799988 -311.099962)
		(end 57.053988 -311.099962)
		(stroke
			(width 0.1016)
			(type default)
		)
		(fill no)
		(layer "In12.Cu")
	)
	(gr_line
		(start 57.324752 -44.358814)
		(end 56.75249 -44.884086)
		(stroke
			(width 0.1016)
			(type default)
		)
		(layer "In12.Cu")
	)
	(gr_line
		(start 57.32526 -44.35856)
		(end 58.78449 -45.949616)
		(stroke
			(width 0.1016)
			(type default)
		)
		(layer "In12.Cu")
	)
	(gr_circle
		(center 57.749948 -313.949842)
		(end 58.003948 -313.949842)
		(stroke
			(width 0.1016)
			(type default)
		)
		(fill no)
		(layer "In12.Cu")
	)
	(gr_circle
		(center 57.749948 -312.999882)
		(end 58.003948 -312.999882)
		(stroke
			(width 0.1016)
			(type default)
		)
		(fill no)
		(layer "In12.Cu")
	)
	(gr_line
		(start 59.074558 -44.626276)
		(end 60.534042 -46.217332)
		(stroke
			(width 0.1016)
			(type default)
		)
		(layer "In12.Cu")
	)
	(gr_line
		(start 59.64682 -44.101004)
		(end 59.074558 -44.626276)
		(stroke
			(width 0.1016)
			(type default)
		)
		(layer "In12.Cu")
	)
	(gr_line
		(start 59.647328 -44.10075)
		(end 61.106558 -45.691806)
		(stroke
			(width 0.1016)
			(type default)
		)
		(layer "In12.Cu")
	)
	(gr_line
		(start 62.2427 -51.235356)
		(end 62.378082 -53.390038)
		(stroke
			(width 0.1016)
			(type default)
		)
		(layer "In12.Cu")
	)
	(gr_line
		(start 63.017908 -51.186334)
		(end 62.2427 -51.235356)
		(stroke
			(width 0.1016)
			(type default)
		)
		(layer "In12.Cu")
	)
	(gr_line
		(start 63.017908 -51.186334)
		(end 63.15329 -53.341016)
		(stroke
			(width 0.1016)
			(type default)
		)
		(layer "In12.Cu")
	)
	(gr_line
		(start 64.107822 -50.856896)
		(end 64.243204 -53.011578)
		(stroke
			(width 0.1016)
			(type default)
		)
		(layer "In12.Cu")
	)
	(gr_line
		(start 64.88303 -50.807874)
		(end 64.107822 -50.856896)
		(stroke
			(width 0.1016)
			(type default)
		)
		(layer "In12.Cu")
	)
	(gr_line
		(start 64.88303 -50.807874)
		(end 65.018412 -52.962556)
		(stroke
			(width 0.1016)
			(type default)
		)
		(layer "In12.Cu")
	)
	(gr_circle
		(center 73.899776 -316.799722)
		(end 74.153776 -316.799722)
		(stroke
			(width 0.1016)
			(type default)
		)
		(fill no)
		(layer "In12.Cu")
	)
	(gr_circle
		(center 73.899776 -315.849762)
		(end 74.153776 -315.849762)
		(stroke
			(width 0.1016)
			(type default)
		)
		(fill no)
		(layer "In12.Cu")
	)
	(gr_circle
		(center 74.84999 -318.699896)
		(end 75.10399 -318.699896)
		(stroke
			(width 0.1016)
			(type default)
		)
		(fill no)
		(layer "In12.Cu")
	)
	(gr_circle
		(center 74.84999 -317.749936)
		(end 75.10399 -317.749936)
		(stroke
			(width 0.1016)
			(type default)
		)
		(fill no)
		(layer "In12.Cu")
	)
	(gr_circle
		(center 75.79995 -316.799722)
		(end 76.05395 -316.799722)
		(stroke
			(width 0.1016)
			(type default)
		)
		(fill no)
		(layer "In12.Cu")
	)
	(gr_circle
		(center 75.79995 -315.849762)
		(end 76.05395 -315.849762)
		(stroke
			(width 0.1016)
			(type default)
		)
		(fill no)
		(layer "In12.Cu")
	)
	(gr_circle
		(center 76.74991 -318.699896)
		(end 77.00391 -318.699896)
		(stroke
			(width 0.1016)
			(type default)
		)
		(fill no)
		(layer "In12.Cu")
	)
	(gr_circle
		(center 76.74991 -317.749936)
		(end 77.00391 -317.749936)
		(stroke
			(width 0.1016)
			(type default)
		)
		(fill no)
		(layer "In12.Cu")
	)
	(gr_circle
		(center 77.69987 -316.799722)
		(end 77.95387 -316.799722)
		(stroke
			(width 0.1016)
			(type default)
		)
		(fill no)
		(layer "In12.Cu")
	)
	(gr_circle
		(center 77.69987 -315.849762)
		(end 77.95387 -315.849762)
		(stroke
			(width 0.1016)
			(type default)
		)
		(fill no)
		(layer "In12.Cu")
	)
	(gr_circle
		(center 78.64983 -318.699896)
		(end 78.90383 -318.699896)
		(stroke
			(width 0.1016)
			(type default)
		)
		(fill no)
		(layer "In12.Cu")
	)
	(gr_circle
		(center 78.64983 -317.749936)
		(end 78.90383 -317.749936)
		(stroke
			(width 0.1016)
			(type default)
		)
		(fill no)
		(layer "In12.Cu")
	)
	(gr_circle
		(center 79.59979 -316.799722)
		(end 79.85379 -316.799722)
		(stroke
			(width 0.1016)
			(type default)
		)
		(fill no)
		(layer "In12.Cu")
	)
	(gr_circle
		(center 79.59979 -315.849762)
		(end 79.85379 -315.849762)
		(stroke
			(width 0.1016)
			(type default)
		)
		(fill no)
		(layer "In12.Cu")
	)
	(gr_circle
		(center 79.59979 -309.199788)
		(end 79.85379 -309.199788)
		(stroke
			(width 0.1016)
			(type default)
		)
		(fill no)
		(layer "In12.Cu")
	)
	(gr_circle
		(center 79.59979 -307.299868)
		(end 79.85379 -307.299868)
		(stroke
			(width 0.1016)
			(type default)
		)
		(fill no)
		(layer "In12.Cu")
	)
	(gr_circle
		(center 79.59979 -305.399948)
		(end 79.85379 -305.399948)
		(stroke
			(width 0.1016)
			(type default)
		)
		(fill no)
		(layer "In12.Cu")
	)
	(gr_circle
		(center 80.54975 -318.699896)
		(end 80.80375 -318.699896)
		(stroke
			(width 0.1016)
			(type default)
		)
		(fill no)
		(layer "In12.Cu")
	)
	(gr_circle
		(center 80.54975 -317.749936)
		(end 80.80375 -317.749936)
		(stroke
			(width 0.1016)
			(type default)
		)
		(fill no)
		(layer "In12.Cu")
	)
	(gr_circle
		(center 80.54975 -309.199788)
		(end 80.80375 -309.199788)
		(stroke
			(width 0.1016)
			(type default)
		)
		(fill no)
		(layer "In12.Cu")
	)
	(gr_circle
		(center 80.54975 -307.299868)
		(end 80.80375 -307.299868)
		(stroke
			(width 0.1016)
			(type default)
		)
		(fill no)
		(layer "In12.Cu")
	)
	(gr_circle
		(center 80.54975 -305.399948)
		(end 80.80375 -305.399948)
		(stroke
			(width 0.1016)
			(type default)
		)
		(fill no)
		(layer "In12.Cu")
	)
	(gr_circle
		(center 81.499964 -316.799722)
		(end 81.753964 -316.799722)
		(stroke
			(width 0.1016)
			(type default)
		)
		(fill no)
		(layer "In12.Cu")
	)
	(gr_circle
		(center 81.499964 -310.149748)
		(end 81.753964 -310.149748)
		(stroke
			(width 0.1016)
			(type default)
		)
		(fill no)
		(layer "In12.Cu")
	)
	(gr_circle
		(center 81.499964 -308.249828)
		(end 81.753964 -308.249828)
		(stroke
			(width 0.1016)
			(type default)
		)
		(fill no)
		(layer "In12.Cu")
	)
	(gr_circle
		(center 81.499964 -306.349908)
		(end 81.753964 -306.349908)
		(stroke
			(width 0.1016)
			(type default)
		)
		(fill no)
		(layer "In12.Cu")
	)
	(gr_circle
		(center 81.499964 -304.449734)
		(end 81.753964 -304.449734)
		(stroke
			(width 0.1016)
			(type default)
		)
		(fill no)
		(layer "In12.Cu")
	)
	(gr_circle
		(center 82.449924 -316.799722)
		(end 82.703924 -316.799722)
		(stroke
			(width 0.1016)
			(type default)
		)
		(fill no)
		(layer "In12.Cu")
	)
	(gr_circle
		(center 82.449924 -310.149748)
		(end 82.703924 -310.149748)
		(stroke
			(width 0.1016)
			(type default)
		)
		(fill no)
		(layer "In12.Cu")
	)
	(gr_circle
		(center 82.449924 -308.249828)
		(end 82.703924 -308.249828)
		(stroke
			(width 0.1016)
			(type default)
		)
		(fill no)
		(layer "In12.Cu")
	)
	(gr_circle
		(center 82.449924 -306.349908)
		(end 82.703924 -306.349908)
		(stroke
			(width 0.1016)
			(type default)
		)
		(fill no)
		(layer "In12.Cu")
	)
	(gr_circle
		(center 82.449924 -304.449734)
		(end 82.703924 -304.449734)
		(stroke
			(width 0.1016)
			(type default)
		)
		(fill no)
		(layer "In12.Cu")
	)
	(gr_line
		(start 82.938366 -45.086524)
		(end 84.39785 -46.67758)
		(stroke
			(width 0.1016)
			(type default)
		)
		(layer "In12.Cu")
	)
	(gr_line
		(start 83.510628 -44.561252)
		(end 82.938366 -45.086524)
		(stroke
			(width 0.1016)
			(type default)
		)
		(layer "In12.Cu")
	)
	(gr_line
		(start 83.511136 -44.560998)
		(end 84.970366 -46.152054)
		(stroke
			(width 0.1016)
			(type default)
		)
		(layer "In12.Cu")
	)
	(gr_line
		(start 84.718906 -44.22648)
		(end 86.17839 -45.817536)
		(stroke
			(width 0.1016)
			(type default)
		)
		(layer "In12.Cu")
	)
	(gr_line
		(start 85.291168 -43.701208)
		(end 84.718906 -44.22648)
		(stroke
			(width 0.1016)
			(type default)
		)
		(layer "In12.Cu")
	)
	(gr_line
		(start 85.291676 -43.700954)
		(end 86.750906 -45.29201)
		(stroke
			(width 0.1016)
			(type default)
		)
		(layer "In12.Cu")
	)
	(gr_line
		(start 88.253316 -51.406298)
		(end 88.388952 -53.56098)
		(stroke
			(width 0.1016)
			(type default)
		)
		(layer "In12.Cu")
	)
	(gr_line
		(start 89.028524 -51.357276)
		(end 88.253316 -51.406298)
		(stroke
			(width 0.1016)
			(type default)
		)
		(layer "In12.Cu")
	)
	(gr_line
		(start 89.029032 -51.357276)
		(end 89.164668 -53.511958)
		(stroke
			(width 0.1016)
			(type default)
		)
		(layer "In12.Cu")
	)
	(gr_line
		(start 90.104468 -50.80762)
		(end 90.240104 -52.962302)
		(stroke
			(width 0.1016)
			(type default)
		)
		(layer "In12.Cu")
	)
	(gr_line
		(start 90.879676 -50.758598)
		(end 90.104468 -50.80762)
		(stroke
			(width 0.1016)
			(type default)
		)
		(layer "In12.Cu")
	)
	(gr_line
		(start 90.880184 -50.758598)
		(end 91.01582 -52.91328)
		(stroke
			(width 0.1016)
			(type default)
		)
		(layer "In12.Cu")
	)
	(gr_line
		(start 103.095806 -37.856414)
		(end 104.129332 -39.752016)
		(stroke
			(width 0.1016)
			(type default)
		)
		(layer "In12.Cu")
	)
	(gr_line
		(start 103.777542 -37.484304)
		(end 103.095806 -37.856414)
		(stroke
			(width 0.1016)
			(type default)
		)
		(layer "In12.Cu")
	)
	(gr_line
		(start 103.77805 -37.48405)
		(end 104.811576 -39.379652)
		(stroke
			(width 0.1016)
			(type default)
		)
		(layer "In12.Cu")
	)
	(gr_line
		(start 105.10393 -37.411152)
		(end 106.137456 -39.306754)
		(stroke
			(width 0.1016)
			(type default)
		)
		(layer "In12.Cu")
	)
	(gr_line
		(start 105.785666 -37.039042)
		(end 105.10393 -37.411152)
		(stroke
			(width 0.1016)
			(type default)
		)
		(layer "In12.Cu")
	)
	(gr_line
		(start 105.786174 -37.038788)
		(end 106.8197 -38.93439)
		(stroke
			(width 0.1016)
			(type default)
		)
		(layer "In12.Cu")
	)
	(gr_line
		(start 106.719624 -45.584364)
		(end 106.762296 -47.742856)
		(stroke
			(width 0.1016)
			(type default)
		)
		(layer "In12.Cu")
	)
	(gr_line
		(start 107.496356 -45.56887)
		(end 106.719624 -45.584364)
		(stroke
			(width 0.1016)
			(type default)
		)
		(layer "In12.Cu")
	)
	(gr_line
		(start 107.496864 -45.568616)
		(end 107.539282 -47.727362)
		(stroke
			(width 0.1016)
			(type default)
		)
		(layer "In12.Cu")
	)
	(gr_line
		(start 108.639102 -45.629322)
		(end 108.681774 -47.787814)
		(stroke
			(width 0.1016)
			(type default)
		)
		(layer "In12.Cu")
	)
	(gr_line
		(start 109.415834 -45.613828)
		(end 108.639102 -45.629322)
		(stroke
			(width 0.1016)
			(type default)
		)
		(layer "In12.Cu")
	)
	(gr_line
		(start 109.416342 -45.613574)
		(end 109.45876 -47.77232)
		(stroke
			(width 0.1016)
			(type default)
		)
		(layer "In12.Cu")
	)
	(gr_line
		(start 147.0279 -45.074586)
		(end 148.487384 -46.665642)
		(stroke
			(width 0.1016)
			(type default)
		)
		(layer "In12.Cu")
	)
	(gr_line
		(start 147.600162 -44.549314)
		(end 147.0279 -45.074586)
		(stroke
			(width 0.1016)
			(type default)
		)
		(layer "In12.Cu")
	)
	(gr_line
		(start 147.60067 -44.54906)
		(end 149.0599 -46.140116)
		(stroke
			(width 0.1016)
			(type default)
		)
		(layer "In12.Cu")
	)
	(gr_line
		(start 148.788628 -44.205398)
		(end 149.361398 -43.679872)
		(stroke
			(width 0.1016)
			(type default)
		)
		(layer "In12.Cu")
	)
	(gr_line
		(start 148.788628 -44.205398)
		(end 150.248112 -45.796454)
		(stroke
			(width 0.1016)
			(type default)
		)
		(layer "In12.Cu")
	)
	(gr_line
		(start 149.361398 -43.679872)
		(end 150.820628 -45.270928)
		(stroke
			(width 0.1016)
			(type default)
		)
		(layer "In12.Cu")
	)
	(gr_line
		(start 150.248112 -45.796454)
		(end 148.788628 -44.205398)
		(stroke
			(width 0.1016)
			(type default)
		)
		(layer "In12.Cu")
	)
	(gr_line
		(start 152.34031 -51.197764)
		(end 152.475692 -53.352446)
		(stroke
			(width 0.1016)
			(type default)
		)
		(layer "In12.Cu")
	)
	(gr_line
		(start 153.115518 -51.148742)
		(end 152.34031 -51.197764)
		(stroke
			(width 0.1016)
			(type default)
		)
		(layer "In12.Cu")
	)
	(gr_line
		(start 153.115518 -51.148742)
		(end 153.2509 -53.303424)
		(stroke
			(width 0.1016)
			(type default)
		)
		(layer "In12.Cu")
	)
	(gr_line
		(start 154.205432 -50.819304)
		(end 154.340814 -52.973986)
		(stroke
			(width 0.1016)
			(type default)
		)
		(layer "In12.Cu")
	)
	(gr_line
		(start 154.98064 -50.770282)
		(end 154.205432 -50.819304)
		(stroke
			(width 0.1016)
			(type default)
		)
		(layer "In12.Cu")
	)
	(gr_line
		(start 154.98064 -50.770282)
		(end 155.116022 -52.924964)
		(stroke
			(width 0.1016)
			(type default)
		)
		(layer "In12.Cu")
	)
	(gr_circle
		(center 159.599884 -316.799722)
		(end 159.853884 -316.799722)
		(stroke
			(width 0.1016)
			(type default)
		)
		(fill no)
		(layer "In12.Cu")
	)
	(gr_circle
		(center 159.599884 -315.849762)
		(end 159.853884 -315.849762)
		(stroke
			(width 0.1016)
			(type default)
		)
		(fill no)
		(layer "In12.Cu")
	)
	(gr_circle
		(center 159.599884 -312.049922)
		(end 159.853884 -312.049922)
		(stroke
			(width 0.1016)
			(type default)
		)
		(fill no)
		(layer "In12.Cu")
	)
	(gr_circle
		(center 159.599884 -311.099962)
		(end 159.853884 -311.099962)
		(stroke
			(width 0.1016)
			(type default)
		)
		(fill no)
		(layer "In12.Cu")
	)
	(gr_circle
		(center 160.549844 -318.699896)
		(end 160.803844 -318.699896)
		(stroke
			(width 0.1016)
			(type default)
		)
		(fill no)
		(layer "In12.Cu")
	)
	(gr_circle
		(center 160.549844 -317.749936)
		(end 160.803844 -317.749936)
		(stroke
			(width 0.1016)
			(type default)
		)
		(fill no)
		(layer "In12.Cu")
	)
	(gr_circle
		(center 160.549844 -313.949842)
		(end 160.803844 -313.949842)
		(stroke
			(width 0.1016)
			(type default)
		)
		(fill no)
		(layer "In12.Cu")
	)
	(gr_circle
		(center 160.549844 -312.999882)
		(end 160.803844 -312.999882)
		(stroke
			(width 0.1016)
			(type default)
		)
		(fill no)
		(layer "In12.Cu")
	)
	(gr_circle
		(center 161.500058 -316.799722)
		(end 161.754058 -316.799722)
		(stroke
			(width 0.1016)
			(type default)
		)
		(fill no)
		(layer "In12.Cu")
	)
	(gr_circle
		(center 161.500058 -315.849762)
		(end 161.754058 -315.849762)
		(stroke
			(width 0.1016)
			(type default)
		)
		(fill no)
		(layer "In12.Cu")
	)
	(gr_circle
		(center 161.500058 -312.049922)
		(end 161.754058 -312.049922)
		(stroke
			(width 0.1016)
			(type default)
		)
		(fill no)
		(layer "In12.Cu")
	)
	(gr_circle
		(center 161.500058 -311.099962)
		(end 161.754058 -311.099962)
		(stroke
			(width 0.1016)
			(type default)
		)
		(fill no)
		(layer "In12.Cu")
	)
	(gr_circle
		(center 162.450018 -318.699896)
		(end 162.704018 -318.699896)
		(stroke
			(width 0.1016)
			(type default)
		)
		(fill no)
		(layer "In12.Cu")
	)
	(gr_circle
		(center 162.450018 -317.749936)
		(end 162.704018 -317.749936)
		(stroke
			(width 0.1016)
			(type default)
		)
		(fill no)
		(layer "In12.Cu")
	)
	(gr_circle
		(center 162.450018 -313.949842)
		(end 162.704018 -313.949842)
		(stroke
			(width 0.1016)
			(type default)
		)
		(fill no)
		(layer "In12.Cu")
	)
	(gr_circle
		(center 162.450018 -312.999882)
		(end 162.704018 -312.999882)
		(stroke
			(width 0.1016)
			(type default)
		)
		(fill no)
		(layer "In12.Cu")
	)
	(gr_circle
		(center 163.399978 -316.799722)
		(end 163.653978 -316.799722)
		(stroke
			(width 0.1016)
			(type default)
		)
		(fill no)
		(layer "In12.Cu")
	)
	(gr_circle
		(center 163.399978 -315.849762)
		(end 163.653978 -315.849762)
		(stroke
			(width 0.1016)
			(type default)
		)
		(fill no)
		(layer "In12.Cu")
	)
	(gr_circle
		(center 163.399978 -312.049922)
		(end 163.653978 -312.049922)
		(stroke
			(width 0.1016)
			(type default)
		)
		(fill no)
		(layer "In12.Cu")
	)
	(gr_circle
		(center 163.399978 -311.099962)
		(end 163.653978 -311.099962)
		(stroke
			(width 0.1016)
			(type default)
		)
		(fill no)
		(layer "In12.Cu")
	)
	(gr_circle
		(center 164.349938 -318.699896)
		(end 164.603938 -318.699896)
		(stroke
			(width 0.1016)
			(type default)
		)
		(fill no)
		(layer "In12.Cu")
	)
	(gr_circle
		(center 164.349938 -317.749936)
		(end 164.603938 -317.749936)
		(stroke
			(width 0.1016)
			(type default)
		)
		(fill no)
		(layer "In12.Cu")
	)
	(gr_circle
		(center 164.349938 -313.949842)
		(end 164.603938 -313.949842)
		(stroke
			(width 0.1016)
			(type default)
		)
		(fill no)
		(layer "In12.Cu")
	)
	(gr_circle
		(center 164.349938 -312.999882)
		(end 164.603938 -312.999882)
		(stroke
			(width 0.1016)
			(type default)
		)
		(fill no)
		(layer "In12.Cu")
	)
	(gr_circle
		(center 165.299898 -316.799722)
		(end 165.553898 -316.799722)
		(stroke
			(width 0.1016)
			(type default)
		)
		(fill no)
		(layer "In12.Cu")
	)
	(gr_circle
		(center 165.299898 -315.849762)
		(end 165.553898 -315.849762)
		(stroke
			(width 0.1016)
			(type default)
		)
		(fill no)
		(layer "In12.Cu")
	)
	(gr_circle
		(center 165.299898 -312.049922)
		(end 165.553898 -312.049922)
		(stroke
			(width 0.1016)
			(type default)
		)
		(fill no)
		(layer "In12.Cu")
	)
	(gr_circle
		(center 165.299898 -311.099962)
		(end 165.553898 -311.099962)
		(stroke
			(width 0.1016)
			(type default)
		)
		(fill no)
		(layer "In12.Cu")
	)
	(gr_circle
		(center 166.249858 -318.699896)
		(end 166.503858 -318.699896)
		(stroke
			(width 0.1016)
			(type default)
		)
		(fill no)
		(layer "In12.Cu")
	)
	(gr_circle
		(center 166.249858 -317.749936)
		(end 166.503858 -317.749936)
		(stroke
			(width 0.1016)
			(type default)
		)
		(fill no)
		(layer "In12.Cu")
	)
	(gr_circle
		(center 166.249858 -313.949842)
		(end 166.503858 -313.949842)
		(stroke
			(width 0.1016)
			(type default)
		)
		(fill no)
		(layer "In12.Cu")
	)
	(gr_circle
		(center 166.249858 -312.999882)
		(end 166.503858 -312.999882)
		(stroke
			(width 0.1016)
			(type default)
		)
		(fill no)
		(layer "In12.Cu")
	)
	(gr_line
		(start 172.852588 -44.884086)
		(end 174.312072 -46.475142)
		(stroke
			(width 0.1016)
			(type default)
		)
		(layer "In12.Cu")
	)
	(gr_line
		(start 173.42485 -44.358814)
		(end 172.852588 -44.884086)
		(stroke
			(width 0.1016)
			(type default)
		)
		(layer "In12.Cu")
	)
	(gr_line
		(start 173.425358 -44.35856)
		(end 174.884588 -45.949616)
		(stroke
			(width 0.1016)
			(type default)
		)
		(layer "In12.Cu")
	)
	(gr_line
		(start 175.174656 -44.626276)
		(end 176.63414 -46.217332)
		(stroke
			(width 0.1016)
			(type default)
		)
		(layer "In12.Cu")
	)
	(gr_line
		(start 175.746918 -44.101004)
		(end 175.174656 -44.626276)
		(stroke
			(width 0.1016)
			(type default)
		)
		(layer "In12.Cu")
	)
	(gr_line
		(start 175.747426 -44.10075)
		(end 177.206656 -45.691806)
		(stroke
			(width 0.1016)
			(type default)
		)
		(layer "In12.Cu")
	)
	(gr_line
		(start 178.342798 -51.235356)
		(end 178.47818 -53.390038)
		(stroke
			(width 0.1016)
			(type default)
		)
		(layer "In12.Cu")
	)
	(gr_line
		(start 179.118006 -51.186334)
		(end 178.342798 -51.235356)
		(stroke
			(width 0.1016)
			(type default)
		)
		(layer "In12.Cu")
	)
	(gr_line
		(start 179.118006 -51.186334)
		(end 179.253388 -53.341016)
		(stroke
			(width 0.1016)
			(type default)
		)
		(layer "In12.Cu")
	)
	(gr_line
		(start 180.20792 -50.856896)
		(end 180.343302 -53.011578)
		(stroke
			(width 0.1016)
			(type default)
		)
		(layer "In12.Cu")
	)
	(gr_line
		(start 180.983128 -50.807874)
		(end 180.20792 -50.856896)
		(stroke
			(width 0.1016)
			(type default)
		)
		(layer "In12.Cu")
	)
	(gr_line
		(start 180.983128 -50.807874)
		(end 181.11851 -52.962556)
		(stroke
			(width 0.1016)
			(type default)
		)
		(layer "In12.Cu")
	)
	(gr_circle
		(center 182.39994 -316.799722)
		(end 182.65394 -316.799722)
		(stroke
			(width 0.1016)
			(type default)
		)
		(fill no)
		(layer "In12.Cu")
	)
	(gr_circle
		(center 182.39994 -315.849762)
		(end 182.65394 -315.849762)
		(stroke
			(width 0.1016)
			(type default)
		)
		(fill no)
		(layer "In12.Cu")
	)
	(gr_circle
		(center 182.39994 -312.049922)
		(end 182.65394 -312.049922)
		(stroke
			(width 0.1016)
			(type default)
		)
		(fill no)
		(layer "In12.Cu")
	)
	(gr_circle
		(center 182.39994 -311.099962)
		(end 182.65394 -311.099962)
		(stroke
			(width 0.1016)
			(type default)
		)
		(fill no)
		(layer "In12.Cu")
	)
	(gr_circle
		(center 183.3499 -318.699896)
		(end 183.6039 -318.699896)
		(stroke
			(width 0.1016)
			(type default)
		)
		(fill no)
		(layer "In12.Cu")
	)
	(gr_circle
		(center 183.3499 -317.749936)
		(end 183.6039 -317.749936)
		(stroke
			(width 0.1016)
			(type default)
		)
		(fill no)
		(layer "In12.Cu")
	)
	(gr_circle
		(center 183.3499 -313.949842)
		(end 183.6039 -313.949842)
		(stroke
			(width 0.1016)
			(type default)
		)
		(fill no)
		(layer "In12.Cu")
	)
	(gr_circle
		(center 183.3499 -312.999882)
		(end 183.6039 -312.999882)
		(stroke
			(width 0.1016)
			(type default)
		)
		(fill no)
		(layer "In12.Cu")
	)
	(gr_circle
		(center 184.29986 -316.799722)
		(end 184.55386 -316.799722)
		(stroke
			(width 0.1016)
			(type default)
		)
		(fill no)
		(layer "In12.Cu")
	)
	(gr_circle
		(center 184.29986 -315.849762)
		(end 184.55386 -315.849762)
		(stroke
			(width 0.1016)
			(type default)
		)
		(fill no)
		(layer "In12.Cu")
	)
	(gr_circle
		(center 184.29986 -312.049922)
		(end 184.55386 -312.049922)
		(stroke
			(width 0.1016)
			(type default)
		)
		(fill no)
		(layer "In12.Cu")
	)
	(gr_circle
		(center 184.29986 -311.099962)
		(end 184.55386 -311.099962)
		(stroke
			(width 0.1016)
			(type default)
		)
		(fill no)
		(layer "In12.Cu")
	)
	(gr_circle
		(center 185.250074 -318.699896)
		(end 185.504074 -318.699896)
		(stroke
			(width 0.1016)
			(type default)
		)
		(fill no)
		(layer "In12.Cu")
	)
	(gr_circle
		(center 185.250074 -317.749936)
		(end 185.504074 -317.749936)
		(stroke
			(width 0.1016)
			(type default)
		)
		(fill no)
		(layer "In12.Cu")
	)
	(gr_circle
		(center 185.250074 -313.949842)
		(end 185.504074 -313.949842)
		(stroke
			(width 0.1016)
			(type default)
		)
		(fill no)
		(layer "In12.Cu")
	)
	(gr_circle
		(center 185.250074 -312.999882)
		(end 185.504074 -312.999882)
		(stroke
			(width 0.1016)
			(type default)
		)
		(fill no)
		(layer "In12.Cu")
	)
	(gr_circle
		(center 186.200034 -316.799722)
		(end 186.454034 -316.799722)
		(stroke
			(width 0.1016)
			(type default)
		)
		(fill no)
		(layer "In12.Cu")
	)
	(gr_circle
		(center 186.200034 -315.849762)
		(end 186.454034 -315.849762)
		(stroke
			(width 0.1016)
			(type default)
		)
		(fill no)
		(layer "In12.Cu")
	)
	(gr_circle
		(center 186.200034 -312.049922)
		(end 186.454034 -312.049922)
		(stroke
			(width 0.1016)
			(type default)
		)
		(fill no)
		(layer "In12.Cu")
	)
	(gr_circle
		(center 186.200034 -311.099962)
		(end 186.454034 -311.099962)
		(stroke
			(width 0.1016)
			(type default)
		)
		(fill no)
		(layer "In12.Cu")
	)
	(gr_circle
		(center 187.149994 -318.699896)
		(end 187.403994 -318.699896)
		(stroke
			(width 0.1016)
			(type default)
		)
		(fill no)
		(layer "In12.Cu")
	)
	(gr_circle
		(center 187.149994 -317.749936)
		(end 187.403994 -317.749936)
		(stroke
			(width 0.1016)
			(type default)
		)
		(fill no)
		(layer "In12.Cu")
	)
	(gr_circle
		(center 187.149994 -313.949842)
		(end 187.403994 -313.949842)
		(stroke
			(width 0.1016)
			(type default)
		)
		(fill no)
		(layer "In12.Cu")
	)
	(gr_circle
		(center 187.149994 -312.999882)
		(end 187.403994 -312.999882)
		(stroke
			(width 0.1016)
			(type default)
		)
		(fill no)
		(layer "In12.Cu")
	)
	(gr_circle
		(center 188.099954 -316.799722)
		(end 188.353954 -316.799722)
		(stroke
			(width 0.1016)
			(type default)
		)
		(fill no)
		(layer "In12.Cu")
	)
	(gr_circle
		(center 188.099954 -315.849762)
		(end 188.353954 -315.849762)
		(stroke
			(width 0.1016)
			(type default)
		)
		(fill no)
		(layer "In12.Cu")
	)
	(gr_circle
		(center 188.099954 -312.049922)
		(end 188.353954 -312.049922)
		(stroke
			(width 0.1016)
			(type default)
		)
		(fill no)
		(layer "In12.Cu")
	)
	(gr_circle
		(center 188.099954 -311.099962)
		(end 188.353954 -311.099962)
		(stroke
			(width 0.1016)
			(type default)
		)
		(fill no)
		(layer "In12.Cu")
	)
	(gr_circle
		(center 189.049914 -318.699896)
		(end 189.303914 -318.699896)
		(stroke
			(width 0.1016)
			(type default)
		)
		(fill no)
		(layer "In12.Cu")
	)
	(gr_circle
		(center 189.049914 -317.749936)
		(end 189.303914 -317.749936)
		(stroke
			(width 0.1016)
			(type default)
		)
		(fill no)
		(layer "In12.Cu")
	)
	(gr_circle
		(center 189.049914 -313.949842)
		(end 189.303914 -313.949842)
		(stroke
			(width 0.1016)
			(type default)
		)
		(fill no)
		(layer "In12.Cu")
	)
	(gr_circle
		(center 189.049914 -312.999882)
		(end 189.303914 -312.999882)
		(stroke
			(width 0.1016)
			(type default)
		)
		(fill no)
		(layer "In12.Cu")
	)
	(gr_line
		(start 199.038464 -45.086524)
		(end 200.497948 -46.67758)
		(stroke
			(width 0.1016)
			(type default)
		)
		(layer "In12.Cu")
	)
	(gr_line
		(start 199.610726 -44.561252)
		(end 199.038464 -45.086524)
		(stroke
			(width 0.1016)
			(type default)
		)
		(layer "In12.Cu")
	)
	(gr_line
		(start 199.611234 -44.560998)
		(end 201.070464 -46.152054)
		(stroke
			(width 0.1016)
			(type default)
		)
		(layer "In12.Cu")
	)
	(gr_line
		(start 200.819004 -44.22648)
		(end 202.278488 -45.817536)
		(stroke
			(width 0.1016)
			(type default)
		)
		(layer "In12.Cu")
	)
	(gr_line
		(start 201.391266 -43.701208)
		(end 200.819004 -44.22648)
		(stroke
			(width 0.1016)
			(type default)
		)
		(layer "In12.Cu")
	)
	(gr_line
		(start 201.391774 -43.700954)
		(end 202.851004 -45.29201)
		(stroke
			(width 0.1016)
			(type default)
		)
		(layer "In12.Cu")
	)
	(gr_line
		(start 204.353414 -51.406298)
		(end 204.48905 -53.56098)
		(stroke
			(width 0.1016)
			(type default)
		)
		(layer "In12.Cu")
	)
	(gr_line
		(start 205.128622 -51.357276)
		(end 204.353414 -51.406298)
		(stroke
			(width 0.1016)
			(type default)
		)
		(layer "In12.Cu")
	)
	(gr_line
		(start 205.12913 -51.357276)
		(end 205.264766 -53.511958)
		(stroke
			(width 0.1016)
			(type default)
		)
		(layer "In12.Cu")
	)
	(gr_line
		(start 206.204566 -50.80762)
		(end 206.340202 -52.962302)
		(stroke
			(width 0.1016)
			(type default)
		)
		(layer "In12.Cu")
	)
	(gr_line
		(start 206.979774 -50.758598)
		(end 206.204566 -50.80762)
		(stroke
			(width 0.1016)
			(type default)
		)
		(layer "In12.Cu")
	)
	(gr_line
		(start 206.980282 -50.758598)
		(end 207.115918 -52.91328)
		(stroke
			(width 0.1016)
			(type default)
		)
		(layer "In12.Cu")
	)
	(gr_line
		(start 219.195904 -37.856414)
		(end 220.22943 -39.752016)
		(stroke
			(width 0.1016)
			(type default)
		)
		(layer "In12.Cu")
	)
	(gr_line
		(start 219.87764 -37.484304)
		(end 219.195904 -37.856414)
		(stroke
			(width 0.1016)
			(type default)
		)
		(layer "In12.Cu")
	)
	(gr_line
		(start 219.878148 -37.48405)
		(end 220.911674 -39.379652)
		(stroke
			(width 0.1016)
			(type default)
		)
		(layer "In12.Cu")
	)
	(gr_line
		(start 221.204028 -37.411152)
		(end 222.237554 -39.306754)
		(stroke
			(width 0.1016)
			(type default)
		)
		(layer "In12.Cu")
	)
	(gr_line
		(start 221.885764 -37.039042)
		(end 221.204028 -37.411152)
		(stroke
			(width 0.1016)
			(type default)
		)
		(layer "In12.Cu")
	)
	(gr_line
		(start 221.886272 -37.038788)
		(end 222.919798 -38.93439)
		(stroke
			(width 0.1016)
			(type default)
		)
		(layer "In12.Cu")
	)
	(gr_line
		(start 222.819722 -45.584364)
		(end 222.862394 -47.742856)
		(stroke
			(width 0.1016)
			(type default)
		)
		(layer "In12.Cu")
	)
	(gr_line
		(start 223.596454 -45.56887)
		(end 222.819722 -45.584364)
		(stroke
			(width 0.1016)
			(type default)
		)
		(layer "In12.Cu")
	)
	(gr_line
		(start 223.596962 -45.568616)
		(end 223.63938 -47.727362)
		(stroke
			(width 0.1016)
			(type default)
		)
		(layer "In12.Cu")
	)
	(gr_line
		(start 224.7392 -45.629322)
		(end 224.781872 -47.787814)
		(stroke
			(width 0.1016)
			(type default)
		)
		(layer "In12.Cu")
	)
	(gr_line
		(start 225.515932 -45.613828)
		(end 224.7392 -45.629322)
		(stroke
			(width 0.1016)
			(type default)
		)
		(layer "In12.Cu")
	)
	(gr_line
		(start 225.51644 -45.613574)
		(end 225.558858 -47.77232)
		(stroke
			(width 0.1016)
			(type default)
		)
		(layer "In12.Cu")
	)
	(gr_line
		(start 263.127744 -45.074586)
		(end 264.587228 -46.665642)
		(stroke
			(width 0.1016)
			(type default)
		)
		(layer "In12.Cu")
	)
	(gr_line
		(start 263.700006 -44.549314)
		(end 263.127744 -45.074586)
		(stroke
			(width 0.1016)
			(type default)
		)
		(layer "In12.Cu")
	)
	(gr_line
		(start 263.700514 -44.54906)
		(end 265.159744 -46.140116)
		(stroke
			(width 0.1016)
			(type default)
		)
		(layer "In12.Cu")
	)
	(gr_line
		(start 264.888472 -44.205398)
		(end 265.461242 -43.679872)
		(stroke
			(width 0.1016)
			(type default)
		)
		(layer "In12.Cu")
	)
	(gr_line
		(start 264.888472 -44.205398)
		(end 266.347956 -45.796454)
		(stroke
			(width 0.1016)
			(type default)
		)
		(layer "In12.Cu")
	)
	(gr_line
		(start 265.461242 -43.679872)
		(end 266.920472 -45.270928)
		(stroke
			(width 0.1016)
			(type default)
		)
		(layer "In12.Cu")
	)
	(gr_line
		(start 266.347956 -45.796454)
		(end 264.888472 -44.205398)
		(stroke
			(width 0.1016)
			(type default)
		)
		(layer "In12.Cu")
	)
	(gr_line
		(start 268.440154 -51.197764)
		(end 268.575536 -53.352446)
		(stroke
			(width 0.1016)
			(type default)
		)
		(layer "In12.Cu")
	)
	(gr_line
		(start 269.215362 -51.148742)
		(end 268.440154 -51.197764)
		(stroke
			(width 0.1016)
			(type default)
		)
		(layer "In12.Cu")
	)
	(gr_line
		(start 269.215362 -51.148742)
		(end 269.350744 -53.303424)
		(stroke
			(width 0.1016)
			(type default)
		)
		(layer "In12.Cu")
	)
	(gr_line
		(start 270.305276 -50.819304)
		(end 270.440658 -52.973986)
		(stroke
			(width 0.1016)
			(type default)
		)
		(layer "In12.Cu")
	)
	(gr_line
		(start 271.080484 -50.770282)
		(end 270.305276 -50.819304)
		(stroke
			(width 0.1016)
			(type default)
		)
		(layer "In12.Cu")
	)
	(gr_line
		(start 271.080484 -50.770282)
		(end 271.215866 -52.924964)
		(stroke
			(width 0.1016)
			(type default)
		)
		(layer "In12.Cu")
	)
	(gr_circle
		(center 275.699728 -312.049922)
		(end 275.953728 -312.049922)
		(stroke
			(width 0.1016)
			(type default)
		)
		(fill no)
		(layer "In12.Cu")
	)
	(gr_circle
		(center 275.699728 -311.099962)
		(end 275.953728 -311.099962)
		(stroke
			(width 0.1016)
			(type default)
		)
		(fill no)
		(layer "In12.Cu")
	)
	(gr_circle
		(center 276.649688 -313.949842)
		(end 276.903688 -313.949842)
		(stroke
			(width 0.1016)
			(type default)
		)
		(fill no)
		(layer "In12.Cu")
	)
	(gr_circle
		(center 276.649688 -312.999882)
		(end 276.903688 -312.999882)
		(stroke
			(width 0.1016)
			(type default)
		)
		(fill no)
		(layer "In12.Cu")
	)
	(gr_circle
		(center 277.599902 -312.049922)
		(end 277.853902 -312.049922)
		(stroke
			(width 0.1016)
			(type default)
		)
		(fill no)
		(layer "In12.Cu")
	)
	(gr_circle
		(center 277.599902 -311.099962)
		(end 277.853902 -311.099962)
		(stroke
			(width 0.1016)
			(type default)
		)
		(fill no)
		(layer "In12.Cu")
	)
	(gr_circle
		(center 278.549862 -313.949842)
		(end 278.803862 -313.949842)
		(stroke
			(width 0.1016)
			(type default)
		)
		(fill no)
		(layer "In12.Cu")
	)
	(gr_circle
		(center 278.549862 -312.999882)
		(end 278.803862 -312.999882)
		(stroke
			(width 0.1016)
			(type default)
		)
		(fill no)
		(layer "In12.Cu")
	)
	(gr_circle
		(center 279.499822 -312.049922)
		(end 279.753822 -312.049922)
		(stroke
			(width 0.1016)
			(type default)
		)
		(fill no)
		(layer "In12.Cu")
	)
	(gr_circle
		(center 279.499822 -311.099962)
		(end 279.753822 -311.099962)
		(stroke
			(width 0.1016)
			(type default)
		)
		(fill no)
		(layer "In12.Cu")
	)
	(gr_circle
		(center 280.449782 -313.949842)
		(end 280.703782 -313.949842)
		(stroke
			(width 0.1016)
			(type default)
		)
		(fill no)
		(layer "In12.Cu")
	)
	(gr_circle
		(center 280.449782 -312.999882)
		(end 280.703782 -312.999882)
		(stroke
			(width 0.1016)
			(type default)
		)
		(fill no)
		(layer "In12.Cu")
	)
	(gr_circle
		(center 281.399742 -312.049922)
		(end 281.653742 -312.049922)
		(stroke
			(width 0.1016)
			(type default)
		)
		(fill no)
		(layer "In12.Cu")
	)
	(gr_circle
		(center 281.399742 -311.099962)
		(end 281.653742 -311.099962)
		(stroke
			(width 0.1016)
			(type default)
		)
		(fill no)
		(layer "In12.Cu")
	)
	(gr_circle
		(center 282.349702 -313.949842)
		(end 282.603702 -313.949842)
		(stroke
			(width 0.1016)
			(type default)
		)
		(fill no)
		(layer "In12.Cu")
	)
	(gr_circle
		(center 282.349702 -312.999882)
		(end 282.603702 -312.999882)
		(stroke
			(width 0.1016)
			(type default)
		)
		(fill no)
		(layer "In12.Cu")
	)
	(gr_circle
		(center 283.299916 -312.049922)
		(end 283.553916 -312.049922)
		(stroke
			(width 0.1016)
			(type default)
		)
		(fill no)
		(layer "In12.Cu")
	)
	(gr_circle
		(center 283.299916 -311.099962)
		(end 283.553916 -311.099962)
		(stroke
			(width 0.1016)
			(type default)
		)
		(fill no)
		(layer "In12.Cu")
	)
	(gr_circle
		(center 284.249876 -313.949842)
		(end 284.503876 -313.949842)
		(stroke
			(width 0.1016)
			(type default)
		)
		(fill no)
		(layer "In12.Cu")
	)
	(gr_circle
		(center 284.249876 -312.999882)
		(end 284.503876 -312.999882)
		(stroke
			(width 0.1016)
			(type default)
		)
		(fill no)
		(layer "In12.Cu")
	)
	(gr_circle
		(center 285.199836 -312.049922)
		(end 285.453836 -312.049922)
		(stroke
			(width 0.1016)
			(type default)
		)
		(fill no)
		(layer "In12.Cu")
	)
	(gr_circle
		(center 285.199836 -311.099962)
		(end 285.453836 -311.099962)
		(stroke
			(width 0.1016)
			(type default)
		)
		(fill no)
		(layer "In12.Cu")
	)
	(gr_circle
		(center 286.149796 -313.949842)
		(end 286.403796 -313.949842)
		(stroke
			(width 0.1016)
			(type default)
		)
		(fill no)
		(layer "In12.Cu")
	)
	(gr_circle
		(center 286.149796 -312.999882)
		(end 286.403796 -312.999882)
		(stroke
			(width 0.1016)
			(type default)
		)
		(fill no)
		(layer "In12.Cu")
	)
	(gr_circle
		(center 287.099756 -312.049922)
		(end 287.353756 -312.049922)
		(stroke
			(width 0.1016)
			(type default)
		)
		(fill no)
		(layer "In12.Cu")
	)
	(gr_circle
		(center 287.099756 -311.099962)
		(end 287.353756 -311.099962)
		(stroke
			(width 0.1016)
			(type default)
		)
		(fill no)
		(layer "In12.Cu")
	)
	(gr_circle
		(center 288.049716 -313.949842)
		(end 288.303716 -313.949842)
		(stroke
			(width 0.1016)
			(type default)
		)
		(fill no)
		(layer "In12.Cu")
	)
	(gr_circle
		(center 288.049716 -312.999882)
		(end 288.303716 -312.999882)
		(stroke
			(width 0.1016)
			(type default)
		)
		(fill no)
		(layer "In12.Cu")
	)
	(gr_line
		(start 288.952432 -44.884086)
		(end 290.411916 -46.475142)
		(stroke
			(width 0.1016)
			(type default)
		)
		(layer "In12.Cu")
	)
	(gr_circle
		(center 288.99993 -312.049922)
		(end 289.25393 -312.049922)
		(stroke
			(width 0.1016)
			(type default)
		)
		(fill no)
		(layer "In12.Cu")
	)
	(gr_circle
		(center 288.99993 -311.099962)
		(end 289.25393 -311.099962)
		(stroke
			(width 0.1016)
			(type default)
		)
		(fill no)
		(layer "In12.Cu")
	)
	(gr_line
		(start 289.524694 -44.358814)
		(end 288.952432 -44.884086)
		(stroke
			(width 0.1016)
			(type default)
		)
		(layer "In12.Cu")
	)
	(gr_line
		(start 289.525202 -44.35856)
		(end 290.984432 -45.949616)
		(stroke
			(width 0.1016)
			(type default)
		)
		(layer "In12.Cu")
	)
	(gr_circle
		(center 289.94989 -313.949842)
		(end 290.20389 -313.949842)
		(stroke
			(width 0.1016)
			(type default)
		)
		(fill no)
		(layer "In12.Cu")
	)
	(gr_circle
		(center 289.94989 -312.999882)
		(end 290.20389 -312.999882)
		(stroke
			(width 0.1016)
			(type default)
		)
		(fill no)
		(layer "In12.Cu")
	)
	(gr_line
		(start 291.2745 -44.626276)
		(end 292.733984 -46.217332)
		(stroke
			(width 0.1016)
			(type default)
		)
		(layer "In12.Cu")
	)
	(gr_line
		(start 291.846762 -44.101004)
		(end 291.2745 -44.626276)
		(stroke
			(width 0.1016)
			(type default)
		)
		(layer "In12.Cu")
	)
	(gr_line
		(start 291.84727 -44.10075)
		(end 293.3065 -45.691806)
		(stroke
			(width 0.1016)
			(type default)
		)
		(layer "In12.Cu")
	)
	(gr_line
		(start 294.442642 -51.235356)
		(end 294.578024 -53.390038)
		(stroke
			(width 0.1016)
			(type default)
		)
		(layer "In12.Cu")
	)
	(gr_line
		(start 295.21785 -51.186334)
		(end 294.442642 -51.235356)
		(stroke
			(width 0.1016)
			(type default)
		)
		(layer "In12.Cu")
	)
	(gr_line
		(start 295.21785 -51.186334)
		(end 295.353232 -53.341016)
		(stroke
			(width 0.1016)
			(type default)
		)
		(layer "In12.Cu")
	)
	(gr_line
		(start 296.307764 -50.856896)
		(end 296.443146 -53.011578)
		(stroke
			(width 0.1016)
			(type default)
		)
		(layer "In12.Cu")
	)
	(gr_line
		(start 297.082972 -50.807874)
		(end 296.307764 -50.856896)
		(stroke
			(width 0.1016)
			(type default)
		)
		(layer "In12.Cu")
	)
	(gr_line
		(start 297.082972 -50.807874)
		(end 297.218354 -52.962556)
		(stroke
			(width 0.1016)
			(type default)
		)
		(layer "In12.Cu")
	)
	(gr_circle
		(center 306.099718 -316.799722)
		(end 306.353718 -316.799722)
		(stroke
			(width 0.1016)
			(type default)
		)
		(fill no)
		(layer "In12.Cu")
	)
	(gr_circle
		(center 306.099718 -315.849762)
		(end 306.353718 -315.849762)
		(stroke
			(width 0.1016)
			(type default)
		)
		(fill no)
		(layer "In12.Cu")
	)
	(gr_circle
		(center 307.049932 -318.699896)
		(end 307.303932 -318.699896)
		(stroke
			(width 0.1016)
			(type default)
		)
		(fill no)
		(layer "In12.Cu")
	)
	(gr_circle
		(center 307.049932 -317.749936)
		(end 307.303932 -317.749936)
		(stroke
			(width 0.1016)
			(type default)
		)
		(fill no)
		(layer "In12.Cu")
	)
	(gr_circle
		(center 307.999892 -316.799722)
		(end 308.253892 -316.799722)
		(stroke
			(width 0.1016)
			(type default)
		)
		(fill no)
		(layer "In12.Cu")
	)
	(gr_circle
		(center 307.999892 -315.849762)
		(end 308.253892 -315.849762)
		(stroke
			(width 0.1016)
			(type default)
		)
		(fill no)
		(layer "In12.Cu")
	)
	(gr_circle
		(center 308.949852 -318.699896)
		(end 309.203852 -318.699896)
		(stroke
			(width 0.1016)
			(type default)
		)
		(fill no)
		(layer "In12.Cu")
	)
	(gr_circle
		(center 308.949852 -317.749936)
		(end 309.203852 -317.749936)
		(stroke
			(width 0.1016)
			(type default)
		)
		(fill no)
		(layer "In12.Cu")
	)
	(gr_circle
		(center 309.899812 -316.799722)
		(end 310.153812 -316.799722)
		(stroke
			(width 0.1016)
			(type default)
		)
		(fill no)
		(layer "In12.Cu")
	)
	(gr_circle
		(center 309.899812 -315.849762)
		(end 310.153812 -315.849762)
		(stroke
			(width 0.1016)
			(type default)
		)
		(fill no)
		(layer "In12.Cu")
	)
	(gr_circle
		(center 310.849772 -318.699896)
		(end 311.103772 -318.699896)
		(stroke
			(width 0.1016)
			(type default)
		)
		(fill no)
		(layer "In12.Cu")
	)
	(gr_circle
		(center 310.849772 -317.749936)
		(end 311.103772 -317.749936)
		(stroke
			(width 0.1016)
			(type default)
		)
		(fill no)
		(layer "In12.Cu")
	)
	(gr_circle
		(center 311.799732 -316.799722)
		(end 312.053732 -316.799722)
		(stroke
			(width 0.1016)
			(type default)
		)
		(fill no)
		(layer "In12.Cu")
	)
	(gr_circle
		(center 311.799732 -315.849762)
		(end 312.053732 -315.849762)
		(stroke
			(width 0.1016)
			(type default)
		)
		(fill no)
		(layer "In12.Cu")
	)
	(gr_circle
		(center 311.799732 -309.199788)
		(end 312.053732 -309.199788)
		(stroke
			(width 0.1016)
			(type default)
		)
		(fill no)
		(layer "In12.Cu")
	)
	(gr_circle
		(center 311.799732 -307.299868)
		(end 312.053732 -307.299868)
		(stroke
			(width 0.1016)
			(type default)
		)
		(fill no)
		(layer "In12.Cu")
	)
	(gr_circle
		(center 311.799732 -305.399948)
		(end 312.053732 -305.399948)
		(stroke
			(width 0.1016)
			(type default)
		)
		(fill no)
		(layer "In12.Cu")
	)
	(gr_circle
		(center 312.749692 -318.699896)
		(end 313.003692 -318.699896)
		(stroke
			(width 0.1016)
			(type default)
		)
		(fill no)
		(layer "In12.Cu")
	)
	(gr_circle
		(center 312.749692 -317.749936)
		(end 313.003692 -317.749936)
		(stroke
			(width 0.1016)
			(type default)
		)
		(fill no)
		(layer "In12.Cu")
	)
	(gr_circle
		(center 312.749692 -309.199788)
		(end 313.003692 -309.199788)
		(stroke
			(width 0.1016)
			(type default)
		)
		(fill no)
		(layer "In12.Cu")
	)
	(gr_circle
		(center 312.749692 -307.299868)
		(end 313.003692 -307.299868)
		(stroke
			(width 0.1016)
			(type default)
		)
		(fill no)
		(layer "In12.Cu")
	)
	(gr_circle
		(center 312.749692 -305.399948)
		(end 313.003692 -305.399948)
		(stroke
			(width 0.1016)
			(type default)
		)
		(fill no)
		(layer "In12.Cu")
	)
	(gr_circle
		(center 313.699906 -316.799722)
		(end 313.953906 -316.799722)
		(stroke
			(width 0.1016)
			(type default)
		)
		(fill no)
		(layer "In12.Cu")
	)
	(gr_circle
		(center 313.699906 -310.149748)
		(end 313.953906 -310.149748)
		(stroke
			(width 0.1016)
			(type default)
		)
		(fill no)
		(layer "In12.Cu")
	)
	(gr_circle
		(center 313.699906 -308.249828)
		(end 313.953906 -308.249828)
		(stroke
			(width 0.1016)
			(type default)
		)
		(fill no)
		(layer "In12.Cu")
	)
	(gr_circle
		(center 313.699906 -306.349908)
		(end 313.953906 -306.349908)
		(stroke
			(width 0.1016)
			(type default)
		)
		(fill no)
		(layer "In12.Cu")
	)
	(gr_circle
		(center 313.699906 -304.449734)
		(end 313.953906 -304.449734)
		(stroke
			(width 0.1016)
			(type default)
		)
		(fill no)
		(layer "In12.Cu")
	)
	(gr_circle
		(center 314.649866 -316.799722)
		(end 314.903866 -316.799722)
		(stroke
			(width 0.1016)
			(type default)
		)
		(fill no)
		(layer "In12.Cu")
	)
	(gr_circle
		(center 314.649866 -310.149748)
		(end 314.903866 -310.149748)
		(stroke
			(width 0.1016)
			(type default)
		)
		(fill no)
		(layer "In12.Cu")
	)
	(gr_circle
		(center 314.649866 -308.249828)
		(end 314.903866 -308.249828)
		(stroke
			(width 0.1016)
			(type default)
		)
		(fill no)
		(layer "In12.Cu")
	)
	(gr_circle
		(center 314.649866 -306.349908)
		(end 314.903866 -306.349908)
		(stroke
			(width 0.1016)
			(type default)
		)
		(fill no)
		(layer "In12.Cu")
	)
	(gr_circle
		(center 314.649866 -304.449734)
		(end 314.903866 -304.449734)
		(stroke
			(width 0.1016)
			(type default)
		)
		(fill no)
		(layer "In12.Cu")
	)
	(gr_line
		(start 315.138308 -45.086524)
		(end 316.597792 -46.67758)
		(stroke
			(width 0.1016)
			(type default)
		)
		(layer "In12.Cu")
	)
	(gr_line
		(start 315.71057 -44.561252)
		(end 315.138308 -45.086524)
		(stroke
			(width 0.1016)
			(type default)
		)
		(layer "In12.Cu")
	)
	(gr_line
		(start 315.711078 -44.560998)
		(end 317.170308 -46.152054)
		(stroke
			(width 0.1016)
			(type default)
		)
		(layer "In12.Cu")
	)
	(gr_line
		(start 316.918848 -44.22648)
		(end 318.378332 -45.817536)
		(stroke
			(width 0.1016)
			(type default)
		)
		(layer "In12.Cu")
	)
	(gr_line
		(start 317.49111 -43.701208)
		(end 316.918848 -44.22648)
		(stroke
			(width 0.1016)
			(type default)
		)
		(layer "In12.Cu")
	)
	(gr_line
		(start 317.491618 -43.700954)
		(end 318.950848 -45.29201)
		(stroke
			(width 0.1016)
			(type default)
		)
		(layer "In12.Cu")
	)
	(gr_line
		(start 320.453258 -51.406298)
		(end 320.588894 -53.56098)
		(stroke
			(width 0.1016)
			(type default)
		)
		(layer "In12.Cu")
	)
	(gr_line
		(start 321.228466 -51.357276)
		(end 320.453258 -51.406298)
		(stroke
			(width 0.1016)
			(type default)
		)
		(layer "In12.Cu")
	)
	(gr_line
		(start 321.228974 -51.357276)
		(end 321.36461 -53.511958)
		(stroke
			(width 0.1016)
			(type default)
		)
		(layer "In12.Cu")
	)
	(gr_line
		(start 322.30441 -50.80762)
		(end 322.440046 -52.962302)
		(stroke
			(width 0.1016)
			(type default)
		)
		(layer "In12.Cu")
	)
	(gr_line
		(start 323.079618 -50.758598)
		(end 322.30441 -50.80762)
		(stroke
			(width 0.1016)
			(type default)
		)
		(layer "In12.Cu")
	)
	(gr_line
		(start 323.080126 -50.758598)
		(end 323.215762 -52.91328)
		(stroke
			(width 0.1016)
			(type default)
		)
		(layer "In12.Cu")
	)
	(gr_line
		(start 335.295748 -37.856414)
		(end 336.329274 -39.752016)
		(stroke
			(width 0.1016)
			(type default)
		)
		(layer "In12.Cu")
	)
	(gr_line
		(start 335.977484 -37.484304)
		(end 335.295748 -37.856414)
		(stroke
			(width 0.1016)
			(type default)
		)
		(layer "In12.Cu")
	)
	(gr_line
		(start 335.977992 -37.48405)
		(end 337.011518 -39.379652)
		(stroke
			(width 0.1016)
			(type default)
		)
		(layer "In12.Cu")
	)
	(gr_line
		(start 337.303872 -37.411152)
		(end 338.337398 -39.306754)
		(stroke
			(width 0.1016)
			(type default)
		)
		(layer "In12.Cu")
	)
	(gr_line
		(start 337.985608 -37.039042)
		(end 337.303872 -37.411152)
		(stroke
			(width 0.1016)
			(type default)
		)
		(layer "In12.Cu")
	)
	(gr_line
		(start 337.986116 -37.038788)
		(end 339.019642 -38.93439)
		(stroke
			(width 0.1016)
			(type default)
		)
		(layer "In12.Cu")
	)
	(gr_line
		(start 338.919566 -45.584364)
		(end 338.962238 -47.742856)
		(stroke
			(width 0.1016)
			(type default)
		)
		(layer "In12.Cu")
	)
	(gr_line
		(start 339.696298 -45.56887)
		(end 338.919566 -45.584364)
		(stroke
			(width 0.1016)
			(type default)
		)
		(layer "In12.Cu")
	)
	(gr_line
		(start 339.696806 -45.568616)
		(end 339.739224 -47.727362)
		(stroke
			(width 0.1016)
			(type default)
		)
		(layer "In12.Cu")
	)
	(gr_line
		(start 340.839044 -45.629322)
		(end 340.881716 -47.787814)
		(stroke
			(width 0.1016)
			(type default)
		)
		(layer "In12.Cu")
	)
	(gr_line
		(start 341.615776 -45.613828)
		(end 340.839044 -45.629322)
		(stroke
			(width 0.1016)
			(type default)
		)
		(layer "In12.Cu")
	)
	(gr_line
		(start 341.616284 -45.613574)
		(end 341.658702 -47.77232)
		(stroke
			(width 0.1016)
			(type default)
		)
		(layer "In12.Cu")
	)
	(gr_line
		(start 379.227842 -45.074586)
		(end 380.687326 -46.665642)
		(stroke
			(width 0.1016)
			(type default)
		)
		(layer "In12.Cu")
	)
	(gr_line
		(start 379.800104 -44.549314)
		(end 379.227842 -45.074586)
		(stroke
			(width 0.1016)
			(type default)
		)
		(layer "In12.Cu")
	)
	(gr_line
		(start 379.800612 -44.54906)
		(end 381.259842 -46.140116)
		(stroke
			(width 0.1016)
			(type default)
		)
		(layer "In12.Cu")
	)
	(gr_line
		(start 380.98857 -44.205398)
		(end 381.56134 -43.679872)
		(stroke
			(width 0.1016)
			(type default)
		)
		(layer "In12.Cu")
	)
	(gr_line
		(start 380.98857 -44.205398)
		(end 382.448054 -45.796454)
		(stroke
			(width 0.1016)
			(type default)
		)
		(layer "In12.Cu")
	)
	(gr_line
		(start 381.56134 -43.679872)
		(end 383.02057 -45.270928)
		(stroke
			(width 0.1016)
			(type default)
		)
		(layer "In12.Cu")
	)
	(gr_line
		(start 382.448054 -45.796454)
		(end 380.98857 -44.205398)
		(stroke
			(width 0.1016)
			(type default)
		)
		(layer "In12.Cu")
	)
	(gr_line
		(start 384.540252 -51.197764)
		(end 384.675634 -53.352446)
		(stroke
			(width 0.1016)
			(type default)
		)
		(layer "In12.Cu")
	)
	(gr_line
		(start 385.31546 -51.148742)
		(end 384.540252 -51.197764)
		(stroke
			(width 0.1016)
			(type default)
		)
		(layer "In12.Cu")
	)
	(gr_line
		(start 385.31546 -51.148742)
		(end 385.450842 -53.303424)
		(stroke
			(width 0.1016)
			(type default)
		)
		(layer "In12.Cu")
	)
	(gr_line
		(start 386.405374 -50.819304)
		(end 386.540756 -52.973986)
		(stroke
			(width 0.1016)
			(type default)
		)
		(layer "In12.Cu")
	)
	(gr_line
		(start 387.180582 -50.770282)
		(end 386.405374 -50.819304)
		(stroke
			(width 0.1016)
			(type default)
		)
		(layer "In12.Cu")
	)
	(gr_line
		(start 387.180582 -50.770282)
		(end 387.315964 -52.924964)
		(stroke
			(width 0.1016)
			(type default)
		)
		(layer "In12.Cu")
	)
	(gr_circle
		(center 391.799826 -316.799722)
		(end 392.053826 -316.799722)
		(stroke
			(width 0.1016)
			(type default)
		)
		(fill no)
		(layer "In12.Cu")
	)
	(gr_circle
		(center 391.799826 -315.849762)
		(end 392.053826 -315.849762)
		(stroke
			(width 0.1016)
			(type default)
		)
		(fill no)
		(layer "In12.Cu")
	)
	(gr_circle
		(center 391.799826 -312.049922)
		(end 392.053826 -312.049922)
		(stroke
			(width 0.1016)
			(type default)
		)
		(fill no)
		(layer "In12.Cu")
	)
	(gr_circle
		(center 391.799826 -311.099962)
		(end 392.053826 -311.099962)
		(stroke
			(width 0.1016)
			(type default)
		)
		(fill no)
		(layer "In12.Cu")
	)
	(gr_circle
		(center 392.749786 -318.699896)
		(end 393.003786 -318.699896)
		(stroke
			(width 0.1016)
			(type default)
		)
		(fill no)
		(layer "In12.Cu")
	)
	(gr_circle
		(center 392.749786 -317.749936)
		(end 393.003786 -317.749936)
		(stroke
			(width 0.1016)
			(type default)
		)
		(fill no)
		(layer "In12.Cu")
	)
	(gr_circle
		(center 392.749786 -313.949842)
		(end 393.003786 -313.949842)
		(stroke
			(width 0.1016)
			(type default)
		)
		(fill no)
		(layer "In12.Cu")
	)
	(gr_circle
		(center 392.749786 -312.999882)
		(end 393.003786 -312.999882)
		(stroke
			(width 0.1016)
			(type default)
		)
		(fill no)
		(layer "In12.Cu")
	)
	(gr_circle
		(center 393.7 -316.799722)
		(end 393.954 -316.799722)
		(stroke
			(width 0.1016)
			(type default)
		)
		(fill no)
		(layer "In12.Cu")
	)
	(gr_circle
		(center 393.7 -315.849762)
		(end 393.954 -315.849762)
		(stroke
			(width 0.1016)
			(type default)
		)
		(fill no)
		(layer "In12.Cu")
	)
	(gr_circle
		(center 393.7 -312.049922)
		(end 393.954 -312.049922)
		(stroke
			(width 0.1016)
			(type default)
		)
		(fill no)
		(layer "In12.Cu")
	)
	(gr_circle
		(center 393.7 -311.099962)
		(end 393.954 -311.099962)
		(stroke
			(width 0.1016)
			(type default)
		)
		(fill no)
		(layer "In12.Cu")
	)
	(gr_circle
		(center 394.64996 -318.699896)
		(end 394.90396 -318.699896)
		(stroke
			(width 0.1016)
			(type default)
		)
		(fill no)
		(layer "In12.Cu")
	)
	(gr_circle
		(center 394.64996 -317.749936)
		(end 394.90396 -317.749936)
		(stroke
			(width 0.1016)
			(type default)
		)
		(fill no)
		(layer "In12.Cu")
	)
	(gr_circle
		(center 394.64996 -313.949842)
		(end 394.90396 -313.949842)
		(stroke
			(width 0.1016)
			(type default)
		)
		(fill no)
		(layer "In12.Cu")
	)
	(gr_circle
		(center 394.64996 -312.999882)
		(end 394.90396 -312.999882)
		(stroke
			(width 0.1016)
			(type default)
		)
		(fill no)
		(layer "In12.Cu")
	)
	(gr_circle
		(center 395.59992 -316.799722)
		(end 395.85392 -316.799722)
		(stroke
			(width 0.1016)
			(type default)
		)
		(fill no)
		(layer "In12.Cu")
	)
	(gr_circle
		(center 395.59992 -315.849762)
		(end 395.85392 -315.849762)
		(stroke
			(width 0.1016)
			(type default)
		)
		(fill no)
		(layer "In12.Cu")
	)
	(gr_circle
		(center 395.59992 -312.049922)
		(end 395.85392 -312.049922)
		(stroke
			(width 0.1016)
			(type default)
		)
		(fill no)
		(layer "In12.Cu")
	)
	(gr_circle
		(center 395.59992 -311.099962)
		(end 395.85392 -311.099962)
		(stroke
			(width 0.1016)
			(type default)
		)
		(fill no)
		(layer "In12.Cu")
	)
	(gr_circle
		(center 396.54988 -318.699896)
		(end 396.80388 -318.699896)
		(stroke
			(width 0.1016)
			(type default)
		)
		(fill no)
		(layer "In12.Cu")
	)
	(gr_circle
		(center 396.54988 -317.749936)
		(end 396.80388 -317.749936)
		(stroke
			(width 0.1016)
			(type default)
		)
		(fill no)
		(layer "In12.Cu")
	)
	(gr_circle
		(center 396.54988 -313.949842)
		(end 396.80388 -313.949842)
		(stroke
			(width 0.1016)
			(type default)
		)
		(fill no)
		(layer "In12.Cu")
	)
	(gr_circle
		(center 396.54988 -312.999882)
		(end 396.80388 -312.999882)
		(stroke
			(width 0.1016)
			(type default)
		)
		(fill no)
		(layer "In12.Cu")
	)
	(gr_circle
		(center 397.49984 -316.799722)
		(end 397.75384 -316.799722)
		(stroke
			(width 0.1016)
			(type default)
		)
		(fill no)
		(layer "In12.Cu")
	)
	(gr_circle
		(center 397.49984 -315.849762)
		(end 397.75384 -315.849762)
		(stroke
			(width 0.1016)
			(type default)
		)
		(fill no)
		(layer "In12.Cu")
	)
	(gr_circle
		(center 397.49984 -312.049922)
		(end 397.75384 -312.049922)
		(stroke
			(width 0.1016)
			(type default)
		)
		(fill no)
		(layer "In12.Cu")
	)
	(gr_circle
		(center 397.49984 -311.099962)
		(end 397.75384 -311.099962)
		(stroke
			(width 0.1016)
			(type default)
		)
		(fill no)
		(layer "In12.Cu")
	)
	(gr_circle
		(center 398.4498 -318.699896)
		(end 398.7038 -318.699896)
		(stroke
			(width 0.1016)
			(type default)
		)
		(fill no)
		(layer "In12.Cu")
	)
	(gr_circle
		(center 398.4498 -317.749936)
		(end 398.7038 -317.749936)
		(stroke
			(width 0.1016)
			(type default)
		)
		(fill no)
		(layer "In12.Cu")
	)
	(gr_circle
		(center 398.4498 -313.949842)
		(end 398.7038 -313.949842)
		(stroke
			(width 0.1016)
			(type default)
		)
		(fill no)
		(layer "In12.Cu")
	)
	(gr_circle
		(center 398.4498 -312.999882)
		(end 398.7038 -312.999882)
		(stroke
			(width 0.1016)
			(type default)
		)
		(fill no)
		(layer "In12.Cu")
	)
	(gr_line
		(start 405.05253 -44.884086)
		(end 406.512014 -46.475142)
		(stroke
			(width 0.1016)
			(type default)
		)
		(layer "In12.Cu")
	)
	(gr_line
		(start 405.624792 -44.358814)
		(end 405.05253 -44.884086)
		(stroke
			(width 0.1016)
			(type default)
		)
		(layer "In12.Cu")
	)
	(gr_line
		(start 405.6253 -44.35856)
		(end 407.08453 -45.949616)
		(stroke
			(width 0.1016)
			(type default)
		)
		(layer "In12.Cu")
	)
	(gr_line
		(start 407.374598 -44.626276)
		(end 408.834082 -46.217332)
		(stroke
			(width 0.1016)
			(type default)
		)
		(layer "In12.Cu")
	)
	(gr_line
		(start 407.94686 -44.101004)
		(end 407.374598 -44.626276)
		(stroke
			(width 0.1016)
			(type default)
		)
		(layer "In12.Cu")
	)
	(gr_line
		(start 407.947368 -44.10075)
		(end 409.406598 -45.691806)
		(stroke
			(width 0.1016)
			(type default)
		)
		(layer "In12.Cu")
	)
	(gr_line
		(start 410.54274 -51.235356)
		(end 410.678122 -53.390038)
		(stroke
			(width 0.1016)
			(type default)
		)
		(layer "In12.Cu")
	)
	(gr_line
		(start 411.317948 -51.186334)
		(end 410.54274 -51.235356)
		(stroke
			(width 0.1016)
			(type default)
		)
		(layer "In12.Cu")
	)
	(gr_line
		(start 411.317948 -51.186334)
		(end 411.45333 -53.341016)
		(stroke
			(width 0.1016)
			(type default)
		)
		(layer "In12.Cu")
	)
	(gr_line
		(start 412.407862 -50.856896)
		(end 412.543244 -53.011578)
		(stroke
			(width 0.1016)
			(type default)
		)
		(layer "In12.Cu")
	)
	(gr_line
		(start 413.18307 -50.807874)
		(end 412.407862 -50.856896)
		(stroke
			(width 0.1016)
			(type default)
		)
		(layer "In12.Cu")
	)
	(gr_line
		(start 413.18307 -50.807874)
		(end 413.318452 -52.962556)
		(stroke
			(width 0.1016)
			(type default)
		)
		(layer "In12.Cu")
	)
	(gr_circle
		(center 414.599882 -316.799722)
		(end 414.853882 -316.799722)
		(stroke
			(width 0.1016)
			(type default)
		)
		(fill no)
		(layer "In12.Cu")
	)
	(gr_circle
		(center 414.599882 -315.849762)
		(end 414.853882 -315.849762)
		(stroke
			(width 0.1016)
			(type default)
		)
		(fill no)
		(layer "In12.Cu")
	)
	(gr_circle
		(center 414.599882 -312.049922)
		(end 414.853882 -312.049922)
		(stroke
			(width 0.1016)
			(type default)
		)
		(fill no)
		(layer "In12.Cu")
	)
	(gr_circle
		(center 414.599882 -311.099962)
		(end 414.853882 -311.099962)
		(stroke
			(width 0.1016)
			(type default)
		)
		(fill no)
		(layer "In12.Cu")
	)
	(gr_circle
		(center 415.549842 -318.699896)
		(end 415.803842 -318.699896)
		(stroke
			(width 0.1016)
			(type default)
		)
		(fill no)
		(layer "In12.Cu")
	)
	(gr_circle
		(center 415.549842 -317.749936)
		(end 415.803842 -317.749936)
		(stroke
			(width 0.1016)
			(type default)
		)
		(fill no)
		(layer "In12.Cu")
	)
	(gr_circle
		(center 415.549842 -313.949842)
		(end 415.803842 -313.949842)
		(stroke
			(width 0.1016)
			(type default)
		)
		(fill no)
		(layer "In12.Cu")
	)
	(gr_circle
		(center 415.549842 -312.999882)
		(end 415.803842 -312.999882)
		(stroke
			(width 0.1016)
			(type default)
		)
		(fill no)
		(layer "In12.Cu")
	)
	(gr_circle
		(center 416.499802 -316.799722)
		(end 416.753802 -316.799722)
		(stroke
			(width 0.1016)
			(type default)
		)
		(fill no)
		(layer "In12.Cu")
	)
	(gr_circle
		(center 416.499802 -315.849762)
		(end 416.753802 -315.849762)
		(stroke
			(width 0.1016)
			(type default)
		)
		(fill no)
		(layer "In12.Cu")
	)
	(gr_circle
		(center 416.499802 -312.049922)
		(end 416.753802 -312.049922)
		(stroke
			(width 0.1016)
			(type default)
		)
		(fill no)
		(layer "In12.Cu")
	)
	(gr_circle
		(center 416.499802 -311.099962)
		(end 416.753802 -311.099962)
		(stroke
			(width 0.1016)
			(type default)
		)
		(fill no)
		(layer "In12.Cu")
	)
	(gr_circle
		(center 417.450016 -318.699896)
		(end 417.704016 -318.699896)
		(stroke
			(width 0.1016)
			(type default)
		)
		(fill no)
		(layer "In12.Cu")
	)
	(gr_circle
		(center 417.450016 -317.749936)
		(end 417.704016 -317.749936)
		(stroke
			(width 0.1016)
			(type default)
		)
		(fill no)
		(layer "In12.Cu")
	)
	(gr_circle
		(center 417.450016 -313.949842)
		(end 417.704016 -313.949842)
		(stroke
			(width 0.1016)
			(type default)
		)
		(fill no)
		(layer "In12.Cu")
	)
	(gr_circle
		(center 417.450016 -312.999882)
		(end 417.704016 -312.999882)
		(stroke
			(width 0.1016)
			(type default)
		)
		(fill no)
		(layer "In12.Cu")
	)
	(gr_circle
		(center 418.399976 -316.799722)
		(end 418.653976 -316.799722)
		(stroke
			(width 0.1016)
			(type default)
		)
		(fill no)
		(layer "In12.Cu")
	)
	(gr_circle
		(center 418.399976 -315.849762)
		(end 418.653976 -315.849762)
		(stroke
			(width 0.1016)
			(type default)
		)
		(fill no)
		(layer "In12.Cu")
	)
	(gr_circle
		(center 418.399976 -312.049922)
		(end 418.653976 -312.049922)
		(stroke
			(width 0.1016)
			(type default)
		)
		(fill no)
		(layer "In12.Cu")
	)
	(gr_circle
		(center 418.399976 -311.099962)
		(end 418.653976 -311.099962)
		(stroke
			(width 0.1016)
			(type default)
		)
		(fill no)
		(layer "In12.Cu")
	)
	(gr_circle
		(center 419.349936 -318.699896)
		(end 419.603936 -318.699896)
		(stroke
			(width 0.1016)
			(type default)
		)
		(fill no)
		(layer "In12.Cu")
	)
	(gr_circle
		(center 419.349936 -317.749936)
		(end 419.603936 -317.749936)
		(stroke
			(width 0.1016)
			(type default)
		)
		(fill no)
		(layer "In12.Cu")
	)
	(gr_circle
		(center 419.349936 -313.949842)
		(end 419.603936 -313.949842)
		(stroke
			(width 0.1016)
			(type default)
		)
		(fill no)
		(layer "In12.Cu")
	)
	(gr_circle
		(center 419.349936 -312.999882)
		(end 419.603936 -312.999882)
		(stroke
			(width 0.1016)
			(type default)
		)
		(fill no)
		(layer "In12.Cu")
	)
	(gr_circle
		(center 420.299896 -316.799722)
		(end 420.553896 -316.799722)
		(stroke
			(width 0.1016)
			(type default)
		)
		(fill no)
		(layer "In12.Cu")
	)
	(gr_circle
		(center 420.299896 -315.849762)
		(end 420.553896 -315.849762)
		(stroke
			(width 0.1016)
			(type default)
		)
		(fill no)
		(layer "In12.Cu")
	)
	(gr_circle
		(center 420.299896 -312.049922)
		(end 420.553896 -312.049922)
		(stroke
			(width 0.1016)
			(type default)
		)
		(fill no)
		(layer "In12.Cu")
	)
	(gr_circle
		(center 420.299896 -311.099962)
		(end 420.553896 -311.099962)
		(stroke
			(width 0.1016)
			(type default)
		)
		(fill no)
		(layer "In12.Cu")
	)
	(gr_circle
		(center 421.249856 -318.699896)
		(end 421.503856 -318.699896)
		(stroke
			(width 0.1016)
			(type default)
		)
		(fill no)
		(layer "In12.Cu")
	)
	(gr_circle
		(center 421.249856 -317.749936)
		(end 421.503856 -317.749936)
		(stroke
			(width 0.1016)
			(type default)
		)
		(fill no)
		(layer "In12.Cu")
	)
	(gr_circle
		(center 421.249856 -313.949842)
		(end 421.503856 -313.949842)
		(stroke
			(width 0.1016)
			(type default)
		)
		(fill no)
		(layer "In12.Cu")
	)
	(gr_circle
		(center 421.249856 -312.999882)
		(end 421.503856 -312.999882)
		(stroke
			(width 0.1016)
			(type default)
		)
		(fill no)
		(layer "In12.Cu")
	)
	(gr_line
		(start 431.238406 -45.086524)
		(end 432.69789 -46.67758)
		(stroke
			(width 0.1016)
			(type default)
		)
		(layer "In12.Cu")
	)
	(gr_line
		(start 431.810668 -44.561252)
		(end 431.238406 -45.086524)
		(stroke
			(width 0.1016)
			(type default)
		)
		(layer "In12.Cu")
	)
	(gr_line
		(start 431.811176 -44.560998)
		(end 433.270406 -46.152054)
		(stroke
			(width 0.1016)
			(type default)
		)
		(layer "In12.Cu")
	)
	(gr_line
		(start 433.018946 -44.22648)
		(end 434.47843 -45.817536)
		(stroke
			(width 0.1016)
			(type default)
		)
		(layer "In12.Cu")
	)
	(gr_line
		(start 433.591208 -43.701208)
		(end 433.018946 -44.22648)
		(stroke
			(width 0.1016)
			(type default)
		)
		(layer "In12.Cu")
	)
	(gr_line
		(start 433.591716 -43.700954)
		(end 435.050946 -45.29201)
		(stroke
			(width 0.1016)
			(type default)
		)
		(layer "In12.Cu")
	)
	(gr_line
		(start 436.553356 -51.406298)
		(end 436.688992 -53.56098)
		(stroke
			(width 0.1016)
			(type default)
		)
		(layer "In12.Cu")
	)
	(gr_line
		(start 437.328564 -51.357276)
		(end 436.553356 -51.406298)
		(stroke
			(width 0.1016)
			(type default)
		)
		(layer "In12.Cu")
	)
	(gr_line
		(start 437.329072 -51.357276)
		(end 437.464708 -53.511958)
		(stroke
			(width 0.1016)
			(type default)
		)
		(layer "In12.Cu")
	)
	(gr_line
		(start 438.404508 -50.80762)
		(end 438.540144 -52.962302)
		(stroke
			(width 0.1016)
			(type default)
		)
		(layer "In12.Cu")
	)
	(gr_line
		(start 439.179716 -50.758598)
		(end 438.404508 -50.80762)
		(stroke
			(width 0.1016)
			(type default)
		)
		(layer "In12.Cu")
	)
	(gr_line
		(start 439.180224 -50.758598)
		(end 439.31586 -52.91328)
		(stroke
			(width 0.1016)
			(type default)
		)
		(layer "In12.Cu")
	)
	(gr_line
		(start 451.395846 -37.856414)
		(end 452.429372 -39.752016)
		(stroke
			(width 0.1016)
			(type default)
		)
		(layer "In12.Cu")
	)
	(gr_line
		(start 452.077582 -37.484304)
		(end 451.395846 -37.856414)
		(stroke
			(width 0.1016)
			(type default)
		)
		(layer "In12.Cu")
	)
	(gr_line
		(start 452.07809 -37.48405)
		(end 453.111616 -39.379652)
		(stroke
			(width 0.1016)
			(type default)
		)
		(layer "In12.Cu")
	)
	(gr_line
		(start 453.40397 -37.411152)
		(end 454.437496 -39.306754)
		(stroke
			(width 0.1016)
			(type default)
		)
		(layer "In12.Cu")
	)
	(gr_line
		(start 454.085706 -37.039042)
		(end 453.40397 -37.411152)
		(stroke
			(width 0.1016)
			(type default)
		)
		(layer "In12.Cu")
	)
	(gr_line
		(start 454.086214 -37.038788)
		(end 455.11974 -38.93439)
		(stroke
			(width 0.1016)
			(type default)
		)
		(layer "In12.Cu")
	)
	(gr_line
		(start 455.019664 -45.584364)
		(end 455.062336 -47.742856)
		(stroke
			(width 0.1016)
			(type default)
		)
		(layer "In12.Cu")
	)
	(gr_line
		(start 455.796396 -45.56887)
		(end 455.019664 -45.584364)
		(stroke
			(width 0.1016)
			(type default)
		)
		(layer "In12.Cu")
	)
	(gr_line
		(start 455.796904 -45.568616)
		(end 455.839322 -47.727362)
		(stroke
			(width 0.1016)
			(type default)
		)
		(layer "In12.Cu")
	)
	(gr_line
		(start 456.939142 -45.629322)
		(end 456.981814 -47.787814)
		(stroke
			(width 0.1016)
			(type default)
		)
		(layer "In12.Cu")
	)
	(gr_line
		(start 457.715874 -45.613828)
		(end 456.939142 -45.629322)
		(stroke
			(width 0.1016)
			(type default)
		)
		(layer "In12.Cu")
	)
	(gr_line
		(start 457.716382 -45.613574)
		(end 457.7588 -47.77232)
		(stroke
			(width 0.1016)
			(type default)
		)
		(layer "In12.Cu")
	)
	(gr_poly
		(pts
			(xy 139.76985 -195.612512) (xy 139.76985 -192.564512) (xy 139.64285 -192.437512) (xy 135.95985 -192.437512)
			(xy 135.70585 -192.691512) (xy 135.70585 -195.485512) (xy 135.95985 -195.739512) (xy 139.64285 -195.739512)
		)
		(stroke
			(width 0)
			(type solid)
		)
		(fill yes)
		(layer "In13.Cu")
		(net "GND")
	)
	(gr_poly
		(pts
			(arc
				(start 6.74751 -34.98977)
				(mid 6.454394 -34.98977)
				(end 6.74751 -34.98977)
			)
		)
		(stroke
			(width 0)
			(type solid)
		)
		(fill yes)
		(layer "In13.Cu")
		(net "GND")
	)
	(gr_poly
		(pts
			(arc
				(start 6.74751 -33.189926)
				(mid 6.454394 -33.189926)
				(end 6.74751 -33.189926)
			)
		)
		(stroke
			(width 0)
			(type solid)
		)
		(fill yes)
		(layer "In13.Cu")
		(net "GND")
	)
	(gr_poly
		(pts
			(arc
				(start 6.74751 -31.389828)
				(mid 6.454394 -31.389828)
				(end 6.74751 -31.389828)
			)
		)
		(stroke
			(width 0)
			(type solid)
		)
		(fill yes)
		(layer "In13.Cu")
		(net "GND")
	)
	(gr_poly
		(pts
			(arc
				(start 6.74751 -29.589984)
				(mid 6.454394 -29.589984)
				(end 6.74751 -29.589984)
			)
		)
		(stroke
			(width 0)
			(type solid)
		)
		(fill yes)
		(layer "In13.Cu")
		(net "GND")
	)
	(gr_poly
		(pts
			(arc
				(start 7.96671 -34.98977)
				(mid 7.673594 -34.98977)
				(end 7.96671 -34.98977)
			)
		)
		(stroke
			(width 0)
			(type solid)
		)
		(fill yes)
		(layer "In13.Cu")
		(net "GND")
	)
	(gr_poly
		(pts
			(arc
				(start 7.96671 -33.189926)
				(mid 7.673594 -33.189926)
				(end 7.96671 -33.189926)
			)
		)
		(stroke
			(width 0)
			(type solid)
		)
		(fill yes)
		(layer "In13.Cu")
		(net "GND")
	)
	(gr_poly
		(pts
			(arc
				(start 7.96671 -31.389828)
				(mid 7.673594 -31.389828)
				(end 7.96671 -31.389828)
			)
		)
		(stroke
			(width 0)
			(type solid)
		)
		(fill yes)
		(layer "In13.Cu")
		(net "GND")
	)
	(gr_poly
		(pts
			(arc
				(start 7.96671 -29.589984)
				(mid 7.673594 -29.589984)
				(end 7.96671 -29.589984)
			)
		)
		(stroke
			(width 0)
			(type solid)
		)
		(fill yes)
		(layer "In13.Cu")
		(net "GND")
	)
	(gr_poly
		(pts
			(arc
				(start 8.60171 -33.189926)
				(mid 8.308594 -33.189926)
				(end 8.60171 -33.189926)
			)
		)
		(stroke
			(width 0)
			(type solid)
		)
		(fill yes)
		(layer "In13.Cu")
		(net "GND")
	)
	(gr_poly
		(pts
			(arc
				(start 8.60171 -31.389828)
				(mid 8.308594 -31.389828)
				(end 8.60171 -31.389828)
			)
		)
		(stroke
			(width 0)
			(type solid)
		)
		(fill yes)
		(layer "In13.Cu")
		(net "GND")
	)
	(gr_poly
		(pts
			(arc
				(start 8.60171 -29.589984)
				(mid 8.308594 -29.589984)
				(end 8.60171 -29.589984)
			)
		)
		(stroke
			(width 0)
			(type solid)
		)
		(fill yes)
		(layer "In13.Cu")
		(net "GND")
	)
	(gr_poly
		(pts
			(arc
				(start 8.60171 -27.789886)
				(mid 8.308594 -27.789886)
				(end 8.60171 -27.789886)
			)
		)
		(stroke
			(width 0)
			(type solid)
		)
		(fill yes)
		(layer "In13.Cu")
		(net "GND")
	)
	(gr_poly
		(pts
			(arc
				(start 32.747458 -34.98977)
				(mid 32.454342 -34.98977)
				(end 32.747458 -34.98977)
			)
		)
		(stroke
			(width 0)
			(type solid)
		)
		(fill yes)
		(layer "In13.Cu")
		(net "GND")
	)
	(gr_poly
		(pts
			(arc
				(start 32.747458 -33.189926)
				(mid 32.454342 -33.189926)
				(end 32.747458 -33.189926)
			)
		)
		(stroke
			(width 0)
			(type solid)
		)
		(fill yes)
		(layer "In13.Cu")
		(net "GND")
	)
	(gr_poly
		(pts
			(arc
				(start 32.747458 -31.389828)
				(mid 32.454342 -31.389828)
				(end 32.747458 -31.389828)
			)
		)
		(stroke
			(width 0)
			(type solid)
		)
		(fill yes)
		(layer "In13.Cu")
		(net "GND")
	)
	(gr_poly
		(pts
			(arc
				(start 32.747458 -29.589984)
				(mid 32.454342 -29.589984)
				(end 32.747458 -29.589984)
			)
		)
		(stroke
			(width 0)
			(type solid)
		)
		(fill yes)
		(layer "In13.Cu")
		(net "GND")
	)
	(gr_poly
		(pts
			(arc
				(start 33.966658 -34.98977)
				(mid 33.673542 -34.98977)
				(end 33.966658 -34.98977)
			)
		)
		(stroke
			(width 0)
			(type solid)
		)
		(fill yes)
		(layer "In13.Cu")
		(net "GND")
	)
	(gr_poly
		(pts
			(arc
				(start 33.966658 -33.189926)
				(mid 33.673542 -33.189926)
				(end 33.966658 -33.189926)
			)
		)
		(stroke
			(width 0)
			(type solid)
		)
		(fill yes)
		(layer "In13.Cu")
		(net "GND")
	)
	(gr_poly
		(pts
			(arc
				(start 33.966658 -31.389828)
				(mid 33.673542 -31.389828)
				(end 33.966658 -31.389828)
			)
		)
		(stroke
			(width 0)
			(type solid)
		)
		(fill yes)
		(layer "In13.Cu")
		(net "GND")
	)
	(gr_poly
		(pts
			(arc
				(start 33.966658 -29.589984)
				(mid 33.673542 -29.589984)
				(end 33.966658 -29.589984)
			)
		)
		(stroke
			(width 0)
			(type solid)
		)
		(fill yes)
		(layer "In13.Cu")
		(net "GND")
	)
	(gr_poly
		(pts
			(arc
				(start 34.601658 -33.189926)
				(mid 34.308542 -33.189926)
				(end 34.601658 -33.189926)
			)
		)
		(stroke
			(width 0)
			(type solid)
		)
		(fill yes)
		(layer "In13.Cu")
		(net "GND")
	)
	(gr_poly
		(pts
			(arc
				(start 34.601658 -31.389828)
				(mid 34.308542 -31.389828)
				(end 34.601658 -31.389828)
			)
		)
		(stroke
			(width 0)
			(type solid)
		)
		(fill yes)
		(layer "In13.Cu")
		(net "GND")
	)
	(gr_poly
		(pts
			(arc
				(start 34.601658 -29.589984)
				(mid 34.308542 -29.589984)
				(end 34.601658 -29.589984)
			)
		)
		(stroke
			(width 0)
			(type solid)
		)
		(fill yes)
		(layer "In13.Cu")
		(net "GND")
	)
	(gr_poly
		(pts
			(arc
				(start 34.601658 -27.789886)
				(mid 34.308542 -27.789886)
				(end 34.601658 -27.789886)
			)
		)
		(stroke
			(width 0)
			(type solid)
		)
		(fill yes)
		(layer "In13.Cu")
		(net "GND")
	)
	(gr_poly
		(pts
			(arc
				(start 53.09616 -24.503634)
				(mid 52.803044 -24.503634)
				(end 53.09616 -24.503634)
			)
		)
		(stroke
			(width 0)
			(type solid)
		)
		(fill yes)
		(layer "In13.Cu")
		(net "GND")
	)
	(gr_poly
		(pts
			(arc
				(start 58.747406 -34.98977)
				(mid 58.45429 -34.98977)
				(end 58.747406 -34.98977)
			)
		)
		(stroke
			(width 0)
			(type solid)
		)
		(fill yes)
		(layer "In13.Cu")
		(net "GND")
	)
	(gr_poly
		(pts
			(arc
				(start 58.747406 -33.189926)
				(mid 58.45429 -33.189926)
				(end 58.747406 -33.189926)
			)
		)
		(stroke
			(width 0)
			(type solid)
		)
		(fill yes)
		(layer "In13.Cu")
		(net "GND")
	)
	(gr_poly
		(pts
			(arc
				(start 58.747406 -31.389828)
				(mid 58.45429 -31.389828)
				(end 58.747406 -31.389828)
			)
		)
		(stroke
			(width 0)
			(type solid)
		)
		(fill yes)
		(layer "In13.Cu")
		(net "GND")
	)
	(gr_poly
		(pts
			(arc
				(start 58.747406 -29.589984)
				(mid 58.45429 -29.589984)
				(end 58.747406 -29.589984)
			)
		)
		(stroke
			(width 0)
			(type solid)
		)
		(fill yes)
		(layer "In13.Cu")
		(net "GND")
	)
	(gr_poly
		(pts
			(arc
				(start 59.966606 -34.98977)
				(mid 59.67349 -34.98977)
				(end 59.966606 -34.98977)
			)
		)
		(stroke
			(width 0)
			(type solid)
		)
		(fill yes)
		(layer "In13.Cu")
		(net "GND")
	)
	(gr_poly
		(pts
			(arc
				(start 59.966606 -33.189926)
				(mid 59.67349 -33.189926)
				(end 59.966606 -33.189926)
			)
		)
		(stroke
			(width 0)
			(type solid)
		)
		(fill yes)
		(layer "In13.Cu")
		(net "GND")
	)
	(gr_poly
		(pts
			(arc
				(start 59.966606 -31.389828)
				(mid 59.67349 -31.389828)
				(end 59.966606 -31.389828)
			)
		)
		(stroke
			(width 0)
			(type solid)
		)
		(fill yes)
		(layer "In13.Cu")
		(net "GND")
	)
	(gr_poly
		(pts
			(arc
				(start 59.966606 -29.589984)
				(mid 59.67349 -29.589984)
				(end 59.966606 -29.589984)
			)
		)
		(stroke
			(width 0)
			(type solid)
		)
		(fill yes)
		(layer "In13.Cu")
		(net "GND")
	)
	(gr_poly
		(pts
			(arc
				(start 60.601606 -33.189926)
				(mid 60.30849 -33.189926)
				(end 60.601606 -33.189926)
			)
		)
		(stroke
			(width 0)
			(type solid)
		)
		(fill yes)
		(layer "In13.Cu")
		(net "GND")
	)
	(gr_poly
		(pts
			(arc
				(start 60.601606 -31.389828)
				(mid 60.30849 -31.389828)
				(end 60.601606 -31.389828)
			)
		)
		(stroke
			(width 0)
			(type solid)
		)
		(fill yes)
		(layer "In13.Cu")
		(net "GND")
	)
	(gr_poly
		(pts
			(arc
				(start 60.601606 -29.589984)
				(mid 60.30849 -29.589984)
				(end 60.601606 -29.589984)
			)
		)
		(stroke
			(width 0)
			(type solid)
		)
		(fill yes)
		(layer "In13.Cu")
		(net "GND")
	)
	(gr_poly
		(pts
			(arc
				(start 60.601606 -27.789886)
				(mid 60.30849 -27.789886)
				(end 60.601606 -27.789886)
			)
		)
		(stroke
			(width 0)
			(type solid)
		)
		(fill yes)
		(layer "In13.Cu")
		(net "GND")
	)
	(gr_poly
		(pts
			(arc
				(start 76.64069 -96.597978)
				(mid 76.347574 -96.597978)
				(end 76.64069 -96.597978)
			)
		)
		(stroke
			(width 0)
			(type solid)
		)
		(fill yes)
		(layer "In13.Cu")
		(net "GND")
	)
	(gr_poly
		(pts
			(arc
				(start 76.67879 -100.417884)
				(mid 76.385674 -100.417884)
				(end 76.67879 -100.417884)
			)
		)
		(stroke
			(width 0)
			(type solid)
		)
		(fill yes)
		(layer "In13.Cu")
		(net "GND")
	)
	(gr_poly
		(pts
			(arc
				(start 76.70038 -101.609906)
				(mid 76.407264 -101.609906)
				(end 76.70038 -101.609906)
			)
		)
		(stroke
			(width 0)
			(type solid)
		)
		(fill yes)
		(layer "In13.Cu")
		(net "GND")
	)
	(gr_poly
		(pts
			(arc
				(start 79.110586 -24.539448)
				(mid 78.81747 -24.539448)
				(end 79.110586 -24.539448)
			)
		)
		(stroke
			(width 0)
			(type solid)
		)
		(fill yes)
		(layer "In13.Cu")
		(net "GND")
	)
	(gr_poly
		(pts
			(arc
				(start 84.747354 -34.98977)
				(mid 84.454238 -34.98977)
				(end 84.747354 -34.98977)
			)
		)
		(stroke
			(width 0)
			(type solid)
		)
		(fill yes)
		(layer "In13.Cu")
		(net "GND")
	)
	(gr_poly
		(pts
			(arc
				(start 84.747354 -33.189672)
				(mid 84.454238 -33.189672)
				(end 84.747354 -33.189672)
			)
		)
		(stroke
			(width 0)
			(type solid)
		)
		(fill yes)
		(layer "In13.Cu")
		(net "GND")
	)
	(gr_poly
		(pts
			(arc
				(start 84.747354 -31.389828)
				(mid 84.454238 -31.389828)
				(end 84.747354 -31.389828)
			)
		)
		(stroke
			(width 0)
			(type solid)
		)
		(fill yes)
		(layer "In13.Cu")
		(net "GND")
	)
	(gr_poly
		(pts
			(arc
				(start 84.747354 -29.589984)
				(mid 84.454238 -29.589984)
				(end 84.747354 -29.589984)
			)
		)
		(stroke
			(width 0)
			(type solid)
		)
		(fill yes)
		(layer "In13.Cu")
		(net "GND")
	)
	(gr_poly
		(pts
			(arc
				(start 85.966554 -34.98977)
				(mid 85.673438 -34.98977)
				(end 85.966554 -34.98977)
			)
		)
		(stroke
			(width 0)
			(type solid)
		)
		(fill yes)
		(layer "In13.Cu")
		(net "GND")
	)
	(gr_poly
		(pts
			(arc
				(start 85.966554 -33.189672)
				(mid 85.673438 -33.189672)
				(end 85.966554 -33.189672)
			)
		)
		(stroke
			(width 0)
			(type solid)
		)
		(fill yes)
		(layer "In13.Cu")
		(net "GND")
	)
	(gr_poly
		(pts
			(arc
				(start 85.966554 -31.389828)
				(mid 85.673438 -31.389828)
				(end 85.966554 -31.389828)
			)
		)
		(stroke
			(width 0)
			(type solid)
		)
		(fill yes)
		(layer "In13.Cu")
		(net "GND")
	)
	(gr_poly
		(pts
			(arc
				(start 85.966554 -29.589984)
				(mid 85.673438 -29.589984)
				(end 85.966554 -29.589984)
			)
		)
		(stroke
			(width 0)
			(type solid)
		)
		(fill yes)
		(layer "In13.Cu")
		(net "GND")
	)
	(gr_poly
		(pts
			(arc
				(start 86.601554 -33.189672)
				(mid 86.308438 -33.189672)
				(end 86.601554 -33.189672)
			)
		)
		(stroke
			(width 0)
			(type solid)
		)
		(fill yes)
		(layer "In13.Cu")
		(net "GND")
	)
	(gr_poly
		(pts
			(arc
				(start 86.601554 -31.389828)
				(mid 86.308438 -31.389828)
				(end 86.601554 -31.389828)
			)
		)
		(stroke
			(width 0)
			(type solid)
		)
		(fill yes)
		(layer "In13.Cu")
		(net "GND")
	)
	(gr_poly
		(pts
			(arc
				(start 86.601554 -29.589984)
				(mid 86.308438 -29.589984)
				(end 86.601554 -29.589984)
			)
		)
		(stroke
			(width 0)
			(type solid)
		)
		(fill yes)
		(layer "In13.Cu")
		(net "GND")
	)
	(gr_poly
		(pts
			(arc
				(start 86.601554 -27.789886)
				(mid 86.308438 -27.789886)
				(end 86.601554 -27.789886)
			)
		)
		(stroke
			(width 0)
			(type solid)
		)
		(fill yes)
		(layer "In13.Cu")
		(net "GND")
	)
	(gr_poly
		(pts
			(arc
				(start 87.795354 -29.589984)
				(mid 87.502238 -29.589984)
				(end 87.795354 -29.589984)
			)
		)
		(stroke
			(width 0)
			(type solid)
		)
		(fill yes)
		(layer "In13.Cu")
		(net "GND")
	)
	(gr_poly
		(pts
			(arc
				(start 87.795354 -27.789632)
				(mid 87.502238 -27.789632)
				(end 87.795354 -27.789632)
			)
		)
		(stroke
			(width 0)
			(type solid)
		)
		(fill yes)
		(layer "In13.Cu")
		(net "GND")
	)
	(gr_poly
		(pts
			(arc
				(start 89.44356 -287.63214)
				(mid 89.150444 -287.63214)
				(end 89.44356 -287.63214)
			)
		)
		(stroke
			(width 0)
			(type solid)
		)
		(fill yes)
		(layer "In13.Cu")
		(net "GND")
	)
	(gr_poly
		(pts
			(arc
				(start 90.552524 -287.538668)
				(mid 90.259408 -287.538668)
				(end 90.552524 -287.538668)
			)
		)
		(stroke
			(width 0)
			(type solid)
		)
		(fill yes)
		(layer "In13.Cu")
		(net "GND")
	)
	(gr_poly
		(pts
			(arc
				(start 117.102382 -220.2307)
				(mid 116.809266 -220.2307)
				(end 117.102382 -220.2307)
			)
		)
		(stroke
			(width 0)
			(type solid)
		)
		(fill yes)
		(layer "In13.Cu")
		(net "GND")
	)
	(gr_poly
		(pts
			(arc
				(start 117.782848 -218.237562)
				(mid 117.489732 -218.237562)
				(end 117.782848 -218.237562)
			)
		)
		(stroke
			(width 0)
			(type solid)
		)
		(fill yes)
		(layer "In13.Cu")
		(net "GND")
	)
	(gr_poly
		(pts
			(arc
				(start 118.890288 -234.831128)
				(mid 118.597172 -234.831128)
				(end 118.890288 -234.831128)
			)
		)
		(stroke
			(width 0)
			(type solid)
		)
		(fill yes)
		(layer "In13.Cu")
		(net "GND")
	)
	(gr_poly
		(pts
			(arc
				(start 120.715024 -217.911426)
				(mid 120.421908 -217.911426)
				(end 120.715024 -217.911426)
			)
		)
		(stroke
			(width 0)
			(type solid)
		)
		(fill yes)
		(layer "In13.Cu")
		(net "GND")
	)
	(gr_poly
		(pts
			(arc
				(start 120.80494 -214.186008)
				(mid 120.511824 -214.186008)
				(end 120.80494 -214.186008)
			)
		)
		(stroke
			(width 0)
			(type solid)
		)
		(fill yes)
		(layer "In13.Cu")
		(net "GND")
	)
	(gr_poly
		(pts
			(arc
				(start 120.808496 -225.031808)
				(mid 120.51538 -225.031808)
				(end 120.808496 -225.031808)
			)
		)
		(stroke
			(width 0)
			(type solid)
		)
		(fill yes)
		(layer "In13.Cu")
		(net "GND")
	)
	(gr_poly
		(pts
			(arc
				(start 122.847608 -34.98977)
				(mid 122.554492 -34.98977)
				(end 122.847608 -34.98977)
			)
		)
		(stroke
			(width 0)
			(type solid)
		)
		(fill yes)
		(layer "In13.Cu")
		(net "GND")
	)
	(gr_poly
		(pts
			(arc
				(start 122.847608 -33.189926)
				(mid 122.554492 -33.189926)
				(end 122.847608 -33.189926)
			)
		)
		(stroke
			(width 0)
			(type solid)
		)
		(fill yes)
		(layer "In13.Cu")
		(net "GND")
	)
	(gr_poly
		(pts
			(arc
				(start 122.847608 -31.389828)
				(mid 122.554492 -31.389828)
				(end 122.847608 -31.389828)
			)
		)
		(stroke
			(width 0)
			(type solid)
		)
		(fill yes)
		(layer "In13.Cu")
		(net "GND")
	)
	(gr_poly
		(pts
			(arc
				(start 122.847608 -29.589984)
				(mid 122.554492 -29.589984)
				(end 122.847608 -29.589984)
			)
		)
		(stroke
			(width 0)
			(type solid)
		)
		(fill yes)
		(layer "In13.Cu")
		(net "GND")
	)
	(gr_poly
		(pts
			(arc
				(start 122.990356 -241.846608)
				(mid 122.69724 -241.846608)
				(end 122.990356 -241.846608)
			)
		)
		(stroke
			(width 0)
			(type solid)
		)
		(fill yes)
		(layer "In13.Cu")
		(net "GND")
	)
	(gr_poly
		(pts
			(arc
				(start 124.066808 -34.98977)
				(mid 123.773692 -34.98977)
				(end 124.066808 -34.98977)
			)
		)
		(stroke
			(width 0)
			(type solid)
		)
		(fill yes)
		(layer "In13.Cu")
		(net "GND")
	)
	(gr_poly
		(pts
			(arc
				(start 124.066808 -33.189926)
				(mid 123.773692 -33.189926)
				(end 124.066808 -33.189926)
			)
		)
		(stroke
			(width 0)
			(type solid)
		)
		(fill yes)
		(layer "In13.Cu")
		(net "GND")
	)
	(gr_poly
		(pts
			(arc
				(start 124.066808 -31.389828)
				(mid 123.773692 -31.389828)
				(end 124.066808 -31.389828)
			)
		)
		(stroke
			(width 0)
			(type solid)
		)
		(fill yes)
		(layer "In13.Cu")
		(net "GND")
	)
	(gr_poly
		(pts
			(arc
				(start 124.066808 -29.589984)
				(mid 123.773692 -29.589984)
				(end 124.066808 -29.589984)
			)
		)
		(stroke
			(width 0)
			(type solid)
		)
		(fill yes)
		(layer "In13.Cu")
		(net "GND")
	)
	(gr_poly
		(pts
			(arc
				(start 124.217938 -217.681302)
				(mid 123.924822 -217.681302)
				(end 124.217938 -217.681302)
			)
		)
		(stroke
			(width 0)
			(type solid)
		)
		(fill yes)
		(layer "In13.Cu")
		(net "GND")
	)
	(gr_poly
		(pts
			(arc
				(start 124.701808 -33.189926)
				(mid 124.408692 -33.189926)
				(end 124.701808 -33.189926)
			)
		)
		(stroke
			(width 0)
			(type solid)
		)
		(fill yes)
		(layer "In13.Cu")
		(net "GND")
	)
	(gr_poly
		(pts
			(arc
				(start 124.701808 -31.389828)
				(mid 124.408692 -31.389828)
				(end 124.701808 -31.389828)
			)
		)
		(stroke
			(width 0)
			(type solid)
		)
		(fill yes)
		(layer "In13.Cu")
		(net "GND")
	)
	(gr_poly
		(pts
			(arc
				(start 124.701808 -29.589984)
				(mid 124.408692 -29.589984)
				(end 124.701808 -29.589984)
			)
		)
		(stroke
			(width 0)
			(type solid)
		)
		(fill yes)
		(layer "In13.Cu")
		(net "GND")
	)
	(gr_poly
		(pts
			(arc
				(start 124.701808 -27.789886)
				(mid 124.408692 -27.789886)
				(end 124.701808 -27.789886)
			)
		)
		(stroke
			(width 0)
			(type solid)
		)
		(fill yes)
		(layer "In13.Cu")
		(net "GND")
	)
	(gr_poly
		(pts
			(arc
				(start 127.043942 -244.846602)
				(mid 126.750826 -244.846602)
				(end 127.043942 -244.846602)
			)
		)
		(stroke
			(width 0)
			(type solid)
		)
		(fill yes)
		(layer "In13.Cu")
		(net "GND")
	)
	(gr_poly
		(pts
			(arc
				(start 130.927856 -241.856006)
				(mid 130.63474 -241.856006)
				(end 130.927856 -241.856006)
			)
		)
		(stroke
			(width 0)
			(type solid)
		)
		(fill yes)
		(layer "In13.Cu")
		(net "GND")
	)
	(gr_poly
		(pts
			(arc
				(start 131.275836 -238.545878)
				(mid 130.98272 -238.545878)
				(end 131.275836 -238.545878)
			)
		)
		(stroke
			(width 0)
			(type solid)
		)
		(fill yes)
		(layer "In13.Cu")
		(net "GND")
	)
	(gr_poly
		(pts
			(arc
				(start 143.205454 -24.590248)
				(mid 142.912338 -24.590248)
				(end 143.205454 -24.590248)
			)
		)
		(stroke
			(width 0)
			(type solid)
		)
		(fill yes)
		(layer "In13.Cu")
		(net "GND")
	)
	(gr_poly
		(pts
			(arc
				(start 146.100292 -196.271642)
				(mid 145.807176 -196.271642)
				(end 146.100292 -196.271642)
			)
		)
		(stroke
			(width 0)
			(type solid)
		)
		(fill yes)
		(layer "In13.Cu")
		(net "GND")
	)
	(gr_poly
		(pts
			(arc
				(start 148.847556 -34.98977)
				(mid 148.55444 -34.98977)
				(end 148.847556 -34.98977)
			)
		)
		(stroke
			(width 0)
			(type solid)
		)
		(fill yes)
		(layer "In13.Cu")
		(net "GND")
	)
	(gr_poly
		(pts
			(arc
				(start 148.847556 -33.189926)
				(mid 148.55444 -33.189926)
				(end 148.847556 -33.189926)
			)
		)
		(stroke
			(width 0)
			(type solid)
		)
		(fill yes)
		(layer "In13.Cu")
		(net "GND")
	)
	(gr_poly
		(pts
			(arc
				(start 148.847556 -31.389828)
				(mid 148.55444 -31.389828)
				(end 148.847556 -31.389828)
			)
		)
		(stroke
			(width 0)
			(type solid)
		)
		(fill yes)
		(layer "In13.Cu")
		(net "GND")
	)
	(gr_poly
		(pts
			(arc
				(start 148.847556 -29.589984)
				(mid 148.55444 -29.589984)
				(end 148.847556 -29.589984)
			)
		)
		(stroke
			(width 0)
			(type solid)
		)
		(fill yes)
		(layer "In13.Cu")
		(net "GND")
	)
	(gr_poly
		(pts
			(arc
				(start 150.066756 -34.98977)
				(mid 149.77364 -34.98977)
				(end 150.066756 -34.98977)
			)
		)
		(stroke
			(width 0)
			(type solid)
		)
		(fill yes)
		(layer "In13.Cu")
		(net "GND")
	)
	(gr_poly
		(pts
			(arc
				(start 150.066756 -33.189926)
				(mid 149.77364 -33.189926)
				(end 150.066756 -33.189926)
			)
		)
		(stroke
			(width 0)
			(type solid)
		)
		(fill yes)
		(layer "In13.Cu")
		(net "GND")
	)
	(gr_poly
		(pts
			(arc
				(start 150.066756 -31.389828)
				(mid 149.77364 -31.389828)
				(end 150.066756 -31.389828)
			)
		)
		(stroke
			(width 0)
			(type solid)
		)
		(fill yes)
		(layer "In13.Cu")
		(net "GND")
	)
	(gr_poly
		(pts
			(arc
				(start 150.066756 -29.589984)
				(mid 149.77364 -29.589984)
				(end 150.066756 -29.589984)
			)
		)
		(stroke
			(width 0)
			(type solid)
		)
		(fill yes)
		(layer "In13.Cu")
		(net "GND")
	)
	(gr_poly
		(pts
			(arc
				(start 150.701756 -33.189926)
				(mid 150.40864 -33.189926)
				(end 150.701756 -33.189926)
			)
		)
		(stroke
			(width 0)
			(type solid)
		)
		(fill yes)
		(layer "In13.Cu")
		(net "GND")
	)
	(gr_poly
		(pts
			(arc
				(start 150.701756 -31.389828)
				(mid 150.40864 -31.389828)
				(end 150.701756 -31.389828)
			)
		)
		(stroke
			(width 0)
			(type solid)
		)
		(fill yes)
		(layer "In13.Cu")
		(net "GND")
	)
	(gr_poly
		(pts
			(arc
				(start 150.701756 -29.589984)
				(mid 150.40864 -29.589984)
				(end 150.701756 -29.589984)
			)
		)
		(stroke
			(width 0)
			(type solid)
		)
		(fill yes)
		(layer "In13.Cu")
		(net "GND")
	)
	(gr_poly
		(pts
			(arc
				(start 150.701756 -27.789886)
				(mid 150.40864 -27.789886)
				(end 150.701756 -27.789886)
			)
		)
		(stroke
			(width 0)
			(type solid)
		)
		(fill yes)
		(layer "In13.Cu")
		(net "GND")
	)
	(gr_poly
		(pts
			(arc
				(start 150.738332 -135.095488)
				(mid 150.445216 -135.095488)
				(end 150.738332 -135.095488)
			)
		)
		(stroke
			(width 0)
			(type solid)
		)
		(fill yes)
		(layer "In13.Cu")
		(net "GND")
	)
	(gr_poly
		(pts
			(arc
				(start 150.738332 -133.836664)
				(mid 150.445216 -133.836664)
				(end 150.738332 -133.836664)
			)
		)
		(stroke
			(width 0)
			(type solid)
		)
		(fill yes)
		(layer "In13.Cu")
		(net "GND")
	)
	(gr_poly
		(pts
			(arc
				(start 150.738332 -131.495546)
				(mid 150.445216 -131.495546)
				(end 150.738332 -131.495546)
			)
		)
		(stroke
			(width 0)
			(type solid)
		)
		(fill yes)
		(layer "In13.Cu")
		(net "GND")
	)
	(gr_poly
		(pts
			(arc
				(start 150.738332 -123.885452)
				(mid 150.445216 -123.885452)
				(end 150.738332 -123.885452)
			)
		)
		(stroke
			(width 0)
			(type solid)
		)
		(fill yes)
		(layer "In13.Cu")
		(net "GND")
	)
	(gr_poly
		(pts
			(arc
				(start 150.738332 -122.626628)
				(mid 150.445216 -122.626628)
				(end 150.738332 -122.626628)
			)
		)
		(stroke
			(width 0)
			(type solid)
		)
		(fill yes)
		(layer "In13.Cu")
		(net "GND")
	)
	(gr_poly
		(pts
			(arc
				(start 150.738332 -120.28551)
				(mid 150.445216 -120.28551)
				(end 150.738332 -120.28551)
			)
		)
		(stroke
			(width 0)
			(type solid)
		)
		(fill yes)
		(layer "In13.Cu")
		(net "GND")
	)
	(gr_poly
		(pts
			(arc
				(start 150.738332 -119.026686)
				(mid 150.445216 -119.026686)
				(end 150.738332 -119.026686)
			)
		)
		(stroke
			(width 0)
			(type solid)
		)
		(fill yes)
		(layer "In13.Cu")
		(net "GND")
	)
	(gr_poly
		(pts
			(arc
				(start 150.738332 -112.981994)
				(mid 150.445216 -112.981994)
				(end 150.738332 -112.981994)
			)
		)
		(stroke
			(width 0)
			(type solid)
		)
		(fill yes)
		(layer "In13.Cu")
		(net "GND")
	)
	(gr_poly
		(pts
			(arc
				(start 150.738332 -111.72317)
				(mid 150.445216 -111.72317)
				(end 150.738332 -111.72317)
			)
		)
		(stroke
			(width 0)
			(type solid)
		)
		(fill yes)
		(layer "In13.Cu")
		(net "GND")
	)
	(gr_poly
		(pts
			(arc
				(start 150.738332 -109.382052)
				(mid 150.445216 -109.382052)
				(end 150.738332 -109.382052)
			)
		)
		(stroke
			(width 0)
			(type solid)
		)
		(fill yes)
		(layer "In13.Cu")
		(net "GND")
	)
	(gr_poly
		(pts
			(arc
				(start 150.738332 -108.123228)
				(mid 150.445216 -108.123228)
				(end 150.738332 -108.123228)
			)
		)
		(stroke
			(width 0)
			(type solid)
		)
		(fill yes)
		(layer "In13.Cu")
		(net "GND")
	)
	(gr_poly
		(pts
			(arc
				(start 150.738332 -105.78211)
				(mid 150.445216 -105.78211)
				(end 150.738332 -105.78211)
			)
		)
		(stroke
			(width 0)
			(type solid)
		)
		(fill yes)
		(layer "In13.Cu")
		(net "GND")
	)
	(gr_poly
		(pts
			(arc
				(start 150.738332 -104.523286)
				(mid 150.445216 -104.523286)
				(end 150.738332 -104.523286)
			)
		)
		(stroke
			(width 0)
			(type solid)
		)
		(fill yes)
		(layer "In13.Cu")
		(net "GND")
	)
	(gr_poly
		(pts
			(arc
				(start 151.347932 -102.181914)
				(mid 151.054816 -102.181914)
				(end 151.347932 -102.181914)
			)
		)
		(stroke
			(width 0)
			(type solid)
		)
		(fill yes)
		(layer "In13.Cu")
		(net "GND")
	)
	(gr_poly
		(pts
			(arc
				(start 151.347932 -100.92309)
				(mid 151.054816 -100.92309)
				(end 151.347932 -100.92309)
			)
		)
		(stroke
			(width 0)
			(type solid)
		)
		(fill yes)
		(layer "In13.Cu")
		(net "GND")
	)
	(gr_poly
		(pts
			(arc
				(start 152.0063 -135.095488)
				(mid 151.713184 -135.095488)
				(end 152.0063 -135.095488)
			)
		)
		(stroke
			(width 0)
			(type solid)
		)
		(fill yes)
		(layer "In13.Cu")
		(net "GND")
	)
	(gr_poly
		(pts
			(arc
				(start 152.0063 -133.836664)
				(mid 151.713184 -133.836664)
				(end 152.0063 -133.836664)
			)
		)
		(stroke
			(width 0)
			(type solid)
		)
		(fill yes)
		(layer "In13.Cu")
		(net "GND")
	)
	(gr_poly
		(pts
			(arc
				(start 152.0063 -131.495546)
				(mid 151.713184 -131.495546)
				(end 152.0063 -131.495546)
			)
		)
		(stroke
			(width 0)
			(type solid)
		)
		(fill yes)
		(layer "In13.Cu")
		(net "GND")
	)
	(gr_poly
		(pts
			(arc
				(start 152.0063 -123.885452)
				(mid 151.713184 -123.885452)
				(end 152.0063 -123.885452)
			)
		)
		(stroke
			(width 0)
			(type solid)
		)
		(fill yes)
		(layer "In13.Cu")
		(net "GND")
	)
	(gr_poly
		(pts
			(arc
				(start 152.0063 -122.626628)
				(mid 151.713184 -122.626628)
				(end 152.0063 -122.626628)
			)
		)
		(stroke
			(width 0)
			(type solid)
		)
		(fill yes)
		(layer "In13.Cu")
		(net "GND")
	)
	(gr_poly
		(pts
			(arc
				(start 152.0063 -120.28551)
				(mid 151.713184 -120.28551)
				(end 152.0063 -120.28551)
			)
		)
		(stroke
			(width 0)
			(type solid)
		)
		(fill yes)
		(layer "In13.Cu")
		(net "GND")
	)
	(gr_poly
		(pts
			(arc
				(start 152.0063 -119.026686)
				(mid 151.713184 -119.026686)
				(end 152.0063 -119.026686)
			)
		)
		(stroke
			(width 0)
			(type solid)
		)
		(fill yes)
		(layer "In13.Cu")
		(net "GND")
	)
	(gr_poly
		(pts
			(arc
				(start 152.0063 -112.981994)
				(mid 151.713184 -112.981994)
				(end 152.0063 -112.981994)
			)
		)
		(stroke
			(width 0)
			(type solid)
		)
		(fill yes)
		(layer "In13.Cu")
		(net "GND")
	)
	(gr_poly
		(pts
			(arc
				(start 152.0063 -111.72317)
				(mid 151.713184 -111.72317)
				(end 152.0063 -111.72317)
			)
		)
		(stroke
			(width 0)
			(type solid)
		)
		(fill yes)
		(layer "In13.Cu")
		(net "GND")
	)
	(gr_poly
		(pts
			(arc
				(start 152.0063 -109.382052)
				(mid 151.713184 -109.382052)
				(end 152.0063 -109.382052)
			)
		)
		(stroke
			(width 0)
			(type solid)
		)
		(fill yes)
		(layer "In13.Cu")
		(net "GND")
	)
	(gr_poly
		(pts
			(arc
				(start 152.0063 -108.123228)
				(mid 151.713184 -108.123228)
				(end 152.0063 -108.123228)
			)
		)
		(stroke
			(width 0)
			(type solid)
		)
		(fill yes)
		(layer "In13.Cu")
		(net "GND")
	)
	(gr_poly
		(pts
			(arc
				(start 152.0063 -105.78211)
				(mid 151.713184 -105.78211)
				(end 152.0063 -105.78211)
			)
		)
		(stroke
			(width 0)
			(type solid)
		)
		(fill yes)
		(layer "In13.Cu")
		(net "GND")
	)
	(gr_poly
		(pts
			(arc
				(start 152.0063 -104.523286)
				(mid 151.713184 -104.523286)
				(end 152.0063 -104.523286)
			)
		)
		(stroke
			(width 0)
			(type solid)
		)
		(fill yes)
		(layer "In13.Cu")
		(net "GND")
	)
	(gr_poly
		(pts
			(arc
				(start 152.6159 -102.181914)
				(mid 152.322784 -102.181914)
				(end 152.6159 -102.181914)
			)
		)
		(stroke
			(width 0)
			(type solid)
		)
		(fill yes)
		(layer "In13.Cu")
		(net "GND")
	)
	(gr_poly
		(pts
			(arc
				(start 152.6159 -100.92309)
				(mid 152.322784 -100.92309)
				(end 152.6159 -100.92309)
			)
		)
		(stroke
			(width 0)
			(type solid)
		)
		(fill yes)
		(layer "In13.Cu")
		(net "GND")
	)
	(gr_poly
		(pts
			(arc
				(start 153.152602 -238.99368)
				(mid 152.859486 -238.99368)
				(end 153.152602 -238.99368)
			)
		)
		(stroke
			(width 0)
			(type solid)
		)
		(fill yes)
		(layer "In13.Cu")
		(net "GND")
	)
	(gr_poly
		(pts
			(arc
				(start 153.38044 -136.901936)
				(mid 153.087324 -136.901936)
				(end 153.38044 -136.901936)
			)
		)
		(stroke
			(width 0)
			(type solid)
		)
		(fill yes)
		(layer "In13.Cu")
		(net "GND")
	)
	(gr_poly
		(pts
			(arc
				(start 153.38044 -135.643112)
				(mid 153.087324 -135.643112)
				(end 153.38044 -135.643112)
			)
		)
		(stroke
			(width 0)
			(type solid)
		)
		(fill yes)
		(layer "In13.Cu")
		(net "GND")
	)
	(gr_poly
		(pts
			(arc
				(start 153.38044 -133.301994)
				(mid 153.087324 -133.301994)
				(end 153.38044 -133.301994)
			)
		)
		(stroke
			(width 0)
			(type solid)
		)
		(fill yes)
		(layer "In13.Cu")
		(net "GND")
	)
	(gr_poly
		(pts
			(arc
				(start 153.38044 -132.04317)
				(mid 153.087324 -132.04317)
				(end 153.38044 -132.04317)
			)
		)
		(stroke
			(width 0)
			(type solid)
		)
		(fill yes)
		(layer "In13.Cu")
		(net "GND")
	)
	(gr_poly
		(pts
			(arc
				(start 153.38044 -125.692154)
				(mid 153.087324 -125.692154)
				(end 153.38044 -125.692154)
			)
		)
		(stroke
			(width 0)
			(type solid)
		)
		(fill yes)
		(layer "In13.Cu")
		(net "GND")
	)
	(gr_poly
		(pts
			(arc
				(start 153.38044 -124.43333)
				(mid 153.087324 -124.43333)
				(end 153.38044 -124.43333)
			)
		)
		(stroke
			(width 0)
			(type solid)
		)
		(fill yes)
		(layer "In13.Cu")
		(net "GND")
	)
	(gr_poly
		(pts
			(arc
				(start 153.38044 -122.091958)
				(mid 153.087324 -122.091958)
				(end 153.38044 -122.091958)
			)
		)
		(stroke
			(width 0)
			(type solid)
		)
		(fill yes)
		(layer "In13.Cu")
		(net "GND")
	)
	(gr_poly
		(pts
			(arc
				(start 153.38044 -120.833134)
				(mid 153.087324 -120.833134)
				(end 153.38044 -120.833134)
			)
		)
		(stroke
			(width 0)
			(type solid)
		)
		(fill yes)
		(layer "In13.Cu")
		(net "GND")
	)
	(gr_poly
		(pts
			(arc
				(start 153.38044 -111.175546)
				(mid 153.087324 -111.175546)
				(end 153.38044 -111.175546)
			)
		)
		(stroke
			(width 0)
			(type solid)
		)
		(fill yes)
		(layer "In13.Cu")
		(net "GND")
	)
	(gr_poly
		(pts
			(arc
				(start 153.38044 -109.916722)
				(mid 153.087324 -109.916722)
				(end 153.38044 -109.916722)
			)
		)
		(stroke
			(width 0)
			(type solid)
		)
		(fill yes)
		(layer "In13.Cu")
		(net "GND")
	)
	(gr_poly
		(pts
			(arc
				(start 153.38044 -107.57535)
				(mid 153.087324 -107.57535)
				(end 153.38044 -107.57535)
			)
		)
		(stroke
			(width 0)
			(type solid)
		)
		(fill yes)
		(layer "In13.Cu")
		(net "GND")
	)
	(gr_poly
		(pts
			(arc
				(start 153.38044 -106.316526)
				(mid 153.087324 -106.316526)
				(end 153.38044 -106.316526)
			)
		)
		(stroke
			(width 0)
			(type solid)
		)
		(fill yes)
		(layer "In13.Cu")
		(net "GND")
	)
	(gr_poly
		(pts
			(arc
				(start 153.38044 -103.975408)
				(mid 153.087324 -103.975408)
				(end 153.38044 -103.975408)
			)
		)
		(stroke
			(width 0)
			(type solid)
		)
		(fill yes)
		(layer "In13.Cu")
		(net "GND")
	)
	(gr_poly
		(pts
			(arc
				(start 153.38044 -102.716584)
				(mid 153.087324 -102.716584)
				(end 153.38044 -102.716584)
			)
		)
		(stroke
			(width 0)
			(type solid)
		)
		(fill yes)
		(layer "In13.Cu")
		(net "GND")
	)
	(gr_poly
		(pts
			(arc
				(start 153.38044 -100.375466)
				(mid 153.087324 -100.375466)
				(end 153.38044 -100.375466)
			)
		)
		(stroke
			(width 0)
			(type solid)
		)
		(fill yes)
		(layer "In13.Cu")
		(net "GND")
	)
	(gr_poly
		(pts
			(arc
				(start 153.38044 -99.116642)
				(mid 153.087324 -99.116642)
				(end 153.38044 -99.116642)
			)
		)
		(stroke
			(width 0)
			(type solid)
		)
		(fill yes)
		(layer "In13.Cu")
		(net "GND")
	)
	(gr_poly
		(pts
			(arc
				(start 154.648408 -136.901936)
				(mid 154.355292 -136.901936)
				(end 154.648408 -136.901936)
			)
		)
		(stroke
			(width 0)
			(type solid)
		)
		(fill yes)
		(layer "In13.Cu")
		(net "GND")
	)
	(gr_poly
		(pts
			(arc
				(start 154.648408 -135.643112)
				(mid 154.355292 -135.643112)
				(end 154.648408 -135.643112)
			)
		)
		(stroke
			(width 0)
			(type solid)
		)
		(fill yes)
		(layer "In13.Cu")
		(net "GND")
	)
	(gr_poly
		(pts
			(arc
				(start 154.648408 -133.301994)
				(mid 154.355292 -133.301994)
				(end 154.648408 -133.301994)
			)
		)
		(stroke
			(width 0)
			(type solid)
		)
		(fill yes)
		(layer "In13.Cu")
		(net "GND")
	)
	(gr_poly
		(pts
			(arc
				(start 154.648408 -132.04317)
				(mid 154.355292 -132.04317)
				(end 154.648408 -132.04317)
			)
		)
		(stroke
			(width 0)
			(type solid)
		)
		(fill yes)
		(layer "In13.Cu")
		(net "GND")
	)
	(gr_poly
		(pts
			(arc
				(start 154.648408 -125.692154)
				(mid 154.355292 -125.692154)
				(end 154.648408 -125.692154)
			)
		)
		(stroke
			(width 0)
			(type solid)
		)
		(fill yes)
		(layer "In13.Cu")
		(net "GND")
	)
	(gr_poly
		(pts
			(arc
				(start 154.648408 -124.43333)
				(mid 154.355292 -124.43333)
				(end 154.648408 -124.43333)
			)
		)
		(stroke
			(width 0)
			(type solid)
		)
		(fill yes)
		(layer "In13.Cu")
		(net "GND")
	)
	(gr_poly
		(pts
			(arc
				(start 154.648408 -122.091958)
				(mid 154.355292 -122.091958)
				(end 154.648408 -122.091958)
			)
		)
		(stroke
			(width 0)
			(type solid)
		)
		(fill yes)
		(layer "In13.Cu")
		(net "GND")
	)
	(gr_poly
		(pts
			(arc
				(start 154.648408 -120.833134)
				(mid 154.355292 -120.833134)
				(end 154.648408 -120.833134)
			)
		)
		(stroke
			(width 0)
			(type solid)
		)
		(fill yes)
		(layer "In13.Cu")
		(net "GND")
	)
	(gr_poly
		(pts
			(arc
				(start 154.648408 -111.175546)
				(mid 154.355292 -111.175546)
				(end 154.648408 -111.175546)
			)
		)
		(stroke
			(width 0)
			(type solid)
		)
		(fill yes)
		(layer "In13.Cu")
		(net "GND")
	)
	(gr_poly
		(pts
			(arc
				(start 154.648408 -109.916722)
				(mid 154.355292 -109.916722)
				(end 154.648408 -109.916722)
			)
		)
		(stroke
			(width 0)
			(type solid)
		)
		(fill yes)
		(layer "In13.Cu")
		(net "GND")
	)
	(gr_poly
		(pts
			(arc
				(start 154.648408 -107.57535)
				(mid 154.355292 -107.57535)
				(end 154.648408 -107.57535)
			)
		)
		(stroke
			(width 0)
			(type solid)
		)
		(fill yes)
		(layer "In13.Cu")
		(net "GND")
	)
	(gr_poly
		(pts
			(arc
				(start 154.648408 -106.316526)
				(mid 154.355292 -106.316526)
				(end 154.648408 -106.316526)
			)
		)
		(stroke
			(width 0)
			(type solid)
		)
		(fill yes)
		(layer "In13.Cu")
		(net "GND")
	)
	(gr_poly
		(pts
			(arc
				(start 154.648408 -103.975408)
				(mid 154.355292 -103.975408)
				(end 154.648408 -103.975408)
			)
		)
		(stroke
			(width 0)
			(type solid)
		)
		(fill yes)
		(layer "In13.Cu")
		(net "GND")
	)
	(gr_poly
		(pts
			(arc
				(start 154.648408 -102.716584)
				(mid 154.355292 -102.716584)
				(end 154.648408 -102.716584)
			)
		)
		(stroke
			(width 0)
			(type solid)
		)
		(fill yes)
		(layer "In13.Cu")
		(net "GND")
	)
	(gr_poly
		(pts
			(arc
				(start 154.648408 -100.375466)
				(mid 154.355292 -100.375466)
				(end 154.648408 -100.375466)
			)
		)
		(stroke
			(width 0)
			(type solid)
		)
		(fill yes)
		(layer "In13.Cu")
		(net "GND")
	)
	(gr_poly
		(pts
			(arc
				(start 154.648408 -99.116642)
				(mid 154.355292 -99.116642)
				(end 154.648408 -99.116642)
			)
		)
		(stroke
			(width 0)
			(type solid)
		)
		(fill yes)
		(layer "In13.Cu")
		(net "GND")
	)
	(gr_poly
		(pts
			(arc
				(start 155.719018 -239.020096)
				(mid 155.425902 -239.020096)
				(end 155.719018 -239.020096)
			)
		)
		(stroke
			(width 0)
			(type solid)
		)
		(fill yes)
		(layer "In13.Cu")
		(net "GND")
	)
	(gr_poly
		(pts
			(arc
				(start 169.098976 -137.164826)
				(mid 168.80586 -137.164826)
				(end 169.098976 -137.164826)
			)
		)
		(stroke
			(width 0)
			(type solid)
		)
		(fill yes)
		(layer "In13.Cu")
		(net "GND")
	)
	(gr_poly
		(pts
			(arc
				(start 169.098976 -135.364728)
				(mid 168.80586 -135.364728)
				(end 169.098976 -135.364728)
			)
		)
		(stroke
			(width 0)
			(type solid)
		)
		(fill yes)
		(layer "In13.Cu")
		(net "GND")
	)
	(gr_poly
		(pts
			(arc
				(start 169.098976 -133.56463)
				(mid 168.80586 -133.56463)
				(end 169.098976 -133.56463)
			)
		)
		(stroke
			(width 0)
			(type solid)
		)
		(fill yes)
		(layer "In13.Cu")
		(net "GND")
	)
	(gr_poly
		(pts
			(arc
				(start 169.098976 -131.764786)
				(mid 168.80586 -131.764786)
				(end 169.098976 -131.764786)
			)
		)
		(stroke
			(width 0)
			(type solid)
		)
		(fill yes)
		(layer "In13.Cu")
		(net "GND")
	)
	(gr_poly
		(pts
			(arc
				(start 169.098976 -125.95479)
				(mid 168.80586 -125.95479)
				(end 169.098976 -125.95479)
			)
		)
		(stroke
			(width 0)
			(type solid)
		)
		(fill yes)
		(layer "In13.Cu")
		(net "GND")
	)
	(gr_poly
		(pts
			(arc
				(start 169.098976 -124.154692)
				(mid 168.80586 -124.154692)
				(end 169.098976 -124.154692)
			)
		)
		(stroke
			(width 0)
			(type solid)
		)
		(fill yes)
		(layer "In13.Cu")
		(net "GND")
	)
	(gr_poly
		(pts
			(arc
				(start 169.098976 -122.354594)
				(mid 168.80586 -122.354594)
				(end 169.098976 -122.354594)
			)
		)
		(stroke
			(width 0)
			(type solid)
		)
		(fill yes)
		(layer "In13.Cu")
		(net "GND")
	)
	(gr_poly
		(pts
			(arc
				(start 169.098976 -120.55475)
				(mid 168.80586 -120.55475)
				(end 169.098976 -120.55475)
			)
		)
		(stroke
			(width 0)
			(type solid)
		)
		(fill yes)
		(layer "In13.Cu")
		(net "GND")
	)
	(gr_poly
		(pts
			(arc
				(start 169.098976 -113.244884)
				(mid 168.80586 -113.244884)
				(end 169.098976 -113.244884)
			)
		)
		(stroke
			(width 0)
			(type solid)
		)
		(fill yes)
		(layer "In13.Cu")
		(net "GND")
	)
	(gr_poly
		(pts
			(arc
				(start 169.098976 -111.444786)
				(mid 168.80586 -111.444786)
				(end 169.098976 -111.444786)
			)
		)
		(stroke
			(width 0)
			(type solid)
		)
		(fill yes)
		(layer "In13.Cu")
		(net "GND")
	)
	(gr_poly
		(pts
			(arc
				(start 169.098976 -109.644688)
				(mid 168.80586 -109.644688)
				(end 169.098976 -109.644688)
			)
		)
		(stroke
			(width 0)
			(type solid)
		)
		(fill yes)
		(layer "In13.Cu")
		(net "GND")
	)
	(gr_poly
		(pts
			(arc
				(start 169.098976 -107.84459)
				(mid 168.80586 -107.84459)
				(end 169.098976 -107.84459)
			)
		)
		(stroke
			(width 0)
			(type solid)
		)
		(fill yes)
		(layer "In13.Cu")
		(net "GND")
	)
	(gr_poly
		(pts
			(arc
				(start 169.098976 -106.044746)
				(mid 168.80586 -106.044746)
				(end 169.098976 -106.044746)
			)
		)
		(stroke
			(width 0)
			(type solid)
		)
		(fill yes)
		(layer "In13.Cu")
		(net "GND")
	)
	(gr_poly
		(pts
			(arc
				(start 169.098976 -104.244648)
				(mid 168.80586 -104.244648)
				(end 169.098976 -104.244648)
			)
		)
		(stroke
			(width 0)
			(type solid)
		)
		(fill yes)
		(layer "In13.Cu")
		(net "GND")
	)
	(gr_poly
		(pts
			(arc
				(start 169.098976 -102.444804)
				(mid 168.80586 -102.444804)
				(end 169.098976 -102.444804)
			)
		)
		(stroke
			(width 0)
			(type solid)
		)
		(fill yes)
		(layer "In13.Cu")
		(net "GND")
	)
	(gr_poly
		(pts
			(arc
				(start 169.098976 -100.644706)
				(mid 168.80586 -100.644706)
				(end 169.098976 -100.644706)
			)
		)
		(stroke
			(width 0)
			(type solid)
		)
		(fill yes)
		(layer "In13.Cu")
		(net "GND")
	)
	(gr_poly
		(pts
			(arc
				(start 169.164 -24.600408)
				(mid 168.870884 -24.600408)
				(end 169.164 -24.600408)
			)
		)
		(stroke
			(width 0)
			(type solid)
		)
		(fill yes)
		(layer "In13.Cu")
		(net "GND")
	)
	(gr_poly
		(pts
			(arc
				(start 169.733976 -135.364728)
				(mid 169.44086 -135.364728)
				(end 169.733976 -135.364728)
			)
		)
		(stroke
			(width 0)
			(type solid)
		)
		(fill yes)
		(layer "In13.Cu")
		(net "GND")
	)
	(gr_poly
		(pts
			(arc
				(start 169.733976 -133.56463)
				(mid 169.44086 -133.56463)
				(end 169.733976 -133.56463)
			)
		)
		(stroke
			(width 0)
			(type solid)
		)
		(fill yes)
		(layer "In13.Cu")
		(net "GND")
	)
	(gr_poly
		(pts
			(arc
				(start 169.733976 -131.764786)
				(mid 169.44086 -131.764786)
				(end 169.733976 -131.764786)
			)
		)
		(stroke
			(width 0)
			(type solid)
		)
		(fill yes)
		(layer "In13.Cu")
		(net "GND")
	)
	(gr_poly
		(pts
			(arc
				(start 169.733976 -129.964688)
				(mid 169.44086 -129.964688)
				(end 169.733976 -129.964688)
			)
		)
		(stroke
			(width 0)
			(type solid)
		)
		(fill yes)
		(layer "In13.Cu")
		(net "GND")
	)
	(gr_poly
		(pts
			(arc
				(start 169.733976 -124.154692)
				(mid 169.44086 -124.154692)
				(end 169.733976 -124.154692)
			)
		)
		(stroke
			(width 0)
			(type solid)
		)
		(fill yes)
		(layer "In13.Cu")
		(net "GND")
	)
	(gr_poly
		(pts
			(arc
				(start 169.733976 -122.354594)
				(mid 169.44086 -122.354594)
				(end 169.733976 -122.354594)
			)
		)
		(stroke
			(width 0)
			(type solid)
		)
		(fill yes)
		(layer "In13.Cu")
		(net "GND")
	)
	(gr_poly
		(pts
			(arc
				(start 169.733976 -120.55475)
				(mid 169.44086 -120.55475)
				(end 169.733976 -120.55475)
			)
		)
		(stroke
			(width 0)
			(type solid)
		)
		(fill yes)
		(layer "In13.Cu")
		(net "GND")
	)
	(gr_poly
		(pts
			(arc
				(start 169.733976 -118.754652)
				(mid 169.44086 -118.754652)
				(end 169.733976 -118.754652)
			)
		)
		(stroke
			(width 0)
			(type solid)
		)
		(fill yes)
		(layer "In13.Cu")
		(net "GND")
	)
	(gr_poly
		(pts
			(arc
				(start 169.733976 -111.444786)
				(mid 169.44086 -111.444786)
				(end 169.733976 -111.444786)
			)
		)
		(stroke
			(width 0)
			(type solid)
		)
		(fill yes)
		(layer "In13.Cu")
		(net "GND")
	)
	(gr_poly
		(pts
			(arc
				(start 169.733976 -109.644688)
				(mid 169.44086 -109.644688)
				(end 169.733976 -109.644688)
			)
		)
		(stroke
			(width 0)
			(type solid)
		)
		(fill yes)
		(layer "In13.Cu")
		(net "GND")
	)
	(gr_poly
		(pts
			(arc
				(start 169.733976 -107.84459)
				(mid 169.44086 -107.84459)
				(end 169.733976 -107.84459)
			)
		)
		(stroke
			(width 0)
			(type solid)
		)
		(fill yes)
		(layer "In13.Cu")
		(net "GND")
	)
	(gr_poly
		(pts
			(arc
				(start 169.733976 -106.044492)
				(mid 169.44086 -106.044492)
				(end 169.733976 -106.044492)
			)
		)
		(stroke
			(width 0)
			(type solid)
		)
		(fill yes)
		(layer "In13.Cu")
		(net "GND")
	)
	(gr_poly
		(pts
			(arc
				(start 169.733976 -104.244648)
				(mid 169.44086 -104.244648)
				(end 169.733976 -104.244648)
			)
		)
		(stroke
			(width 0)
			(type solid)
		)
		(fill yes)
		(layer "In13.Cu")
		(net "GND")
	)
	(gr_poly
		(pts
			(arc
				(start 169.733976 -102.44455)
				(mid 169.44086 -102.44455)
				(end 169.733976 -102.44455)
			)
		)
		(stroke
			(width 0)
			(type solid)
		)
		(fill yes)
		(layer "In13.Cu")
		(net "GND")
	)
	(gr_poly
		(pts
			(arc
				(start 169.733976 -100.644706)
				(mid 169.44086 -100.644706)
				(end 169.733976 -100.644706)
			)
		)
		(stroke
			(width 0)
			(type solid)
		)
		(fill yes)
		(layer "In13.Cu")
		(net "GND")
	)
	(gr_poly
		(pts
			(arc
				(start 169.733976 -98.844608)
				(mid 169.44086 -98.844608)
				(end 169.733976 -98.844608)
			)
		)
		(stroke
			(width 0)
			(type solid)
		)
		(fill yes)
		(layer "In13.Cu")
		(net "GND")
	)
	(gr_poly
		(pts
			(arc
				(start 170.953176 -135.364728)
				(mid 170.66006 -135.364728)
				(end 170.953176 -135.364728)
			)
		)
		(stroke
			(width 0)
			(type solid)
		)
		(fill yes)
		(layer "In13.Cu")
		(net "GND")
	)
	(gr_poly
		(pts
			(arc
				(start 170.953176 -133.56463)
				(mid 170.66006 -133.56463)
				(end 170.953176 -133.56463)
			)
		)
		(stroke
			(width 0)
			(type solid)
		)
		(fill yes)
		(layer "In13.Cu")
		(net "GND")
	)
	(gr_poly
		(pts
			(arc
				(start 170.953176 -131.764786)
				(mid 170.66006 -131.764786)
				(end 170.953176 -131.764786)
			)
		)
		(stroke
			(width 0)
			(type solid)
		)
		(fill yes)
		(layer "In13.Cu")
		(net "GND")
	)
	(gr_poly
		(pts
			(arc
				(start 170.953176 -129.964688)
				(mid 170.66006 -129.964688)
				(end 170.953176 -129.964688)
			)
		)
		(stroke
			(width 0)
			(type solid)
		)
		(fill yes)
		(layer "In13.Cu")
		(net "GND")
	)
	(gr_poly
		(pts
			(arc
				(start 170.953176 -124.154692)
				(mid 170.66006 -124.154692)
				(end 170.953176 -124.154692)
			)
		)
		(stroke
			(width 0)
			(type solid)
		)
		(fill yes)
		(layer "In13.Cu")
		(net "GND")
	)
	(gr_poly
		(pts
			(arc
				(start 170.953176 -122.354594)
				(mid 170.66006 -122.354594)
				(end 170.953176 -122.354594)
			)
		)
		(stroke
			(width 0)
			(type solid)
		)
		(fill yes)
		(layer "In13.Cu")
		(net "GND")
	)
	(gr_poly
		(pts
			(arc
				(start 170.953176 -120.55475)
				(mid 170.66006 -120.55475)
				(end 170.953176 -120.55475)
			)
		)
		(stroke
			(width 0)
			(type solid)
		)
		(fill yes)
		(layer "In13.Cu")
		(net "GND")
	)
	(gr_poly
		(pts
			(arc
				(start 170.953176 -118.754652)
				(mid 170.66006 -118.754652)
				(end 170.953176 -118.754652)
			)
		)
		(stroke
			(width 0)
			(type solid)
		)
		(fill yes)
		(layer "In13.Cu")
		(net "GND")
	)
	(gr_poly
		(pts
			(arc
				(start 170.953176 -111.444786)
				(mid 170.66006 -111.444786)
				(end 170.953176 -111.444786)
			)
		)
		(stroke
			(width 0)
			(type solid)
		)
		(fill yes)
		(layer "In13.Cu")
		(net "GND")
	)
	(gr_poly
		(pts
			(arc
				(start 170.953176 -109.644688)
				(mid 170.66006 -109.644688)
				(end 170.953176 -109.644688)
			)
		)
		(stroke
			(width 0)
			(type solid)
		)
		(fill yes)
		(layer "In13.Cu")
		(net "GND")
	)
	(gr_poly
		(pts
			(arc
				(start 170.953176 -107.84459)
				(mid 170.66006 -107.84459)
				(end 170.953176 -107.84459)
			)
		)
		(stroke
			(width 0)
			(type solid)
		)
		(fill yes)
		(layer "In13.Cu")
		(net "GND")
	)
	(gr_poly
		(pts
			(arc
				(start 170.953176 -106.044492)
				(mid 170.66006 -106.044492)
				(end 170.953176 -106.044492)
			)
		)
		(stroke
			(width 0)
			(type solid)
		)
		(fill yes)
		(layer "In13.Cu")
		(net "GND")
	)
	(gr_poly
		(pts
			(arc
				(start 170.953176 -104.244648)
				(mid 170.66006 -104.244648)
				(end 170.953176 -104.244648)
			)
		)
		(stroke
			(width 0)
			(type solid)
		)
		(fill yes)
		(layer "In13.Cu")
		(net "GND")
	)
	(gr_poly
		(pts
			(arc
				(start 170.953176 -102.44455)
				(mid 170.66006 -102.44455)
				(end 170.953176 -102.44455)
			)
		)
		(stroke
			(width 0)
			(type solid)
		)
		(fill yes)
		(layer "In13.Cu")
		(net "GND")
	)
	(gr_poly
		(pts
			(arc
				(start 170.953176 -100.644706)
				(mid 170.66006 -100.644706)
				(end 170.953176 -100.644706)
			)
		)
		(stroke
			(width 0)
			(type solid)
		)
		(fill yes)
		(layer "In13.Cu")
		(net "GND")
	)
	(gr_poly
		(pts
			(arc
				(start 170.953176 -98.844608)
				(mid 170.66006 -98.844608)
				(end 170.953176 -98.844608)
			)
		)
		(stroke
			(width 0)
			(type solid)
		)
		(fill yes)
		(layer "In13.Cu")
		(net "GND")
	)
	(gr_poly
		(pts
			(arc
				(start 174.847504 -34.98977)
				(mid 174.554388 -34.98977)
				(end 174.847504 -34.98977)
			)
		)
		(stroke
			(width 0)
			(type solid)
		)
		(fill yes)
		(layer "In13.Cu")
		(net "GND")
	)
	(gr_poly
		(pts
			(arc
				(start 174.847504 -33.189672)
				(mid 174.554388 -33.189672)
				(end 174.847504 -33.189672)
			)
		)
		(stroke
			(width 0)
			(type solid)
		)
		(fill yes)
		(layer "In13.Cu")
		(net "GND")
	)
	(gr_poly
		(pts
			(arc
				(start 174.847504 -31.389828)
				(mid 174.554388 -31.389828)
				(end 174.847504 -31.389828)
			)
		)
		(stroke
			(width 0)
			(type solid)
		)
		(fill yes)
		(layer "In13.Cu")
		(net "GND")
	)
	(gr_poly
		(pts
			(arc
				(start 174.847504 -29.58973)
				(mid 174.554388 -29.58973)
				(end 174.847504 -29.58973)
			)
		)
		(stroke
			(width 0)
			(type solid)
		)
		(fill yes)
		(layer "In13.Cu")
		(net "GND")
	)
	(gr_poly
		(pts
			(arc
				(start 176.066704 -34.98977)
				(mid 175.773588 -34.98977)
				(end 176.066704 -34.98977)
			)
		)
		(stroke
			(width 0)
			(type solid)
		)
		(fill yes)
		(layer "In13.Cu")
		(net "GND")
	)
	(gr_poly
		(pts
			(arc
				(start 176.066704 -33.189672)
				(mid 175.773588 -33.189672)
				(end 176.066704 -33.189672)
			)
		)
		(stroke
			(width 0)
			(type solid)
		)
		(fill yes)
		(layer "In13.Cu")
		(net "GND")
	)
	(gr_poly
		(pts
			(arc
				(start 176.066704 -31.389828)
				(mid 175.773588 -31.389828)
				(end 176.066704 -31.389828)
			)
		)
		(stroke
			(width 0)
			(type solid)
		)
		(fill yes)
		(layer "In13.Cu")
		(net "GND")
	)
	(gr_poly
		(pts
			(arc
				(start 176.066704 -29.58973)
				(mid 175.773588 -29.58973)
				(end 176.066704 -29.58973)
			)
		)
		(stroke
			(width 0)
			(type solid)
		)
		(fill yes)
		(layer "In13.Cu")
		(net "GND")
	)
	(gr_poly
		(pts
			(arc
				(start 176.701704 -33.189672)
				(mid 176.408588 -33.189672)
				(end 176.701704 -33.189672)
			)
		)
		(stroke
			(width 0)
			(type solid)
		)
		(fill yes)
		(layer "In13.Cu")
		(net "GND")
	)
	(gr_poly
		(pts
			(arc
				(start 176.701704 -31.389574)
				(mid 176.408588 -31.389574)
				(end 176.701704 -31.389574)
			)
		)
		(stroke
			(width 0)
			(type solid)
		)
		(fill yes)
		(layer "In13.Cu")
		(net "GND")
	)
	(gr_poly
		(pts
			(arc
				(start 176.701704 -29.58973)
				(mid 176.408588 -29.58973)
				(end 176.701704 -29.58973)
			)
		)
		(stroke
			(width 0)
			(type solid)
		)
		(fill yes)
		(layer "In13.Cu")
		(net "GND")
	)
	(gr_poly
		(pts
			(arc
				(start 180.840126 -156.554932)
				(mid 180.54701 -156.554932)
				(end 180.840126 -156.554932)
			)
		)
		(stroke
			(width 0)
			(type solid)
		)
		(fill yes)
		(layer "In13.Cu")
		(net "GND")
	)
	(gr_poly
		(pts
			(arc
				(start 180.840126 -154.754834)
				(mid 180.54701 -154.754834)
				(end 180.840126 -154.754834)
			)
		)
		(stroke
			(width 0)
			(type solid)
		)
		(fill yes)
		(layer "In13.Cu")
		(net "GND")
	)
	(gr_poly
		(pts
			(arc
				(start 180.840126 -152.95499)
				(mid 180.54701 -152.95499)
				(end 180.840126 -152.95499)
			)
		)
		(stroke
			(width 0)
			(type solid)
		)
		(fill yes)
		(layer "In13.Cu")
		(net "GND")
	)
	(gr_poly
		(pts
			(arc
				(start 180.840126 -151.154892)
				(mid 180.54701 -151.154892)
				(end 180.840126 -151.154892)
			)
		)
		(stroke
			(width 0)
			(type solid)
		)
		(fill yes)
		(layer "In13.Cu")
		(net "GND")
	)
	(gr_poly
		(pts
			(arc
				(start 180.840126 -149.355048)
				(mid 180.54701 -149.355048)
				(end 180.840126 -149.355048)
			)
		)
		(stroke
			(width 0)
			(type solid)
		)
		(fill yes)
		(layer "In13.Cu")
		(net "GND")
	)
	(gr_poly
		(pts
			(arc
				(start 180.840126 -147.55495)
				(mid 180.54701 -147.55495)
				(end 180.840126 -147.55495)
			)
		)
		(stroke
			(width 0)
			(type solid)
		)
		(fill yes)
		(layer "In13.Cu")
		(net "GND")
	)
	(gr_poly
		(pts
			(arc
				(start 180.840126 -145.755106)
				(mid 180.54701 -145.755106)
				(end 180.840126 -145.755106)
			)
		)
		(stroke
			(width 0)
			(type solid)
		)
		(fill yes)
		(layer "In13.Cu")
		(net "GND")
	)
	(gr_poly
		(pts
			(arc
				(start 180.840126 -143.955008)
				(mid 180.54701 -143.955008)
				(end 180.840126 -143.955008)
			)
		)
		(stroke
			(width 0)
			(type solid)
		)
		(fill yes)
		(layer "In13.Cu")
		(net "GND")
	)
	(gr_poly
		(pts
			(arc
				(start 180.840126 -136.644888)
				(mid 180.54701 -136.644888)
				(end 180.840126 -136.644888)
			)
		)
		(stroke
			(width 0)
			(type solid)
		)
		(fill yes)
		(layer "In13.Cu")
		(net "GND")
	)
	(gr_poly
		(pts
			(arc
				(start 180.840126 -134.84479)
				(mid 180.54701 -134.84479)
				(end 180.840126 -134.84479)
			)
		)
		(stroke
			(width 0)
			(type solid)
		)
		(fill yes)
		(layer "In13.Cu")
		(net "GND")
	)
	(gr_poly
		(pts
			(arc
				(start 180.840126 -133.044946)
				(mid 180.54701 -133.044946)
				(end 180.840126 -133.044946)
			)
		)
		(stroke
			(width 0)
			(type solid)
		)
		(fill yes)
		(layer "In13.Cu")
		(net "GND")
	)
	(gr_poly
		(pts
			(arc
				(start 180.840126 -131.244848)
				(mid 180.54701 -131.244848)
				(end 180.840126 -131.244848)
			)
		)
		(stroke
			(width 0)
			(type solid)
		)
		(fill yes)
		(layer "In13.Cu")
		(net "GND")
	)
	(gr_poly
		(pts
			(arc
				(start 180.840126 -125.434852)
				(mid 180.54701 -125.434852)
				(end 180.840126 -125.434852)
			)
		)
		(stroke
			(width 0)
			(type solid)
		)
		(fill yes)
		(layer "In13.Cu")
		(net "GND")
	)
	(gr_poly
		(pts
			(arc
				(start 180.840126 -123.634754)
				(mid 180.54701 -123.634754)
				(end 180.840126 -123.634754)
			)
		)
		(stroke
			(width 0)
			(type solid)
		)
		(fill yes)
		(layer "In13.Cu")
		(net "GND")
	)
	(gr_poly
		(pts
			(arc
				(start 180.840126 -121.83491)
				(mid 180.54701 -121.83491)
				(end 180.840126 -121.83491)
			)
		)
		(stroke
			(width 0)
			(type solid)
		)
		(fill yes)
		(layer "In13.Cu")
		(net "GND")
	)
	(gr_poly
		(pts
			(arc
				(start 180.840126 -120.034812)
				(mid 180.54701 -120.034812)
				(end 180.840126 -120.034812)
			)
		)
		(stroke
			(width 0)
			(type solid)
		)
		(fill yes)
		(layer "In13.Cu")
		(net "GND")
	)
	(gr_poly
		(pts
			(arc
				(start 182.059326 -156.554932)
				(mid 181.76621 -156.554932)
				(end 182.059326 -156.554932)
			)
		)
		(stroke
			(width 0)
			(type solid)
		)
		(fill yes)
		(layer "In13.Cu")
		(net "GND")
	)
	(gr_poly
		(pts
			(arc
				(start 182.059326 -154.754834)
				(mid 181.76621 -154.754834)
				(end 182.059326 -154.754834)
			)
		)
		(stroke
			(width 0)
			(type solid)
		)
		(fill yes)
		(layer "In13.Cu")
		(net "GND")
	)
	(gr_poly
		(pts
			(arc
				(start 182.059326 -152.95499)
				(mid 181.76621 -152.95499)
				(end 182.059326 -152.95499)
			)
		)
		(stroke
			(width 0)
			(type solid)
		)
		(fill yes)
		(layer "In13.Cu")
		(net "GND")
	)
	(gr_poly
		(pts
			(arc
				(start 182.059326 -151.154892)
				(mid 181.76621 -151.154892)
				(end 182.059326 -151.154892)
			)
		)
		(stroke
			(width 0)
			(type solid)
		)
		(fill yes)
		(layer "In13.Cu")
		(net "GND")
	)
	(gr_poly
		(pts
			(arc
				(start 182.059326 -149.355048)
				(mid 181.76621 -149.355048)
				(end 182.059326 -149.355048)
			)
		)
		(stroke
			(width 0)
			(type solid)
		)
		(fill yes)
		(layer "In13.Cu")
		(net "GND")
	)
	(gr_poly
		(pts
			(arc
				(start 182.059326 -147.55495)
				(mid 181.76621 -147.55495)
				(end 182.059326 -147.55495)
			)
		)
		(stroke
			(width 0)
			(type solid)
		)
		(fill yes)
		(layer "In13.Cu")
		(net "GND")
	)
	(gr_poly
		(pts
			(arc
				(start 182.059326 -145.755106)
				(mid 181.76621 -145.755106)
				(end 182.059326 -145.755106)
			)
		)
		(stroke
			(width 0)
			(type solid)
		)
		(fill yes)
		(layer "In13.Cu")
		(net "GND")
	)
	(gr_poly
		(pts
			(arc
				(start 182.059326 -143.955008)
				(mid 181.76621 -143.955008)
				(end 182.059326 -143.955008)
			)
		)
		(stroke
			(width 0)
			(type solid)
		)
		(fill yes)
		(layer "In13.Cu")
		(net "GND")
	)
	(gr_poly
		(pts
			(arc
				(start 182.059326 -136.644888)
				(mid 181.76621 -136.644888)
				(end 182.059326 -136.644888)
			)
		)
		(stroke
			(width 0)
			(type solid)
		)
		(fill yes)
		(layer "In13.Cu")
		(net "GND")
	)
	(gr_poly
		(pts
			(arc
				(start 182.059326 -134.84479)
				(mid 181.76621 -134.84479)
				(end 182.059326 -134.84479)
			)
		)
		(stroke
			(width 0)
			(type solid)
		)
		(fill yes)
		(layer "In13.Cu")
		(net "GND")
	)
	(gr_poly
		(pts
			(arc
				(start 182.059326 -133.044946)
				(mid 181.76621 -133.044946)
				(end 182.059326 -133.044946)
			)
		)
		(stroke
			(width 0)
			(type solid)
		)
		(fill yes)
		(layer "In13.Cu")
		(net "GND")
	)
	(gr_poly
		(pts
			(arc
				(start 182.059326 -131.244848)
				(mid 181.76621 -131.244848)
				(end 182.059326 -131.244848)
			)
		)
		(stroke
			(width 0)
			(type solid)
		)
		(fill yes)
		(layer "In13.Cu")
		(net "GND")
	)
	(gr_poly
		(pts
			(arc
				(start 182.059326 -125.434852)
				(mid 181.76621 -125.434852)
				(end 182.059326 -125.434852)
			)
		)
		(stroke
			(width 0)
			(type solid)
		)
		(fill yes)
		(layer "In13.Cu")
		(net "GND")
	)
	(gr_poly
		(pts
			(arc
				(start 182.059326 -123.634754)
				(mid 181.76621 -123.634754)
				(end 182.059326 -123.634754)
			)
		)
		(stroke
			(width 0)
			(type solid)
		)
		(fill yes)
		(layer "In13.Cu")
		(net "GND")
	)
	(gr_poly
		(pts
			(arc
				(start 182.059326 -121.83491)
				(mid 181.76621 -121.83491)
				(end 182.059326 -121.83491)
			)
		)
		(stroke
			(width 0)
			(type solid)
		)
		(fill yes)
		(layer "In13.Cu")
		(net "GND")
	)
	(gr_poly
		(pts
			(arc
				(start 182.059326 -120.034812)
				(mid 181.76621 -120.034812)
				(end 182.059326 -120.034812)
			)
		)
		(stroke
			(width 0)
			(type solid)
		)
		(fill yes)
		(layer "In13.Cu")
		(net "GND")
	)
	(gr_poly
		(pts
			(arc
				(start 182.694326 -154.754834)
				(mid 182.40121 -154.754834)
				(end 182.694326 -154.754834)
			)
		)
		(stroke
			(width 0)
			(type solid)
		)
		(fill yes)
		(layer "In13.Cu")
		(net "GND")
	)
	(gr_poly
		(pts
			(arc
				(start 182.694326 -152.954736)
				(mid 182.40121 -152.954736)
				(end 182.694326 -152.954736)
			)
		)
		(stroke
			(width 0)
			(type solid)
		)
		(fill yes)
		(layer "In13.Cu")
		(net "GND")
	)
	(gr_poly
		(pts
			(arc
				(start 182.694326 -151.154892)
				(mid 182.40121 -151.154892)
				(end 182.694326 -151.154892)
			)
		)
		(stroke
			(width 0)
			(type solid)
		)
		(fill yes)
		(layer "In13.Cu")
		(net "GND")
	)
	(gr_poly
		(pts
			(arc
				(start 182.694326 -149.354794)
				(mid 182.40121 -149.354794)
				(end 182.694326 -149.354794)
			)
		)
		(stroke
			(width 0)
			(type solid)
		)
		(fill yes)
		(layer "In13.Cu")
		(net "GND")
	)
	(gr_poly
		(pts
			(arc
				(start 182.694326 -147.55495)
				(mid 182.40121 -147.55495)
				(end 182.694326 -147.55495)
			)
		)
		(stroke
			(width 0)
			(type solid)
		)
		(fill yes)
		(layer "In13.Cu")
		(net "GND")
	)
	(gr_poly
		(pts
			(arc
				(start 182.694326 -145.754852)
				(mid 182.40121 -145.754852)
				(end 182.694326 -145.754852)
			)
		)
		(stroke
			(width 0)
			(type solid)
		)
		(fill yes)
		(layer "In13.Cu")
		(net "GND")
	)
	(gr_poly
		(pts
			(arc
				(start 182.694326 -143.955008)
				(mid 182.40121 -143.955008)
				(end 182.694326 -143.955008)
			)
		)
		(stroke
			(width 0)
			(type solid)
		)
		(fill yes)
		(layer "In13.Cu")
		(net "GND")
	)
	(gr_poly
		(pts
			(arc
				(start 182.694326 -142.15491)
				(mid 182.40121 -142.15491)
				(end 182.694326 -142.15491)
			)
		)
		(stroke
			(width 0)
			(type solid)
		)
		(fill yes)
		(layer "In13.Cu")
		(net "GND")
	)
	(gr_poly
		(pts
			(arc
				(start 182.694326 -134.84479)
				(mid 182.40121 -134.84479)
				(end 182.694326 -134.84479)
			)
		)
		(stroke
			(width 0)
			(type solid)
		)
		(fill yes)
		(layer "In13.Cu")
		(net "GND")
	)
	(gr_poly
		(pts
			(arc
				(start 182.694326 -133.044946)
				(mid 182.40121 -133.044946)
				(end 182.694326 -133.044946)
			)
		)
		(stroke
			(width 0)
			(type solid)
		)
		(fill yes)
		(layer "In13.Cu")
		(net "GND")
	)
	(gr_poly
		(pts
			(arc
				(start 182.694326 -131.244848)
				(mid 182.40121 -131.244848)
				(end 182.694326 -131.244848)
			)
		)
		(stroke
			(width 0)
			(type solid)
		)
		(fill yes)
		(layer "In13.Cu")
		(net "GND")
	)
	(gr_poly
		(pts
			(arc
				(start 182.694326 -129.44475)
				(mid 182.40121 -129.44475)
				(end 182.694326 -129.44475)
			)
		)
		(stroke
			(width 0)
			(type solid)
		)
		(fill yes)
		(layer "In13.Cu")
		(net "GND")
	)
	(gr_poly
		(pts
			(arc
				(start 182.694326 -123.634754)
				(mid 182.40121 -123.634754)
				(end 182.694326 -123.634754)
			)
		)
		(stroke
			(width 0)
			(type solid)
		)
		(fill yes)
		(layer "In13.Cu")
		(net "GND")
	)
	(gr_poly
		(pts
			(arc
				(start 182.694326 -121.834656)
				(mid 182.40121 -121.834656)
				(end 182.694326 -121.834656)
			)
		)
		(stroke
			(width 0)
			(type solid)
		)
		(fill yes)
		(layer "In13.Cu")
		(net "GND")
	)
	(gr_poly
		(pts
			(arc
				(start 182.694326 -120.034812)
				(mid 182.40121 -120.034812)
				(end 182.694326 -120.034812)
			)
		)
		(stroke
			(width 0)
			(type solid)
		)
		(fill yes)
		(layer "In13.Cu")
		(net "GND")
	)
	(gr_poly
		(pts
			(arc
				(start 182.694326 -118.234714)
				(mid 182.40121 -118.234714)
				(end 182.694326 -118.234714)
			)
		)
		(stroke
			(width 0)
			(type solid)
		)
		(fill yes)
		(layer "In13.Cu")
		(net "GND")
	)
	(gr_poly
		(pts
			(arc
				(start 195.200524 -24.609806)
				(mid 194.907408 -24.609806)
				(end 195.200524 -24.609806)
			)
		)
		(stroke
			(width 0)
			(type solid)
		)
		(fill yes)
		(layer "In13.Cu")
		(net "GND")
	)
	(gr_poly
		(pts
			(arc
				(start 197.144894 -154.476958)
				(mid 196.851778 -154.476958)
				(end 197.144894 -154.476958)
			)
		)
		(stroke
			(width 0)
			(type solid)
		)
		(fill yes)
		(layer "In13.Cu")
		(net "GND")
	)
	(gr_poly
		(pts
			(arc
				(start 197.144894 -153.218134)
				(mid 196.851778 -153.218134)
				(end 197.144894 -153.218134)
			)
		)
		(stroke
			(width 0)
			(type solid)
		)
		(fill yes)
		(layer "In13.Cu")
		(net "GND")
	)
	(gr_poly
		(pts
			(arc
				(start 197.144894 -150.876762)
				(mid 196.851778 -150.876762)
				(end 197.144894 -150.876762)
			)
		)
		(stroke
			(width 0)
			(type solid)
		)
		(fill yes)
		(layer "In13.Cu")
		(net "GND")
	)
	(gr_poly
		(pts
			(arc
				(start 197.144894 -149.617938)
				(mid 196.851778 -149.617938)
				(end 197.144894 -149.617938)
			)
		)
		(stroke
			(width 0)
			(type solid)
		)
		(fill yes)
		(layer "In13.Cu")
		(net "GND")
	)
	(gr_poly
		(pts
			(arc
				(start 197.144894 -147.27682)
				(mid 196.851778 -147.27682)
				(end 197.144894 -147.27682)
			)
		)
		(stroke
			(width 0)
			(type solid)
		)
		(fill yes)
		(layer "In13.Cu")
		(net "GND")
	)
	(gr_poly
		(pts
			(arc
				(start 197.144894 -146.017996)
				(mid 196.851778 -146.017996)
				(end 197.144894 -146.017996)
			)
		)
		(stroke
			(width 0)
			(type solid)
		)
		(fill yes)
		(layer "In13.Cu")
		(net "GND")
	)
	(gr_poly
		(pts
			(arc
				(start 197.144894 -143.676878)
				(mid 196.851778 -143.676878)
				(end 197.144894 -143.676878)
			)
		)
		(stroke
			(width 0)
			(type solid)
		)
		(fill yes)
		(layer "In13.Cu")
		(net "GND")
	)
	(gr_poly
		(pts
			(arc
				(start 197.144894 -142.418054)
				(mid 196.851778 -142.418054)
				(end 197.144894 -142.418054)
			)
		)
		(stroke
			(width 0)
			(type solid)
		)
		(fill yes)
		(layer "In13.Cu")
		(net "GND")
	)
	(gr_poly
		(pts
			(arc
				(start 197.144894 -134.566914)
				(mid 196.851778 -134.566914)
				(end 197.144894 -134.566914)
			)
		)
		(stroke
			(width 0)
			(type solid)
		)
		(fill yes)
		(layer "In13.Cu")
		(net "GND")
	)
	(gr_poly
		(pts
			(arc
				(start 197.144894 -133.30809)
				(mid 196.851778 -133.30809)
				(end 197.144894 -133.30809)
			)
		)
		(stroke
			(width 0)
			(type solid)
		)
		(fill yes)
		(layer "In13.Cu")
		(net "GND")
	)
	(gr_poly
		(pts
			(arc
				(start 197.144894 -130.966718)
				(mid 196.851778 -130.966718)
				(end 197.144894 -130.966718)
			)
		)
		(stroke
			(width 0)
			(type solid)
		)
		(fill yes)
		(layer "In13.Cu")
		(net "GND")
	)
	(gr_poly
		(pts
			(arc
				(start 197.144894 -129.707894)
				(mid 196.851778 -129.707894)
				(end 197.144894 -129.707894)
			)
		)
		(stroke
			(width 0)
			(type solid)
		)
		(fill yes)
		(layer "In13.Cu")
		(net "GND")
	)
	(gr_poly
		(pts
			(arc
				(start 197.144894 -123.356878)
				(mid 196.851778 -123.356878)
				(end 197.144894 -123.356878)
			)
		)
		(stroke
			(width 0)
			(type solid)
		)
		(fill yes)
		(layer "In13.Cu")
		(net "GND")
	)
	(gr_poly
		(pts
			(arc
				(start 197.144894 -122.098054)
				(mid 196.851778 -122.098054)
				(end 197.144894 -122.098054)
			)
		)
		(stroke
			(width 0)
			(type solid)
		)
		(fill yes)
		(layer "In13.Cu")
		(net "GND")
	)
	(gr_poly
		(pts
			(arc
				(start 197.144894 -119.756936)
				(mid 196.851778 -119.756936)
				(end 197.144894 -119.756936)
			)
		)
		(stroke
			(width 0)
			(type solid)
		)
		(fill yes)
		(layer "In13.Cu")
		(net "GND")
	)
	(gr_poly
		(pts
			(arc
				(start 197.145148 -118.498112)
				(mid 196.852032 -118.498112)
				(end 197.145148 -118.498112)
			)
		)
		(stroke
			(width 0)
			(type solid)
		)
		(fill yes)
		(layer "In13.Cu")
		(net "GND")
	)
	(gr_poly
		(pts
			(arc
				(start 198.412862 -154.476958)
				(mid 198.119746 -154.476958)
				(end 198.412862 -154.476958)
			)
		)
		(stroke
			(width 0)
			(type solid)
		)
		(fill yes)
		(layer "In13.Cu")
		(net "GND")
	)
	(gr_poly
		(pts
			(arc
				(start 198.412862 -153.218134)
				(mid 198.119746 -153.218134)
				(end 198.412862 -153.218134)
			)
		)
		(stroke
			(width 0)
			(type solid)
		)
		(fill yes)
		(layer "In13.Cu")
		(net "GND")
	)
	(gr_poly
		(pts
			(arc
				(start 198.412862 -150.876762)
				(mid 198.119746 -150.876762)
				(end 198.412862 -150.876762)
			)
		)
		(stroke
			(width 0)
			(type solid)
		)
		(fill yes)
		(layer "In13.Cu")
		(net "GND")
	)
	(gr_poly
		(pts
			(arc
				(start 198.412862 -149.617938)
				(mid 198.119746 -149.617938)
				(end 198.412862 -149.617938)
			)
		)
		(stroke
			(width 0)
			(type solid)
		)
		(fill yes)
		(layer "In13.Cu")
		(net "GND")
	)
	(gr_poly
		(pts
			(arc
				(start 198.412862 -147.27682)
				(mid 198.119746 -147.27682)
				(end 198.412862 -147.27682)
			)
		)
		(stroke
			(width 0)
			(type solid)
		)
		(fill yes)
		(layer "In13.Cu")
		(net "GND")
	)
	(gr_poly
		(pts
			(arc
				(start 198.412862 -146.017996)
				(mid 198.119746 -146.017996)
				(end 198.412862 -146.017996)
			)
		)
		(stroke
			(width 0)
			(type solid)
		)
		(fill yes)
		(layer "In13.Cu")
		(net "GND")
	)
	(gr_poly
		(pts
			(arc
				(start 198.412862 -143.676878)
				(mid 198.119746 -143.676878)
				(end 198.412862 -143.676878)
			)
		)
		(stroke
			(width 0)
			(type solid)
		)
		(fill yes)
		(layer "In13.Cu")
		(net "GND")
	)
	(gr_poly
		(pts
			(arc
				(start 198.412862 -142.418054)
				(mid 198.119746 -142.418054)
				(end 198.412862 -142.418054)
			)
		)
		(stroke
			(width 0)
			(type solid)
		)
		(fill yes)
		(layer "In13.Cu")
		(net "GND")
	)
	(gr_poly
		(pts
			(arc
				(start 198.412862 -134.566914)
				(mid 198.119746 -134.566914)
				(end 198.412862 -134.566914)
			)
		)
		(stroke
			(width 0)
			(type solid)
		)
		(fill yes)
		(layer "In13.Cu")
		(net "GND")
	)
	(gr_poly
		(pts
			(arc
				(start 198.412862 -133.30809)
				(mid 198.119746 -133.30809)
				(end 198.412862 -133.30809)
			)
		)
		(stroke
			(width 0)
			(type solid)
		)
		(fill yes)
		(layer "In13.Cu")
		(net "GND")
	)
	(gr_poly
		(pts
			(arc
				(start 198.412862 -130.966718)
				(mid 198.119746 -130.966718)
				(end 198.412862 -130.966718)
			)
		)
		(stroke
			(width 0)
			(type solid)
		)
		(fill yes)
		(layer "In13.Cu")
		(net "GND")
	)
	(gr_poly
		(pts
			(arc
				(start 198.412862 -129.707894)
				(mid 198.119746 -129.707894)
				(end 198.412862 -129.707894)
			)
		)
		(stroke
			(width 0)
			(type solid)
		)
		(fill yes)
		(layer "In13.Cu")
		(net "GND")
	)
	(gr_poly
		(pts
			(arc
				(start 198.412862 -123.356878)
				(mid 198.119746 -123.356878)
				(end 198.412862 -123.356878)
			)
		)
		(stroke
			(width 0)
			(type solid)
		)
		(fill yes)
		(layer "In13.Cu")
		(net "GND")
	)
	(gr_poly
		(pts
			(arc
				(start 198.412862 -122.098054)
				(mid 198.119746 -122.098054)
				(end 198.412862 -122.098054)
			)
		)
		(stroke
			(width 0)
			(type solid)
		)
		(fill yes)
		(layer "In13.Cu")
		(net "GND")
	)
	(gr_poly
		(pts
			(arc
				(start 198.412862 -119.756936)
				(mid 198.119746 -119.756936)
				(end 198.412862 -119.756936)
			)
		)
		(stroke
			(width 0)
			(type solid)
		)
		(fill yes)
		(layer "In13.Cu")
		(net "GND")
	)
	(gr_poly
		(pts
			(arc
				(start 198.412862 -118.498112)
				(mid 198.119746 -118.498112)
				(end 198.412862 -118.498112)
			)
		)
		(stroke
			(width 0)
			(type solid)
		)
		(fill yes)
		(layer "In13.Cu")
		(net "GND")
	)
	(gr_poly
		(pts
			(arc
				(start 199.787002 -156.283406)
				(mid 199.493886 -156.283406)
				(end 199.787002 -156.283406)
			)
		)
		(stroke
			(width 0)
			(type solid)
		)
		(fill yes)
		(layer "In13.Cu")
		(net "GND")
	)
	(gr_poly
		(pts
			(arc
				(start 199.787002 -155.024582)
				(mid 199.493886 -155.024582)
				(end 199.787002 -155.024582)
			)
		)
		(stroke
			(width 0)
			(type solid)
		)
		(fill yes)
		(layer "In13.Cu")
		(net "GND")
	)
	(gr_poly
		(pts
			(arc
				(start 199.787002 -152.683464)
				(mid 199.493886 -152.683464)
				(end 199.787002 -152.683464)
			)
		)
		(stroke
			(width 0)
			(type solid)
		)
		(fill yes)
		(layer "In13.Cu")
		(net "GND")
	)
	(gr_poly
		(pts
			(arc
				(start 199.787002 -151.42464)
				(mid 199.493886 -151.42464)
				(end 199.787002 -151.42464)
			)
		)
		(stroke
			(width 0)
			(type solid)
		)
		(fill yes)
		(layer "In13.Cu")
		(net "GND")
	)
	(gr_poly
		(pts
			(arc
				(start 199.787002 -149.083522)
				(mid 199.493886 -149.083522)
				(end 199.787002 -149.083522)
			)
		)
		(stroke
			(width 0)
			(type solid)
		)
		(fill yes)
		(layer "In13.Cu")
		(net "GND")
	)
	(gr_poly
		(pts
			(arc
				(start 199.787002 -147.824698)
				(mid 199.493886 -147.824698)
				(end 199.787002 -147.824698)
			)
		)
		(stroke
			(width 0)
			(type solid)
		)
		(fill yes)
		(layer "In13.Cu")
		(net "GND")
	)
	(gr_poly
		(pts
			(arc
				(start 199.787002 -145.483326)
				(mid 199.493886 -145.483326)
				(end 199.787002 -145.483326)
			)
		)
		(stroke
			(width 0)
			(type solid)
		)
		(fill yes)
		(layer "In13.Cu")
		(net "GND")
	)
	(gr_poly
		(pts
			(arc
				(start 199.787002 -144.224502)
				(mid 199.493886 -144.224502)
				(end 199.787002 -144.224502)
			)
		)
		(stroke
			(width 0)
			(type solid)
		)
		(fill yes)
		(layer "In13.Cu")
		(net "GND")
	)
	(gr_poly
		(pts
			(arc
				(start 199.787002 -136.373362)
				(mid 199.493886 -136.373362)
				(end 199.787002 -136.373362)
			)
		)
		(stroke
			(width 0)
			(type solid)
		)
		(fill yes)
		(layer "In13.Cu")
		(net "GND")
	)
	(gr_poly
		(pts
			(arc
				(start 199.787002 -135.114538)
				(mid 199.493886 -135.114538)
				(end 199.787002 -135.114538)
			)
		)
		(stroke
			(width 0)
			(type solid)
		)
		(fill yes)
		(layer "In13.Cu")
		(net "GND")
	)
	(gr_poly
		(pts
			(arc
				(start 199.787002 -132.77342)
				(mid 199.493886 -132.77342)
				(end 199.787002 -132.77342)
			)
		)
		(stroke
			(width 0)
			(type solid)
		)
		(fill yes)
		(layer "In13.Cu")
		(net "GND")
	)
	(gr_poly
		(pts
			(arc
				(start 199.787002 -131.514596)
				(mid 199.493886 -131.514596)
				(end 199.787002 -131.514596)
			)
		)
		(stroke
			(width 0)
			(type solid)
		)
		(fill yes)
		(layer "In13.Cu")
		(net "GND")
	)
	(gr_poly
		(pts
			(arc
				(start 199.787002 -125.163326)
				(mid 199.493886 -125.163326)
				(end 199.787002 -125.163326)
			)
		)
		(stroke
			(width 0)
			(type solid)
		)
		(fill yes)
		(layer "In13.Cu")
		(net "GND")
	)
	(gr_poly
		(pts
			(arc
				(start 199.787002 -123.904502)
				(mid 199.493886 -123.904502)
				(end 199.787002 -123.904502)
			)
		)
		(stroke
			(width 0)
			(type solid)
		)
		(fill yes)
		(layer "In13.Cu")
		(net "GND")
	)
	(gr_poly
		(pts
			(arc
				(start 199.787002 -121.563384)
				(mid 199.493886 -121.563384)
				(end 199.787002 -121.563384)
			)
		)
		(stroke
			(width 0)
			(type solid)
		)
		(fill yes)
		(layer "In13.Cu")
		(net "GND")
	)
	(gr_poly
		(pts
			(arc
				(start 199.787002 -120.30456)
				(mid 199.493886 -120.30456)
				(end 199.787002 -120.30456)
			)
		)
		(stroke
			(width 0)
			(type solid)
		)
		(fill yes)
		(layer "In13.Cu")
		(net "GND")
	)
	(gr_poly
		(pts
			(arc
				(start 200.847452 -34.98977)
				(mid 200.554336 -34.98977)
				(end 200.847452 -34.98977)
			)
		)
		(stroke
			(width 0)
			(type solid)
		)
		(fill yes)
		(layer "In13.Cu")
		(net "GND")
	)
	(gr_poly
		(pts
			(arc
				(start 200.847452 -33.189672)
				(mid 200.554336 -33.189672)
				(end 200.847452 -33.189672)
			)
		)
		(stroke
			(width 0)
			(type solid)
		)
		(fill yes)
		(layer "In13.Cu")
		(net "GND")
	)
	(gr_poly
		(pts
			(arc
				(start 200.847452 -31.389828)
				(mid 200.554336 -31.389828)
				(end 200.847452 -31.389828)
			)
		)
		(stroke
			(width 0)
			(type solid)
		)
		(fill yes)
		(layer "In13.Cu")
		(net "GND")
	)
	(gr_poly
		(pts
			(arc
				(start 200.847452 -29.58973)
				(mid 200.554336 -29.58973)
				(end 200.847452 -29.58973)
			)
		)
		(stroke
			(width 0)
			(type solid)
		)
		(fill yes)
		(layer "In13.Cu")
		(net "GND")
	)
	(gr_poly
		(pts
			(arc
				(start 201.05497 -156.283406)
				(mid 200.761854 -156.283406)
				(end 201.05497 -156.283406)
			)
		)
		(stroke
			(width 0)
			(type solid)
		)
		(fill yes)
		(layer "In13.Cu")
		(net "GND")
	)
	(gr_poly
		(pts
			(arc
				(start 201.05497 -155.024582)
				(mid 200.761854 -155.024582)
				(end 201.05497 -155.024582)
			)
		)
		(stroke
			(width 0)
			(type solid)
		)
		(fill yes)
		(layer "In13.Cu")
		(net "GND")
	)
	(gr_poly
		(pts
			(arc
				(start 201.05497 -152.683464)
				(mid 200.761854 -152.683464)
				(end 201.05497 -152.683464)
			)
		)
		(stroke
			(width 0)
			(type solid)
		)
		(fill yes)
		(layer "In13.Cu")
		(net "GND")
	)
	(gr_poly
		(pts
			(arc
				(start 201.05497 -151.42464)
				(mid 200.761854 -151.42464)
				(end 201.05497 -151.42464)
			)
		)
		(stroke
			(width 0)
			(type solid)
		)
		(fill yes)
		(layer "In13.Cu")
		(net "GND")
	)
	(gr_poly
		(pts
			(arc
				(start 201.05497 -149.083522)
				(mid 200.761854 -149.083522)
				(end 201.05497 -149.083522)
			)
		)
		(stroke
			(width 0)
			(type solid)
		)
		(fill yes)
		(layer "In13.Cu")
		(net "GND")
	)
	(gr_poly
		(pts
			(arc
				(start 201.05497 -147.824698)
				(mid 200.761854 -147.824698)
				(end 201.05497 -147.824698)
			)
		)
		(stroke
			(width 0)
			(type solid)
		)
		(fill yes)
		(layer "In13.Cu")
		(net "GND")
	)
	(gr_poly
		(pts
			(arc
				(start 201.05497 -145.483326)
				(mid 200.761854 -145.483326)
				(end 201.05497 -145.483326)
			)
		)
		(stroke
			(width 0)
			(type solid)
		)
		(fill yes)
		(layer "In13.Cu")
		(net "GND")
	)
	(gr_poly
		(pts
			(arc
				(start 201.05497 -144.224502)
				(mid 200.761854 -144.224502)
				(end 201.05497 -144.224502)
			)
		)
		(stroke
			(width 0)
			(type solid)
		)
		(fill yes)
		(layer "In13.Cu")
		(net "GND")
	)
	(gr_poly
		(pts
			(arc
				(start 201.05497 -136.373362)
				(mid 200.761854 -136.373362)
				(end 201.05497 -136.373362)
			)
		)
		(stroke
			(width 0)
			(type solid)
		)
		(fill yes)
		(layer "In13.Cu")
		(net "GND")
	)
	(gr_poly
		(pts
			(arc
				(start 201.05497 -135.114538)
				(mid 200.761854 -135.114538)
				(end 201.05497 -135.114538)
			)
		)
		(stroke
			(width 0)
			(type solid)
		)
		(fill yes)
		(layer "In13.Cu")
		(net "GND")
	)
	(gr_poly
		(pts
			(arc
				(start 201.05497 -132.77342)
				(mid 200.761854 -132.77342)
				(end 201.05497 -132.77342)
			)
		)
		(stroke
			(width 0)
			(type solid)
		)
		(fill yes)
		(layer "In13.Cu")
		(net "GND")
	)
	(gr_poly
		(pts
			(arc
				(start 201.05497 -131.514596)
				(mid 200.761854 -131.514596)
				(end 201.05497 -131.514596)
			)
		)
		(stroke
			(width 0)
			(type solid)
		)
		(fill yes)
		(layer "In13.Cu")
		(net "GND")
	)
	(gr_poly
		(pts
			(arc
				(start 201.05497 -125.163326)
				(mid 200.761854 -125.163326)
				(end 201.05497 -125.163326)
			)
		)
		(stroke
			(width 0)
			(type solid)
		)
		(fill yes)
		(layer "In13.Cu")
		(net "GND")
	)
	(gr_poly
		(pts
			(arc
				(start 201.05497 -123.904502)
				(mid 200.761854 -123.904502)
				(end 201.05497 -123.904502)
			)
		)
		(stroke
			(width 0)
			(type solid)
		)
		(fill yes)
		(layer "In13.Cu")
		(net "GND")
	)
	(gr_poly
		(pts
			(arc
				(start 201.05497 -121.563384)
				(mid 200.761854 -121.563384)
				(end 201.05497 -121.563384)
			)
		)
		(stroke
			(width 0)
			(type solid)
		)
		(fill yes)
		(layer "In13.Cu")
		(net "GND")
	)
	(gr_poly
		(pts
			(arc
				(start 201.05497 -120.30456)
				(mid 200.761854 -120.30456)
				(end 201.05497 -120.30456)
			)
		)
		(stroke
			(width 0)
			(type solid)
		)
		(fill yes)
		(layer "In13.Cu")
		(net "GND")
	)
	(gr_poly
		(pts
			(arc
				(start 202.066652 -34.98977)
				(mid 201.773536 -34.98977)
				(end 202.066652 -34.98977)
			)
		)
		(stroke
			(width 0)
			(type solid)
		)
		(fill yes)
		(layer "In13.Cu")
		(net "GND")
	)
	(gr_poly
		(pts
			(arc
				(start 202.066652 -33.189672)
				(mid 201.773536 -33.189672)
				(end 202.066652 -33.189672)
			)
		)
		(stroke
			(width 0)
			(type solid)
		)
		(fill yes)
		(layer "In13.Cu")
		(net "GND")
	)
	(gr_poly
		(pts
			(arc
				(start 202.066652 -31.389828)
				(mid 201.773536 -31.389828)
				(end 202.066652 -31.389828)
			)
		)
		(stroke
			(width 0)
			(type solid)
		)
		(fill yes)
		(layer "In13.Cu")
		(net "GND")
	)
	(gr_poly
		(pts
			(arc
				(start 202.066652 -29.58973)
				(mid 201.773536 -29.58973)
				(end 202.066652 -29.58973)
			)
		)
		(stroke
			(width 0)
			(type solid)
		)
		(fill yes)
		(layer "In13.Cu")
		(net "GND")
	)
	(gr_poly
		(pts
			(arc
				(start 202.701652 -33.189672)
				(mid 202.408536 -33.189672)
				(end 202.701652 -33.189672)
			)
		)
		(stroke
			(width 0)
			(type solid)
		)
		(fill yes)
		(layer "In13.Cu")
		(net "GND")
	)
	(gr_poly
		(pts
			(arc
				(start 202.701652 -31.389574)
				(mid 202.408536 -31.389574)
				(end 202.701652 -31.389574)
			)
		)
		(stroke
			(width 0)
			(type solid)
		)
		(fill yes)
		(layer "In13.Cu")
		(net "GND")
	)
	(gr_poly
		(pts
			(arc
				(start 202.701652 -29.58973)
				(mid 202.408536 -29.58973)
				(end 202.701652 -29.58973)
			)
		)
		(stroke
			(width 0)
			(type solid)
		)
		(fill yes)
		(layer "In13.Cu")
		(net "GND")
	)
	(gr_poly
		(pts
			(arc
				(start 205.805786 -287.854136)
				(mid 205.51267 -287.854136)
				(end 205.805786 -287.854136)
			)
		)
		(stroke
			(width 0)
			(type solid)
		)
		(fill yes)
		(layer "In13.Cu")
		(net "GND")
	)
	(gr_poly
		(pts
			(arc
				(start 206.600806 -230.672894)
				(mid 206.30769 -230.672894)
				(end 206.600806 -230.672894)
			)
		)
		(stroke
			(width 0)
			(type solid)
		)
		(fill yes)
		(layer "In13.Cu")
		(net "GND")
	)
	(gr_poly
		(pts
			(arc
				(start 207.414876 -212.86089)
				(mid 207.12176 -212.86089)
				(end 207.414876 -212.86089)
			)
		)
		(stroke
			(width 0)
			(type solid)
		)
		(fill yes)
		(layer "In13.Cu")
		(net "GND")
	)
	(gr_poly
		(pts
			(arc
				(start 207.666082 -287.788858)
				(mid 207.372966 -287.788858)
				(end 207.666082 -287.788858)
			)
		)
		(stroke
			(width 0)
			(type solid)
		)
		(fill yes)
		(layer "In13.Cu")
		(net "GND")
	)
	(gr_poly
		(pts
			(arc
				(start 208.936082 -287.072832)
				(mid 208.642966 -287.072832)
				(end 208.936082 -287.072832)
			)
		)
		(stroke
			(width 0)
			(type solid)
		)
		(fill yes)
		(layer "In13.Cu")
		(net "GND")
	)
	(gr_poly
		(pts
			(arc
				(start 209.05216 -232.433876)
				(mid 208.759044 -232.433876)
				(end 209.05216 -232.433876)
			)
		)
		(stroke
			(width 0)
			(type solid)
		)
		(fill yes)
		(layer "In13.Cu")
		(net "GND")
	)
	(gr_poly
		(pts
			(arc
				(start 209.82559 -232.122726)
				(mid 209.532474 -232.122726)
				(end 209.82559 -232.122726)
			)
		)
		(stroke
			(width 0)
			(type solid)
		)
		(fill yes)
		(layer "In13.Cu")
		(net "GND")
	)
	(gr_poly
		(pts
			(arc
				(start 210.507834 -241.128042)
				(mid 210.214718 -241.128042)
				(end 210.507834 -241.128042)
			)
		)
		(stroke
			(width 0)
			(type solid)
		)
		(fill yes)
		(layer "In13.Cu")
		(net "GND")
	)
	(gr_poly
		(pts
			(arc
				(start 210.556348 -284.632146)
				(mid 210.263232 -284.632146)
				(end 210.556348 -284.632146)
			)
		)
		(stroke
			(width 0)
			(type solid)
		)
		(fill yes)
		(layer "In13.Cu")
		(net "GND")
	)
	(gr_poly
		(pts
			(arc
				(start 210.809332 -88.401144)
				(mid 210.516216 -88.401144)
				(end 210.809332 -88.401144)
			)
		)
		(stroke
			(width 0)
			(type solid)
		)
		(fill yes)
		(layer "In13.Cu")
		(net "GND")
	)
	(gr_poly
		(pts
			(arc
				(start 213.2838 -238.672116)
				(mid 212.990684 -238.672116)
				(end 213.2838 -238.672116)
			)
		)
		(stroke
			(width 0)
			(type solid)
		)
		(fill yes)
		(layer "In13.Cu")
		(net "GND")
	)
	(gr_poly
		(pts
			(arc
				(start 213.3981 -82.633058)
				(mid 213.104984 -82.633058)
				(end 213.3981 -82.633058)
			)
		)
		(stroke
			(width 0)
			(type solid)
		)
		(fill yes)
		(layer "In13.Cu")
		(net "GND")
	)
	(gr_poly
		(pts
			(arc
				(start 214.942928 -227.440744)
				(mid 214.649812 -227.440744)
				(end 214.942928 -227.440744)
			)
		)
		(stroke
			(width 0)
			(type solid)
		)
		(fill yes)
		(layer "In13.Cu")
		(net "GND")
	)
	(gr_poly
		(pts
			(arc
				(start 221.226888 -24.571198)
				(mid 220.933772 -24.571198)
				(end 221.226888 -24.571198)
			)
		)
		(stroke
			(width 0)
			(type solid)
		)
		(fill yes)
		(layer "In13.Cu")
		(net "GND")
	)
	(gr_poly
		(pts
			(arc
				(start 222.07474 -90.892376)
				(mid 221.781624 -90.892376)
				(end 222.07474 -90.892376)
			)
		)
		(stroke
			(width 0)
			(type solid)
		)
		(fill yes)
		(layer "In13.Cu")
		(net "GND")
	)
	(gr_poly
		(pts
			(arc
				(start 223.061276 -190.368682)
				(mid 222.76816 -190.368682)
				(end 223.061276 -190.368682)
			)
		)
		(stroke
			(width 0)
			(type solid)
		)
		(fill yes)
		(layer "In13.Cu")
		(net "GND")
	)
	(gr_poly
		(pts
			(arc
				(start 225.197162 -88.032336)
				(mid 224.904046 -88.032336)
				(end 225.197162 -88.032336)
			)
		)
		(stroke
			(width 0)
			(type solid)
		)
		(fill yes)
		(layer "In13.Cu")
		(net "GND")
	)
	(gr_poly
		(pts
			(arc
				(start 227.749862 -60.329318)
				(mid 227.456746 -60.329318)
				(end 227.749862 -60.329318)
			)
		)
		(stroke
			(width 0)
			(type solid)
		)
		(fill yes)
		(layer "In13.Cu")
		(net "GND")
	)
	(gr_poly
		(pts
			(arc
				(start 227.749862 -59.070494)
				(mid 227.456746 -59.070494)
				(end 227.749862 -59.070494)
			)
		)
		(stroke
			(width 0)
			(type solid)
		)
		(fill yes)
		(layer "In13.Cu")
		(net "GND")
	)
	(gr_poly
		(pts
			(arc
				(start 228.720904 -157.23616)
				(mid 228.427788 -157.23616)
				(end 228.720904 -157.23616)
			)
		)
		(stroke
			(width 0)
			(type solid)
		)
		(fill yes)
		(layer "In13.Cu")
		(net "GND")
	)
	(gr_poly
		(pts
			(arc
				(start 229.21595 -78.176628)
				(mid 228.922834 -78.176628)
				(end 229.21595 -78.176628)
			)
		)
		(stroke
			(width 0)
			(type solid)
		)
		(fill yes)
		(layer "In13.Cu")
		(net "GND")
	)
	(gr_poly
		(pts
			(arc
				(start 229.979728 -157.23616)
				(mid 229.686612 -157.23616)
				(end 229.979728 -157.23616)
			)
		)
		(stroke
			(width 0)
			(type solid)
		)
		(fill yes)
		(layer "In13.Cu")
		(net "GND")
	)
	(gr_poly
		(pts
			(arc
				(start 230.047038 -77.430122)
				(mid 229.753922 -77.430122)
				(end 230.047038 -77.430122)
			)
		)
		(stroke
			(width 0)
			(type solid)
		)
		(fill yes)
		(layer "In13.Cu")
		(net "GND")
	)
	(gr_poly
		(pts
			(arc
				(start 230.964232 -157.25648)
				(mid 230.671116 -157.25648)
				(end 230.964232 -157.25648)
			)
		)
		(stroke
			(width 0)
			(type solid)
		)
		(fill yes)
		(layer "In13.Cu")
		(net "GND")
	)
	(gr_poly
		(pts
			(arc
				(start 231.305862 -77.430122)
				(mid 231.012746 -77.430122)
				(end 231.305862 -77.430122)
			)
		)
		(stroke
			(width 0)
			(type solid)
		)
		(fill yes)
		(layer "In13.Cu")
		(net "GND")
	)
	(gr_poly
		(pts
			(arc
				(start 231.994202 -77.901038)
				(mid 231.701086 -77.901038)
				(end 231.994202 -77.901038)
			)
		)
		(stroke
			(width 0)
			(type solid)
		)
		(fill yes)
		(layer "In13.Cu")
		(net "GND")
	)
	(gr_poly
		(pts
			(arc
				(start 232.100882 -85.468206)
				(mid 231.807766 -85.468206)
				(end 232.100882 -85.468206)
			)
		)
		(stroke
			(width 0)
			(type solid)
		)
		(fill yes)
		(layer "In13.Cu")
		(net "GND")
	)
	(gr_poly
		(pts
			(arc
				(start 232.223056 -157.25648)
				(mid 231.92994 -157.25648)
				(end 232.223056 -157.25648)
			)
		)
		(stroke
			(width 0)
			(type solid)
		)
		(fill yes)
		(layer "In13.Cu")
		(net "GND")
	)
	(gr_poly
		(pts
			(arc
				(start 232.606088 -169.33418)
				(mid 232.312972 -169.33418)
				(end 232.606088 -169.33418)
			)
		)
		(stroke
			(width 0)
			(type solid)
		)
		(fill yes)
		(layer "In13.Cu")
		(net "GND")
	)
	(gr_poly
		(pts
			(arc
				(start 233.28249 -84.189062)
				(mid 232.989374 -84.189062)
				(end 233.28249 -84.189062)
			)
		)
		(stroke
			(width 0)
			(type solid)
		)
		(fill yes)
		(layer "In13.Cu")
		(net "GND")
	)
	(gr_poly
		(pts
			(arc
				(start 233.294682 -81.70418)
				(mid 233.001566 -81.70418)
				(end 233.294682 -81.70418)
			)
		)
		(stroke
			(width 0)
			(type solid)
		)
		(fill yes)
		(layer "In13.Cu")
		(net "GND")
	)
	(gr_poly
		(pts
			(arc
				(start 234.38485 -86.880954)
				(mid 234.091734 -86.880954)
				(end 234.38485 -86.880954)
			)
		)
		(stroke
			(width 0)
			(type solid)
		)
		(fill yes)
		(layer "In13.Cu")
		(net "GND")
	)
	(gr_poly
		(pts
			(arc
				(start 234.494324 -85.498686)
				(mid 234.201208 -85.498686)
				(end 234.494324 -85.498686)
			)
		)
		(stroke
			(width 0)
			(type solid)
		)
		(fill yes)
		(layer "In13.Cu")
		(net "GND")
	)
	(gr_poly
		(pts
			(arc
				(start 236.46765 -86.8807)
				(mid 236.174534 -86.8807)
				(end 236.46765 -86.8807)
			)
		)
		(stroke
			(width 0)
			(type solid)
		)
		(fill yes)
		(layer "In13.Cu")
		(net "GND")
	)
	(gr_poly
		(pts
			(arc
				(start 236.76737 -150.029672)
				(mid 236.474254 -150.029672)
				(end 236.76737 -150.029672)
			)
		)
		(stroke
			(width 0)
			(type solid)
		)
		(fill yes)
		(layer "In13.Cu")
		(net "GND")
	)
	(gr_poly
		(pts
			(arc
				(start 236.771434 -152.252426)
				(mid 236.478318 -152.252426)
				(end 236.771434 -152.252426)
			)
		)
		(stroke
			(width 0)
			(type solid)
		)
		(fill yes)
		(layer "In13.Cu")
		(net "GND")
	)
	(gr_poly
		(pts
			(arc
				(start 236.778038 -148.441664)
				(mid 236.484922 -148.441664)
				(end 236.778038 -148.441664)
			)
		)
		(stroke
			(width 0)
			(type solid)
		)
		(fill yes)
		(layer "In13.Cu")
		(net "GND")
	)
	(gr_poly
		(pts
			(arc
				(start 236.784896 -150.69058)
				(mid 236.49178 -150.69058)
				(end 236.784896 -150.69058)
			)
		)
		(stroke
			(width 0)
			(type solid)
		)
		(fill yes)
		(layer "In13.Cu")
		(net "GND")
	)
	(gr_poly
		(pts
			(arc
				(start 238.00562 -87.715344)
				(mid 237.712504 -87.715344)
				(end 238.00562 -87.715344)
			)
		)
		(stroke
			(width 0)
			(type solid)
		)
		(fill yes)
		(layer "In13.Cu")
		(net "GND")
	)
	(gr_poly
		(pts
			(arc
				(start 238.04499 -82.818732)
				(mid 237.751874 -82.818732)
				(end 238.04499 -82.818732)
			)
		)
		(stroke
			(width 0)
			(type solid)
		)
		(fill yes)
		(layer "In13.Cu")
		(net "GND")
	)
	(gr_poly
		(pts
			(arc
				(start 238.806482 -78.872334)
				(mid 238.513366 -78.872334)
				(end 238.806482 -78.872334)
			)
		)
		(stroke
			(width 0)
			(type solid)
		)
		(fill yes)
		(layer "In13.Cu")
		(net "GND")
	)
	(gr_poly
		(pts
			(arc
				(start 238.81842 -80.638396)
				(mid 238.525304 -80.638396)
				(end 238.81842 -80.638396)
			)
		)
		(stroke
			(width 0)
			(type solid)
		)
		(fill yes)
		(layer "In13.Cu")
		(net "GND")
	)
	(gr_poly
		(pts
			(arc
				(start 238.947452 -29.58973)
				(mid 238.654336 -29.58973)
				(end 238.947452 -29.58973)
			)
		)
		(stroke
			(width 0)
			(type solid)
		)
		(fill yes)
		(layer "In13.Cu")
		(net "GND")
	)
	(gr_poly
		(pts
			(arc
				(start 239.141254 -83.555586)
				(mid 238.848138 -83.555586)
				(end 239.141254 -83.555586)
			)
		)
		(stroke
			(width 0)
			(type solid)
		)
		(fill yes)
		(layer "In13.Cu")
		(net "GND")
	)
	(gr_poly
		(pts
			(arc
				(start 239.153446 -85.912452)
				(mid 238.86033 -85.912452)
				(end 239.153446 -85.912452)
			)
		)
		(stroke
			(width 0)
			(type solid)
		)
		(fill yes)
		(layer "In13.Cu")
		(net "GND")
	)
	(gr_poly
		(pts
			(arc
				(start 239.575848 -225.17608)
				(mid 239.282732 -225.17608)
				(end 239.575848 -225.17608)
			)
		)
		(stroke
			(width 0)
			(type solid)
		)
		(fill yes)
		(layer "In13.Cu")
		(net "GND")
	)
	(gr_poly
		(pts
			(arc
				(start 240.166652 -34.98977)
				(mid 239.873536 -34.98977)
				(end 240.166652 -34.98977)
			)
		)
		(stroke
			(width 0)
			(type solid)
		)
		(fill yes)
		(layer "In13.Cu")
		(net "GND")
	)
	(gr_poly
		(pts
			(arc
				(start 240.166652 -33.189672)
				(mid 239.873536 -33.189672)
				(end 240.166652 -33.189672)
			)
		)
		(stroke
			(width 0)
			(type solid)
		)
		(fill yes)
		(layer "In13.Cu")
		(net "GND")
	)
	(gr_poly
		(pts
			(arc
				(start 240.166652 -31.389828)
				(mid 239.873536 -31.389828)
				(end 240.166652 -31.389828)
			)
		)
		(stroke
			(width 0)
			(type solid)
		)
		(fill yes)
		(layer "In13.Cu")
		(net "GND")
	)
	(gr_poly
		(pts
			(arc
				(start 240.166652 -29.58973)
				(mid 239.873536 -29.58973)
				(end 240.166652 -29.58973)
			)
		)
		(stroke
			(width 0)
			(type solid)
		)
		(fill yes)
		(layer "In13.Cu")
		(net "GND")
	)
	(gr_poly
		(pts
			(arc
				(start 240.207038 -82.916014)
				(mid 239.913922 -82.916014)
				(end 240.207038 -82.916014)
			)
		)
		(stroke
			(width 0)
			(type solid)
		)
		(fill yes)
		(layer "In13.Cu")
		(net "GND")
	)
	(gr_poly
		(pts
			(arc
				(start 240.328704 -87.727282)
				(mid 240.035588 -87.727282)
				(end 240.328704 -87.727282)
			)
		)
		(stroke
			(width 0)
			(type solid)
		)
		(fill yes)
		(layer "In13.Cu")
		(net "GND")
	)
	(gr_poly
		(pts
			(arc
				(start 240.59388 -251.80544)
				(mid 240.300764 -251.80544)
				(end 240.59388 -251.80544)
			)
		)
		(stroke
			(width 0)
			(type solid)
		)
		(fill yes)
		(layer "In13.Cu")
		(net "GND")
	)
	(gr_poly
		(pts
			(arc
				(start 240.801652 -33.189672)
				(mid 240.508536 -33.189672)
				(end 240.801652 -33.189672)
			)
		)
		(stroke
			(width 0)
			(type solid)
		)
		(fill yes)
		(layer "In13.Cu")
		(net "GND")
	)
	(gr_poly
		(pts
			(arc
				(start 240.801652 -31.389574)
				(mid 240.508536 -31.389574)
				(end 240.801652 -31.389574)
			)
		)
		(stroke
			(width 0)
			(type solid)
		)
		(fill yes)
		(layer "In13.Cu")
		(net "GND")
	)
	(gr_poly
		(pts
			(arc
				(start 240.801652 -29.58973)
				(mid 240.508536 -29.58973)
				(end 240.801652 -29.58973)
			)
		)
		(stroke
			(width 0)
			(type solid)
		)
		(fill yes)
		(layer "In13.Cu")
		(net "GND")
	)
	(gr_poly
		(pts
			(arc
				(start 242.142264 -225.202496)
				(mid 241.849148 -225.202496)
				(end 242.142264 -225.202496)
			)
		)
		(stroke
			(width 0)
			(type solid)
		)
		(fill yes)
		(layer "In13.Cu")
		(net "GND")
	)
	(gr_poly
		(pts
			(arc
				(start 244.79631 -169.57548)
				(mid 244.503194 -169.57548)
				(end 244.79631 -169.57548)
			)
		)
		(stroke
			(width 0)
			(type solid)
		)
		(fill yes)
		(layer "In13.Cu")
		(net "GND")
	)
	(gr_poly
		(pts
			(arc
				(start 247.323864 -169.575734)
				(mid 247.030748 -169.575734)
				(end 247.323864 -169.575734)
			)
		)
		(stroke
			(width 0)
			(type solid)
		)
		(fill yes)
		(layer "In13.Cu")
		(net "GND")
	)
	(gr_poly
		(pts
			(arc
				(start 248.573798 -189.848998)
				(mid 248.280682 -189.848998)
				(end 248.573798 -189.848998)
			)
		)
		(stroke
			(width 0)
			(type solid)
		)
		(fill yes)
		(layer "In13.Cu")
		(net "GND")
	)
	(gr_poly
		(pts
			(arc
				(start 253.659894 -31.117794)
				(mid 253.366778 -31.117794)
				(end 253.659894 -31.117794)
			)
		)
		(stroke
			(width 0)
			(type solid)
		)
		(fill yes)
		(layer "In13.Cu")
		(net "GND")
	)
	(gr_poly
		(pts
			(arc
				(start 253.659894 -29.85897)
				(mid 253.366778 -29.85897)
				(end 253.659894 -29.85897)
			)
		)
		(stroke
			(width 0)
			(type solid)
		)
		(fill yes)
		(layer "In13.Cu")
		(net "GND")
	)
	(gr_poly
		(pts
			(arc
				(start 258.757928 -173.769782)
				(mid 258.464812 -173.769782)
				(end 258.757928 -173.769782)
			)
		)
		(stroke
			(width 0)
			(type solid)
		)
		(fill yes)
		(layer "In13.Cu")
		(net "GND")
	)
	(gr_poly
		(pts
			(arc
				(start 258.77901 -172.376592)
				(mid 258.485894 -172.376592)
				(end 258.77901 -172.376592)
			)
		)
		(stroke
			(width 0)
			(type solid)
		)
		(fill yes)
		(layer "In13.Cu")
		(net "GND")
	)
	(gr_poly
		(pts
			(arc
				(start 259.291074 -24.655018)
				(mid 258.997958 -24.655018)
				(end 259.291074 -24.655018)
			)
		)
		(stroke
			(width 0)
			(type solid)
		)
		(fill yes)
		(layer "In13.Cu")
		(net "GND")
	)
	(gr_poly
		(pts
			(arc
				(start 264.9474 -34.98977)
				(mid 264.654284 -34.98977)
				(end 264.9474 -34.98977)
			)
		)
		(stroke
			(width 0)
			(type solid)
		)
		(fill yes)
		(layer "In13.Cu")
		(net "GND")
	)
	(gr_poly
		(pts
			(arc
				(start 264.9474 -33.189926)
				(mid 264.654284 -33.189926)
				(end 264.9474 -33.189926)
			)
		)
		(stroke
			(width 0)
			(type solid)
		)
		(fill yes)
		(layer "In13.Cu")
		(net "GND")
	)
	(gr_poly
		(pts
			(arc
				(start 264.9474 -31.389828)
				(mid 264.654284 -31.389828)
				(end 264.9474 -31.389828)
			)
		)
		(stroke
			(width 0)
			(type solid)
		)
		(fill yes)
		(layer "In13.Cu")
		(net "GND")
	)
	(gr_poly
		(pts
			(arc
				(start 264.9474 -29.589984)
				(mid 264.654284 -29.589984)
				(end 264.9474 -29.589984)
			)
		)
		(stroke
			(width 0)
			(type solid)
		)
		(fill yes)
		(layer "In13.Cu")
		(net "GND")
	)
	(gr_poly
		(pts
			(arc
				(start 266.1666 -34.98977)
				(mid 265.873484 -34.98977)
				(end 266.1666 -34.98977)
			)
		)
		(stroke
			(width 0)
			(type solid)
		)
		(fill yes)
		(layer "In13.Cu")
		(net "GND")
	)
	(gr_poly
		(pts
			(arc
				(start 266.1666 -33.189926)
				(mid 265.873484 -33.189926)
				(end 266.1666 -33.189926)
			)
		)
		(stroke
			(width 0)
			(type solid)
		)
		(fill yes)
		(layer "In13.Cu")
		(net "GND")
	)
	(gr_poly
		(pts
			(arc
				(start 266.1666 -31.389828)
				(mid 265.873484 -31.389828)
				(end 266.1666 -31.389828)
			)
		)
		(stroke
			(width 0)
			(type solid)
		)
		(fill yes)
		(layer "In13.Cu")
		(net "GND")
	)
	(gr_poly
		(pts
			(arc
				(start 266.1666 -29.589984)
				(mid 265.873484 -29.589984)
				(end 266.1666 -29.589984)
			)
		)
		(stroke
			(width 0)
			(type solid)
		)
		(fill yes)
		(layer "In13.Cu")
		(net "GND")
	)
	(gr_poly
		(pts
			(arc
				(start 266.515088 -71.160894)
				(mid 266.221972 -71.160894)
				(end 266.515088 -71.160894)
			)
		)
		(stroke
			(width 0)
			(type solid)
		)
		(fill yes)
		(layer "In13.Cu")
		(net "GND")
	)
	(gr_poly
		(pts
			(arc
				(start 266.8016 -33.189926)
				(mid 266.508484 -33.189926)
				(end 266.8016 -33.189926)
			)
		)
		(stroke
			(width 0)
			(type solid)
		)
		(fill yes)
		(layer "In13.Cu")
		(net "GND")
	)
	(gr_poly
		(pts
			(arc
				(start 266.8016 -31.389828)
				(mid 266.508484 -31.389828)
				(end 266.8016 -31.389828)
			)
		)
		(stroke
			(width 0)
			(type solid)
		)
		(fill yes)
		(layer "In13.Cu")
		(net "GND")
	)
	(gr_poly
		(pts
			(arc
				(start 266.8016 -29.589984)
				(mid 266.508484 -29.589984)
				(end 266.8016 -29.589984)
			)
		)
		(stroke
			(width 0)
			(type solid)
		)
		(fill yes)
		(layer "In13.Cu")
		(net "GND")
	)
	(gr_poly
		(pts
			(arc
				(start 266.8016 -27.789886)
				(mid 266.508484 -27.789886)
				(end 266.8016 -27.789886)
			)
		)
		(stroke
			(width 0)
			(type solid)
		)
		(fill yes)
		(layer "In13.Cu")
		(net "GND")
	)
	(gr_poly
		(pts
			(arc
				(start 266.838176 -135.095488)
				(mid 266.54506 -135.095488)
				(end 266.838176 -135.095488)
			)
		)
		(stroke
			(width 0)
			(type solid)
		)
		(fill yes)
		(layer "In13.Cu")
		(net "GND")
	)
	(gr_poly
		(pts
			(arc
				(start 266.838176 -133.836664)
				(mid 266.54506 -133.836664)
				(end 266.838176 -133.836664)
			)
		)
		(stroke
			(width 0)
			(type solid)
		)
		(fill yes)
		(layer "In13.Cu")
		(net "GND")
	)
	(gr_poly
		(pts
			(arc
				(start 266.838176 -131.495546)
				(mid 266.54506 -131.495546)
				(end 266.838176 -131.495546)
			)
		)
		(stroke
			(width 0)
			(type solid)
		)
		(fill yes)
		(layer "In13.Cu")
		(net "GND")
	)
	(gr_poly
		(pts
			(arc
				(start 266.838176 -130.236722)
				(mid 266.54506 -130.236722)
				(end 266.838176 -130.236722)
			)
		)
		(stroke
			(width 0)
			(type solid)
		)
		(fill yes)
		(layer "In13.Cu")
		(net "GND")
	)
	(gr_poly
		(pts
			(arc
				(start 266.838176 -123.885452)
				(mid 266.54506 -123.885452)
				(end 266.838176 -123.885452)
			)
		)
		(stroke
			(width 0)
			(type solid)
		)
		(fill yes)
		(layer "In13.Cu")
		(net "GND")
	)
	(gr_poly
		(pts
			(arc
				(start 266.838176 -122.626628)
				(mid 266.54506 -122.626628)
				(end 266.838176 -122.626628)
			)
		)
		(stroke
			(width 0)
			(type solid)
		)
		(fill yes)
		(layer "In13.Cu")
		(net "GND")
	)
	(gr_poly
		(pts
			(arc
				(start 266.838176 -120.28551)
				(mid 266.54506 -120.28551)
				(end 266.838176 -120.28551)
			)
		)
		(stroke
			(width 0)
			(type solid)
		)
		(fill yes)
		(layer "In13.Cu")
		(net "GND")
	)
	(gr_poly
		(pts
			(arc
				(start 266.838176 -119.026686)
				(mid 266.54506 -119.026686)
				(end 266.838176 -119.026686)
			)
		)
		(stroke
			(width 0)
			(type solid)
		)
		(fill yes)
		(layer "In13.Cu")
		(net "GND")
	)
	(gr_poly
		(pts
			(arc
				(start 266.838176 -112.981994)
				(mid 266.54506 -112.981994)
				(end 266.838176 -112.981994)
			)
		)
		(stroke
			(width 0)
			(type solid)
		)
		(fill yes)
		(layer "In13.Cu")
		(net "GND")
	)
	(gr_poly
		(pts
			(arc
				(start 266.838176 -111.72317)
				(mid 266.54506 -111.72317)
				(end 266.838176 -111.72317)
			)
		)
		(stroke
			(width 0)
			(type solid)
		)
		(fill yes)
		(layer "In13.Cu")
		(net "GND")
	)
	(gr_poly
		(pts
			(arc
				(start 266.838176 -109.382052)
				(mid 266.54506 -109.382052)
				(end 266.838176 -109.382052)
			)
		)
		(stroke
			(width 0)
			(type solid)
		)
		(fill yes)
		(layer "In13.Cu")
		(net "GND")
	)
	(gr_poly
		(pts
			(arc
				(start 266.838176 -108.123228)
				(mid 266.54506 -108.123228)
				(end 266.838176 -108.123228)
			)
		)
		(stroke
			(width 0)
			(type solid)
		)
		(fill yes)
		(layer "In13.Cu")
		(net "GND")
	)
	(gr_poly
		(pts
			(arc
				(start 266.838176 -105.78211)
				(mid 266.54506 -105.78211)
				(end 266.838176 -105.78211)
			)
		)
		(stroke
			(width 0)
			(type solid)
		)
		(fill yes)
		(layer "In13.Cu")
		(net "GND")
	)
	(gr_poly
		(pts
			(arc
				(start 266.838176 -104.523286)
				(mid 266.54506 -104.523286)
				(end 266.838176 -104.523286)
			)
		)
		(stroke
			(width 0)
			(type solid)
		)
		(fill yes)
		(layer "In13.Cu")
		(net "GND")
	)
	(gr_poly
		(pts
			(arc
				(start 267.447776 -102.181914)
				(mid 267.15466 -102.181914)
				(end 267.447776 -102.181914)
			)
		)
		(stroke
			(width 0)
			(type solid)
		)
		(fill yes)
		(layer "In13.Cu")
		(net "GND")
	)
	(gr_poly
		(pts
			(arc
				(start 267.447776 -100.92309)
				(mid 267.15466 -100.92309)
				(end 267.447776 -100.92309)
			)
		)
		(stroke
			(width 0)
			(type solid)
		)
		(fill yes)
		(layer "In13.Cu")
		(net "GND")
	)
	(gr_poly
		(pts
			(arc
				(start 268.106144 -135.095488)
				(mid 267.813028 -135.095488)
				(end 268.106144 -135.095488)
			)
		)
		(stroke
			(width 0)
			(type solid)
		)
		(fill yes)
		(layer "In13.Cu")
		(net "GND")
	)
	(gr_poly
		(pts
			(arc
				(start 268.106144 -133.836664)
				(mid 267.813028 -133.836664)
				(end 268.106144 -133.836664)
			)
		)
		(stroke
			(width 0)
			(type solid)
		)
		(fill yes)
		(layer "In13.Cu")
		(net "GND")
	)
	(gr_poly
		(pts
			(arc
				(start 268.106144 -131.495546)
				(mid 267.813028 -131.495546)
				(end 268.106144 -131.495546)
			)
		)
		(stroke
			(width 0)
			(type solid)
		)
		(fill yes)
		(layer "In13.Cu")
		(net "GND")
	)
	(gr_poly
		(pts
			(arc
				(start 268.106144 -130.236722)
				(mid 267.813028 -130.236722)
				(end 268.106144 -130.236722)
			)
		)
		(stroke
			(width 0)
			(type solid)
		)
		(fill yes)
		(layer "In13.Cu")
		(net "GND")
	)
	(gr_poly
		(pts
			(arc
				(start 268.106144 -123.885452)
				(mid 267.813028 -123.885452)
				(end 268.106144 -123.885452)
			)
		)
		(stroke
			(width 0)
			(type solid)
		)
		(fill yes)
		(layer "In13.Cu")
		(net "GND")
	)
	(gr_poly
		(pts
			(arc
				(start 268.106144 -122.626628)
				(mid 267.813028 -122.626628)
				(end 268.106144 -122.626628)
			)
		)
		(stroke
			(width 0)
			(type solid)
		)
		(fill yes)
		(layer "In13.Cu")
		(net "GND")
	)
	(gr_poly
		(pts
			(arc
				(start 268.106144 -120.28551)
				(mid 267.813028 -120.28551)
				(end 268.106144 -120.28551)
			)
		)
		(stroke
			(width 0)
			(type solid)
		)
		(fill yes)
		(layer "In13.Cu")
		(net "GND")
	)
	(gr_poly
		(pts
			(arc
				(start 268.106144 -119.026686)
				(mid 267.813028 -119.026686)
				(end 268.106144 -119.026686)
			)
		)
		(stroke
			(width 0)
			(type solid)
		)
		(fill yes)
		(layer "In13.Cu")
		(net "GND")
	)
	(gr_poly
		(pts
			(arc
				(start 268.106144 -112.981994)
				(mid 267.813028 -112.981994)
				(end 268.106144 -112.981994)
			)
		)
		(stroke
			(width 0)
			(type solid)
		)
		(fill yes)
		(layer "In13.Cu")
		(net "GND")
	)
	(gr_poly
		(pts
			(arc
				(start 268.106144 -111.72317)
				(mid 267.813028 -111.72317)
				(end 268.106144 -111.72317)
			)
		)
		(stroke
			(width 0)
			(type solid)
		)
		(fill yes)
		(layer "In13.Cu")
		(net "GND")
	)
	(gr_poly
		(pts
			(arc
				(start 268.106144 -109.382052)
				(mid 267.813028 -109.382052)
				(end 268.106144 -109.382052)
			)
		)
		(stroke
			(width 0)
			(type solid)
		)
		(fill yes)
		(layer "In13.Cu")
		(net "GND")
	)
	(gr_poly
		(pts
			(arc
				(start 268.106144 -108.123228)
				(mid 267.813028 -108.123228)
				(end 268.106144 -108.123228)
			)
		)
		(stroke
			(width 0)
			(type solid)
		)
		(fill yes)
		(layer "In13.Cu")
		(net "GND")
	)
	(gr_poly
		(pts
			(arc
				(start 268.106144 -105.78211)
				(mid 267.813028 -105.78211)
				(end 268.106144 -105.78211)
			)
		)
		(stroke
			(width 0)
			(type solid)
		)
		(fill yes)
		(layer "In13.Cu")
		(net "GND")
	)
	(gr_poly
		(pts
			(arc
				(start 268.106144 -104.523286)
				(mid 267.813028 -104.523286)
				(end 268.106144 -104.523286)
			)
		)
		(stroke
			(width 0)
			(type solid)
		)
		(fill yes)
		(layer "In13.Cu")
		(net "GND")
	)
	(gr_poly
		(pts
			(arc
				(start 268.715744 -102.181914)
				(mid 268.422628 -102.181914)
				(end 268.715744 -102.181914)
			)
		)
		(stroke
			(width 0)
			(type solid)
		)
		(fill yes)
		(layer "In13.Cu")
		(net "GND")
	)
	(gr_poly
		(pts
			(arc
				(start 268.715744 -100.92309)
				(mid 268.422628 -100.92309)
				(end 268.715744 -100.92309)
			)
		)
		(stroke
			(width 0)
			(type solid)
		)
		(fill yes)
		(layer "In13.Cu")
		(net "GND")
	)
	(gr_poly
		(pts
			(arc
				(start 269.480284 -136.901936)
				(mid 269.187168 -136.901936)
				(end 269.480284 -136.901936)
			)
		)
		(stroke
			(width 0)
			(type solid)
		)
		(fill yes)
		(layer "In13.Cu")
		(net "GND")
	)
	(gr_poly
		(pts
			(arc
				(start 269.480284 -135.643112)
				(mid 269.187168 -135.643112)
				(end 269.480284 -135.643112)
			)
		)
		(stroke
			(width 0)
			(type solid)
		)
		(fill yes)
		(layer "In13.Cu")
		(net "GND")
	)
	(gr_poly
		(pts
			(arc
				(start 269.480284 -133.301994)
				(mid 269.187168 -133.301994)
				(end 269.480284 -133.301994)
			)
		)
		(stroke
			(width 0)
			(type solid)
		)
		(fill yes)
		(layer "In13.Cu")
		(net "GND")
	)
	(gr_poly
		(pts
			(arc
				(start 269.480284 -132.04317)
				(mid 269.187168 -132.04317)
				(end 269.480284 -132.04317)
			)
		)
		(stroke
			(width 0)
			(type solid)
		)
		(fill yes)
		(layer "In13.Cu")
		(net "GND")
	)
	(gr_poly
		(pts
			(arc
				(start 269.480284 -125.692154)
				(mid 269.187168 -125.692154)
				(end 269.480284 -125.692154)
			)
		)
		(stroke
			(width 0)
			(type solid)
		)
		(fill yes)
		(layer "In13.Cu")
		(net "GND")
	)
	(gr_poly
		(pts
			(arc
				(start 269.480284 -124.43333)
				(mid 269.187168 -124.43333)
				(end 269.480284 -124.43333)
			)
		)
		(stroke
			(width 0)
			(type solid)
		)
		(fill yes)
		(layer "In13.Cu")
		(net "GND")
	)
	(gr_poly
		(pts
			(arc
				(start 269.480284 -122.091958)
				(mid 269.187168 -122.091958)
				(end 269.480284 -122.091958)
			)
		)
		(stroke
			(width 0)
			(type solid)
		)
		(fill yes)
		(layer "In13.Cu")
		(net "GND")
	)
	(gr_poly
		(pts
			(arc
				(start 269.480284 -120.833134)
				(mid 269.187168 -120.833134)
				(end 269.480284 -120.833134)
			)
		)
		(stroke
			(width 0)
			(type solid)
		)
		(fill yes)
		(layer "In13.Cu")
		(net "GND")
	)
	(gr_poly
		(pts
			(arc
				(start 269.480284 -111.175546)
				(mid 269.187168 -111.175546)
				(end 269.480284 -111.175546)
			)
		)
		(stroke
			(width 0)
			(type solid)
		)
		(fill yes)
		(layer "In13.Cu")
		(net "GND")
	)
	(gr_poly
		(pts
			(arc
				(start 269.480284 -109.916722)
				(mid 269.187168 -109.916722)
				(end 269.480284 -109.916722)
			)
		)
		(stroke
			(width 0)
			(type solid)
		)
		(fill yes)
		(layer "In13.Cu")
		(net "GND")
	)
	(gr_poly
		(pts
			(arc
				(start 269.480284 -107.57535)
				(mid 269.187168 -107.57535)
				(end 269.480284 -107.57535)
			)
		)
		(stroke
			(width 0)
			(type solid)
		)
		(fill yes)
		(layer "In13.Cu")
		(net "GND")
	)
	(gr_poly
		(pts
			(arc
				(start 269.480284 -106.316526)
				(mid 269.187168 -106.316526)
				(end 269.480284 -106.316526)
			)
		)
		(stroke
			(width 0)
			(type solid)
		)
		(fill yes)
		(layer "In13.Cu")
		(net "GND")
	)
	(gr_poly
		(pts
			(arc
				(start 269.480284 -103.975408)
				(mid 269.187168 -103.975408)
				(end 269.480284 -103.975408)
			)
		)
		(stroke
			(width 0)
			(type solid)
		)
		(fill yes)
		(layer "In13.Cu")
		(net "GND")
	)
	(gr_poly
		(pts
			(arc
				(start 269.480284 -102.716584)
				(mid 269.187168 -102.716584)
				(end 269.480284 -102.716584)
			)
		)
		(stroke
			(width 0)
			(type solid)
		)
		(fill yes)
		(layer "In13.Cu")
		(net "GND")
	)
	(gr_poly
		(pts
			(arc
				(start 269.480284 -100.375466)
				(mid 269.187168 -100.375466)
				(end 269.480284 -100.375466)
			)
		)
		(stroke
			(width 0)
			(type solid)
		)
		(fill yes)
		(layer "In13.Cu")
		(net "GND")
	)
	(gr_poly
		(pts
			(arc
				(start 269.480284 -99.116642)
				(mid 269.187168 -99.116642)
				(end 269.480284 -99.116642)
			)
		)
		(stroke
			(width 0)
			(type solid)
		)
		(fill yes)
		(layer "In13.Cu")
		(net "GND")
	)
	(gr_poly
		(pts
			(arc
				(start 270.748252 -136.901936)
				(mid 270.455136 -136.901936)
				(end 270.748252 -136.901936)
			)
		)
		(stroke
			(width 0)
			(type solid)
		)
		(fill yes)
		(layer "In13.Cu")
		(net "GND")
	)
	(gr_poly
		(pts
			(arc
				(start 270.748252 -135.643112)
				(mid 270.455136 -135.643112)
				(end 270.748252 -135.643112)
			)
		)
		(stroke
			(width 0)
			(type solid)
		)
		(fill yes)
		(layer "In13.Cu")
		(net "GND")
	)
	(gr_poly
		(pts
			(arc
				(start 270.748252 -133.301994)
				(mid 270.455136 -133.301994)
				(end 270.748252 -133.301994)
			)
		)
		(stroke
			(width 0)
			(type solid)
		)
		(fill yes)
		(layer "In13.Cu")
		(net "GND")
	)
	(gr_poly
		(pts
			(arc
				(start 270.748252 -132.04317)
				(mid 270.455136 -132.04317)
				(end 270.748252 -132.04317)
			)
		)
		(stroke
			(width 0)
			(type solid)
		)
		(fill yes)
		(layer "In13.Cu")
		(net "GND")
	)
	(gr_poly
		(pts
			(arc
				(start 270.748252 -125.692154)
				(mid 270.455136 -125.692154)
				(end 270.748252 -125.692154)
			)
		)
		(stroke
			(width 0)
			(type solid)
		)
		(fill yes)
		(layer "In13.Cu")
		(net "GND")
	)
	(gr_poly
		(pts
			(arc
				(start 270.748252 -124.43333)
				(mid 270.455136 -124.43333)
				(end 270.748252 -124.43333)
			)
		)
		(stroke
			(width 0)
			(type solid)
		)
		(fill yes)
		(layer "In13.Cu")
		(net "GND")
	)
	(gr_poly
		(pts
			(arc
				(start 270.748252 -122.091958)
				(mid 270.455136 -122.091958)
				(end 270.748252 -122.091958)
			)
		)
		(stroke
			(width 0)
			(type solid)
		)
		(fill yes)
		(layer "In13.Cu")
		(net "GND")
	)
	(gr_poly
		(pts
			(arc
				(start 270.748252 -120.833134)
				(mid 270.455136 -120.833134)
				(end 270.748252 -120.833134)
			)
		)
		(stroke
			(width 0)
			(type solid)
		)
		(fill yes)
		(layer "In13.Cu")
		(net "GND")
	)
	(gr_poly
		(pts
			(arc
				(start 270.748252 -111.175546)
				(mid 270.455136 -111.175546)
				(end 270.748252 -111.175546)
			)
		)
		(stroke
			(width 0)
			(type solid)
		)
		(fill yes)
		(layer "In13.Cu")
		(net "GND")
	)
	(gr_poly
		(pts
			(arc
				(start 270.748252 -109.916722)
				(mid 270.455136 -109.916722)
				(end 270.748252 -109.916722)
			)
		)
		(stroke
			(width 0)
			(type solid)
		)
		(fill yes)
		(layer "In13.Cu")
		(net "GND")
	)
	(gr_poly
		(pts
			(arc
				(start 270.748252 -107.57535)
				(mid 270.455136 -107.57535)
				(end 270.748252 -107.57535)
			)
		)
		(stroke
			(width 0)
			(type solid)
		)
		(fill yes)
		(layer "In13.Cu")
		(net "GND")
	)
	(gr_poly
		(pts
			(arc
				(start 270.748252 -106.316526)
				(mid 270.455136 -106.316526)
				(end 270.748252 -106.316526)
			)
		)
		(stroke
			(width 0)
			(type solid)
		)
		(fill yes)
		(layer "In13.Cu")
		(net "GND")
	)
	(gr_poly
		(pts
			(arc
				(start 270.748252 -103.975408)
				(mid 270.455136 -103.975408)
				(end 270.748252 -103.975408)
			)
		)
		(stroke
			(width 0)
			(type solid)
		)
		(fill yes)
		(layer "In13.Cu")
		(net "GND")
	)
	(gr_poly
		(pts
			(arc
				(start 270.748252 -102.716584)
				(mid 270.455136 -102.716584)
				(end 270.748252 -102.716584)
			)
		)
		(stroke
			(width 0)
			(type solid)
		)
		(fill yes)
		(layer "In13.Cu")
		(net "GND")
	)
	(gr_poly
		(pts
			(arc
				(start 270.748252 -100.375466)
				(mid 270.455136 -100.375466)
				(end 270.748252 -100.375466)
			)
		)
		(stroke
			(width 0)
			(type solid)
		)
		(fill yes)
		(layer "In13.Cu")
		(net "GND")
	)
	(gr_poly
		(pts
			(arc
				(start 270.748252 -99.116642)
				(mid 270.455136 -99.116642)
				(end 270.748252 -99.116642)
			)
		)
		(stroke
			(width 0)
			(type solid)
		)
		(fill yes)
		(layer "In13.Cu")
		(net "GND")
	)
	(gr_poly
		(pts
			(arc
				(start 272.26895 -266.827762)
				(mid 271.975834 -266.827762)
				(end 272.26895 -266.827762)
			)
		)
		(stroke
			(width 0)
			(type solid)
		)
		(fill yes)
		(layer "In13.Cu")
		(net "GND")
	)
	(gr_poly
		(pts
			(arc
				(start 272.343372 -268.739366)
				(mid 272.050256 -268.739366)
				(end 272.343372 -268.739366)
			)
		)
		(stroke
			(width 0)
			(type solid)
		)
		(fill yes)
		(layer "In13.Cu")
		(net "GND")
	)
	(gr_poly
		(pts
			(arc
				(start 273.768566 -82.174334)
				(mid 273.47545 -82.174334)
				(end 273.768566 -82.174334)
			)
		)
		(stroke
			(width 0)
			(type solid)
		)
		(fill yes)
		(layer "In13.Cu")
		(net "GND")
	)
	(gr_poly
		(pts
			(arc
				(start 273.768566 -80.91551)
				(mid 273.47545 -80.91551)
				(end 273.768566 -80.91551)
			)
		)
		(stroke
			(width 0)
			(type solid)
		)
		(fill yes)
		(layer "In13.Cu")
		(net "GND")
	)
	(gr_poly
		(pts
			(arc
				(start 273.921728 -84.438236)
				(mid 273.628612 -84.438236)
				(end 273.921728 -84.438236)
			)
		)
		(stroke
			(width 0)
			(type solid)
		)
		(fill yes)
		(layer "In13.Cu")
		(net "GND")
	)
	(gr_poly
		(pts
			(arc
				(start 273.921728 -83.179412)
				(mid 273.628612 -83.179412)
				(end 273.921728 -83.179412)
			)
		)
		(stroke
			(width 0)
			(type solid)
		)
		(fill yes)
		(layer "In13.Cu")
		(net "GND")
	)
	(gr_poly
		(pts
			(arc
				(start 274.418044 -262.734044)
				(mid 274.124928 -262.734044)
				(end 274.418044 -262.734044)
			)
		)
		(stroke
			(width 0)
			(type solid)
		)
		(fill yes)
		(layer "In13.Cu")
		(net "GND")
	)
	(gr_poly
		(pts
			(arc
				(start 274.43176 -87.79764)
				(mid 274.138644 -87.79764)
				(end 274.43176 -87.79764)
			)
		)
		(stroke
			(width 0)
			(type solid)
		)
		(fill yes)
		(layer "In13.Cu")
		(net "GND")
	)
	(gr_poly
		(pts
			(arc
				(start 284.756606 -156.802328)
				(mid 284.46349 -156.802328)
				(end 284.756606 -156.802328)
			)
		)
		(stroke
			(width 0)
			(type solid)
		)
		(fill yes)
		(layer "In13.Cu")
		(net "GND")
	)
	(gr_poly
		(pts
			(arc
				(start 284.886146 -154.3685)
				(mid 284.59303 -154.3685)
				(end 284.886146 -154.3685)
			)
		)
		(stroke
			(width 0)
			(type solid)
		)
		(fill yes)
		(layer "In13.Cu")
		(net "GND")
	)
	(gr_poly
		(pts
			(arc
				(start 284.929072 -155.58897)
				(mid 284.635956 -155.58897)
				(end 284.929072 -155.58897)
			)
		)
		(stroke
			(width 0)
			(type solid)
		)
		(fill yes)
		(layer "In13.Cu")
		(net "GND")
	)
	(gr_poly
		(pts
			(arc
				(start 285.19882 -137.16508)
				(mid 284.905704 -137.16508)
				(end 285.19882 -137.16508)
			)
		)
		(stroke
			(width 0)
			(type solid)
		)
		(fill yes)
		(layer "In13.Cu")
		(net "GND")
	)
	(gr_poly
		(pts
			(arc
				(start 285.19882 -135.364982)
				(mid 284.905704 -135.364982)
				(end 285.19882 -135.364982)
			)
		)
		(stroke
			(width 0)
			(type solid)
		)
		(fill yes)
		(layer "In13.Cu")
		(net "GND")
	)
	(gr_poly
		(pts
			(arc
				(start 285.19882 -133.564884)
				(mid 284.905704 -133.564884)
				(end 285.19882 -133.564884)
			)
		)
		(stroke
			(width 0)
			(type solid)
		)
		(fill yes)
		(layer "In13.Cu")
		(net "GND")
	)
	(gr_poly
		(pts
			(arc
				(start 285.19882 -131.76504)
				(mid 284.905704 -131.76504)
				(end 285.19882 -131.76504)
			)
		)
		(stroke
			(width 0)
			(type solid)
		)
		(fill yes)
		(layer "In13.Cu")
		(net "GND")
	)
	(gr_poly
		(pts
			(arc
				(start 285.19882 -125.955044)
				(mid 284.905704 -125.955044)
				(end 285.19882 -125.955044)
			)
		)
		(stroke
			(width 0)
			(type solid)
		)
		(fill yes)
		(layer "In13.Cu")
		(net "GND")
	)
	(gr_poly
		(pts
			(arc
				(start 285.19882 -124.154946)
				(mid 284.905704 -124.154946)
				(end 285.19882 -124.154946)
			)
		)
		(stroke
			(width 0)
			(type solid)
		)
		(fill yes)
		(layer "In13.Cu")
		(net "GND")
	)
	(gr_poly
		(pts
			(arc
				(start 285.19882 -122.354848)
				(mid 284.905704 -122.354848)
				(end 285.19882 -122.354848)
			)
		)
		(stroke
			(width 0)
			(type solid)
		)
		(fill yes)
		(layer "In13.Cu")
		(net "GND")
	)
	(gr_poly
		(pts
			(arc
				(start 285.19882 -120.555004)
				(mid 284.905704 -120.555004)
				(end 285.19882 -120.555004)
			)
		)
		(stroke
			(width 0)
			(type solid)
		)
		(fill yes)
		(layer "In13.Cu")
		(net "GND")
	)
	(gr_poly
		(pts
			(arc
				(start 285.19882 -113.245138)
				(mid 284.905704 -113.245138)
				(end 285.19882 -113.245138)
			)
		)
		(stroke
			(width 0)
			(type solid)
		)
		(fill yes)
		(layer "In13.Cu")
		(net "GND")
	)
	(gr_poly
		(pts
			(arc
				(start 285.19882 -111.44504)
				(mid 284.905704 -111.44504)
				(end 285.19882 -111.44504)
			)
		)
		(stroke
			(width 0)
			(type solid)
		)
		(fill yes)
		(layer "In13.Cu")
		(net "GND")
	)
	(gr_poly
		(pts
			(arc
				(start 285.19882 -109.644942)
				(mid 284.905704 -109.644942)
				(end 285.19882 -109.644942)
			)
		)
		(stroke
			(width 0)
			(type solid)
		)
		(fill yes)
		(layer "In13.Cu")
		(net "GND")
	)
	(gr_poly
		(pts
			(arc
				(start 285.19882 -107.844844)
				(mid 284.905704 -107.844844)
				(end 285.19882 -107.844844)
			)
		)
		(stroke
			(width 0)
			(type solid)
		)
		(fill yes)
		(layer "In13.Cu")
		(net "GND")
	)
	(gr_poly
		(pts
			(arc
				(start 285.19882 -106.045)
				(mid 284.905704 -106.045)
				(end 285.19882 -106.045)
			)
		)
		(stroke
			(width 0)
			(type solid)
		)
		(fill yes)
		(layer "In13.Cu")
		(net "GND")
	)
	(gr_poly
		(pts
			(arc
				(start 285.19882 -104.244902)
				(mid 284.905704 -104.244902)
				(end 285.19882 -104.244902)
			)
		)
		(stroke
			(width 0)
			(type solid)
		)
		(fill yes)
		(layer "In13.Cu")
		(net "GND")
	)
	(gr_poly
		(pts
			(arc
				(start 285.19882 -102.445058)
				(mid 284.905704 -102.445058)
				(end 285.19882 -102.445058)
			)
		)
		(stroke
			(width 0)
			(type solid)
		)
		(fill yes)
		(layer "In13.Cu")
		(net "GND")
	)
	(gr_poly
		(pts
			(arc
				(start 285.19882 -100.64496)
				(mid 284.905704 -100.64496)
				(end 285.19882 -100.64496)
			)
		)
		(stroke
			(width 0)
			(type solid)
		)
		(fill yes)
		(layer "In13.Cu")
		(net "GND")
	)
	(gr_poly
		(pts
			(arc
				(start 285.29026 -24.648414)
				(mid 284.997144 -24.648414)
				(end 285.29026 -24.648414)
			)
		)
		(stroke
			(width 0)
			(type solid)
		)
		(fill yes)
		(layer "In13.Cu")
		(net "GND")
	)
	(gr_poly
		(pts
			(arc
				(start 285.31693 -152.109678)
				(mid 285.023814 -152.109678)
				(end 285.31693 -152.109678)
			)
		)
		(stroke
			(width 0)
			(type solid)
		)
		(fill yes)
		(layer "In13.Cu")
		(net "GND")
	)
	(gr_poly
		(pts
			(arc
				(start 285.83382 -135.364982)
				(mid 285.540704 -135.364982)
				(end 285.83382 -135.364982)
			)
		)
		(stroke
			(width 0)
			(type solid)
		)
		(fill yes)
		(layer "In13.Cu")
		(net "GND")
	)
	(gr_poly
		(pts
			(arc
				(start 285.83382 -133.564884)
				(mid 285.540704 -133.564884)
				(end 285.83382 -133.564884)
			)
		)
		(stroke
			(width 0)
			(type solid)
		)
		(fill yes)
		(layer "In13.Cu")
		(net "GND")
	)
	(gr_poly
		(pts
			(arc
				(start 285.83382 -131.76504)
				(mid 285.540704 -131.76504)
				(end 285.83382 -131.76504)
			)
		)
		(stroke
			(width 0)
			(type solid)
		)
		(fill yes)
		(layer "In13.Cu")
		(net "GND")
	)
	(gr_poly
		(pts
			(arc
				(start 285.83382 -129.964942)
				(mid 285.540704 -129.964942)
				(end 285.83382 -129.964942)
			)
		)
		(stroke
			(width 0)
			(type solid)
		)
		(fill yes)
		(layer "In13.Cu")
		(net "GND")
	)
	(gr_poly
		(pts
			(arc
				(start 285.83382 -124.154946)
				(mid 285.540704 -124.154946)
				(end 285.83382 -124.154946)
			)
		)
		(stroke
			(width 0)
			(type solid)
		)
		(fill yes)
		(layer "In13.Cu")
		(net "GND")
	)
	(gr_poly
		(pts
			(arc
				(start 285.83382 -122.354848)
				(mid 285.540704 -122.354848)
				(end 285.83382 -122.354848)
			)
		)
		(stroke
			(width 0)
			(type solid)
		)
		(fill yes)
		(layer "In13.Cu")
		(net "GND")
	)
	(gr_poly
		(pts
			(arc
				(start 285.83382 -120.555004)
				(mid 285.540704 -120.555004)
				(end 285.83382 -120.555004)
			)
		)
		(stroke
			(width 0)
			(type solid)
		)
		(fill yes)
		(layer "In13.Cu")
		(net "GND")
	)
	(gr_poly
		(pts
			(arc
				(start 285.83382 -118.754906)
				(mid 285.540704 -118.754906)
				(end 285.83382 -118.754906)
			)
		)
		(stroke
			(width 0)
			(type solid)
		)
		(fill yes)
		(layer "In13.Cu")
		(net "GND")
	)
	(gr_poly
		(pts
			(arc
				(start 285.83382 -111.44504)
				(mid 285.540704 -111.44504)
				(end 285.83382 -111.44504)
			)
		)
		(stroke
			(width 0)
			(type solid)
		)
		(fill yes)
		(layer "In13.Cu")
		(net "GND")
	)
	(gr_poly
		(pts
			(arc
				(start 285.83382 -109.644942)
				(mid 285.540704 -109.644942)
				(end 285.83382 -109.644942)
			)
		)
		(stroke
			(width 0)
			(type solid)
		)
		(fill yes)
		(layer "In13.Cu")
		(net "GND")
	)
	(gr_poly
		(pts
			(arc
				(start 285.83382 -107.844844)
				(mid 285.540704 -107.844844)
				(end 285.83382 -107.844844)
			)
		)
		(stroke
			(width 0)
			(type solid)
		)
		(fill yes)
		(layer "In13.Cu")
		(net "GND")
	)
	(gr_poly
		(pts
			(arc
				(start 285.83382 -106.044746)
				(mid 285.540704 -106.044746)
				(end 285.83382 -106.044746)
			)
		)
		(stroke
			(width 0)
			(type solid)
		)
		(fill yes)
		(layer "In13.Cu")
		(net "GND")
	)
	(gr_poly
		(pts
			(arc
				(start 285.83382 -104.244902)
				(mid 285.540704 -104.244902)
				(end 285.83382 -104.244902)
			)
		)
		(stroke
			(width 0)
			(type solid)
		)
		(fill yes)
		(layer "In13.Cu")
		(net "GND")
	)
	(gr_poly
		(pts
			(arc
				(start 285.83382 -102.444804)
				(mid 285.540704 -102.444804)
				(end 285.83382 -102.444804)
			)
		)
		(stroke
			(width 0)
			(type solid)
		)
		(fill yes)
		(layer "In13.Cu")
		(net "GND")
	)
	(gr_poly
		(pts
			(arc
				(start 285.83382 -100.64496)
				(mid 285.540704 -100.64496)
				(end 285.83382 -100.64496)
			)
		)
		(stroke
			(width 0)
			(type solid)
		)
		(fill yes)
		(layer "In13.Cu")
		(net "GND")
	)
	(gr_poly
		(pts
			(arc
				(start 285.83382 -98.844862)
				(mid 285.540704 -98.844862)
				(end 285.83382 -98.844862)
			)
		)
		(stroke
			(width 0)
			(type solid)
		)
		(fill yes)
		(layer "In13.Cu")
		(net "GND")
	)
	(gr_poly
		(pts
			(arc
				(start 287.05302 -135.364982)
				(mid 286.759904 -135.364982)
				(end 287.05302 -135.364982)
			)
		)
		(stroke
			(width 0)
			(type solid)
		)
		(fill yes)
		(layer "In13.Cu")
		(net "GND")
	)
	(gr_poly
		(pts
			(arc
				(start 287.05302 -133.564884)
				(mid 286.759904 -133.564884)
				(end 287.05302 -133.564884)
			)
		)
		(stroke
			(width 0)
			(type solid)
		)
		(fill yes)
		(layer "In13.Cu")
		(net "GND")
	)
	(gr_poly
		(pts
			(arc
				(start 287.05302 -131.76504)
				(mid 286.759904 -131.76504)
				(end 287.05302 -131.76504)
			)
		)
		(stroke
			(width 0)
			(type solid)
		)
		(fill yes)
		(layer "In13.Cu")
		(net "GND")
	)
	(gr_poly
		(pts
			(arc
				(start 287.05302 -129.964942)
				(mid 286.759904 -129.964942)
				(end 287.05302 -129.964942)
			)
		)
		(stroke
			(width 0)
			(type solid)
		)
		(fill yes)
		(layer "In13.Cu")
		(net "GND")
	)
	(gr_poly
		(pts
			(arc
				(start 287.05302 -124.154946)
				(mid 286.759904 -124.154946)
				(end 287.05302 -124.154946)
			)
		)
		(stroke
			(width 0)
			(type solid)
		)
		(fill yes)
		(layer "In13.Cu")
		(net "GND")
	)
	(gr_poly
		(pts
			(arc
				(start 287.05302 -122.354848)
				(mid 286.759904 -122.354848)
				(end 287.05302 -122.354848)
			)
		)
		(stroke
			(width 0)
			(type solid)
		)
		(fill yes)
		(layer "In13.Cu")
		(net "GND")
	)
	(gr_poly
		(pts
			(arc
				(start 287.05302 -120.555004)
				(mid 286.759904 -120.555004)
				(end 287.05302 -120.555004)
			)
		)
		(stroke
			(width 0)
			(type solid)
		)
		(fill yes)
		(layer "In13.Cu")
		(net "GND")
	)
	(gr_poly
		(pts
			(arc
				(start 287.05302 -118.754906)
				(mid 286.759904 -118.754906)
				(end 287.05302 -118.754906)
			)
		)
		(stroke
			(width 0)
			(type solid)
		)
		(fill yes)
		(layer "In13.Cu")
		(net "GND")
	)
	(gr_poly
		(pts
			(arc
				(start 287.05302 -111.44504)
				(mid 286.759904 -111.44504)
				(end 287.05302 -111.44504)
			)
		)
		(stroke
			(width 0)
			(type solid)
		)
		(fill yes)
		(layer "In13.Cu")
		(net "GND")
	)
	(gr_poly
		(pts
			(arc
				(start 287.05302 -109.644942)
				(mid 286.759904 -109.644942)
				(end 287.05302 -109.644942)
			)
		)
		(stroke
			(width 0)
			(type solid)
		)
		(fill yes)
		(layer "In13.Cu")
		(net "GND")
	)
	(gr_poly
		(pts
			(arc
				(start 287.05302 -107.844844)
				(mid 286.759904 -107.844844)
				(end 287.05302 -107.844844)
			)
		)
		(stroke
			(width 0)
			(type solid)
		)
		(fill yes)
		(layer "In13.Cu")
		(net "GND")
	)
	(gr_poly
		(pts
			(arc
				(start 287.05302 -106.044746)
				(mid 286.759904 -106.044746)
				(end 287.05302 -106.044746)
			)
		)
		(stroke
			(width 0)
			(type solid)
		)
		(fill yes)
		(layer "In13.Cu")
		(net "GND")
	)
	(gr_poly
		(pts
			(arc
				(start 287.05302 -104.244902)
				(mid 286.759904 -104.244902)
				(end 287.05302 -104.244902)
			)
		)
		(stroke
			(width 0)
			(type solid)
		)
		(fill yes)
		(layer "In13.Cu")
		(net "GND")
	)
	(gr_poly
		(pts
			(arc
				(start 287.05302 -102.444804)
				(mid 286.759904 -102.444804)
				(end 287.05302 -102.444804)
			)
		)
		(stroke
			(width 0)
			(type solid)
		)
		(fill yes)
		(layer "In13.Cu")
		(net "GND")
	)
	(gr_poly
		(pts
			(arc
				(start 287.05302 -100.64496)
				(mid 286.759904 -100.64496)
				(end 287.05302 -100.64496)
			)
		)
		(stroke
			(width 0)
			(type solid)
		)
		(fill yes)
		(layer "In13.Cu")
		(net "GND")
	)
	(gr_poly
		(pts
			(arc
				(start 287.05302 -98.844862)
				(mid 286.759904 -98.844862)
				(end 287.05302 -98.844862)
			)
		)
		(stroke
			(width 0)
			(type solid)
		)
		(fill yes)
		(layer "In13.Cu")
		(net "GND")
	)
	(gr_poly
		(pts
			(arc
				(start 290.947348 -34.98977)
				(mid 290.654232 -34.98977)
				(end 290.947348 -34.98977)
			)
		)
		(stroke
			(width 0)
			(type solid)
		)
		(fill yes)
		(layer "In13.Cu")
		(net "GND")
	)
	(gr_poly
		(pts
			(arc
				(start 290.947348 -33.189926)
				(mid 290.654232 -33.189926)
				(end 290.947348 -33.189926)
			)
		)
		(stroke
			(width 0)
			(type solid)
		)
		(fill yes)
		(layer "In13.Cu")
		(net "GND")
	)
	(gr_poly
		(pts
			(arc
				(start 290.947348 -31.389828)
				(mid 290.654232 -31.389828)
				(end 290.947348 -31.389828)
			)
		)
		(stroke
			(width 0)
			(type solid)
		)
		(fill yes)
		(layer "In13.Cu")
		(net "GND")
	)
	(gr_poly
		(pts
			(arc
				(start 290.947348 -29.589984)
				(mid 290.654232 -29.589984)
				(end 290.947348 -29.589984)
			)
		)
		(stroke
			(width 0)
			(type solid)
		)
		(fill yes)
		(layer "In13.Cu")
		(net "GND")
	)
	(gr_poly
		(pts
			(arc
				(start 292.166548 -34.98977)
				(mid 291.873432 -34.98977)
				(end 292.166548 -34.98977)
			)
		)
		(stroke
			(width 0)
			(type solid)
		)
		(fill yes)
		(layer "In13.Cu")
		(net "GND")
	)
	(gr_poly
		(pts
			(arc
				(start 292.166548 -33.189926)
				(mid 291.873432 -33.189926)
				(end 292.166548 -33.189926)
			)
		)
		(stroke
			(width 0)
			(type solid)
		)
		(fill yes)
		(layer "In13.Cu")
		(net "GND")
	)
	(gr_poly
		(pts
			(arc
				(start 292.166548 -31.389828)
				(mid 291.873432 -31.389828)
				(end 292.166548 -31.389828)
			)
		)
		(stroke
			(width 0)
			(type solid)
		)
		(fill yes)
		(layer "In13.Cu")
		(net "GND")
	)
	(gr_poly
		(pts
			(arc
				(start 292.166548 -29.589984)
				(mid 291.873432 -29.589984)
				(end 292.166548 -29.589984)
			)
		)
		(stroke
			(width 0)
			(type solid)
		)
		(fill yes)
		(layer "In13.Cu")
		(net "GND")
	)
	(gr_poly
		(pts
			(arc
				(start 292.801548 -33.189926)
				(mid 292.508432 -33.189926)
				(end 292.801548 -33.189926)
			)
		)
		(stroke
			(width 0)
			(type solid)
		)
		(fill yes)
		(layer "In13.Cu")
		(net "GND")
	)
	(gr_poly
		(pts
			(arc
				(start 292.801548 -31.389828)
				(mid 292.508432 -31.389828)
				(end 292.801548 -31.389828)
			)
		)
		(stroke
			(width 0)
			(type solid)
		)
		(fill yes)
		(layer "In13.Cu")
		(net "GND")
	)
	(gr_poly
		(pts
			(arc
				(start 292.801548 -29.589984)
				(mid 292.508432 -29.589984)
				(end 292.801548 -29.589984)
			)
		)
		(stroke
			(width 0)
			(type solid)
		)
		(fill yes)
		(layer "In13.Cu")
		(net "GND")
	)
	(gr_poly
		(pts
			(arc
				(start 292.801548 -27.789886)
				(mid 292.508432 -27.789886)
				(end 292.801548 -27.789886)
			)
		)
		(stroke
			(width 0)
			(type solid)
		)
		(fill yes)
		(layer "In13.Cu")
		(net "GND")
	)
	(gr_poly
		(pts
			(arc
				(start 295.110154 -139.817348)
				(mid 294.817038 -139.817348)
				(end 295.110154 -139.817348)
			)
		)
		(stroke
			(width 0)
			(type solid)
		)
		(fill yes)
		(layer "In13.Cu")
		(net "GND")
	)
	(gr_poly
		(pts
			(arc
				(start 296.756582 -23.554182)
				(mid 296.463466 -23.554182)
				(end 296.756582 -23.554182)
			)
		)
		(stroke
			(width 0)
			(type solid)
		)
		(fill yes)
		(layer "In13.Cu")
		(net "GND")
	)
	(gr_poly
		(pts
			(arc
				(start 296.93997 -156.555186)
				(mid 296.646854 -156.555186)
				(end 296.93997 -156.555186)
			)
		)
		(stroke
			(width 0)
			(type solid)
		)
		(fill yes)
		(layer "In13.Cu")
		(net "GND")
	)
	(gr_poly
		(pts
			(arc
				(start 296.93997 -154.755088)
				(mid 296.646854 -154.755088)
				(end 296.93997 -154.755088)
			)
		)
		(stroke
			(width 0)
			(type solid)
		)
		(fill yes)
		(layer "In13.Cu")
		(net "GND")
	)
	(gr_poly
		(pts
			(arc
				(start 296.93997 -152.955244)
				(mid 296.646854 -152.955244)
				(end 296.93997 -152.955244)
			)
		)
		(stroke
			(width 0)
			(type solid)
		)
		(fill yes)
		(layer "In13.Cu")
		(net "GND")
	)
	(gr_poly
		(pts
			(arc
				(start 296.93997 -151.155146)
				(mid 296.646854 -151.155146)
				(end 296.93997 -151.155146)
			)
		)
		(stroke
			(width 0)
			(type solid)
		)
		(fill yes)
		(layer "In13.Cu")
		(net "GND")
	)
	(gr_poly
		(pts
			(arc
				(start 296.93997 -149.355302)
				(mid 296.646854 -149.355302)
				(end 296.93997 -149.355302)
			)
		)
		(stroke
			(width 0)
			(type solid)
		)
		(fill yes)
		(layer "In13.Cu")
		(net "GND")
	)
	(gr_poly
		(pts
			(arc
				(start 296.93997 -147.555204)
				(mid 296.646854 -147.555204)
				(end 296.93997 -147.555204)
			)
		)
		(stroke
			(width 0)
			(type solid)
		)
		(fill yes)
		(layer "In13.Cu")
		(net "GND")
	)
	(gr_poly
		(pts
			(arc
				(start 296.93997 -145.75536)
				(mid 296.646854 -145.75536)
				(end 296.93997 -145.75536)
			)
		)
		(stroke
			(width 0)
			(type solid)
		)
		(fill yes)
		(layer "In13.Cu")
		(net "GND")
	)
	(gr_poly
		(pts
			(arc
				(start 296.93997 -143.955262)
				(mid 296.646854 -143.955262)
				(end 296.93997 -143.955262)
			)
		)
		(stroke
			(width 0)
			(type solid)
		)
		(fill yes)
		(layer "In13.Cu")
		(net "GND")
	)
	(gr_poly
		(pts
			(arc
				(start 296.93997 -136.645142)
				(mid 296.646854 -136.645142)
				(end 296.93997 -136.645142)
			)
		)
		(stroke
			(width 0)
			(type solid)
		)
		(fill yes)
		(layer "In13.Cu")
		(net "GND")
	)
	(gr_poly
		(pts
			(arc
				(start 296.93997 -134.845044)
				(mid 296.646854 -134.845044)
				(end 296.93997 -134.845044)
			)
		)
		(stroke
			(width 0)
			(type solid)
		)
		(fill yes)
		(layer "In13.Cu")
		(net "GND")
	)
	(gr_poly
		(pts
			(arc
				(start 296.93997 -133.0452)
				(mid 296.646854 -133.0452)
				(end 296.93997 -133.0452)
			)
		)
		(stroke
			(width 0)
			(type solid)
		)
		(fill yes)
		(layer "In13.Cu")
		(net "GND")
	)
	(gr_poly
		(pts
			(arc
				(start 296.93997 -131.245102)
				(mid 296.646854 -131.245102)
				(end 296.93997 -131.245102)
			)
		)
		(stroke
			(width 0)
			(type solid)
		)
		(fill yes)
		(layer "In13.Cu")
		(net "GND")
	)
	(gr_poly
		(pts
			(arc
				(start 296.93997 -125.435106)
				(mid 296.646854 -125.435106)
				(end 296.93997 -125.435106)
			)
		)
		(stroke
			(width 0)
			(type solid)
		)
		(fill yes)
		(layer "In13.Cu")
		(net "GND")
	)
	(gr_poly
		(pts
			(arc
				(start 296.93997 -123.635008)
				(mid 296.646854 -123.635008)
				(end 296.93997 -123.635008)
			)
		)
		(stroke
			(width 0)
			(type solid)
		)
		(fill yes)
		(layer "In13.Cu")
		(net "GND")
	)
	(gr_poly
		(pts
			(arc
				(start 296.93997 -121.835164)
				(mid 296.646854 -121.835164)
				(end 296.93997 -121.835164)
			)
		)
		(stroke
			(width 0)
			(type solid)
		)
		(fill yes)
		(layer "In13.Cu")
		(net "GND")
	)
	(gr_poly
		(pts
			(arc
				(start 296.93997 -120.035066)
				(mid 296.646854 -120.035066)
				(end 296.93997 -120.035066)
			)
		)
		(stroke
			(width 0)
			(type solid)
		)
		(fill yes)
		(layer "In13.Cu")
		(net "GND")
	)
	(gr_poly
		(pts
			(arc
				(start 298.15917 -156.555186)
				(mid 297.866054 -156.555186)
				(end 298.15917 -156.555186)
			)
		)
		(stroke
			(width 0)
			(type solid)
		)
		(fill yes)
		(layer "In13.Cu")
		(net "GND")
	)
	(gr_poly
		(pts
			(arc
				(start 298.15917 -154.755088)
				(mid 297.866054 -154.755088)
				(end 298.15917 -154.755088)
			)
		)
		(stroke
			(width 0)
			(type solid)
		)
		(fill yes)
		(layer "In13.Cu")
		(net "GND")
	)
	(gr_poly
		(pts
			(arc
				(start 298.15917 -152.955244)
				(mid 297.866054 -152.955244)
				(end 298.15917 -152.955244)
			)
		)
		(stroke
			(width 0)
			(type solid)
		)
		(fill yes)
		(layer "In13.Cu")
		(net "GND")
	)
	(gr_poly
		(pts
			(arc
				(start 298.15917 -151.155146)
				(mid 297.866054 -151.155146)
				(end 298.15917 -151.155146)
			)
		)
		(stroke
			(width 0)
			(type solid)
		)
		(fill yes)
		(layer "In13.Cu")
		(net "GND")
	)
	(gr_poly
		(pts
			(arc
				(start 298.15917 -149.355302)
				(mid 297.866054 -149.355302)
				(end 298.15917 -149.355302)
			)
		)
		(stroke
			(width 0)
			(type solid)
		)
		(fill yes)
		(layer "In13.Cu")
		(net "GND")
	)
	(gr_poly
		(pts
			(arc
				(start 298.15917 -147.555204)
				(mid 297.866054 -147.555204)
				(end 298.15917 -147.555204)
			)
		)
		(stroke
			(width 0)
			(type solid)
		)
		(fill yes)
		(layer "In13.Cu")
		(net "GND")
	)
	(gr_poly
		(pts
			(arc
				(start 298.15917 -145.75536)
				(mid 297.866054 -145.75536)
				(end 298.15917 -145.75536)
			)
		)
		(stroke
			(width 0)
			(type solid)
		)
		(fill yes)
		(layer "In13.Cu")
		(net "GND")
	)
	(gr_poly
		(pts
			(arc
				(start 298.15917 -143.955262)
				(mid 297.866054 -143.955262)
				(end 298.15917 -143.955262)
			)
		)
		(stroke
			(width 0)
			(type solid)
		)
		(fill yes)
		(layer "In13.Cu")
		(net "GND")
	)
	(gr_poly
		(pts
			(arc
				(start 298.15917 -136.645142)
				(mid 297.866054 -136.645142)
				(end 298.15917 -136.645142)
			)
		)
		(stroke
			(width 0)
			(type solid)
		)
		(fill yes)
		(layer "In13.Cu")
		(net "GND")
	)
	(gr_poly
		(pts
			(arc
				(start 298.15917 -134.845044)
				(mid 297.866054 -134.845044)
				(end 298.15917 -134.845044)
			)
		)
		(stroke
			(width 0)
			(type solid)
		)
		(fill yes)
		(layer "In13.Cu")
		(net "GND")
	)
	(gr_poly
		(pts
			(arc
				(start 298.15917 -133.0452)
				(mid 297.866054 -133.0452)
				(end 298.15917 -133.0452)
			)
		)
		(stroke
			(width 0)
			(type solid)
		)
		(fill yes)
		(layer "In13.Cu")
		(net "GND")
	)
	(gr_poly
		(pts
			(arc
				(start 298.15917 -131.245102)
				(mid 297.866054 -131.245102)
				(end 298.15917 -131.245102)
			)
		)
		(stroke
			(width 0)
			(type solid)
		)
		(fill yes)
		(layer "In13.Cu")
		(net "GND")
	)
	(gr_poly
		(pts
			(arc
				(start 298.15917 -125.435106)
				(mid 297.866054 -125.435106)
				(end 298.15917 -125.435106)
			)
		)
		(stroke
			(width 0)
			(type solid)
		)
		(fill yes)
		(layer "In13.Cu")
		(net "GND")
	)
	(gr_poly
		(pts
			(arc
				(start 298.15917 -123.635008)
				(mid 297.866054 -123.635008)
				(end 298.15917 -123.635008)
			)
		)
		(stroke
			(width 0)
			(type solid)
		)
		(fill yes)
		(layer "In13.Cu")
		(net "GND")
	)
	(gr_poly
		(pts
			(arc
				(start 298.15917 -121.835164)
				(mid 297.866054 -121.835164)
				(end 298.15917 -121.835164)
			)
		)
		(stroke
			(width 0)
			(type solid)
		)
		(fill yes)
		(layer "In13.Cu")
		(net "GND")
	)
	(gr_poly
		(pts
			(arc
				(start 298.15917 -120.035066)
				(mid 297.866054 -120.035066)
				(end 298.15917 -120.035066)
			)
		)
		(stroke
			(width 0)
			(type solid)
		)
		(fill yes)
		(layer "In13.Cu")
		(net "GND")
	)
	(gr_poly
		(pts
			(arc
				(start 298.79417 -154.755088)
				(mid 298.501054 -154.755088)
				(end 298.79417 -154.755088)
			)
		)
		(stroke
			(width 0)
			(type solid)
		)
		(fill yes)
		(layer "In13.Cu")
		(net "GND")
	)
	(gr_poly
		(pts
			(arc
				(start 298.79417 -152.95499)
				(mid 298.501054 -152.95499)
				(end 298.79417 -152.95499)
			)
		)
		(stroke
			(width 0)
			(type solid)
		)
		(fill yes)
		(layer "In13.Cu")
		(net "GND")
	)
	(gr_poly
		(pts
			(arc
				(start 298.79417 -151.155146)
				(mid 298.501054 -151.155146)
				(end 298.79417 -151.155146)
			)
		)
		(stroke
			(width 0)
			(type solid)
		)
		(fill yes)
		(layer "In13.Cu")
		(net "GND")
	)
	(gr_poly
		(pts
			(arc
				(start 298.79417 -149.355048)
				(mid 298.501054 -149.355048)
				(end 298.79417 -149.355048)
			)
		)
		(stroke
			(width 0)
			(type solid)
		)
		(fill yes)
		(layer "In13.Cu")
		(net "GND")
	)
	(gr_poly
		(pts
			(arc
				(start 298.79417 -147.555204)
				(mid 298.501054 -147.555204)
				(end 298.79417 -147.555204)
			)
		)
		(stroke
			(width 0)
			(type solid)
		)
		(fill yes)
		(layer "In13.Cu")
		(net "GND")
	)
	(gr_poly
		(pts
			(arc
				(start 298.79417 -145.755106)
				(mid 298.501054 -145.755106)
				(end 298.79417 -145.755106)
			)
		)
		(stroke
			(width 0)
			(type solid)
		)
		(fill yes)
		(layer "In13.Cu")
		(net "GND")
	)
	(gr_poly
		(pts
			(arc
				(start 298.79417 -143.955262)
				(mid 298.501054 -143.955262)
				(end 298.79417 -143.955262)
			)
		)
		(stroke
			(width 0)
			(type solid)
		)
		(fill yes)
		(layer "In13.Cu")
		(net "GND")
	)
	(gr_poly
		(pts
			(arc
				(start 298.79417 -142.155164)
				(mid 298.501054 -142.155164)
				(end 298.79417 -142.155164)
			)
		)
		(stroke
			(width 0)
			(type solid)
		)
		(fill yes)
		(layer "In13.Cu")
		(net "GND")
	)
	(gr_poly
		(pts
			(arc
				(start 298.79417 -134.845044)
				(mid 298.501054 -134.845044)
				(end 298.79417 -134.845044)
			)
		)
		(stroke
			(width 0)
			(type solid)
		)
		(fill yes)
		(layer "In13.Cu")
		(net "GND")
	)
	(gr_poly
		(pts
			(arc
				(start 298.79417 -133.0452)
				(mid 298.501054 -133.0452)
				(end 298.79417 -133.0452)
			)
		)
		(stroke
			(width 0)
			(type solid)
		)
		(fill yes)
		(layer "In13.Cu")
		(net "GND")
	)
	(gr_poly
		(pts
			(arc
				(start 298.79417 -131.245102)
				(mid 298.501054 -131.245102)
				(end 298.79417 -131.245102)
			)
		)
		(stroke
			(width 0)
			(type solid)
		)
		(fill yes)
		(layer "In13.Cu")
		(net "GND")
	)
	(gr_poly
		(pts
			(arc
				(start 298.79417 -123.635008)
				(mid 298.501054 -123.635008)
				(end 298.79417 -123.635008)
			)
		)
		(stroke
			(width 0)
			(type solid)
		)
		(fill yes)
		(layer "In13.Cu")
		(net "GND")
	)
	(gr_poly
		(pts
			(arc
				(start 298.79417 -121.83491)
				(mid 298.501054 -121.83491)
				(end 298.79417 -121.83491)
			)
		)
		(stroke
			(width 0)
			(type solid)
		)
		(fill yes)
		(layer "In13.Cu")
		(net "GND")
	)
	(gr_poly
		(pts
			(arc
				(start 298.79417 -120.035066)
				(mid 298.501054 -120.035066)
				(end 298.79417 -120.035066)
			)
		)
		(stroke
			(width 0)
			(type solid)
		)
		(fill yes)
		(layer "In13.Cu")
		(net "GND")
	)
	(gr_poly
		(pts
			(arc
				(start 298.79417 -118.234968)
				(mid 298.501054 -118.234968)
				(end 298.79417 -118.234968)
			)
		)
		(stroke
			(width 0)
			(type solid)
		)
		(fill yes)
		(layer "In13.Cu")
		(net "GND")
	)
	(gr_poly
		(pts
			(arc
				(start 299.06849 -77.859636)
				(mid 298.775374 -77.859636)
				(end 299.06849 -77.859636)
			)
		)
		(stroke
			(width 0)
			(type solid)
		)
		(fill yes)
		(layer "In13.Cu")
		(net "GND")
	)
	(gr_poly
		(pts
			(arc
				(start 302.42256 -214.471758)
				(mid 302.129444 -214.471758)
				(end 302.42256 -214.471758)
			)
		)
		(stroke
			(width 0)
			(type solid)
		)
		(fill yes)
		(layer "In13.Cu")
		(net "GND")
	)
	(gr_poly
		(pts
			(arc
				(start 303.041558 -81.8896)
				(mid 302.748442 -81.8896)
				(end 303.041558 -81.8896)
			)
		)
		(stroke
			(width 0)
			(type solid)
		)
		(fill yes)
		(layer "In13.Cu")
		(net "GND")
	)
	(gr_poly
		(pts
			(arc
				(start 311.306972 -24.658066)
				(mid 311.013856 -24.658066)
				(end 311.306972 -24.658066)
			)
		)
		(stroke
			(width 0)
			(type solid)
		)
		(fill yes)
		(layer "In13.Cu")
		(net "GND")
	)
	(gr_poly
		(pts
			(arc
				(start 313.244738 -154.476958)
				(mid 312.951622 -154.476958)
				(end 313.244738 -154.476958)
			)
		)
		(stroke
			(width 0)
			(type solid)
		)
		(fill yes)
		(layer "In13.Cu")
		(net "GND")
	)
	(gr_poly
		(pts
			(arc
				(start 313.244738 -153.218134)
				(mid 312.951622 -153.218134)
				(end 313.244738 -153.218134)
			)
		)
		(stroke
			(width 0)
			(type solid)
		)
		(fill yes)
		(layer "In13.Cu")
		(net "GND")
	)
	(gr_poly
		(pts
			(arc
				(start 313.244738 -150.876762)
				(mid 312.951622 -150.876762)
				(end 313.244738 -150.876762)
			)
		)
		(stroke
			(width 0)
			(type solid)
		)
		(fill yes)
		(layer "In13.Cu")
		(net "GND")
	)
	(gr_poly
		(pts
			(arc
				(start 313.244738 -149.617938)
				(mid 312.951622 -149.617938)
				(end 313.244738 -149.617938)
			)
		)
		(stroke
			(width 0)
			(type solid)
		)
		(fill yes)
		(layer "In13.Cu")
		(net "GND")
	)
	(gr_poly
		(pts
			(arc
				(start 313.244738 -147.27682)
				(mid 312.951622 -147.27682)
				(end 313.244738 -147.27682)
			)
		)
		(stroke
			(width 0)
			(type solid)
		)
		(fill yes)
		(layer "In13.Cu")
		(net "GND")
	)
	(gr_poly
		(pts
			(arc
				(start 313.244738 -146.017996)
				(mid 312.951622 -146.017996)
				(end 313.244738 -146.017996)
			)
		)
		(stroke
			(width 0)
			(type solid)
		)
		(fill yes)
		(layer "In13.Cu")
		(net "GND")
	)
	(gr_poly
		(pts
			(arc
				(start 313.244738 -143.676878)
				(mid 312.951622 -143.676878)
				(end 313.244738 -143.676878)
			)
		)
		(stroke
			(width 0)
			(type solid)
		)
		(fill yes)
		(layer "In13.Cu")
		(net "GND")
	)
	(gr_poly
		(pts
			(arc
				(start 313.244738 -142.418054)
				(mid 312.951622 -142.418054)
				(end 313.244738 -142.418054)
			)
		)
		(stroke
			(width 0)
			(type solid)
		)
		(fill yes)
		(layer "In13.Cu")
		(net "GND")
	)
	(gr_poly
		(pts
			(arc
				(start 313.244738 -134.566914)
				(mid 312.951622 -134.566914)
				(end 313.244738 -134.566914)
			)
		)
		(stroke
			(width 0)
			(type solid)
		)
		(fill yes)
		(layer "In13.Cu")
		(net "GND")
	)
	(gr_poly
		(pts
			(arc
				(start 313.244738 -133.30809)
				(mid 312.951622 -133.30809)
				(end 313.244738 -133.30809)
			)
		)
		(stroke
			(width 0)
			(type solid)
		)
		(fill yes)
		(layer "In13.Cu")
		(net "GND")
	)
	(gr_poly
		(pts
			(arc
				(start 313.244738 -130.966718)
				(mid 312.951622 -130.966718)
				(end 313.244738 -130.966718)
			)
		)
		(stroke
			(width 0)
			(type solid)
		)
		(fill yes)
		(layer "In13.Cu")
		(net "GND")
	)
	(gr_poly
		(pts
			(arc
				(start 313.244738 -129.707894)
				(mid 312.951622 -129.707894)
				(end 313.244738 -129.707894)
			)
		)
		(stroke
			(width 0)
			(type solid)
		)
		(fill yes)
		(layer "In13.Cu")
		(net "GND")
	)
	(gr_poly
		(pts
			(arc
				(start 313.244738 -123.356878)
				(mid 312.951622 -123.356878)
				(end 313.244738 -123.356878)
			)
		)
		(stroke
			(width 0)
			(type solid)
		)
		(fill yes)
		(layer "In13.Cu")
		(net "GND")
	)
	(gr_poly
		(pts
			(arc
				(start 313.244738 -122.098054)
				(mid 312.951622 -122.098054)
				(end 313.244738 -122.098054)
			)
		)
		(stroke
			(width 0)
			(type solid)
		)
		(fill yes)
		(layer "In13.Cu")
		(net "GND")
	)
	(gr_poly
		(pts
			(arc
				(start 313.244738 -119.756936)
				(mid 312.951622 -119.756936)
				(end 313.244738 -119.756936)
			)
		)
		(stroke
			(width 0)
			(type solid)
		)
		(fill yes)
		(layer "In13.Cu")
		(net "GND")
	)
	(gr_poly
		(pts
			(arc
				(start 313.244738 -118.498112)
				(mid 312.951622 -118.498112)
				(end 313.244738 -118.498112)
			)
		)
		(stroke
			(width 0)
			(type solid)
		)
		(fill yes)
		(layer "In13.Cu")
		(net "GND")
	)
	(gr_poly
		(pts
			(arc
				(start 314.512706 -154.476958)
				(mid 314.21959 -154.476958)
				(end 314.512706 -154.476958)
			)
		)
		(stroke
			(width 0)
			(type solid)
		)
		(fill yes)
		(layer "In13.Cu")
		(net "GND")
	)
	(gr_poly
		(pts
			(arc
				(start 314.512706 -153.218134)
				(mid 314.21959 -153.218134)
				(end 314.512706 -153.218134)
			)
		)
		(stroke
			(width 0)
			(type solid)
		)
		(fill yes)
		(layer "In13.Cu")
		(net "GND")
	)
	(gr_poly
		(pts
			(arc
				(start 314.512706 -150.876762)
				(mid 314.21959 -150.876762)
				(end 314.512706 -150.876762)
			)
		)
		(stroke
			(width 0)
			(type solid)
		)
		(fill yes)
		(layer "In13.Cu")
		(net "GND")
	)
	(gr_poly
		(pts
			(arc
				(start 314.512706 -149.617938)
				(mid 314.21959 -149.617938)
				(end 314.512706 -149.617938)
			)
		)
		(stroke
			(width 0)
			(type solid)
		)
		(fill yes)
		(layer "In13.Cu")
		(net "GND")
	)
	(gr_poly
		(pts
			(arc
				(start 314.512706 -147.27682)
				(mid 314.21959 -147.27682)
				(end 314.512706 -147.27682)
			)
		)
		(stroke
			(width 0)
			(type solid)
		)
		(fill yes)
		(layer "In13.Cu")
		(net "GND")
	)
	(gr_poly
		(pts
			(arc
				(start 314.512706 -146.017996)
				(mid 314.21959 -146.017996)
				(end 314.512706 -146.017996)
			)
		)
		(stroke
			(width 0)
			(type solid)
		)
		(fill yes)
		(layer "In13.Cu")
		(net "GND")
	)
	(gr_poly
		(pts
			(arc
				(start 314.512706 -143.676878)
				(mid 314.21959 -143.676878)
				(end 314.512706 -143.676878)
			)
		)
		(stroke
			(width 0)
			(type solid)
		)
		(fill yes)
		(layer "In13.Cu")
		(net "GND")
	)
	(gr_poly
		(pts
			(arc
				(start 314.512706 -142.418054)
				(mid 314.21959 -142.418054)
				(end 314.512706 -142.418054)
			)
		)
		(stroke
			(width 0)
			(type solid)
		)
		(fill yes)
		(layer "In13.Cu")
		(net "GND")
	)
	(gr_poly
		(pts
			(arc
				(start 314.512706 -134.566914)
				(mid 314.21959 -134.566914)
				(end 314.512706 -134.566914)
			)
		)
		(stroke
			(width 0)
			(type solid)
		)
		(fill yes)
		(layer "In13.Cu")
		(net "GND")
	)
	(gr_poly
		(pts
			(arc
				(start 314.512706 -133.30809)
				(mid 314.21959 -133.30809)
				(end 314.512706 -133.30809)
			)
		)
		(stroke
			(width 0)
			(type solid)
		)
		(fill yes)
		(layer "In13.Cu")
		(net "GND")
	)
	(gr_poly
		(pts
			(arc
				(start 314.512706 -130.966718)
				(mid 314.21959 -130.966718)
				(end 314.512706 -130.966718)
			)
		)
		(stroke
			(width 0)
			(type solid)
		)
		(fill yes)
		(layer "In13.Cu")
		(net "GND")
	)
	(gr_poly
		(pts
			(arc
				(start 314.512706 -129.707894)
				(mid 314.21959 -129.707894)
				(end 314.512706 -129.707894)
			)
		)
		(stroke
			(width 0)
			(type solid)
		)
		(fill yes)
		(layer "In13.Cu")
		(net "GND")
	)
	(gr_poly
		(pts
			(arc
				(start 314.512706 -123.356878)
				(mid 314.21959 -123.356878)
				(end 314.512706 -123.356878)
			)
		)
		(stroke
			(width 0)
			(type solid)
		)
		(fill yes)
		(layer "In13.Cu")
		(net "GND")
	)
	(gr_poly
		(pts
			(arc
				(start 314.512706 -122.098054)
				(mid 314.21959 -122.098054)
				(end 314.512706 -122.098054)
			)
		)
		(stroke
			(width 0)
			(type solid)
		)
		(fill yes)
		(layer "In13.Cu")
		(net "GND")
	)
	(gr_poly
		(pts
			(arc
				(start 314.512706 -119.756936)
				(mid 314.21959 -119.756936)
				(end 314.512706 -119.756936)
			)
		)
		(stroke
			(width 0)
			(type solid)
		)
		(fill yes)
		(layer "In13.Cu")
		(net "GND")
	)
	(gr_poly
		(pts
			(arc
				(start 314.512706 -118.498112)
				(mid 314.21959 -118.498112)
				(end 314.512706 -118.498112)
			)
		)
		(stroke
			(width 0)
			(type solid)
		)
		(fill yes)
		(layer "In13.Cu")
		(net "GND")
	)
	(gr_poly
		(pts
			(arc
				(start 315.886846 -156.283406)
				(mid 315.59373 -156.283406)
				(end 315.886846 -156.283406)
			)
		)
		(stroke
			(width 0)
			(type solid)
		)
		(fill yes)
		(layer "In13.Cu")
		(net "GND")
	)
	(gr_poly
		(pts
			(arc
				(start 315.886846 -155.024582)
				(mid 315.59373 -155.024582)
				(end 315.886846 -155.024582)
			)
		)
		(stroke
			(width 0)
			(type solid)
		)
		(fill yes)
		(layer "In13.Cu")
		(net "GND")
	)
	(gr_poly
		(pts
			(arc
				(start 315.886846 -152.683464)
				(mid 315.59373 -152.683464)
				(end 315.886846 -152.683464)
			)
		)
		(stroke
			(width 0)
			(type solid)
		)
		(fill yes)
		(layer "In13.Cu")
		(net "GND")
	)
	(gr_poly
		(pts
			(arc
				(start 315.886846 -151.42464)
				(mid 315.59373 -151.42464)
				(end 315.886846 -151.42464)
			)
		)
		(stroke
			(width 0)
			(type solid)
		)
		(fill yes)
		(layer "In13.Cu")
		(net "GND")
	)
	(gr_poly
		(pts
			(arc
				(start 315.886846 -149.083522)
				(mid 315.59373 -149.083522)
				(end 315.886846 -149.083522)
			)
		)
		(stroke
			(width 0)
			(type solid)
		)
		(fill yes)
		(layer "In13.Cu")
		(net "GND")
	)
	(gr_poly
		(pts
			(arc
				(start 315.886846 -147.824698)
				(mid 315.59373 -147.824698)
				(end 315.886846 -147.824698)
			)
		)
		(stroke
			(width 0)
			(type solid)
		)
		(fill yes)
		(layer "In13.Cu")
		(net "GND")
	)
	(gr_poly
		(pts
			(arc
				(start 315.886846 -145.483326)
				(mid 315.59373 -145.483326)
				(end 315.886846 -145.483326)
			)
		)
		(stroke
			(width 0)
			(type solid)
		)
		(fill yes)
		(layer "In13.Cu")
		(net "GND")
	)
	(gr_poly
		(pts
			(arc
				(start 315.886846 -144.224502)
				(mid 315.59373 -144.224502)
				(end 315.886846 -144.224502)
			)
		)
		(stroke
			(width 0)
			(type solid)
		)
		(fill yes)
		(layer "In13.Cu")
		(net "GND")
	)
	(gr_poly
		(pts
			(arc
				(start 315.886846 -136.373362)
				(mid 315.59373 -136.373362)
				(end 315.886846 -136.373362)
			)
		)
		(stroke
			(width 0)
			(type solid)
		)
		(fill yes)
		(layer "In13.Cu")
		(net "GND")
	)
	(gr_poly
		(pts
			(arc
				(start 315.886846 -135.114538)
				(mid 315.59373 -135.114538)
				(end 315.886846 -135.114538)
			)
		)
		(stroke
			(width 0)
			(type solid)
		)
		(fill yes)
		(layer "In13.Cu")
		(net "GND")
	)
	(gr_poly
		(pts
			(arc
				(start 315.886846 -132.77342)
				(mid 315.59373 -132.77342)
				(end 315.886846 -132.77342)
			)
		)
		(stroke
			(width 0)
			(type solid)
		)
		(fill yes)
		(layer "In13.Cu")
		(net "GND")
	)
	(gr_poly
		(pts
			(arc
				(start 315.886846 -131.514596)
				(mid 315.59373 -131.514596)
				(end 315.886846 -131.514596)
			)
		)
		(stroke
			(width 0)
			(type solid)
		)
		(fill yes)
		(layer "In13.Cu")
		(net "GND")
	)
	(gr_poly
		(pts
			(arc
				(start 315.886846 -125.163326)
				(mid 315.59373 -125.163326)
				(end 315.886846 -125.163326)
			)
		)
		(stroke
			(width 0)
			(type solid)
		)
		(fill yes)
		(layer "In13.Cu")
		(net "GND")
	)
	(gr_poly
		(pts
			(arc
				(start 315.886846 -123.904502)
				(mid 315.59373 -123.904502)
				(end 315.886846 -123.904502)
			)
		)
		(stroke
			(width 0)
			(type solid)
		)
		(fill yes)
		(layer "In13.Cu")
		(net "GND")
	)
	(gr_poly
		(pts
			(arc
				(start 315.886846 -121.563384)
				(mid 315.59373 -121.563384)
				(end 315.886846 -121.563384)
			)
		)
		(stroke
			(width 0)
			(type solid)
		)
		(fill yes)
		(layer "In13.Cu")
		(net "GND")
	)
	(gr_poly
		(pts
			(arc
				(start 315.886846 -120.30456)
				(mid 315.59373 -120.30456)
				(end 315.886846 -120.30456)
			)
		)
		(stroke
			(width 0)
			(type solid)
		)
		(fill yes)
		(layer "In13.Cu")
		(net "GND")
	)
	(gr_poly
		(pts
			(arc
				(start 316.947296 -34.98977)
				(mid 316.65418 -34.98977)
				(end 316.947296 -34.98977)
			)
		)
		(stroke
			(width 0)
			(type solid)
		)
		(fill yes)
		(layer "In13.Cu")
		(net "GND")
	)
	(gr_poly
		(pts
			(arc
				(start 316.947296 -33.189926)
				(mid 316.65418 -33.189926)
				(end 316.947296 -33.189926)
			)
		)
		(stroke
			(width 0)
			(type solid)
		)
		(fill yes)
		(layer "In13.Cu")
		(net "GND")
	)
	(gr_poly
		(pts
			(arc
				(start 316.947296 -31.389828)
				(mid 316.65418 -31.389828)
				(end 316.947296 -31.389828)
			)
		)
		(stroke
			(width 0)
			(type solid)
		)
		(fill yes)
		(layer "In13.Cu")
		(net "GND")
	)
	(gr_poly
		(pts
			(arc
				(start 316.947296 -29.589984)
				(mid 316.65418 -29.589984)
				(end 316.947296 -29.589984)
			)
		)
		(stroke
			(width 0)
			(type solid)
		)
		(fill yes)
		(layer "In13.Cu")
		(net "GND")
	)
	(gr_poly
		(pts
			(arc
				(start 317.154814 -156.283406)
				(mid 316.861698 -156.283406)
				(end 317.154814 -156.283406)
			)
		)
		(stroke
			(width 0)
			(type solid)
		)
		(fill yes)
		(layer "In13.Cu")
		(net "GND")
	)
	(gr_poly
		(pts
			(arc
				(start 317.154814 -155.024582)
				(mid 316.861698 -155.024582)
				(end 317.154814 -155.024582)
			)
		)
		(stroke
			(width 0)
			(type solid)
		)
		(fill yes)
		(layer "In13.Cu")
		(net "GND")
	)
	(gr_poly
		(pts
			(arc
				(start 317.154814 -152.683464)
				(mid 316.861698 -152.683464)
				(end 317.154814 -152.683464)
			)
		)
		(stroke
			(width 0)
			(type solid)
		)
		(fill yes)
		(layer "In13.Cu")
		(net "GND")
	)
	(gr_poly
		(pts
			(arc
				(start 317.154814 -151.42464)
				(mid 316.861698 -151.42464)
				(end 317.154814 -151.42464)
			)
		)
		(stroke
			(width 0)
			(type solid)
		)
		(fill yes)
		(layer "In13.Cu")
		(net "GND")
	)
	(gr_poly
		(pts
			(arc
				(start 317.154814 -149.083522)
				(mid 316.861698 -149.083522)
				(end 317.154814 -149.083522)
			)
		)
		(stroke
			(width 0)
			(type solid)
		)
		(fill yes)
		(layer "In13.Cu")
		(net "GND")
	)
	(gr_poly
		(pts
			(arc
				(start 317.154814 -147.824698)
				(mid 316.861698 -147.824698)
				(end 317.154814 -147.824698)
			)
		)
		(stroke
			(width 0)
			(type solid)
		)
		(fill yes)
		(layer "In13.Cu")
		(net "GND")
	)
	(gr_poly
		(pts
			(arc
				(start 317.154814 -145.483326)
				(mid 316.861698 -145.483326)
				(end 317.154814 -145.483326)
			)
		)
		(stroke
			(width 0)
			(type solid)
		)
		(fill yes)
		(layer "In13.Cu")
		(net "GND")
	)
	(gr_poly
		(pts
			(arc
				(start 317.154814 -144.224502)
				(mid 316.861698 -144.224502)
				(end 317.154814 -144.224502)
			)
		)
		(stroke
			(width 0)
			(type solid)
		)
		(fill yes)
		(layer "In13.Cu")
		(net "GND")
	)
	(gr_poly
		(pts
			(arc
				(start 317.154814 -136.373362)
				(mid 316.861698 -136.373362)
				(end 317.154814 -136.373362)
			)
		)
		(stroke
			(width 0)
			(type solid)
		)
		(fill yes)
		(layer "In13.Cu")
		(net "GND")
	)
	(gr_poly
		(pts
			(arc
				(start 317.154814 -135.114538)
				(mid 316.861698 -135.114538)
				(end 317.154814 -135.114538)
			)
		)
		(stroke
			(width 0)
			(type solid)
		)
		(fill yes)
		(layer "In13.Cu")
		(net "GND")
	)
	(gr_poly
		(pts
			(arc
				(start 317.154814 -132.77342)
				(mid 316.861698 -132.77342)
				(end 317.154814 -132.77342)
			)
		)
		(stroke
			(width 0)
			(type solid)
		)
		(fill yes)
		(layer "In13.Cu")
		(net "GND")
	)
	(gr_poly
		(pts
			(arc
				(start 317.154814 -131.514596)
				(mid 316.861698 -131.514596)
				(end 317.154814 -131.514596)
			)
		)
		(stroke
			(width 0)
			(type solid)
		)
		(fill yes)
		(layer "In13.Cu")
		(net "GND")
	)
	(gr_poly
		(pts
			(arc
				(start 317.154814 -125.163326)
				(mid 316.861698 -125.163326)
				(end 317.154814 -125.163326)
			)
		)
		(stroke
			(width 0)
			(type solid)
		)
		(fill yes)
		(layer "In13.Cu")
		(net "GND")
	)
	(gr_poly
		(pts
			(arc
				(start 317.154814 -123.904502)
				(mid 316.861698 -123.904502)
				(end 317.154814 -123.904502)
			)
		)
		(stroke
			(width 0)
			(type solid)
		)
		(fill yes)
		(layer "In13.Cu")
		(net "GND")
	)
	(gr_poly
		(pts
			(arc
				(start 317.154814 -121.563384)
				(mid 316.861698 -121.563384)
				(end 317.154814 -121.563384)
			)
		)
		(stroke
			(width 0)
			(type solid)
		)
		(fill yes)
		(layer "In13.Cu")
		(net "GND")
	)
	(gr_poly
		(pts
			(arc
				(start 317.154814 -120.30456)
				(mid 316.861698 -120.30456)
				(end 317.154814 -120.30456)
			)
		)
		(stroke
			(width 0)
			(type solid)
		)
		(fill yes)
		(layer "In13.Cu")
		(net "GND")
	)
	(gr_poly
		(pts
			(arc
				(start 318.166496 -34.98977)
				(mid 317.87338 -34.98977)
				(end 318.166496 -34.98977)
			)
		)
		(stroke
			(width 0)
			(type solid)
		)
		(fill yes)
		(layer "In13.Cu")
		(net "GND")
	)
	(gr_poly
		(pts
			(arc
				(start 318.166496 -33.189926)
				(mid 317.87338 -33.189926)
				(end 318.166496 -33.189926)
			)
		)
		(stroke
			(width 0)
			(type solid)
		)
		(fill yes)
		(layer "In13.Cu")
		(net "GND")
	)
	(gr_poly
		(pts
			(arc
				(start 318.166496 -31.389828)
				(mid 317.87338 -31.389828)
				(end 318.166496 -31.389828)
			)
		)
		(stroke
			(width 0)
			(type solid)
		)
		(fill yes)
		(layer "In13.Cu")
		(net "GND")
	)
	(gr_poly
		(pts
			(arc
				(start 318.166496 -29.589984)
				(mid 317.87338 -29.589984)
				(end 318.166496 -29.589984)
			)
		)
		(stroke
			(width 0)
			(type solid)
		)
		(fill yes)
		(layer "In13.Cu")
		(net "GND")
	)
	(gr_poly
		(pts
			(arc
				(start 318.801496 -33.189926)
				(mid 318.50838 -33.189926)
				(end 318.801496 -33.189926)
			)
		)
		(stroke
			(width 0)
			(type solid)
		)
		(fill yes)
		(layer "In13.Cu")
		(net "GND")
	)
	(gr_poly
		(pts
			(arc
				(start 318.801496 -31.389828)
				(mid 318.50838 -31.389828)
				(end 318.801496 -31.389828)
			)
		)
		(stroke
			(width 0)
			(type solid)
		)
		(fill yes)
		(layer "In13.Cu")
		(net "GND")
	)
	(gr_poly
		(pts
			(arc
				(start 318.801496 -29.589984)
				(mid 318.50838 -29.589984)
				(end 318.801496 -29.589984)
			)
		)
		(stroke
			(width 0)
			(type solid)
		)
		(fill yes)
		(layer "In13.Cu")
		(net "GND")
	)
	(gr_poly
		(pts
			(arc
				(start 318.801496 -27.789886)
				(mid 318.50838 -27.789886)
				(end 318.801496 -27.789886)
			)
		)
		(stroke
			(width 0)
			(type solid)
		)
		(fill yes)
		(layer "In13.Cu")
		(net "GND")
	)
	(gr_poly
		(pts
			(arc
				(start 320.059558 -83.82)
				(mid 319.766442 -83.82)
				(end 320.059558 -83.82)
			)
		)
		(stroke
			(width 0)
			(type solid)
		)
		(fill yes)
		(layer "In13.Cu")
		(net "GND")
	)
	(gr_poly
		(pts
			(arc
				(start 321.324732 -76.256642)
				(mid 321.031616 -76.256642)
				(end 321.324732 -76.256642)
			)
		)
		(stroke
			(width 0)
			(type solid)
		)
		(fill yes)
		(layer "In13.Cu")
		(net "GND")
	)
	(gr_poly
		(pts
			(arc
				(start 323.848476 -218.938856)
				(mid 323.55536 -218.938856)
				(end 323.848476 -218.938856)
			)
		)
		(stroke
			(width 0)
			(type solid)
		)
		(fill yes)
		(layer "In13.Cu")
		(net "GND")
	)
	(gr_poly
		(pts
			(arc
				(start 328.500232 -84.28228)
				(mid 328.207116 -84.28228)
				(end 328.500232 -84.28228)
			)
		)
		(stroke
			(width 0)
			(type solid)
		)
		(fill yes)
		(layer "In13.Cu")
		(net "GND")
	)
	(gr_poly
		(pts
			(arc
				(start 331.531214 -259.959348)
				(mid 331.238098 -259.959348)
				(end 331.531214 -259.959348)
			)
		)
		(stroke
			(width 0)
			(type solid)
		)
		(fill yes)
		(layer "In13.Cu")
		(net "GND")
	)
	(gr_poly
		(pts
			(arc
				(start 332.870556 -263.407652)
				(mid 332.57744 -263.407652)
				(end 332.870556 -263.407652)
			)
		)
		(stroke
			(width 0)
			(type solid)
		)
		(fill yes)
		(layer "In13.Cu")
		(net "GND")
	)
	(gr_poly
		(pts
			(arc
				(start 334.63738 -235.103162)
				(mid 334.344264 -235.103162)
				(end 334.63738 -235.103162)
			)
		)
		(stroke
			(width 0)
			(type solid)
		)
		(fill yes)
		(layer "In13.Cu")
		(net "GND")
	)
	(gr_poly
		(pts
			(arc
				(start 342.319102 -198.13016)
				(mid 342.025986 -198.13016)
				(end 342.319102 -198.13016)
			)
		)
		(stroke
			(width 0)
			(type solid)
		)
		(fill yes)
		(layer "In13.Cu")
		(net "GND")
	)
	(gr_poly
		(pts
			(arc
				(start 351.475294 -149.263608)
				(mid 351.182178 -149.263608)
				(end 351.475294 -149.263608)
			)
		)
		(stroke
			(width 0)
			(type solid)
		)
		(fill yes)
		(layer "In13.Cu")
		(net "GND")
	)
	(gr_poly
		(pts
			(arc
				(start 355.04755 -34.98977)
				(mid 354.754434 -34.98977)
				(end 355.04755 -34.98977)
			)
		)
		(stroke
			(width 0)
			(type solid)
		)
		(fill yes)
		(layer "In13.Cu")
		(net "GND")
	)
	(gr_poly
		(pts
			(arc
				(start 355.04755 -33.189926)
				(mid 354.754434 -33.189926)
				(end 355.04755 -33.189926)
			)
		)
		(stroke
			(width 0)
			(type solid)
		)
		(fill yes)
		(layer "In13.Cu")
		(net "GND")
	)
	(gr_poly
		(pts
			(arc
				(start 355.04755 -31.389828)
				(mid 354.754434 -31.389828)
				(end 355.04755 -31.389828)
			)
		)
		(stroke
			(width 0)
			(type solid)
		)
		(fill yes)
		(layer "In13.Cu")
		(net "GND")
	)
	(gr_poly
		(pts
			(arc
				(start 355.04755 -29.589984)
				(mid 354.754434 -29.589984)
				(end 355.04755 -29.589984)
			)
		)
		(stroke
			(width 0)
			(type solid)
		)
		(fill yes)
		(layer "In13.Cu")
		(net "GND")
	)
	(gr_poly
		(pts
			(arc
				(start 355.301296 -235.270294)
				(mid 355.00818 -235.270294)
				(end 355.301296 -235.270294)
			)
		)
		(stroke
			(width 0)
			(type solid)
		)
		(fill yes)
		(layer "In13.Cu")
		(net "GND")
	)
	(gr_poly
		(pts
			(arc
				(start 356.26675 -34.98977)
				(mid 355.973634 -34.98977)
				(end 356.26675 -34.98977)
			)
		)
		(stroke
			(width 0)
			(type solid)
		)
		(fill yes)
		(layer "In13.Cu")
		(net "GND")
	)
	(gr_poly
		(pts
			(arc
				(start 356.26675 -33.189926)
				(mid 355.973634 -33.189926)
				(end 356.26675 -33.189926)
			)
		)
		(stroke
			(width 0)
			(type solid)
		)
		(fill yes)
		(layer "In13.Cu")
		(net "GND")
	)
	(gr_poly
		(pts
			(arc
				(start 356.26675 -31.389828)
				(mid 355.973634 -31.389828)
				(end 356.26675 -31.389828)
			)
		)
		(stroke
			(width 0)
			(type solid)
		)
		(fill yes)
		(layer "In13.Cu")
		(net "GND")
	)
	(gr_poly
		(pts
			(arc
				(start 356.26675 -29.589984)
				(mid 355.973634 -29.589984)
				(end 356.26675 -29.589984)
			)
		)
		(stroke
			(width 0)
			(type solid)
		)
		(fill yes)
		(layer "In13.Cu")
		(net "GND")
	)
	(gr_poly
		(pts
			(arc
				(start 356.843076 -251.316744)
				(mid 356.54996 -251.316744)
				(end 356.843076 -251.316744)
			)
		)
		(stroke
			(width 0)
			(type solid)
		)
		(fill yes)
		(layer "In13.Cu")
		(net "GND")
	)
	(gr_poly
		(pts
			(arc
				(start 356.90175 -33.189926)
				(mid 356.608634 -33.189926)
				(end 356.90175 -33.189926)
			)
		)
		(stroke
			(width 0)
			(type solid)
		)
		(fill yes)
		(layer "In13.Cu")
		(net "GND")
	)
	(gr_poly
		(pts
			(arc
				(start 356.90175 -31.389828)
				(mid 356.608634 -31.389828)
				(end 356.90175 -31.389828)
			)
		)
		(stroke
			(width 0)
			(type solid)
		)
		(fill yes)
		(layer "In13.Cu")
		(net "GND")
	)
	(gr_poly
		(pts
			(arc
				(start 356.90175 -29.589984)
				(mid 356.608634 -29.589984)
				(end 356.90175 -29.589984)
			)
		)
		(stroke
			(width 0)
			(type solid)
		)
		(fill yes)
		(layer "In13.Cu")
		(net "GND")
	)
	(gr_poly
		(pts
			(arc
				(start 356.90175 -27.789886)
				(mid 356.608634 -27.789886)
				(end 356.90175 -27.789886)
			)
		)
		(stroke
			(width 0)
			(type solid)
		)
		(fill yes)
		(layer "In13.Cu")
		(net "GND")
	)
	(gr_poly
		(pts
			(arc
				(start 358.55021 -250.286266)
				(mid 358.257094 -250.286266)
				(end 358.55021 -250.286266)
			)
		)
		(stroke
			(width 0)
			(type solid)
		)
		(fill yes)
		(layer "In13.Cu")
		(net "GND")
	)
	(gr_poly
		(pts
			(arc
				(start 365.54791 -96.669606)
				(mid 365.254794 -96.669606)
				(end 365.54791 -96.669606)
			)
		)
		(stroke
			(width 0)
			(type solid)
		)
		(fill yes)
		(layer "In13.Cu")
		(net "GND")
	)
	(gr_poly
		(pts
			(arc
				(start 365.766604 -248.668286)
				(mid 365.473488 -248.668286)
				(end 365.766604 -248.668286)
			)
		)
		(stroke
			(width 0)
			(type solid)
		)
		(fill yes)
		(layer "In13.Cu")
		(net "GND")
	)
	(gr_poly
		(pts
			(arc
				(start 366.05083 -93.869764)
				(mid 365.757714 -93.869764)
				(end 366.05083 -93.869764)
			)
		)
		(stroke
			(width 0)
			(type solid)
		)
		(fill yes)
		(layer "In13.Cu")
		(net "GND")
	)
	(gr_poly
		(pts
			(arc
				(start 368.349784 -92.27566)
				(mid 368.056668 -92.27566)
				(end 368.349784 -92.27566)
			)
		)
		(stroke
			(width 0)
			(type solid)
		)
		(fill yes)
		(layer "In13.Cu")
		(net "GND")
	)
	(gr_poly
		(pts
			(arc
				(start 369.965224 -99.506024)
				(mid 369.672108 -99.506024)
				(end 369.965224 -99.506024)
			)
		)
		(stroke
			(width 0)
			(type solid)
		)
		(fill yes)
		(layer "In13.Cu")
		(net "GND")
	)
	(gr_poly
		(pts
			(arc
				(start 370.532406 -102.456996)
				(mid 370.23929 -102.456996)
				(end 370.532406 -102.456996)
			)
		)
		(stroke
			(width 0)
			(type solid)
		)
		(fill yes)
		(layer "In13.Cu")
		(net "GND")
	)
	(gr_poly
		(pts
			(arc
				(start 373.34698 -108.91901)
				(mid 373.053864 -108.91901)
				(end 373.34698 -108.91901)
			)
		)
		(stroke
			(width 0)
			(type solid)
		)
		(fill yes)
		(layer "In13.Cu")
		(net "GND")
	)
	(gr_poly
		(pts
			(arc
				(start 374.13692 -106.003852)
				(mid 373.843804 -106.003852)
				(end 374.13692 -106.003852)
			)
		)
		(stroke
			(width 0)
			(type solid)
		)
		(fill yes)
		(layer "In13.Cu")
		(net "GND")
	)
	(gr_poly
		(pts
			(arc
				(start 374.381014 -104.323896)
				(mid 374.087898 -104.323896)
				(end 374.381014 -104.323896)
			)
		)
		(stroke
			(width 0)
			(type solid)
		)
		(fill yes)
		(layer "In13.Cu")
		(net "GND")
	)
	(gr_poly
		(pts
			(arc
				(start 381.047498 -34.98977)
				(mid 380.754382 -34.98977)
				(end 381.047498 -34.98977)
			)
		)
		(stroke
			(width 0)
			(type solid)
		)
		(fill yes)
		(layer "In13.Cu")
		(net "GND")
	)
	(gr_poly
		(pts
			(arc
				(start 381.047498 -33.189926)
				(mid 380.754382 -33.189926)
				(end 381.047498 -33.189926)
			)
		)
		(stroke
			(width 0)
			(type solid)
		)
		(fill yes)
		(layer "In13.Cu")
		(net "GND")
	)
	(gr_poly
		(pts
			(arc
				(start 381.047498 -31.389828)
				(mid 380.754382 -31.389828)
				(end 381.047498 -31.389828)
			)
		)
		(stroke
			(width 0)
			(type solid)
		)
		(fill yes)
		(layer "In13.Cu")
		(net "GND")
	)
	(gr_poly
		(pts
			(arc
				(start 381.047498 -29.589984)
				(mid 380.754382 -29.589984)
				(end 381.047498 -29.589984)
			)
		)
		(stroke
			(width 0)
			(type solid)
		)
		(fill yes)
		(layer "In13.Cu")
		(net "GND")
	)
	(gr_poly
		(pts
			(arc
				(start 381.268478 -75.114658)
				(mid 380.975362 -75.114658)
				(end 381.268478 -75.114658)
			)
		)
		(stroke
			(width 0)
			(type solid)
		)
		(fill yes)
		(layer "In13.Cu")
		(net "GND")
	)
	(gr_poly
		(pts
			(arc
				(start 382.266698 -34.98977)
				(mid 381.973582 -34.98977)
				(end 382.266698 -34.98977)
			)
		)
		(stroke
			(width 0)
			(type solid)
		)
		(fill yes)
		(layer "In13.Cu")
		(net "GND")
	)
	(gr_poly
		(pts
			(arc
				(start 382.266698 -33.189926)
				(mid 381.973582 -33.189926)
				(end 382.266698 -33.189926)
			)
		)
		(stroke
			(width 0)
			(type solid)
		)
		(fill yes)
		(layer "In13.Cu")
		(net "GND")
	)
	(gr_poly
		(pts
			(arc
				(start 382.266698 -31.389828)
				(mid 381.973582 -31.389828)
				(end 382.266698 -31.389828)
			)
		)
		(stroke
			(width 0)
			(type solid)
		)
		(fill yes)
		(layer "In13.Cu")
		(net "GND")
	)
	(gr_poly
		(pts
			(arc
				(start 382.266698 -29.589984)
				(mid 381.973582 -29.589984)
				(end 382.266698 -29.589984)
			)
		)
		(stroke
			(width 0)
			(type solid)
		)
		(fill yes)
		(layer "In13.Cu")
		(net "GND")
	)
	(gr_poly
		(pts
			(arc
				(start 382.901698 -33.189926)
				(mid 382.608582 -33.189926)
				(end 382.901698 -33.189926)
			)
		)
		(stroke
			(width 0)
			(type solid)
		)
		(fill yes)
		(layer "In13.Cu")
		(net "GND")
	)
	(gr_poly
		(pts
			(arc
				(start 382.901698 -31.389828)
				(mid 382.608582 -31.389828)
				(end 382.901698 -31.389828)
			)
		)
		(stroke
			(width 0)
			(type solid)
		)
		(fill yes)
		(layer "In13.Cu")
		(net "GND")
	)
	(gr_poly
		(pts
			(arc
				(start 382.901698 -29.589984)
				(mid 382.608582 -29.589984)
				(end 382.901698 -29.589984)
			)
		)
		(stroke
			(width 0)
			(type solid)
		)
		(fill yes)
		(layer "In13.Cu")
		(net "GND")
	)
	(gr_poly
		(pts
			(arc
				(start 382.901698 -27.789886)
				(mid 382.608582 -27.789886)
				(end 382.901698 -27.789886)
			)
		)
		(stroke
			(width 0)
			(type solid)
		)
		(fill yes)
		(layer "In13.Cu")
		(net "GND")
	)
	(gr_poly
		(pts
			(arc
				(start 382.938274 -135.095488)
				(mid 382.645158 -135.095488)
				(end 382.938274 -135.095488)
			)
		)
		(stroke
			(width 0)
			(type solid)
		)
		(fill yes)
		(layer "In13.Cu")
		(net "GND")
	)
	(gr_poly
		(pts
			(arc
				(start 382.938274 -133.836664)
				(mid 382.645158 -133.836664)
				(end 382.938274 -133.836664)
			)
		)
		(stroke
			(width 0)
			(type solid)
		)
		(fill yes)
		(layer "In13.Cu")
		(net "GND")
	)
	(gr_poly
		(pts
			(arc
				(start 382.938274 -131.495546)
				(mid 382.645158 -131.495546)
				(end 382.938274 -131.495546)
			)
		)
		(stroke
			(width 0)
			(type solid)
		)
		(fill yes)
		(layer "In13.Cu")
		(net "GND")
	)
	(gr_poly
		(pts
			(arc
				(start 382.938274 -130.236722)
				(mid 382.645158 -130.236722)
				(end 382.938274 -130.236722)
			)
		)
		(stroke
			(width 0)
			(type solid)
		)
		(fill yes)
		(layer "In13.Cu")
		(net "GND")
	)
	(gr_poly
		(pts
			(arc
				(start 382.938274 -123.885452)
				(mid 382.645158 -123.885452)
				(end 382.938274 -123.885452)
			)
		)
		(stroke
			(width 0)
			(type solid)
		)
		(fill yes)
		(layer "In13.Cu")
		(net "GND")
	)
	(gr_poly
		(pts
			(arc
				(start 382.938274 -122.626628)
				(mid 382.645158 -122.626628)
				(end 382.938274 -122.626628)
			)
		)
		(stroke
			(width 0)
			(type solid)
		)
		(fill yes)
		(layer "In13.Cu")
		(net "GND")
	)
	(gr_poly
		(pts
			(arc
				(start 382.938274 -120.28551)
				(mid 382.645158 -120.28551)
				(end 382.938274 -120.28551)
			)
		)
		(stroke
			(width 0)
			(type solid)
		)
		(fill yes)
		(layer "In13.Cu")
		(net "GND")
	)
	(gr_poly
		(pts
			(arc
				(start 382.938274 -119.026686)
				(mid 382.645158 -119.026686)
				(end 382.938274 -119.026686)
			)
		)
		(stroke
			(width 0)
			(type solid)
		)
		(fill yes)
		(layer "In13.Cu")
		(net "GND")
	)
	(gr_poly
		(pts
			(arc
				(start 382.938274 -112.981994)
				(mid 382.645158 -112.981994)
				(end 382.938274 -112.981994)
			)
		)
		(stroke
			(width 0)
			(type solid)
		)
		(fill yes)
		(layer "In13.Cu")
		(net "GND")
	)
	(gr_poly
		(pts
			(arc
				(start 382.938274 -111.72317)
				(mid 382.645158 -111.72317)
				(end 382.938274 -111.72317)
			)
		)
		(stroke
			(width 0)
			(type solid)
		)
		(fill yes)
		(layer "In13.Cu")
		(net "GND")
	)
	(gr_poly
		(pts
			(arc
				(start 382.938274 -109.382052)
				(mid 382.645158 -109.382052)
				(end 382.938274 -109.382052)
			)
		)
		(stroke
			(width 0)
			(type solid)
		)
		(fill yes)
		(layer "In13.Cu")
		(net "GND")
	)
	(gr_poly
		(pts
			(arc
				(start 382.938274 -108.123228)
				(mid 382.645158 -108.123228)
				(end 382.938274 -108.123228)
			)
		)
		(stroke
			(width 0)
			(type solid)
		)
		(fill yes)
		(layer "In13.Cu")
		(net "GND")
	)
	(gr_poly
		(pts
			(arc
				(start 382.938274 -105.78211)
				(mid 382.645158 -105.78211)
				(end 382.938274 -105.78211)
			)
		)
		(stroke
			(width 0)
			(type solid)
		)
		(fill yes)
		(layer "In13.Cu")
		(net "GND")
	)
	(gr_poly
		(pts
			(arc
				(start 382.938274 -104.523286)
				(mid 382.645158 -104.523286)
				(end 382.938274 -104.523286)
			)
		)
		(stroke
			(width 0)
			(type solid)
		)
		(fill yes)
		(layer "In13.Cu")
		(net "GND")
	)
	(gr_poly
		(pts
			(arc
				(start 383.547874 -102.181914)
				(mid 383.254758 -102.181914)
				(end 383.547874 -102.181914)
			)
		)
		(stroke
			(width 0)
			(type solid)
		)
		(fill yes)
		(layer "In13.Cu")
		(net "GND")
	)
	(gr_poly
		(pts
			(arc
				(start 383.547874 -100.92309)
				(mid 383.254758 -100.92309)
				(end 383.547874 -100.92309)
			)
		)
		(stroke
			(width 0)
			(type solid)
		)
		(fill yes)
		(layer "In13.Cu")
		(net "GND")
	)
	(gr_poly
		(pts
			(arc
				(start 384.206242 -135.095488)
				(mid 383.913126 -135.095488)
				(end 384.206242 -135.095488)
			)
		)
		(stroke
			(width 0)
			(type solid)
		)
		(fill yes)
		(layer "In13.Cu")
		(net "GND")
	)
	(gr_poly
		(pts
			(arc
				(start 384.206242 -133.836664)
				(mid 383.913126 -133.836664)
				(end 384.206242 -133.836664)
			)
		)
		(stroke
			(width 0)
			(type solid)
		)
		(fill yes)
		(layer "In13.Cu")
		(net "GND")
	)
	(gr_poly
		(pts
			(arc
				(start 384.206242 -131.495546)
				(mid 383.913126 -131.495546)
				(end 384.206242 -131.495546)
			)
		)
		(stroke
			(width 0)
			(type solid)
		)
		(fill yes)
		(layer "In13.Cu")
		(net "GND")
	)
	(gr_poly
		(pts
			(arc
				(start 384.206242 -130.236722)
				(mid 383.913126 -130.236722)
				(end 384.206242 -130.236722)
			)
		)
		(stroke
			(width 0)
			(type solid)
		)
		(fill yes)
		(layer "In13.Cu")
		(net "GND")
	)
	(gr_poly
		(pts
			(arc
				(start 384.206242 -123.885452)
				(mid 383.913126 -123.885452)
				(end 384.206242 -123.885452)
			)
		)
		(stroke
			(width 0)
			(type solid)
		)
		(fill yes)
		(layer "In13.Cu")
		(net "GND")
	)
	(gr_poly
		(pts
			(arc
				(start 384.206242 -122.626628)
				(mid 383.913126 -122.626628)
				(end 384.206242 -122.626628)
			)
		)
		(stroke
			(width 0)
			(type solid)
		)
		(fill yes)
		(layer "In13.Cu")
		(net "GND")
	)
	(gr_poly
		(pts
			(arc
				(start 384.206242 -120.28551)
				(mid 383.913126 -120.28551)
				(end 384.206242 -120.28551)
			)
		)
		(stroke
			(width 0)
			(type solid)
		)
		(fill yes)
		(layer "In13.Cu")
		(net "GND")
	)
	(gr_poly
		(pts
			(arc
				(start 384.206242 -119.026686)
				(mid 383.913126 -119.026686)
				(end 384.206242 -119.026686)
			)
		)
		(stroke
			(width 0)
			(type solid)
		)
		(fill yes)
		(layer "In13.Cu")
		(net "GND")
	)
	(gr_poly
		(pts
			(arc
				(start 384.206242 -112.981994)
				(mid 383.913126 -112.981994)
				(end 384.206242 -112.981994)
			)
		)
		(stroke
			(width 0)
			(type solid)
		)
		(fill yes)
		(layer "In13.Cu")
		(net "GND")
	)
	(gr_poly
		(pts
			(arc
				(start 384.206242 -111.72317)
				(mid 383.913126 -111.72317)
				(end 384.206242 -111.72317)
			)
		)
		(stroke
			(width 0)
			(type solid)
		)
		(fill yes)
		(layer "In13.Cu")
		(net "GND")
	)
	(gr_poly
		(pts
			(arc
				(start 384.206242 -109.382052)
				(mid 383.913126 -109.382052)
				(end 384.206242 -109.382052)
			)
		)
		(stroke
			(width 0)
			(type solid)
		)
		(fill yes)
		(layer "In13.Cu")
		(net "GND")
	)
	(gr_poly
		(pts
			(arc
				(start 384.206242 -108.123228)
				(mid 383.913126 -108.123228)
				(end 384.206242 -108.123228)
			)
		)
		(stroke
			(width 0)
			(type solid)
		)
		(fill yes)
		(layer "In13.Cu")
		(net "GND")
	)
	(gr_poly
		(pts
			(arc
				(start 384.206242 -105.78211)
				(mid 383.913126 -105.78211)
				(end 384.206242 -105.78211)
			)
		)
		(stroke
			(width 0)
			(type solid)
		)
		(fill yes)
		(layer "In13.Cu")
		(net "GND")
	)
	(gr_poly
		(pts
			(arc
				(start 384.206242 -104.523286)
				(mid 383.913126 -104.523286)
				(end 384.206242 -104.523286)
			)
		)
		(stroke
			(width 0)
			(type solid)
		)
		(fill yes)
		(layer "In13.Cu")
		(net "GND")
	)
	(gr_poly
		(pts
			(arc
				(start 384.815842 -102.181914)
				(mid 384.522726 -102.181914)
				(end 384.815842 -102.181914)
			)
		)
		(stroke
			(width 0)
			(type solid)
		)
		(fill yes)
		(layer "In13.Cu")
		(net "GND")
	)
	(gr_poly
		(pts
			(arc
				(start 384.815842 -100.92309)
				(mid 384.522726 -100.92309)
				(end 384.815842 -100.92309)
			)
		)
		(stroke
			(width 0)
			(type solid)
		)
		(fill yes)
		(layer "In13.Cu")
		(net "GND")
	)
	(gr_poly
		(pts
			(arc
				(start 385.154424 -89.304876)
				(mid 384.861308 -89.304876)
				(end 385.154424 -89.304876)
			)
		)
		(stroke
			(width 0)
			(type solid)
		)
		(fill yes)
		(layer "In13.Cu")
		(net "GND")
	)
	(gr_poly
		(pts
			(arc
				(start 385.580382 -136.901936)
				(mid 385.287266 -136.901936)
				(end 385.580382 -136.901936)
			)
		)
		(stroke
			(width 0)
			(type solid)
		)
		(fill yes)
		(layer "In13.Cu")
		(net "GND")
	)
	(gr_poly
		(pts
			(arc
				(start 385.580382 -135.643112)
				(mid 385.287266 -135.643112)
				(end 385.580382 -135.643112)
			)
		)
		(stroke
			(width 0)
			(type solid)
		)
		(fill yes)
		(layer "In13.Cu")
		(net "GND")
	)
	(gr_poly
		(pts
			(arc
				(start 385.580382 -133.301994)
				(mid 385.287266 -133.301994)
				(end 385.580382 -133.301994)
			)
		)
		(stroke
			(width 0)
			(type solid)
		)
		(fill yes)
		(layer "In13.Cu")
		(net "GND")
	)
	(gr_poly
		(pts
			(arc
				(start 385.580382 -132.04317)
				(mid 385.287266 -132.04317)
				(end 385.580382 -132.04317)
			)
		)
		(stroke
			(width 0)
			(type solid)
		)
		(fill yes)
		(layer "In13.Cu")
		(net "GND")
	)
	(gr_poly
		(pts
			(arc
				(start 385.580382 -125.692154)
				(mid 385.287266 -125.692154)
				(end 385.580382 -125.692154)
			)
		)
		(stroke
			(width 0)
			(type solid)
		)
		(fill yes)
		(layer "In13.Cu")
		(net "GND")
	)
	(gr_poly
		(pts
			(arc
				(start 385.580382 -124.43333)
				(mid 385.287266 -124.43333)
				(end 385.580382 -124.43333)
			)
		)
		(stroke
			(width 0)
			(type solid)
		)
		(fill yes)
		(layer "In13.Cu")
		(net "GND")
	)
	(gr_poly
		(pts
			(arc
				(start 385.580382 -122.091958)
				(mid 385.287266 -122.091958)
				(end 385.580382 -122.091958)
			)
		)
		(stroke
			(width 0)
			(type solid)
		)
		(fill yes)
		(layer "In13.Cu")
		(net "GND")
	)
	(gr_poly
		(pts
			(arc
				(start 385.580382 -120.833134)
				(mid 385.287266 -120.833134)
				(end 385.580382 -120.833134)
			)
		)
		(stroke
			(width 0)
			(type solid)
		)
		(fill yes)
		(layer "In13.Cu")
		(net "GND")
	)
	(gr_poly
		(pts
			(arc
				(start 385.580382 -111.175546)
				(mid 385.287266 -111.175546)
				(end 385.580382 -111.175546)
			)
		)
		(stroke
			(width 0)
			(type solid)
		)
		(fill yes)
		(layer "In13.Cu")
		(net "GND")
	)
	(gr_poly
		(pts
			(arc
				(start 385.580382 -109.916722)
				(mid 385.287266 -109.916722)
				(end 385.580382 -109.916722)
			)
		)
		(stroke
			(width 0)
			(type solid)
		)
		(fill yes)
		(layer "In13.Cu")
		(net "GND")
	)
	(gr_poly
		(pts
			(arc
				(start 385.580382 -107.57535)
				(mid 385.287266 -107.57535)
				(end 385.580382 -107.57535)
			)
		)
		(stroke
			(width 0)
			(type solid)
		)
		(fill yes)
		(layer "In13.Cu")
		(net "GND")
	)
	(gr_poly
		(pts
			(arc
				(start 385.580382 -106.316526)
				(mid 385.287266 -106.316526)
				(end 385.580382 -106.316526)
			)
		)
		(stroke
			(width 0)
			(type solid)
		)
		(fill yes)
		(layer "In13.Cu")
		(net "GND")
	)
	(gr_poly
		(pts
			(arc
				(start 385.580382 -103.975408)
				(mid 385.287266 -103.975408)
				(end 385.580382 -103.975408)
			)
		)
		(stroke
			(width 0)
			(type solid)
		)
		(fill yes)
		(layer "In13.Cu")
		(net "GND")
	)
	(gr_poly
		(pts
			(arc
				(start 385.580382 -102.716584)
				(mid 385.287266 -102.716584)
				(end 385.580382 -102.716584)
			)
		)
		(stroke
			(width 0)
			(type solid)
		)
		(fill yes)
		(layer "In13.Cu")
		(net "GND")
	)
	(gr_poly
		(pts
			(arc
				(start 385.580382 -100.375466)
				(mid 385.287266 -100.375466)
				(end 385.580382 -100.375466)
			)
		)
		(stroke
			(width 0)
			(type solid)
		)
		(fill yes)
		(layer "In13.Cu")
		(net "GND")
	)
	(gr_poly
		(pts
			(arc
				(start 385.580382 -99.116642)
				(mid 385.287266 -99.116642)
				(end 385.580382 -99.116642)
			)
		)
		(stroke
			(width 0)
			(type solid)
		)
		(fill yes)
		(layer "In13.Cu")
		(net "GND")
	)
	(gr_poly
		(pts
			(arc
				(start 386.84835 -136.901936)
				(mid 386.555234 -136.901936)
				(end 386.84835 -136.901936)
			)
		)
		(stroke
			(width 0)
			(type solid)
		)
		(fill yes)
		(layer "In13.Cu")
		(net "GND")
	)
	(gr_poly
		(pts
			(arc
				(start 386.84835 -135.643112)
				(mid 386.555234 -135.643112)
				(end 386.84835 -135.643112)
			)
		)
		(stroke
			(width 0)
			(type solid)
		)
		(fill yes)
		(layer "In13.Cu")
		(net "GND")
	)
	(gr_poly
		(pts
			(arc
				(start 386.84835 -133.301994)
				(mid 386.555234 -133.301994)
				(end 386.84835 -133.301994)
			)
		)
		(stroke
			(width 0)
			(type solid)
		)
		(fill yes)
		(layer "In13.Cu")
		(net "GND")
	)
	(gr_poly
		(pts
			(arc
				(start 386.84835 -132.04317)
				(mid 386.555234 -132.04317)
				(end 386.84835 -132.04317)
			)
		)
		(stroke
			(width 0)
			(type solid)
		)
		(fill yes)
		(layer "In13.Cu")
		(net "GND")
	)
	(gr_poly
		(pts
			(arc
				(start 386.84835 -125.692154)
				(mid 386.555234 -125.692154)
				(end 386.84835 -125.692154)
			)
		)
		(stroke
			(width 0)
			(type solid)
		)
		(fill yes)
		(layer "In13.Cu")
		(net "GND")
	)
	(gr_poly
		(pts
			(arc
				(start 386.84835 -124.43333)
				(mid 386.555234 -124.43333)
				(end 386.84835 -124.43333)
			)
		)
		(stroke
			(width 0)
			(type solid)
		)
		(fill yes)
		(layer "In13.Cu")
		(net "GND")
	)
	(gr_poly
		(pts
			(arc
				(start 386.84835 -122.091958)
				(mid 386.555234 -122.091958)
				(end 386.84835 -122.091958)
			)
		)
		(stroke
			(width 0)
			(type solid)
		)
		(fill yes)
		(layer "In13.Cu")
		(net "GND")
	)
	(gr_poly
		(pts
			(arc
				(start 386.84835 -120.833134)
				(mid 386.555234 -120.833134)
				(end 386.84835 -120.833134)
			)
		)
		(stroke
			(width 0)
			(type solid)
		)
		(fill yes)
		(layer "In13.Cu")
		(net "GND")
	)
	(gr_poly
		(pts
			(arc
				(start 386.84835 -111.175546)
				(mid 386.555234 -111.175546)
				(end 386.84835 -111.175546)
			)
		)
		(stroke
			(width 0)
			(type solid)
		)
		(fill yes)
		(layer "In13.Cu")
		(net "GND")
	)
	(gr_poly
		(pts
			(arc
				(start 386.84835 -109.916722)
				(mid 386.555234 -109.916722)
				(end 386.84835 -109.916722)
			)
		)
		(stroke
			(width 0)
			(type solid)
		)
		(fill yes)
		(layer "In13.Cu")
		(net "GND")
	)
	(gr_poly
		(pts
			(arc
				(start 386.84835 -107.57535)
				(mid 386.555234 -107.57535)
				(end 386.84835 -107.57535)
			)
		)
		(stroke
			(width 0)
			(type solid)
		)
		(fill yes)
		(layer "In13.Cu")
		(net "GND")
	)
	(gr_poly
		(pts
			(arc
				(start 386.84835 -106.316526)
				(mid 386.555234 -106.316526)
				(end 386.84835 -106.316526)
			)
		)
		(stroke
			(width 0)
			(type solid)
		)
		(fill yes)
		(layer "In13.Cu")
		(net "GND")
	)
	(gr_poly
		(pts
			(arc
				(start 386.84835 -103.975408)
				(mid 386.555234 -103.975408)
				(end 386.84835 -103.975408)
			)
		)
		(stroke
			(width 0)
			(type solid)
		)
		(fill yes)
		(layer "In13.Cu")
		(net "GND")
	)
	(gr_poly
		(pts
			(arc
				(start 386.84835 -102.716584)
				(mid 386.555234 -102.716584)
				(end 386.84835 -102.716584)
			)
		)
		(stroke
			(width 0)
			(type solid)
		)
		(fill yes)
		(layer "In13.Cu")
		(net "GND")
	)
	(gr_poly
		(pts
			(arc
				(start 386.84835 -100.375466)
				(mid 386.555234 -100.375466)
				(end 386.84835 -100.375466)
			)
		)
		(stroke
			(width 0)
			(type solid)
		)
		(fill yes)
		(layer "In13.Cu")
		(net "GND")
	)
	(gr_poly
		(pts
			(arc
				(start 386.84835 -99.116642)
				(mid 386.555234 -99.116642)
				(end 386.84835 -99.116642)
			)
		)
		(stroke
			(width 0)
			(type solid)
		)
		(fill yes)
		(layer "In13.Cu")
		(net "GND")
	)
	(gr_poly
		(pts
			(arc
				(start 399.998946 -159.987234)
				(mid 399.70583 -159.987234)
				(end 399.998946 -159.987234)
			)
		)
		(stroke
			(width 0)
			(type solid)
		)
		(fill yes)
		(layer "In13.Cu")
		(net "GND")
	)
	(gr_poly
		(pts
			(arc
				(start 400.987514 -154.321002)
				(mid 400.694398 -154.321002)
				(end 400.987514 -154.321002)
			)
		)
		(stroke
			(width 0)
			(type solid)
		)
		(fill yes)
		(layer "In13.Cu")
		(net "GND")
	)
	(gr_poly
		(pts
			(arc
				(start 401.131024 -155.713938)
				(mid 400.837908 -155.713938)
				(end 401.131024 -155.713938)
			)
		)
		(stroke
			(width 0)
			(type solid)
		)
		(fill yes)
		(layer "In13.Cu")
		(net "GND")
	)
	(gr_poly
		(pts
			(arc
				(start 401.298918 -137.164826)
				(mid 401.005802 -137.164826)
				(end 401.298918 -137.164826)
			)
		)
		(stroke
			(width 0)
			(type solid)
		)
		(fill yes)
		(layer "In13.Cu")
		(net "GND")
	)
	(gr_poly
		(pts
			(arc
				(start 401.298918 -135.364728)
				(mid 401.005802 -135.364728)
				(end 401.298918 -135.364728)
			)
		)
		(stroke
			(width 0)
			(type solid)
		)
		(fill yes)
		(layer "In13.Cu")
		(net "GND")
	)
	(gr_poly
		(pts
			(arc
				(start 401.298918 -133.56463)
				(mid 401.005802 -133.56463)
				(end 401.298918 -133.56463)
			)
		)
		(stroke
			(width 0)
			(type solid)
		)
		(fill yes)
		(layer "In13.Cu")
		(net "GND")
	)
	(gr_poly
		(pts
			(arc
				(start 401.298918 -131.764786)
				(mid 401.005802 -131.764786)
				(end 401.298918 -131.764786)
			)
		)
		(stroke
			(width 0)
			(type solid)
		)
		(fill yes)
		(layer "In13.Cu")
		(net "GND")
	)
	(gr_poly
		(pts
			(arc
				(start 401.298918 -125.95479)
				(mid 401.005802 -125.95479)
				(end 401.298918 -125.95479)
			)
		)
		(stroke
			(width 0)
			(type solid)
		)
		(fill yes)
		(layer "In13.Cu")
		(net "GND")
	)
	(gr_poly
		(pts
			(arc
				(start 401.298918 -124.154692)
				(mid 401.005802 -124.154692)
				(end 401.298918 -124.154692)
			)
		)
		(stroke
			(width 0)
			(type solid)
		)
		(fill yes)
		(layer "In13.Cu")
		(net "GND")
	)
	(gr_poly
		(pts
			(arc
				(start 401.298918 -122.354594)
				(mid 401.005802 -122.354594)
				(end 401.298918 -122.354594)
			)
		)
		(stroke
			(width 0)
			(type solid)
		)
		(fill yes)
		(layer "In13.Cu")
		(net "GND")
	)
	(gr_poly
		(pts
			(arc
				(start 401.298918 -120.55475)
				(mid 401.005802 -120.55475)
				(end 401.298918 -120.55475)
			)
		)
		(stroke
			(width 0)
			(type solid)
		)
		(fill yes)
		(layer "In13.Cu")
		(net "GND")
	)
	(gr_poly
		(pts
			(arc
				(start 401.298918 -113.244884)
				(mid 401.005802 -113.244884)
				(end 401.298918 -113.244884)
			)
		)
		(stroke
			(width 0)
			(type solid)
		)
		(fill yes)
		(layer "In13.Cu")
		(net "GND")
	)
	(gr_poly
		(pts
			(arc
				(start 401.298918 -111.444786)
				(mid 401.005802 -111.444786)
				(end 401.298918 -111.444786)
			)
		)
		(stroke
			(width 0)
			(type solid)
		)
		(fill yes)
		(layer "In13.Cu")
		(net "GND")
	)
	(gr_poly
		(pts
			(arc
				(start 401.298918 -109.644688)
				(mid 401.005802 -109.644688)
				(end 401.298918 -109.644688)
			)
		)
		(stroke
			(width 0)
			(type solid)
		)
		(fill yes)
		(layer "In13.Cu")
		(net "GND")
	)
	(gr_poly
		(pts
			(arc
				(start 401.298918 -107.84459)
				(mid 401.005802 -107.84459)
				(end 401.298918 -107.84459)
			)
		)
		(stroke
			(width 0)
			(type solid)
		)
		(fill yes)
		(layer "In13.Cu")
		(net "GND")
	)
	(gr_poly
		(pts
			(arc
				(start 401.298918 -106.044746)
				(mid 401.005802 -106.044746)
				(end 401.298918 -106.044746)
			)
		)
		(stroke
			(width 0)
			(type solid)
		)
		(fill yes)
		(layer "In13.Cu")
		(net "GND")
	)
	(gr_poly
		(pts
			(arc
				(start 401.298918 -104.244648)
				(mid 401.005802 -104.244648)
				(end 401.298918 -104.244648)
			)
		)
		(stroke
			(width 0)
			(type solid)
		)
		(fill yes)
		(layer "In13.Cu")
		(net "GND")
	)
	(gr_poly
		(pts
			(arc
				(start 401.298918 -102.444804)
				(mid 401.005802 -102.444804)
				(end 401.298918 -102.444804)
			)
		)
		(stroke
			(width 0)
			(type solid)
		)
		(fill yes)
		(layer "In13.Cu")
		(net "GND")
	)
	(gr_poly
		(pts
			(arc
				(start 401.298918 -100.644706)
				(mid 401.005802 -100.644706)
				(end 401.298918 -100.644706)
			)
		)
		(stroke
			(width 0)
			(type solid)
		)
		(fill yes)
		(layer "In13.Cu")
		(net "GND")
	)
	(gr_poly
		(pts
			(arc
				(start 401.40382 -152.1714)
				(mid 401.110704 -152.1714)
				(end 401.40382 -152.1714)
			)
		)
		(stroke
			(width 0)
			(type solid)
		)
		(fill yes)
		(layer "In13.Cu")
		(net "GND")
	)
	(gr_poly
		(pts
			(arc
				(start 401.933918 -135.364728)
				(mid 401.640802 -135.364728)
				(end 401.933918 -135.364728)
			)
		)
		(stroke
			(width 0)
			(type solid)
		)
		(fill yes)
		(layer "In13.Cu")
		(net "GND")
	)
	(gr_poly
		(pts
			(arc
				(start 401.933918 -133.56463)
				(mid 401.640802 -133.56463)
				(end 401.933918 -133.56463)
			)
		)
		(stroke
			(width 0)
			(type solid)
		)
		(fill yes)
		(layer "In13.Cu")
		(net "GND")
	)
	(gr_poly
		(pts
			(arc
				(start 401.933918 -131.764786)
				(mid 401.640802 -131.764786)
				(end 401.933918 -131.764786)
			)
		)
		(stroke
			(width 0)
			(type solid)
		)
		(fill yes)
		(layer "In13.Cu")
		(net "GND")
	)
	(gr_poly
		(pts
			(arc
				(start 401.933918 -129.964688)
				(mid 401.640802 -129.964688)
				(end 401.933918 -129.964688)
			)
		)
		(stroke
			(width 0)
			(type solid)
		)
		(fill yes)
		(layer "In13.Cu")
		(net "GND")
	)
	(gr_poly
		(pts
			(arc
				(start 401.933918 -124.154692)
				(mid 401.640802 -124.154692)
				(end 401.933918 -124.154692)
			)
		)
		(stroke
			(width 0)
			(type solid)
		)
		(fill yes)
		(layer "In13.Cu")
		(net "GND")
	)
	(gr_poly
		(pts
			(arc
				(start 401.933918 -122.354594)
				(mid 401.640802 -122.354594)
				(end 401.933918 -122.354594)
			)
		)
		(stroke
			(width 0)
			(type solid)
		)
		(fill yes)
		(layer "In13.Cu")
		(net "GND")
	)
	(gr_poly
		(pts
			(arc
				(start 401.933918 -120.55475)
				(mid 401.640802 -120.55475)
				(end 401.933918 -120.55475)
			)
		)
		(stroke
			(width 0)
			(type solid)
		)
		(fill yes)
		(layer "In13.Cu")
		(net "GND")
	)
	(gr_poly
		(pts
			(arc
				(start 401.933918 -118.754652)
				(mid 401.640802 -118.754652)
				(end 401.933918 -118.754652)
			)
		)
		(stroke
			(width 0)
			(type solid)
		)
		(fill yes)
		(layer "In13.Cu")
		(net "GND")
	)
	(gr_poly
		(pts
			(arc
				(start 401.933918 -111.444786)
				(mid 401.640802 -111.444786)
				(end 401.933918 -111.444786)
			)
		)
		(stroke
			(width 0)
			(type solid)
		)
		(fill yes)
		(layer "In13.Cu")
		(net "GND")
	)
	(gr_poly
		(pts
			(arc
				(start 401.933918 -109.644688)
				(mid 401.640802 -109.644688)
				(end 401.933918 -109.644688)
			)
		)
		(stroke
			(width 0)
			(type solid)
		)
		(fill yes)
		(layer "In13.Cu")
		(net "GND")
	)
	(gr_poly
		(pts
			(arc
				(start 401.933918 -107.84459)
				(mid 401.640802 -107.84459)
				(end 401.933918 -107.84459)
			)
		)
		(stroke
			(width 0)
			(type solid)
		)
		(fill yes)
		(layer "In13.Cu")
		(net "GND")
	)
	(gr_poly
		(pts
			(arc
				(start 401.933918 -106.044492)
				(mid 401.640802 -106.044492)
				(end 401.933918 -106.044492)
			)
		)
		(stroke
			(width 0)
			(type solid)
		)
		(fill yes)
		(layer "In13.Cu")
		(net "GND")
	)
	(gr_poly
		(pts
			(arc
				(start 401.933918 -104.244648)
				(mid 401.640802 -104.244648)
				(end 401.933918 -104.244648)
			)
		)
		(stroke
			(width 0)
			(type solid)
		)
		(fill yes)
		(layer "In13.Cu")
		(net "GND")
	)
	(gr_poly
		(pts
			(arc
				(start 401.933918 -102.44455)
				(mid 401.640802 -102.44455)
				(end 401.933918 -102.44455)
			)
		)
		(stroke
			(width 0)
			(type solid)
		)
		(fill yes)
		(layer "In13.Cu")
		(net "GND")
	)
	(gr_poly
		(pts
			(arc
				(start 401.933918 -100.644706)
				(mid 401.640802 -100.644706)
				(end 401.933918 -100.644706)
			)
		)
		(stroke
			(width 0)
			(type solid)
		)
		(fill yes)
		(layer "In13.Cu")
		(net "GND")
	)
	(gr_poly
		(pts
			(arc
				(start 401.933918 -98.844608)
				(mid 401.640802 -98.844608)
				(end 401.933918 -98.844608)
			)
		)
		(stroke
			(width 0)
			(type solid)
		)
		(fill yes)
		(layer "In13.Cu")
		(net "GND")
	)
	(gr_poly
		(pts
			(arc
				(start 403.153118 -135.364728)
				(mid 402.860002 -135.364728)
				(end 403.153118 -135.364728)
			)
		)
		(stroke
			(width 0)
			(type solid)
		)
		(fill yes)
		(layer "In13.Cu")
		(net "GND")
	)
	(gr_poly
		(pts
			(arc
				(start 403.153118 -133.56463)
				(mid 402.860002 -133.56463)
				(end 403.153118 -133.56463)
			)
		)
		(stroke
			(width 0)
			(type solid)
		)
		(fill yes)
		(layer "In13.Cu")
		(net "GND")
	)
	(gr_poly
		(pts
			(arc
				(start 403.153118 -131.764786)
				(mid 402.860002 -131.764786)
				(end 403.153118 -131.764786)
			)
		)
		(stroke
			(width 0)
			(type solid)
		)
		(fill yes)
		(layer "In13.Cu")
		(net "GND")
	)
	(gr_poly
		(pts
			(arc
				(start 403.153118 -129.964688)
				(mid 402.860002 -129.964688)
				(end 403.153118 -129.964688)
			)
		)
		(stroke
			(width 0)
			(type solid)
		)
		(fill yes)
		(layer "In13.Cu")
		(net "GND")
	)
	(gr_poly
		(pts
			(arc
				(start 403.153118 -124.154692)
				(mid 402.860002 -124.154692)
				(end 403.153118 -124.154692)
			)
		)
		(stroke
			(width 0)
			(type solid)
		)
		(fill yes)
		(layer "In13.Cu")
		(net "GND")
	)
	(gr_poly
		(pts
			(arc
				(start 403.153118 -122.354594)
				(mid 402.860002 -122.354594)
				(end 403.153118 -122.354594)
			)
		)
		(stroke
			(width 0)
			(type solid)
		)
		(fill yes)
		(layer "In13.Cu")
		(net "GND")
	)
	(gr_poly
		(pts
			(arc
				(start 403.153118 -120.55475)
				(mid 402.860002 -120.55475)
				(end 403.153118 -120.55475)
			)
		)
		(stroke
			(width 0)
			(type solid)
		)
		(fill yes)
		(layer "In13.Cu")
		(net "GND")
	)
	(gr_poly
		(pts
			(arc
				(start 403.153118 -118.754652)
				(mid 402.860002 -118.754652)
				(end 403.153118 -118.754652)
			)
		)
		(stroke
			(width 0)
			(type solid)
		)
		(fill yes)
		(layer "In13.Cu")
		(net "GND")
	)
	(gr_poly
		(pts
			(arc
				(start 403.153118 -111.444786)
				(mid 402.860002 -111.444786)
				(end 403.153118 -111.444786)
			)
		)
		(stroke
			(width 0)
			(type solid)
		)
		(fill yes)
		(layer "In13.Cu")
		(net "GND")
	)
	(gr_poly
		(pts
			(arc
				(start 403.153118 -109.644688)
				(mid 402.860002 -109.644688)
				(end 403.153118 -109.644688)
			)
		)
		(stroke
			(width 0)
			(type solid)
		)
		(fill yes)
		(layer "In13.Cu")
		(net "GND")
	)
	(gr_poly
		(pts
			(arc
				(start 403.153118 -107.84459)
				(mid 402.860002 -107.84459)
				(end 403.153118 -107.84459)
			)
		)
		(stroke
			(width 0)
			(type solid)
		)
		(fill yes)
		(layer "In13.Cu")
		(net "GND")
	)
	(gr_poly
		(pts
			(arc
				(start 403.153118 -106.044492)
				(mid 402.860002 -106.044492)
				(end 403.153118 -106.044492)
			)
		)
		(stroke
			(width 0)
			(type solid)
		)
		(fill yes)
		(layer "In13.Cu")
		(net "GND")
	)
	(gr_poly
		(pts
			(arc
				(start 403.153118 -104.244648)
				(mid 402.860002 -104.244648)
				(end 403.153118 -104.244648)
			)
		)
		(stroke
			(width 0)
			(type solid)
		)
		(fill yes)
		(layer "In13.Cu")
		(net "GND")
	)
	(gr_poly
		(pts
			(arc
				(start 403.153118 -102.44455)
				(mid 402.860002 -102.44455)
				(end 403.153118 -102.44455)
			)
		)
		(stroke
			(width 0)
			(type solid)
		)
		(fill yes)
		(layer "In13.Cu")
		(net "GND")
	)
	(gr_poly
		(pts
			(arc
				(start 403.153118 -100.644706)
				(mid 402.860002 -100.644706)
				(end 403.153118 -100.644706)
			)
		)
		(stroke
			(width 0)
			(type solid)
		)
		(fill yes)
		(layer "In13.Cu")
		(net "GND")
	)
	(gr_poly
		(pts
			(arc
				(start 403.153118 -98.844608)
				(mid 402.860002 -98.844608)
				(end 403.153118 -98.844608)
			)
		)
		(stroke
			(width 0)
			(type solid)
		)
		(fill yes)
		(layer "In13.Cu")
		(net "GND")
	)
	(gr_poly
		(pts
			(arc
				(start 405.711914 -97.282508)
				(mid 405.418798 -97.282508)
				(end 405.711914 -97.282508)
			)
		)
		(stroke
			(width 0)
			(type solid)
		)
		(fill yes)
		(layer "In13.Cu")
		(net "GND")
	)
	(gr_poly
		(pts
			(arc
				(start 405.786082 -73.765918)
				(mid 405.492966 -73.765918)
				(end 405.786082 -73.765918)
			)
		)
		(stroke
			(width 0)
			(type solid)
		)
		(fill yes)
		(layer "In13.Cu")
		(net "GND")
	)
	(gr_poly
		(pts
			(arc
				(start 406.038558 -377.444)
				(mid 405.745442 -377.444)
				(end 406.038558 -377.444)
			)
		)
		(stroke
			(width 0)
			(type solid)
		)
		(fill yes)
		(layer "In13.Cu")
		(net "GND")
	)
	(gr_poly
		(pts
			(arc
				(start 406.165558 -374.015)
				(mid 405.872442 -374.015)
				(end 406.165558 -374.015)
			)
		)
		(stroke
			(width 0)
			(type solid)
		)
		(fill yes)
		(layer "In13.Cu")
		(net "GND")
	)
	(gr_poly
		(pts
			(arc
				(start 406.324816 -95.398844)
				(mid 406.0317 -95.398844)
				(end 406.324816 -95.398844)
			)
		)
		(stroke
			(width 0)
			(type solid)
		)
		(fill yes)
		(layer "In13.Cu")
		(net "GND")
	)
	(gr_poly
		(pts
			(arc
				(start 407.047446 -34.98977)
				(mid 406.75433 -34.98977)
				(end 407.047446 -34.98977)
			)
		)
		(stroke
			(width 0)
			(type solid)
		)
		(fill yes)
		(layer "In13.Cu")
		(net "GND")
	)
	(gr_poly
		(pts
			(arc
				(start 407.047446 -33.189926)
				(mid 406.75433 -33.189926)
				(end 407.047446 -33.189926)
			)
		)
		(stroke
			(width 0)
			(type solid)
		)
		(fill yes)
		(layer "In13.Cu")
		(net "GND")
	)
	(gr_poly
		(pts
			(arc
				(start 407.047446 -31.389828)
				(mid 406.75433 -31.389828)
				(end 407.047446 -31.389828)
			)
		)
		(stroke
			(width 0)
			(type solid)
		)
		(fill yes)
		(layer "In13.Cu")
		(net "GND")
	)
	(gr_poly
		(pts
			(arc
				(start 407.047446 -29.589984)
				(mid 406.75433 -29.589984)
				(end 407.047446 -29.589984)
			)
		)
		(stroke
			(width 0)
			(type solid)
		)
		(fill yes)
		(layer "In13.Cu")
		(net "GND")
	)
	(gr_poly
		(pts
			(arc
				(start 407.562558 -385.064)
				(mid 407.269442 -385.064)
				(end 407.562558 -385.064)
			)
		)
		(stroke
			(width 0)
			(type solid)
		)
		(fill yes)
		(layer "In13.Cu")
		(net "GND")
	)
	(gr_poly
		(pts
			(arc
				(start 408.266646 -34.98977)
				(mid 407.97353 -34.98977)
				(end 408.266646 -34.98977)
			)
		)
		(stroke
			(width 0)
			(type solid)
		)
		(fill yes)
		(layer "In13.Cu")
		(net "GND")
	)
	(gr_poly
		(pts
			(arc
				(start 408.266646 -33.189926)
				(mid 407.97353 -33.189926)
				(end 408.266646 -33.189926)
			)
		)
		(stroke
			(width 0)
			(type solid)
		)
		(fill yes)
		(layer "In13.Cu")
		(net "GND")
	)
	(gr_poly
		(pts
			(arc
				(start 408.266646 -31.389828)
				(mid 407.97353 -31.389828)
				(end 408.266646 -31.389828)
			)
		)
		(stroke
			(width 0)
			(type solid)
		)
		(fill yes)
		(layer "In13.Cu")
		(net "GND")
	)
	(gr_poly
		(pts
			(arc
				(start 408.266646 -29.589984)
				(mid 407.97353 -29.589984)
				(end 408.266646 -29.589984)
			)
		)
		(stroke
			(width 0)
			(type solid)
		)
		(fill yes)
		(layer "In13.Cu")
		(net "GND")
	)
	(gr_poly
		(pts
			(arc
				(start 408.901646 -33.189926)
				(mid 408.60853 -33.189926)
				(end 408.901646 -33.189926)
			)
		)
		(stroke
			(width 0)
			(type solid)
		)
		(fill yes)
		(layer "In13.Cu")
		(net "GND")
	)
	(gr_poly
		(pts
			(arc
				(start 408.901646 -31.389828)
				(mid 408.60853 -31.389828)
				(end 408.901646 -31.389828)
			)
		)
		(stroke
			(width 0)
			(type solid)
		)
		(fill yes)
		(layer "In13.Cu")
		(net "GND")
	)
	(gr_poly
		(pts
			(arc
				(start 408.901646 -29.589984)
				(mid 408.60853 -29.589984)
				(end 408.901646 -29.589984)
			)
		)
		(stroke
			(width 0)
			(type solid)
		)
		(fill yes)
		(layer "In13.Cu")
		(net "GND")
	)
	(gr_poly
		(pts
			(arc
				(start 408.901646 -27.789886)
				(mid 408.60853 -27.789886)
				(end 408.901646 -27.789886)
			)
		)
		(stroke
			(width 0)
			(type solid)
		)
		(fill yes)
		(layer "In13.Cu")
		(net "GND")
	)
	(gr_poly
		(pts
			(arc
				(start 413.040068 -156.554932)
				(mid 412.746952 -156.554932)
				(end 413.040068 -156.554932)
			)
		)
		(stroke
			(width 0)
			(type solid)
		)
		(fill yes)
		(layer "In13.Cu")
		(net "GND")
	)
	(gr_poly
		(pts
			(arc
				(start 413.040068 -154.754834)
				(mid 412.746952 -154.754834)
				(end 413.040068 -154.754834)
			)
		)
		(stroke
			(width 0)
			(type solid)
		)
		(fill yes)
		(layer "In13.Cu")
		(net "GND")
	)
	(gr_poly
		(pts
			(arc
				(start 413.040068 -152.95499)
				(mid 412.746952 -152.95499)
				(end 413.040068 -152.95499)
			)
		)
		(stroke
			(width 0)
			(type solid)
		)
		(fill yes)
		(layer "In13.Cu")
		(net "GND")
	)
	(gr_poly
		(pts
			(arc
				(start 413.040068 -151.154892)
				(mid 412.746952 -151.154892)
				(end 413.040068 -151.154892)
			)
		)
		(stroke
			(width 0)
			(type solid)
		)
		(fill yes)
		(layer "In13.Cu")
		(net "GND")
	)
	(gr_poly
		(pts
			(arc
				(start 413.040068 -149.355048)
				(mid 412.746952 -149.355048)
				(end 413.040068 -149.355048)
			)
		)
		(stroke
			(width 0)
			(type solid)
		)
		(fill yes)
		(layer "In13.Cu")
		(net "GND")
	)
	(gr_poly
		(pts
			(arc
				(start 413.040068 -147.55495)
				(mid 412.746952 -147.55495)
				(end 413.040068 -147.55495)
			)
		)
		(stroke
			(width 0)
			(type solid)
		)
		(fill yes)
		(layer "In13.Cu")
		(net "GND")
	)
	(gr_poly
		(pts
			(arc
				(start 413.040068 -145.755106)
				(mid 412.746952 -145.755106)
				(end 413.040068 -145.755106)
			)
		)
		(stroke
			(width 0)
			(type solid)
		)
		(fill yes)
		(layer "In13.Cu")
		(net "GND")
	)
	(gr_poly
		(pts
			(arc
				(start 413.040068 -143.955008)
				(mid 412.746952 -143.955008)
				(end 413.040068 -143.955008)
			)
		)
		(stroke
			(width 0)
			(type solid)
		)
		(fill yes)
		(layer "In13.Cu")
		(net "GND")
	)
	(gr_poly
		(pts
			(arc
				(start 413.040068 -136.644888)
				(mid 412.746952 -136.644888)
				(end 413.040068 -136.644888)
			)
		)
		(stroke
			(width 0)
			(type solid)
		)
		(fill yes)
		(layer "In13.Cu")
		(net "GND")
	)
	(gr_poly
		(pts
			(arc
				(start 413.040068 -134.84479)
				(mid 412.746952 -134.84479)
				(end 413.040068 -134.84479)
			)
		)
		(stroke
			(width 0)
			(type solid)
		)
		(fill yes)
		(layer "In13.Cu")
		(net "GND")
	)
	(gr_poly
		(pts
			(arc
				(start 413.040068 -133.044946)
				(mid 412.746952 -133.044946)
				(end 413.040068 -133.044946)
			)
		)
		(stroke
			(width 0)
			(type solid)
		)
		(fill yes)
		(layer "In13.Cu")
		(net "GND")
	)
	(gr_poly
		(pts
			(arc
				(start 413.040068 -131.244848)
				(mid 412.746952 -131.244848)
				(end 413.040068 -131.244848)
			)
		)
		(stroke
			(width 0)
			(type solid)
		)
		(fill yes)
		(layer "In13.Cu")
		(net "GND")
	)
	(gr_poly
		(pts
			(arc
				(start 413.040068 -125.434852)
				(mid 412.746952 -125.434852)
				(end 413.040068 -125.434852)
			)
		)
		(stroke
			(width 0)
			(type solid)
		)
		(fill yes)
		(layer "In13.Cu")
		(net "GND")
	)
	(gr_poly
		(pts
			(arc
				(start 413.040068 -123.634754)
				(mid 412.746952 -123.634754)
				(end 413.040068 -123.634754)
			)
		)
		(stroke
			(width 0)
			(type solid)
		)
		(fill yes)
		(layer "In13.Cu")
		(net "GND")
	)
	(gr_poly
		(pts
			(arc
				(start 413.040068 -121.83491)
				(mid 412.746952 -121.83491)
				(end 413.040068 -121.83491)
			)
		)
		(stroke
			(width 0)
			(type solid)
		)
		(fill yes)
		(layer "In13.Cu")
		(net "GND")
	)
	(gr_poly
		(pts
			(arc
				(start 413.040068 -120.034812)
				(mid 412.746952 -120.034812)
				(end 413.040068 -120.034812)
			)
		)
		(stroke
			(width 0)
			(type solid)
		)
		(fill yes)
		(layer "In13.Cu")
		(net "GND")
	)
	(gr_poly
		(pts
			(arc
				(start 414.259268 -156.554932)
				(mid 413.966152 -156.554932)
				(end 414.259268 -156.554932)
			)
		)
		(stroke
			(width 0)
			(type solid)
		)
		(fill yes)
		(layer "In13.Cu")
		(net "GND")
	)
	(gr_poly
		(pts
			(arc
				(start 414.259268 -154.754834)
				(mid 413.966152 -154.754834)
				(end 414.259268 -154.754834)
			)
		)
		(stroke
			(width 0)
			(type solid)
		)
		(fill yes)
		(layer "In13.Cu")
		(net "GND")
	)
	(gr_poly
		(pts
			(arc
				(start 414.259268 -152.95499)
				(mid 413.966152 -152.95499)
				(end 414.259268 -152.95499)
			)
		)
		(stroke
			(width 0)
			(type solid)
		)
		(fill yes)
		(layer "In13.Cu")
		(net "GND")
	)
	(gr_poly
		(pts
			(arc
				(start 414.259268 -151.154892)
				(mid 413.966152 -151.154892)
				(end 414.259268 -151.154892)
			)
		)
		(stroke
			(width 0)
			(type solid)
		)
		(fill yes)
		(layer "In13.Cu")
		(net "GND")
	)
	(gr_poly
		(pts
			(arc
				(start 414.259268 -149.355048)
				(mid 413.966152 -149.355048)
				(end 414.259268 -149.355048)
			)
		)
		(stroke
			(width 0)
			(type solid)
		)
		(fill yes)
		(layer "In13.Cu")
		(net "GND")
	)
	(gr_poly
		(pts
			(arc
				(start 414.259268 -147.55495)
				(mid 413.966152 -147.55495)
				(end 414.259268 -147.55495)
			)
		)
		(stroke
			(width 0)
			(type solid)
		)
		(fill yes)
		(layer "In13.Cu")
		(net "GND")
	)
	(gr_poly
		(pts
			(arc
				(start 414.259268 -145.755106)
				(mid 413.966152 -145.755106)
				(end 414.259268 -145.755106)
			)
		)
		(stroke
			(width 0)
			(type solid)
		)
		(fill yes)
		(layer "In13.Cu")
		(net "GND")
	)
	(gr_poly
		(pts
			(arc
				(start 414.259268 -143.955008)
				(mid 413.966152 -143.955008)
				(end 414.259268 -143.955008)
			)
		)
		(stroke
			(width 0)
			(type solid)
		)
		(fill yes)
		(layer "In13.Cu")
		(net "GND")
	)
	(gr_poly
		(pts
			(arc
				(start 414.259268 -136.644888)
				(mid 413.966152 -136.644888)
				(end 414.259268 -136.644888)
			)
		)
		(stroke
			(width 0)
			(type solid)
		)
		(fill yes)
		(layer "In13.Cu")
		(net "GND")
	)
	(gr_poly
		(pts
			(arc
				(start 414.259268 -134.84479)
				(mid 413.966152 -134.84479)
				(end 414.259268 -134.84479)
			)
		)
		(stroke
			(width 0)
			(type solid)
		)
		(fill yes)
		(layer "In13.Cu")
		(net "GND")
	)
	(gr_poly
		(pts
			(arc
				(start 414.259268 -133.044946)
				(mid 413.966152 -133.044946)
				(end 414.259268 -133.044946)
			)
		)
		(stroke
			(width 0)
			(type solid)
		)
		(fill yes)
		(layer "In13.Cu")
		(net "GND")
	)
	(gr_poly
		(pts
			(arc
				(start 414.259268 -131.244848)
				(mid 413.966152 -131.244848)
				(end 414.259268 -131.244848)
			)
		)
		(stroke
			(width 0)
			(type solid)
		)
		(fill yes)
		(layer "In13.Cu")
		(net "GND")
	)
	(gr_poly
		(pts
			(arc
				(start 414.259268 -125.434852)
				(mid 413.966152 -125.434852)
				(end 414.259268 -125.434852)
			)
		)
		(stroke
			(width 0)
			(type solid)
		)
		(fill yes)
		(layer "In13.Cu")
		(net "GND")
	)
	(gr_poly
		(pts
			(arc
				(start 414.259268 -123.634754)
				(mid 413.966152 -123.634754)
				(end 414.259268 -123.634754)
			)
		)
		(stroke
			(width 0)
			(type solid)
		)
		(fill yes)
		(layer "In13.Cu")
		(net "GND")
	)
	(gr_poly
		(pts
			(arc
				(start 414.259268 -121.83491)
				(mid 413.966152 -121.83491)
				(end 414.259268 -121.83491)
			)
		)
		(stroke
			(width 0)
			(type solid)
		)
		(fill yes)
		(layer "In13.Cu")
		(net "GND")
	)
	(gr_poly
		(pts
			(arc
				(start 414.259268 -120.034812)
				(mid 413.966152 -120.034812)
				(end 414.259268 -120.034812)
			)
		)
		(stroke
			(width 0)
			(type solid)
		)
		(fill yes)
		(layer "In13.Cu")
		(net "GND")
	)
	(gr_poly
		(pts
			(arc
				(start 414.34512 -89.066116)
				(mid 414.052004 -89.066116)
				(end 414.34512 -89.066116)
			)
		)
		(stroke
			(width 0)
			(type solid)
		)
		(fill yes)
		(layer "In13.Cu")
		(net "GND")
	)
	(gr_poly
		(pts
			(arc
				(start 414.894268 -154.754834)
				(mid 414.601152 -154.754834)
				(end 414.894268 -154.754834)
			)
		)
		(stroke
			(width 0)
			(type solid)
		)
		(fill yes)
		(layer "In13.Cu")
		(net "GND")
	)
	(gr_poly
		(pts
			(arc
				(start 414.894268 -152.954736)
				(mid 414.601152 -152.954736)
				(end 414.894268 -152.954736)
			)
		)
		(stroke
			(width 0)
			(type solid)
		)
		(fill yes)
		(layer "In13.Cu")
		(net "GND")
	)
	(gr_poly
		(pts
			(arc
				(start 414.894268 -151.154892)
				(mid 414.601152 -151.154892)
				(end 414.894268 -151.154892)
			)
		)
		(stroke
			(width 0)
			(type solid)
		)
		(fill yes)
		(layer "In13.Cu")
		(net "GND")
	)
	(gr_poly
		(pts
			(arc
				(start 414.894268 -149.354794)
				(mid 414.601152 -149.354794)
				(end 414.894268 -149.354794)
			)
		)
		(stroke
			(width 0)
			(type solid)
		)
		(fill yes)
		(layer "In13.Cu")
		(net "GND")
	)
	(gr_poly
		(pts
			(arc
				(start 414.894268 -147.55495)
				(mid 414.601152 -147.55495)
				(end 414.894268 -147.55495)
			)
		)
		(stroke
			(width 0)
			(type solid)
		)
		(fill yes)
		(layer "In13.Cu")
		(net "GND")
	)
	(gr_poly
		(pts
			(arc
				(start 414.894268 -145.754852)
				(mid 414.601152 -145.754852)
				(end 414.894268 -145.754852)
			)
		)
		(stroke
			(width 0)
			(type solid)
		)
		(fill yes)
		(layer "In13.Cu")
		(net "GND")
	)
	(gr_poly
		(pts
			(arc
				(start 414.894268 -143.955008)
				(mid 414.601152 -143.955008)
				(end 414.894268 -143.955008)
			)
		)
		(stroke
			(width 0)
			(type solid)
		)
		(fill yes)
		(layer "In13.Cu")
		(net "GND")
	)
	(gr_poly
		(pts
			(arc
				(start 414.894268 -134.84479)
				(mid 414.601152 -134.84479)
				(end 414.894268 -134.84479)
			)
		)
		(stroke
			(width 0)
			(type solid)
		)
		(fill yes)
		(layer "In13.Cu")
		(net "GND")
	)
	(gr_poly
		(pts
			(arc
				(start 414.894268 -133.044946)
				(mid 414.601152 -133.044946)
				(end 414.894268 -133.044946)
			)
		)
		(stroke
			(width 0)
			(type solid)
		)
		(fill yes)
		(layer "In13.Cu")
		(net "GND")
	)
	(gr_poly
		(pts
			(arc
				(start 414.894268 -131.244848)
				(mid 414.601152 -131.244848)
				(end 414.894268 -131.244848)
			)
		)
		(stroke
			(width 0)
			(type solid)
		)
		(fill yes)
		(layer "In13.Cu")
		(net "GND")
	)
	(gr_poly
		(pts
			(arc
				(start 414.894268 -125.434852)
				(mid 414.601152 -125.434852)
				(end 414.894268 -125.434852)
			)
		)
		(stroke
			(width 0)
			(type solid)
		)
		(fill yes)
		(layer "In13.Cu")
		(net "GND")
	)
	(gr_poly
		(pts
			(arc
				(start 414.894268 -123.634754)
				(mid 414.601152 -123.634754)
				(end 414.894268 -123.634754)
			)
		)
		(stroke
			(width 0)
			(type solid)
		)
		(fill yes)
		(layer "In13.Cu")
		(net "GND")
	)
	(gr_poly
		(pts
			(arc
				(start 414.894268 -121.834656)
				(mid 414.601152 -121.834656)
				(end 414.894268 -121.834656)
			)
		)
		(stroke
			(width 0)
			(type solid)
		)
		(fill yes)
		(layer "In13.Cu")
		(net "GND")
	)
	(gr_poly
		(pts
			(arc
				(start 414.894268 -120.034812)
				(mid 414.601152 -120.034812)
				(end 414.894268 -120.034812)
			)
		)
		(stroke
			(width 0)
			(type solid)
		)
		(fill yes)
		(layer "In13.Cu")
		(net "GND")
	)
	(gr_poly
		(pts
			(arc
				(start 414.894268 -118.234714)
				(mid 414.601152 -118.234714)
				(end 414.894268 -118.234714)
			)
		)
		(stroke
			(width 0)
			(type solid)
		)
		(fill yes)
		(layer "In13.Cu")
		(net "GND")
	)
	(gr_poly
		(pts
			(arc
				(start 415.687256 -85.24621)
				(mid 415.39414 -85.24621)
				(end 415.687256 -85.24621)
			)
		)
		(stroke
			(width 0)
			(type solid)
		)
		(fill yes)
		(layer "In13.Cu")
		(net "GND")
	)
	(gr_poly
		(pts
			(arc
				(start 415.80943 -87.780876)
				(mid 415.516314 -87.780876)
				(end 415.80943 -87.780876)
			)
		)
		(stroke
			(width 0)
			(type solid)
		)
		(fill yes)
		(layer "In13.Cu")
		(net "GND")
	)
	(gr_poly
		(pts
			(arc
				(start 419.137592 -249.899678)
				(mid 418.844476 -249.899678)
				(end 419.137592 -249.899678)
			)
		)
		(stroke
			(width 0)
			(type solid)
		)
		(fill yes)
		(layer "In13.Cu")
		(net "GND")
	)
	(gr_poly
		(pts
			(arc
				(start 420.407846 -196.012054)
				(mid 420.11473 -196.012054)
				(end 420.407846 -196.012054)
			)
		)
		(stroke
			(width 0)
			(type solid)
		)
		(fill yes)
		(layer "In13.Cu")
		(net "GND")
	)
	(gr_poly
		(pts
			(arc
				(start 423.63009 -77.555852)
				(mid 423.336974 -77.555852)
				(end 423.63009 -77.555852)
			)
		)
		(stroke
			(width 0)
			(type solid)
		)
		(fill yes)
		(layer "In13.Cu")
		(net "GND")
	)
	(gr_poly
		(pts
			(arc
				(start 429.344836 -154.476958)
				(mid 429.05172 -154.476958)
				(end 429.344836 -154.476958)
			)
		)
		(stroke
			(width 0)
			(type solid)
		)
		(fill yes)
		(layer "In13.Cu")
		(net "GND")
	)
	(gr_poly
		(pts
			(arc
				(start 429.344836 -153.218134)
				(mid 429.05172 -153.218134)
				(end 429.344836 -153.218134)
			)
		)
		(stroke
			(width 0)
			(type solid)
		)
		(fill yes)
		(layer "In13.Cu")
		(net "GND")
	)
	(gr_poly
		(pts
			(arc
				(start 429.344836 -150.876762)
				(mid 429.05172 -150.876762)
				(end 429.344836 -150.876762)
			)
		)
		(stroke
			(width 0)
			(type solid)
		)
		(fill yes)
		(layer "In13.Cu")
		(net "GND")
	)
	(gr_poly
		(pts
			(arc
				(start 429.344836 -149.617938)
				(mid 429.05172 -149.617938)
				(end 429.344836 -149.617938)
			)
		)
		(stroke
			(width 0)
			(type solid)
		)
		(fill yes)
		(layer "In13.Cu")
		(net "GND")
	)
	(gr_poly
		(pts
			(arc
				(start 429.344836 -147.27682)
				(mid 429.05172 -147.27682)
				(end 429.344836 -147.27682)
			)
		)
		(stroke
			(width 0)
			(type solid)
		)
		(fill yes)
		(layer "In13.Cu")
		(net "GND")
	)
	(gr_poly
		(pts
			(arc
				(start 429.344836 -146.017996)
				(mid 429.05172 -146.017996)
				(end 429.344836 -146.017996)
			)
		)
		(stroke
			(width 0)
			(type solid)
		)
		(fill yes)
		(layer "In13.Cu")
		(net "GND")
	)
	(gr_poly
		(pts
			(arc
				(start 429.344836 -143.676878)
				(mid 429.05172 -143.676878)
				(end 429.344836 -143.676878)
			)
		)
		(stroke
			(width 0)
			(type solid)
		)
		(fill yes)
		(layer "In13.Cu")
		(net "GND")
	)
	(gr_poly
		(pts
			(arc
				(start 429.344836 -134.566914)
				(mid 429.05172 -134.566914)
				(end 429.344836 -134.566914)
			)
		)
		(stroke
			(width 0)
			(type solid)
		)
		(fill yes)
		(layer "In13.Cu")
		(net "GND")
	)
	(gr_poly
		(pts
			(arc
				(start 429.344836 -133.30809)
				(mid 429.05172 -133.30809)
				(end 429.344836 -133.30809)
			)
		)
		(stroke
			(width 0)
			(type solid)
		)
		(fill yes)
		(layer "In13.Cu")
		(net "GND")
	)
	(gr_poly
		(pts
			(arc
				(start 429.344836 -130.966718)
				(mid 429.05172 -130.966718)
				(end 429.344836 -130.966718)
			)
		)
		(stroke
			(width 0)
			(type solid)
		)
		(fill yes)
		(layer "In13.Cu")
		(net "GND")
	)
	(gr_poly
		(pts
			(arc
				(start 429.344836 -129.707894)
				(mid 429.05172 -129.707894)
				(end 429.344836 -129.707894)
			)
		)
		(stroke
			(width 0)
			(type solid)
		)
		(fill yes)
		(layer "In13.Cu")
		(net "GND")
	)
	(gr_poly
		(pts
			(arc
				(start 429.344836 -123.356878)
				(mid 429.05172 -123.356878)
				(end 429.344836 -123.356878)
			)
		)
		(stroke
			(width 0)
			(type solid)
		)
		(fill yes)
		(layer "In13.Cu")
		(net "GND")
	)
	(gr_poly
		(pts
			(arc
				(start 429.344836 -122.098054)
				(mid 429.05172 -122.098054)
				(end 429.344836 -122.098054)
			)
		)
		(stroke
			(width 0)
			(type solid)
		)
		(fill yes)
		(layer "In13.Cu")
		(net "GND")
	)
	(gr_poly
		(pts
			(arc
				(start 429.344836 -119.756936)
				(mid 429.05172 -119.756936)
				(end 429.344836 -119.756936)
			)
		)
		(stroke
			(width 0)
			(type solid)
		)
		(fill yes)
		(layer "In13.Cu")
		(net "GND")
	)
	(gr_poly
		(pts
			(arc
				(start 429.344836 -118.498112)
				(mid 429.05172 -118.498112)
				(end 429.344836 -118.498112)
			)
		)
		(stroke
			(width 0)
			(type solid)
		)
		(fill yes)
		(layer "In13.Cu")
		(net "GND")
	)
	(gr_poly
		(pts
			(arc
				(start 430.612804 -154.476958)
				(mid 430.319688 -154.476958)
				(end 430.612804 -154.476958)
			)
		)
		(stroke
			(width 0)
			(type solid)
		)
		(fill yes)
		(layer "In13.Cu")
		(net "GND")
	)
	(gr_poly
		(pts
			(arc
				(start 430.612804 -153.218134)
				(mid 430.319688 -153.218134)
				(end 430.612804 -153.218134)
			)
		)
		(stroke
			(width 0)
			(type solid)
		)
		(fill yes)
		(layer "In13.Cu")
		(net "GND")
	)
	(gr_poly
		(pts
			(arc
				(start 430.612804 -150.876762)
				(mid 430.319688 -150.876762)
				(end 430.612804 -150.876762)
			)
		)
		(stroke
			(width 0)
			(type solid)
		)
		(fill yes)
		(layer "In13.Cu")
		(net "GND")
	)
	(gr_poly
		(pts
			(arc
				(start 430.612804 -149.617938)
				(mid 430.319688 -149.617938)
				(end 430.612804 -149.617938)
			)
		)
		(stroke
			(width 0)
			(type solid)
		)
		(fill yes)
		(layer "In13.Cu")
		(net "GND")
	)
	(gr_poly
		(pts
			(arc
				(start 430.612804 -147.27682)
				(mid 430.319688 -147.27682)
				(end 430.612804 -147.27682)
			)
		)
		(stroke
			(width 0)
			(type solid)
		)
		(fill yes)
		(layer "In13.Cu")
		(net "GND")
	)
	(gr_poly
		(pts
			(arc
				(start 430.612804 -146.017996)
				(mid 430.319688 -146.017996)
				(end 430.612804 -146.017996)
			)
		)
		(stroke
			(width 0)
			(type solid)
		)
		(fill yes)
		(layer "In13.Cu")
		(net "GND")
	)
	(gr_poly
		(pts
			(arc
				(start 430.612804 -143.676878)
				(mid 430.319688 -143.676878)
				(end 430.612804 -143.676878)
			)
		)
		(stroke
			(width 0)
			(type solid)
		)
		(fill yes)
		(layer "In13.Cu")
		(net "GND")
	)
	(gr_poly
		(pts
			(arc
				(start 430.612804 -134.566914)
				(mid 430.319688 -134.566914)
				(end 430.612804 -134.566914)
			)
		)
		(stroke
			(width 0)
			(type solid)
		)
		(fill yes)
		(layer "In13.Cu")
		(net "GND")
	)
	(gr_poly
		(pts
			(arc
				(start 430.612804 -133.30809)
				(mid 430.319688 -133.30809)
				(end 430.612804 -133.30809)
			)
		)
		(stroke
			(width 0)
			(type solid)
		)
		(fill yes)
		(layer "In13.Cu")
		(net "GND")
	)
	(gr_poly
		(pts
			(arc
				(start 430.612804 -130.966718)
				(mid 430.319688 -130.966718)
				(end 430.612804 -130.966718)
			)
		)
		(stroke
			(width 0)
			(type solid)
		)
		(fill yes)
		(layer "In13.Cu")
		(net "GND")
	)
	(gr_poly
		(pts
			(arc
				(start 430.612804 -129.707894)
				(mid 430.319688 -129.707894)
				(end 430.612804 -129.707894)
			)
		)
		(stroke
			(width 0)
			(type solid)
		)
		(fill yes)
		(layer "In13.Cu")
		(net "GND")
	)
	(gr_poly
		(pts
			(arc
				(start 430.612804 -123.356878)
				(mid 430.319688 -123.356878)
				(end 430.612804 -123.356878)
			)
		)
		(stroke
			(width 0)
			(type solid)
		)
		(fill yes)
		(layer "In13.Cu")
		(net "GND")
	)
	(gr_poly
		(pts
			(arc
				(start 430.612804 -122.098054)
				(mid 430.319688 -122.098054)
				(end 430.612804 -122.098054)
			)
		)
		(stroke
			(width 0)
			(type solid)
		)
		(fill yes)
		(layer "In13.Cu")
		(net "GND")
	)
	(gr_poly
		(pts
			(arc
				(start 430.612804 -119.756936)
				(mid 430.319688 -119.756936)
				(end 430.612804 -119.756936)
			)
		)
		(stroke
			(width 0)
			(type solid)
		)
		(fill yes)
		(layer "In13.Cu")
		(net "GND")
	)
	(gr_poly
		(pts
			(arc
				(start 430.612804 -118.498112)
				(mid 430.319688 -118.498112)
				(end 430.612804 -118.498112)
			)
		)
		(stroke
			(width 0)
			(type solid)
		)
		(fill yes)
		(layer "In13.Cu")
		(net "GND")
	)
	(gr_poly
		(pts
			(arc
				(start 431.986944 -156.283406)
				(mid 431.693828 -156.283406)
				(end 431.986944 -156.283406)
			)
		)
		(stroke
			(width 0)
			(type solid)
		)
		(fill yes)
		(layer "In13.Cu")
		(net "GND")
	)
	(gr_poly
		(pts
			(arc
				(start 431.986944 -155.024582)
				(mid 431.693828 -155.024582)
				(end 431.986944 -155.024582)
			)
		)
		(stroke
			(width 0)
			(type solid)
		)
		(fill yes)
		(layer "In13.Cu")
		(net "GND")
	)
	(gr_poly
		(pts
			(arc
				(start 431.986944 -152.683464)
				(mid 431.693828 -152.683464)
				(end 431.986944 -152.683464)
			)
		)
		(stroke
			(width 0)
			(type solid)
		)
		(fill yes)
		(layer "In13.Cu")
		(net "GND")
	)
	(gr_poly
		(pts
			(arc
				(start 431.986944 -151.42464)
				(mid 431.693828 -151.42464)
				(end 431.986944 -151.42464)
			)
		)
		(stroke
			(width 0)
			(type solid)
		)
		(fill yes)
		(layer "In13.Cu")
		(net "GND")
	)
	(gr_poly
		(pts
			(arc
				(start 431.986944 -149.083522)
				(mid 431.693828 -149.083522)
				(end 431.986944 -149.083522)
			)
		)
		(stroke
			(width 0)
			(type solid)
		)
		(fill yes)
		(layer "In13.Cu")
		(net "GND")
	)
	(gr_poly
		(pts
			(arc
				(start 431.986944 -147.824698)
				(mid 431.693828 -147.824698)
				(end 431.986944 -147.824698)
			)
		)
		(stroke
			(width 0)
			(type solid)
		)
		(fill yes)
		(layer "In13.Cu")
		(net "GND")
	)
	(gr_poly
		(pts
			(arc
				(start 431.986944 -145.483326)
				(mid 431.693828 -145.483326)
				(end 431.986944 -145.483326)
			)
		)
		(stroke
			(width 0)
			(type solid)
		)
		(fill yes)
		(layer "In13.Cu")
		(net "GND")
	)
	(gr_poly
		(pts
			(arc
				(start 431.986944 -144.224502)
				(mid 431.693828 -144.224502)
				(end 431.986944 -144.224502)
			)
		)
		(stroke
			(width 0)
			(type solid)
		)
		(fill yes)
		(layer "In13.Cu")
		(net "GND")
	)
	(gr_poly
		(pts
			(arc
				(start 431.986944 -136.373362)
				(mid 431.693828 -136.373362)
				(end 431.986944 -136.373362)
			)
		)
		(stroke
			(width 0)
			(type solid)
		)
		(fill yes)
		(layer "In13.Cu")
		(net "GND")
	)
	(gr_poly
		(pts
			(arc
				(start 431.986944 -135.114538)
				(mid 431.693828 -135.114538)
				(end 431.986944 -135.114538)
			)
		)
		(stroke
			(width 0)
			(type solid)
		)
		(fill yes)
		(layer "In13.Cu")
		(net "GND")
	)
	(gr_poly
		(pts
			(arc
				(start 431.986944 -132.77342)
				(mid 431.693828 -132.77342)
				(end 431.986944 -132.77342)
			)
		)
		(stroke
			(width 0)
			(type solid)
		)
		(fill yes)
		(layer "In13.Cu")
		(net "GND")
	)
	(gr_poly
		(pts
			(arc
				(start 431.986944 -131.514596)
				(mid 431.693828 -131.514596)
				(end 431.986944 -131.514596)
			)
		)
		(stroke
			(width 0)
			(type solid)
		)
		(fill yes)
		(layer "In13.Cu")
		(net "GND")
	)
	(gr_poly
		(pts
			(arc
				(start 431.986944 -125.163326)
				(mid 431.693828 -125.163326)
				(end 431.986944 -125.163326)
			)
		)
		(stroke
			(width 0)
			(type solid)
		)
		(fill yes)
		(layer "In13.Cu")
		(net "GND")
	)
	(gr_poly
		(pts
			(arc
				(start 431.986944 -123.904502)
				(mid 431.693828 -123.904502)
				(end 431.986944 -123.904502)
			)
		)
		(stroke
			(width 0)
			(type solid)
		)
		(fill yes)
		(layer "In13.Cu")
		(net "GND")
	)
	(gr_poly
		(pts
			(arc
				(start 431.986944 -121.563384)
				(mid 431.693828 -121.563384)
				(end 431.986944 -121.563384)
			)
		)
		(stroke
			(width 0)
			(type solid)
		)
		(fill yes)
		(layer "In13.Cu")
		(net "GND")
	)
	(gr_poly
		(pts
			(arc
				(start 431.986944 -120.30456)
				(mid 431.693828 -120.30456)
				(end 431.986944 -120.30456)
			)
		)
		(stroke
			(width 0)
			(type solid)
		)
		(fill yes)
		(layer "In13.Cu")
		(net "GND")
	)
	(gr_poly
		(pts
			(arc
				(start 433.047394 -34.990024)
				(mid 432.754278 -34.990024)
				(end 433.047394 -34.990024)
			)
		)
		(stroke
			(width 0)
			(type solid)
		)
		(fill yes)
		(layer "In13.Cu")
		(net "GND")
	)
	(gr_poly
		(pts
			(arc
				(start 433.047394 -33.189926)
				(mid 432.754278 -33.189926)
				(end 433.047394 -33.189926)
			)
		)
		(stroke
			(width 0)
			(type solid)
		)
		(fill yes)
		(layer "In13.Cu")
		(net "GND")
	)
	(gr_poly
		(pts
			(arc
				(start 433.047394 -31.389828)
				(mid 432.754278 -31.389828)
				(end 433.047394 -31.389828)
			)
		)
		(stroke
			(width 0)
			(type solid)
		)
		(fill yes)
		(layer "In13.Cu")
		(net "GND")
	)
	(gr_poly
		(pts
			(arc
				(start 433.047394 -29.589984)
				(mid 432.754278 -29.589984)
				(end 433.047394 -29.589984)
			)
		)
		(stroke
			(width 0)
			(type solid)
		)
		(fill yes)
		(layer "In13.Cu")
		(net "GND")
	)
	(gr_poly
		(pts
			(arc
				(start 433.254912 -156.283406)
				(mid 432.961796 -156.283406)
				(end 433.254912 -156.283406)
			)
		)
		(stroke
			(width 0)
			(type solid)
		)
		(fill yes)
		(layer "In13.Cu")
		(net "GND")
	)
	(gr_poly
		(pts
			(arc
				(start 433.254912 -155.024582)
				(mid 432.961796 -155.024582)
				(end 433.254912 -155.024582)
			)
		)
		(stroke
			(width 0)
			(type solid)
		)
		(fill yes)
		(layer "In13.Cu")
		(net "GND")
	)
	(gr_poly
		(pts
			(arc
				(start 433.254912 -152.683464)
				(mid 432.961796 -152.683464)
				(end 433.254912 -152.683464)
			)
		)
		(stroke
			(width 0)
			(type solid)
		)
		(fill yes)
		(layer "In13.Cu")
		(net "GND")
	)
	(gr_poly
		(pts
			(arc
				(start 433.254912 -151.42464)
				(mid 432.961796 -151.42464)
				(end 433.254912 -151.42464)
			)
		)
		(stroke
			(width 0)
			(type solid)
		)
		(fill yes)
		(layer "In13.Cu")
		(net "GND")
	)
	(gr_poly
		(pts
			(arc
				(start 433.254912 -149.083522)
				(mid 432.961796 -149.083522)
				(end 433.254912 -149.083522)
			)
		)
		(stroke
			(width 0)
			(type solid)
		)
		(fill yes)
		(layer "In13.Cu")
		(net "GND")
	)
	(gr_poly
		(pts
			(arc
				(start 433.254912 -147.824698)
				(mid 432.961796 -147.824698)
				(end 433.254912 -147.824698)
			)
		)
		(stroke
			(width 0)
			(type solid)
		)
		(fill yes)
		(layer "In13.Cu")
		(net "GND")
	)
	(gr_poly
		(pts
			(arc
				(start 433.254912 -145.483326)
				(mid 432.961796 -145.483326)
				(end 433.254912 -145.483326)
			)
		)
		(stroke
			(width 0)
			(type solid)
		)
		(fill yes)
		(layer "In13.Cu")
		(net "GND")
	)
	(gr_poly
		(pts
			(arc
				(start 433.254912 -144.224502)
				(mid 432.961796 -144.224502)
				(end 433.254912 -144.224502)
			)
		)
		(stroke
			(width 0)
			(type solid)
		)
		(fill yes)
		(layer "In13.Cu")
		(net "GND")
	)
	(gr_poly
		(pts
			(arc
				(start 433.254912 -136.373362)
				(mid 432.961796 -136.373362)
				(end 433.254912 -136.373362)
			)
		)
		(stroke
			(width 0)
			(type solid)
		)
		(fill yes)
		(layer "In13.Cu")
		(net "GND")
	)
	(gr_poly
		(pts
			(arc
				(start 433.254912 -135.114538)
				(mid 432.961796 -135.114538)
				(end 433.254912 -135.114538)
			)
		)
		(stroke
			(width 0)
			(type solid)
		)
		(fill yes)
		(layer "In13.Cu")
		(net "GND")
	)
	(gr_poly
		(pts
			(arc
				(start 433.254912 -132.77342)
				(mid 432.961796 -132.77342)
				(end 433.254912 -132.77342)
			)
		)
		(stroke
			(width 0)
			(type solid)
		)
		(fill yes)
		(layer "In13.Cu")
		(net "GND")
	)
	(gr_poly
		(pts
			(arc
				(start 433.254912 -131.514596)
				(mid 432.961796 -131.514596)
				(end 433.254912 -131.514596)
			)
		)
		(stroke
			(width 0)
			(type solid)
		)
		(fill yes)
		(layer "In13.Cu")
		(net "GND")
	)
	(gr_poly
		(pts
			(arc
				(start 433.254912 -125.163326)
				(mid 432.961796 -125.163326)
				(end 433.254912 -125.163326)
			)
		)
		(stroke
			(width 0)
			(type solid)
		)
		(fill yes)
		(layer "In13.Cu")
		(net "GND")
	)
	(gr_poly
		(pts
			(arc
				(start 433.254912 -123.904502)
				(mid 432.961796 -123.904502)
				(end 433.254912 -123.904502)
			)
		)
		(stroke
			(width 0)
			(type solid)
		)
		(fill yes)
		(layer "In13.Cu")
		(net "GND")
	)
	(gr_poly
		(pts
			(arc
				(start 433.254912 -121.563384)
				(mid 432.961796 -121.563384)
				(end 433.254912 -121.563384)
			)
		)
		(stroke
			(width 0)
			(type solid)
		)
		(fill yes)
		(layer "In13.Cu")
		(net "GND")
	)
	(gr_poly
		(pts
			(arc
				(start 433.254912 -120.30456)
				(mid 432.961796 -120.30456)
				(end 433.254912 -120.30456)
			)
		)
		(stroke
			(width 0)
			(type solid)
		)
		(fill yes)
		(layer "In13.Cu")
		(net "GND")
	)
	(gr_poly
		(pts
			(arc
				(start 434.266594 -34.990024)
				(mid 433.973478 -34.990024)
				(end 434.266594 -34.990024)
			)
		)
		(stroke
			(width 0)
			(type solid)
		)
		(fill yes)
		(layer "In13.Cu")
		(net "GND")
	)
	(gr_poly
		(pts
			(arc
				(start 434.266594 -33.189926)
				(mid 433.973478 -33.189926)
				(end 434.266594 -33.189926)
			)
		)
		(stroke
			(width 0)
			(type solid)
		)
		(fill yes)
		(layer "In13.Cu")
		(net "GND")
	)
	(gr_poly
		(pts
			(arc
				(start 434.266594 -31.389828)
				(mid 433.973478 -31.389828)
				(end 434.266594 -31.389828)
			)
		)
		(stroke
			(width 0)
			(type solid)
		)
		(fill yes)
		(layer "In13.Cu")
		(net "GND")
	)
	(gr_poly
		(pts
			(arc
				(start 434.266594 -29.589984)
				(mid 433.973478 -29.589984)
				(end 434.266594 -29.589984)
			)
		)
		(stroke
			(width 0)
			(type solid)
		)
		(fill yes)
		(layer "In13.Cu")
		(net "GND")
	)
	(gr_poly
		(pts
			(arc
				(start 434.901594 -33.189926)
				(mid 434.608478 -33.189926)
				(end 434.901594 -33.189926)
			)
		)
		(stroke
			(width 0)
			(type solid)
		)
		(fill yes)
		(layer "In13.Cu")
		(net "GND")
	)
	(gr_poly
		(pts
			(arc
				(start 434.901594 -31.389828)
				(mid 434.608478 -31.389828)
				(end 434.901594 -31.389828)
			)
		)
		(stroke
			(width 0)
			(type solid)
		)
		(fill yes)
		(layer "In13.Cu")
		(net "GND")
	)
	(gr_poly
		(pts
			(arc
				(start 434.901594 -29.589984)
				(mid 434.608478 -29.589984)
				(end 434.901594 -29.589984)
			)
		)
		(stroke
			(width 0)
			(type solid)
		)
		(fill yes)
		(layer "In13.Cu")
		(net "GND")
	)
	(gr_poly
		(pts
			(arc
				(start 434.901594 -27.789886)
				(mid 434.608478 -27.789886)
				(end 434.901594 -27.789886)
			)
		)
		(stroke
			(width 0)
			(type solid)
		)
		(fill yes)
		(layer "In13.Cu")
		(net "GND")
	)
	(gr_poly
		(pts
			(arc
				(start 435.180994 -86.495382)
				(mid 434.887878 -86.495382)
				(end 435.180994 -86.495382)
			)
		)
		(stroke
			(width 0)
			(type solid)
		)
		(fill yes)
		(layer "In13.Cu")
		(net "GND")
	)
	(gr_poly
		(pts
			(arc
				(start 435.935628 -83.487514)
				(mid 435.642512 -83.487514)
				(end 435.935628 -83.487514)
			)
		)
		(stroke
			(width 0)
			(type solid)
		)
		(fill yes)
		(layer "In13.Cu")
		(net "GND")
	)
	(gr_poly
		(pts
			(arc
				(start 438.79516 -287.609026)
				(mid 438.502044 -287.609026)
				(end 438.79516 -287.609026)
			)
		)
		(stroke
			(width 0)
			(type solid)
		)
		(fill yes)
		(layer "In13.Cu")
		(net "GND")
	)
	(gr_poly
		(pts
			(arc
				(start 439.738008 -287.619694)
				(mid 439.444892 -287.619694)
				(end 439.738008 -287.619694)
			)
		)
		(stroke
			(width 0)
			(type solid)
		)
		(fill yes)
		(layer "In13.Cu")
		(net "GND")
	)
	(gr_poly
		(pts
			(arc
				(start 442.925454 -284.23997)
				(mid 442.632338 -284.23997)
				(end 442.925454 -284.23997)
			)
		)
		(stroke
			(width 0)
			(type solid)
		)
		(fill yes)
		(layer "In13.Cu")
		(net "GND")
	)
	(gr_poly
		(pts
			(arc
				(start 446.219326 -253.017528)
				(mid 445.92621 -253.017528)
				(end 446.219326 -253.017528)
			)
		)
		(stroke
			(width 0)
			(type solid)
		)
		(fill yes)
		(layer "In13.Cu")
		(net "GND")
	)
	(gr_poly
		(pts
			(arc
				(start 454.94194 -77.1525)
				(mid 454.648824 -77.1525)
				(end 454.94194 -77.1525)
			)
		)
		(stroke
			(width 0)
			(type solid)
		)
		(fill yes)
		(layer "In13.Cu")
		(net "GND")
	)
	(gr_poly
		(pts
			(arc
				(start 458.61478 -75.588114)
				(mid 458.321664 -75.588114)
				(end 458.61478 -75.588114)
			)
		)
		(stroke
			(width 0)
			(type solid)
		)
		(fill yes)
		(layer "In13.Cu")
		(net "GND")
	)
	(gr_poly
		(pts
			(arc
				(start 29.01696 -223.841564)
				(mid 28.692348 -223.841564)
				(end 29.01696 -223.841564)
			)
		)
		(stroke
			(width 0)
			(type solid)
		)
		(fill yes)
		(layer "In13.Cu")
		(net "GND")
	)
	(gr_poly
		(pts
			(arc
				(start 32.437324 -226.43973)
				(mid 32.112712 -226.43973)
				(end 32.437324 -226.43973)
			)
		)
		(stroke
			(width 0)
			(type solid)
		)
		(fill yes)
		(layer "In13.Cu")
		(net "GND")
	)
	(gr_poly
		(pts
			(arc
				(start 65.495932 -79.268574)
				(mid 65.174876 -79.268574)
				(end 65.495932 -79.268574)
			)
		)
		(stroke
			(width 0)
			(type solid)
		)
		(fill yes)
		(layer "In13.Cu")
		(net "GND")
	)
	(gr_poly
		(pts
			(arc
				(start 85.903562 -258.646676)
				(mid 85.57895 -258.646676)
				(end 85.903562 -258.646676)
			)
		)
		(stroke
			(width 0)
			(type solid)
		)
		(fill yes)
		(layer "In13.Cu")
		(net "GND")
	)
	(gr_poly
		(pts
			(arc
				(start 88.647778 -81.860136)
				(mid 88.326722 -81.860136)
				(end 88.647778 -81.860136)
			)
		)
		(stroke
			(width 0)
			(type solid)
		)
		(fill yes)
		(layer "In13.Cu")
		(net "GND")
	)
	(gr_poly
		(pts
			(arc
				(start 88.7984 -84.617052)
				(mid 88.477344 -84.617052)
				(end 88.7984 -84.617052)
			)
		)
		(stroke
			(width 0)
			(type solid)
		)
		(fill yes)
		(layer "In13.Cu")
		(net "GND")
	)
	(gr_poly
		(pts
			(arc
				(start 92.85351 -95.054928)
				(mid 92.532454 -95.054928)
				(end 92.85351 -95.054928)
			)
		)
		(stroke
			(width 0)
			(type solid)
		)
		(fill yes)
		(layer "In13.Cu")
		(net "GND")
	)
	(gr_poly
		(pts
			(arc
				(start 93.620082 -240.304828)
				(mid 93.29547 -240.304828)
				(end 93.620082 -240.304828)
			)
		)
		(stroke
			(width 0)
			(type solid)
		)
		(fill yes)
		(layer "In13.Cu")
		(net "GND")
	)
	(gr_poly
		(pts
			(arc
				(start 96.947736 -256.398776)
				(mid 96.623124 -256.398776)
				(end 96.947736 -256.398776)
			)
		)
		(stroke
			(width 0)
			(type solid)
		)
		(fill yes)
		(layer "In13.Cu")
		(net "GND")
	)
	(gr_poly
		(pts
			(arc
				(start 97.032064 -254.764032)
				(mid 96.707452 -254.764032)
				(end 97.032064 -254.764032)
			)
		)
		(stroke
			(width 0)
			(type solid)
		)
		(fill yes)
		(layer "In13.Cu")
		(net "GND")
	)
	(gr_poly
		(pts
			(arc
				(start 103.665528 -89.952068)
				(mid 103.340916 -89.952068)
				(end 103.665528 -89.952068)
			)
		)
		(stroke
			(width 0)
			(type solid)
		)
		(fill yes)
		(layer "In13.Cu")
		(net "GND")
	)
	(gr_poly
		(pts
			(arc
				(start 109.493812 -90.96121)
				(mid 109.1692 -90.96121)
				(end 109.493812 -90.96121)
			)
		)
		(stroke
			(width 0)
			(type solid)
		)
		(fill yes)
		(layer "In13.Cu")
		(net "GND")
	)
	(gr_poly
		(pts
			(arc
				(start 113.977674 -95.44558)
				(mid 113.653062 -95.44558)
				(end 113.977674 -95.44558)
			)
		)
		(stroke
			(width 0)
			(type solid)
		)
		(fill yes)
		(layer "In13.Cu")
		(net "GND")
	)
	(gr_poly
		(pts
			(arc
				(start 117.571774 -205.687168)
				(mid 117.247162 -205.687168)
				(end 117.571774 -205.687168)
			)
		)
		(stroke
			(width 0)
			(type solid)
		)
		(fill yes)
		(layer "In13.Cu")
		(net "GND")
	)
	(gr_poly
		(pts
			(arc
				(start 118.621556 -93.05671)
				(mid 118.296944 -93.05671)
				(end 118.621556 -93.05671)
			)
		)
		(stroke
			(width 0)
			(type solid)
		)
		(fill yes)
		(layer "In13.Cu")
		(net "GND")
	)
	(gr_poly
		(pts
			(arc
				(start 119.641112 -98.946462)
				(mid 119.3165 -98.946462)
				(end 119.641112 -98.946462)
			)
		)
		(stroke
			(width 0)
			(type solid)
		)
		(fill yes)
		(layer "In13.Cu")
		(net "GND")
	)
	(gr_poly
		(pts
			(arc
				(start 122.486928 -209.902298)
				(mid 122.162316 -209.902298)
				(end 122.486928 -209.902298)
			)
		)
		(stroke
			(width 0)
			(type solid)
		)
		(fill yes)
		(layer "In13.Cu")
		(net "GND")
	)
	(gr_poly
		(pts
			(arc
				(start 123.353576 -167.581834)
				(mid 123.028964 -167.581834)
				(end 123.353576 -167.581834)
			)
		)
		(stroke
			(width 0)
			(type solid)
		)
		(fill yes)
		(layer "In13.Cu")
		(net "GND")
	)
	(gr_poly
		(pts
			(arc
				(start 123.561602 -208.225898)
				(mid 123.23699 -208.225898)
				(end 123.561602 -208.225898)
			)
		)
		(stroke
			(width 0)
			(type solid)
		)
		(fill yes)
		(layer "In13.Cu")
		(net "GND")
	)
	(gr_poly
		(pts
			(arc
				(start 124.991368 -211.974684)
				(mid 124.666756 -211.974684)
				(end 124.991368 -211.974684)
			)
		)
		(stroke
			(width 0)
			(type solid)
		)
		(fill yes)
		(layer "In13.Cu")
		(net "GND")
	)
	(gr_poly
		(pts
			(arc
				(start 125.042676 -210.609942)
				(mid 124.718064 -210.609942)
				(end 125.042676 -210.609942)
			)
		)
		(stroke
			(width 0)
			(type solid)
		)
		(fill yes)
		(layer "In13.Cu")
		(net "GND")
	)
	(gr_poly
		(pts
			(arc
				(start 125.333252 -215.007952)
				(mid 125.00864 -215.007952)
				(end 125.333252 -215.007952)
			)
		)
		(stroke
			(width 0)
			(type solid)
		)
		(fill yes)
		(layer "In13.Cu")
		(net "GND")
	)
	(gr_poly
		(pts
			(arc
				(start 127.070866 -218.830652)
				(mid 126.746254 -218.830652)
				(end 127.070866 -218.830652)
			)
		)
		(stroke
			(width 0)
			(type solid)
		)
		(fill yes)
		(layer "In13.Cu")
		(net "GND")
	)
	(gr_poly
		(pts
			(arc
				(start 128.26492 -206.25816)
				(mid 127.940308 -206.25816)
				(end 128.26492 -206.25816)
			)
		)
		(stroke
			(width 0)
			(type solid)
		)
		(fill yes)
		(layer "In13.Cu")
		(net "GND")
	)
	(gr_poly
		(pts
			(arc
				(start 128.74879 -209.471006)
				(mid 128.424178 -209.471006)
				(end 128.74879 -209.471006)
			)
		)
		(stroke
			(width 0)
			(type solid)
		)
		(fill yes)
		(layer "In13.Cu")
		(net "GND")
	)
	(gr_poly
		(pts
			(arc
				(start 129.206752 -222.958406)
				(mid 128.88214 -222.958406)
				(end 129.206752 -222.958406)
			)
		)
		(stroke
			(width 0)
			(type solid)
		)
		(fill yes)
		(layer "In13.Cu")
		(net "GND")
	)
	(gr_poly
		(pts
			(arc
				(start 129.227326 -200.021952)
				(mid 128.902714 -200.021952)
				(end 129.227326 -200.021952)
			)
		)
		(stroke
			(width 0)
			(type solid)
		)
		(fill yes)
		(layer "In13.Cu")
		(net "GND")
	)
	(gr_poly
		(pts
			(arc
				(start 129.464308 -198.848218)
				(mid 129.139696 -198.848218)
				(end 129.464308 -198.848218)
			)
		)
		(stroke
			(width 0)
			(type solid)
		)
		(fill yes)
		(layer "In13.Cu")
		(net "GND")
	)
	(gr_poly
		(pts
			(arc
				(start 129.557018 -225.65106)
				(mid 129.232406 -225.65106)
				(end 129.557018 -225.65106)
			)
		)
		(stroke
			(width 0)
			(type solid)
		)
		(fill yes)
		(layer "In13.Cu")
		(net "GND")
	)
	(gr_poly
		(pts
			(arc
				(start 129.962656 -231.506522)
				(mid 129.638044 -231.506522)
				(end 129.962656 -231.506522)
			)
		)
		(stroke
			(width 0)
			(type solid)
		)
		(fill yes)
		(layer "In13.Cu")
		(net "GND")
	)
	(gr_poly
		(pts
			(arc
				(start 133.424168 -163.47313)
				(mid 133.099556 -163.47313)
				(end 133.424168 -163.47313)
			)
		)
		(stroke
			(width 0)
			(type solid)
		)
		(fill yes)
		(layer "In13.Cu")
		(net "GND")
	)
	(gr_poly
		(pts
			(arc
				(start 134.206488 -215.144604)
				(mid 133.881876 -215.144604)
				(end 134.206488 -215.144604)
			)
		)
		(stroke
			(width 0)
			(type solid)
		)
		(fill yes)
		(layer "In13.Cu")
		(net "GND")
	)
	(gr_poly
		(pts
			(arc
				(start 137.527284 -207.405224)
				(mid 137.202672 -207.405224)
				(end 137.527284 -207.405224)
			)
		)
		(stroke
			(width 0)
			(type solid)
		)
		(fill yes)
		(layer "In13.Cu")
		(net "GND")
	)
	(gr_poly
		(pts
			(arc
				(start 138.628882 -230.89235)
				(mid 138.30427 -230.89235)
				(end 138.628882 -230.89235)
			)
		)
		(stroke
			(width 0)
			(type solid)
		)
		(fill yes)
		(layer "In13.Cu")
		(net "GND")
	)
	(gr_poly
		(pts
			(arc
				(start 139.472162 -209.081624)
				(mid 139.14755 -209.081624)
				(end 139.472162 -209.081624)
			)
		)
		(stroke
			(width 0)
			(type solid)
		)
		(fill yes)
		(layer "In13.Cu")
		(net "GND")
	)
	(gr_poly
		(pts
			(arc
				(start 139.931902 -167.303704)
				(mid 139.60729 -167.303704)
				(end 139.931902 -167.303704)
			)
		)
		(stroke
			(width 0)
			(type solid)
		)
		(fill yes)
		(layer "In13.Cu")
		(net "GND")
	)
	(gr_poly
		(pts
			(arc
				(start 140.84554 -206.069692)
				(mid 140.520928 -206.069692)
				(end 140.84554 -206.069692)
			)
		)
		(stroke
			(width 0)
			(type solid)
		)
		(fill yes)
		(layer "In13.Cu")
		(net "GND")
	)
	(gr_poly
		(pts
			(arc
				(start 142.307056 -187.860686)
				(mid 141.982444 -187.860686)
				(end 142.307056 -187.860686)
			)
		)
		(stroke
			(width 0)
			(type solid)
		)
		(fill yes)
		(layer "In13.Cu")
		(net "GND")
	)
	(gr_poly
		(pts
			(arc
				(start 142.609062 -228.859588)
				(mid 142.28445 -228.859588)
				(end 142.609062 -228.859588)
			)
		)
		(stroke
			(width 0)
			(type solid)
		)
		(fill yes)
		(layer "In13.Cu")
		(net "GND")
	)
	(gr_poly
		(pts
			(arc
				(start 142.75816 -206.055468)
				(mid 142.433548 -206.055468)
				(end 142.75816 -206.055468)
			)
		)
		(stroke
			(width 0)
			(type solid)
		)
		(fill yes)
		(layer "In13.Cu")
		(net "GND")
	)
	(gr_poly
		(pts
			(arc
				(start 142.88135 -184.947052)
				(mid 142.556738 -184.947052)
				(end 142.88135 -184.947052)
			)
		)
		(stroke
			(width 0)
			(type solid)
		)
		(fill yes)
		(layer "In13.Cu")
		(net "GND")
	)
	(gr_poly
		(pts
			(arc
				(start 143.48841 -197.282054)
				(mid 143.163798 -197.282054)
				(end 143.48841 -197.282054)
			)
		)
		(stroke
			(width 0)
			(type solid)
		)
		(fill yes)
		(layer "In13.Cu")
		(net "GND")
	)
	(gr_poly
		(pts
			(arc
				(start 144.73555 -199.982328)
				(mid 144.410938 -199.982328)
				(end 144.73555 -199.982328)
			)
		)
		(stroke
			(width 0)
			(type solid)
		)
		(fill yes)
		(layer "In13.Cu")
		(net "GND")
	)
	(gr_poly
		(pts
			(arc
				(start 144.834864 -225.275902)
				(mid 144.510252 -225.275902)
				(end 144.834864 -225.275902)
			)
		)
		(stroke
			(width 0)
			(type solid)
		)
		(fill yes)
		(layer "In13.Cu")
		(net "GND")
	)
	(gr_poly
		(pts
			(arc
				(start 145.118836 -194.831208)
				(mid 144.794224 -194.831208)
				(end 145.118836 -194.831208)
			)
		)
		(stroke
			(width 0)
			(type solid)
		)
		(fill yes)
		(layer "In13.Cu")
		(net "GND")
	)
	(gr_poly
		(pts
			(arc
				(start 145.908776 -184.988454)
				(mid 145.584164 -184.988454)
				(end 145.908776 -184.988454)
			)
		)
		(stroke
			(width 0)
			(type solid)
		)
		(fill yes)
		(layer "In13.Cu")
		(net "GND")
	)
	(gr_poly
		(pts
			(arc
				(start 147.420838 -207.709262)
				(mid 147.096226 -207.709262)
				(end 147.420838 -207.709262)
			)
		)
		(stroke
			(width 0)
			(type solid)
		)
		(fill yes)
		(layer "In13.Cu")
		(net "GND")
	)
	(gr_poly
		(pts
			(arc
				(start 148.656802 -198.5899)
				(mid 148.33219 -198.5899)
				(end 148.656802 -198.5899)
			)
		)
		(stroke
			(width 0)
			(type solid)
		)
		(fill yes)
		(layer "In13.Cu")
		(net "GND")
	)
	(gr_poly
		(pts
			(arc
				(start 150.590758 -223.675448)
				(mid 150.266146 -223.675448)
				(end 150.590758 -223.675448)
			)
		)
		(stroke
			(width 0)
			(type solid)
		)
		(fill yes)
		(layer "In13.Cu")
		(net "GND")
	)
	(gr_poly
		(pts
			(arc
				(start 181.305454 -110.361222)
				(mid 180.980842 -110.361222)
				(end 181.305454 -110.361222)
			)
		)
		(stroke
			(width 0)
			(type solid)
		)
		(fill yes)
		(layer "In13.Cu")
		(net "GND")
	)
	(gr_poly
		(pts
			(arc
				(start 186.75223 -96.408748)
				(mid 186.427618 -96.408748)
				(end 186.75223 -96.408748)
			)
		)
		(stroke
			(width 0)
			(type solid)
		)
		(fill yes)
		(layer "In13.Cu")
		(net "GND")
	)
	(gr_poly
		(pts
			(arc
				(start 187.793884 -250.939808)
				(mid 187.469272 -250.939808)
				(end 187.793884 -250.939808)
			)
		)
		(stroke
			(width 0)
			(type solid)
		)
		(fill yes)
		(layer "In13.Cu")
		(net "GND")
	)
	(gr_poly
		(pts
			(arc
				(start 189.563248 -255.780286)
				(mid 189.238636 -255.780286)
				(end 189.563248 -255.780286)
			)
		)
		(stroke
			(width 0)
			(type solid)
		)
		(fill yes)
		(layer "In13.Cu")
		(net "GND")
	)
	(gr_poly
		(pts
			(arc
				(start 191.25692 -103.415592)
				(mid 190.932308 -103.415592)
				(end 191.25692 -103.415592)
			)
		)
		(stroke
			(width 0)
			(type solid)
		)
		(fill yes)
		(layer "In13.Cu")
		(net "GND")
	)
	(gr_poly
		(pts
			(arc
				(start 192.389506 -102.571296)
				(mid 192.064894 -102.571296)
				(end 192.389506 -102.571296)
			)
		)
		(stroke
			(width 0)
			(type solid)
		)
		(fill yes)
		(layer "In13.Cu")
		(net "GND")
	)
	(gr_poly
		(pts
			(arc
				(start 192.703958 -96.810322)
				(mid 192.379346 -96.810322)
				(end 192.703958 -96.810322)
			)
		)
		(stroke
			(width 0)
			(type solid)
		)
		(fill yes)
		(layer "In13.Cu")
		(net "GND")
	)
	(gr_poly
		(pts
			(arc
				(start 192.79108 -100.429314)
				(mid 192.466468 -100.429314)
				(end 192.79108 -100.429314)
			)
		)
		(stroke
			(width 0)
			(type solid)
		)
		(fill yes)
		(layer "In13.Cu")
		(net "GND")
	)
	(gr_poly
		(pts
			(arc
				(start 206.5782 -205.748128)
				(mid 206.253588 -205.748128)
				(end 206.5782 -205.748128)
			)
		)
		(stroke
			(width 0)
			(type solid)
		)
		(fill yes)
		(layer "In13.Cu")
		(net "GND")
	)
	(gr_poly
		(pts
			(arc
				(start 208.022444 -238.66094)
				(mid 207.697832 -238.66094)
				(end 208.022444 -238.66094)
			)
		)
		(stroke
			(width 0)
			(type solid)
		)
		(fill yes)
		(layer "In13.Cu")
		(net "GND")
	)
	(gr_poly
		(pts
			(arc
				(start 215.830658 -241.574574)
				(mid 215.506046 -241.574574)
				(end 215.830658 -241.574574)
			)
		)
		(stroke
			(width 0)
			(type solid)
		)
		(fill yes)
		(layer "In13.Cu")
		(net "GND")
	)
	(gr_poly
		(pts
			(arc
				(start 220.430852 -241.140488)
				(mid 220.10624 -241.140488)
				(end 220.430852 -241.140488)
			)
		)
		(stroke
			(width 0)
			(type solid)
		)
		(fill yes)
		(layer "In13.Cu")
		(net "GND")
	)
	(gr_poly
		(pts
			(arc
				(start 220.864938 -237.14456)
				(mid 220.540326 -237.14456)
				(end 220.864938 -237.14456)
			)
		)
		(stroke
			(width 0)
			(type solid)
		)
		(fill yes)
		(layer "In13.Cu")
		(net "GND")
	)
	(gr_poly
		(pts
			(arc
				(start 225.844862 -202.590908)
				(mid 225.52025 -202.590908)
				(end 225.844862 -202.590908)
			)
		)
		(stroke
			(width 0)
			(type solid)
		)
		(fill yes)
		(layer "In13.Cu")
		(net "GND")
	)
	(gr_poly
		(pts
			(arc
				(start 225.852736 -199.524112)
				(mid 225.528124 -199.524112)
				(end 225.852736 -199.524112)
			)
		)
		(stroke
			(width 0)
			(type solid)
		)
		(fill yes)
		(layer "In13.Cu")
		(net "GND")
	)
	(gr_poly
		(pts
			(arc
				(start 231.493568 -181.829456)
				(mid 231.168956 -181.829456)
				(end 231.493568 -181.829456)
			)
		)
		(stroke
			(width 0)
			(type solid)
		)
		(fill yes)
		(layer "In13.Cu")
		(net "GND")
	)
	(gr_poly
		(pts
			(arc
				(start 231.646476 -240.006886)
				(mid 231.321864 -240.006886)
				(end 231.646476 -240.006886)
			)
		)
		(stroke
			(width 0)
			(type solid)
		)
		(fill yes)
		(layer "In13.Cu")
		(net "GND")
	)
	(gr_poly
		(pts
			(arc
				(start 233.15295 -172.62475)
				(mid 232.828338 -172.62475)
				(end 233.15295 -172.62475)
			)
		)
		(stroke
			(width 0)
			(type solid)
		)
		(fill yes)
		(layer "In13.Cu")
		(net "GND")
	)
	(gr_poly
		(pts
			(arc
				(start 234.982004 -241.615976)
				(mid 234.657392 -241.615976)
				(end 234.982004 -241.615976)
			)
		)
		(stroke
			(width 0)
			(type solid)
		)
		(fill yes)
		(layer "In13.Cu")
		(net "GND")
	)
	(gr_poly
		(pts
			(arc
				(start 241.765836 -184.69991)
				(mid 241.441224 -184.69991)
				(end 241.765836 -184.69991)
			)
		)
		(stroke
			(width 0)
			(type solid)
		)
		(fill yes)
		(layer "In13.Cu")
		(net "GND")
	)
	(gr_poly
		(pts
			(arc
				(start 242.14328 -186.755024)
				(mid 241.818668 -186.755024)
				(end 242.14328 -186.755024)
			)
		)
		(stroke
			(width 0)
			(type solid)
		)
		(fill yes)
		(layer "In13.Cu")
		(net "GND")
	)
	(gr_poly
		(pts
			(arc
				(start 242.75415 -198.068692)
				(mid 242.429538 -198.068692)
				(end 242.75415 -198.068692)
			)
		)
		(stroke
			(width 0)
			(type solid)
		)
		(fill yes)
		(layer "In13.Cu")
		(net "GND")
	)
	(gr_poly
		(pts
			(arc
				(start 242.99926 -201.659998)
				(mid 242.674648 -201.659998)
				(end 242.99926 -201.659998)
			)
		)
		(stroke
			(width 0)
			(type solid)
		)
		(fill yes)
		(layer "In13.Cu")
		(net "GND")
	)
	(gr_poly
		(pts
			(arc
				(start 243.068348 -190.096648)
				(mid 242.743736 -190.096648)
				(end 243.068348 -190.096648)
			)
		)
		(stroke
			(width 0)
			(type solid)
		)
		(fill yes)
		(layer "In13.Cu")
		(net "GND")
	)
	(gr_poly
		(pts
			(arc
				(start 243.360702 -194.164204)
				(mid 243.03609 -194.164204)
				(end 243.360702 -194.164204)
			)
		)
		(stroke
			(width 0)
			(type solid)
		)
		(fill yes)
		(layer "In13.Cu")
		(net "GND")
	)
	(gr_poly
		(pts
			(arc
				(start 246.115332 -209.852514)
				(mid 245.79072 -209.852514)
				(end 246.115332 -209.852514)
			)
		)
		(stroke
			(width 0)
			(type solid)
		)
		(fill yes)
		(layer "In13.Cu")
		(net "GND")
	)
	(gr_poly
		(pts
			(arc
				(start 248.047256 -217.114882)
				(mid 247.722644 -217.114882)
				(end 248.047256 -217.114882)
			)
		)
		(stroke
			(width 0)
			(type solid)
		)
		(fill yes)
		(layer "In13.Cu")
		(net "GND")
	)
	(gr_poly
		(pts
			(arc
				(start 248.260362 -199.787002)
				(mid 247.93575 -199.787002)
				(end 248.260362 -199.787002)
			)
		)
		(stroke
			(width 0)
			(type solid)
		)
		(fill yes)
		(layer "In13.Cu")
		(net "GND")
	)
	(gr_poly
		(pts
			(arc
				(start 248.375678 -203.753212)
				(mid 248.051066 -203.753212)
				(end 248.375678 -203.753212)
			)
		)
		(stroke
			(width 0)
			(type solid)
		)
		(fill yes)
		(layer "In13.Cu")
		(net "GND")
	)
	(gr_poly
		(pts
			(arc
				(start 250.176284 -190.101728)
				(mid 249.851672 -190.101728)
				(end 250.176284 -190.101728)
			)
		)
		(stroke
			(width 0)
			(type solid)
		)
		(fill yes)
		(layer "In13.Cu")
		(net "GND")
	)
	(gr_poly
		(pts
			(arc
				(start 250.324874 -220.65488)
				(mid 250.000262 -220.65488)
				(end 250.324874 -220.65488)
			)
		)
		(stroke
			(width 0)
			(type solid)
		)
		(fill yes)
		(layer "In13.Cu")
		(net "GND")
	)
	(gr_poly
		(pts
			(arc
				(start 251.060966 -227.735384)
				(mid 250.736354 -227.735384)
				(end 251.060966 -227.735384)
			)
		)
		(stroke
			(width 0)
			(type solid)
		)
		(fill yes)
		(layer "In13.Cu")
		(net "GND")
	)
	(gr_poly
		(pts
			(arc
				(start 251.2314 -257.515614)
				(mid 250.906788 -257.515614)
				(end 251.2314 -257.515614)
			)
		)
		(stroke
			(width 0)
			(type solid)
		)
		(fill yes)
		(layer "In13.Cu")
		(net "GND")
	)
	(gr_poly
		(pts
			(arc
				(start 252.926088 -225.679762)
				(mid 252.601476 -225.679762)
				(end 252.926088 -225.679762)
			)
		)
		(stroke
			(width 0)
			(type solid)
		)
		(fill yes)
		(layer "In13.Cu")
		(net "GND")
	)
	(gr_poly
		(pts
			(arc
				(start 254.882142 -197.458076)
				(mid 254.55753 -197.458076)
				(end 254.882142 -197.458076)
			)
		)
		(stroke
			(width 0)
			(type solid)
		)
		(fill yes)
		(layer "In13.Cu")
		(net "GND")
	)
	(gr_poly
		(pts
			(arc
				(start 255.061212 -193.708528)
				(mid 254.7366 -193.708528)
				(end 255.061212 -193.708528)
			)
		)
		(stroke
			(width 0)
			(type solid)
		)
		(fill yes)
		(layer "In13.Cu")
		(net "GND")
	)
	(gr_poly
		(pts
			(arc
				(start 256.281174 -193.48069)
				(mid 255.956562 -193.48069)
				(end 256.281174 -193.48069)
			)
		)
		(stroke
			(width 0)
			(type solid)
		)
		(fill yes)
		(layer "In13.Cu")
		(net "GND")
	)
	(gr_poly
		(pts
			(arc
				(start 258.176522 -193.155316)
				(mid 257.85191 -193.155316)
				(end 258.176522 -193.155316)
			)
		)
		(stroke
			(width 0)
			(type solid)
		)
		(fill yes)
		(layer "In13.Cu")
		(net "GND")
	)
	(gr_poly
		(pts
			(arc
				(start 260.789166 -195.819522)
				(mid 260.464554 -195.819522)
				(end 260.789166 -195.819522)
			)
		)
		(stroke
			(width 0)
			(type solid)
		)
		(fill yes)
		(layer "In13.Cu")
		(net "GND")
	)
	(gr_poly
		(pts
			(arc
				(start 264.01649 -193.871088)
				(mid 263.691878 -193.871088)
				(end 264.01649 -193.871088)
			)
		)
		(stroke
			(width 0)
			(type solid)
		)
		(fill yes)
		(layer "In13.Cu")
		(net "GND")
	)
	(gr_poly
		(pts
			(arc
				(start 265.148314 -229.235254)
				(mid 264.823702 -229.235254)
				(end 265.148314 -229.235254)
			)
		)
		(stroke
			(width 0)
			(type solid)
		)
		(fill yes)
		(layer "In13.Cu")
		(net "GND")
	)
	(gr_poly
		(pts
			(arc
				(start 265.366754 -197.82409)
				(mid 265.042142 -197.82409)
				(end 265.366754 -197.82409)
			)
		)
		(stroke
			(width 0)
			(type solid)
		)
		(fill yes)
		(layer "In13.Cu")
		(net "GND")
	)
	(gr_poly
		(pts
			(arc
				(start 304.707544 -200.81494)
				(mid 304.382932 -200.81494)
				(end 304.707544 -200.81494)
			)
		)
		(stroke
			(width 0)
			(type solid)
		)
		(fill yes)
		(layer "In13.Cu")
		(net "GND")
	)
	(gr_poly
		(pts
			(arc
				(start 221.818708 -366.35817)
				(mid 221.838231 -366.354269)
				(end 221.854776 -366.343184)
			)
			(arc
				(start 221.967044 -366.230916)
				(mid 221.978155 -366.214382)
				(end 221.98203 -366.194848)
			)
			(arc
				(start 221.98203 -362.193332)
				(mid 221.978129 -362.173809)
				(end 221.967044 -362.157264)
			)
			(arc
				(start 221.870778 -362.060998)
				(mid 221.854244 -362.049887)
				(end 221.83471 -362.046012)
			)
			(arc
				(start 217.824812 -362.046012)
				(mid 217.805289 -362.049913)
				(end 217.788744 -362.060998)
			)
			(arc
				(start 217.684858 -362.164884)
				(mid 217.673747 -362.181418)
				(end 217.669872 -362.200952)
			)
			(arc
				(start 217.669872 -366.210596)
				(mid 217.673773 -366.230119)
				(end 217.684858 -366.246664)
			)
			(arc
				(start 217.781378 -366.343184)
				(mid 217.797912 -366.354295)
				(end 217.817446 -366.35817)
			)
		)
		(stroke
			(width 0)
			(type solid)
		)
		(fill yes)
		(layer "In13.Cu")
		(net "P12V_AUX")
	)
	(gr_poly
		(pts
			(arc
				(start 232.437178 -366.389412)
				(mid 232.456701 -366.385511)
				(end 232.473246 -366.374426)
			)
			(arc
				(start 232.664 -366.183672)
				(mid 232.675111 -366.167138)
				(end 232.678986 -366.147604)
			)
			(arc
				(start 232.678986 -362.185458)
				(mid 232.675085 -362.165935)
				(end 232.664 -362.14939)
			)
			(arc
				(start 232.504742 -361.990132)
				(mid 232.488208 -361.979021)
				(end 232.468674 -361.975146)
			)
			(arc
				(start 228.577394 -361.975146)
				(mid 228.557871 -361.979047)
				(end 228.541326 -361.990132)
			)
			(arc
				(start 228.350572 -362.180886)
				(mid 228.339461 -362.19742)
				(end 228.335586 -362.216954)
			)
			(arc
				(start 228.335586 -366.218724)
				(mid 228.339487 -366.238247)
				(end 228.350572 -366.254792)
			)
			(arc
				(start 228.470206 -366.374426)
				(mid 228.48674 -366.385537)
				(end 228.506274 -366.389412)
			)
		)
		(stroke
			(width 0)
			(type solid)
		)
		(fill yes)
		(layer "In13.Cu")
		(net "P12V_AUX")
	)
	(gr_poly
		(pts
			(arc
				(start 252.431042 -397.963136)
				(mid 252.450565 -397.959235)
				(end 252.46711 -397.94815)
			)
			(arc
				(start 252.932438 -397.482822)
				(mid 252.943549 -397.466288)
				(end 252.947424 -397.446754)
			)
			(arc
				(start 252.947424 -392.961114)
				(mid 252.943523 -392.941591)
				(end 252.932438 -392.925046)
			)
			(arc
				(start 252.451362 -392.44397)
				(mid 252.434828 -392.432859)
				(end 252.415294 -392.428984)
			)
			(arc
				(start 245.184422 -392.428984)
				(mid 245.164899 -392.432885)
				(end 245.148354 -392.44397)
			)
			(arc
				(start 244.746526 -392.845798)
				(mid 244.735415 -392.862332)
				(end 244.73154 -392.881866)
			)
			(arc
				(start 244.73154 -397.594328)
				(mid 244.735441 -397.613851)
				(end 244.746526 -397.630396)
			)
			(arc
				(start 245.06428 -397.94815)
				(mid 245.080814 -397.959261)
				(end 245.100348 -397.963136)
			)
		)
		(stroke
			(width 0)
			(type solid)
		)
		(fill yes)
		(layer "In13.Cu")
		(net "P12V_STBY_FUSE")
	)
	(gr_poly
		(pts
			(arc
				(start 241.82197 -376.463306)
				(mid 241.841493 -376.459405)
				(end 241.858038 -376.44832)
			)
			(arc
				(start 242.310666 -375.995692)
				(mid 242.321777 -375.979158)
				(end 242.325652 -375.959624)
			)
			(arc
				(start 242.325652 -368.584988)
				(mid 242.321751 -368.565465)
				(end 242.310666 -368.54892)
			)
			(arc
				(start 242.213638 -368.451892)
				(mid 242.197104 -368.440781)
				(end 242.17757 -368.436906)
			)
			(xy 236.966252 -368.436906) (xy 236.959648 -368.44351)
			(arc
				(start 236.44987 -368.44351)
				(mid 236.430347 -368.447411)
				(end 236.413802 -368.458496)
			)
			(arc
				(start 236.101128 -368.77117)
				(mid 236.090017 -368.787704)
				(end 236.086142 -368.807238)
			)
			(arc
				(start 236.086142 -376.096022)
				(mid 236.090043 -376.115545)
				(end 236.101128 -376.13209)
			)
			(arc
				(start 236.417358 -376.44832)
				(mid 236.433892 -376.459431)
				(end 236.453426 -376.463306)
			)
		)
		(stroke
			(width 0)
			(type solid)
		)
		(fill yes)
		(layer "In13.Cu")
		(net "P12V_STBY_R1")
	)
	(gr_poly
		(pts
			(arc
				(start 309.290212 -65.573656)
				(mid 309.322438 -65.562126)
				(end 309.339996 -65.532762)
			)
			(xy 309.343552 -65.514728) (xy 309.326534 -65.482724)
			(arc
				(start 307.815234 -64.856868)
				(mid 307.805655 -64.853884)
				(end 307.795676 -64.852804)
			)
			(arc
				(start 305.161188 -64.852804)
				(mid 305.137888 -64.858594)
				(end 305.119786 -64.874394)
			)
			(xy 305.087274 -64.920368)
			(arc
				(start 305.080924 -64.929258)
				(mid 305.073052 -64.947229)
				(end 305.072542 -64.96685)
			)
			(xy 305.073304 -64.971168) (xy 305.074574 -64.974978) (xy 305.074574 -64.975232)
			(arc
				(start 305.075844 -64.979042)
				(mid 305.089143 -65.029551)
				(end 305.095402 -65.081404)
			)
			(xy 305.095402 -65.081658) (xy 305.09591 -65.09639)
			(arc
				(start 305.09591 -65.101724)
				(mid 305.059779 -65.263023)
				(end 304.95875 -65.393824)
			)
			(xy 304.946558 -65.404238) (xy 304.938176 -65.435226)
			(arc
				(start 304.976022 -65.540128)
				(mid 304.994606 -65.564423)
				(end 305.023774 -65.573656)
			)
		)
		(stroke
			(width 0)
			(type solid)
		)
		(fill yes)
		(layer "In13.Cu")
		(net "GND")
	)
	(gr_poly
		(pts
			(arc
				(start 208.875122 -366.381792)
				(mid 208.894645 -366.377891)
				(end 208.91119 -366.366806)
			)
			(arc
				(start 209.031078 -366.246918)
				(mid 209.042189 -366.230384)
				(end 209.046064 -366.21085)
			)
			(arc
				(start 209.046064 -365.054896)
				(mid 209.049965 -365.035373)
				(end 209.06105 -365.018828)
			)
			(arc
				(start 209.196686 -364.883192)
				(mid 209.21322 -364.872081)
				(end 209.232754 -364.868206)
			)
			(arc
				(start 210.475322 -364.868206)
				(mid 210.494845 -364.864305)
				(end 210.51139 -364.85322)
			)
			(arc
				(start 211.301076 -364.063534)
				(mid 211.312187 -364.047)
				(end 211.316062 -364.027466)
			)
			(arc
				(start 211.316062 -363.147102)
				(mid 211.312161 -363.127579)
				(end 211.301076 -363.111034)
			)
			(arc
				(start 210.519264 -362.329222)
				(mid 210.50273 -362.318111)
				(end 210.483196 -362.314236)
			)
			(arc
				(start 208.546446 -362.314236)
				(mid 208.526923 -362.318137)
				(end 208.510378 -362.329222)
			)
			(arc
				(start 207.176624 -363.662976)
				(mid 207.16009 -363.674087)
				(end 207.140556 -363.677962)
			)
			(arc
				(start 205.653386 -363.677962)
				(mid 205.633863 -363.681863)
				(end 205.617318 -363.692948)
			)
			(arc
				(start 205.497684 -363.812582)
				(mid 205.486573 -363.829116)
				(end 205.482698 -363.84865)
			)
			(arc
				(start 205.482698 -366.230408)
				(mid 205.486599 -366.249931)
				(end 205.497684 -366.266476)
			)
			(arc
				(start 205.598014 -366.366806)
				(mid 205.614548 -366.377917)
				(end 205.634082 -366.381792)
			)
		)
		(stroke
			(width 0)
			(type solid)
		)
		(fill yes)
		(layer "In13.Cu")
		(net "P12V_AUX")
	)
	(gr_poly
		(pts
			(arc
				(start 132.2832 -179.03444)
				(mid 132.325377 -179.027631)
				(end 132.368036 -179.025296)
			)
			(arc
				(start 132.368036 -179.025296)
				(mid 132.410693 -179.027645)
				(end 132.452872 -179.03444)
			)
			(xy 132.457952 -179.035456)
			(arc
				(start 133.987286 -179.035456)
				(mid 134.006809 -179.031555)
				(end 134.023354 -179.02047)
			)
			(arc
				(start 134.097268 -178.946556)
				(mid 134.108379 -178.930022)
				(end 134.112254 -178.910488)
			)
			(arc
				(start 134.112254 -176.398428)
				(mid 134.108353 -176.378905)
				(end 134.097268 -176.36236)
			)
			(arc
				(start 134.003796 -176.268888)
				(mid 133.987262 -176.257777)
				(end 133.967728 -176.253902)
			)
			(arc
				(start 131.460748 -176.253902)
				(mid 131.441225 -176.257803)
				(end 131.42468 -176.268888)
			)
			(arc
				(start 131.335018 -176.35855)
				(mid 131.323907 -176.375084)
				(end 131.320032 -176.394618)
			)
			(xy 131.320032 -176.597056)
			(arc
				(start 131.322318 -176.604168)
				(mid 131.339848 -176.722278)
				(end 131.322318 -176.840388)
			)
			(xy 131.320032 -176.8475) (xy 131.320032 -178.0032)
			(arc
				(start 131.322826 -178.011074)
				(mid 131.339356 -178.076198)
				(end 131.344924 -178.143154)
			)
			(arc
				(start 131.344924 -178.143154)
				(mid 131.339336 -178.210107)
				(end 131.322826 -178.275234)
			)
			(xy 131.320032 -178.283108)
			(arc
				(start 131.320032 -178.682396)
				(mid 131.323933 -178.701919)
				(end 131.335018 -178.718464)
			)
			(arc
				(start 131.637024 -179.02047)
				(mid 131.653558 -179.031581)
				(end 131.673092 -179.035456)
			)
			(xy 132.27812 -179.035456)
		)
		(stroke
			(width 0)
			(type solid)
		)
		(fill yes)
		(layer "In13.Cu")
		(net "GND")
	)
	(gr_poly
		(pts
			(arc
				(start 263.911588 -377.747276)
				(mid 263.945184 -377.734581)
				(end 263.96188 -377.702826)
			)
			(arc
				(start 263.96188 -377.702826)
				(mid 264.783363 -375.042932)
				(end 266.467844 -372.826534)
			)
			(arc
				(start 266.467844 -372.826534)
				(mid 266.479908 -372.809571)
				(end 266.4841 -372.789196)
			)
			(arc
				(start 266.4841 -368.772694)
				(mid 266.480199 -368.753171)
				(end 266.469114 -368.736626)
			)
			(arc
				(start 266.291568 -368.55908)
				(mid 266.275034 -368.547969)
				(end 266.2555 -368.544094)
			)
			(xy 243.539264 -368.544094) (xy 243.533676 -368.538506)
			(arc
				(start 242.778534 -368.538506)
				(mid 242.759011 -368.542407)
				(end 242.742466 -368.553492)
			)
			(arc
				(start 242.620038 -368.67592)
				(mid 242.608927 -368.692454)
				(end 242.605052 -368.711988)
			)
			(arc
				(start 242.605052 -377.229624)
				(mid 242.608953 -377.249147)
				(end 242.620038 -377.265692)
			)
			(arc
				(start 243.08689 -377.73229)
				(mid 243.103424 -377.743401)
				(end 243.122958 -377.747276)
			)
		)
		(stroke
			(width 0)
			(type solid)
		)
		(fill yes)
		(layer "In13.Cu")
		(net "P12V_STBY_R2")
	)
	(gr_poly
		(pts
			(arc
				(start 265.912092 -366.269524)
				(mid 265.931615 -366.265623)
				(end 265.94816 -366.254538)
			)
			(arc
				(start 266.349226 -365.853472)
				(mid 266.360337 -365.836938)
				(end 266.364212 -365.817404)
			)
			(arc
				(start 266.364212 -362.170726)
				(mid 266.360311 -362.151203)
				(end 266.349226 -362.134658)
			)
			(arc
				(start 265.603736 -361.389168)
				(mid 265.587202 -361.378057)
				(end 265.567668 -361.374182)
			)
			(arc
				(start 262.018018 -361.374182)
				(mid 261.998495 -361.370281)
				(end 261.98195 -361.359196)
			)
			(arc
				(start 261.514336 -360.891582)
				(mid 261.503225 -360.875048)
				(end 261.49935 -360.855514)
			)
			(arc
				(start 261.49935 -357.15448)
				(mid 261.495449 -357.134957)
				(end 261.484364 -357.118412)
			)
			(arc
				(start 261.275576 -356.909624)
				(mid 261.259042 -356.898513)
				(end 261.239508 -356.894638)
			)
			(arc
				(start 253.270258 -356.894638)
				(mid 253.250735 -356.898539)
				(end 253.23419 -356.909624)
			)
			(arc
				(start 252.95987 -357.183944)
				(mid 252.948759 -357.200478)
				(end 252.944884 -357.220012)
			)
			(arc
				(start 252.944884 -358.53751)
				(mid 252.940983 -358.557033)
				(end 252.929898 -358.573578)
			)
			(arc
				(start 251.742448 -359.761028)
				(mid 251.725914 -359.772139)
				(end 251.70638 -359.776014)
			)
			(arc
				(start 246.79783 -359.776014)
				(mid 246.778307 -359.779915)
				(end 246.761762 -359.791)
			)
			(arc
				(start 245.756938 -360.795824)
				(mid 245.740404 -360.806935)
				(end 245.72087 -360.81081)
			)
			(xy 237.54461 -360.81081) (xy 237.542324 -360.813096) (xy 237.533942 -360.813096)
			(arc
				(start 236.994446 -361.352592)
				(mid 236.983335 -361.369126)
				(end 236.97946 -361.38866)
			)
			(arc
				(start 236.97946 -365.942626)
				(mid 236.983361 -365.962149)
				(end 236.994446 -365.978694)
			)
			(arc
				(start 237.27029 -366.254538)
				(mid 237.286824 -366.265649)
				(end 237.306358 -366.269524)
			)
		)
		(stroke
			(width 0)
			(type solid)
		)
		(fill yes)
		(layer "In13.Cu")
		(net "P12V_AUX")
	)
	(gr_poly
		(pts
			(arc
				(start 250.795028 -82.265012)
				(mid 250.814551 -82.261111)
				(end 250.831096 -82.250026)
			)
			(arc
				(start 250.992894 -82.088228)
				(mid 251.004005 -82.071694)
				(end 251.00788 -82.05216)
			)
			(arc
				(start 251.00788 -80.25638)
				(mid 251.003275 -80.234989)
				(end 250.9901 -80.217518)
			)
			(xy 250.922536 -80.160114) (xy 250.9012 -80.154272)
			(arc
				(start 250.890024 -80.15605)
				(mid 250.859767 -80.159673)
				(end 250.829318 -80.160876)
			)
			(arc
				(start 250.829318 -80.160876)
				(mid 250.44781 -79.779368)
				(end 250.829318 -79.39786)
			)
			(arc
				(start 250.829318 -79.39786)
				(mid 250.859768 -79.399057)
				(end 250.890024 -79.402686)
			)
			(xy 250.9012 -79.404464) (xy 250.922536 -79.398622)
			(arc
				(start 250.9901 -79.341218)
				(mid 251.003276 -79.323748)
				(end 251.00788 -79.302356)
			)
			(arc
				(start 251.00788 -78.410562)
				(mid 251.003979 -78.391039)
				(end 250.992894 -78.374494)
			)
			(xy 250.43765 -77.81925) (xy 250.430538 -77.811884) (xy 250.411742 -77.804264)
			(arc
				(start 247.658636 -77.804264)
				(mid 247.639249 -77.808214)
				(end 247.622822 -77.81925)
			)
			(arc
				(start 247.35663 -78.085188)
				(mid 247.345656 -78.101751)
				(end 247.341898 -78.121256)
			)
			(arc
				(start 247.341898 -82.17535)
				(mid 247.345799 -82.194873)
				(end 247.356884 -82.211418)
			)
			(arc
				(start 247.395492 -82.250026)
				(mid 247.412026 -82.261137)
				(end 247.43156 -82.265012)
			)
		)
		(stroke
			(width 0)
			(type solid)
		)
		(fill yes)
		(layer "In13.Cu")
		(net "GND")
	)
	(gr_poly
		(pts
			(arc
				(start 456.481688 -278.581104)
				(mid 456.504227 -278.575956)
				(end 456.522074 -278.561292)
			)
			(xy 456.578462 -278.48814) (xy 456.583034 -278.46528)
			(arc
				(start 456.579986 -278.453596)
				(mid 456.570641 -278.40561)
				(end 456.56754 -278.356822)
			)
			(arc
				(start 456.56754 -278.356822)
				(mid 456.595626 -278.213151)
				(end 456.675744 -278.09063)
			)
			(xy 456.684126 -278.081994) (xy 456.691238 -278.059896) (xy 456.676252 -277.956264) (xy 456.663044 -277.937214)
			(arc
				(start 456.65263 -277.931118)
				(mid 456.577876 -277.876324)
				(end 456.518518 -277.805134)
			)
			(xy 456.51293 -277.796752) (xy 456.496928 -277.785322) (xy 456.408282 -277.765002) (xy 456.388724 -277.768304)
			(arc
				(start 456.380088 -277.773384)
				(mid 456.284627 -277.815032)
				(end 456.18146 -277.829264)
			)
			(arc
				(start 456.18146 -277.829264)
				(mid 456.041208 -277.802549)
				(end 455.920602 -277.72614)
			)
			(xy 455.91349 -277.719536) (xy 455.895964 -277.712424) (xy 455.806556 -277.712424) (xy 455.78903 -277.719536)
			(arc
				(start 455.781918 -277.72614)
				(mid 455.52106 -277.829259)
				(end 455.260202 -277.72614)
			)
			(xy 455.25309 -277.719536) (xy 455.235564 -277.712424) (xy 455.146156 -277.712424) (xy 455.12863 -277.719536)
			(xy 455.121518 -277.72614) (xy 455.11085 -277.735792) (xy 455.102214 -277.743412) (xy 455.09307 -277.763986)
			(xy 455.09561 -277.865078) (xy 455.10577 -277.885398)
			(arc
				(start 455.11466 -277.892256)
				(mid 455.222288 -278.025542)
				(end 455.26071 -278.192484)
			)
			(arc
				(start 455.26071 -278.192484)
				(mid 455.241508 -278.311741)
				(end 455.186034 -278.419052)
			)
			(xy 455.177398 -278.430736) (xy 455.175112 -278.459184)
			(arc
				(start 455.222356 -278.553164)
				(mid 455.241116 -278.573623)
				(end 455.267822 -278.581104)
			)
		)
		(stroke
			(width 0)
			(type solid)
		)
		(fill yes)
		(layer "In13.Cu")
		(net "P1V25_SERDES_VDDPLL_PEX3")
	)
	(gr_poly
		(pts
			(arc
				(start 330.464922 -206.127096)
				(mid 330.482353 -206.124012)
				(end 330.497688 -206.115158)
			)
			(arc
				(start 330.497688 -206.115158)
				(mid 330.612677 -206.048492)
				(end 330.74356 -206.025242)
			)
			(arc
				(start 330.74356 -206.025242)
				(mid 330.874474 -206.048407)
				(end 330.989432 -206.115158)
			)
			(arc
				(start 330.989432 -206.115158)
				(mid 331.004756 -206.124042)
				(end 331.022198 -206.127096)
			)
			(xy 331.221842 -205.927452) (xy 331.440536 -205.708758) (xy 332.45171 -205.708758) (xy 332.581758 -205.57871)
			(arc
				(start 332.581758 -203.269088)
				(mid 332.577857 -203.249565)
				(end 332.566772 -203.23302)
			)
			(arc
				(start 332.097126 -202.763374)
				(mid 332.08068 -202.752448)
				(end 332.061312 -202.748642)
			)
			(arc
				(start 330.349606 -202.748642)
				(mid 330.328029 -202.753452)
				(end 330.31049 -202.76693)
			)
			(xy 330.25334 -202.836018) (xy 330.247752 -202.857608)
			(arc
				(start 330.249784 -202.869038)
				(mid 330.254724 -202.90419)
				(end 330.256388 -202.93965)
			)
			(arc
				(start 330.256388 -202.93965)
				(mid 330.144647 -203.209417)
				(end 329.87488 -203.321158)
			)
			(arc
				(start 329.87488 -203.321158)
				(mid 329.681427 -203.268513)
				(end 329.541378 -203.12507)
			)
			(xy 329.535028 -203.113386) (xy 329.512676 -203.09967) (xy 329.3999 -203.094336) (xy 329.376532 -203.105766)
			(arc
				(start 329.368912 -203.116942)
				(mid 329.232183 -203.238258)
				(end 329.054714 -203.282042)
			)
			(arc
				(start 329.054714 -203.282042)
				(mid 328.952274 -203.267961)
				(end 328.857356 -203.226924)
			)
			(xy 328.845418 -203.219812) (xy 328.81824 -203.219304)
			(arc
				(start 328.729086 -203.269596)
				(mid 328.710122 -203.288306)
				(end 328.703178 -203.314046)
			)
			(arc
				(start 328.703178 -205.820518)
				(mid 328.707079 -205.840041)
				(end 328.718164 -205.856586)
			)
			(arc
				(start 328.973688 -206.11211)
				(mid 328.990222 -206.123221)
				(end 329.009756 -206.127096)
			)
		)
		(stroke
			(width 0)
			(type solid)
		)
		(fill yes)
		(layer "In13.Cu")
		(net "GND")
	)
	(gr_poly
		(pts
			(arc
				(start 232.57256 -138.453876)
				(mid 232.591917 -138.450043)
				(end 232.608374 -138.439144)
			)
			(xy 232.608628 -138.43889)
			(arc
				(start 232.66146 -138.376152)
				(mid 232.66773 -138.366941)
				(end 232.671874 -138.356594)
			)
			(xy 232.674414 -138.346942)
			(arc
				(start 232.672636 -138.335258)
				(mid 232.667849 -138.297038)
				(end 232.666286 -138.25855)
			)
			(arc
				(start 232.666286 -138.25855)
				(mid 233.123994 -137.800842)
				(end 233.581702 -138.25855)
			)
			(arc
				(start 233.581702 -138.25855)
				(mid 233.580145 -138.297038)
				(end 233.575352 -138.335258)
			)
			(xy 233.573574 -138.346942)
			(arc
				(start 233.576114 -138.356594)
				(mid 233.580228 -138.366957)
				(end 233.586528 -138.376152)
			)
			(xy 233.63936 -138.43889)
			(arc
				(start 233.639614 -138.439144)
				(mid 233.65606 -138.45007)
				(end 233.675428 -138.453876)
			)
			(arc
				(start 234.410504 -138.453876)
				(mid 234.430027 -138.449975)
				(end 234.446572 -138.43889)
			)
			(arc
				(start 235.079286 -137.806176)
				(mid 235.090397 -137.789642)
				(end 235.094272 -137.770108)
			)
			(arc
				(start 235.094272 -134.749794)
				(mid 235.090371 -134.730271)
				(end 235.079286 -134.713726)
			)
			(arc
				(start 234.822238 -134.456678)
				(mid 234.805704 -134.445567)
				(end 234.78617 -134.441692)
			)
			(arc
				(start 230.369872 -134.441692)
				(mid 230.350349 -134.445593)
				(end 230.333804 -134.456678)
			)
			(xy 230.162608 -134.627874)
			(arc
				(start 230.113332 -134.67715)
				(mid 230.102358 -134.693713)
				(end 230.0986 -134.713218)
			)
			(xy 230.0986 -135.259826) (xy 230.098346 -135.266938)
			(arc
				(start 230.098346 -135.45693)
				(mid 230.102247 -135.476453)
				(end 230.113332 -135.492998)
			)
			(xy 230.177086 -135.556752) (xy 230.181404 -135.56107)
			(arc
				(start 230.618538 -135.998204)
				(mid 230.629649 -136.014738)
				(end 230.633524 -136.034272)
			)
			(arc
				(start 230.633524 -138.144504)
				(mid 230.637425 -138.164027)
				(end 230.64851 -138.180572)
			)
			(arc
				(start 230.906828 -138.43889)
				(mid 230.923362 -138.450001)
				(end 230.942896 -138.453876)
			)
		)
		(stroke
			(width 0)
			(type solid)
		)
		(fill yes)
		(layer "In13.Cu")
		(net "GND")
	)
	(gr_poly
		(pts
			(xy 242.973098 -94.5388) (xy 242.983168 -94.538377) (xy 243.001773 -94.530663) (xy 243.009166 -94.523814)
			(xy 243.793518 -93.739462) (xy 243.800367 -93.732065) (xy 243.808101 -93.713466) (xy 243.808504 -93.703394)
			(xy 243.808504 -90.333322) (xy 243.808067 -90.323258) (xy 243.800333 -90.304674) (xy 243.793518 -90.297254)
			(xy 243.609368 -90.113104) (xy 243.553488 -90.057224) (xy 243.546079 -90.050539) (xy 243.527642 -90.042958)
			(xy 243.517674 -90.042492) (xy 240.377472 -90.042492) (xy 240.369344 -90.042238) (xy 239.540034 -90.042238)
			(xy 239.530045 -90.042771) (xy 239.511607 -90.05048) (xy 239.50422 -90.057224) (xy 239.258856 -90.302334)
			(xy 238.698786 -90.862404) (xy 238.691931 -90.869799) (xy 238.684184 -90.888398) (xy 238.6838 -90.898472)
			(xy 238.6838 -91.650312) (xy 239.454434 -91.650312) (xy 239.458505 -91.59469) (xy 239.470631 -91.540253)
			(xy 239.490554 -91.488162) (xy 239.51785 -91.439527) (xy 239.551936 -91.395384) (xy 239.592085 -91.356675)
			(xy 239.637443 -91.324224) (xy 239.687043 -91.298723) (xy 239.739827 -91.280716) (xy 239.79467 -91.270586)
			(xy 239.850404 -91.268549) (xy 239.905841 -91.274649) (xy 239.959798 -91.288755) (xy 240.011127 -91.310567)
			(xy 240.058733 -91.339621) (xy 240.101601 -91.375296) (xy 240.138818 -91.416833) (xy 240.169591 -91.463346)
			(xy 240.193263 -91.513843) (xy 240.209331 -91.56725) (xy 240.217451 -91.622426) (xy 240.21796 -91.650312)
			(xy 240.217451 -91.678198) (xy 240.209331 -91.733374) (xy 240.193263 -91.786781) (xy 240.169591 -91.837278)
			(xy 240.138818 -91.883791) (xy 240.101601 -91.925328) (xy 240.058733 -91.961003) (xy 240.011127 -91.990057)
			(xy 239.959798 -92.011869) (xy 239.905841 -92.025975) (xy 239.850404 -92.032075) (xy 239.79467 -92.030038)
			(xy 239.739827 -92.019908) (xy 239.687043 -92.001901) (xy 239.637443 -91.9764) (xy 239.592085 -91.943949)
			(xy 239.551936 -91.90524) (xy 239.51785 -91.861097) (xy 239.490554 -91.812462) (xy 239.470631 -91.760371)
			(xy 239.458505 -91.705934) (xy 239.454434 -91.650312) (xy 238.6838 -91.650312) (xy 238.6838 -91.753944)
			(xy 238.684065 -91.761587) (xy 238.688597 -91.776185) (xy 238.69269 -91.782646) (xy 238.708633 -91.80666)
			(xy 238.733877 -91.858477) (xy 238.751032 -91.913504) (xy 238.759708 -91.970487) (xy 238.759707 -92.028126)
			(xy 238.751029 -92.085108) (xy 238.733872 -92.140135) (xy 238.708627 -92.191952) (xy 238.69269 -92.21597)
			(xy 238.68858 -92.222422) (xy 238.684051 -92.237027) (xy 238.6838 -92.244672) (xy 238.6838 -94.289118)
			(xy 238.684227 -94.299187) (xy 238.691946 -94.317786) (xy 238.698786 -94.325186) (xy 238.897414 -94.523814)
			(xy 238.904809 -94.530668) (xy 238.923408 -94.53841) (xy 238.933482 -94.5388)
		)
		(stroke
			(width 0)
			(type solid)
		)
		(fill yes)
		(layer "In13.Cu")
		(net "GND")
	)
	(gr_poly
		(pts
			(arc
				(start 238.103918 -218.946476)
				(mid 238.123441 -218.942575)
				(end 238.139986 -218.93149)
			)
			(arc
				(start 238.376714 -218.694762)
				(mid 238.387825 -218.678228)
				(end 238.3917 -218.658694)
			)
			(arc
				(start 238.3917 -217.910918)
				(mid 238.387799 -217.891395)
				(end 238.376714 -217.87485)
			)
			(arc
				(start 235.72978 -215.227916)
				(mid 235.713246 -215.216805)
				(end 235.693712 -215.21293)
			)
			(arc
				(start 234.831636 -215.21293)
				(mid 234.812113 -215.216831)
				(end 234.795568 -215.227916)
			)
			(arc
				(start 234.46994 -215.553544)
				(mid 234.458829 -215.570078)
				(end 234.454954 -215.589612)
			)
			(arc
				(start 234.454954 -216.006426)
				(mid 234.459959 -216.028414)
				(end 234.474004 -216.04605)
			)
			(arc
				(start 234.474004 -216.04605)
				(mid 234.598215 -216.304368)
				(end 234.474004 -216.562686)
			)
			(arc
				(start 234.474004 -216.562686)
				(mid 234.459982 -216.580333)
				(end 234.454954 -216.60231)
			)
			(arc
				(start 234.454954 -216.806526)
				(mid 234.459959 -216.828514)
				(end 234.474004 -216.84615)
			)
			(arc
				(start 234.474004 -216.84615)
				(mid 234.598215 -217.104468)
				(end 234.474004 -217.362786)
			)
			(arc
				(start 234.474004 -217.362786)
				(mid 234.459982 -217.380433)
				(end 234.454954 -217.40241)
			)
			(arc
				(start 234.454954 -217.439748)
				(mid 234.458855 -217.459271)
				(end 234.46994 -217.475816)
			)
			(arc
				(start 234.659678 -217.665554)
				(mid 234.676595 -217.676671)
				(end 234.696508 -217.680286)
			)
			(xy 234.780074 -217.678762) (xy 234.79887 -217.67038)
			(arc
				(start 234.805982 -217.662506)
				(mid 234.924739 -217.578146)
				(end 235.067348 -217.54846)
			)
			(arc
				(start 235.067348 -217.54846)
				(mid 235.203581 -217.575465)
				(end 235.319062 -217.6526)
			)
			(arc
				(start 235.417106 -217.750644)
				(mid 235.43364 -217.761755)
				(end 235.453174 -217.76563)
			)
			(arc
				(start 235.996226 -217.76563)
				(mid 236.015749 -217.769531)
				(end 236.032294 -217.780616)
			)
			(xy 236.033564 -217.781886)
			(arc
				(start 236.05998 -217.77706)
				(mid 236.090451 -217.772705)
				(end 236.121194 -217.771218)
			)
			(arc
				(start 236.121194 -217.771218)
				(mid 236.35504 -217.86808)
				(end 236.451902 -218.101926)
			)
			(arc
				(start 236.451902 -218.101926)
				(mid 236.450399 -218.132668)
				(end 236.44606 -218.16314)
			)
			(xy 236.443774 -218.175586) (xy 236.451394 -218.199716)
			(arc
				(start 237.183168 -218.93149)
				(mid 237.199702 -218.942601)
				(end 237.219236 -218.946476)
			)
		)
		(stroke
			(width 0)
			(type solid)
		)
		(fill yes)
		(layer "In13.Cu")
		(net "P1V2_BIC_ADCVREFREXT0")
	)
	(gr_poly
		(pts
			(xy 68.431156 -13.728954) (xy 68.431156 -13.494512) (xy 68.294758 -13.358114)
			(arc
				(start 60.96508 -13.358114)
				(mid 59.898764 -12.916432)
				(end 59.457082 -11.850116)
			)
			(arc
				(start 59.457082 -1.999996)
				(mid 59.020086 -0.944996)
				(end 57.965086 -0.508)
			)
			(arc
				(start 45.96511 -0.508)
				(mid 44.91011 -0.944996)
				(end 44.473114 -1.999996)
			)
			(xy 44.473114 -11.796522) (xy 44.980352 -11.796522)
			(arc
				(start 44.980352 -1.999996)
				(mid 45.268617 -1.303936)
				(end 45.964602 -1.015492)
			)
			(arc
				(start 57.965086 -1.015492)
				(mid 58.661325 -1.303831)
				(end 58.949844 -1.999996)
			)
			(arc
				(start 58.949844 -11.850116)
				(mid 59.540093 -13.275103)
				(end 60.96508 -13.865352)
			)
			(xy 68.294758 -13.865352)
		)
		(stroke
			(width 0)
			(type solid)
		)
		(fill yes)
		(layer "In13.Cu")
		(net "GND")
	)
	(gr_poly
		(pts
			(xy 132.291582 -13.80998) (xy 132.291582 -13.413486) (xy 132.23621 -13.358114)
			(arc
				(start 125.065028 -13.358114)
				(mid 123.998712 -12.916432)
				(end 123.55703 -11.850116)
			)
			(arc
				(start 123.55703 -1.999996)
				(mid 123.120034 -0.944996)
				(end 122.065034 -0.508)
			)
			(arc
				(start 97.965006 -0.508)
				(mid 96.910006 -0.944996)
				(end 96.47301 -1.999996)
			)
			(xy 96.47301 -11.506454) (xy 96.980248 -11.506454)
			(arc
				(start 96.980248 -1.999996)
				(mid 97.268513 -1.303936)
				(end 97.964498 -1.015492)
			)
			(arc
				(start 122.065034 -1.015492)
				(mid 122.761273 -1.303831)
				(end 123.049792 -1.999996)
			)
			(arc
				(start 123.049792 -11.850116)
				(mid 123.640041 -13.275103)
				(end 125.065028 -13.865352)
			)
			(xy 132.23621 -13.865352)
		)
		(stroke
			(width 0)
			(type solid)
		)
		(fill yes)
		(layer "In13.Cu")
		(net "GND")
	)
	(gr_poly
		(pts
			(xy 158.365444 -13.805662) (xy 158.365444 -13.417804) (xy 158.305754 -13.358114)
			(arc
				(start 151.064976 -13.358114)
				(mid 149.99866 -12.916432)
				(end 149.556978 -11.850116)
			)
			(arc
				(start 149.556978 -1.999996)
				(mid 149.119982 -0.944996)
				(end 148.064982 -0.508)
			)
			(arc
				(start 136.065006 -0.508)
				(mid 135.010006 -0.944996)
				(end 134.57301 -1.999996)
			)
			(xy 134.57301 -11.619738) (xy 135.080248 -11.619738)
			(arc
				(start 135.080248 -1.999996)
				(mid 135.368513 -1.303936)
				(end 136.064498 -1.015492)
			)
			(arc
				(start 148.064982 -1.015492)
				(mid 148.761221 -1.303831)
				(end 149.04974 -1.999996)
			)
			(arc
				(start 149.04974 -11.850116)
				(mid 149.639989 -13.275103)
				(end 151.064976 -13.865352)
			)
			(xy 158.305754 -13.865352)
		)
		(stroke
			(width 0)
			(type solid)
		)
		(fill yes)
		(layer "In13.Cu")
		(net "GND")
	)
	(gr_poly
		(pts
			(xy 184.389268 -13.77569) (xy 184.389268 -13.447776) (xy 184.299606 -13.358114)
			(arc
				(start 177.064924 -13.358114)
				(mid 175.998608 -12.916432)
				(end 175.556926 -11.850116)
			)
			(arc
				(start 175.556926 -1.999996)
				(mid 175.11993 -0.944996)
				(end 174.06493 -0.508)
			)
			(arc
				(start 162.064954 -0.508)
				(mid 161.009954 -0.944996)
				(end 160.572958 -1.999996)
			)
			(xy 160.572958 -11.783314) (xy 161.080196 -11.783314)
			(arc
				(start 161.080196 -1.999996)
				(mid 161.368461 -1.303936)
				(end 162.064446 -1.015492)
			)
			(arc
				(start 174.06493 -1.015492)
				(mid 174.761169 -1.303831)
				(end 175.049688 -1.999996)
			)
			(arc
				(start 175.049688 -11.850116)
				(mid 175.639937 -13.275103)
				(end 177.064924 -13.865352)
			)
			(xy 184.299606 -13.865352)
		)
		(stroke
			(width 0)
			(type solid)
		)
		(fill yes)
		(layer "In13.Cu")
		(net "GND")
	)
	(gr_poly
		(pts
			(xy 210.250024 -13.829284) (xy 210.250024 -13.394182) (xy 210.213956 -13.358114)
			(arc
				(start 203.064872 -13.358114)
				(mid 201.998721 -12.916342)
				(end 201.556874 -11.850116)
			)
			(arc
				(start 201.556874 -1.999996)
				(mid 201.119878 -0.944996)
				(end 200.064878 -0.508)
			)
			(arc
				(start 188.064902 -0.508)
				(mid 187.009902 -0.944996)
				(end 186.572906 -1.999996)
			)
			(xy 186.572906 -11.664696) (xy 187.080144 -11.664696)
			(arc
				(start 187.080144 -1.999996)
				(mid 187.368409 -1.303936)
				(end 188.064394 -1.015492)
			)
			(arc
				(start 200.064878 -1.015492)
				(mid 200.761117 -1.303831)
				(end 201.049636 -1.999996)
			)
			(arc
				(start 201.049636 -11.850116)
				(mid 201.63987 -13.275193)
				(end 203.064872 -13.865352)
			)
			(xy 210.213956 -13.865352)
		)
		(stroke
			(width 0)
			(type solid)
		)
		(fill yes)
		(layer "In13.Cu")
		(net "GND")
	)
	(gr_poly
		(pts
			(xy 248.61139 -13.829538) (xy 248.61139 -13.393928) (xy 248.575576 -13.358114)
			(arc
				(start 241.164872 -13.358114)
				(mid 240.098721 -12.916342)
				(end 239.656874 -11.850116)
			)
			(arc
				(start 239.656874 -1.999996)
				(mid 239.219878 -0.944996)
				(end 238.164878 -0.508)
			)
			(arc
				(start 214.065104 -0.508)
				(mid 213.010104 -0.944996)
				(end 212.573108 -1.999996)
			)
			(xy 212.573108 -11.820906) (xy 213.0806 -11.820906)
			(arc
				(start 213.0806 -1.999996)
				(mid 213.368955 -1.303847)
				(end 214.065104 -1.015492)
			)
			(arc
				(start 238.164878 -1.015492)
				(mid 238.861117 -1.303831)
				(end 239.149636 -1.999996)
			)
			(arc
				(start 239.149636 -11.850116)
				(mid 239.73987 -13.275193)
				(end 241.164872 -13.865352)
			)
			(xy 248.575576 -13.865352)
		)
		(stroke
			(width 0)
			(type solid)
		)
		(fill yes)
		(layer "In13.Cu")
		(net "GND")
	)
	(gr_poly
		(pts
			(xy 274.599654 -13.810742) (xy 274.599654 -13.412724) (xy 274.545044 -13.358114)
			(arc
				(start 267.165074 -13.358114)
				(mid 266.098758 -12.916432)
				(end 265.657076 -11.850116)
			)
			(arc
				(start 265.657076 -1.999996)
				(mid 265.22008 -0.944996)
				(end 264.16508 -0.508)
			)
			(arc
				(start 252.165104 -0.508)
				(mid 251.110104 -0.944996)
				(end 250.673108 -1.999996)
			)
			(xy 250.673108 -11.725656) (xy 251.1806 -11.725656)
			(arc
				(start 251.1806 -1.999996)
				(mid 251.468955 -1.303847)
				(end 252.165104 -1.015492)
			)
			(arc
				(start 264.16508 -1.015492)
				(mid 264.861229 -1.303847)
				(end 265.149584 -1.999996)
			)
			(arc
				(start 265.149584 -11.850116)
				(mid 265.739997 -13.275118)
				(end 267.165074 -13.865352)
			)
			(xy 274.545044 -13.865352)
		)
		(stroke
			(width 0)
			(type solid)
		)
		(fill yes)
		(layer "In13.Cu")
		(net "GND")
	)
	(gr_poly
		(pts
			(xy 442.67882 -13.82903) (xy 442.67882 -13.394436) (xy 442.642498 -13.358114)
			(arc
				(start 435.265068 -13.358114)
				(mid 434.198752 -12.916432)
				(end 433.75707 -11.850116)
			)
			(arc
				(start 433.75707 -1.999996)
				(mid 433.320074 -0.944996)
				(end 432.265074 -0.508)
			)
			(arc
				(start 420.265098 -0.508)
				(mid 419.210098 -0.944996)
				(end 418.773102 -1.999996)
			)
			(xy 418.773102 -11.813286) (xy 419.28034 -11.813286)
			(arc
				(start 419.28034 -1.999996)
				(mid 419.568605 -1.303936)
				(end 420.26459 -1.015492)
			)
			(arc
				(start 432.265074 -1.015492)
				(mid 432.961313 -1.303831)
				(end 433.249832 -1.999996)
			)
			(arc
				(start 433.249832 -11.850116)
				(mid 433.840081 -13.275103)
				(end 435.265068 -13.865352)
			)
			(xy 442.642498 -13.865352)
		)
		(stroke
			(width 0)
			(type solid)
		)
		(fill yes)
		(layer "In13.Cu")
		(net "GND")
	)
	(gr_poly
		(pts
			(xy 300.515782 -13.7541) (xy 300.515782 -13.469366) (xy 300.40453 -13.358114)
			(arc
				(start 293.165022 -13.358114)
				(mid 292.098706 -12.916432)
				(end 291.657024 -11.850116)
			)
			(arc
				(start 291.657024 -1.999996)
				(mid 291.220028 -0.944996)
				(end 290.165028 -0.508)
			)
			(arc
				(start 278.165052 -0.508)
				(mid 277.110052 -0.944996)
				(end 276.673056 -1.999996)
			)
			(xy 276.673056 -11.850116) (xy 276.673056 -11.850624) (xy 277.180548 -11.850624)
			(arc
				(start 277.180548 -1.999996)
				(mid 277.468903 -1.303847)
				(end 278.165052 -1.015492)
			)
			(arc
				(start 290.165028 -1.015492)
				(mid 290.861177 -1.303847)
				(end 291.149532 -1.999996)
			)
			(arc
				(start 291.149532 -11.850116)
				(mid 291.739945 -13.275118)
				(end 293.165022 -13.865352)
			)
			(xy 300.40453 -13.865352)
		)
		(stroke
			(width 0)
			(type solid)
		)
		(fill yes)
		(layer "In13.Cu")
		(net "GND")
	)
	(gr_poly
		(pts
			(xy 94.285816 -13.833856) (xy 94.285816 -13.444728) (xy 94.199202 -13.358114)
			(arc
				(start 86.965028 -13.358114)
				(mid 85.898712 -12.916432)
				(end 85.45703 -11.850116)
			)
			(arc
				(start 85.45703 -1.999996)
				(mid 85.020034 -0.944996)
				(end 83.965034 -0.508)
			)
			(arc
				(start 71.965058 -0.508)
				(mid 70.910058 -0.944996)
				(end 70.473062 -1.999996)
			)
			(xy 70.473062 -11.850116) (xy 70.473062 -11.85037) (xy 70.9803 -11.85037)
			(arc
				(start 70.9803 -1.999996)
				(mid 71.268565 -1.303936)
				(end 71.96455 -1.015492)
			)
			(arc
				(start 83.965034 -1.015492)
				(mid 84.661273 -1.303831)
				(end 84.949792 -1.999996)
			)
			(arc
				(start 84.949792 -11.850116)
				(mid 85.540041 -13.275103)
				(end 86.965028 -13.865352)
			)
			(xy 94.199202 -13.865352) (xy 94.25432 -13.865352)
		)
		(stroke
			(width 0)
			(type solid)
		)
		(fill yes)
		(layer "In13.Cu")
		(net "GND")
	)
	(gr_poly
		(pts
			(xy 42.390314 -13.820648) (xy 42.390314 -13.401548) (xy 42.34688 -13.358114) (xy 42.330624 -13.358114)
			(arc
				(start 34.964878 -13.358114)
				(mid 33.898562 -12.916432)
				(end 33.45688 -11.850116)
			)
			(arc
				(start 33.45688 -1.999996)
				(mid 33.019884 -0.944996)
				(end 31.964884 -0.508)
			)
			(arc
				(start 19.964908 -0.508)
				(mid 18.909908 -0.944996)
				(end 18.472912 -1.999996)
			)
			(xy 18.472912 -11.47953) (xy 18.646902 -11.65352) (xy 18.980404 -11.65352)
			(arc
				(start 18.980404 -1.999996)
				(mid 19.268759 -1.303847)
				(end 19.964908 -1.015492)
			)
			(arc
				(start 31.964884 -1.015492)
				(mid 32.661033 -1.303847)
				(end 32.949388 -1.999996)
			)
			(arc
				(start 32.949388 -11.850116)
				(mid 33.539801 -13.275118)
				(end 34.964878 -13.865352)
			)
			(xy 42.330624 -13.865352) (xy 42.34561 -13.865352)
		)
		(stroke
			(width 0)
			(type solid)
		)
		(fill yes)
		(layer "In13.Cu")
		(net "GND")
	)
	(gr_poly
		(pts
			(xy 239.626648 -205.472538)
			(arc
				(start 239.627918 -205.452218)
				(mid 239.74781 -205.198646)
				(end 240.008664 -205.095602)
			)
			(arc
				(start 240.008664 -205.095602)
				(mid 240.200989 -205.147586)
				(end 240.340896 -205.289404)
			)
			(xy 240.346738 -205.299818) (xy 240.366296 -205.31328)
			(arc
				(start 240.458244 -205.325726)
				(mid 240.481391 -205.323507)
				(end 240.50117 -205.311248)
			)
			(arc
				(start 240.670334 -205.142084)
				(mid 240.681396 -205.125667)
				(end 240.68532 -205.10627)
			)
			(arc
				(start 240.68532 -204.702156)
				(mid 240.711207 -204.529696)
				(end 240.786666 -204.372464)
			)
			(arc
				(start 240.786666 -204.372464)
				(mid 240.793242 -204.358906)
				(end 240.795556 -204.344016)
			)
			(arc
				(start 240.795556 -200.381108)
				(mid 240.791655 -200.361585)
				(end 240.78057 -200.34504)
			)
			(xy 240.643156 -200.207626) (xy 240.636044 -200.20026) (xy 240.617248 -200.19264)
			(arc
				(start 239.886236 -200.19264)
				(mid 239.862297 -200.198634)
				(end 239.844072 -200.215246)
			)
			(xy 239.78997 -200.296018) (xy 239.78743 -200.321164)
			(arc
				(start 239.792256 -200.333102)
				(mid 239.813879 -200.404451)
				(end 239.821212 -200.478644)
			)
			(arc
				(start 239.821212 -200.478644)
				(mid 239.439704 -200.860152)
				(end 239.058196 -200.478644)
			)
			(arc
				(start 239.058196 -200.478644)
				(mid 239.06553 -200.404452)
				(end 239.087152 -200.333102)
			)
			(xy 239.091978 -200.321164) (xy 239.089438 -200.296018)
			(arc
				(start 239.035336 -200.215246)
				(mid 239.017074 -200.198703)
				(end 238.993172 -200.19264)
			)
			(arc
				(start 237.806738 -200.19264)
				(mid 237.787215 -200.196541)
				(end 237.77067 -200.207626)
			)
			(arc
				(start 237.352586 -200.62571)
				(mid 237.341475 -200.642244)
				(end 237.3376 -200.661778)
			)
			(arc
				(start 237.3376 -202.513438)
				(mid 237.338149 -202.521148)
				(end 237.339886 -202.528678)
			)
			(xy 237.346744 -202.550014)
			(arc
				(start 237.350554 -202.55611)
				(mid 237.414454 -202.767438)
				(end 237.350554 -202.978766)
			)
			(xy 237.346744 -202.984862)
			(arc
				(start 237.339886 -203.006198)
				(mid 237.338174 -203.013732)
				(end 237.3376 -203.021438)
			)
			(arc
				(start 237.3376 -205.017878)
				(mid 237.341501 -205.037401)
				(end 237.352586 -205.053946)
			)
			(xy 237.403386 -205.104746)
			(arc
				(start 237.460536 -205.161896)
				(mid 237.468135 -205.168144)
				(end 237.476792 -205.172818)
			)
			(arc
				(start 237.867952 -205.33487)
				(mid 237.886707 -205.338771)
				(end 237.905544 -205.335378)
			)
			(xy 237.979966 -205.30693) (xy 237.99419 -205.293722)
			(arc
				(start 237.998508 -205.284832)
				(mid 238.139268 -205.126674)
				(end 238.342678 -205.067916)
			)
			(arc
				(start 238.342678 -205.067916)
				(mid 238.612355 -205.179567)
				(end 238.724186 -205.44917)
			)
			(xy 238.724186 -205.470252) (xy 238.753904 -205.499716) (xy 239.597438 -205.499716)
		)
		(stroke
			(width 0)
			(type solid)
		)
		(fill yes)
		(layer "In13.Cu")
		(net "GND")
	)
	(gr_poly
		(pts
			(xy 416.458146 -13.816076) (xy 416.458146 -13.40739) (xy 416.40887 -13.358114)
			(arc
				(start 409.26512 -13.358114)
				(mid 408.198804 -12.916432)
				(end 407.757122 -11.850116)
			)
			(arc
				(start 407.757122 -1.999996)
				(mid 407.320126 -0.944996)
				(end 406.265126 -0.508)
			)
			(arc
				(start 394.264896 -0.508)
				(mid 393.209896 -0.944996)
				(end 392.7729 -1.999996)
			)
			(arc
				(start 392.7729 -11.850116)
				(mid 392.702216 -12.306469)
				(end 392.496802 -12.720066)
			)
			(xy 392.496802 -12.748514) (xy 392.499088 -12.7508)
			(arc
				(start 393.067794 -12.7508)
				(mid 393.226496 -12.312827)
				(end 393.280392 -11.850116)
			)
			(arc
				(start 393.280392 -1.999996)
				(mid 393.568747 -1.303847)
				(end 394.264896 -1.015492)
			)
			(arc
				(start 406.265126 -1.015492)
				(mid 406.961365 -1.303831)
				(end 407.249884 -1.999996)
			)
			(arc
				(start 407.249884 -11.850116)
				(mid 407.840133 -13.275103)
				(end 409.26512 -13.865352)
			)
			(xy 416.40887 -13.865352)
		)
		(stroke
			(width 0)
			(type solid)
		)
		(fill yes)
		(layer "In13.Cu")
		(net "GND")
	)
	(gr_poly
		(pts
			(xy 364.71606 -13.770102) (xy 364.71606 -13.453364) (xy 364.62081 -13.358114)
			(arc
				(start 357.26497 -13.358114)
				(mid 356.198654 -12.916432)
				(end 355.756972 -11.850116)
			)
			(arc
				(start 355.756972 -1.999996)
				(mid 355.319976 -0.944996)
				(end 354.264976 -0.508)
			)
			(arc
				(start 330.164948 -0.508)
				(mid 329.109948 -0.944996)
				(end 328.672952 -1.999996)
			)
			(arc
				(start 328.672952 -11.850116)
				(mid 328.570197 -12.397292)
				(end 328.27595 -12.869926)
			)
			(xy 328.27595 -12.876784) (xy 328.28738 -12.888214) (xy 328.885042 -12.888214)
			(arc
				(start 328.90333 -12.869926)
				(mid 329.10994 -12.378512)
				(end 329.180444 -11.850116)
			)
			(arc
				(start 329.180444 -1.999996)
				(mid 329.468799 -1.303847)
				(end 330.164948 -1.015492)
			)
			(arc
				(start 354.264976 -1.015492)
				(mid 354.961125 -1.303847)
				(end 355.24948 -1.999996)
			)
			(arc
				(start 355.24948 -11.850116)
				(mid 355.839893 -13.275118)
				(end 357.26497 -13.865352)
			)
			(xy 364.62081 -13.865352)
		)
		(stroke
			(width 0)
			(type solid)
		)
		(fill yes)
		(layer "In13.Cu")
		(net "GND")
	)
	(gr_poly
		(pts
			(xy 390.499092 -13.810996) (xy 390.499092 -13.41247) (xy 390.444736 -13.358114)
			(arc
				(start 383.264918 -13.358114)
				(mid 382.198602 -12.916432)
				(end 381.75692 -11.850116)
			)
			(arc
				(start 381.75692 -1.999996)
				(mid 381.319924 -0.944996)
				(end 380.264924 -0.508)
			)
			(arc
				(start 368.264948 -0.508)
				(mid 367.209948 -0.944996)
				(end 366.772952 -1.999996)
			)
			(arc
				(start 366.772952 -11.850116)
				(mid 366.670132 -12.397459)
				(end 366.375696 -12.87018)
			)
			(xy 366.375696 -12.899644) (xy 366.434878 -12.958826) (xy 366.914684 -12.958826)
			(arc
				(start 367.00333 -12.87018)
				(mid 367.209881 -12.378884)
				(end 367.280444 -11.850624)
			)
			(arc
				(start 367.280444 -1.999996)
				(mid 367.568799 -1.303847)
				(end 368.264948 -1.015492)
			)
			(arc
				(start 380.264924 -1.015492)
				(mid 380.961073 -1.303847)
				(end 381.249428 -1.999996)
			)
			(arc
				(start 381.249428 -11.850116)
				(mid 381.839841 -13.275118)
				(end 383.264918 -13.865352)
			)
			(xy 390.444736 -13.865352)
		)
		(stroke
			(width 0)
			(type solid)
		)
		(fill yes)
		(layer "In13.Cu")
		(net "GND")
	)
	(gr_poly
		(pts
			(xy 326.45985 -13.852906) (xy 326.45985 -13.37945) (xy 326.438514 -13.358114)
			(arc
				(start 319.16497 -13.358114)
				(mid 318.098654 -12.916432)
				(end 317.656972 -11.850116)
			)
			(arc
				(start 317.656972 -1.999996)
				(mid 317.219976 -0.944996)
				(end 316.164976 -0.508)
			)
			(arc
				(start 304.165 -0.508)
				(mid 303.11 -0.944996)
				(end 302.673004 -1.999996)
			)
			(arc
				(start 302.673004 -11.850116)
				(mid 302.577528 -12.378214)
				(end 302.30318 -12.839446)
			)
			(xy 302.30318 -12.884912) (xy 302.304196 -12.885928) (xy 302.874426 -12.885928)
			(arc
				(start 302.920908 -12.839446)
				(mid 303.114524 -12.361527)
				(end 303.180496 -11.850116)
			)
			(arc
				(start 303.180496 -1.999996)
				(mid 303.468851 -1.303847)
				(end 304.165 -1.015492)
			)
			(arc
				(start 316.164976 -1.015492)
				(mid 316.861125 -1.303847)
				(end 317.14948 -1.999996)
			)
			(arc
				(start 317.14948 -11.850116)
				(mid 317.739893 -13.275118)
				(end 319.16497 -13.865352)
			)
			(xy 326.438514 -13.865352) (xy 326.447404 -13.865352)
		)
		(stroke
			(width 0)
			(type solid)
		)
		(fill yes)
		(layer "In13.Cu")
		(net "GND")
	)
	(gr_poly
		(pts
			(xy 415.714942 -238.204756) (xy 415.724925 -238.20421) (xy 415.743342 -238.196481) (xy 415.750756 -238.18977)
			(xy 416.56889 -237.37189) (xy 416.590541 -237.351023) (xy 416.639183 -237.315676) (xy 416.692758 -237.288377)
			(xy 416.749945 -237.269801) (xy 416.809335 -237.260405) (xy 416.8394 -237.259876) (xy 418.107622 -237.259876)
			(xy 418.11769 -237.259448) (xy 418.136286 -237.251726) (xy 418.14369 -237.24489) (xy 418.75456 -236.63402)
			(xy 418.761334 -236.626594) (xy 418.768926 -236.607998) (xy 418.769292 -236.597952) (xy 418.769292 -235.256324)
			(xy 418.768877 -235.2463) (xy 418.761211 -235.227776) (xy 418.747037 -235.213598) (xy 418.728516 -235.205927)
			(xy 418.718492 -235.205524) (xy 393.670536 -235.205524) (xy 393.660206 -235.206024) (xy 393.641211 -235.214153)
			(xy 393.626898 -235.229056) (xy 393.622784 -235.238544) (xy 393.583668 -235.342684) (xy 393.591288 -235.37291)
			(xy 393.60348 -235.383578) (xy 393.623486 -235.401787) (xy 393.658673 -235.442876) (xy 393.687708 -235.488519)
			(xy 393.710011 -235.537804) (xy 393.725135 -235.589743) (xy 393.732778 -235.643296) (xy 393.733274 -235.670344)
			(xy 393.732788 -235.697595) (xy 393.725032 -235.751543) (xy 393.709677 -235.803838) (xy 393.687035 -235.853415)
			(xy 393.657569 -235.899265) (xy 393.621878 -235.940456) (xy 393.580687 -235.976147) (xy 393.534837 -236.005613)
			(xy 393.48526 -236.028255) (xy 393.432965 -236.04361) (xy 393.379017 -236.051366) (xy 393.324515 -236.051366)
			(xy 393.270567 -236.04361) (xy 393.218272 -236.028255) (xy 393.168695 -236.005613) (xy 393.122845 -235.976147)
			(xy 393.081654 -235.940456) (xy 393.045963 -235.899265) (xy 393.016497 -235.853415) (xy 392.993855 -235.803838)
			(xy 392.9785 -235.751543) (xy 392.970744 -235.697595) (xy 392.970258 -235.670344) (xy 392.970726 -235.643293)
			(xy 392.97836 -235.589734) (xy 392.993481 -235.537789) (xy 393.015787 -235.4885) (xy 393.04483 -235.442856)
			(xy 393.080028 -235.40177) (xy 393.100052 -235.383578) (xy 393.112244 -235.37291) (xy 393.119864 -235.342684)
			(xy 393.080748 -235.238544) (xy 393.076701 -235.229004) (xy 393.062413 -235.214024) (xy 393.04335 -235.205953)
			(xy 393.032996 -235.205524) (xy 390.920732 -235.205524) (xy 390.910742 -235.206056) (xy 390.892304 -235.213764)
			(xy 390.884918 -235.22051) (xy 389.47852 -236.626908) (xy 392.966446 -236.626908) (xy 392.970517 -236.571286)
			(xy 392.982643 -236.516849) (xy 393.002566 -236.464758) (xy 393.029862 -236.416123) (xy 393.063948 -236.37198)
			(xy 393.104097 -236.333271) (xy 393.149455 -236.30082) (xy 393.199055 -236.275319) (xy 393.251839 -236.257312)
			(xy 393.306682 -236.247182) (xy 393.362416 -236.245145) (xy 393.417853 -236.251245) (xy 393.47181 -236.265351)
			(xy 393.523139 -236.287163) (xy 393.570745 -236.316217) (xy 393.613613 -236.351892) (xy 393.65083 -236.393429)
			(xy 393.681603 -236.439942) (xy 393.705275 -236.490439) (xy 393.721343 -236.543846) (xy 393.729463 -236.599022)
			(xy 393.729972 -236.626908) (xy 393.729463 -236.654794) (xy 393.721343 -236.70997) (xy 393.705275 -236.763377)
			(xy 393.681603 -236.813874) (xy 393.65083 -236.860387) (xy 393.613613 -236.901924) (xy 393.570745 -236.937599)
			(xy 393.523139 -236.966653) (xy 393.47181 -236.988465) (xy 393.417853 -237.002571) (xy 393.362416 -237.008671)
			(xy 393.306682 -237.006634) (xy 393.251839 -236.996504) (xy 393.199055 -236.978497) (xy 393.149455 -236.952996)
			(xy 393.104097 -236.920545) (xy 393.063948 -236.881836) (xy 393.029862 -236.837693) (xy 393.002566 -236.789058)
			(xy 392.982643 -236.736967) (xy 392.970517 -236.68253) (xy 392.966446 -236.626908) (xy 389.47852 -236.626908)
			(xy 389.285988 -236.81944) (xy 389.262435 -236.842389) (xy 389.211038 -236.883416) (xy 389.155368 -236.918427)
			(xy 389.096126 -236.946979) (xy 389.034058 -236.968715) (xy 388.969945 -236.98336) (xy 388.904596 -236.99073)
			(xy 388.871714 -236.991144) (xy 388.315454 -236.991144) (xy 388.289292 -237.009178) (xy 388.283704 -237.024164)
			(xy 388.273827 -237.049666) (xy 388.247818 -237.097772) (xy 388.215202 -237.141669) (xy 388.17665 -237.180456)
			(xy 388.132953 -237.213338) (xy 388.085006 -237.23964) (xy 388.033793 -237.258822) (xy 387.980365 -237.270491)
			(xy 387.925818 -237.274407) (xy 387.871271 -237.270491) (xy 387.817843 -237.258822) (xy 387.76663 -237.23964)
			(xy 387.718683 -237.213338) (xy 387.674986 -237.180456) (xy 387.636434 -237.141669) (xy 387.603818 -237.097772)
			(xy 387.577809 -237.049666) (xy 387.567932 -237.024164) (xy 387.562344 -237.009178) (xy 387.536182 -236.991144)
			(xy 387.158484 -236.991144) (xy 387.148519 -236.991622) (xy 387.130085 -236.999202) (xy 387.12267 -237.005876)
			(xy 386.512054 -237.616492) (xy 386.5052 -237.623887) (xy 386.497455 -237.642486) (xy 386.497068 -237.65256)
			(xy 386.497068 -237.731554) (xy 386.497604 -237.742159) (xy 386.506125 -237.761583) (xy 386.513578 -237.769146)
			(xy 386.576824 -237.827058) (xy 386.596636 -237.833916) (xy 386.607558 -237.8329) (xy 386.641086 -237.831376)
			(xy 386.668452 -237.831846) (xy 386.722623 -237.839665) (xy 386.775121 -237.855145) (xy 386.824867 -237.877967)
			(xy 386.870842 -237.907664) (xy 386.912102 -237.943626) (xy 386.947799 -237.985115) (xy 386.977202 -238.031279)
			(xy 386.999705 -238.081171) (xy 387.014849 -238.133767) (xy 387.019038 -238.160814) (xy 387.021578 -238.179864)
			(xy 387.05028 -238.204756)
		)
		(stroke
			(width 0)
			(type solid)
		)
		(fill yes)
		(layer "In13.Cu")
		(net "GND")
	)
	(gr_poly
		(pts
			(arc
				(start 200.481692 -418.081968)
				(mid 201.086106 -417.953924)
				(end 201.586846 -417.592002)
			)
			(arc
				(start 201.586846 -417.592002)
				(mid 202.42889 -416.98332)
				(end 203.445364 -416.768026)
			)
			(arc
				(start 271.794732 -416.768026)
				(mid 272.811071 -416.983322)
				(end 273.652996 -417.592002)
			)
			(arc
				(start 273.652996 -417.592002)
				(mid 274.153727 -417.953921)
				(end 274.75815 -418.081968)
			)
			(arc
				(start 465.600034 -418.081968)
				(mid 466.655034 -417.644972)
				(end 467.09203 -416.589972)
			)
			(xy 467.09203 -317.499746) (xy 466.584792 -317.499746)
			(arc
				(start 466.584792 -416.589972)
				(mid 466.296527 -417.286032)
				(end 465.600542 -417.574476)
			)
			(xy 414.915604 -417.574476) (xy 414.915604 -417.797742) (xy 400.95424 -417.797742) (xy 400.95424 -417.574476)
			(xy 326.621648 -417.574476) (xy 326.621648 -417.747958) (xy 313.065922 -417.747958) (xy 313.065922 -417.574476)
			(arc
				(start 274.757896 -417.574476)
				(mid 274.359217 -417.490052)
				(end 274.028916 -417.251388)
			)
			(arc
				(start 274.028916 -417.251388)
				(mid 273.01669 -416.519565)
				(end 271.794732 -416.260788)
			)
			(arc
				(start 203.445364 -416.260788)
				(mid 202.223266 -416.519531)
				(end 201.210926 -417.251388)
			)
			(arc
				(start 201.210926 -417.251388)
				(mid 200.880626 -417.490098)
				(end 200.481946 -417.574476)
			)
			(xy 154.673554 -417.574476) (xy 154.673554 -417.693856) (xy 141.027912 -417.693856) (xy 141.027912 -417.574476)
			(xy 66.745104 -417.574476) (xy 66.745104 -417.671758) (xy 53.039772 -417.671758) (xy 53.039772 -417.574476)
			(arc
				(start 1.999996 -417.574476)
				(mid 1.303847 -417.286121)
				(end 1.015492 -416.589972)
			)
			(xy 1.015492 -316.13983) (xy 0.508 -316.13983)
			(arc
				(start 0.508 -416.589972)
				(mid 0.944996 -417.644972)
				(end 1.999996 -418.081968)
			)
		)
		(stroke
			(width 0)
			(type solid)
		)
		(fill yes)
		(layer "In13.Cu")
		(net "GND")
	)
	(gr_poly
		(pts
			(arc
				(start 467.09203 -246.488204)
				(mid 466.978493 -245.917325)
				(end 466.65515 -245.433342)
			)
			(arc
				(start 464.026504 -242.80495)
				(mid 463.482885 -241.991412)
				(end 463.291936 -241.031776)
			)
			(arc
				(start 463.291936 -87.588344)
				(mid 463.482826 -86.628673)
				(end 464.026504 -85.81517)
			)
			(arc
				(start 466.65515 -83.186524)
				(mid 466.978483 -82.702667)
				(end 467.09203 -82.131916)
			)
			(arc
				(start 467.09203 -1.999996)
				(mid 466.655034 -0.944996)
				(end 465.600034 -0.508)
			)
			(arc
				(start 446.265046 -0.508)
				(mid 445.210046 -0.944996)
				(end 444.77305 -1.999996)
			)
			(arc
				(start 444.77305 -11.850116)
				(mid 444.676277 -12.381671)
				(end 444.3984 -12.845034)
			)
			(xy 444.3984 -12.869164) (xy 444.399924 -12.870688)
			(arc
				(start 445.002666 -12.870688)
				(mid 445.20965 -12.378943)
				(end 445.280288 -11.850116)
			)
			(arc
				(start 445.280288 -1.999996)
				(mid 445.568553 -1.303936)
				(end 446.264538 -1.015492)
			)
			(arc
				(start 465.600034 -1.015492)
				(mid 466.296273 -1.303831)
				(end 466.584792 -1.999996)
			)
			(arc
				(start 466.584792 -82.131916)
				(mid 466.509885 -82.508586)
				(end 466.296502 -82.827876)
			)
			(arc
				(start 463.667856 -85.456522)
				(mid 463.014235 -86.434595)
				(end 462.784698 -87.588344)
			)
			(xy 462.784444 -87.588344) (xy 462.784444 -241.031776)
			(arc
				(start 462.784698 -241.031776)
				(mid 463.014268 -242.185519)
				(end 463.667856 -243.163598)
			)
			(arc
				(start 466.296502 -245.79199)
				(mid 466.509882 -246.11143)
				(end 466.584792 -246.488204)
			)
			(xy 466.584792 -311.303416) (xy 467.09203 -311.303416)
		)
		(stroke
			(width 0)
			(type solid)
		)
		(fill yes)
		(layer "In13.Cu")
		(net "GND")
	)
	(gr_poly
		(pts
			(xy 404.786338 -172.07738) (xy 404.796339 -172.076885) (xy 404.814814 -172.069218) (xy 404.828951 -172.055066)
			(xy 404.836597 -172.036582) (xy 404.837138 -172.02658) (xy 404.837138 -168.313354) (xy 404.836705 -168.303289)
			(xy 404.828972 -168.284702) (xy 404.822152 -168.277286) (xy 401.97405 -165.429184) (xy 401.966653 -165.422336)
			(xy 401.948054 -165.414607) (xy 401.937982 -165.414198) (xy 400.621754 -165.414198) (xy 400.611688 -165.413766)
			(xy 400.593095 -165.40604) (xy 400.585686 -165.399212) (xy 400.567144 -165.391592) (xy 397.726154 -165.391592)
			(xy 397.716368 -165.39204) (xy 397.698215 -165.399358) (xy 397.690848 -165.405816) (xy 397.671362 -165.423925)
			(xy 397.62828 -165.455127) (xy 397.581284 -165.480045) (xy 397.531282 -165.498197) (xy 397.479245 -165.50923)
			(xy 397.42618 -165.512932) (xy 397.373115 -165.50923) (xy 397.321078 -165.498197) (xy 397.271076 -165.480045)
			(xy 397.22408 -165.455127) (xy 397.180998 -165.423925) (xy 397.161512 -165.405816) (xy 397.154162 -165.39933)
			(xy 397.136 -165.392) (xy 397.126206 -165.391592) (xy 391.662666 -165.391592) (xy 391.652598 -165.392021)
			(xy 391.634002 -165.399743) (xy 391.626598 -165.406578) (xy 389.983218 -167.049958) (xy 389.976379 -167.057359)
			(xy 389.968663 -167.075957) (xy 389.968232 -167.086026) (xy 389.968232 -168.397174) (xy 398.941796 -168.397174)
			(xy 398.945867 -168.341552) (xy 398.957993 -168.287115) (xy 398.977916 -168.235024) (xy 399.005212 -168.186389)
			(xy 399.039298 -168.142246) (xy 399.079447 -168.103537) (xy 399.124805 -168.071086) (xy 399.174405 -168.045585)
			(xy 399.227189 -168.027578) (xy 399.282032 -168.017448) (xy 399.337766 -168.015411) (xy 399.393203 -168.021511)
			(xy 399.44716 -168.035617) (xy 399.498489 -168.057429) (xy 399.546095 -168.086483) (xy 399.588963 -168.122158)
			(xy 399.62618 -168.163695) (xy 399.656953 -168.210208) (xy 399.680625 -168.260705) (xy 399.696693 -168.314112)
			(xy 399.704813 -168.369288) (xy 399.705322 -168.397174) (xy 399.704813 -168.42506) (xy 399.696693 -168.480236)
			(xy 399.680625 -168.533643) (xy 399.656953 -168.58414) (xy 399.62618 -168.630653) (xy 399.588963 -168.67219)
			(xy 399.546095 -168.707865) (xy 399.498489 -168.736919) (xy 399.44716 -168.758731) (xy 399.393203 -168.772837)
			(xy 399.337766 -168.778937) (xy 399.282032 -168.7769) (xy 399.227189 -168.76677) (xy 399.174405 -168.748763)
			(xy 399.124805 -168.723262) (xy 399.079447 -168.690811) (xy 399.039298 -168.652102) (xy 399.005212 -168.607959)
			(xy 398.977916 -168.559324) (xy 398.957993 -168.507233) (xy 398.945867 -168.452796) (xy 398.941796 -168.397174)
			(xy 389.968232 -168.397174) (xy 389.968232 -168.933876) (xy 389.968648 -168.943898) (xy 389.976315 -168.962418)
			(xy 389.990489 -168.97659) (xy 390.00901 -168.984254) (xy 390.019032 -168.984676) (xy 395.859 -168.984676)
			(xy 395.89184 -168.985111) (xy 395.957114 -168.992405) (xy 396.021163 -169.006948) (xy 396.083187 -169.028555)
			(xy 396.113 -169.042334) (xy 396.123668 -169.047668) (xy 396.147798 -169.04716) (xy 396.241524 -168.998138)
			(xy 396.255494 -168.97858) (xy 396.257272 -168.966642) (xy 396.26191 -168.940023) (xy 396.277709 -168.888351)
			(xy 396.30064 -168.839426) (xy 396.330245 -168.794225) (xy 396.365931 -168.753654) (xy 396.406985 -168.718523)
			(xy 396.452584 -168.689536) (xy 396.501817 -168.667274) (xy 396.553699 -168.65218) (xy 396.607192 -168.644557)
			(xy 396.634208 -168.644062) (xy 396.66146 -168.644548) (xy 396.715408 -168.652306) (xy 396.767704 -168.667661)
			(xy 396.817282 -168.690302) (xy 396.863133 -168.719768) (xy 396.904325 -168.755459) (xy 396.940018 -168.796649)
			(xy 396.969487 -168.842499) (xy 396.992131 -168.892076) (xy 397.00749 -168.94437) (xy 397.01525 -168.998318)
			(xy 397.015716 -169.02557) (xy 397.015227 -169.05356) (xy 397.007051 -169.108938) (xy 396.99087 -169.162528)
			(xy 396.967033 -169.213178) (xy 396.93605 -169.2598) (xy 396.898586 -169.301395) (xy 396.855447 -169.337069)
			(xy 396.807557 -169.366056) (xy 396.755946 -169.387734) (xy 396.72895 -169.39514) (xy 396.715742 -169.398442)
			(xy 396.696184 -169.417746) (xy 396.66926 -169.516044) (xy 396.667266 -169.524765) (xy 396.668809 -169.542579)
			(xy 396.676357 -169.558788) (xy 396.682468 -169.56532) (xy 397.203168 -170.08602) (xy 397.210577 -170.092707)
			(xy 397.229013 -170.100298) (xy 397.238982 -170.100752) (xy 397.275558 -170.100752) (xy 397.285581 -170.100339)
			(xy 397.304104 -170.092675) (xy 397.318278 -170.078499) (xy 397.32594 -170.059975) (xy 397.326358 -170.049952)
			(xy 397.326358 -170.038268) (xy 397.316452 -170.017694) (xy 397.307054 -170.010328) (xy 397.284859 -169.992119)
			(xy 397.245665 -169.950171) (xy 397.213193 -169.902829) (xy 397.188173 -169.851159) (xy 397.17117 -169.796326)
			(xy 397.162567 -169.739566) (xy 397.16202 -169.710862) (xy 397.162506 -169.683611) (xy 397.170262 -169.629663)
			(xy 397.185617 -169.577368) (xy 397.208259 -169.527791) (xy 397.237725 -169.481941) (xy 397.273416 -169.44075)
			(xy 397.314607 -169.405059) (xy 397.360457 -169.375593) (xy 397.410034 -169.352951) (xy 397.462329 -169.337596)
			(xy 397.516277 -169.32984) (xy 397.570779 -169.32984) (xy 397.624727 -169.337596) (xy 397.677022 -169.352951)
			(xy 397.726599 -169.375593) (xy 397.772449 -169.405059) (xy 397.81364 -169.44075) (xy 397.849331 -169.481941)
			(xy 397.878797 -169.527791) (xy 397.901439 -169.577368) (xy 397.916794 -169.629663) (xy 397.92455 -169.683611)
			(xy 397.925036 -169.710862) (xy 397.924439 -169.741398) (xy 397.914724 -169.801692) (xy 397.895536 -169.859671)
			(xy 397.867363 -169.913857) (xy 397.849598 -169.9387) (xy 397.840962 -169.950384) (xy 397.838422 -169.978832)
			(xy 397.885666 -170.072812) (xy 397.8903 -170.08098) (xy 397.904239 -170.09354) (xy 397.921751 -170.100278)
			(xy 397.931132 -170.100752) (xy 399.13433 -170.100752) (xy 399.167207 -170.10123) (xy 399.232546 -170.108622)
			(xy 399.296648 -170.123277) (xy 399.358708 -170.14501) (xy 399.417947 -170.173549) (xy 399.473622 -170.208535)
			(xy 399.525035 -170.24953) (xy 399.548604 -170.272456) (xy 400.616674 -171.340526) (xy 400.639584 -171.364104)
			(xy 400.680557 -171.415518) (xy 400.715518 -171.471196) (xy 400.744027 -171.530437) (xy 400.765725 -171.592497)
			(xy 400.78034 -171.656596) (xy 400.787688 -171.721928) (xy 400.788124 -171.7548) (xy 400.788124 -171.957492)
			(xy 400.788587 -171.967126) (xy 400.795764 -171.985013) (xy 400.802094 -171.99229) (xy 400.822668 -172.014134)
			(xy 400.829055 -172.020424) (xy 400.845055 -172.028483) (xy 400.85391 -172.029882) (xy 400.877519 -172.032873)
			(xy 400.923794 -172.043981) (xy 400.968324 -172.06077) (xy 400.989546 -172.071538) (xy 400.995134 -172.074332)
			(xy 401.007072 -172.07738)
		)
		(stroke
			(width 0)
			(type solid)
		)
		(fill yes)
		(layer "In13.Cu")
		(net "GND")
	)
	(gr_poly
		(pts
			(arc
				(start 1.015492 -246.48795)
				(mid 1.090466 -246.111319)
				(end 1.303782 -245.79199)
			)
			(arc
				(start 3.93192 -243.163852)
				(mid 4.58575 -242.18556)
				(end 4.815332 -241.031522)
			)
			(arc
				(start 4.815332 -87.588344)
				(mid 4.585694 -86.434435)
				(end 3.93192 -85.456268)
			)
			(arc
				(start 1.303528 -82.827876)
				(mid 1.090411 -82.508641)
				(end 1.015492 -82.13217)
			)
			(arc
				(start 1.015492 -1.999996)
				(mid 1.303847 -1.303847)
				(end 1.999996 -1.015492)
			)
			(arc
				(start 5.964936 -1.015492)
				(mid 6.661085 -1.303847)
				(end 6.94944 -1.999996)
			)
			(arc
				(start 6.94944 -11.850116)
				(mid 7.539853 -13.275118)
				(end 8.96493 -13.865352)
			)
			(xy 16.2814 -13.865352) (xy 16.371316 -13.775436) (xy 16.371316 -13.44803) (xy 16.2814 -13.358114)
			(arc
				(start 8.96493 -13.358114)
				(mid 7.898614 -12.916432)
				(end 7.456932 -11.850116)
			)
			(arc
				(start 7.456932 -1.999996)
				(mid 7.019936 -0.944996)
				(end 5.964936 -0.508)
			)
			(arc
				(start 1.999996 -0.508)
				(mid 0.944996 -0.944996)
				(end 0.508 -1.999996)
			)
			(arc
				(start 0.508 -82.131916)
				(mid 0.621601 -82.702644)
				(end 0.94488 -83.186524)
			)
			(arc
				(start 3.573272 -85.81517)
				(mid 4.117081 -86.628665)
				(end 4.308094 -87.588344)
			)
			(arc
				(start 4.308094 -241.031522)
				(mid 4.117082 -241.991334)
				(end 3.573272 -242.80495)
			)
			(arc
				(start 0.94488 -245.433342)
				(mid 0.621552 -245.917331)
				(end 0.508 -246.488204)
			)
			(xy 0.508 -307.918358) (xy 1.015492 -307.918358)
		)
		(stroke
			(width 0)
			(type solid)
		)
		(fill yes)
		(layer "In13.Cu")
		(net "GND")
	)
	(gr_poly
		(pts
			(xy 213.304374 -98.700082) (xy 213.303873 -98.599942) (xy 213.29586 -98.399822) (xy 213.279846 -98.200182)
			(xy 213.255858 -98.001343) (xy 213.223934 -97.803624) (xy 213.184124 -97.607339) (xy 213.136494 -97.412805)
			(xy 213.081118 -97.220332) (xy 213.018085 -97.030229) (xy 212.947497 -96.8428) (xy 212.869467 -96.658345)
			(xy 212.784119 -96.47716) (xy 212.69159 -96.299535) (xy 212.592029 -96.125754) (xy 212.485595 -95.956095)
			(xy 212.372458 -95.790831) (xy 212.252799 -95.630226) (xy 212.12681 -95.474537) (xy 211.994693 -95.324013)
			(xy 211.85666 -95.178895) (xy 211.712931 -95.039417) (xy 211.563736 -94.905801) (xy 211.409315 -94.778261)
			(xy 211.249915 -94.657001) (xy 211.085791 -94.542216) (xy 210.917206 -94.43409) (xy 210.74443 -94.332795)
			(xy 210.567739 -94.238493) (xy 210.387417 -94.151337) (xy 210.203752 -94.071465) (xy 210.017039 -93.999006)
			(xy 209.827576 -93.934074) (xy 209.635666 -93.876776) (xy 209.441618 -93.827201) (xy 209.245742 -93.785429)
			(xy 209.048352 -93.751529) (xy 208.849763 -93.725552) (xy 208.650294 -93.707542) (xy 208.450264 -93.697527)
			(xy 208.249993 -93.695523) (xy 208.049803 -93.701534) (xy 207.850013 -93.715549) (xy 207.650945 -93.737547)
			(xy 207.452915 -93.767492) (xy 207.256243 -93.805335) (xy 207.061242 -93.851017) (xy 206.868224 -93.904465)
			(xy 206.6775 -93.965592) (xy 206.489374 -94.034301) (xy 206.304148 -94.110482) (xy 206.122118 -94.194013)
			(xy 205.943576 -94.28476) (xy 205.768807 -94.382578) (xy 205.598093 -94.487309) (xy 205.431705 -94.598788)
			(xy 205.26991 -94.716833) (xy 205.112968 -94.841258) (xy 204.96113 -94.971862) (xy 204.814639 -95.108437)
			(xy 204.67373 -95.250764) (xy 204.538627 -95.398614) (xy 204.409549 -95.551751) (xy 204.2867 -95.70993)
			(xy 204.170279 -95.872897) (xy 204.060471 -96.040392) (xy 203.957453 -96.212146) (xy 203.861389 -96.387885)
			(xy 203.772433 -96.567326) (xy 203.690727 -96.750182) (xy 203.616403 -96.936161) (xy 203.54958 -97.124965)
			(xy 203.490364 -97.316292) (xy 203.43885 -97.509834) (xy 203.395121 -97.705282) (xy 203.359247 -97.902324)
			(xy 203.331285 -98.100643) (xy 203.31128 -98.299922) (xy 203.299264 -98.499842) (xy 203.295257 -98.700082)
			(xy 203.296593 -98.766863) (xy 206.090008 -98.766863) (xy 206.090008 -98.633301) (xy 206.098072 -98.499983)
			(xy 206.114172 -98.367395) (xy 206.138247 -98.236021) (xy 206.17021 -98.10634) (xy 206.209945 -97.978826)
			(xy 206.257307 -97.853943) (xy 206.312122 -97.732148) (xy 206.374192 -97.613885) (xy 206.443288 -97.499586)
			(xy 206.51916 -97.389666) (xy 206.60153 -97.284529) (xy 206.690098 -97.184556) (xy 206.78454 -97.090114)
			(xy 206.884513 -97.001546) (xy 206.98965 -96.919176) (xy 207.09957 -96.843304) (xy 207.213869 -96.774208)
			(xy 207.332132 -96.712138) (xy 207.453927 -96.657323) (xy 207.57881 -96.609961) (xy 207.706324 -96.570226)
			(xy 207.836005 -96.538263) (xy 207.967379 -96.514188) (xy 208.099967 -96.498088) (xy 208.233285 -96.490024)
			(xy 208.366847 -96.490024) (xy 208.500165 -96.498088) (xy 208.632753 -96.514188) (xy 208.764127 -96.538263)
			(xy 208.893808 -96.570226) (xy 209.021322 -96.609961) (xy 209.146205 -96.657323) (xy 209.268 -96.712138)
			(xy 209.386263 -96.774208) (xy 209.500562 -96.843304) (xy 209.610482 -96.919176) (xy 209.715619 -97.001546)
			(xy 209.815592 -97.090114) (xy 209.910034 -97.184556) (xy 209.998602 -97.284529) (xy 210.080972 -97.389666)
			(xy 210.156844 -97.499586) (xy 210.22594 -97.613885) (xy 210.28801 -97.732148) (xy 210.342825 -97.853943)
			(xy 210.390187 -97.978826) (xy 210.429922 -98.10634) (xy 210.461885 -98.236021) (xy 210.48596 -98.367395)
			(xy 210.50206 -98.499983) (xy 210.510124 -98.633301) (xy 210.510628 -98.700082) (xy 210.510124 -98.766863)
			(xy 210.50206 -98.900181) (xy 210.48596 -99.032769) (xy 210.461885 -99.164143) (xy 210.429922 -99.293824)
			(xy 210.390187 -99.421338) (xy 210.342825 -99.546221) (xy 210.28801 -99.668016) (xy 210.22594 -99.786279)
			(xy 210.156844 -99.900578) (xy 210.080972 -100.010498) (xy 209.998602 -100.115635) (xy 209.910034 -100.215608)
			(xy 209.815592 -100.31005) (xy 209.715619 -100.398618) (xy 209.610482 -100.480988) (xy 209.500562 -100.55686)
			(xy 209.386263 -100.625956) (xy 209.268 -100.688026) (xy 209.146205 -100.742841) (xy 209.021322 -100.790203)
			(xy 208.893808 -100.829938) (xy 208.764127 -100.861901) (xy 208.632753 -100.885976) (xy 208.500165 -100.902076)
			(xy 208.366847 -100.91014) (xy 208.233285 -100.91014) (xy 208.099967 -100.902076) (xy 207.967379 -100.885976)
			(xy 207.836005 -100.861901) (xy 207.706324 -100.829938) (xy 207.57881 -100.790203) (xy 207.453927 -100.742841)
			(xy 207.332132 -100.688026) (xy 207.213869 -100.625956) (xy 207.09957 -100.55686) (xy 206.98965 -100.480988)
			(xy 206.884513 -100.398618) (xy 206.78454 -100.31005) (xy 206.690098 -100.215608) (xy 206.60153 -100.115635)
			(xy 206.51916 -100.010498) (xy 206.443288 -99.900578) (xy 206.374192 -99.786279) (xy 206.312122 -99.668016)
			(xy 206.257307 -99.546221) (xy 206.209945 -99.421338) (xy 206.17021 -99.293824) (xy 206.138247 -99.164143)
			(xy 206.114172 -99.032769) (xy 206.098072 -98.900181) (xy 206.090008 -98.766863) (xy 203.296593 -98.766863)
			(xy 203.299264 -98.900322) (xy 203.31128 -99.100242) (xy 203.331285 -99.299521) (xy 203.359247 -99.49784)
			(xy 203.395121 -99.694882) (xy 203.43885 -99.89033) (xy 203.490364 -100.083872) (xy 203.54958 -100.275199)
			(xy 203.616403 -100.464003) (xy 203.690727 -100.649982) (xy 203.772433 -100.832838) (xy 203.861389 -101.012279)
			(xy 203.957453 -101.188018) (xy 204.060471 -101.359772) (xy 204.170279 -101.527267) (xy 204.2867 -101.690234)
			(xy 204.409549 -101.848413) (xy 204.538627 -102.00155) (xy 204.67373 -102.1494) (xy 204.814639 -102.291727)
			(xy 204.96113 -102.428302) (xy 205.112968 -102.558906) (xy 205.26991 -102.683331) (xy 205.431705 -102.801376)
			(xy 205.598093 -102.912855) (xy 205.768807 -103.017586) (xy 205.943576 -103.115404) (xy 206.122118 -103.206151)
			(xy 206.304148 -103.289682) (xy 206.489374 -103.365863) (xy 206.6775 -103.434572) (xy 206.868224 -103.495699)
			(xy 207.061242 -103.549147) (xy 207.256243 -103.594829) (xy 207.452915 -103.632672) (xy 207.650945 -103.662617)
			(xy 207.850013 -103.684615) (xy 208.049803 -103.69863) (xy 208.249993 -103.704641) (xy 208.450264 -103.702637)
			(xy 208.650294 -103.692622) (xy 208.849763 -103.674612) (xy 209.048352 -103.648635) (xy 209.245742 -103.614735)
			(xy 209.441618 -103.572963) (xy 209.635666 -103.523388) (xy 209.827576 -103.46609) (xy 210.017039 -103.401158)
			(xy 210.203752 -103.328699) (xy 210.387417 -103.248827) (xy 210.567739 -103.161671) (xy 210.74443 -103.067369)
			(xy 210.917206 -102.966074) (xy 211.085791 -102.857948) (xy 211.249915 -102.743163) (xy 211.409315 -102.621903)
			(xy 211.563736 -102.494363) (xy 211.712931 -102.360747) (xy 211.85666 -102.221269) (xy 211.994693 -102.076151)
			(xy 212.12681 -101.925627) (xy 212.252799 -101.769938) (xy 212.372458 -101.609333) (xy 212.485595 -101.444069)
			(xy 212.592029 -101.27441) (xy 212.69159 -101.100629) (xy 212.784119 -100.923004) (xy 212.869467 -100.741819)
			(xy 212.947497 -100.557364) (xy 213.018085 -100.369935) (xy 213.081118 -100.179832) (xy 213.136494 -99.987359)
			(xy 213.184124 -99.792825) (xy 213.223934 -99.59654) (xy 213.255858 -99.398821) (xy 213.279846 -99.199982)
			(xy 213.29586 -99.000342) (xy 213.303873 -98.800222)
		)
		(stroke
			(width 0)
			(type solid)
		)
		(fill yes)
		(layer "In13.Cu")
		(net "GND")
	)
	(gr_poly
		(pts
			(xy 264.304272 -98.700082) (xy 264.303771 -98.599942) (xy 264.295758 -98.399822) (xy 264.279744 -98.200182)
			(xy 264.255756 -98.001343) (xy 264.223832 -97.803624) (xy 264.184022 -97.607339) (xy 264.136392 -97.412805)
			(xy 264.081016 -97.220332) (xy 264.017983 -97.030229) (xy 263.947395 -96.8428) (xy 263.869365 -96.658345)
			(xy 263.784017 -96.47716) (xy 263.691488 -96.299535) (xy 263.591927 -96.125754) (xy 263.485493 -95.956095)
			(xy 263.372356 -95.790831) (xy 263.252697 -95.630226) (xy 263.126708 -95.474537) (xy 262.994591 -95.324013)
			(xy 262.856558 -95.178895) (xy 262.712829 -95.039417) (xy 262.563634 -94.905801) (xy 262.409213 -94.778261)
			(xy 262.249813 -94.657001) (xy 262.085689 -94.542216) (xy 261.917104 -94.43409) (xy 261.744328 -94.332795)
			(xy 261.567637 -94.238493) (xy 261.387315 -94.151337) (xy 261.20365 -94.071465) (xy 261.016937 -93.999006)
			(xy 260.827474 -93.934074) (xy 260.635564 -93.876776) (xy 260.441516 -93.827201) (xy 260.24564 -93.785429)
			(xy 260.04825 -93.751529) (xy 259.849661 -93.725552) (xy 259.650192 -93.707542) (xy 259.450162 -93.697527)
			(xy 259.249891 -93.695523) (xy 259.049701 -93.701534) (xy 258.849911 -93.715549) (xy 258.650843 -93.737547)
			(xy 258.452813 -93.767492) (xy 258.256141 -93.805335) (xy 258.06114 -93.851017) (xy 257.868122 -93.904465)
			(xy 257.677398 -93.965592) (xy 257.489272 -94.034301) (xy 257.304046 -94.110482) (xy 257.122016 -94.194013)
			(xy 256.943474 -94.28476) (xy 256.768705 -94.382578) (xy 256.597991 -94.487309) (xy 256.431603 -94.598788)
			(xy 256.269808 -94.716833) (xy 256.112866 -94.841258) (xy 255.961028 -94.971862) (xy 255.814537 -95.108437)
			(xy 255.673628 -95.250764) (xy 255.538525 -95.398614) (xy 255.409447 -95.551751) (xy 255.286598 -95.70993)
			(xy 255.170177 -95.872897) (xy 255.060369 -96.040392) (xy 254.957351 -96.212146) (xy 254.861287 -96.387885)
			(xy 254.772331 -96.567326) (xy 254.690625 -96.750182) (xy 254.616301 -96.936161) (xy 254.549478 -97.124965)
			(xy 254.490262 -97.316292) (xy 254.438748 -97.509834) (xy 254.395019 -97.705282) (xy 254.359145 -97.902324)
			(xy 254.331183 -98.100643) (xy 254.311178 -98.299922) (xy 254.299162 -98.499842) (xy 254.295155 -98.700082)
			(xy 254.296491 -98.766863) (xy 257.089906 -98.766863) (xy 257.089906 -98.633301) (xy 257.09797 -98.499983)
			(xy 257.11407 -98.367395) (xy 257.138145 -98.236021) (xy 257.170108 -98.10634) (xy 257.209843 -97.978826)
			(xy 257.257205 -97.853943) (xy 257.31202 -97.732148) (xy 257.37409 -97.613885) (xy 257.443186 -97.499586)
			(xy 257.519058 -97.389666) (xy 257.601428 -97.284529) (xy 257.689996 -97.184556) (xy 257.784438 -97.090114)
			(xy 257.884411 -97.001546) (xy 257.989548 -96.919176) (xy 258.099468 -96.843304) (xy 258.213767 -96.774208)
			(xy 258.33203 -96.712138) (xy 258.453825 -96.657323) (xy 258.578708 -96.609961) (xy 258.706222 -96.570226)
			(xy 258.835903 -96.538263) (xy 258.967277 -96.514188) (xy 259.099865 -96.498088) (xy 259.233183 -96.490024)
			(xy 259.366745 -96.490024) (xy 259.500063 -96.498088) (xy 259.632651 -96.514188) (xy 259.764025 -96.538263)
			(xy 259.893706 -96.570226) (xy 260.02122 -96.609961) (xy 260.146103 -96.657323) (xy 260.267898 -96.712138)
			(xy 260.386161 -96.774208) (xy 260.50046 -96.843304) (xy 260.61038 -96.919176) (xy 260.715517 -97.001546)
			(xy 260.81549 -97.090114) (xy 260.909932 -97.184556) (xy 260.9985 -97.284529) (xy 261.08087 -97.389666)
			(xy 261.156742 -97.499586) (xy 261.225838 -97.613885) (xy 261.287908 -97.732148) (xy 261.342723 -97.853943)
			(xy 261.390085 -97.978826) (xy 261.42982 -98.10634) (xy 261.461783 -98.236021) (xy 261.485858 -98.367395)
			(xy 261.501958 -98.499983) (xy 261.510022 -98.633301) (xy 261.510526 -98.700082) (xy 261.510022 -98.766863)
			(xy 261.501958 -98.900181) (xy 261.485858 -99.032769) (xy 261.461783 -99.164143) (xy 261.42982 -99.293824)
			(xy 261.390085 -99.421338) (xy 261.342723 -99.546221) (xy 261.287908 -99.668016) (xy 261.225838 -99.786279)
			(xy 261.156742 -99.900578) (xy 261.08087 -100.010498) (xy 260.9985 -100.115635) (xy 260.909932 -100.215608)
			(xy 260.81549 -100.31005) (xy 260.715517 -100.398618) (xy 260.61038 -100.480988) (xy 260.50046 -100.55686)
			(xy 260.386161 -100.625956) (xy 260.267898 -100.688026) (xy 260.146103 -100.742841) (xy 260.02122 -100.790203)
			(xy 259.893706 -100.829938) (xy 259.764025 -100.861901) (xy 259.632651 -100.885976) (xy 259.500063 -100.902076)
			(xy 259.366745 -100.91014) (xy 259.233183 -100.91014) (xy 259.099865 -100.902076) (xy 258.967277 -100.885976)
			(xy 258.835903 -100.861901) (xy 258.706222 -100.829938) (xy 258.578708 -100.790203) (xy 258.453825 -100.742841)
			(xy 258.33203 -100.688026) (xy 258.213767 -100.625956) (xy 258.099468 -100.55686) (xy 257.989548 -100.480988)
			(xy 257.884411 -100.398618) (xy 257.784438 -100.31005) (xy 257.689996 -100.215608) (xy 257.601428 -100.115635)
			(xy 257.519058 -100.010498) (xy 257.443186 -99.900578) (xy 257.37409 -99.786279) (xy 257.31202 -99.668016)
			(xy 257.257205 -99.546221) (xy 257.209843 -99.421338) (xy 257.170108 -99.293824) (xy 257.138145 -99.164143)
			(xy 257.11407 -99.032769) (xy 257.09797 -98.900181) (xy 257.089906 -98.766863) (xy 254.296491 -98.766863)
			(xy 254.299162 -98.900322) (xy 254.311178 -99.100242) (xy 254.331183 -99.299521) (xy 254.359145 -99.49784)
			(xy 254.395019 -99.694882) (xy 254.438748 -99.89033) (xy 254.490262 -100.083872) (xy 254.549478 -100.275199)
			(xy 254.616301 -100.464003) (xy 254.690625 -100.649982) (xy 254.772331 -100.832838) (xy 254.861287 -101.012279)
			(xy 254.957351 -101.188018) (xy 255.060369 -101.359772) (xy 255.170177 -101.527267) (xy 255.286598 -101.690234)
			(xy 255.409447 -101.848413) (xy 255.538525 -102.00155) (xy 255.673628 -102.1494) (xy 255.814537 -102.291727)
			(xy 255.961028 -102.428302) (xy 256.112866 -102.558906) (xy 256.269808 -102.683331) (xy 256.431603 -102.801376)
			(xy 256.597991 -102.912855) (xy 256.768705 -103.017586) (xy 256.943474 -103.115404) (xy 257.122016 -103.206151)
			(xy 257.304046 -103.289682) (xy 257.489272 -103.365863) (xy 257.677398 -103.434572) (xy 257.868122 -103.495699)
			(xy 258.06114 -103.549147) (xy 258.256141 -103.594829) (xy 258.452813 -103.632672) (xy 258.650843 -103.662617)
			(xy 258.849911 -103.684615) (xy 259.049701 -103.69863) (xy 259.249891 -103.704641) (xy 259.450162 -103.702637)
			(xy 259.650192 -103.692622) (xy 259.849661 -103.674612) (xy 260.04825 -103.648635) (xy 260.24564 -103.614735)
			(xy 260.441516 -103.572963) (xy 260.635564 -103.523388) (xy 260.827474 -103.46609) (xy 261.016937 -103.401158)
			(xy 261.20365 -103.328699) (xy 261.387315 -103.248827) (xy 261.567637 -103.161671) (xy 261.744328 -103.067369)
			(xy 261.917104 -102.966074) (xy 262.085689 -102.857948) (xy 262.249813 -102.743163) (xy 262.409213 -102.621903)
			(xy 262.563634 -102.494363) (xy 262.712829 -102.360747) (xy 262.856558 -102.221269) (xy 262.994591 -102.076151)
			(xy 263.126708 -101.925627) (xy 263.252697 -101.769938) (xy 263.372356 -101.609333) (xy 263.485493 -101.444069)
			(xy 263.591927 -101.27441) (xy 263.691488 -101.100629) (xy 263.784017 -100.923004) (xy 263.869365 -100.741819)
			(xy 263.947395 -100.557364) (xy 264.017983 -100.369935) (xy 264.081016 -100.179832) (xy 264.136392 -99.987359)
			(xy 264.184022 -99.792825) (xy 264.223832 -99.59654) (xy 264.255756 -99.398821) (xy 264.279744 -99.199982)
			(xy 264.295758 -99.000342) (xy 264.303771 -98.800222)
		)
		(stroke
			(width 0)
			(type solid)
		)
		(fill yes)
		(layer "In13.Cu")
		(net "GND")
	)
	(gr_poly
		(pts
			(xy 378.390404 -237.555024) (xy 378.398865 -237.562573) (xy 378.420228 -237.57009) (xy 378.431552 -237.569502)
			(xy 378.521468 -237.560104) (xy 378.541026 -237.548166) (xy 378.547376 -237.538514) (xy 378.556993 -237.524154)
			(xy 378.578755 -237.497304) (xy 378.59081 -237.48492) (xy 381.103886 -234.971844) (xy 381.122678 -234.953758)
			(xy 381.164889 -234.923127) (xy 381.211374 -234.89948) (xy 381.260987 -234.883399) (xy 381.312505 -234.875281)
			(xy 381.338582 -234.874816) (xy 387.494018 -234.874816) (xy 387.504004 -234.874275) (xy 387.522433 -234.866559)
			(xy 387.529832 -234.85983) (xy 388.401814 -233.987848) (xy 388.408661 -233.980451) (xy 388.41639 -233.961852)
			(xy 388.4168 -233.95178) (xy 388.4168 -233.706924) (xy 388.416385 -233.6969) (xy 388.408719 -233.678374)
			(xy 388.394546 -233.664195) (xy 388.376024 -233.65652) (xy 388.366 -233.656124) (xy 386.795264 -233.656124)
			(xy 386.78678 -233.656436) (xy 386.770749 -233.661997) (xy 386.757439 -233.67252) (xy 386.752592 -233.679492)
			(xy 386.699252 -233.762296) (xy 386.697474 -233.788204) (xy 386.702808 -233.799888) (xy 386.713615 -233.824811)
			(xy 386.72887 -233.876946) (xy 386.736591 -233.930716) (xy 386.737098 -233.957876) (xy 386.736612 -233.985127)
			(xy 386.728856 -234.039075) (xy 386.713501 -234.09137) (xy 386.690859 -234.140947) (xy 386.661393 -234.186797)
			(xy 386.625702 -234.227988) (xy 386.584511 -234.263679) (xy 386.538661 -234.293145) (xy 386.489084 -234.315787)
			(xy 386.436789 -234.331142) (xy 386.382841 -234.338898) (xy 386.328339 -234.338898) (xy 386.274391 -234.331142)
			(xy 386.222096 -234.315787) (xy 386.172519 -234.293145) (xy 386.126669 -234.263679) (xy 386.085478 -234.227988)
			(xy 386.049787 -234.186797) (xy 386.020321 -234.140947) (xy 385.997679 -234.09137) (xy 385.982324 -234.039075)
			(xy 385.974568 -233.985127) (xy 385.974082 -233.957876) (xy 385.974559 -233.930713) (xy 385.98227 -233.876938)
			(xy 385.997548 -233.824805) (xy 386.008372 -233.799888) (xy 386.013706 -233.788204) (xy 386.011928 -233.762296)
			(xy 385.958588 -233.679492) (xy 385.953736 -233.672529) (xy 385.940412 -233.662031) (xy 385.924396 -233.656442)
			(xy 385.915916 -233.656124) (xy 385.29514 -233.656124) (xy 385.286658 -233.65644) (xy 385.270633 -233.662006)
			(xy 385.257329 -233.672531) (xy 385.252468 -233.679492) (xy 385.199128 -233.762296) (xy 385.19735 -233.788204)
			(xy 385.202684 -233.799888) (xy 385.213491 -233.824811) (xy 385.228747 -233.876946) (xy 385.236469 -233.930716)
			(xy 385.236974 -233.957876) (xy 385.236488 -233.985127) (xy 385.228732 -234.039075) (xy 385.213377 -234.09137)
			(xy 385.190735 -234.140947) (xy 385.161269 -234.186797) (xy 385.125578 -234.227988) (xy 385.084387 -234.263679)
			(xy 385.038537 -234.293145) (xy 384.98896 -234.315787) (xy 384.936665 -234.331142) (xy 384.882717 -234.338898)
			(xy 384.828215 -234.338898) (xy 384.774267 -234.331142) (xy 384.721972 -234.315787) (xy 384.672395 -234.293145)
			(xy 384.626545 -234.263679) (xy 384.585354 -234.227988) (xy 384.549663 -234.186797) (xy 384.520197 -234.140947)
			(xy 384.497555 -234.09137) (xy 384.4822 -234.039075) (xy 384.474444 -233.985127) (xy 384.473958 -233.957876)
			(xy 384.474435 -233.930713) (xy 384.482146 -233.876938) (xy 384.497422 -233.824805) (xy 384.508248 -233.799888)
			(xy 384.513582 -233.788204) (xy 384.511804 -233.762296) (xy 384.458464 -233.679492) (xy 384.453611 -233.672531)
			(xy 384.440286 -233.66204) (xy 384.424271 -233.656458) (xy 384.415792 -233.656124) (xy 384.089148 -233.656124)
			(xy 384.056275 -233.655693) (xy 383.99094 -233.648356) (xy 383.926839 -233.633747) (xy 383.864777 -233.612049)
			(xy 383.805536 -233.583536) (xy 383.749863 -233.548567) (xy 383.698456 -233.507581) (xy 383.674874 -233.484674)
			(xy 383.144014 -232.953814) (xy 383.13667 -232.947) (xy 383.118208 -232.93926) (xy 383.1082 -232.938828)
			(xy 377.465336 -232.938828) (xy 377.455312 -232.939242) (xy 377.436788 -232.946906) (xy 377.422611 -232.961081)
			(xy 377.414944 -232.979604) (xy 377.414536 -232.989628) (xy 377.414536 -233.99496) (xy 381.97358 -233.99496)
			(xy 381.977651 -233.939338) (xy 381.989777 -233.884901) (xy 382.0097 -233.83281) (xy 382.036996 -233.784175)
			(xy 382.071082 -233.740032) (xy 382.111231 -233.701323) (xy 382.156589 -233.668872) (xy 382.206189 -233.643371)
			(xy 382.258973 -233.625364) (xy 382.313816 -233.615234) (xy 382.36955 -233.613197) (xy 382.424987 -233.619297)
			(xy 382.478944 -233.633403) (xy 382.530273 -233.655215) (xy 382.577879 -233.684269) (xy 382.620747 -233.719944)
			(xy 382.657964 -233.761481) (xy 382.688737 -233.807994) (xy 382.712409 -233.858491) (xy 382.728477 -233.911898)
			(xy 382.736597 -233.967074) (xy 382.737041 -233.991404) (xy 382.973578 -233.991404) (xy 382.977649 -233.935782)
			(xy 382.989775 -233.881345) (xy 383.009698 -233.829254) (xy 383.036994 -233.780619) (xy 383.07108 -233.736476)
			(xy 383.111229 -233.697767) (xy 383.156587 -233.665316) (xy 383.206187 -233.639815) (xy 383.258971 -233.621808)
			(xy 383.313814 -233.611678) (xy 383.369548 -233.609641) (xy 383.424985 -233.615741) (xy 383.478942 -233.629847)
			(xy 383.530271 -233.651659) (xy 383.577877 -233.680713) (xy 383.620745 -233.716388) (xy 383.657962 -233.757925)
			(xy 383.688735 -233.804438) (xy 383.712407 -233.854935) (xy 383.728475 -233.908342) (xy 383.736595 -233.963518)
			(xy 383.737104 -233.991404) (xy 383.736595 -234.01929) (xy 383.728475 -234.074466) (xy 383.712407 -234.127873)
			(xy 383.688735 -234.17837) (xy 383.657962 -234.224883) (xy 383.620745 -234.26642) (xy 383.577877 -234.302095)
			(xy 383.530271 -234.331149) (xy 383.478942 -234.352961) (xy 383.424985 -234.367067) (xy 383.369548 -234.373167)
			(xy 383.313814 -234.37113) (xy 383.258971 -234.361) (xy 383.206187 -234.342993) (xy 383.156587 -234.317492)
			(xy 383.111229 -234.285041) (xy 383.07108 -234.246332) (xy 383.036994 -234.202189) (xy 383.009698 -234.153554)
			(xy 382.989775 -234.101463) (xy 382.977649 -234.047026) (xy 382.973578 -233.991404) (xy 382.737041 -233.991404)
			(xy 382.737106 -233.99496) (xy 382.736597 -234.022846) (xy 382.728477 -234.078022) (xy 382.712409 -234.131429)
			(xy 382.688737 -234.181926) (xy 382.657964 -234.228439) (xy 382.620747 -234.269976) (xy 382.577879 -234.305651)
			(xy 382.530273 -234.334705) (xy 382.478944 -234.356517) (xy 382.424987 -234.370623) (xy 382.36955 -234.376723)
			(xy 382.313816 -234.374686) (xy 382.258973 -234.364556) (xy 382.206189 -234.346549) (xy 382.156589 -234.321048)
			(xy 382.111231 -234.288597) (xy 382.071082 -234.249888) (xy 382.036996 -234.205745) (xy 382.0097 -234.15711)
			(xy 381.989777 -234.105019) (xy 381.977651 -234.050582) (xy 381.97358 -233.99496) (xy 377.414536 -233.99496)
			(xy 377.414536 -234.393486) (xy 377.414874 -234.402376) (xy 377.420961 -234.419082) (xy 377.432404 -234.432691)
			(xy 377.439936 -234.437428) (xy 377.528074 -234.488228) (xy 377.555506 -234.488228) (xy 377.56719 -234.48137)
			(xy 377.589106 -234.469064) (xy 377.635483 -234.449685) (xy 377.684004 -234.436569) (xy 377.733829 -234.429945)
			(xy 377.75896 -234.429554) (xy 377.786217 -234.430014) (xy 377.840178 -234.437767) (xy 377.892486 -234.453121)
			(xy 377.942076 -234.475764) (xy 377.987939 -234.505234) (xy 378.029141 -234.540931) (xy 378.064842 -234.582129)
			(xy 378.094317 -234.627989) (xy 378.116965 -234.677576) (xy 378.132324 -234.729883) (xy 378.140083 -234.783843)
			(xy 378.140083 -234.838357) (xy 378.132324 -234.892317) (xy 378.116965 -234.944624) (xy 378.094317 -234.994211)
			(xy 378.064842 -235.040071) (xy 378.029141 -235.081269) (xy 377.987939 -235.116966) (xy 377.942076 -235.146436)
			(xy 377.892486 -235.169079) (xy 377.840178 -235.184433) (xy 377.786217 -235.192186) (xy 377.75896 -235.19257)
			(xy 377.733831 -235.192148) (xy 377.684014 -235.185511) (xy 377.635497 -235.172396) (xy 377.58912 -235.153031)
			(xy 377.56719 -235.140754) (xy 377.555506 -235.133896) (xy 377.528074 -235.133896) (xy 377.439936 -235.184696)
			(xy 377.432445 -235.189478) (xy 377.421031 -235.203082) (xy 377.414931 -235.21976) (xy 377.414536 -235.228638)
			(xy 377.414536 -235.259372) (xy 377.42114 -235.276644) (xy 377.427744 -235.283756) (xy 377.446285 -235.304937)
			(xy 377.477579 -235.351728) (xy 377.501663 -235.402607) (xy 377.518016 -235.456471) (xy 377.526282 -235.512151)
			(xy 377.526282 -235.568443) (xy 377.518017 -235.624124) (xy 377.501666 -235.677988) (xy 377.477582 -235.728867)
			(xy 377.446289 -235.775658) (xy 377.427744 -235.796836) (xy 377.421784 -235.804063) (xy 377.415019 -235.821516)
			(xy 377.414536 -235.830872) (xy 377.414536 -236.46511) (xy 377.43257 -236.491018) (xy 377.44781 -236.496606)
			(xy 377.474307 -236.506824) (xy 377.524184 -236.533977) (xy 377.569481 -236.568227) (xy 377.609197 -236.608817)
			(xy 377.642453 -236.654849) (xy 377.668513 -236.705305) (xy 377.686801 -236.759068) (xy 377.696913 -236.814949)
			(xy 377.698254 -236.843316) (xy 377.698508 -236.853222) (xy 377.706382 -236.871002)
		)
		(stroke
			(width 0)
			(type solid)
		)
		(fill yes)
		(layer "In13.Cu")
		(net "GND")
	)
	(gr_poly
		(pts
			(arc
				(start 235.636562 -413.132016)
				(mid 235.656085 -413.128115)
				(end 235.67263 -413.11703)
			)
			(arc
				(start 236.812328 -411.977332)
				(mid 236.823439 -411.960798)
				(end 236.827314 -411.941264)
			)
			(arc
				(start 236.827314 -402.776436)
				(mid 236.831215 -402.756913)
				(end 236.8423 -402.740368)
			)
			(arc
				(start 238.886238 -400.69643)
				(mid 238.902772 -400.685319)
				(end 238.922306 -400.681444)
			)
			(arc
				(start 242.916964 -400.681444)
				(mid 242.936487 -400.677543)
				(end 242.953032 -400.666458)
			)
			(arc
				(start 243.86286 -399.75663)
				(mid 243.873971 -399.740096)
				(end 243.877846 -399.720562)
			)
			(arc
				(start 243.877846 -392.486896)
				(mid 243.881747 -392.467373)
				(end 243.892832 -392.450828)
			)
			(xy 243.896388 -392.447272)
			(arc
				(start 243.896388 -391.97026)
				(mid 243.900289 -391.950737)
				(end 243.911374 -391.934192)
			)
			(arc
				(start 245.02999 -390.815576)
				(mid 245.046524 -390.804465)
				(end 245.066058 -390.80059)
			)
			(arc
				(start 259.092954 -390.80059)
				(mid 259.112477 -390.796689)
				(end 259.129022 -390.785604)
			)
			(arc
				(start 262.060944 -387.853682)
				(mid 262.072055 -387.837148)
				(end 262.07593 -387.817614)
			)
			(arc
				(start 262.07593 -379.165866)
				(mid 262.072029 -379.146343)
				(end 262.060944 -379.129798)
			)
			(arc
				(start 261.987538 -379.056392)
				(mid 261.971004 -379.045281)
				(end 261.95147 -379.041406)
			)
			(xy 243.1415 -379.041406) (xy 243.140484 -379.042422)
			(arc
				(start 240.581688 -379.042422)
				(mid 240.562165 -379.046323)
				(end 240.54562 -379.057408)
			)
			(arc
				(start 239.903 -379.700028)
				(mid 239.886466 -379.711139)
				(end 239.866932 -379.715014)
			)
			(arc
				(start 237.06963 -379.715014)
				(mid 237.050107 -379.711113)
				(end 237.033562 -379.700028)
			)
			(arc
				(start 232.94086 -375.607326)
				(mid 232.929749 -375.590792)
				(end 232.925874 -375.571258)
			)
			(arc
				(start 232.925874 -372.098062)
				(mid 232.921973 -372.078539)
				(end 232.910888 -372.061994)
			)
			(arc
				(start 232.189274 -371.34038)
				(mid 232.178163 -371.323846)
				(end 232.174288 -371.304312)
			)
			(arc
				(start 232.174288 -371.057424)
				(mid 232.170387 -371.037901)
				(end 232.159302 -371.021356)
			)
			(xy 232.119932 -370.981986) (xy 232.118408 -370.981986)
			(arc
				(start 232.015284 -370.878862)
				(mid 232.004173 -370.862328)
				(end 232.000298 -370.842794)
			)
			(arc
				(start 232.000298 -367.379758)
				(mid 231.996397 -367.360235)
				(end 231.985312 -367.34369)
			)
			(arc
				(start 231.905048 -367.263426)
				(mid 231.888514 -367.252315)
				(end 231.86898 -367.24844)
			)
			(arc
				(start 228.707696 -367.24844)
				(mid 228.688173 -367.252341)
				(end 228.671628 -367.263426)
			)
			(arc
				(start 228.614478 -367.320576)
				(mid 228.603367 -367.33711)
				(end 228.599492 -367.356644)
			)
			(arc
				(start 228.599492 -370.828062)
				(mid 228.595591 -370.847585)
				(end 228.584506 -370.86413)
			)
			(arc
				(start 228.431344 -371.017292)
				(mid 228.420233 -371.033826)
				(end 228.416358 -371.05336)
			)
			(arc
				(start 228.416358 -371.446552)
				(mid 228.412457 -371.466075)
				(end 228.401372 -371.48262)
			)
			(arc
				(start 227.137722 -372.74627)
				(mid 227.126611 -372.762804)
				(end 227.122736 -372.782338)
			)
			(arc
				(start 227.122736 -374.248426)
				(mid 227.118835 -374.267949)
				(end 227.10775 -374.284494)
			)
			(arc
				(start 225.693224 -375.69902)
				(mid 225.67669 -375.710131)
				(end 225.657156 -375.714006)
			)
			(xy 225.267012 -375.714006) (xy 225.254566 -375.71426) (xy 224.258124 -375.71426) (xy 224.245424 -375.714006)
			(arc
				(start 223.582484 -375.714006)
				(mid 223.562961 -375.710105)
				(end 223.546416 -375.69902)
			)
			(arc
				(start 221.539816 -373.69242)
				(mid 221.528705 -373.675886)
				(end 221.52483 -373.656352)
			)
			(arc
				(start 221.52483 -371.070124)
				(mid 221.520929 -371.050601)
				(end 221.509844 -371.034056)
			)
			(arc
				(start 221.337632 -370.861844)
				(mid 221.326521 -370.84531)
				(end 221.322646 -370.825776)
			)
			(arc
				(start 221.322646 -367.359692)
				(mid 221.318745 -367.340169)
				(end 221.30766 -367.323624)
			)
			(arc
				(start 221.24416 -367.260124)
				(mid 221.227626 -367.249013)
				(end 221.208092 -367.245138)
			)
			(arc
				(start 218.078304 -367.245138)
				(mid 218.058781 -367.249039)
				(end 218.042236 -367.260124)
			)
			(arc
				(start 217.916506 -367.385854)
				(mid 217.905395 -367.402388)
				(end 217.90152 -367.421922)
			)
			(arc
				(start 217.90152 -370.80063)
				(mid 217.897619 -370.820153)
				(end 217.886534 -370.836698)
			)
			(arc
				(start 216.72931 -371.993922)
				(mid 216.712776 -372.005033)
				(end 216.693242 -372.008908)
			)
			(xy 213.081362 -372.008908) (xy 213.069678 -372.011702)
			(arc
				(start 213.064344 -372.014496)
				(mid 212.991286 -372.041381)
				(end 212.913976 -372.050564)
			)
			(arc
				(start 210.985354 -372.050564)
				(mid 210.908031 -372.041434)
				(end 210.834986 -372.014496)
			)
			(xy 210.829652 -372.011702) (xy 210.817968 -372.008908)
			(arc
				(start 210.338924 -372.008908)
				(mid 210.319401 -372.005007)
				(end 210.302856 -371.993922)
			)
			(arc
				(start 210.054698 -371.745764)
				(mid 210.043587 -371.72923)
				(end 210.039712 -371.709696)
			)
			(arc
				(start 210.039712 -371.274086)
				(mid 210.035811 -371.254563)
				(end 210.024726 -371.238018)
			)
			(arc
				(start 209.986626 -371.199918)
				(mid 209.970063 -371.188944)
				(end 209.950558 -371.185186)
			)
			(arc
				(start 209.475324 -371.185186)
				(mid 209.455801 -371.181285)
				(end 209.439256 -371.1702)
			)
			(arc
				(start 208.832196 -370.56314)
				(mid 208.821085 -370.546606)
				(end 208.81721 -370.527072)
			)
			(arc
				(start 208.81721 -370.46027)
				(mid 208.813309 -370.440747)
				(end 208.802224 -370.424202)
			)
			(xy 208.795366 -370.417344)
			(arc
				(start 208.220056 -370.417344)
				(mid 208.200533 -370.413443)
				(end 208.183988 -370.402358)
			)
			(arc
				(start 208.098898 -370.317268)
				(mid 208.087787 -370.300734)
				(end 208.083912 -370.2812)
			)
			(arc
				(start 208.083912 -367.384584)
				(mid 208.080011 -367.365061)
				(end 208.068926 -367.348516)
			)
			(arc
				(start 207.996028 -367.275618)
				(mid 207.979494 -367.264507)
				(end 207.95996 -367.260632)
			)
			(arc
				(start 204.786484 -367.260632)
				(mid 204.766961 -367.264533)
				(end 204.750416 -367.275618)
			)
			(arc
				(start 204.68082 -367.345214)
				(mid 204.669894 -367.36166)
				(end 204.666088 -367.381028)
			)
			(xy 204.666088 -367.632488) (xy 204.665834 -367.645188) (xy 204.665834 -368.527076) (xy 204.666088 -368.539776)
			(arc
				(start 204.666088 -370.837968)
				(mid 204.669921 -370.857325)
				(end 204.68082 -370.873782)
			)
			(arc
				(start 204.794104 -370.987066)
				(mid 204.805215 -371.0036)
				(end 204.80909 -371.023134)
			)
			(xy 204.80909 -371.273578) (xy 204.809344 -371.286024) (xy 204.809344 -371.8052) (xy 204.80909 -371.8179)
			(xy 204.80909 -372.680992) (xy 204.809344 -372.693692)
			(arc
				(start 204.809344 -372.841012)
				(mid 204.815725 -372.865662)
				(end 204.83322 -372.884192)
			)
			(xy 204.917548 -372.93677) (xy 204.94371 -372.93804)
			(arc
				(start 204.955648 -372.932198)
				(mid 205.037716 -372.902845)
				(end 205.124304 -372.892828)
			)
			(arc
				(start 205.124304 -372.892828)
				(mid 205.505812 -373.274336)
				(end 205.124304 -373.655844)
			)
			(arc
				(start 205.124304 -373.655844)
				(mid 205.037702 -373.645885)
				(end 204.955648 -373.616474)
			)
			(xy 204.94371 -373.610632) (xy 204.917548 -373.611902)
			(arc
				(start 204.83322 -373.66448)
				(mid 204.81565 -373.682968)
				(end 204.809344 -373.70766)
			)
			(arc
				(start 204.809344 -374.49887)
				(mid 204.813177 -374.518227)
				(end 204.824076 -374.534684)
			)
			(arc
				(start 204.905102 -374.61571)
				(mid 204.916213 -374.632244)
				(end 204.920088 -374.651778)
			)
			(arc
				(start 204.920088 -387.060948)
				(mid 204.923989 -387.080471)
				(end 204.935074 -387.097016)
			)
			(arc
				(start 207.491838 -389.65378)
				(mid 207.502949 -389.670314)
				(end 207.506824 -389.689848)
			)
			(arc
				(start 207.506824 -411.710124)
				(mid 207.510725 -411.729647)
				(end 207.52181 -411.746192)
			)
			(arc
				(start 208.892648 -413.11703)
				(mid 208.909182 -413.128141)
				(end 208.928716 -413.132016)
			)
		)
		(stroke
			(width 0)
			(type solid)
		)
		(fill yes)
		(layer "In13.Cu")
		(net "P12V_STBY")
	)
	(gr_poly
		(pts
			(xy 410.713936 -191.99225) (xy 410.721301 -191.999079) (xy 410.739813 -192.006827) (xy 410.759882 -192.006888)
			(xy 410.769308 -192.003426) (xy 410.783786 -191.99733) (xy 410.800804 -191.97193) (xy 410.800804 -190.492126)
			(xy 410.801231 -190.459252) (xy 410.80856 -190.393913) (xy 410.823162 -190.329807) (xy 410.844855 -190.26774)
			(xy 410.873364 -190.208494) (xy 410.90833 -190.152815) (xy 410.949315 -190.101404) (xy 410.972254 -190.077852)
			(xy 412.12389 -188.926216) (xy 412.130688 -188.918867) (xy 412.138392 -188.900404) (xy 412.138876 -188.890402)
			(xy 412.138876 -183.8452) (xy 412.139304 -183.812326) (xy 412.146636 -183.746989) (xy 412.16124 -183.682884)
			(xy 412.182934 -183.620818) (xy 412.211443 -183.561573) (xy 412.24641 -183.505895) (xy 412.287394 -183.454485)
			(xy 412.310326 -183.430926) (xy 413.635698 -182.105554) (xy 413.642502 -182.098206) (xy 413.650218 -182.079744)
			(xy 413.650684 -182.06974) (xy 413.650684 -181.182772) (xy 413.650177 -181.172965) (xy 413.64272 -181.154817)
			(xy 413.636206 -181.147466) (xy 413.579818 -181.089554) (xy 413.561784 -181.08168) (xy 413.551878 -181.081172)
			(xy 413.525152 -181.07995) (xy 413.472415 -181.070951) (xy 413.421452 -181.054675) (xy 413.373261 -181.031441)
			(xy 413.328788 -181.001704) (xy 413.288903 -180.966047) (xy 413.25439 -180.925169) (xy 413.225924 -180.879871)
			(xy 413.204063 -180.831042) (xy 413.189236 -180.779638) (xy 413.181734 -180.726667) (xy 413.181292 -180.699918)
			(xy 413.181754 -180.672664) (xy 413.189509 -180.618711) (xy 413.204863 -180.566411) (xy 413.227505 -180.516829)
			(xy 413.256972 -180.470974) (xy 413.292666 -180.429779) (xy 413.333859 -180.394083) (xy 413.379713 -180.364614)
			(xy 413.429295 -180.34197) (xy 413.481594 -180.326613) (xy 413.535546 -180.318855) (xy 413.5628 -180.31841)
			(xy 413.575246 -180.318664) (xy 413.585156 -180.318487) (xy 413.603703 -180.311553) (xy 413.611314 -180.305202)
			(xy 413.634174 -180.284374) (xy 413.641722 -180.276877) (xy 413.650261 -180.257413) (xy 413.650684 -180.246782)
			(xy 413.650684 -180.226462) (xy 413.650139 -180.216478) (xy 413.642414 -180.198057) (xy 413.635698 -180.190648)
			(xy 411.33776 -177.89271) (xy 411.330413 -177.885905) (xy 411.31195 -177.878185) (xy 411.301946 -177.877724)
			(xy 408.914854 -177.877724) (xy 408.881981 -177.877294) (xy 408.816646 -177.869957) (xy 408.752544 -177.855349)
			(xy 408.690482 -177.833651) (xy 408.631241 -177.805139) (xy 408.575566 -177.770169) (xy 408.52416 -177.729184)
			(xy 408.50058 -177.706274) (xy 404.927816 -174.13351) (xy 404.920467 -174.126712) (xy 404.902004 -174.119008)
			(xy 404.892002 -174.118524) (xy 399.974054 -174.118524) (xy 399.941181 -174.118094) (xy 399.875846 -174.110757)
			(xy 399.811744 -174.096149) (xy 399.749682 -174.074451) (xy 399.690441 -174.045939) (xy 399.634766 -174.010969)
			(xy 399.58336 -173.969984) (xy 399.55978 -173.947074) (xy 399.254726 -173.64202) (xy 399.231818 -173.618441)
			(xy 399.19085 -173.567026) (xy 399.155894 -173.511347) (xy 399.127391 -173.452106) (xy 399.105699 -173.390046)
			(xy 399.09109 -173.325948) (xy 399.083747 -173.260617) (xy 399.083276 -173.227746) (xy 399.083276 -172.272706)
			(xy 399.082739 -172.262719) (xy 399.075025 -172.244287) (xy 399.06829 -172.236892) (xy 399.068036 -172.236638)
			(xy 399.060369 -172.229614) (xy 399.041093 -172.221875) (xy 399.030698 -172.221652) (xy 398.946116 -172.223938)
			(xy 398.927574 -172.232574) (xy 398.920462 -172.240702) (xy 398.902294 -172.260321) (xy 398.861415 -172.294786)
			(xy 398.816122 -172.323204) (xy 398.767304 -172.345017) (xy 398.715918 -172.359799) (xy 398.662971 -172.367258)
			(xy 398.636236 -172.367702) (xy 398.608982 -172.367241) (xy 398.555027 -172.359488) (xy 398.502725 -172.344135)
			(xy 398.453141 -172.321495) (xy 398.407284 -172.292028) (xy 398.366087 -172.256334) (xy 398.33039 -172.21514)
			(xy 398.30092 -172.169285) (xy 398.278275 -172.119703) (xy 398.262918 -172.067402) (xy 398.255161 -172.013448)
			(xy 398.254728 -171.986194) (xy 398.254858 -171.970887) (xy 398.257271 -171.94037) (xy 398.259554 -171.925234)
			(xy 398.261332 -171.914058) (xy 398.25549 -171.892722) (xy 398.198086 -171.825158) (xy 398.190548 -171.817058)
			(xy 398.170527 -171.807697) (xy 398.159478 -171.807124) (xy 396.799562 -171.807124) (xy 396.766689 -171.806694)
			(xy 396.701353 -171.799358) (xy 396.637251 -171.784751) (xy 396.575188 -171.763054) (xy 396.515946 -171.734542)
			(xy 396.460271 -171.699573) (xy 396.408864 -171.658587) (xy 396.385288 -171.635674) (xy 395.555724 -170.80611)
			(xy 395.548375 -170.79931) (xy 395.529912 -170.791604) (xy 395.51991 -170.791124) (xy 390.019032 -170.791124)
			(xy 390.009008 -170.791539) (xy 389.990485 -170.799204) (xy 389.976308 -170.813378) (xy 389.96864 -170.8319)
			(xy 389.968232 -170.841924) (xy 389.968232 -171.225464) (xy 389.968667 -171.235528) (xy 389.976402 -171.254113)
			(xy 389.983218 -171.261532) (xy 393.21232 -174.490634) (xy 398.11147 -174.490634) (xy 398.115541 -174.435012)
			(xy 398.127667 -174.380575) (xy 398.14759 -174.328484) (xy 398.174886 -174.279849) (xy 398.208972 -174.235706)
			(xy 398.249121 -174.196997) (xy 398.294479 -174.164546) (xy 398.344079 -174.139045) (xy 398.396863 -174.121038)
			(xy 398.451706 -174.110908) (xy 398.50744 -174.108871) (xy 398.562877 -174.114971) (xy 398.616834 -174.129077)
			(xy 398.668163 -174.150889) (xy 398.715769 -174.179943) (xy 398.758637 -174.215618) (xy 398.795854 -174.257155)
			(xy 398.826627 -174.303668) (xy 398.850299 -174.354165) (xy 398.866367 -174.407572) (xy 398.874487 -174.462748)
			(xy 398.874996 -174.490634) (xy 398.874487 -174.51852) (xy 398.866367 -174.573696) (xy 398.850299 -174.627103)
			(xy 398.826627 -174.6776) (xy 398.795854 -174.724113) (xy 398.758637 -174.76565) (xy 398.715769 -174.801325)
			(xy 398.668163 -174.830379) (xy 398.616834 -174.852191) (xy 398.562877 -174.866297) (xy 398.50744 -174.872397)
			(xy 398.451706 -174.87036) (xy 398.396863 -174.86023) (xy 398.344079 -174.842223) (xy 398.294479 -174.816722)
			(xy 398.249121 -174.784271) (xy 398.208972 -174.745562) (xy 398.174886 -174.701419) (xy 398.14759 -174.652784)
			(xy 398.127667 -174.600693) (xy 398.115541 -174.546256) (xy 398.11147 -174.490634) (xy 393.21232 -174.490634)
			(xy 398.450054 -179.728368) (xy 399.71675 -179.728368) (xy 399.720821 -179.672746) (xy 399.732947 -179.618309)
			(xy 399.75287 -179.566218) (xy 399.780166 -179.517583) (xy 399.814252 -179.47344) (xy 399.854401 -179.434731)
			(xy 399.899759 -179.40228) (xy 399.949359 -179.376779) (xy 400.002143 -179.358772) (xy 400.056986 -179.348642)
			(xy 400.11272 -179.346605) (xy 400.168157 -179.352705) (xy 400.222114 -179.366811) (xy 400.273443 -179.388623)
			(xy 400.321049 -179.417677) (xy 400.363917 -179.453352) (xy 400.401134 -179.494889) (xy 400.431907 -179.541402)
			(xy 400.455579 -179.591899) (xy 400.471647 -179.645306) (xy 400.479767 -179.700482) (xy 400.480276 -179.728368)
			(xy 400.479767 -179.756254) (xy 400.471647 -179.81143) (xy 400.455579 -179.864837) (xy 400.431907 -179.915334)
			(xy 400.401134 -179.961847) (xy 400.363917 -180.003384) (xy 400.321049 -180.039059) (xy 400.273443 -180.068113)
			(xy 400.222114 -180.089925) (xy 400.168157 -180.104031) (xy 400.11272 -180.110131) (xy 400.056986 -180.108094)
			(xy 400.002143 -180.097964) (xy 399.949359 -180.079957) (xy 399.899759 -180.054456) (xy 399.854401 -180.022005)
			(xy 399.814252 -179.983296) (xy 399.780166 -179.939153) (xy 399.75287 -179.890518) (xy 399.732947 -179.838427)
			(xy 399.720821 -179.78399) (xy 399.71675 -179.728368) (xy 398.450054 -179.728368) (xy 401.118832 -182.397146)
			(xy 401.126176 -182.403957) (xy 401.144639 -182.411687) (xy 401.154646 -182.412132) (xy 408.602688 -182.412132)
			(xy 408.612677 -182.411598) (xy 408.631115 -182.403891) (xy 408.638502 -182.397146) (xy 409.30449 -181.731158)
			(xy 409.311295 -181.723811) (xy 409.319014 -181.705348) (xy 409.319476 -181.695344) (xy 409.319476 -179.493672)
			(xy 409.316428 -179.481734) (xy 409.313634 -179.476146) (xy 409.299802 -179.448617) (xy 409.280231 -179.390203)
			(xy 409.270309 -179.329402) (xy 409.269692 -179.2986) (xy 409.270178 -179.271349) (xy 409.277934 -179.217401)
			(xy 409.293289 -179.165106) (xy 409.315931 -179.115529) (xy 409.345397 -179.069679) (xy 409.381088 -179.028488)
			(xy 409.422279 -178.992797) (xy 409.468129 -178.963331) (xy 409.517706 -178.940689) (xy 409.570001 -178.925334)
			(xy 409.623949 -178.917578) (xy 409.678451 -178.917578) (xy 409.732399 -178.925334) (xy 409.784694 -178.940689)
			(xy 409.834271 -178.963331) (xy 409.880121 -178.992797) (xy 409.921312 -179.028488) (xy 409.957003 -179.069679)
			(xy 409.986469 -179.115529) (xy 410.009111 -179.165106) (xy 410.024466 -179.217401) (xy 410.032222 -179.271349)
			(xy 410.032708 -179.2986) (xy 411.250382 -179.2986) (xy 411.254453 -179.242978) (xy 411.266579 -179.188541)
			(xy 411.286502 -179.13645) (xy 411.313798 -179.087815) (xy 411.347884 -179.043672) (xy 411.388033 -179.004963)
			(xy 411.433391 -178.972512) (xy 411.482991 -178.947011) (xy 411.535775 -178.929004) (xy 411.590618 -178.918874)
			(xy 411.646352 -178.916837) (xy 411.701789 -178.922937) (xy 411.755746 -178.937043) (xy 411.807075 -178.958855)
			(xy 411.854681 -178.987909) (xy 411.897549 -179.023584) (xy 411.934766 -179.065121) (xy 411.965539 -179.111634)
			(xy 411.989211 -179.162131) (xy 412.005279 -179.215538) (xy 412.013399 -179.270714) (xy 412.013908 -179.2986)
			(xy 412.013399 -179.326486) (xy 412.005279 -179.381662) (xy 411.989211 -179.435069) (xy 411.965539 -179.485566)
			(xy 411.934766 -179.532079) (xy 411.897549 -179.573616) (xy 411.854681 -179.609291) (xy 411.807075 -179.638345)
			(xy 411.755746 -179.660157) (xy 411.701789 -179.674263) (xy 411.646352 -179.680363) (xy 411.590618 -179.678326)
			(xy 411.535775 -179.668196) (xy 411.482991 -179.650189) (xy 411.433391 -179.624688) (xy 411.388033 -179.592237)
			(xy 411.347884 -179.553528) (xy 411.313798 -179.509385) (xy 411.286502 -179.46075) (xy 411.266579 -179.408659)
			(xy 411.254453 -179.354222) (xy 411.250382 -179.2986) (xy 410.032708 -179.2986) (xy 410.032096 -179.329402)
			(xy 410.022158 -179.390199) (xy 410.002587 -179.448612) (xy 409.988766 -179.476146) (xy 409.985972 -179.481734)
			(xy 409.982924 -179.493672) (xy 409.982924 -181.85384) (xy 409.982459 -181.879917) (xy 409.974339 -181.931434)
			(xy 409.958257 -181.981046) (xy 409.934609 -182.027531) (xy 409.90398 -182.069742) (xy 409.885896 -182.088536)
			(xy 408.99588 -182.978552) (xy 408.977088 -182.996636) (xy 408.934876 -183.027263) (xy 408.88839 -183.050906)
			(xy 408.838778 -183.066982) (xy 408.787261 -183.075095) (xy 408.761184 -183.07558) (xy 408.22372 -183.07558)
			(xy 408.213671 -183.076001) (xy 408.195108 -183.083701) (xy 408.180918 -183.097933) (xy 408.17673 -183.107076)
			(xy 408.170888 -183.121554) (xy 408.17673 -183.151272) (xy 408.64917 -183.623712) (xy 408.656922 -183.630802)
			(xy 408.676436 -183.638514) (xy 408.697403 -183.637706) (xy 408.707082 -183.633618) (xy 408.808174 -183.584596)
			(xy 408.823668 -183.556402) (xy 408.82189 -183.540146) (xy 408.820708 -183.529263) (xy 408.819439 -183.507405)
			(xy 408.81935 -183.496458) (xy 408.819816 -183.469202) (xy 408.82758 -183.415246) (xy 408.842943 -183.362944)
			(xy 408.865594 -183.313361) (xy 408.89507 -183.267506) (xy 408.930772 -183.226313) (xy 408.971973 -183.19062)
			(xy 409.017835 -183.161153) (xy 409.067423 -183.138514) (xy 409.119728 -183.123162) (xy 409.173686 -183.11541)
			(xy 409.228198 -183.115416) (xy 409.282154 -183.12318) (xy 409.334456 -183.138543) (xy 409.384039 -183.161194)
			(xy 409.429894 -183.19067) (xy 409.471087 -183.226372) (xy 409.50678 -183.267573) (xy 409.536247 -183.313435)
			(xy 409.558886 -183.363023) (xy 409.574238 -183.415328) (xy 409.58199 -183.469286) (xy 409.581984 -183.523798)
			(xy 409.57422 -183.577754) (xy 409.558857 -183.630056) (xy 409.536206 -183.679639) (xy 409.527746 -183.6928)
			(xy 411.224982 -183.6928) (xy 411.229053 -183.637178) (xy 411.241179 -183.582741) (xy 411.261102 -183.53065)
			(xy 411.288398 -183.482015) (xy 411.322484 -183.437872) (xy 411.362633 -183.399163) (xy 411.407991 -183.366712)
			(xy 411.457591 -183.341211) (xy 411.510375 -183.323204) (xy 411.565218 -183.313074) (xy 411.620952 -183.311037)
			(xy 411.676389 -183.317137) (xy 411.730346 -183.331243) (xy 411.781675 -183.353055) (xy 411.829281 -183.382109)
			(xy 411.872149 -183.417784) (xy 411.909366 -183.459321) (xy 411.940139 -183.505834) (xy 411.963811 -183.556331)
			(xy 411.979879 -183.609738) (xy 411.987999 -183.664914) (xy 411.988508 -183.6928) (xy 411.987999 -183.720686)
			(xy 411.979879 -183.775862) (xy 411.963811 -183.829269) (xy 411.940139 -183.879766) (xy 411.909366 -183.926279)
			(xy 411.872149 -183.967816) (xy 411.829281 -184.003491) (xy 411.781675 -184.032545) (xy 411.730346 -184.054357)
			(xy 411.676389 -184.068463) (xy 411.620952 -184.074563) (xy 411.565218 -184.072526) (xy 411.510375 -184.062396)
			(xy 411.457591 -184.044389) (xy 411.407991 -184.018888) (xy 411.362633 -183.986437) (xy 411.322484 -183.947728)
			(xy 411.288398 -183.903585) (xy 411.261102 -183.85495) (xy 411.241179 -183.802859) (xy 411.229053 -183.748422)
			(xy 411.224982 -183.6928) (xy 409.527746 -183.6928) (xy 409.50673 -183.725494) (xy 409.471028 -183.766687)
			(xy 409.429827 -183.80238) (xy 409.383965 -183.831847) (xy 409.334377 -183.854486) (xy 409.282072 -183.869838)
			(xy 409.228114 -183.87759) (xy 409.200858 -183.877966) (xy 409.189911 -183.877881) (xy 409.168053 -183.876611)
			(xy 409.15717 -183.875426) (xy 409.140914 -183.873648) (xy 409.11272 -183.889142) (xy 409.063698 -183.990234)
			(xy 409.059671 -183.999913) (xy 409.058959 -184.020842) (xy 409.066608 -184.040336) (xy 409.073604 -184.048146)
			(xy 410.238194 -185.212736) (xy 410.256308 -185.231516) (xy 410.286994 -185.273713) (xy 410.310695 -185.320194)
			(xy 410.326826 -185.369812) (xy 410.33499 -185.421345) (xy 410.335476 -185.447432) (xy 410.335476 -187.456826)
			(xy 410.334988 -187.482913) (xy 410.327808 -187.5282) (xy 411.123382 -187.5282) (xy 411.127453 -187.472578)
			(xy 411.139579 -187.418141) (xy 411.159502 -187.36605) (xy 411.186798 -187.317415) (xy 411.220884 -187.273272)
			(xy 411.261033 -187.234563) (xy 411.306391 -187.202112) (xy 411.355991 -187.176611) (xy 411.408775 -187.158604)
			(xy 411.463618 -187.148474) (xy 411.519352 -187.146437) (xy 411.574789 -187.152537) (xy 411.628746 -187.166643)
			(xy 411.680075 -187.188455) (xy 411.727681 -187.217509) (xy 411.770549 -187.253184) (xy 411.807766 -187.294721)
			(xy 411.838539 -187.341234) (xy 411.862211 -187.391731) (xy 411.878279 -187.445138) (xy 411.886399 -187.500314)
			(xy 411.886908 -187.5282) (xy 411.886399 -187.556086) (xy 411.878279 -187.611262) (xy 411.862211 -187.664669)
			(xy 411.838539 -187.715166) (xy 411.807766 -187.761679) (xy 411.770549 -187.803216) (xy 411.727681 -187.838891)
			(xy 411.680075 -187.867945) (xy 411.628746 -187.889757) (xy 411.574789 -187.903863) (xy 411.519352 -187.909963)
			(xy 411.463618 -187.907926) (xy 411.408775 -187.897796) (xy 411.355991 -187.879789) (xy 411.306391 -187.854288)
			(xy 411.261033 -187.821837) (xy 411.220884 -187.783128) (xy 411.186798 -187.738985) (xy 411.159502 -187.69035)
			(xy 411.139579 -187.638259) (xy 411.127453 -187.583822) (xy 411.123382 -187.5282) (xy 410.327808 -187.5282)
			(xy 410.326818 -187.534442) (xy 410.310684 -187.584058) (xy 410.286982 -187.630537) (xy 410.256299 -187.672734)
			(xy 410.238194 -187.691522) (xy 409.940252 -187.989464) (xy 409.933567 -187.996874) (xy 409.92598 -188.015309)
			(xy 409.92552 -188.025278) (xy 409.92552 -189.107318) (xy 410.255464 -189.107318) (xy 410.259535 -189.051696)
			(xy 410.271661 -188.997259) (xy 410.291584 -188.945168) (xy 410.31888 -188.896533) (xy 410.352966 -188.85239)
			(xy 410.393115 -188.813681) (xy 410.438473 -188.78123) (xy 410.488073 -188.755729) (xy 410.540857 -188.737722)
			(xy 410.5957 -188.727592) (xy 410.651434 -188.725555) (xy 410.706871 -188.731655) (xy 410.760828 -188.745761)
			(xy 410.812157 -188.767573) (xy 410.859763 -188.796627) (xy 410.902631 -188.832302) (xy 410.939848 -188.873839)
			(xy 410.970621 -188.920352) (xy 410.994293 -188.970849) (xy 411.010361 -189.024256) (xy 411.018481 -189.079432)
			(xy 411.01899 -189.107318) (xy 411.018481 -189.135204) (xy 411.010361 -189.19038) (xy 410.994293 -189.243787)
			(xy 410.970621 -189.294284) (xy 410.939848 -189.340797) (xy 410.902631 -189.382334) (xy 410.859763 -189.418009)
			(xy 410.812157 -189.447063) (xy 410.760828 -189.468875) (xy 410.706871 -189.482981) (xy 410.651434 -189.489081)
			(xy 410.5957 -189.487044) (xy 410.540857 -189.476914) (xy 410.488073 -189.458907) (xy 410.438473 -189.433406)
			(xy 410.393115 -189.400955) (xy 410.352966 -189.362246) (xy 410.31888 -189.318103) (xy 410.291584 -189.269468)
			(xy 410.271661 -189.217377) (xy 410.259535 -189.16294) (xy 410.255464 -189.107318) (xy 409.92552 -189.107318)
			(xy 409.92552 -191.182752) (xy 409.926004 -191.192715) (xy 409.93359 -191.211141) (xy 409.940252 -191.218566)
		)
		(stroke
			(width 0)
			(type solid)
		)
		(fill yes)
		(layer "In13.Cu")
		(net "GND")
	)
	(gr_poly
		(pts
			(xy 429.714406 -236.929676) (xy 429.72445 -236.92925) (xy 429.742999 -236.92154) (xy 429.757171 -236.907303)
			(xy 429.761396 -236.89818) (xy 429.767492 -236.883702) (xy 429.761396 -236.853984) (xy 417.13531 -224.227644)
			(xy 417.127883 -224.220871) (xy 417.109287 -224.213282) (xy 417.099242 -224.212912) (xy 381.23114 -224.212912)
			(xy 381.221109 -224.213352) (xy 381.202536 -224.220929) (xy 381.195072 -224.227644) (xy 380.185422 -225.237294)
			(xy 414.952686 -225.237294) (xy 414.956757 -225.181672) (xy 414.968883 -225.127235) (xy 414.988806 -225.075144)
			(xy 415.016102 -225.026509) (xy 415.050188 -224.982366) (xy 415.090337 -224.943657) (xy 415.135695 -224.911206)
			(xy 415.185295 -224.885705) (xy 415.238079 -224.867698) (xy 415.292922 -224.857568) (xy 415.348656 -224.855531)
			(xy 415.404093 -224.861631) (xy 415.45805 -224.875737) (xy 415.509379 -224.897549) (xy 415.556985 -224.926603)
			(xy 415.599853 -224.962278) (xy 415.63707 -225.003815) (xy 415.667843 -225.050328) (xy 415.691515 -225.100825)
			(xy 415.707583 -225.154232) (xy 415.715703 -225.209408) (xy 415.716212 -225.237294) (xy 415.715703 -225.26518)
			(xy 415.707583 -225.320356) (xy 415.691515 -225.373763) (xy 415.667843 -225.42426) (xy 415.63707 -225.470773)
			(xy 415.599853 -225.51231) (xy 415.556985 -225.547985) (xy 415.509379 -225.577039) (xy 415.45805 -225.598851)
			(xy 415.404093 -225.612957) (xy 415.348656 -225.619057) (xy 415.292922 -225.61702) (xy 415.238079 -225.60689)
			(xy 415.185295 -225.588883) (xy 415.135695 -225.563382) (xy 415.090337 -225.530931) (xy 415.050188 -225.492222)
			(xy 415.016102 -225.448079) (xy 414.988806 -225.399444) (xy 414.968883 -225.347353) (xy 414.956757 -225.292916)
			(xy 414.952686 -225.237294) (xy 380.185422 -225.237294) (xy 378.889006 -226.53371) (xy 378.882161 -226.541109)
			(xy 378.874429 -226.559707) (xy 378.87402 -226.569778) (xy 378.87402 -227.397056) (xy 379.336298 -227.397056)
			(xy 379.340369 -227.341434) (xy 379.352495 -227.286997) (xy 379.372418 -227.234906) (xy 379.399714 -227.186271)
			(xy 379.4338 -227.142128) (xy 379.473949 -227.103419) (xy 379.519307 -227.070968) (xy 379.568907 -227.045467)
			(xy 379.621691 -227.02746) (xy 379.676534 -227.01733) (xy 379.732268 -227.015293) (xy 379.787705 -227.021393)
			(xy 379.841662 -227.035499) (xy 379.892991 -227.057311) (xy 379.940597 -227.086365) (xy 379.983465 -227.12204)
			(xy 380.020682 -227.163577) (xy 380.051455 -227.21009) (xy 380.075127 -227.260587) (xy 380.091195 -227.313994)
			(xy 380.099315 -227.36917) (xy 380.099824 -227.397056) (xy 380.099315 -227.424942) (xy 380.091195 -227.480118)
			(xy 380.075127 -227.533525) (xy 380.051455 -227.584022) (xy 380.020682 -227.630535) (xy 379.983465 -227.672072)
			(xy 379.940597 -227.707747) (xy 379.892991 -227.736801) (xy 379.841662 -227.758613) (xy 379.787705 -227.772719)
			(xy 379.732268 -227.778819) (xy 379.676534 -227.776782) (xy 379.621691 -227.766652) (xy 379.568907 -227.748645)
			(xy 379.519307 -227.723144) (xy 379.473949 -227.690693) (xy 379.4338 -227.651984) (xy 379.399714 -227.607841)
			(xy 379.372418 -227.559206) (xy 379.352495 -227.507115) (xy 379.340369 -227.452678) (xy 379.336298 -227.397056)
			(xy 378.87402 -227.397056) (xy 378.87402 -228.467666) (xy 381.166114 -228.467666) (xy 381.170185 -228.412044)
			(xy 381.182311 -228.357607) (xy 381.202234 -228.305516) (xy 381.22953 -228.256881) (xy 381.263616 -228.212738)
			(xy 381.303765 -228.174029) (xy 381.349123 -228.141578) (xy 381.398723 -228.116077) (xy 381.451507 -228.09807)
			(xy 381.50635 -228.08794) (xy 381.562084 -228.085903) (xy 381.617521 -228.092003) (xy 381.671478 -228.106109)
			(xy 381.722807 -228.127921) (xy 381.770413 -228.156975) (xy 381.813281 -228.19265) (xy 381.850498 -228.234187)
			(xy 381.881271 -228.2807) (xy 381.904943 -228.331197) (xy 381.921011 -228.384604) (xy 381.929131 -228.43978)
			(xy 381.92964 -228.467666) (xy 381.929131 -228.495552) (xy 381.921011 -228.550728) (xy 381.904943 -228.604135)
			(xy 381.881271 -228.654632) (xy 381.850498 -228.701145) (xy 381.813281 -228.742682) (xy 381.770413 -228.778357)
			(xy 381.722807 -228.807411) (xy 381.671478 -228.829223) (xy 381.617521 -228.843329) (xy 381.562084 -228.849429)
			(xy 381.50635 -228.847392) (xy 381.451507 -228.837262) (xy 381.398723 -228.819255) (xy 381.349123 -228.793754)
			(xy 381.303765 -228.761303) (xy 381.263616 -228.722594) (xy 381.22953 -228.678451) (xy 381.202234 -228.629816)
			(xy 381.182311 -228.577725) (xy 381.170185 -228.523288) (xy 381.166114 -228.467666) (xy 378.87402 -228.467666)
			(xy 378.87402 -228.492304) (xy 378.873431 -228.522364) (xy 378.864029 -228.581745) (xy 378.845459 -228.638926)
			(xy 378.818176 -228.6925) (xy 378.782852 -228.741148) (xy 378.762006 -228.762814) (xy 378.662203 -228.862636)
			(xy 386.430266 -228.862636) (xy 386.430729 -228.836217) (xy 386.43801 -228.783882) (xy 386.45245 -228.733056)
			(xy 386.473773 -228.684711) (xy 386.50157 -228.639775) (xy 386.535308 -228.59911) (xy 386.57434 -228.563496)
			(xy 386.595874 -228.548184) (xy 386.606928 -228.540017) (xy 386.6246 -228.518983) (xy 386.636016 -228.493996)
			(xy 386.640347 -228.466868) (xy 386.63728 -228.439568) (xy 386.627037 -228.414077) (xy 386.61036 -228.392246)
			(xy 386.599684 -228.383592) (xy 386.576676 -228.365401) (xy 386.535941 -228.323205) (xy 386.502137 -228.275277)
			(xy 386.476061 -228.222742) (xy 386.458325 -228.166838) (xy 386.449348 -228.108879) (xy 386.448808 -228.079554)
			(xy 386.449294 -228.052303) (xy 386.45705 -227.998355) (xy 386.472405 -227.94606) (xy 386.495047 -227.896483)
			(xy 386.524513 -227.850633) (xy 386.560204 -227.809442) (xy 386.601395 -227.773751) (xy 386.647245 -227.744285)
			(xy 386.696822 -227.721643) (xy 386.749117 -227.706288) (xy 386.803065 -227.698532) (xy 386.857567 -227.698532)
			(xy 386.911515 -227.706288) (xy 386.96381 -227.721643) (xy 387.013387 -227.744285) (xy 387.059237 -227.773751)
			(xy 387.100428 -227.809442) (xy 387.136119 -227.850633) (xy 387.165585 -227.896483) (xy 387.188227 -227.94606)
			(xy 387.203582 -227.998355) (xy 387.211338 -228.052303) (xy 387.211824 -228.079554) (xy 387.211358 -228.105973)
			(xy 387.204078 -228.158308) (xy 387.189639 -228.209135) (xy 387.168317 -228.257479) (xy 387.14052 -228.302415)
			(xy 387.106782 -228.34308) (xy 387.06775 -228.378694) (xy 387.046216 -228.394006) (xy 387.035172 -228.402186)
			(xy 387.017502 -228.423217) (xy 387.006087 -228.448201) (xy 387.001755 -228.475326) (xy 387.00482 -228.502624)
			(xy 387.01506 -228.528113) (xy 387.031732 -228.549943) (xy 387.042406 -228.558598) (xy 387.065455 -228.57674)
			(xy 387.106188 -228.618945) (xy 387.139987 -228.666884) (xy 387.166057 -228.719428) (xy 387.183783 -228.775342)
			(xy 387.192749 -228.833308) (xy 387.193282 -228.862636) (xy 387.192796 -228.889887) (xy 387.18504 -228.943835)
			(xy 387.169685 -228.99613) (xy 387.147043 -229.045707) (xy 387.117577 -229.091557) (xy 387.081886 -229.132748)
			(xy 387.040695 -229.168439) (xy 386.994845 -229.197905) (xy 386.945268 -229.220547) (xy 386.892973 -229.235902)
			(xy 386.839025 -229.243658) (xy 386.784523 -229.243658) (xy 386.730575 -229.235902) (xy 386.67828 -229.220547)
			(xy 386.628703 -229.197905) (xy 386.582853 -229.168439) (xy 386.541662 -229.132748) (xy 386.505971 -229.091557)
			(xy 386.476505 -229.045707) (xy 386.453863 -228.99613) (xy 386.438508 -228.943835) (xy 386.430752 -228.889887)
			(xy 386.430266 -228.862636) (xy 378.662203 -228.862636) (xy 378.147697 -229.37724) (xy 392.719558 -229.37724)
			(xy 392.723629 -229.321618) (xy 392.735755 -229.267181) (xy 392.755678 -229.21509) (xy 392.782974 -229.166455)
			(xy 392.81706 -229.122312) (xy 392.857209 -229.083603) (xy 392.902567 -229.051152) (xy 392.952167 -229.025651)
			(xy 393.004951 -229.007644) (xy 393.059794 -228.997514) (xy 393.115528 -228.995477) (xy 393.170965 -229.001577)
			(xy 393.224922 -229.015683) (xy 393.276251 -229.037495) (xy 393.323857 -229.066549) (xy 393.366725 -229.102224)
			(xy 393.403942 -229.143761) (xy 393.434715 -229.190274) (xy 393.458387 -229.240771) (xy 393.474455 -229.294178)
			(xy 393.482575 -229.349354) (xy 393.483084 -229.37724) (xy 393.482575 -229.405126) (xy 393.474455 -229.460302)
			(xy 393.458387 -229.513709) (xy 393.434715 -229.564206) (xy 393.403942 -229.610719) (xy 393.366725 -229.652256)
			(xy 393.323857 -229.687931) (xy 393.276251 -229.716985) (xy 393.224922 -229.738797) (xy 393.170965 -229.752903)
			(xy 393.115528 -229.759003) (xy 393.059794 -229.756966) (xy 393.004951 -229.746836) (xy 392.952167 -229.728829)
			(xy 392.902567 -229.703328) (xy 392.857209 -229.670877) (xy 392.81706 -229.632168) (xy 392.782974 -229.588025)
			(xy 392.755678 -229.53939) (xy 392.735755 -229.487299) (xy 392.723629 -229.432862) (xy 392.719558 -229.37724)
			(xy 378.147697 -229.37724) (xy 377.429522 -230.095552) (xy 377.422717 -230.102899) (xy 377.415 -230.121362)
			(xy 377.414536 -230.131366) (xy 377.414536 -231.07396) (xy 381.686814 -231.07396) (xy 381.690885 -231.018338)
			(xy 381.703011 -230.963901) (xy 381.722934 -230.91181) (xy 381.75023 -230.863175) (xy 381.784316 -230.819032)
			(xy 381.824465 -230.780323) (xy 381.869823 -230.747872) (xy 381.919423 -230.722371) (xy 381.972207 -230.704364)
			(xy 382.02705 -230.694234) (xy 382.082784 -230.692197) (xy 382.138221 -230.698297) (xy 382.192178 -230.712403)
			(xy 382.243507 -230.734215) (xy 382.291113 -230.763269) (xy 382.333981 -230.798944) (xy 382.371198 -230.840481)
			(xy 382.401971 -230.886994) (xy 382.40975 -230.903589) (xy 383.216061 -230.903589) (xy 383.216061 -230.843611)
			(xy 383.22389 -230.784147) (xy 383.239413 -230.726213) (xy 383.262366 -230.670801) (xy 383.292355 -230.618858)
			(xy 383.328867 -230.571275) (xy 383.371278 -230.528865) (xy 383.418862 -230.492353) (xy 383.470804 -230.462364)
			(xy 383.526216 -230.439412) (xy 383.584151 -230.423889) (xy 383.643615 -230.416061) (xy 383.673604 -230.415592)
			(xy 384.537204 -230.415592) (xy 384.567185 -230.416174) (xy 384.626634 -230.424001) (xy 384.684553 -230.439521)
			(xy 384.739951 -230.462468) (xy 384.79188 -230.492449) (xy 384.839451 -230.528952) (xy 384.88185 -230.571352)
			(xy 384.918353 -230.618924) (xy 384.948334 -230.670853) (xy 384.97128 -230.726251) (xy 384.986799 -230.78417)
			(xy 384.994626 -230.843619) (xy 384.994626 -230.903581) (xy 384.986799 -230.96303) (xy 384.97128 -231.020949)
			(xy 384.96847 -231.027732) (xy 386.97357 -231.027732) (xy 386.977641 -230.97211) (xy 386.989767 -230.917673)
			(xy 387.00969 -230.865582) (xy 387.036986 -230.816947) (xy 387.071072 -230.772804) (xy 387.111221 -230.734095)
			(xy 387.156579 -230.701644) (xy 387.206179 -230.676143) (xy 387.258963 -230.658136) (xy 387.313806 -230.648006)
			(xy 387.36954 -230.645969) (xy 387.424977 -230.652069) (xy 387.478934 -230.666175) (xy 387.530263 -230.687987)
			(xy 387.577869 -230.717041) (xy 387.620737 -230.752716) (xy 387.657954 -230.794253) (xy 387.688727 -230.840766)
			(xy 387.712399 -230.891263) (xy 387.728467 -230.94467) (xy 387.736587 -230.999846) (xy 387.737096 -231.027732)
			(xy 387.736587 -231.055618) (xy 387.728467 -231.110794) (xy 387.712399 -231.164201) (xy 387.688727 -231.214698)
			(xy 387.657954 -231.261211) (xy 387.620737 -231.302748) (xy 387.585253 -231.332278) (xy 392.830302 -231.332278)
			(xy 392.834373 -231.276656) (xy 392.846499 -231.222219) (xy 392.866422 -231.170128) (xy 392.893718 -231.121493)
			(xy 392.927804 -231.07735) (xy 392.967953 -231.038641) (xy 393.013311 -231.00619) (xy 393.062911 -230.980689)
			(xy 393.115695 -230.962682) (xy 393.170538 -230.952552) (xy 393.226272 -230.950515) (xy 393.247056 -230.952802)
			(xy 417.376354 -230.952802) (xy 417.380425 -230.89718) (xy 417.392551 -230.842743) (xy 417.412474 -230.790652)
			(xy 417.43977 -230.742017) (xy 417.473856 -230.697874) (xy 417.514005 -230.659165) (xy 417.559363 -230.626714)
			(xy 417.608963 -230.601213) (xy 417.661747 -230.583206) (xy 417.71659 -230.573076) (xy 417.772324 -230.571039)
			(xy 417.827761 -230.577139) (xy 417.881718 -230.591245) (xy 417.933047 -230.613057) (xy 417.980653 -230.642111)
			(xy 418.023521 -230.677786) (xy 418.060738 -230.719323) (xy 418.091511 -230.765836) (xy 418.115183 -230.816333)
			(xy 418.131251 -230.86974) (xy 418.139371 -230.924916) (xy 418.13988 -230.952802) (xy 418.139371 -230.980688)
			(xy 418.131251 -231.035864) (xy 418.115183 -231.089271) (xy 418.091511 -231.139768) (xy 418.060738 -231.186281)
			(xy 418.023521 -231.227818) (xy 417.980653 -231.263493) (xy 417.933047 -231.292547) (xy 417.881718 -231.314359)
			(xy 417.827761 -231.328465) (xy 417.772324 -231.334565) (xy 417.71659 -231.332528) (xy 417.661747 -231.322398)
			(xy 417.608963 -231.304391) (xy 417.559363 -231.27889) (xy 417.514005 -231.246439) (xy 417.473856 -231.20773)
			(xy 417.43977 -231.163587) (xy 417.412474 -231.114952) (xy 417.392551 -231.062861) (xy 417.380425 -231.008424)
			(xy 417.376354 -230.952802) (xy 393.247056 -230.952802) (xy 393.281709 -230.956615) (xy 393.335666 -230.970721)
			(xy 393.386995 -230.992533) (xy 393.434601 -231.021587) (xy 393.477469 -231.057262) (xy 393.514686 -231.098799)
			(xy 393.545459 -231.145312) (xy 393.569131 -231.195809) (xy 393.585199 -231.249216) (xy 393.593319 -231.304392)
			(xy 393.593828 -231.332278) (xy 393.593319 -231.360164) (xy 393.585199 -231.41534) (xy 393.569131 -231.468747)
			(xy 393.545459 -231.519244) (xy 393.514686 -231.565757) (xy 393.477469 -231.607294) (xy 393.434601 -231.642969)
			(xy 393.386995 -231.672023) (xy 393.335666 -231.693835) (xy 393.281709 -231.707941) (xy 393.226272 -231.714041)
			(xy 393.170538 -231.712004) (xy 393.115695 -231.701874) (xy 393.062911 -231.683867) (xy 393.013311 -231.658366)
			(xy 392.967953 -231.625915) (xy 392.927804 -231.587206) (xy 392.893718 -231.543063) (xy 392.866422 -231.494428)
			(xy 392.846499 -231.442337) (xy 392.834373 -231.3879) (xy 392.830302 -231.332278) (xy 387.585253 -231.332278)
			(xy 387.577869 -231.338423) (xy 387.530263 -231.367477) (xy 387.478934 -231.389289) (xy 387.424977 -231.403395)
			(xy 387.36954 -231.409495) (xy 387.313806 -231.407458) (xy 387.258963 -231.397328) (xy 387.206179 -231.379321)
			(xy 387.156579 -231.35382) (xy 387.111221 -231.321369) (xy 387.071072 -231.28266) (xy 387.036986 -231.238517)
			(xy 387.00969 -231.189882) (xy 386.989767 -231.137791) (xy 386.977641 -231.083354) (xy 386.97357 -231.027732)
			(xy 384.96847 -231.027732) (xy 384.948334 -231.076347) (xy 384.918353 -231.128276) (xy 384.88185 -231.175848)
			(xy 384.839451 -231.218248) (xy 384.79188 -231.254751) (xy 384.739951 -231.284732) (xy 384.684553 -231.307679)
			(xy 384.626634 -231.323199) (xy 384.567185 -231.331026) (xy 384.537204 -231.331516) (xy 383.673604 -231.331516)
			(xy 383.643615 -231.331139) (xy 383.584151 -231.323311) (xy 383.526216 -231.307788) (xy 383.470804 -231.284836)
			(xy 383.418862 -231.254847) (xy 383.371278 -231.218335) (xy 383.328867 -231.175925) (xy 383.292355 -231.128342)
			(xy 383.262366 -231.076399) (xy 383.239413 -231.020987) (xy 383.22389 -230.963053) (xy 383.216061 -230.903589)
			(xy 382.40975 -230.903589) (xy 382.425643 -230.937491) (xy 382.441711 -230.990898) (xy 382.449831 -231.046074)
			(xy 382.45034 -231.07396) (xy 382.449831 -231.101846) (xy 382.441711 -231.157022) (xy 382.425643 -231.210429)
			(xy 382.401971 -231.260926) (xy 382.371198 -231.307439) (xy 382.333981 -231.348976) (xy 382.291113 -231.384651)
			(xy 382.243507 -231.413705) (xy 382.192178 -231.435517) (xy 382.138221 -231.449623) (xy 382.082784 -231.455723)
			(xy 382.02705 -231.453686) (xy 381.972207 -231.443556) (xy 381.919423 -231.425549) (xy 381.869823 -231.400048)
			(xy 381.824465 -231.367597) (xy 381.784316 -231.328888) (xy 381.75023 -231.284745) (xy 381.722934 -231.23611)
			(xy 381.703011 -231.184019) (xy 381.690885 -231.129582) (xy 381.686814 -231.07396) (xy 377.414536 -231.07396)
			(xy 377.414536 -231.71658) (xy 377.414953 -231.726601) (xy 377.42262 -231.745119) (xy 377.436795 -231.759289)
			(xy 377.455315 -231.76695) (xy 377.465336 -231.76738) (xy 383.371852 -231.76738) (xy 383.404725 -231.767811)
			(xy 383.470059 -231.775148) (xy 383.534161 -231.789757) (xy 383.596223 -231.811455) (xy 383.655463 -231.839968)
			(xy 383.711137 -231.874938) (xy 383.762543 -231.915924) (xy 383.786126 -231.93883) (xy 384.316986 -232.46969)
			(xy 384.32433 -232.476504) (xy 384.342792 -232.484243) (xy 384.3528 -232.484676) (xy 392.930888 -232.484676)
			(xy 392.95705 -232.466388) (xy 392.962638 -232.451402) (xy 392.972629 -232.42606) (xy 392.998767 -232.378268)
			(xy 393.031437 -232.33468) (xy 393.069973 -232.296181) (xy 393.113594 -232.263554) (xy 393.161411 -232.237464)
			(xy 393.212453 -232.218439) (xy 393.265682 -232.206867) (xy 393.320016 -232.202983) (xy 393.37435 -232.206867)
			(xy 393.427579 -232.218439) (xy 393.478621 -232.237464) (xy 393.526438 -232.263554) (xy 393.570059 -232.296181)
			(xy 393.608595 -232.33468) (xy 393.641265 -232.378268) (xy 393.667403 -232.42606) (xy 393.677394 -232.451402)
			(xy 393.682982 -232.466388) (xy 393.709144 -232.484676) (xy 414.518348 -232.484676) (xy 414.528339 -232.484147)
			(xy 414.546783 -232.476445) (xy 414.554162 -232.46969) (xy 414.901126 -232.122726) (xy 414.924704 -232.099816)
			(xy 414.976118 -232.058843) (xy 415.031796 -232.023882) (xy 415.091037 -231.995373) (xy 415.153097 -231.973675)
			(xy 415.217196 -231.95906) (xy 415.282528 -231.951712) (xy 415.3154 -231.951276) (xy 418.794946 -231.951276)
			(xy 418.827819 -231.951706) (xy 418.893154 -231.959043) (xy 418.957256 -231.973651) (xy 419.019318 -231.995349)
			(xy 419.078559 -232.023861) (xy 419.134234 -232.058831) (xy 419.18564 -232.099816) (xy 419.20922 -232.122726)
			(xy 424.001184 -236.91469) (xy 424.008533 -236.921488) (xy 424.026996 -236.929192) (xy 424.036998 -236.929676)
		)
		(stroke
			(width 0)
			(type solid)
		)
		(fill yes)
		(layer "In13.Cu")
		(net "GND")
	)
	(gr_poly
		(pts
			(xy 292.978332 -204.32522) (xy 292.987705 -204.324873) (xy 293.005197 -204.318135) (xy 293.019055 -204.305515)
			(xy 293.023544 -204.29728) (xy 293.071042 -204.2033) (xy 293.068502 -204.174852) (xy 293.059866 -204.163168)
			(xy 293.042184 -204.138357) (xy 293.014104 -204.084291) (xy 292.99498 -204.026448) (xy 292.9853 -203.966299)
			(xy 292.984682 -203.935838) (xy 292.985168 -203.908587) (xy 292.992924 -203.854639) (xy 293.008279 -203.802344)
			(xy 293.030921 -203.752767) (xy 293.060387 -203.706917) (xy 293.096078 -203.665726) (xy 293.137269 -203.630035)
			(xy 293.183119 -203.600569) (xy 293.232696 -203.577927) (xy 293.284991 -203.562572) (xy 293.338939 -203.554816)
			(xy 293.393441 -203.554816) (xy 293.447389 -203.562572) (xy 293.499684 -203.577927) (xy 293.549261 -203.600569)
			(xy 293.595111 -203.630035) (xy 293.636302 -203.665726) (xy 293.671993 -203.706917) (xy 293.701459 -203.752767)
			(xy 293.724101 -203.802344) (xy 293.739456 -203.854639) (xy 293.747212 -203.908587) (xy 293.747698 -203.935838)
			(xy 293.747098 -203.966299) (xy 293.737405 -204.026446) (xy 293.718271 -204.084286) (xy 293.690184 -204.138348)
			(xy 293.672514 -204.163168) (xy 293.663878 -204.174852) (xy 293.661338 -204.2033) (xy 293.708836 -204.29728)
			(xy 293.713439 -204.305422) (xy 293.727293 -204.317964) (xy 293.744707 -204.324745) (xy 293.754048 -204.32522)
			(xy 297.613832 -204.32522) (xy 297.623579 -204.324789) (xy 297.641657 -204.317503) (xy 297.655684 -204.303968)
			(xy 297.66006 -204.295248) (xy 297.704002 -204.196696) (xy 297.69943 -204.167232) (xy 297.68927 -204.155802)
			(xy 297.670957 -204.134689) (xy 297.640066 -204.088113) (xy 297.616297 -204.037529) (xy 297.600159 -203.984021)
			(xy 297.591996 -203.928731) (xy 297.59148 -203.900786) (xy 297.591966 -203.873535) (xy 297.599722 -203.819587)
			(xy 297.615077 -203.767292) (xy 297.637719 -203.717715) (xy 297.667185 -203.671865) (xy 297.702876 -203.630674)
			(xy 297.744067 -203.594983) (xy 297.789917 -203.565517) (xy 297.839494 -203.542875) (xy 297.891789 -203.52752)
			(xy 297.945737 -203.519764) (xy 298.000239 -203.519764) (xy 298.054187 -203.52752) (xy 298.106482 -203.542875)
			(xy 298.156059 -203.565517) (xy 298.201909 -203.594983) (xy 298.2431 -203.630674) (xy 298.278791 -203.671865)
			(xy 298.308257 -203.717715) (xy 298.330899 -203.767292) (xy 298.346254 -203.819587) (xy 298.35401 -203.873535)
			(xy 298.354496 -203.900786) (xy 298.354007 -203.928732) (xy 298.34585 -203.984026) (xy 298.329708 -204.037536)
			(xy 298.305927 -204.088117) (xy 298.275016 -204.134684) (xy 298.256706 -204.155802) (xy 298.246546 -204.167232)
			(xy 298.241974 -204.196696) (xy 298.285916 -204.295248) (xy 298.290322 -204.303941) (xy 298.304364 -204.317432)
			(xy 298.32241 -204.32475) (xy 298.332144 -204.32522) (xy 298.771564 -204.32522) (xy 298.781527 -204.324735)
			(xy 298.799954 -204.31715) (xy 298.807378 -204.310488) (xy 300.146212 -202.971654) (xy 300.153061 -202.964257)
			(xy 300.160793 -202.945658) (xy 300.161198 -202.935586) (xy 300.161198 -200.1012) (xy 300.160775 -200.09113)
			(xy 300.15306 -200.072526) (xy 300.146212 -200.065132) (xy 298.949618 -198.868538) (xy 298.942217 -198.8617)
			(xy 298.923618 -198.85399) (xy 298.91355 -198.853552) (xy 280.216864 -198.853552) (xy 280.206798 -198.853121)
			(xy 280.188207 -198.845392) (xy 280.180796 -198.838566) (xy 280.086308 -198.744078) (xy 280.076402 -198.740268)
			(xy 280.054988 -198.731603) (xy 280.014593 -198.709191) (xy 279.977705 -198.681384) (xy 279.961086 -198.665338)
			(xy 265.909298 -184.61355) (xy 265.901902 -184.606698) (xy 265.883303 -184.598957) (xy 265.87323 -184.598564)
			(xy 261.351268 -184.598564) (xy 261.341201 -184.598134) (xy 261.322608 -184.590408) (xy 261.3152 -184.583578)
			(xy 260.738112 -184.00649) (xy 260.730767 -183.999679) (xy 260.712305 -183.991944) (xy 260.702298 -183.991504)
			(xy 260.465824 -183.991504) (xy 260.439747 -183.991037) (xy 260.388231 -183.982913) (xy 260.338621 -183.966829)
			(xy 260.292137 -183.943183) (xy 260.249925 -183.912556) (xy 260.231128 -183.894476) (xy 257.946906 -181.610254)
			(xy 257.93951 -181.603401) (xy 257.920912 -181.595656) (xy 257.910838 -181.595268) (xy 257.459734 -181.595268)
			(xy 257.449682 -181.595771) (xy 257.431117 -181.603488) (xy 257.423666 -181.610254) (xy 256.057654 -182.976266)
			(xy 256.050812 -182.983665) (xy 256.043093 -183.002264) (xy 256.042668 -183.012334) (xy 256.042668 -183.858408)
			(xy 256.043092 -183.868478) (xy 256.050805 -183.887084) (xy 256.057654 -183.894476) (xy 258.172527 -186.009349)
			(xy 261.43028 -186.009349) (xy 261.43028 -185.954851) (xy 261.438035 -185.900907) (xy 261.453388 -185.848615)
			(xy 261.476027 -185.799041) (xy 261.505489 -185.753192) (xy 261.541176 -185.712003) (xy 261.582362 -185.676312)
			(xy 261.628207 -185.646845) (xy 261.677779 -185.624202) (xy 261.730069 -185.608843) (xy 261.784013 -185.601082)
			(xy 261.811262 -185.600594) (xy 261.835623 -185.600999) (xy 261.883946 -185.607217) (xy 261.931083 -185.619543)
			(xy 261.976265 -185.637777) (xy 261.997698 -185.649362) (xy 262.005826 -185.653934) (xy 262.02386 -185.656474)
			(xy 262.107426 -185.638948) (xy 262.122666 -185.629296) (xy 262.128508 -185.62193) (xy 262.146628 -185.598797)
			(xy 262.188819 -185.557897) (xy 262.236777 -185.523944) (xy 262.289372 -185.49774) (xy 262.34536 -185.479903)
			(xy 262.40342 -185.470855) (xy 262.4328 -185.470292) (xy 262.460051 -185.470778) (xy 262.513999 -185.478534)
			(xy 262.566294 -185.493889) (xy 262.615871 -185.516531) (xy 262.661721 -185.545997) (xy 262.702912 -185.581688)
			(xy 262.738603 -185.622879) (xy 262.768069 -185.668729) (xy 262.790711 -185.718306) (xy 262.806066 -185.770601)
			(xy 262.813822 -185.824549) (xy 262.813822 -185.879051) (xy 262.806066 -185.932999) (xy 262.790711 -185.985294)
			(xy 262.768069 -186.034871) (xy 262.738603 -186.080721) (xy 262.702912 -186.121912) (xy 262.661721 -186.157603)
			(xy 262.615871 -186.187069) (xy 262.566294 -186.209711) (xy 262.513999 -186.225066) (xy 262.460051 -186.232822)
			(xy 262.4328 -186.233308) (xy 262.408439 -186.232918) (xy 262.360115 -186.226696) (xy 262.312978 -186.214365)
			(xy 262.267797 -186.196127) (xy 262.246364 -186.18454) (xy 262.238236 -186.179968) (xy 262.220202 -186.177428)
			(xy 262.136636 -186.194954) (xy 262.121396 -186.204606) (xy 262.115554 -186.211972) (xy 262.097399 -186.235076)
			(xy 262.055215 -186.275977) (xy 262.007264 -186.309933) (xy 261.954676 -186.336143) (xy 261.898695 -186.353986)
			(xy 261.84064 -186.363042) (xy 261.811262 -186.36361) (xy 261.784013 -186.363118) (xy 261.730069 -186.355357)
			(xy 261.677779 -186.339998) (xy 261.628207 -186.317355) (xy 261.582362 -186.287888) (xy 261.541176 -186.252197)
			(xy 261.505489 -186.211008) (xy 261.476027 -186.165159) (xy 261.453388 -186.115585) (xy 261.438035 -186.063293)
			(xy 261.43028 -186.009349) (xy 258.172527 -186.009349) (xy 259.621274 -187.458096) (xy 259.628682 -187.464785)
			(xy 259.647118 -187.472377) (xy 259.657088 -187.472828) (xy 263.938512 -187.472828) (xy 263.97139 -187.473305)
			(xy 264.03673 -187.480695) (xy 264.100833 -187.495348) (xy 264.162895 -187.517079) (xy 264.222136 -187.545615)
			(xy 264.277814 -187.5806) (xy 264.329229 -187.621592) (xy 264.352786 -187.644532) (xy 277.648504 -200.94025)
			(xy 292.043362 -200.94025) (xy 292.043362 -200.88575) (xy 292.051117 -200.831803) (xy 292.066471 -200.77951)
			(xy 292.08911 -200.729933) (xy 292.118574 -200.684083) (xy 292.154262 -200.642892) (xy 292.195449 -200.607199)
			(xy 292.241296 -200.57773) (xy 292.29087 -200.555086) (xy 292.343162 -200.539726) (xy 292.397108 -200.531965)
			(xy 292.424358 -200.531476) (xy 292.45082 -200.53195) (xy 292.503237 -200.539248) (xy 292.554142 -200.553722)
			(xy 292.602557 -200.575096) (xy 292.647552 -200.602959) (xy 292.688262 -200.636775) (xy 292.723906 -200.675894)
			(xy 292.753799 -200.719567) (xy 292.765988 -200.743058) (xy 292.772338 -200.756012) (xy 292.796214 -200.770998)
			(xy 292.915086 -200.773284) (xy 292.93947 -200.75906) (xy 292.946328 -200.74636) (xy 292.960762 -200.720886)
			(xy 292.996205 -200.674284) (xy 293.038352 -200.633646) (xy 293.086213 -200.599923) (xy 293.138665 -200.57391)
			(xy 293.194475 -200.556216) (xy 293.252334 -200.547256) (xy 293.281608 -200.546716) (xy 293.307713 -200.547177)
			(xy 293.359433 -200.554305) (xy 293.4097 -200.568413) (xy 293.457577 -200.589237) (xy 293.50217 -200.61639)
			(xy 293.542648 -200.649365) (xy 293.578256 -200.687548) (xy 293.60833 -200.730225) (xy 293.620698 -200.753218)
			(xy 293.627048 -200.765664) (xy 293.650416 -200.780396) (xy 293.76751 -200.783444) (xy 293.79164 -200.769982)
			(xy 293.798752 -200.75779) (xy 293.813578 -200.73354) (xy 293.84918 -200.689238) (xy 293.89096 -200.650709)
			(xy 293.937996 -200.618806) (xy 293.989244 -200.594236) (xy 294.043571 -200.577541) (xy 294.099773 -200.569092)
			(xy 294.12819 -200.56856) (xy 294.157562 -200.569104) (xy 294.215609 -200.578134) (xy 294.271586 -200.595953)
			(xy 294.324172 -200.622138) (xy 294.372125 -200.656072) (xy 294.414311 -200.696953) (xy 294.449735 -200.743816)
			(xy 294.47756 -200.795553) (xy 294.487854 -200.823068) (xy 294.49268 -200.836276) (xy 294.514016 -200.854056)
			(xy 294.630094 -200.872344) (xy 294.656002 -200.86193) (xy 294.664638 -200.850754) (xy 294.682815 -200.827854)
			(xy 294.724945 -200.78732) (xy 294.772768 -200.75369) (xy 294.825163 -200.727754) (xy 294.880904 -200.710119)
			(xy 294.938682 -200.701198) (xy 294.967914 -200.70064) (xy 294.995168 -200.701031) (xy 295.049121 -200.70879)
			(xy 295.101421 -200.724148) (xy 295.151002 -200.746793) (xy 295.196857 -200.776263) (xy 295.238051 -200.811959)
			(xy 295.273745 -200.853154) (xy 295.303214 -200.89901) (xy 295.325857 -200.948592) (xy 295.341213 -201.000893)
			(xy 295.34897 -201.054846) (xy 295.34897 -201.109354) (xy 295.343788 -201.145394) (xy 297.73702 -201.145394)
			(xy 297.741091 -201.089772) (xy 297.753217 -201.035335) (xy 297.77314 -200.983244) (xy 297.800436 -200.934609)
			(xy 297.834522 -200.890466) (xy 297.874671 -200.851757) (xy 297.920029 -200.819306) (xy 297.969629 -200.793805)
			(xy 298.022413 -200.775798) (xy 298.077256 -200.765668) (xy 298.13299 -200.763631) (xy 298.188427 -200.769731)
			(xy 298.242384 -200.783837) (xy 298.293713 -200.805649) (xy 298.341319 -200.834703) (xy 298.384187 -200.870378)
			(xy 298.421404 -200.911915) (xy 298.452177 -200.958428) (xy 298.475849 -201.008925) (xy 298.491917 -201.062332)
			(xy 298.500037 -201.117508) (xy 298.500546 -201.145394) (xy 298.500037 -201.17328) (xy 298.491917 -201.228456)
			(xy 298.475849 -201.281863) (xy 298.452177 -201.33236) (xy 298.421404 -201.378873) (xy 298.384187 -201.42041)
			(xy 298.341319 -201.456085) (xy 298.293713 -201.485139) (xy 298.242384 -201.506951) (xy 298.188427 -201.521057)
			(xy 298.13299 -201.527157) (xy 298.077256 -201.52512) (xy 298.022413 -201.51499) (xy 297.969629 -201.496983)
			(xy 297.920029 -201.471482) (xy 297.874671 -201.439031) (xy 297.834522 -201.400322) (xy 297.800436 -201.356179)
			(xy 297.77314 -201.307544) (xy 297.753217 -201.255453) (xy 297.741091 -201.201016) (xy 297.73702 -201.145394)
			(xy 295.343788 -201.145394) (xy 295.341213 -201.163307) (xy 295.325857 -201.215608) (xy 295.303214 -201.26519)
			(xy 295.273745 -201.311046) (xy 295.238051 -201.352241) (xy 295.196857 -201.387937) (xy 295.151002 -201.417407)
			(xy 295.101421 -201.440052) (xy 295.049121 -201.45541) (xy 294.995168 -201.463169) (xy 294.967914 -201.463656)
			(xy 294.938542 -201.463098) (xy 294.880497 -201.454069) (xy 294.82452 -201.436252) (xy 294.771935 -201.410068)
			(xy 294.723983 -201.376136) (xy 294.681796 -201.335257) (xy 294.646371 -201.288397) (xy 294.618545 -201.236662)
			(xy 294.60825 -201.209148) (xy 294.603424 -201.19594) (xy 294.582088 -201.17816) (xy 294.46601 -201.159872)
			(xy 294.440102 -201.170286) (xy 294.431466 -201.181462) (xy 294.413286 -201.204361) (xy 294.371161 -201.244904)
			(xy 294.32334 -201.27854) (xy 294.270945 -201.304482) (xy 294.215204 -201.322122) (xy 294.157423 -201.331046)
			(xy 294.12819 -201.331576) (xy 294.102085 -201.33112) (xy 294.050364 -201.323992) (xy 294.000097 -201.309884)
			(xy 293.95222 -201.289059) (xy 293.907627 -201.261905) (xy 293.867149 -201.228929) (xy 293.831541 -201.190746)
			(xy 293.801468 -201.148067) (xy 293.7891 -201.125074) (xy 293.78275 -201.112628) (xy 293.759382 -201.097896)
			(xy 293.642288 -201.094848) (xy 293.618158 -201.10831) (xy 293.611046 -201.120502) (xy 293.596255 -201.144774)
			(xy 293.560644 -201.189071) (xy 293.518856 -201.227595) (xy 293.471814 -201.259494) (xy 293.420562 -201.284061)
			(xy 293.366231 -201.300753) (xy 293.310026 -201.309201) (xy 293.281608 -201.309732) (xy 293.255146 -201.309282)
			(xy 293.202727 -201.30198) (xy 293.151822 -201.287501) (xy 293.103407 -201.266123) (xy 293.058413 -201.238257)
			(xy 293.017703 -201.204439) (xy 292.982059 -201.165317) (xy 292.952167 -201.121642) (xy 292.939978 -201.09815)
			(xy 292.933628 -201.085196) (xy 292.909752 -201.07021) (xy 292.79088 -201.067924) (xy 292.766496 -201.082148)
			(xy 292.759638 -201.094848) (xy 292.745192 -201.120316) (xy 292.709755 -201.166921) (xy 292.667612 -201.207564)
			(xy 292.619753 -201.241289) (xy 292.567302 -201.267304) (xy 292.511491 -201.284997) (xy 292.453632 -201.293954)
			(xy 292.424358 -201.294492) (xy 292.397108 -201.294035) (xy 292.343162 -201.286274) (xy 292.29087 -201.270914)
			(xy 292.241296 -201.24827) (xy 292.195449 -201.218801) (xy 292.154262 -201.183108) (xy 292.118574 -201.141917)
			(xy 292.08911 -201.096067) (xy 292.066471 -201.04649) (xy 292.051117 -200.994197) (xy 292.043362 -200.94025)
			(xy 277.648504 -200.94025) (xy 278.439372 -201.731118) (xy 290.679122 -201.731118) (xy 290.683193 -201.675496)
			(xy 290.695319 -201.621059) (xy 290.715242 -201.568968) (xy 290.742538 -201.520333) (xy 290.776624 -201.47619)
			(xy 290.816773 -201.437481) (xy 290.862131 -201.40503) (xy 290.911731 -201.379529) (xy 290.964515 -201.361522)
			(xy 291.019358 -201.351392) (xy 291.075092 -201.349355) (xy 291.130529 -201.355455) (xy 291.184486 -201.369561)
			(xy 291.235815 -201.391373) (xy 291.283421 -201.420427) (xy 291.326289 -201.456102) (xy 291.363506 -201.497639)
			(xy 291.394279 -201.544152) (xy 291.417951 -201.594649) (xy 291.434019 -201.648056) (xy 291.442139 -201.703232)
			(xy 291.442648 -201.731118) (xy 291.442139 -201.759004) (xy 291.434019 -201.81418) (xy 291.417951 -201.867587)
			(xy 291.394279 -201.918084) (xy 291.363506 -201.964597) (xy 291.326289 -202.006134) (xy 291.283421 -202.041809)
			(xy 291.235815 -202.070863) (xy 291.184486 -202.092675) (xy 291.130529 -202.106781) (xy 291.075092 -202.112881)
			(xy 291.019358 -202.110844) (xy 290.964515 -202.100714) (xy 290.911731 -202.082707) (xy 290.862131 -202.057206)
			(xy 290.816773 -202.024755) (xy 290.776624 -201.986046) (xy 290.742538 -201.941903) (xy 290.715242 -201.893268)
			(xy 290.695319 -201.841177) (xy 290.683193 -201.78674) (xy 290.679122 -201.731118) (xy 278.439372 -201.731118)
			(xy 280.136854 -203.4286) (xy 294.389046 -203.4286) (xy 294.393117 -203.372978) (xy 294.405243 -203.318541)
			(xy 294.425166 -203.26645) (xy 294.452462 -203.217815) (xy 294.486548 -203.173672) (xy 294.526697 -203.134963)
			(xy 294.572055 -203.102512) (xy 294.621655 -203.077011) (xy 294.674439 -203.059004) (xy 294.729282 -203.048874)
			(xy 294.785016 -203.046837) (xy 294.840453 -203.052937) (xy 294.89441 -203.067043) (xy 294.945739 -203.088855)
			(xy 294.993345 -203.117909) (xy 295.036213 -203.153584) (xy 295.07343 -203.195121) (xy 295.104203 -203.241634)
			(xy 295.127875 -203.292131) (xy 295.143943 -203.345538) (xy 295.152063 -203.400714) (xy 295.152572 -203.4286)
			(xy 295.152063 -203.456486) (xy 295.143943 -203.511662) (xy 295.127875 -203.565069) (xy 295.104203 -203.615566)
			(xy 295.07343 -203.662079) (xy 295.036213 -203.703616) (xy 294.993345 -203.739291) (xy 294.945739 -203.768345)
			(xy 294.926958 -203.776326) (xy 295.45991 -203.776326) (xy 295.463981 -203.720704) (xy 295.476107 -203.666267)
			(xy 295.49603 -203.614176) (xy 295.523326 -203.565541) (xy 295.557412 -203.521398) (xy 295.597561 -203.482689)
			(xy 295.642919 -203.450238) (xy 295.692519 -203.424737) (xy 295.745303 -203.40673) (xy 295.800146 -203.3966)
			(xy 295.85588 -203.394563) (xy 295.911317 -203.400663) (xy 295.92005 -203.402946) (xy 296.611546 -203.402946)
			(xy 296.615617 -203.347324) (xy 296.627743 -203.292887) (xy 296.647666 -203.240796) (xy 296.674962 -203.192161)
			(xy 296.709048 -203.148018) (xy 296.749197 -203.109309) (xy 296.794555 -203.076858) (xy 296.844155 -203.051357)
			(xy 296.896939 -203.03335) (xy 296.951782 -203.02322) (xy 297.007516 -203.021183) (xy 297.062953 -203.027283)
			(xy 297.11691 -203.041389) (xy 297.168239 -203.063201) (xy 297.215845 -203.092255) (xy 297.258713 -203.12793)
			(xy 297.29593 -203.169467) (xy 297.326703 -203.21598) (xy 297.350375 -203.266477) (xy 297.366443 -203.319884)
			(xy 297.374563 -203.37506) (xy 297.375072 -203.402946) (xy 297.374563 -203.430832) (xy 297.366443 -203.486008)
			(xy 297.350375 -203.539415) (xy 297.326703 -203.589912) (xy 297.29593 -203.636425) (xy 297.258713 -203.677962)
			(xy 297.215845 -203.713637) (xy 297.168239 -203.742691) (xy 297.11691 -203.764503) (xy 297.062953 -203.778609)
			(xy 297.007516 -203.784709) (xy 296.951782 -203.782672) (xy 296.896939 -203.772542) (xy 296.844155 -203.754535)
			(xy 296.794555 -203.729034) (xy 296.749197 -203.696583) (xy 296.709048 -203.657874) (xy 296.674962 -203.613731)
			(xy 296.647666 -203.565096) (xy 296.627743 -203.513005) (xy 296.615617 -203.458568) (xy 296.611546 -203.402946)
			(xy 295.92005 -203.402946) (xy 295.965274 -203.414769) (xy 296.016603 -203.436581) (xy 296.064209 -203.465635)
			(xy 296.107077 -203.50131) (xy 296.144294 -203.542847) (xy 296.175067 -203.58936) (xy 296.198739 -203.639857)
			(xy 296.214807 -203.693264) (xy 296.222927 -203.74844) (xy 296.223436 -203.776326) (xy 296.222927 -203.804212)
			(xy 296.214807 -203.859388) (xy 296.198739 -203.912795) (xy 296.175067 -203.963292) (xy 296.144294 -204.009805)
			(xy 296.107077 -204.051342) (xy 296.064209 -204.087017) (xy 296.016603 -204.116071) (xy 295.965274 -204.137883)
			(xy 295.911317 -204.151989) (xy 295.85588 -204.158089) (xy 295.800146 -204.156052) (xy 295.745303 -204.145922)
			(xy 295.692519 -204.127915) (xy 295.642919 -204.102414) (xy 295.597561 -204.069963) (xy 295.557412 -204.031254)
			(xy 295.523326 -203.987111) (xy 295.49603 -203.938476) (xy 295.476107 -203.886385) (xy 295.463981 -203.831948)
			(xy 295.45991 -203.776326) (xy 294.926958 -203.776326) (xy 294.89441 -203.790157) (xy 294.840453 -203.804263)
			(xy 294.785016 -203.810363) (xy 294.729282 -203.808326) (xy 294.674439 -203.798196) (xy 294.621655 -203.780189)
			(xy 294.572055 -203.754688) (xy 294.526697 -203.722237) (xy 294.486548 -203.683528) (xy 294.452462 -203.639385)
			(xy 294.425166 -203.59075) (xy 294.405243 -203.538659) (xy 294.393117 -203.484222) (xy 294.389046 -203.4286)
			(xy 280.136854 -203.4286) (xy 281.018742 -204.310488) (xy 281.026153 -204.317167) (xy 281.04459 -204.324736)
			(xy 281.054556 -204.32522)
		)
		(stroke
			(width 0)
			(type solid)
		)
		(fill yes)
		(layer "In13.Cu")
		(net "P1V8_PEX")
	)
	(gr_poly
		(pts
			(arc
				(start 200.481692 -418.081968)
				(mid 201.086106 -417.953924)
				(end 201.586846 -417.592002)
			)
			(arc
				(start 201.586846 -417.592002)
				(mid 202.42889 -416.98332)
				(end 203.445364 -416.768026)
			)
			(arc
				(start 271.794732 -416.768026)
				(mid 272.811071 -416.983322)
				(end 273.652996 -417.592002)
			)
			(arc
				(start 273.652996 -417.592002)
				(mid 274.153727 -417.953921)
				(end 274.75815 -418.081968)
			)
			(arc
				(start 465.600034 -418.081968)
				(mid 466.655034 -417.644972)
				(end 467.09203 -416.589972)
			)
			(arc
				(start 467.09203 -246.488204)
				(mid 466.978493 -245.917325)
				(end 466.65515 -245.433342)
			)
			(arc
				(start 464.026504 -242.80495)
				(mid 463.482885 -241.991412)
				(end 463.291936 -241.031776)
			)
			(arc
				(start 463.291936 -87.588344)
				(mid 463.482826 -86.628673)
				(end 464.026504 -85.81517)
			)
			(arc
				(start 466.65515 -83.186524)
				(mid 466.978483 -82.702667)
				(end 467.09203 -82.131916)
			)
			(arc
				(start 467.09203 -1.999996)
				(mid 466.655034 -0.944996)
				(end 465.600034 -0.508)
			)
			(arc
				(start 446.265046 -0.508)
				(mid 445.210046 -0.944996)
				(end 444.77305 -1.999996)
			)
			(arc
				(start 444.77305 -11.850116)
				(mid 444.676277 -12.381671)
				(end 444.3984 -12.845034)
			)
			(xy 444.3984 -12.869164) (xy 444.399924 -12.870688)
			(arc
				(start 445.002666 -12.870688)
				(mid 445.20965 -12.378943)
				(end 445.280288 -11.850116)
			)
			(arc
				(start 445.280288 -1.999996)
				(mid 445.568553 -1.303936)
				(end 446.264538 -1.015492)
			)
			(arc
				(start 465.600034 -1.015492)
				(mid 466.296273 -1.303831)
				(end 466.584792 -1.999996)
			)
			(arc
				(start 466.584792 -82.131916)
				(mid 466.509885 -82.508586)
				(end 466.296502 -82.827876)
			)
			(arc
				(start 463.667856 -85.456522)
				(mid 463.014235 -86.434595)
				(end 462.784698 -87.588344)
			)
			(xy 462.784444 -87.588344) (xy 462.784444 -241.031776)
			(arc
				(start 462.784698 -241.031776)
				(mid 463.014268 -242.185519)
				(end 463.667856 -243.163598)
			)
			(arc
				(start 466.296502 -245.79199)
				(mid 466.509882 -246.11143)
				(end 466.584792 -246.488204)
			)
			(arc
				(start 466.584792 -416.589972)
				(mid 466.296527 -417.286032)
				(end 465.600542 -417.574476)
			)
			(xy 414.915604 -417.574476) (xy 414.915604 -417.797742) (xy 400.95424 -417.797742) (xy 400.95424 -417.574476)
			(xy 326.621648 -417.574476) (xy 326.621648 -417.747958) (xy 313.065922 -417.747958) (xy 313.065922 -417.574476)
			(arc
				(start 274.757896 -417.574476)
				(mid 274.359217 -417.490052)
				(end 274.028916 -417.251388)
			)
			(arc
				(start 274.028916 -417.251388)
				(mid 273.01669 -416.519565)
				(end 271.794732 -416.260788)
			)
			(arc
				(start 203.445364 -416.260788)
				(mid 202.223266 -416.519531)
				(end 201.210926 -417.251388)
			)
			(arc
				(start 201.210926 -417.251388)
				(mid 200.880626 -417.490098)
				(end 200.481946 -417.574476)
			)
			(xy 154.673554 -417.574476) (xy 154.673554 -417.693856) (xy 141.027912 -417.693856) (xy 141.027912 -417.574476)
			(xy 66.745104 -417.574476) (xy 66.745104 -417.671758) (xy 53.039772 -417.671758) (xy 53.039772 -417.574476)
			(arc
				(start 1.999996 -417.574476)
				(mid 1.303847 -417.286121)
				(end 1.015492 -416.589972)
			)
			(arc
				(start 1.015492 -246.48795)
				(mid 1.090466 -246.111319)
				(end 1.303782 -245.79199)
			)
			(arc
				(start 3.93192 -243.163852)
				(mid 4.58575 -242.18556)
				(end 4.815332 -241.031522)
			)
			(arc
				(start 4.815332 -87.588344)
				(mid 4.585694 -86.434435)
				(end 3.93192 -85.456268)
			)
			(arc
				(start 1.303528 -82.827876)
				(mid 1.090411 -82.508641)
				(end 1.015492 -82.13217)
			)
			(arc
				(start 1.015492 -1.999996)
				(mid 1.303847 -1.303847)
				(end 1.999996 -1.015492)
			)
			(arc
				(start 5.964936 -1.015492)
				(mid 6.661085 -1.303847)
				(end 6.94944 -1.999996)
			)
			(arc
				(start 6.94944 -11.850116)
				(mid 7.539853 -13.275118)
				(end 8.96493 -13.865352)
			)
			(xy 16.2814 -13.865352) (xy 16.371316 -13.775436) (xy 16.371316 -13.44803) (xy 16.2814 -13.358114)
			(arc
				(start 8.96493 -13.358114)
				(mid 7.898614 -12.916432)
				(end 7.456932 -11.850116)
			)
			(arc
				(start 7.456932 -1.999996)
				(mid 7.019936 -0.944996)
				(end 5.964936 -0.508)
			)
			(arc
				(start 1.999996 -0.508)
				(mid 0.944996 -0.944996)
				(end 0.508 -1.999996)
			)
			(arc
				(start 0.508 -82.131916)
				(mid 0.621601 -82.702644)
				(end 0.94488 -83.186524)
			)
			(arc
				(start 3.573272 -85.81517)
				(mid 4.117081 -86.628665)
				(end 4.308094 -87.588344)
			)
			(arc
				(start 4.308094 -241.031522)
				(mid 4.117082 -241.991334)
				(end 3.573272 -242.80495)
			)
			(arc
				(start 0.94488 -245.433342)
				(mid 0.621552 -245.917331)
				(end 0.508 -246.488204)
			)
			(arc
				(start 0.508 -416.589972)
				(mid 0.944996 -417.644972)
				(end 1.999996 -418.081968)
			)
		)
		(stroke
			(width 0)
			(type solid)
		)
		(fill yes)
		(layer "In13.Cu")
		(net "GND")
	)
	(gr_poly
		(pts
			(xy 462.542128 -321.566286) (xy 462.552004 -321.565824) (xy 462.570299 -321.558377) (xy 462.577688 -321.551808)
			(xy 462.577942 -321.551554) (xy 462.909158 -321.220338) (xy 462.909666 -321.21983) (xy 462.916244 -321.212447)
			(xy 462.923687 -321.194148) (xy 462.924144 -321.18427) (xy 462.924144 -317.052706) (xy 462.92367 -317.042473)
			(xy 462.91568 -317.023629) (xy 462.900993 -317.009372) (xy 462.891632 -317.005208) (xy 462.815757 -316.97563)
			(xy 462.666642 -316.910124) (xy 462.520857 -316.837508) (xy 462.37874 -316.757953) (xy 462.240621 -316.671642)
			(xy 462.106821 -316.578776) (xy 461.977652 -316.479571) (xy 461.853412 -316.374258) (xy 461.734392 -316.26308)
			(xy 461.620867 -316.146297) (xy 461.5131 -316.024178) (xy 461.411344 -315.89701) (xy 461.315832 -315.765085)
			(xy 461.226789 -315.628712) (xy 461.14442 -315.488207) (xy 461.068917 -315.343896) (xy 461.000455 -315.196115)
			(xy 460.939193 -315.045206) (xy 460.885274 -314.891521) (xy 460.838823 -314.735416) (xy 460.799948 -314.577255)
			(xy 460.768738 -314.417404) (xy 460.745268 -314.256235) (xy 460.72959 -314.094122) (xy 460.721742 -313.931442)
			(xy 460.721742 -313.768573) (xy 460.729589 -313.605893) (xy 460.745266 -313.44378) (xy 460.768736 -313.28261)
			(xy 460.799945 -313.122759) (xy 460.838819 -312.964597) (xy 460.88527 -312.808493) (xy 460.939188 -312.654807)
			(xy 461.000449 -312.503898) (xy 461.068911 -312.356117) (xy 461.144413 -312.211806) (xy 461.226781 -312.0713)
			(xy 461.315824 -311.934926) (xy 461.411335 -311.803002) (xy 461.513091 -311.675832) (xy 461.620857 -311.553714)
			(xy 461.734382 -311.43693) (xy 461.853402 -311.325752) (xy 461.977641 -311.220438) (xy 462.10681 -311.121232)
			(xy 462.240609 -311.028366) (xy 462.378727 -310.942054) (xy 462.520844 -310.862498) (xy 462.666629 -310.789882)
			(xy 462.815744 -310.724376) (xy 462.891632 -310.694832) (xy 462.901026 -310.690721) (xy 462.915737 -310.676465)
			(xy 462.923675 -310.65758) (xy 462.924144 -310.647334) (xy 462.924144 -309.967884) (xy 462.923654 -309.957875)
			(xy 462.915993 -309.939381) (xy 462.901842 -309.925223) (xy 462.883352 -309.917552) (xy 462.873344 -309.917084)
			(xy 462.18475 -309.917084) (xy 462.174786 -309.917567) (xy 462.156356 -309.925149) (xy 462.148936 -309.931816)
			(xy 461.018128 -311.062624) (xy 461.011778 -311.073292) (xy 461.009746 -311.079134) (xy 461.001352 -311.104841)
			(xy 460.977406 -311.153325) (xy 460.945913 -311.197283) (xy 460.927196 -311.216802) (xy 460.453232 -311.690512)
			(xy 460.44993 -311.696862) (xy 460.435351 -311.721926) (xy 460.399801 -311.76773) (xy 460.357737 -311.807634)
			(xy 460.310123 -311.840721) (xy 460.258055 -311.86623) (xy 460.20273 -311.883576) (xy 460.145418 -311.89236)
			(xy 460.116428 -311.89295) (xy 460.089174 -311.892466) (xy 460.035221 -311.884713) (xy 459.982921 -311.869361)
			(xy 459.933337 -311.846722) (xy 459.88748 -311.817257) (xy 459.846283 -311.781566) (xy 459.810585 -311.740376)
			(xy 459.781112 -311.694524) (xy 459.758464 -311.644945) (xy 459.743102 -311.592647) (xy 459.735339 -311.538696)
			(xy 459.73492 -311.511442) (xy 459.735391 -311.484449) (xy 459.743007 -311.431001) (xy 459.758078 -311.379161)
			(xy 459.780303 -311.329961) (xy 459.80924 -311.284384) (xy 459.84431 -311.243339) (xy 459.884814 -311.207646)
			(xy 459.929944 -311.178016) (xy 459.978798 -311.155042) (xy 460.030402 -311.13918) (xy 460.056992 -311.134506)
			(xy 460.06512 -311.133236) (xy 460.079344 -311.12587) (xy 460.366872 -310.838342) (xy 460.373222 -310.827674)
			(xy 460.375254 -310.821832) (xy 460.383643 -310.796122) (xy 460.407583 -310.747632) (xy 460.43907 -310.703667)
			(xy 460.457804 -310.684164) (xy 461.791558 -309.35041) (xy 461.810338 -309.332298) (xy 461.852536 -309.301614)
			(xy 461.899017 -309.277915) (xy 461.948635 -309.261787) (xy 462.000167 -309.253626) (xy 462.026254 -309.253128)
			(xy 463.592672 -309.253128) (xy 463.602634 -309.252642) (xy 463.62106 -309.245056) (xy 463.628486 -309.238396)
			(xy 464.83143 -308.035452) (xy 464.838277 -308.028054) (xy 464.846005 -308.009455) (xy 464.846416 -307.999384)
			(xy 464.846416 -304.781966) (xy 464.845987 -304.771898) (xy 464.838266 -304.753301) (xy 464.83143 -304.745898)
			(xy 464.726528 -304.640996) (xy 464.719125 -304.634161) (xy 464.700527 -304.626454) (xy 464.69046 -304.62601)
			(xy 449.617846 -304.62601) (xy 449.60778 -304.626443) (xy 449.589191 -304.634173) (xy 449.581778 -304.640996)
			(xy 448.86118 -305.361594) (xy 448.854324 -305.368988) (xy 448.846575 -305.387587) (xy 448.846194 -305.397662)
			(xy 448.846194 -305.4858) (xy 448.846427 -305.493069) (xy 448.850565 -305.507004) (xy 448.854322 -305.513232)
			(xy 448.871594 -305.54041) (xy 448.882262 -305.549808) (xy 448.888866 -305.552856) (xy 448.963814 -305.588688)
			(xy 449.110481 -305.666743) (xy 449.253134 -305.751912) (xy 449.391429 -305.84399) (xy 449.525031 -305.942753)
			(xy 449.653618 -306.047964) (xy 449.77608 -306.158646) (xy 459.899002 -306.158646) (xy 459.903073 -306.103024)
			(xy 459.915199 -306.048587) (xy 459.935122 -305.996496) (xy 459.962418 -305.947861) (xy 459.996504 -305.903718)
			(xy 460.036653 -305.865009) (xy 460.082011 -305.832558) (xy 460.131611 -305.807057) (xy 460.184395 -305.78905)
			(xy 460.239238 -305.77892) (xy 460.294972 -305.776883) (xy 460.350409 -305.782983) (xy 460.404366 -305.797089)
			(xy 460.455695 -305.818901) (xy 460.503301 -305.847955) (xy 460.546169 -305.88363) (xy 460.583386 -305.925167)
			(xy 460.614159 -305.97168) (xy 460.637831 -306.022177) (xy 460.653899 -306.075584) (xy 460.662019 -306.13076)
			(xy 460.662528 -306.158646) (xy 460.662019 -306.186532) (xy 460.653899 -306.241708) (xy 460.637831 -306.295115)
			(xy 460.614159 -306.345612) (xy 460.583386 -306.392125) (xy 460.546169 -306.433662) (xy 460.503301 -306.469337)
			(xy 460.455695 -306.498391) (xy 460.404366 -306.520203) (xy 460.350409 -306.534309) (xy 460.294972 -306.540409)
			(xy 460.239238 -306.538372) (xy 460.184395 -306.528242) (xy 460.131611 -306.510235) (xy 460.082011 -306.484734)
			(xy 460.036653 -306.452283) (xy 459.996504 -306.413574) (xy 459.962418 -306.369431) (xy 459.935122 -306.320796)
			(xy 459.915199 -306.268705) (xy 459.903073 -306.214268) (xy 459.899002 -306.158646) (xy 449.77608 -306.158646)
			(xy 449.776878 -306.159367) (xy 449.894513 -306.276694) (xy 450.00624 -306.399661) (xy 450.111788 -306.527971)
			(xy 450.210902 -306.661313) (xy 450.303342 -306.799366) (xy 450.3443 -306.86756) (xy 452.570594 -306.86756)
			(xy 452.574665 -306.811938) (xy 452.586791 -306.757501) (xy 452.606714 -306.70541) (xy 452.63401 -306.656775)
			(xy 452.668096 -306.612632) (xy 452.708245 -306.573923) (xy 452.753603 -306.541472) (xy 452.803203 -306.515971)
			(xy 452.855987 -306.497964) (xy 452.91083 -306.487834) (xy 452.966564 -306.485797) (xy 453.022001 -306.491897)
			(xy 453.075958 -306.506003) (xy 453.127287 -306.527815) (xy 453.174893 -306.556869) (xy 453.217761 -306.592544)
			(xy 453.254978 -306.634081) (xy 453.285751 -306.680594) (xy 453.309423 -306.731091) (xy 453.325491 -306.784498)
			(xy 453.333611 -306.839674) (xy 453.33412 -306.86756) (xy 453.333611 -306.895446) (xy 453.325491 -306.950622)
			(xy 453.309423 -307.004029) (xy 453.285751 -307.054526) (xy 453.254978 -307.101039) (xy 453.217761 -307.142576)
			(xy 453.174893 -307.178251) (xy 453.127287 -307.207305) (xy 453.075958 -307.229117) (xy 453.022001 -307.243223)
			(xy 452.966564 -307.249323) (xy 452.91083 -307.247286) (xy 452.855987 -307.237156) (xy 452.803203 -307.219149)
			(xy 452.753603 -307.193648) (xy 452.708245 -307.161197) (xy 452.668096 -307.122488) (xy 452.63401 -307.078345)
			(xy 452.606714 -307.02971) (xy 452.586791 -306.977619) (xy 452.574665 -306.923182) (xy 452.570594 -306.86756)
			(xy 450.3443 -306.86756) (xy 450.388886 -306.941795) (xy 450.467326 -307.088256) (xy 450.538472 -307.238396)
			(xy 450.602153 -307.391851) (xy 450.658215 -307.54825) (xy 450.664785 -307.56987) (xy 457.496162 -307.56987)
			(xy 457.500233 -307.514248) (xy 457.512359 -307.459811) (xy 457.532282 -307.40772) (xy 457.559578 -307.359085)
			(xy 457.593664 -307.314942) (xy 457.633813 -307.276233) (xy 457.679171 -307.243782) (xy 457.728771 -307.218281)
			(xy 457.781555 -307.200274) (xy 457.836398 -307.190144) (xy 457.892132 -307.188107) (xy 457.947569 -307.194207)
			(xy 458.001526 -307.208313) (xy 458.052855 -307.230125) (xy 458.100461 -307.259179) (xy 458.143329 -307.294854)
			(xy 458.180546 -307.336391) (xy 458.211319 -307.382904) (xy 458.234991 -307.433401) (xy 458.251059 -307.486808)
			(xy 458.259179 -307.541984) (xy 458.259688 -307.56987) (xy 458.259179 -307.597756) (xy 458.257713 -307.607716)
			(xy 462.556604 -307.607716) (xy 462.560677 -307.552057) (xy 462.572812 -307.497584) (xy 462.592748 -307.445458)
			(xy 462.620062 -307.39679) (xy 462.65417 -307.352618) (xy 462.694347 -307.313883) (xy 462.739735 -307.281411)
			(xy 462.789367 -307.255893) (xy 462.842187 -307.237874) (xy 462.897066 -307.227737) (xy 462.952837 -307.225699)
			(xy 463.008311 -307.231802) (xy 463.062304 -307.245918) (xy 463.113667 -307.267745) (xy 463.161305 -307.296818)
			(xy 463.204201 -307.332517) (xy 463.241443 -307.374081) (xy 463.272237 -307.420625) (xy 463.295925 -307.471156)
			(xy 463.312003 -307.524598) (xy 463.320129 -307.579812) (xy 463.320638 -307.607716) (xy 463.320129 -307.63562)
			(xy 463.312003 -307.690834) (xy 463.295925 -307.744276) (xy 463.272237 -307.794807) (xy 463.241443 -307.841351)
			(xy 463.204201 -307.882915) (xy 463.161305 -307.918614) (xy 463.113667 -307.947687) (xy 463.062304 -307.969514)
			(xy 463.008311 -307.98363) (xy 462.952837 -307.989733) (xy 462.897066 -307.987695) (xy 462.842187 -307.977558)
			(xy 462.789367 -307.959539) (xy 462.739735 -307.934021) (xy 462.694347 -307.901549) (xy 462.65417 -307.862814)
			(xy 462.620062 -307.818642) (xy 462.592748 -307.769974) (xy 462.572812 -307.717848) (xy 462.560677 -307.663375)
			(xy 462.556604 -307.607716) (xy 458.257713 -307.607716) (xy 458.251059 -307.652932) (xy 458.234991 -307.706339)
			(xy 458.211319 -307.756836) (xy 458.180546 -307.803349) (xy 458.143329 -307.844886) (xy 458.100461 -307.880561)
			(xy 458.052855 -307.909615) (xy 458.001526 -307.931427) (xy 457.947569 -307.945533) (xy 457.892132 -307.951633)
			(xy 457.836398 -307.949596) (xy 457.781555 -307.939466) (xy 457.728771 -307.921459) (xy 457.679171 -307.895958)
			(xy 457.633813 -307.863507) (xy 457.593664 -307.824798) (xy 457.559578 -307.780655) (xy 457.532282 -307.73202)
			(xy 457.512359 -307.679929) (xy 457.500233 -307.625492) (xy 457.496162 -307.56987) (xy 450.664785 -307.56987)
			(xy 450.706523 -307.707216) (xy 450.746958 -307.868364) (xy 450.779425 -308.031305) (xy 450.803844 -308.195644)
			(xy 450.820156 -308.360985) (xy 450.82826 -308.525672) (xy 458.554072 -308.525672) (xy 458.558143 -308.47005)
			(xy 458.570269 -308.415613) (xy 458.590192 -308.363522) (xy 458.617488 -308.314887) (xy 458.651574 -308.270744)
			(xy 458.691723 -308.232035) (xy 458.737081 -308.199584) (xy 458.786681 -308.174083) (xy 458.839465 -308.156076)
			(xy 458.894308 -308.145946) (xy 458.950042 -308.143909) (xy 459.005479 -308.150009) (xy 459.059436 -308.164115)
			(xy 459.110765 -308.185927) (xy 459.158371 -308.214981) (xy 459.201239 -308.250656) (xy 459.238456 -308.292193)
			(xy 459.269229 -308.338706) (xy 459.292901 -308.389203) (xy 459.308969 -308.44261) (xy 459.317089 -308.497786)
			(xy 459.317598 -308.525672) (xy 459.317089 -308.553558) (xy 459.308969 -308.608734) (xy 459.292901 -308.662141)
			(xy 459.278765 -308.692296) (xy 462.556604 -308.692296) (xy 462.560677 -308.636637) (xy 462.572812 -308.582164)
			(xy 462.592748 -308.530038) (xy 462.620062 -308.48137) (xy 462.65417 -308.437198) (xy 462.694347 -308.398463)
			(xy 462.739735 -308.365991) (xy 462.789367 -308.340473) (xy 462.842187 -308.322454) (xy 462.897066 -308.312317)
			(xy 462.952837 -308.310279) (xy 463.008311 -308.316382) (xy 463.062304 -308.330498) (xy 463.113667 -308.352325)
			(xy 463.161305 -308.381398) (xy 463.204201 -308.417097) (xy 463.241443 -308.458661) (xy 463.272237 -308.505205)
			(xy 463.295925 -308.555736) (xy 463.312003 -308.609178) (xy 463.320129 -308.664392) (xy 463.320638 -308.692296)
			(xy 463.320129 -308.7202) (xy 463.312003 -308.775414) (xy 463.295925 -308.828856) (xy 463.272237 -308.879387)
			(xy 463.241443 -308.925931) (xy 463.204201 -308.967495) (xy 463.161305 -309.003194) (xy 463.113667 -309.032267)
			(xy 463.062304 -309.054094) (xy 463.008311 -309.06821) (xy 462.952837 -309.074313) (xy 462.897066 -309.072275)
			(xy 462.842187 -309.062138) (xy 462.789367 -309.044119) (xy 462.739735 -309.018601) (xy 462.694347 -308.986129)
			(xy 462.65417 -308.947394) (xy 462.620062 -308.903222) (xy 462.592748 -308.854554) (xy 462.572812 -308.802428)
			(xy 462.560677 -308.747955) (xy 462.556604 -308.692296) (xy 459.278765 -308.692296) (xy 459.269229 -308.712638)
			(xy 459.238456 -308.759151) (xy 459.201239 -308.800688) (xy 459.158371 -308.836363) (xy 459.110765 -308.865417)
			(xy 459.059436 -308.887229) (xy 459.005479 -308.901335) (xy 458.950042 -308.907435) (xy 458.894308 -308.905398)
			(xy 458.839465 -308.895268) (xy 458.786681 -308.877261) (xy 458.737081 -308.85176) (xy 458.691723 -308.819309)
			(xy 458.651574 -308.7806) (xy 458.617488 -308.736457) (xy 458.590192 -308.687822) (xy 458.570269 -308.635731)
			(xy 458.558143 -308.581294) (xy 458.554072 -308.525672) (xy 450.82826 -308.525672) (xy 450.828322 -308.526928)
			(xy 450.828322 -308.693072) (xy 450.820156 -308.859015) (xy 450.803844 -309.024356) (xy 450.78642 -309.141622)
			(xy 460.562196 -309.141622) (xy 460.566267 -309.086) (xy 460.578393 -309.031563) (xy 460.598316 -308.979472)
			(xy 460.625612 -308.930837) (xy 460.659698 -308.886694) (xy 460.699847 -308.847985) (xy 460.745205 -308.815534)
			(xy 460.794805 -308.790033) (xy 460.847589 -308.772026) (xy 460.902432 -308.761896) (xy 460.958166 -308.759859)
			(xy 461.013603 -308.765959) (xy 461.06756 -308.780065) (xy 461.118889 -308.801877) (xy 461.166495 -308.830931)
			(xy 461.209363 -308.866606) (xy 461.24658 -308.908143) (xy 461.277353 -308.954656) (xy 461.301025 -309.005153)
			(xy 461.317093 -309.05856) (xy 461.325213 -309.113736) (xy 461.325722 -309.141622) (xy 461.325213 -309.169508)
			(xy 461.317093 -309.224684) (xy 461.301025 -309.278091) (xy 461.277353 -309.328588) (xy 461.24658 -309.375101)
			(xy 461.209363 -309.416638) (xy 461.166495 -309.452313) (xy 461.118889 -309.481367) (xy 461.06756 -309.503179)
			(xy 461.013603 -309.517285) (xy 460.958166 -309.523385) (xy 460.902432 -309.521348) (xy 460.847589 -309.511218)
			(xy 460.794805 -309.493211) (xy 460.745205 -309.46771) (xy 460.699847 -309.435259) (xy 460.659698 -309.39655)
			(xy 460.625612 -309.352407) (xy 460.598316 -309.303772) (xy 460.578393 -309.251681) (xy 460.566267 -309.197244)
			(xy 460.562196 -309.141622) (xy 450.78642 -309.141622) (xy 450.779425 -309.188695) (xy 450.746958 -309.351636)
			(xy 450.706523 -309.512784) (xy 450.658215 -309.67175) (xy 450.602153 -309.828149) (xy 450.538472 -309.981604)
			(xy 450.514642 -310.031892) (xy 456.942188 -310.031892) (xy 456.946259 -309.97627) (xy 456.958385 -309.921833)
			(xy 456.978308 -309.869742) (xy 457.005604 -309.821107) (xy 457.03969 -309.776964) (xy 457.079839 -309.738255)
			(xy 457.125197 -309.705804) (xy 457.174797 -309.680303) (xy 457.227581 -309.662296) (xy 457.282424 -309.652166)
			(xy 457.338158 -309.650129) (xy 457.393595 -309.656229) (xy 457.447552 -309.670335) (xy 457.498881 -309.692147)
			(xy 457.546487 -309.721201) (xy 457.589355 -309.756876) (xy 457.626572 -309.798413) (xy 457.657345 -309.844926)
			(xy 457.668429 -309.86857) (xy 458.657704 -309.86857) (xy 458.661775 -309.812948) (xy 458.673901 -309.758511)
			(xy 458.693824 -309.70642) (xy 458.72112 -309.657785) (xy 458.755206 -309.613642) (xy 458.795355 -309.574933)
			(xy 458.840713 -309.542482) (xy 458.890313 -309.516981) (xy 458.943097 -309.498974) (xy 458.99794 -309.488844)
			(xy 459.053674 -309.486807) (xy 459.109111 -309.492907) (xy 459.163068 -309.507013) (xy 459.214397 -309.528825)
			(xy 459.262003 -309.557879) (xy 459.304871 -309.593554) (xy 459.342088 -309.635091) (xy 459.372861 -309.681604)
			(xy 459.396533 -309.732101) (xy 459.412601 -309.785508) (xy 459.420721 -309.840684) (xy 459.42123 -309.86857)
			(xy 459.420721 -309.896456) (xy 459.412601 -309.951632) (xy 459.396533 -310.005039) (xy 459.372861 -310.055536)
			(xy 459.342088 -310.102049) (xy 459.304871 -310.143586) (xy 459.262003 -310.179261) (xy 459.214397 -310.208315)
			(xy 459.163068 -310.230127) (xy 459.109111 -310.244233) (xy 459.053674 -310.250333) (xy 458.99794 -310.248296)
			(xy 458.943097 -310.238166) (xy 458.890313 -310.220159) (xy 458.840713 -310.194658) (xy 458.795355 -310.162207)
			(xy 458.755206 -310.123498) (xy 458.72112 -310.079355) (xy 458.693824 -310.03072) (xy 458.673901 -309.978629)
			(xy 458.661775 -309.924192) (xy 458.657704 -309.86857) (xy 457.668429 -309.86857) (xy 457.681017 -309.895423)
			(xy 457.697085 -309.94883) (xy 457.705205 -310.004006) (xy 457.705714 -310.031892) (xy 457.705205 -310.059778)
			(xy 457.697085 -310.114954) (xy 457.681017 -310.168361) (xy 457.657345 -310.218858) (xy 457.626572 -310.265371)
			(xy 457.589355 -310.306908) (xy 457.546487 -310.342583) (xy 457.498881 -310.371637) (xy 457.447552 -310.393449)
			(xy 457.393595 -310.407555) (xy 457.338158 -310.413655) (xy 457.282424 -310.411618) (xy 457.227581 -310.401488)
			(xy 457.174797 -310.383481) (xy 457.125197 -310.35798) (xy 457.079839 -310.325529) (xy 457.03969 -310.28682)
			(xy 457.005604 -310.242677) (xy 456.978308 -310.194042) (xy 456.958385 -310.141951) (xy 456.946259 -310.087514)
			(xy 456.942188 -310.031892) (xy 450.514642 -310.031892) (xy 450.467326 -310.131744) (xy 450.388886 -310.278205)
			(xy 450.303342 -310.420634) (xy 450.210902 -310.558687) (xy 450.111788 -310.692029) (xy 450.00624 -310.820339)
			(xy 449.894513 -310.943306) (xy 449.776878 -311.060633) (xy 449.653618 -311.172036) (xy 449.525031 -311.277247)
			(xy 449.441183 -311.33923) (xy 458.119986 -311.33923) (xy 458.124057 -311.283608) (xy 458.136183 -311.229171)
			(xy 458.156106 -311.17708) (xy 458.183402 -311.128445) (xy 458.217488 -311.084302) (xy 458.257637 -311.045593)
			(xy 458.302995 -311.013142) (xy 458.352595 -310.987641) (xy 458.405379 -310.969634) (xy 458.460222 -310.959504)
			(xy 458.515956 -310.957467) (xy 458.571393 -310.963567) (xy 458.62535 -310.977673) (xy 458.676679 -310.999485)
			(xy 458.724285 -311.028539) (xy 458.767153 -311.064214) (xy 458.80437 -311.105751) (xy 458.835143 -311.152264)
			(xy 458.858815 -311.202761) (xy 458.874883 -311.256168) (xy 458.883003 -311.311344) (xy 458.883512 -311.33923)
			(xy 458.883003 -311.367116) (xy 458.874883 -311.422292) (xy 458.858815 -311.475699) (xy 458.835143 -311.526196)
			(xy 458.80437 -311.572709) (xy 458.767153 -311.614246) (xy 458.724285 -311.649921) (xy 458.676679 -311.678975)
			(xy 458.62535 -311.700787) (xy 458.571393 -311.714893) (xy 458.515956 -311.720993) (xy 458.460222 -311.718956)
			(xy 458.405379 -311.708826) (xy 458.352595 -311.690819) (xy 458.302995 -311.665318) (xy 458.257637 -311.632867)
			(xy 458.217488 -311.594158) (xy 458.183402 -311.550015) (xy 458.156106 -311.50138) (xy 458.136183 -311.449289)
			(xy 458.124057 -311.394852) (xy 458.119986 -311.33923) (xy 449.441183 -311.33923) (xy 449.391429 -311.37601)
			(xy 449.253134 -311.468088) (xy 449.110481 -311.553257) (xy 448.963814 -311.631312) (xy 448.888866 -311.667144)
			(xy 448.882262 -311.670192) (xy 448.871594 -311.67959) (xy 448.854322 -311.706768) (xy 448.850613 -311.713016)
			(xy 448.84648 -311.72694) (xy 448.846194 -311.7342) (xy 448.846194 -320.940176) (xy 455.509122 -320.940176)
			(xy 455.509569 -320.912805) (xy 455.51739 -320.858625) (xy 455.532884 -320.806121) (xy 455.55573 -320.756375)
			(xy 455.585459 -320.710409) (xy 455.603102 -320.689478) (xy 455.609198 -320.682366) (xy 455.615548 -320.665348)
			(xy 455.615548 -320.580004) (xy 455.609198 -320.562986) (xy 455.603102 -320.555874) (xy 455.585484 -320.534925)
			(xy 455.555769 -320.488957) (xy 455.532929 -320.439213) (xy 455.517433 -320.386717) (xy 455.509599 -320.332544)
			(xy 455.509122 -320.305176) (xy 455.509533 -320.277921) (xy 455.517294 -320.223967) (xy 455.532654 -320.171666)
			(xy 455.555302 -320.122084) (xy 455.584775 -320.076229) (xy 455.620474 -320.035036) (xy 455.661673 -319.999343)
			(xy 455.707531 -319.969876) (xy 455.757117 -319.947235) (xy 455.80942 -319.931882) (xy 455.863375 -319.924129)
			(xy 455.89063 -319.923668) (xy 455.918002 -319.9241) (xy 455.972183 -319.931923) (xy 456.024687 -319.94742)
			(xy 456.074433 -319.970269) (xy 456.120398 -320.000002) (xy 456.141328 -320.017648) (xy 456.14844 -320.023744)
			(xy 456.165458 -320.030094) (xy 456.250802 -320.030094) (xy 456.26782 -320.023744) (xy 456.274932 -320.017648)
			(xy 456.295865 -320.000007) (xy 456.341833 -319.970283) (xy 456.391579 -319.947437) (xy 456.444081 -319.931941)
			(xy 456.498259 -319.924112) (xy 456.553001 -319.924112) (xy 456.607179 -319.931941) (xy 456.659681 -319.947437)
			(xy 456.709427 -319.970283) (xy 456.755395 -320.000007) (xy 456.776328 -320.017648) (xy 456.78344 -320.023744)
			(xy 456.800458 -320.030094) (xy 456.885802 -320.030094) (xy 456.90282 -320.023744) (xy 456.909932 -320.017648)
			(xy 456.930885 -320.000035) (xy 456.976851 -319.970317) (xy 457.026593 -319.947476) (xy 457.07909 -319.931979)
			(xy 457.133262 -319.924145) (xy 457.16063 -319.923668) (xy 457.187881 -319.92415) (xy 457.241828 -319.93191)
			(xy 457.294121 -319.947268) (xy 457.343697 -319.96991) (xy 457.389546 -319.999378) (xy 457.430735 -320.035069)
			(xy 457.466426 -320.076259) (xy 457.495892 -320.122109) (xy 457.518535 -320.171685) (xy 457.533891 -320.223978)
			(xy 457.541651 -320.277925) (xy 457.542138 -320.305176) (xy 457.541673 -320.332546) (xy 457.533857 -320.386726)
			(xy 457.518369 -320.43923) (xy 457.495526 -320.488977) (xy 457.4658 -320.534943) (xy 457.448158 -320.555874)
			(xy 457.442062 -320.562986) (xy 457.435712 -320.580004) (xy 457.435712 -320.665348) (xy 457.442062 -320.682366)
			(xy 457.448158 -320.689478) (xy 457.465794 -320.710413) (xy 457.495507 -320.756384) (xy 457.518345 -320.806131)
			(xy 457.533836 -320.858631) (xy 457.541664 -320.912807) (xy 457.542138 -320.940176) (xy 457.5416 -320.967425)
			(xy 457.533847 -321.021369) (xy 457.518496 -321.073661) (xy 457.49586 -321.123236) (xy 457.466399 -321.169085)
			(xy 457.430713 -321.210275) (xy 457.389529 -321.245967) (xy 457.343684 -321.275434) (xy 457.294112 -321.298078)
			(xy 457.241822 -321.313436) (xy 457.187879 -321.321196) (xy 457.16063 -321.321684) (xy 457.13326 -321.321204)
			(xy 457.079082 -321.31339) (xy 457.026578 -321.297905) (xy 456.976831 -321.275066) (xy 456.930864 -321.245344)
			(xy 456.909932 -321.227704) (xy 456.90282 -321.221608) (xy 456.885802 -321.215258) (xy 456.800458 -321.215258)
			(xy 456.78344 -321.221608) (xy 456.776328 -321.227704) (xy 456.755395 -321.245345) (xy 456.709427 -321.275069)
			(xy 456.659681 -321.297915) (xy 456.607179 -321.313411) (xy 456.553001 -321.32124) (xy 456.498259 -321.32124)
			(xy 456.444081 -321.313411) (xy 456.391579 -321.297915) (xy 456.341833 -321.275069) (xy 456.295865 -321.245345)
			(xy 456.274932 -321.227704) (xy 456.26782 -321.221608) (xy 456.250802 -321.215258) (xy 456.165458 -321.215258)
			(xy 456.14844 -321.221608) (xy 456.141328 -321.227704) (xy 456.120397 -321.245344) (xy 456.074424 -321.275056)
			(xy 456.024676 -321.297891) (xy 455.972175 -321.313382) (xy 455.917999 -321.32121) (xy 455.89063 -321.321684)
			(xy 455.863377 -321.321217) (xy 455.809425 -321.313463) (xy 455.757126 -321.29811) (xy 455.707544 -321.275469)
			(xy 455.661689 -321.246002) (xy 455.620496 -321.210308) (xy 455.584802 -321.169115) (xy 455.555334 -321.123261)
			(xy 455.532692 -321.07368) (xy 455.517338 -321.021381) (xy 455.509584 -320.967429) (xy 455.509122 -320.940176)
			(xy 448.846194 -320.940176) (xy 448.846194 -321.245992) (xy 448.846667 -321.255863) (xy 448.854129 -321.274143)
			(xy 448.860672 -321.281552) (xy 448.860926 -321.281806) (xy 449.13042 -321.5513) (xy 449.130928 -321.551808)
			(xy 449.138306 -321.558399) (xy 449.156605 -321.565865) (xy 449.166488 -321.566286)
		)
		(stroke
			(width 0)
			(type solid)
		)
		(fill yes)
		(layer "In13.Cu")
		(net "GND")
	)
	(gr_poly
		(pts
			(xy 110.105952 -241.983514) (xy 110.116018 -241.983082) (xy 110.13461 -241.975356) (xy 110.14202 -241.968528)
			(xy 110.260638 -241.84991) (xy 110.267493 -241.842515) (xy 110.275241 -241.823916) (xy 110.275624 -241.813842)
			(xy 110.275624 -223.823022) (xy 110.282482 -223.816164) (xy 110.282482 -213.486492) (xy 110.282061 -213.476473)
			(xy 110.274389 -213.457962) (xy 110.260216 -213.443796) (xy 110.241701 -213.436134) (xy 110.231682 -213.435692)
			(xy 98.330512 -213.435692) (xy 98.320551 -213.436182) (xy 98.302132 -213.443774) (xy 98.294698 -213.450424)
			(xy 98.010218 -213.734904) (xy 98.00337 -213.742302) (xy 97.995635 -213.7609) (xy 97.995232 -213.770972)
			(xy 97.995232 -219.08643) (xy 97.995838 -219.097759) (xy 98.005602 -219.118203) (xy 98.014028 -219.1258)
			(xy 98.083878 -219.182696) (xy 98.105722 -219.188284) (xy 98.117152 -219.185744) (xy 98.13606 -219.182147)
			(xy 98.17436 -219.178328) (xy 98.193606 -219.178124) (xy 98.220855 -219.178611) (xy 98.274797 -219.186367)
			(xy 98.327087 -219.201721) (xy 98.376659 -219.224361) (xy 98.422505 -219.253825) (xy 98.463691 -219.289513)
			(xy 98.499379 -219.3307) (xy 98.528842 -219.376546) (xy 98.551481 -219.426119) (xy 98.566834 -219.478409)
			(xy 98.57459 -219.532351) (xy 98.57459 -219.559886) (xy 100.279706 -219.559886) (xy 100.283777 -219.504264)
			(xy 100.295903 -219.449827) (xy 100.315826 -219.397736) (xy 100.343122 -219.349101) (xy 100.377208 -219.304958)
			(xy 100.417357 -219.266249) (xy 100.462715 -219.233798) (xy 100.512315 -219.208297) (xy 100.565099 -219.19029)
			(xy 100.619942 -219.18016) (xy 100.675676 -219.178123) (xy 100.731113 -219.184223) (xy 100.78507 -219.198329)
			(xy 100.836399 -219.220141) (xy 100.884005 -219.249195) (xy 100.926873 -219.28487) (xy 100.96409 -219.326407)
			(xy 100.994863 -219.37292) (xy 101.018535 -219.423417) (xy 101.034603 -219.476824) (xy 101.042723 -219.532)
			(xy 101.043223 -219.559378) (xy 102.352854 -219.559378) (xy 102.356925 -219.503756) (xy 102.369051 -219.449319)
			(xy 102.388974 -219.397228) (xy 102.41627 -219.348593) (xy 102.450356 -219.30445) (xy 102.490505 -219.265741)
			(xy 102.535863 -219.23329) (xy 102.585463 -219.207789) (xy 102.638247 -219.189782) (xy 102.69309 -219.179652)
			(xy 102.748824 -219.177615) (xy 102.804261 -219.183715) (xy 102.858218 -219.197821) (xy 102.909547 -219.219633)
			(xy 102.957153 -219.248687) (xy 103.000021 -219.284362) (xy 103.037238 -219.325899) (xy 103.068011 -219.372412)
			(xy 103.091683 -219.422909) (xy 103.107751 -219.476316) (xy 103.115871 -219.531492) (xy 103.11638 -219.559378)
			(xy 103.115871 -219.587264) (xy 103.107751 -219.64244) (xy 103.091683 -219.695847) (xy 103.068011 -219.746344)
			(xy 103.037238 -219.792857) (xy 103.000021 -219.834394) (xy 102.957153 -219.870069) (xy 102.909547 -219.899123)
			(xy 102.858218 -219.920935) (xy 102.804261 -219.935041) (xy 102.748824 -219.941141) (xy 102.69309 -219.939104)
			(xy 102.638247 -219.928974) (xy 102.585463 -219.910967) (xy 102.535863 -219.885466) (xy 102.490505 -219.853015)
			(xy 102.450356 -219.814306) (xy 102.41627 -219.770163) (xy 102.388974 -219.721528) (xy 102.369051 -219.669437)
			(xy 102.356925 -219.615) (xy 102.352854 -219.559378) (xy 101.043223 -219.559378) (xy 101.043232 -219.559886)
			(xy 101.042723 -219.587772) (xy 101.034603 -219.642948) (xy 101.018535 -219.696355) (xy 100.994863 -219.746852)
			(xy 100.96409 -219.793365) (xy 100.926873 -219.834902) (xy 100.884005 -219.870577) (xy 100.836399 -219.899631)
			(xy 100.78507 -219.921443) (xy 100.731113 -219.935549) (xy 100.675676 -219.941649) (xy 100.619942 -219.939612)
			(xy 100.565099 -219.929482) (xy 100.512315 -219.911475) (xy 100.462715 -219.885974) (xy 100.417357 -219.853523)
			(xy 100.377208 -219.814814) (xy 100.343122 -219.770671) (xy 100.315826 -219.722036) (xy 100.295903 -219.669945)
			(xy 100.283777 -219.615508) (xy 100.279706 -219.559886) (xy 98.57459 -219.559886) (xy 98.57459 -219.586849)
			(xy 98.566834 -219.640791) (xy 98.551481 -219.693081) (xy 98.528842 -219.742654) (xy 98.499379 -219.7885)
			(xy 98.463691 -219.829687) (xy 98.422505 -219.865375) (xy 98.376659 -219.894839) (xy 98.327087 -219.917479)
			(xy 98.274797 -219.932833) (xy 98.220855 -219.940589) (xy 98.193606 -219.94114) (xy 98.174361 -219.940923)
			(xy 98.136062 -219.937103) (xy 98.117152 -219.93352) (xy 98.105722 -219.93098) (xy 98.083878 -219.936568)
			(xy 98.014028 -219.993464) (xy 98.005639 -220.001084) (xy 97.9959 -220.021518) (xy 97.995232 -220.032834)
			(xy 97.995232 -221.146116) (xy 100.565456 -221.146116) (xy 100.569527 -221.090494) (xy 100.581653 -221.036057)
			(xy 100.601576 -220.983966) (xy 100.628872 -220.935331) (xy 100.662958 -220.891188) (xy 100.703107 -220.852479)
			(xy 100.748465 -220.820028) (xy 100.798065 -220.794527) (xy 100.850849 -220.77652) (xy 100.905692 -220.76639)
			(xy 100.961426 -220.764353) (xy 101.016863 -220.770453) (xy 101.07082 -220.784559) (xy 101.122149 -220.806371)
			(xy 101.169755 -220.835425) (xy 101.212623 -220.8711) (xy 101.24984 -220.912637) (xy 101.255253 -220.920818)
			(xy 102.937562 -220.920818) (xy 102.941633 -220.865196) (xy 102.953759 -220.810759) (xy 102.973682 -220.758668)
			(xy 103.000978 -220.710033) (xy 103.035064 -220.66589) (xy 103.075213 -220.627181) (xy 103.120571 -220.59473)
			(xy 103.170171 -220.569229) (xy 103.222955 -220.551222) (xy 103.277798 -220.541092) (xy 103.333532 -220.539055)
			(xy 103.388969 -220.545155) (xy 103.442926 -220.559261) (xy 103.494255 -220.581073) (xy 103.541861 -220.610127)
			(xy 103.584729 -220.645802) (xy 103.621946 -220.687339) (xy 103.652719 -220.733852) (xy 103.676391 -220.784349)
			(xy 103.692459 -220.837756) (xy 103.700579 -220.892932) (xy 103.701088 -220.920818) (xy 103.700579 -220.948704)
			(xy 103.692459 -221.00388) (xy 103.676391 -221.057287) (xy 103.652719 -221.107784) (xy 103.621946 -221.154297)
			(xy 103.584729 -221.195834) (xy 103.541861 -221.231509) (xy 103.494255 -221.260563) (xy 103.442926 -221.282375)
			(xy 103.388969 -221.296481) (xy 103.333532 -221.302581) (xy 103.277798 -221.300544) (xy 103.222955 -221.290414)
			(xy 103.170171 -221.272407) (xy 103.120571 -221.246906) (xy 103.075213 -221.214455) (xy 103.035064 -221.175746)
			(xy 103.000978 -221.131603) (xy 102.973682 -221.082968) (xy 102.953759 -221.030877) (xy 102.941633 -220.97644)
			(xy 102.937562 -220.920818) (xy 101.255253 -220.920818) (xy 101.280613 -220.95915) (xy 101.304285 -221.009647)
			(xy 101.320353 -221.063054) (xy 101.328473 -221.11823) (xy 101.328982 -221.146116) (xy 101.328473 -221.174002)
			(xy 101.320353 -221.229178) (xy 101.304285 -221.282585) (xy 101.280613 -221.333082) (xy 101.24984 -221.379595)
			(xy 101.212623 -221.421132) (xy 101.169755 -221.456807) (xy 101.122149 -221.485861) (xy 101.07082 -221.507673)
			(xy 101.016863 -221.521779) (xy 100.961426 -221.527879) (xy 100.905692 -221.525842) (xy 100.850849 -221.515712)
			(xy 100.798065 -221.497705) (xy 100.748465 -221.472204) (xy 100.703107 -221.439753) (xy 100.662958 -221.401044)
			(xy 100.628872 -221.356901) (xy 100.601576 -221.308266) (xy 100.581653 -221.256175) (xy 100.569527 -221.201738)
			(xy 100.565456 -221.146116) (xy 97.995232 -221.146116) (xy 97.995232 -222.46463) (xy 99.334318 -222.46463)
			(xy 99.338389 -222.409008) (xy 99.350515 -222.354571) (xy 99.370438 -222.30248) (xy 99.397734 -222.253845)
			(xy 99.43182 -222.209702) (xy 99.471969 -222.170993) (xy 99.517327 -222.138542) (xy 99.566927 -222.113041)
			(xy 99.619711 -222.095034) (xy 99.674554 -222.084904) (xy 99.730288 -222.082867) (xy 99.785725 -222.088967)
			(xy 99.839682 -222.103073) (xy 99.891011 -222.124885) (xy 99.938617 -222.153939) (xy 99.981485 -222.189614)
			(xy 100.018702 -222.231151) (xy 100.049475 -222.277664) (xy 100.073147 -222.328161) (xy 100.089215 -222.381568)
			(xy 100.097335 -222.436744) (xy 100.097844 -222.46463) (xy 100.097335 -222.492516) (xy 100.089215 -222.547692)
			(xy 100.073147 -222.601099) (xy 100.049475 -222.651596) (xy 100.018702 -222.698109) (xy 99.981485 -222.739646)
			(xy 99.938617 -222.775321) (xy 99.891011 -222.804375) (xy 99.839682 -222.826187) (xy 99.785725 -222.840293)
			(xy 99.730288 -222.846393) (xy 99.674554 -222.844356) (xy 99.619711 -222.834226) (xy 99.566927 -222.816219)
			(xy 99.517327 -222.790718) (xy 99.471969 -222.758267) (xy 99.43182 -222.719558) (xy 99.397734 -222.675415)
			(xy 99.370438 -222.62678) (xy 99.350515 -222.574689) (xy 99.338389 -222.520252) (xy 99.334318 -222.46463)
			(xy 97.995232 -222.46463) (xy 97.995232 -223.135698) (xy 101.499414 -223.135698) (xy 101.503485 -223.080076)
			(xy 101.515611 -223.025639) (xy 101.535534 -222.973548) (xy 101.56283 -222.924913) (xy 101.596916 -222.88077)
			(xy 101.637065 -222.842061) (xy 101.682423 -222.80961) (xy 101.732023 -222.784109) (xy 101.784807 -222.766102)
			(xy 101.83965 -222.755972) (xy 101.895384 -222.753935) (xy 101.950821 -222.760035) (xy 102.004778 -222.774141)
			(xy 102.056107 -222.795953) (xy 102.103713 -222.825007) (xy 102.146581 -222.860682) (xy 102.183798 -222.902219)
			(xy 102.214571 -222.948732) (xy 102.238243 -222.999229) (xy 102.254311 -223.052636) (xy 102.262431 -223.107812)
			(xy 102.26294 -223.135698) (xy 102.262431 -223.163584) (xy 102.254311 -223.21876) (xy 102.238243 -223.272167)
			(xy 102.214571 -223.322664) (xy 102.183798 -223.369177) (xy 102.146581 -223.410714) (xy 102.103713 -223.446389)
			(xy 102.056107 -223.475443) (xy 102.004778 -223.497255) (xy 101.950821 -223.511361) (xy 101.895384 -223.517461)
			(xy 101.83965 -223.515424) (xy 101.784807 -223.505294) (xy 101.732023 -223.487287) (xy 101.682423 -223.461786)
			(xy 101.637065 -223.429335) (xy 101.596916 -223.390626) (xy 101.56283 -223.346483) (xy 101.535534 -223.297848)
			(xy 101.515611 -223.245757) (xy 101.503485 -223.19132) (xy 101.499414 -223.135698) (xy 97.995232 -223.135698)
			(xy 97.995232 -223.849946) (xy 102.606346 -223.849946) (xy 102.610417 -223.794324) (xy 102.622543 -223.739887)
			(xy 102.642466 -223.687796) (xy 102.669762 -223.639161) (xy 102.703848 -223.595018) (xy 102.743997 -223.556309)
			(xy 102.789355 -223.523858) (xy 102.838955 -223.498357) (xy 102.891739 -223.48035) (xy 102.946582 -223.47022)
			(xy 103.002316 -223.468183) (xy 103.057753 -223.474283) (xy 103.11171 -223.488389) (xy 103.163039 -223.510201)
			(xy 103.210645 -223.539255) (xy 103.253513 -223.57493) (xy 103.29073 -223.616467) (xy 103.321503 -223.66298)
			(xy 103.345175 -223.713477) (xy 103.361243 -223.766884) (xy 103.369363 -223.82206) (xy 103.369872 -223.849946)
			(xy 103.369363 -223.877832) (xy 103.361243 -223.933008) (xy 103.345175 -223.986415) (xy 103.321503 -224.036912)
			(xy 103.29073 -224.083425) (xy 103.253513 -224.124962) (xy 103.210645 -224.160637) (xy 103.163039 -224.189691)
			(xy 103.11171 -224.211503) (xy 103.057753 -224.225609) (xy 103.002316 -224.231709) (xy 102.946582 -224.229672)
			(xy 102.891739 -224.219542) (xy 102.838955 -224.201535) (xy 102.789355 -224.176034) (xy 102.743997 -224.143583)
			(xy 102.703848 -224.104874) (xy 102.669762 -224.060731) (xy 102.642466 -224.012096) (xy 102.622543 -223.960005)
			(xy 102.610417 -223.905568) (xy 102.606346 -223.849946) (xy 97.995232 -223.849946) (xy 97.995232 -224.531174)
			(xy 107.58373 -224.531174) (xy 107.587801 -224.475552) (xy 107.599927 -224.421115) (xy 107.61985 -224.369024)
			(xy 107.647146 -224.320389) (xy 107.681232 -224.276246) (xy 107.721381 -224.237537) (xy 107.766739 -224.205086)
			(xy 107.816339 -224.179585) (xy 107.869123 -224.161578) (xy 107.923966 -224.151448) (xy 107.9797 -224.149411)
			(xy 108.035137 -224.155511) (xy 108.089094 -224.169617) (xy 108.140423 -224.191429) (xy 108.188029 -224.220483)
			(xy 108.230897 -224.256158) (xy 108.268114 -224.297695) (xy 108.298887 -224.344208) (xy 108.322559 -224.394705)
			(xy 108.338627 -224.448112) (xy 108.346747 -224.503288) (xy 108.347256 -224.531174) (xy 108.346747 -224.55906)
			(xy 108.338627 -224.614236) (xy 108.322559 -224.667643) (xy 108.298887 -224.71814) (xy 108.268114 -224.764653)
			(xy 108.230897 -224.80619) (xy 108.188029 -224.841865) (xy 108.140423 -224.870919) (xy 108.089094 -224.892731)
			(xy 108.035137 -224.906837) (xy 107.9797 -224.912937) (xy 107.923966 -224.9109) (xy 107.869123 -224.90077)
			(xy 107.816339 -224.882763) (xy 107.766739 -224.857262) (xy 107.721381 -224.824811) (xy 107.681232 -224.786102)
			(xy 107.647146 -224.741959) (xy 107.61985 -224.693324) (xy 107.599927 -224.641233) (xy 107.587801 -224.586796)
			(xy 107.58373 -224.531174) (xy 97.995232 -224.531174) (xy 97.995232 -236.391704) (xy 99.087938 -236.391704)
			(xy 99.092009 -236.336082) (xy 99.104135 -236.281645) (xy 99.124058 -236.229554) (xy 99.151354 -236.180919)
			(xy 99.18544 -236.136776) (xy 99.225589 -236.098067) (xy 99.270947 -236.065616) (xy 99.320547 -236.040115)
			(xy 99.373331 -236.022108) (xy 99.428174 -236.011978) (xy 99.483908 -236.009941) (xy 99.539345 -236.016041)
			(xy 99.593302 -236.030147) (xy 99.644631 -236.051959) (xy 99.692237 -236.081013) (xy 99.735105 -236.116688)
			(xy 99.772322 -236.158225) (xy 99.803095 -236.204738) (xy 99.826767 -236.255235) (xy 99.842835 -236.308642)
			(xy 99.850955 -236.363818) (xy 99.851464 -236.391704) (xy 99.850955 -236.41959) (xy 99.842835 -236.474766)
			(xy 99.826767 -236.528173) (xy 99.803095 -236.57867) (xy 99.772322 -236.625183) (xy 99.735105 -236.66672)
			(xy 99.692237 -236.702395) (xy 99.644631 -236.731449) (xy 99.593302 -236.753261) (xy 99.539345 -236.767367)
			(xy 99.483908 -236.773467) (xy 99.428174 -236.77143) (xy 99.373331 -236.7613) (xy 99.320547 -236.743293)
			(xy 99.270947 -236.717792) (xy 99.225589 -236.685341) (xy 99.18544 -236.646632) (xy 99.151354 -236.602489)
			(xy 99.124058 -236.553854) (xy 99.104135 -236.501763) (xy 99.092009 -236.447326) (xy 99.087938 -236.391704)
			(xy 97.995232 -236.391704) (xy 97.995232 -236.775244) (xy 101.503226 -236.775244) (xy 101.503712 -236.747874)
			(xy 101.511524 -236.693696) (xy 101.527008 -236.641193) (xy 101.549845 -236.591446) (xy 101.579566 -236.545478)
			(xy 101.597206 -236.524546) (xy 101.603302 -236.517434) (xy 101.609652 -236.500416) (xy 101.609652 -236.415072)
			(xy 101.603302 -236.398054) (xy 101.597206 -236.390942) (xy 101.579574 -236.370004) (xy 101.549861 -236.324033)
			(xy 101.527024 -236.274287) (xy 101.511531 -236.221788) (xy 101.503701 -236.167613) (xy 101.503226 -236.140244)
			(xy 101.503712 -236.112993) (xy 101.511468 -236.059045) (xy 101.526823 -236.00675) (xy 101.549465 -235.957173)
			(xy 101.578931 -235.911323) (xy 101.614622 -235.870132) (xy 101.655813 -235.834441) (xy 101.701663 -235.804975)
			(xy 101.75124 -235.782333) (xy 101.803535 -235.766978) (xy 101.857483 -235.759222) (xy 101.911985 -235.759222)
			(xy 101.965933 -235.766978) (xy 102.018228 -235.782333) (xy 102.067805 -235.804975) (xy 102.113655 -235.834441)
			(xy 102.154846 -235.870132) (xy 102.190537 -235.911323) (xy 102.220003 -235.957173) (xy 102.242645 -236.00675)
			(xy 102.258 -236.059045) (xy 102.265756 -236.112993) (xy 102.266242 -236.140244) (xy 102.265757 -236.167614)
			(xy 102.257946 -236.221793) (xy 102.242462 -236.274296) (xy 102.219624 -236.324043) (xy 102.189902 -236.37001)
			(xy 102.172262 -236.390942) (xy 102.166166 -236.398054) (xy 102.159816 -236.415072) (xy 102.159816 -236.500416)
			(xy 102.166166 -236.517434) (xy 102.172262 -236.524546) (xy 102.189883 -236.545492) (xy 102.219599 -236.591461)
			(xy 102.242439 -236.641205) (xy 102.257934 -236.693702) (xy 102.265766 -236.747876) (xy 102.266242 -236.775244)
			(xy 103.535226 -236.775244) (xy 103.535712 -236.747874) (xy 103.543524 -236.693696) (xy 103.559008 -236.641193)
			(xy 103.581845 -236.591446) (xy 103.611566 -236.545478) (xy 103.629206 -236.524546) (xy 103.635302 -236.517434)
			(xy 103.641652 -236.500416) (xy 103.641652 -236.415072) (xy 103.635302 -236.398054) (xy 103.629206 -236.390942)
			(xy 103.611574 -236.370004) (xy 103.581861 -236.324033) (xy 103.559024 -236.274287) (xy 103.543531 -236.221788)
			(xy 103.535701 -236.167613) (xy 103.535226 -236.140244) (xy 103.535712 -236.112993) (xy 103.543468 -236.059045)
			(xy 103.558823 -236.00675) (xy 103.581465 -235.957173) (xy 103.610931 -235.911323) (xy 103.646622 -235.870132)
			(xy 103.687813 -235.834441) (xy 103.733663 -235.804975) (xy 103.78324 -235.782333) (xy 103.835535 -235.766978)
			(xy 103.889483 -235.759222) (xy 103.943985 -235.759222) (xy 103.997933 -235.766978) (xy 104.050228 -235.782333)
			(xy 104.099805 -235.804975) (xy 104.145655 -235.834441) (xy 104.186846 -235.870132) (xy 104.222537 -235.911323)
			(xy 104.252003 -235.957173) (xy 104.274645 -236.00675) (xy 104.29 -236.059045) (xy 104.297756 -236.112993)
			(xy 104.298242 -236.140244) (xy 104.297757 -236.167614) (xy 104.289946 -236.221793) (xy 104.274462 -236.274296)
			(xy 104.251624 -236.324043) (xy 104.221902 -236.37001) (xy 104.204262 -236.390942) (xy 104.198166 -236.398054)
			(xy 104.191816 -236.415072) (xy 104.191816 -236.500416) (xy 104.198166 -236.517434) (xy 104.204262 -236.524546)
			(xy 104.221883 -236.545492) (xy 104.251599 -236.591461) (xy 104.274439 -236.641205) (xy 104.289934 -236.693702)
			(xy 104.297766 -236.747876) (xy 104.298242 -236.775244) (xy 105.567226 -236.775244) (xy 105.567712 -236.747874)
			(xy 105.575524 -236.693696) (xy 105.591008 -236.641193) (xy 105.613845 -236.591446) (xy 105.643566 -236.545478)
			(xy 105.661206 -236.524546) (xy 105.667302 -236.517434) (xy 105.673652 -236.500416) (xy 105.673652 -236.415072)
			(xy 105.667302 -236.398054) (xy 105.661206 -236.390942) (xy 105.643574 -236.370004) (xy 105.613861 -236.324033)
			(xy 105.591024 -236.274287) (xy 105.575531 -236.221788) (xy 105.567701 -236.167613) (xy 105.567226 -236.140244)
			(xy 105.567712 -236.112993) (xy 105.575468 -236.059045) (xy 105.590823 -236.00675) (xy 105.613465 -235.957173)
			(xy 105.642931 -235.911323) (xy 105.678622 -235.870132) (xy 105.719813 -235.834441) (xy 105.765663 -235.804975)
			(xy 105.81524 -235.782333) (xy 105.867535 -235.766978) (xy 105.921483 -235.759222) (xy 105.975985 -235.759222)
			(xy 106.029933 -235.766978) (xy 106.082228 -235.782333) (xy 106.131805 -235.804975) (xy 106.177655 -235.834441)
			(xy 106.218846 -235.870132) (xy 106.254537 -235.911323) (xy 106.284003 -235.957173) (xy 106.306645 -236.00675)
			(xy 106.322 -236.059045) (xy 106.329756 -236.112993) (xy 106.330242 -236.140244) (xy 106.329757 -236.167614)
			(xy 106.321946 -236.221793) (xy 106.306462 -236.274296) (xy 106.283624 -236.324043) (xy 106.253902 -236.37001)
			(xy 106.236262 -236.390942) (xy 106.230166 -236.398054) (xy 106.223816 -236.415072) (xy 106.223816 -236.500416)
			(xy 106.230166 -236.517434) (xy 106.236262 -236.524546) (xy 106.253883 -236.545492) (xy 106.283599 -236.591461)
			(xy 106.306439 -236.641205) (xy 106.321934 -236.693702) (xy 106.329766 -236.747876) (xy 106.330242 -236.775244)
			(xy 107.599226 -236.775244) (xy 107.599712 -236.747874) (xy 107.607524 -236.693696) (xy 107.623008 -236.641193)
			(xy 107.645845 -236.591446) (xy 107.675566 -236.545478) (xy 107.693206 -236.524546) (xy 107.699302 -236.517434)
			(xy 107.705652 -236.500416) (xy 107.705652 -236.415072) (xy 107.699302 -236.398054) (xy 107.693206 -236.390942)
			(xy 107.675574 -236.370004) (xy 107.645861 -236.324033) (xy 107.623024 -236.274287) (xy 107.607531 -236.221788)
			(xy 107.599701 -236.167613) (xy 107.599226 -236.140244) (xy 107.599712 -236.112993) (xy 107.607468 -236.059045)
			(xy 107.622823 -236.00675) (xy 107.645465 -235.957173) (xy 107.674931 -235.911323) (xy 107.710622 -235.870132)
			(xy 107.751813 -235.834441) (xy 107.797663 -235.804975) (xy 107.84724 -235.782333) (xy 107.899535 -235.766978)
			(xy 107.953483 -235.759222) (xy 108.007985 -235.759222) (xy 108.061933 -235.766978) (xy 108.114228 -235.782333)
			(xy 108.163805 -235.804975) (xy 108.209655 -235.834441) (xy 108.250846 -235.870132) (xy 108.286537 -235.911323)
			(xy 108.316003 -235.957173) (xy 108.338645 -236.00675) (xy 108.354 -236.059045) (xy 108.361756 -236.112993)
			(xy 108.362242 -236.140244) (xy 108.361757 -236.167614) (xy 108.353946 -236.221793) (xy 108.338462 -236.274296)
			(xy 108.315624 -236.324043) (xy 108.285902 -236.37001) (xy 108.268262 -236.390942) (xy 108.262166 -236.398054)
			(xy 108.255816 -236.415072) (xy 108.255816 -236.500416) (xy 108.262166 -236.517434) (xy 108.268262 -236.524546)
			(xy 108.285883 -236.545492) (xy 108.315599 -236.591461) (xy 108.338439 -236.641205) (xy 108.353934 -236.693702)
			(xy 108.361766 -236.747876) (xy 108.362242 -236.775244) (xy 108.361756 -236.802495) (xy 108.354 -236.856443)
			(xy 108.338645 -236.908738) (xy 108.316003 -236.958315) (xy 108.286537 -237.004165) (xy 108.250846 -237.045356)
			(xy 108.209655 -237.081047) (xy 108.163805 -237.110513) (xy 108.114228 -237.133155) (xy 108.061933 -237.14851)
			(xy 108.007985 -237.156266) (xy 107.953483 -237.156266) (xy 107.899535 -237.14851) (xy 107.84724 -237.133155)
			(xy 107.797663 -237.110513) (xy 107.751813 -237.081047) (xy 107.710622 -237.045356) (xy 107.674931 -237.004165)
			(xy 107.645465 -236.958315) (xy 107.622823 -236.908738) (xy 107.607468 -236.856443) (xy 107.599712 -236.802495)
			(xy 107.599226 -236.775244) (xy 106.330242 -236.775244) (xy 106.329756 -236.802495) (xy 106.322 -236.856443)
			(xy 106.306645 -236.908738) (xy 106.284003 -236.958315) (xy 106.254537 -237.004165) (xy 106.218846 -237.045356)
			(xy 106.177655 -237.081047) (xy 106.131805 -237.110513) (xy 106.082228 -237.133155) (xy 106.029933 -237.14851)
			(xy 105.975985 -237.156266) (xy 105.921483 -237.156266) (xy 105.867535 -237.14851) (xy 105.81524 -237.133155)
			(xy 105.765663 -237.110513) (xy 105.719813 -237.081047) (xy 105.678622 -237.045356) (xy 105.642931 -237.004165)
			(xy 105.613465 -236.958315) (xy 105.590823 -236.908738) (xy 105.575468 -236.856443) (xy 105.567712 -236.802495)
			(xy 105.567226 -236.775244) (xy 104.298242 -236.775244) (xy 104.297756 -236.802495) (xy 104.29 -236.856443)
			(xy 104.274645 -236.908738) (xy 104.252003 -236.958315) (xy 104.222537 -237.004165) (xy 104.186846 -237.045356)
			(xy 104.145655 -237.081047) (xy 104.099805 -237.110513) (xy 104.050228 -237.133155) (xy 103.997933 -237.14851)
			(xy 103.943985 -237.156266) (xy 103.889483 -237.156266) (xy 103.835535 -237.14851) (xy 103.78324 -237.133155)
			(xy 103.733663 -237.110513) (xy 103.687813 -237.081047) (xy 103.646622 -237.045356) (xy 103.610931 -237.004165)
			(xy 103.581465 -236.958315) (xy 103.558823 -236.908738) (xy 103.543468 -236.856443) (xy 103.535712 -236.802495)
			(xy 103.535226 -236.775244) (xy 102.266242 -236.775244) (xy 102.265756 -236.802495) (xy 102.258 -236.856443)
			(xy 102.242645 -236.908738) (xy 102.220003 -236.958315) (xy 102.190537 -237.004165) (xy 102.154846 -237.045356)
			(xy 102.113655 -237.081047) (xy 102.067805 -237.110513) (xy 102.018228 -237.133155) (xy 101.965933 -237.14851)
			(xy 101.911985 -237.156266) (xy 101.857483 -237.156266) (xy 101.803535 -237.14851) (xy 101.75124 -237.133155)
			(xy 101.701663 -237.110513) (xy 101.655813 -237.081047) (xy 101.614622 -237.045356) (xy 101.578931 -237.004165)
			(xy 101.549465 -236.958315) (xy 101.526823 -236.908738) (xy 101.511468 -236.856443) (xy 101.503712 -236.802495)
			(xy 101.503226 -236.775244) (xy 97.995232 -236.775244) (xy 97.995232 -240.470436) (xy 97.995664 -240.481008)
			(xy 98.004205 -240.500348) (xy 98.011742 -240.507774) (xy 98.030804 -240.525924) (xy 98.064263 -240.566554)
			(xy 98.091825 -240.611396) (xy 98.112966 -240.659597) (xy 98.127287 -240.710246) (xy 98.134516 -240.762381)
			(xy 98.134932 -240.788698) (xy 98.13451 -240.815016) (xy 98.127308 -240.867158) (xy 98.112999 -240.917812)
			(xy 98.091857 -240.966015) (xy 98.064282 -241.010851) (xy 98.0308 -241.051465) (xy 98.011742 -241.069622)
			(xy 98.004353 -241.077149) (xy 97.995848 -241.096428) (xy 97.995232 -241.10696) (xy 97.995232 -241.199162)
			(xy 97.995723 -241.20916) (xy 98.003353 -241.227645) (xy 98.017442 -241.241837) (xy 98.026474 -241.246152)
			(xy 98.040952 -241.252248) (xy 98.070924 -241.246152) (xy 98.730308 -240.586514) (xy 98.753026 -240.564496)
			(xy 98.80322 -240.525985) (xy 98.858012 -240.494357) (xy 98.916465 -240.470154) (xy 98.977579 -240.453791)
			(xy 99.040305 -240.445548) (xy 99.071938 -240.445036) (xy 99.79914 -240.445036) (xy 99.830766 -240.445556)
			(xy 99.893477 -240.453817) (xy 99.954572 -240.470192) (xy 100.013008 -240.494401) (xy 100.067785 -240.52603)
			(xy 100.117964 -240.564538) (xy 100.162688 -240.609266) (xy 100.201192 -240.659449) (xy 100.232817 -240.714228)
			(xy 100.257021 -240.772666) (xy 100.273391 -240.833763) (xy 100.281647 -240.896474) (xy 100.281647 -240.959726)
			(xy 100.273391 -241.022437) (xy 100.257021 -241.083534) (xy 100.232817 -241.141972) (xy 100.201192 -241.196751)
			(xy 100.162688 -241.246934) (xy 100.117964 -241.291662) (xy 100.067785 -241.33017) (xy 100.013008 -241.361799)
			(xy 99.954572 -241.386008) (xy 99.893477 -241.402383) (xy 99.830766 -241.410644) (xy 99.79914 -241.411252)
			(xy 99.292918 -241.411252) (xy 99.282958 -241.411742) (xy 99.264543 -241.41934) (xy 99.257104 -241.425984)
			(xy 98.786188 -241.8969) (xy 98.779488 -241.904341) (xy 98.771882 -241.92284) (xy 98.771898 -241.942842)
			(xy 98.775266 -241.952272) (xy 98.781362 -241.966496) (xy 98.806508 -241.983514)
		)
		(stroke
			(width 0)
			(type solid)
		)
		(fill yes)
		(layer "In13.Cu")
		(net "GND")
	)
	(gr_poly
		(pts
			(xy 303.505362 -230.388668) (xy 303.515352 -230.388137) (xy 303.533791 -230.380429) (xy 303.541176 -230.373682)
			(xy 303.728374 -230.186484) (xy 303.735221 -230.179086) (xy 303.742953 -230.160488) (xy 303.74336 -230.150416)
			(xy 303.74336 -229.098094) (xy 303.742935 -229.088025) (xy 303.735214 -229.069426) (xy 303.728374 -229.062026)
			(xy 302.991774 -228.325426) (xy 302.984375 -228.318581) (xy 302.965777 -228.310852) (xy 302.955706 -228.31044)
			(xy 302.122078 -228.31044) (xy 302.11201 -228.310868) (xy 302.093416 -228.318593) (xy 302.08601 -228.325426)
			(xy 301.568358 -228.843078) (xy 301.560958 -228.84992) (xy 301.54236 -228.857643) (xy 301.53229 -228.858064)
			(xy 279.952196 -228.858064) (xy 279.942127 -228.857639) (xy 279.923527 -228.84992) (xy 279.916128 -228.843078)
			(xy 279.559512 -228.486462) (xy 279.55875 -228.485954) (xy 279.549352 -228.47681) (xy 271.515332 -220.44279)
			(xy 271.507934 -220.435945) (xy 271.489335 -220.428221) (xy 271.479264 -220.427804) (xy 262.188452 -220.427804)
			(xy 262.178386 -220.427372) (xy 262.159794 -220.419646) (xy 262.152384 -220.412818) (xy 257.720846 -215.98128)
			(xy 257.713449 -215.974433) (xy 257.694849 -215.966706) (xy 257.684778 -215.966294) (xy 256.030222 -215.966294)
			(xy 256.020158 -215.966731) (xy 256.001573 -215.974465) (xy 255.994154 -215.98128) (xy 255.64084 -216.334594)
			(xy 255.633439 -216.341432) (xy 255.61484 -216.349145) (xy 255.604772 -216.34958) (xy 252.05817 -216.34958)
			(xy 252.048557 -216.349985) (xy 252.030662 -216.357019) (xy 252.023372 -216.363296) (xy 251.96546 -216.417398)
			(xy 251.957332 -216.434416) (xy 251.956824 -216.444322) (xy 251.954536 -216.471576) (xy 251.943142 -216.525067)
			(xy 251.924228 -216.576384) (xy 251.898181 -216.624475) (xy 251.865535 -216.668355) (xy 251.82696 -216.707125)
			(xy 251.783244 -216.73999) (xy 251.735285 -216.766277) (xy 251.684063 -216.785449) (xy 251.630629 -216.797111)
			(xy 251.576078 -216.801025) (xy 251.521527 -216.797111) (xy 251.468093 -216.785449) (xy 251.416871 -216.766277)
			(xy 251.368912 -216.73999) (xy 251.325196 -216.707125) (xy 251.286621 -216.668355) (xy 251.253975 -216.624475)
			(xy 251.227928 -216.576384) (xy 251.209014 -216.525067) (xy 251.19762 -216.471576) (xy 251.195332 -216.444322)
			(xy 251.194824 -216.434416) (xy 251.186696 -216.417398) (xy 251.128784 -216.363296) (xy 251.121491 -216.357019)
			(xy 251.103601 -216.349976) (xy 251.093986 -216.34958) (xy 249.528584 -216.34958) (xy 249.518516 -216.349153)
			(xy 249.499917 -216.341433) (xy 249.492516 -216.334594) (xy 249.115834 -215.957912) (xy 249.108432 -215.951075)
			(xy 249.089834 -215.943363) (xy 249.079766 -215.942926) (xy 247.805956 -215.942926) (xy 247.796237 -215.943416)
			(xy 247.778224 -215.950736) (xy 247.770904 -215.95715) (xy 247.749457 -215.976905) (xy 247.701687 -216.010336)
			(xy 247.649389 -216.036114) (xy 247.593779 -216.05364) (xy 247.536151 -216.062506) (xy 247.506998 -216.063068)
			(xy 247.480806 -216.06262) (xy 247.42892 -216.055417) (xy 247.378509 -216.041175) (xy 247.354344 -216.031064)
			(xy 247.34139 -216.025476) (xy 247.313196 -216.029286) (xy 247.220994 -216.102946) (xy 247.211088 -216.129616)
			(xy 247.213882 -216.143332) (xy 247.21711 -216.161191) (xy 247.220545 -216.197321) (xy 247.22074 -216.215468)
			(xy 247.220255 -216.242639) (xy 247.212537 -216.296432) (xy 247.197266 -216.348585) (xy 247.174752 -216.398045)
			(xy 247.145449 -216.443811) (xy 247.109951 -216.484958) (xy 247.068975 -216.520652) (xy 247.023349 -216.550174)
			(xy 246.973998 -216.572925) (xy 246.921918 -216.588445) (xy 246.895112 -216.592912) (xy 246.883682 -216.59469)
			(xy 246.864886 -216.607136) (xy 246.812562 -216.694766) (xy 246.81053 -216.717118) (xy 246.814594 -216.72804)
			(xy 246.825256 -216.759556) (xy 246.836755 -216.825079) (xy 246.837454 -216.858342) (xy 246.836968 -216.885593)
			(xy 246.829212 -216.939541) (xy 246.813857 -216.991836) (xy 246.791215 -217.041413) (xy 246.761749 -217.087263)
			(xy 246.737818 -217.114882) (xy 247.467627 -217.114882) (xy 247.471688 -217.056802) (xy 247.483793 -216.999852)
			(xy 247.503706 -216.945141) (xy 247.53104 -216.893735) (xy 247.565262 -216.846632) (xy 247.605706 -216.804751)
			(xy 247.651586 -216.768906) (xy 247.702008 -216.739795) (xy 247.75599 -216.717984) (xy 247.812483 -216.703899)
			(xy 247.870386 -216.697813) (xy 247.928572 -216.699845) (xy 247.98591 -216.709955) (xy 248.041282 -216.727947)
			(xy 248.093612 -216.75347) (xy 248.14188 -216.786027) (xy 248.185147 -216.824985) (xy 248.222571 -216.869586)
			(xy 248.253424 -216.918961) (xy 248.277105 -216.972149) (xy 248.293153 -217.028116) (xy 248.301256 -217.085771)
			(xy 248.301764 -217.114882) (xy 248.301256 -217.143993) (xy 248.293153 -217.201648) (xy 248.277105 -217.257615)
			(xy 248.253424 -217.310803) (xy 248.222571 -217.360178) (xy 248.185147 -217.404779) (xy 248.14188 -217.443737)
			(xy 248.093612 -217.476294) (xy 248.044597 -217.5002) (xy 248.970292 -217.5002) (xy 248.970814 -217.472815)
			(xy 248.978659 -217.418609) (xy 248.994174 -217.366083) (xy 249.01704 -217.316314) (xy 249.046787 -217.270326)
			(xy 249.082804 -217.229063) (xy 249.12435 -217.193375) (xy 249.170572 -217.163993) (xy 249.220521 -217.141522)
			(xy 249.273169 -217.126424) (xy 249.300238 -217.122248) (xy 249.314655 -217.11981) (xy 249.341335 -217.107883)
			(xy 249.363537 -217.088879) (xy 249.379438 -217.064359) (xy 249.387732 -217.036336) (xy 249.387739 -217.007111)
			(xy 249.384058 -216.992962) (xy 249.376928 -216.966871) (xy 249.369285 -216.913326) (xy 249.368818 -216.886282)
			(xy 249.369304 -216.859031) (xy 249.37706 -216.805083) (xy 249.392415 -216.752788) (xy 249.415057 -216.703211)
			(xy 249.444523 -216.657361) (xy 249.480214 -216.61617) (xy 249.521405 -216.580479) (xy 249.567255 -216.551013)
			(xy 249.616832 -216.528371) (xy 249.669127 -216.513016) (xy 249.723075 -216.50526) (xy 249.777577 -216.50526)
			(xy 249.831525 -216.513016) (xy 249.88382 -216.528371) (xy 249.933397 -216.551013) (xy 249.979247 -216.580479)
			(xy 250.020438 -216.61617) (xy 250.056129 -216.657361) (xy 250.085595 -216.703211) (xy 250.108237 -216.752788)
			(xy 250.123592 -216.805083) (xy 250.127816 -216.834466) (xy 254.78054 -216.834466) (xy 254.784611 -216.778844)
			(xy 254.796737 -216.724407) (xy 254.81666 -216.672316) (xy 254.843956 -216.623681) (xy 254.878042 -216.579538)
			(xy 254.918191 -216.540829) (xy 254.963549 -216.508378) (xy 255.013149 -216.482877) (xy 255.065933 -216.46487)
			(xy 255.120776 -216.45474) (xy 255.17651 -216.452703) (xy 255.231947 -216.458803) (xy 255.285904 -216.472909)
			(xy 255.337233 -216.494721) (xy 255.384839 -216.523775) (xy 255.427707 -216.55945) (xy 255.464924 -216.600987)
			(xy 255.495697 -216.6475) (xy 255.519369 -216.697997) (xy 255.535437 -216.751404) (xy 255.543557 -216.80658)
			(xy 255.544066 -216.834466) (xy 255.543557 -216.862352) (xy 255.535437 -216.917528) (xy 255.519369 -216.970935)
			(xy 255.495697 -217.021432) (xy 255.464924 -217.067945) (xy 255.427707 -217.109482) (xy 255.384839 -217.145157)
			(xy 255.337233 -217.174211) (xy 255.285904 -217.196023) (xy 255.231947 -217.210129) (xy 255.17651 -217.216229)
			(xy 255.120776 -217.214192) (xy 255.065933 -217.204062) (xy 255.013149 -217.186055) (xy 254.963549 -217.160554)
			(xy 254.918191 -217.128103) (xy 254.878042 -217.089394) (xy 254.843956 -217.045251) (xy 254.81666 -216.996616)
			(xy 254.796737 -216.944525) (xy 254.784611 -216.890088) (xy 254.78054 -216.834466) (xy 250.127816 -216.834466)
			(xy 250.131348 -216.859031) (xy 250.131834 -216.886282) (xy 250.131359 -216.913669) (xy 250.123515 -216.96788)
			(xy 250.107998 -217.020412) (xy 250.085129 -217.070184) (xy 250.055377 -217.116175) (xy 250.019355 -217.157439)
			(xy 249.977801 -217.193127) (xy 249.931571 -217.222506) (xy 249.881615 -217.244972) (xy 249.82896 -217.260063)
			(xy 249.801888 -217.264234) (xy 249.787468 -217.266643) (xy 249.760793 -217.278585) (xy 249.738597 -217.297597)
			(xy 249.722699 -217.32212) (xy 249.714404 -217.350144) (xy 249.714391 -217.379369) (xy 249.718068 -217.39352)
			(xy 249.725195 -217.419612) (xy 249.73284 -217.473156) (xy 249.733308 -217.5002) (xy 249.732822 -217.527451)
			(xy 249.725066 -217.581399) (xy 249.709711 -217.633694) (xy 249.687069 -217.683271) (xy 249.657603 -217.729121)
			(xy 249.621912 -217.770312) (xy 249.580721 -217.806003) (xy 249.534871 -217.835469) (xy 249.485294 -217.858111)
			(xy 249.432999 -217.873466) (xy 249.379051 -217.881222) (xy 249.324549 -217.881222) (xy 249.270601 -217.873466)
			(xy 249.218306 -217.858111) (xy 249.168729 -217.835469) (xy 249.122879 -217.806003) (xy 249.081688 -217.770312)
			(xy 249.045997 -217.729121) (xy 249.016531 -217.683271) (xy 248.993889 -217.633694) (xy 248.978534 -217.581399)
			(xy 248.970778 -217.527451) (xy 248.970292 -217.5002) (xy 248.044597 -217.5002) (xy 248.041282 -217.501817)
			(xy 247.98591 -217.519809) (xy 247.928572 -217.529919) (xy 247.870386 -217.531951) (xy 247.812483 -217.525865)
			(xy 247.75599 -217.51178) (xy 247.702008 -217.489969) (xy 247.651586 -217.460858) (xy 247.605706 -217.425013)
			(xy 247.565262 -217.383132) (xy 247.53104 -217.336029) (xy 247.503706 -217.284623) (xy 247.483793 -217.229912)
			(xy 247.471688 -217.172962) (xy 247.467627 -217.114882) (xy 246.737818 -217.114882) (xy 246.726058 -217.128454)
			(xy 246.684867 -217.164145) (xy 246.639017 -217.193611) (xy 246.58944 -217.216253) (xy 246.537145 -217.231608)
			(xy 246.483197 -217.239364) (xy 246.428695 -217.239364) (xy 246.374747 -217.231608) (xy 246.322452 -217.216253)
			(xy 246.272875 -217.193611) (xy 246.227025 -217.164145) (xy 246.185834 -217.128454) (xy 246.150143 -217.087263)
			(xy 246.120677 -217.041413) (xy 246.098035 -216.991836) (xy 246.08268 -216.939541) (xy 246.074924 -216.885593)
			(xy 246.074438 -216.858342) (xy 246.074922 -216.83117) (xy 246.082639 -216.777375) (xy 246.097908 -216.72522)
			(xy 246.120422 -216.675757) (xy 246.149724 -216.629989) (xy 246.185221 -216.588839) (xy 246.226197 -216.553141)
			(xy 246.271822 -216.523616) (xy 246.321174 -216.500862) (xy 246.373255 -216.485338) (xy 246.400066 -216.480898)
			(xy 246.411496 -216.47912) (xy 246.430292 -216.466674) (xy 246.482616 -216.379044) (xy 246.484648 -216.356692)
			(xy 246.480584 -216.34577) (xy 246.469922 -216.314254) (xy 246.458422 -216.248731) (xy 246.457724 -216.215468)
			(xy 246.458212 -216.188219) (xy 246.465973 -216.134277) (xy 246.481331 -216.081988) (xy 246.503974 -216.032416)
			(xy 246.533442 -215.986572) (xy 246.569134 -215.945389) (xy 246.610324 -215.909704) (xy 246.656173 -215.880244)
			(xy 246.705748 -215.857609) (xy 246.758039 -215.842259) (xy 246.811983 -215.834508) (xy 246.839232 -215.83396)
			(xy 246.86773 -215.834512) (xy 246.924087 -215.843029) (xy 246.978553 -215.859824) (xy 247.029919 -215.884525)
			(xy 247.077045 -215.916582) (xy 247.098312 -215.93556) (xy 247.106249 -215.942259) (xy 247.125797 -215.949214)
			(xy 247.146503 -215.947875) (xy 247.164993 -215.938459) (xy 247.178255 -215.922501) (xy 247.184127 -215.9026)
			(xy 247.181654 -215.881999) (xy 247.176798 -215.872822) (xy 247.159272 -215.838278) (xy 247.155208 -215.829642)
			(xy 246.253508 -214.927942) (xy 246.246165 -214.921126) (xy 246.227703 -214.913384) (xy 246.217694 -214.912956)
			(xy 246.1895 -214.912956) (xy 246.163425 -214.912487) (xy 246.111911 -214.904358) (xy 246.062304 -214.888271)
			(xy 246.015825 -214.86462) (xy 245.973619 -214.833989) (xy 245.954804 -214.815928) (xy 245.671594 -214.532718)
			(xy 245.653478 -214.513939) (xy 245.622786 -214.471743) (xy 245.599078 -214.425263) (xy 245.582939 -214.375644)
			(xy 245.574767 -214.324111) (xy 245.574312 -214.298022) (xy 245.574312 -214.278718) (xy 245.573823 -214.268757)
			(xy 245.566233 -214.250336) (xy 245.55958 -214.242904) (xy 245.034054 -213.717378) (xy 245.023871 -213.706938)
			(xy 245.005175 -213.684553) (xy 244.996716 -213.672674) (xy 244.993922 -213.668864) (xy 244.96649 -213.641432)
			(xy 244.957346 -213.632034) (xy 244.956076 -213.63051) (xy 244.884702 -213.559136) (xy 244.877865 -213.551734)
			(xy 244.870154 -213.533136) (xy 244.869716 -213.523068) (xy 244.869716 -213.421468) (xy 244.869208 -213.406736)
			(xy 244.869208 -212.928708) (xy 244.868735 -212.91874) (xy 244.861167 -212.900295) (xy 244.854476 -212.892894)
			(xy 243.65966 -211.698078) (xy 243.652811 -211.690681) (xy 243.645075 -211.672082) (xy 243.644674 -211.66201)
			(xy 243.644674 -211.4296) (xy 243.643658 -211.42452) (xy 243.640663 -211.408368) (xy 243.637486 -211.375669)
			(xy 243.637308 -211.359242) (xy 243.637308 -210.074764) (xy 243.636764 -210.064779) (xy 243.629042 -210.046356)
			(xy 243.622322 -210.03895) (xy 243.461286 -209.877914) (xy 243.453887 -209.871068) (xy 243.435289 -209.863337)
			(xy 243.425218 -209.862928) (xy 241.653568 -209.862928) (xy 241.643501 -209.863358) (xy 241.624908 -209.871083)
			(xy 241.6175 -209.877914) (xy 241.518186 -209.977228) (xy 241.511335 -209.984624) (xy 241.503597 -210.003223)
			(xy 241.5032 -210.013296) (xy 241.5032 -210.712558) (xy 242.502688 -210.712558) (xy 242.506759 -210.656936)
			(xy 242.518885 -210.602499) (xy 242.538808 -210.550408) (xy 242.566104 -210.501773) (xy 242.60019 -210.45763)
			(xy 242.640339 -210.418921) (xy 242.685697 -210.38647) (xy 242.735297 -210.360969) (xy 242.788081 -210.342962)
			(xy 242.842924 -210.332832) (xy 242.898658 -210.330795) (xy 242.954095 -210.336895) (xy 243.008052 -210.351001)
			(xy 243.059381 -210.372813) (xy 243.106987 -210.401867) (xy 243.149855 -210.437542) (xy 243.187072 -210.479079)
			(xy 243.217845 -210.525592) (xy 243.241517 -210.576089) (xy 243.257585 -210.629496) (xy 243.265705 -210.684672)
			(xy 243.266214 -210.712558) (xy 243.265705 -210.740444) (xy 243.257585 -210.79562) (xy 243.241517 -210.849027)
			(xy 243.217845 -210.899524) (xy 243.187072 -210.946037) (xy 243.149855 -210.987574) (xy 243.106987 -211.023249)
			(xy 243.059381 -211.052303) (xy 243.008052 -211.074115) (xy 242.954095 -211.088221) (xy 242.898658 -211.094321)
			(xy 242.842924 -211.092284) (xy 242.788081 -211.082154) (xy 242.735297 -211.064147) (xy 242.685697 -211.038646)
			(xy 242.640339 -211.006195) (xy 242.60019 -210.967486) (xy 242.566104 -210.923343) (xy 242.538808 -210.874708)
			(xy 242.518885 -210.822617) (xy 242.506759 -210.76818) (xy 242.502688 -210.712558) (xy 241.5032 -210.712558)
			(xy 241.5032 -211.232496) (xy 241.503623 -211.242567) (xy 241.511336 -211.261172) (xy 241.518186 -211.268564)
			(xy 241.927634 -211.678012) (xy 241.950546 -211.701589) (xy 241.991523 -211.753002) (xy 242.026488 -211.808679)
			(xy 242.03817 -211.832952) (xy 242.36883 -211.832952) (xy 242.372901 -211.77733) (xy 242.385027 -211.722893)
			(xy 242.40495 -211.670802) (xy 242.432246 -211.622167) (xy 242.466332 -211.578024) (xy 242.506481 -211.539315)
			(xy 242.551839 -211.506864) (xy 242.601439 -211.481363) (xy 242.654223 -211.463356) (xy 242.709066 -211.453226)
			(xy 242.7648 -211.451189) (xy 242.820237 -211.457289) (xy 242.874194 -211.471395) (xy 242.925523 -211.493207)
			(xy 242.973129 -211.522261) (xy 243.015997 -211.557936) (xy 243.053214 -211.599473) (xy 243.083987 -211.645986)
			(xy 243.107659 -211.696483) (xy 243.123727 -211.74989) (xy 243.131847 -211.805066) (xy 243.132356 -211.832952)
			(xy 243.131847 -211.860838) (xy 243.123727 -211.916014) (xy 243.107659 -211.969421) (xy 243.083987 -212.019918)
			(xy 243.053214 -212.066431) (xy 243.015997 -212.107968) (xy 242.973129 -212.143643) (xy 242.925523 -212.172697)
			(xy 242.874194 -212.194509) (xy 242.820237 -212.208615) (xy 242.7648 -212.214715) (xy 242.709066 -212.212678)
			(xy 242.654223 -212.202548) (xy 242.601439 -212.184541) (xy 242.551839 -212.15904) (xy 242.506481 -212.126589)
			(xy 242.466332 -212.08788) (xy 242.432246 -212.043737) (xy 242.40495 -211.995102) (xy 242.385027 -211.943011)
			(xy 242.372901 -211.888574) (xy 242.36883 -211.832952) (xy 242.03817 -211.832952) (xy 242.055 -211.86792)
			(xy 242.076701 -211.929981) (xy 242.091318 -211.99408) (xy 242.098668 -212.059413) (xy 242.099084 -212.092286)
			(xy 242.099084 -212.391752) (xy 242.099578 -212.401186) (xy 242.106492 -212.41875) (xy 242.119264 -212.432647)
			(xy 242.127532 -212.437218) (xy 242.22202 -212.483954) (xy 242.250976 -212.48116) (xy 242.262406 -212.472524)
			(xy 242.282419 -212.457748) (xy 242.325548 -212.432957) (xy 242.371536 -212.413988) (xy 242.419601 -212.401165)
			(xy 242.468927 -212.394705) (xy 242.4938 -212.394292) (xy 242.521051 -212.394778) (xy 242.574999 -212.402534)
			(xy 242.627294 -212.417889) (xy 242.676871 -212.440531) (xy 242.722721 -212.469997) (xy 242.763912 -212.505688)
			(xy 242.799603 -212.546879) (xy 242.829069 -212.592729) (xy 242.851711 -212.642306) (xy 242.867066 -212.694601)
			(xy 242.874822 -212.748549) (xy 242.875308 -212.7758) (xy 242.874796 -212.804422) (xy 242.866248 -212.861024)
			(xy 242.849344 -212.915715) (xy 242.824462 -212.967269) (xy 242.812104 -212.98535) (xy 243.756432 -212.98535)
			(xy 243.760503 -212.929728) (xy 243.772629 -212.875291) (xy 243.792552 -212.8232) (xy 243.819848 -212.774565)
			(xy 243.853934 -212.730422) (xy 243.894083 -212.691713) (xy 243.939441 -212.659262) (xy 243.989041 -212.633761)
			(xy 244.041825 -212.615754) (xy 244.096668 -212.605624) (xy 244.152402 -212.603587) (xy 244.207839 -212.609687)
			(xy 244.261796 -212.623793) (xy 244.313125 -212.645605) (xy 244.360731 -212.674659) (xy 244.403599 -212.710334)
			(xy 244.440816 -212.751871) (xy 244.471589 -212.798384) (xy 244.495261 -212.848881) (xy 244.511329 -212.902288)
			(xy 244.519449 -212.957464) (xy 244.519958 -212.98535) (xy 244.519449 -213.013236) (xy 244.511329 -213.068412)
			(xy 244.495261 -213.121819) (xy 244.471589 -213.172316) (xy 244.440816 -213.218829) (xy 244.403599 -213.260366)
			(xy 244.360731 -213.296041) (xy 244.313125 -213.325095) (xy 244.261796 -213.346907) (xy 244.207839 -213.361013)
			(xy 244.152402 -213.367113) (xy 244.096668 -213.365076) (xy 244.041825 -213.354946) (xy 243.989041 -213.336939)
			(xy 243.939441 -213.311438) (xy 243.894083 -213.278987) (xy 243.853934 -213.240278) (xy 243.819848 -213.196135)
			(xy 243.792552 -213.1475) (xy 243.772629 -213.095409) (xy 243.760503 -213.040972) (xy 243.756432 -212.98535)
			(xy 242.812104 -212.98535) (xy 242.792161 -213.014528) (xy 242.753165 -213.056435) (xy 242.708348 -213.092049)
			(xy 242.683792 -213.106762) (xy 242.673378 -213.112604) (xy 242.66017 -213.132162) (xy 242.647978 -213.223856)
			(xy 242.647049 -213.235569) (xy 242.654592 -213.257797) (xy 242.662456 -213.266528) (xy 242.872768 -213.47684)
			(xy 242.879612 -213.484239) (xy 242.887337 -213.502838) (xy 242.887754 -213.512908) (xy 242.887754 -214.418926)
			(xy 242.888183 -214.428993) (xy 242.89591 -214.447585) (xy 242.90274 -214.454994) (xy 243.035836 -214.58809)
			(xy 243.043183 -214.594896) (xy 243.061645 -214.602617) (xy 243.07165 -214.603076) (xy 243.205 -214.603076)
			(xy 243.239075 -214.60357) (xy 243.306766 -214.611477) (xy 243.373082 -214.627184) (xy 243.437128 -214.650479)
			(xy 243.49804 -214.681046) (xy 243.554993 -214.718475) (xy 243.581428 -214.739982) (xy 243.590386 -214.746781)
			(xy 243.612085 -214.752584) (xy 243.634187 -214.748584) (xy 243.643658 -214.742522) (xy 243.66806 -214.725765)
			(xy 243.720955 -214.699195) (xy 243.777321 -214.68112) (xy 243.835803 -214.671972) (xy 243.8654 -214.671402)
			(xy 243.892653 -214.671865) (xy 243.946603 -214.679622) (xy 243.9989 -214.694979) (xy 244.04848 -214.717621)
			(xy 244.094332 -214.747089) (xy 244.135524 -214.782783) (xy 244.171217 -214.823976) (xy 244.200684 -214.869829)
			(xy 244.223325 -214.919409) (xy 244.23868 -214.971707) (xy 244.246435 -215.025657) (xy 244.246908 -215.05291)
			(xy 244.246369 -215.082235) (xy 244.237387 -215.140192) (xy 244.219637 -215.19609) (xy 244.193537 -215.248612)
			(xy 244.177058 -215.272874) (xy 244.16639 -215.288114) (xy 244.169438 -215.324944) (xy 247.006061 -218.161362)
			(xy 250.778262 -218.161362) (xy 250.782333 -218.10574) (xy 250.794459 -218.051303) (xy 250.814382 -217.999212)
			(xy 250.841678 -217.950577) (xy 250.875764 -217.906434) (xy 250.915913 -217.867725) (xy 250.961271 -217.835274)
			(xy 251.010871 -217.809773) (xy 251.063655 -217.791766) (xy 251.118498 -217.781636) (xy 251.174232 -217.779599)
			(xy 251.229669 -217.785699) (xy 251.283626 -217.799805) (xy 251.334955 -217.821617) (xy 251.382561 -217.850671)
			(xy 251.425429 -217.886346) (xy 251.462646 -217.927883) (xy 251.493419 -217.974396) (xy 251.517091 -218.024893)
			(xy 251.533159 -218.0783) (xy 251.541279 -218.133476) (xy 251.541788 -218.161362) (xy 251.541279 -218.189248)
			(xy 251.533159 -218.244424) (xy 251.517091 -218.297831) (xy 251.493419 -218.348328) (xy 251.462646 -218.394841)
			(xy 251.425429 -218.436378) (xy 251.382561 -218.472053) (xy 251.334955 -218.501107) (xy 251.283626 -218.522919)
			(xy 251.229669 -218.537025) (xy 251.174232 -218.543125) (xy 251.118498 -218.541088) (xy 251.063655 -218.530958)
			(xy 251.010871 -218.512951) (xy 250.961271 -218.48745) (xy 250.915913 -218.454999) (xy 250.875764 -218.41629)
			(xy 250.841678 -218.372147) (xy 250.814382 -218.323512) (xy 250.794459 -218.271421) (xy 250.782333 -218.216984)
			(xy 250.778262 -218.161362) (xy 247.006061 -218.161362) (xy 247.691402 -218.846654) (xy 247.698745 -218.853469)
			(xy 247.717208 -218.861208) (xy 247.727216 -218.86164) (xy 255.083564 -218.86164) (xy 255.116439 -218.862065)
			(xy 255.181779 -218.869393) (xy 255.245887 -218.883994) (xy 255.307956 -218.905683) (xy 255.367204 -218.934189)
			(xy 255.422887 -218.969153) (xy 255.474303 -219.010134) (xy 255.497838 -219.03309) (xy 255.64084 -219.176092)
			(xy 255.64824 -219.182933) (xy 255.666838 -219.190654) (xy 255.676908 -219.191078) (xy 258.7752 -219.191078)
			(xy 258.785271 -219.1915) (xy 258.803877 -219.199212) (xy 258.811268 -219.206064) (xy 260.03123 -220.426026)
			(xy 260.038573 -220.43284) (xy 260.057037 -220.440573) (xy 260.067044 -220.441012) (xy 260.193536 -220.441012)
			(xy 260.226409 -220.441442) (xy 260.291744 -220.448778) (xy 260.355846 -220.463386) (xy 260.417908 -220.485084)
			(xy 260.477149 -220.513597) (xy 260.532823 -220.548567) (xy 260.584229 -220.589554) (xy 260.60781 -220.612462)
			(xy 261.572756 -221.577408) (xy 265.124182 -221.577408) (xy 265.128253 -221.521786) (xy 265.140379 -221.467349)
			(xy 265.160302 -221.415258) (xy 265.187598 -221.366623) (xy 265.221684 -221.32248) (xy 265.261833 -221.283771)
			(xy 265.307191 -221.25132) (xy 265.356791 -221.225819) (xy 265.409575 -221.207812) (xy 265.464418 -221.197682)
			(xy 265.520152 -221.195645) (xy 265.575589 -221.201745) (xy 265.629546 -221.215851) (xy 265.680875 -221.237663)
			(xy 265.728481 -221.266717) (xy 265.771349 -221.302392) (xy 265.808566 -221.343929) (xy 265.839339 -221.390442)
			(xy 265.863011 -221.440939) (xy 265.879079 -221.494346) (xy 265.887199 -221.549522) (xy 265.887708 -221.577408)
			(xy 265.887199 -221.605294) (xy 265.879079 -221.66047) (xy 265.863011 -221.713877) (xy 265.839339 -221.764374)
			(xy 265.808566 -221.810887) (xy 265.771349 -221.852424) (xy 265.728481 -221.888099) (xy 265.680875 -221.917153)
			(xy 265.629546 -221.938965) (xy 265.575589 -221.953071) (xy 265.520152 -221.959171) (xy 265.464418 -221.957134)
			(xy 265.409575 -221.947004) (xy 265.356791 -221.928997) (xy 265.307191 -221.903496) (xy 265.261833 -221.871045)
			(xy 265.221684 -221.832336) (xy 265.187598 -221.788193) (xy 265.160302 -221.739558) (xy 265.140379 -221.687467)
			(xy 265.128253 -221.63303) (xy 265.124182 -221.577408) (xy 261.572756 -221.577408) (xy 262.228838 -222.23349)
			(xy 262.236185 -222.240296) (xy 262.254647 -222.248016) (xy 262.264652 -222.248476) (xy 263.347454 -222.248476)
			(xy 263.374378 -222.22841) (xy 263.379204 -222.212408) (xy 263.387511 -222.186655) (xy 263.410382 -222.137615)
			(xy 263.439954 -222.0923) (xy 263.475633 -222.051618) (xy 263.516704 -222.016387) (xy 263.562341 -221.987315)
			(xy 263.611629 -221.964984) (xy 263.663579 -221.949843) (xy 263.717147 -221.942195) (xy 263.771257 -221.942195)
			(xy 263.824825 -221.949843) (xy 263.876775 -221.964984) (xy 263.926063 -221.987315) (xy 263.9717 -222.016387)
			(xy 264.012771 -222.051618) (xy 264.04845 -222.0923) (xy 264.078022 -222.137615) (xy 264.100893 -222.186655)
			(xy 264.1092 -222.212408) (xy 264.114026 -222.22841) (xy 264.14095 -222.248476) (xy 269.621 -222.248476)
			(xy 269.656041 -222.248961) (xy 269.72563 -222.257257) (xy 269.793736 -222.273777) (xy 269.82674 -222.28556)
			(xy 269.835376 -222.288862) (xy 270.576548 -222.288862) (xy 270.586613 -222.289296) (xy 270.605199 -222.297029)
			(xy 270.612616 -222.303848) (xy 276.477222 -228.168454) (xy 276.485686 -228.175996) (xy 276.507046 -228.183501)
			(xy 276.51837 -228.182932) (xy 276.60854 -228.17328) (xy 276.628098 -228.161342) (xy 276.634448 -228.151436)
			(xy 276.649595 -228.128801) (xy 276.685287 -228.087663) (xy 276.726467 -228.052021) (xy 276.772298 -228.022598)
			(xy 276.821847 -227.999992) (xy 276.874109 -227.984664) (xy 276.928019 -227.976925) (xy 276.95525 -227.97643)
			(xy 276.982504 -227.97689) (xy 277.036459 -227.984641) (xy 277.08876 -227.999993) (xy 277.138344 -228.022634)
			(xy 277.184201 -228.052101) (xy 277.225396 -228.087795) (xy 277.261092 -228.12899) (xy 277.290561 -228.174845)
			(xy 277.313202 -228.224429) (xy 277.328556 -228.27673) (xy 277.336309 -228.330684) (xy 277.336758 -228.357938)
			(xy 277.336271 -228.385168) (xy 277.328522 -228.439075) (xy 277.313187 -228.491332) (xy 277.290577 -228.540878)
			(xy 277.261152 -228.586706) (xy 277.22551 -228.627884) (xy 277.184375 -228.663576) (xy 277.161752 -228.67874)
			(xy 277.151846 -228.68509) (xy 277.139908 -228.704648) (xy 277.130256 -228.794818) (xy 277.129661 -228.806146)
			(xy 277.137164 -228.827521) (xy 277.144734 -228.835966) (xy 278.68245 -230.373682) (xy 278.689797 -230.380487)
			(xy 278.70826 -230.388204) (xy 278.718264 -230.388668)
		)
		(stroke
			(width 0)
			(type solid)
		)
		(fill yes)
		(layer "In13.Cu")
		(net "P5V_AUX")
	)
	(gr_poly
		(pts
			(xy 107.1372 -360.5022) (xy 107.149031 -360.501565) (xy 107.170192 -360.490972) (xy 107.184409 -360.472054)
			(xy 107.187238 -360.460544) (xy 107.466638 -358.938322) (xy 107.4674 -358.929178) (xy 107.4674 -356.916482)
			(xy 107.466973 -356.906413) (xy 107.459254 -356.887814) (xy 107.452414 -356.880414) (xy 106.999786 -356.427786)
			(xy 106.992932 -356.420391) (xy 106.98519 -356.401792) (xy 106.9848 -356.391718) (xy 106.9848 -353.625912)
			(xy 106.984384 -353.616303) (xy 106.977334 -353.598425) (xy 106.971084 -353.591114) (xy 106.916728 -353.533202)
			(xy 106.89971 -353.525074) (xy 106.889804 -353.524566) (xy 106.862539 -353.522291) (xy 106.809022 -353.510919)
			(xy 106.757678 -353.49202) (xy 106.709559 -353.465982) (xy 106.665652 -353.433339) (xy 106.626857 -353.39476)
			(xy 106.593969 -353.351036) (xy 106.567663 -353.303063) (xy 106.548479 -353.251825) (xy 106.536808 -353.198373)
			(xy 106.532891 -353.143801) (xy 106.536808 -353.08923) (xy 106.548478 -353.035777) (xy 106.567662 -352.984539)
			(xy 106.593968 -352.936566) (xy 106.626855 -352.892842) (xy 106.66565 -352.854263) (xy 106.709557 -352.821619)
			(xy 106.757675 -352.795581) (xy 106.809019 -352.776682) (xy 106.862536 -352.76531) (xy 106.889804 -352.763074)
			(xy 106.89971 -352.762566) (xy 106.916728 -352.754438) (xy 106.971084 -352.696526) (xy 106.97737 -352.689236)
			(xy 106.98443 -352.671346) (xy 106.9848 -352.661728) (xy 106.9848 -351.994978) (xy 106.984253 -351.984377)
			(xy 106.975722 -351.964965) (xy 106.96829 -351.957386) (xy 106.905044 -351.899474) (xy 106.885232 -351.89287)
			(xy 106.874564 -351.893632) (xy 106.841544 -351.895156) (xy 106.814286 -351.894696) (xy 106.760323 -351.886943)
			(xy 106.708013 -351.871589) (xy 106.658421 -351.848946) (xy 106.612557 -351.819476) (xy 106.571354 -351.783777)
			(xy 106.535651 -351.742578) (xy 106.506175 -351.696717) (xy 106.483526 -351.647128) (xy 106.468166 -351.59482)
			(xy 106.460407 -351.540858) (xy 106.460407 -351.486342) (xy 106.468166 -351.43238) (xy 106.483526 -351.380072)
			(xy 106.506175 -351.330483) (xy 106.535651 -351.284622) (xy 106.571354 -351.243423) (xy 106.612557 -351.207724)
			(xy 106.658421 -351.178254) (xy 106.708013 -351.155611) (xy 106.760323 -351.140257) (xy 106.814286 -351.132504)
			(xy 106.841544 -351.13214) (xy 106.874564 -351.133664) (xy 106.885232 -351.134426) (xy 106.905044 -351.127822)
			(xy 106.96829 -351.06991) (xy 106.975842 -351.062414) (xy 106.984392 -351.04295) (xy 106.9848 -351.032318)
			(xy 106.9848 -349.271082) (xy 106.985227 -349.261013) (xy 106.992946 -349.242414) (xy 106.999786 -349.235014)
			(xy 108.544614 -347.690186) (xy 108.551468 -347.682791) (xy 108.55921 -347.664192) (xy 108.5596 -347.654118)
			(xy 108.5596 -346.214954) (xy 108.559168 -346.204888) (xy 108.551442 -346.186295) (xy 108.544614 -346.178886)
			(xy 108.303822 -345.938094) (xy 108.277914 -345.930982) (xy 108.264706 -345.934538) (xy 108.240759 -345.94047)
			(xy 108.191837 -345.946844) (xy 108.16717 -345.947238) (xy 108.138574 -345.946725) (xy 108.082024 -345.938183)
			(xy 108.027384 -345.921293) (xy 107.975877 -345.896435) (xy 107.928659 -345.864165) (xy 107.886788 -345.825208)
			(xy 107.851202 -345.780436) (xy 107.822699 -345.730854) (xy 107.801918 -345.677571) (xy 107.79506 -345.649804)
			(xy 107.792012 -345.636088) (xy 107.772962 -345.616022) (xy 107.674156 -345.58732) (xy 107.66534 -345.585192)
			(xy 107.64727 -345.586583) (xy 107.630797 -345.594139) (xy 107.624118 -345.600274) (xy 106.018076 -347.206316)
			(xy 106.011397 -347.213728) (xy 106.003824 -347.232163) (xy 106.003344 -347.24213) (xy 106.003344 -347.954854)
			(xy 106.003702 -347.963552) (xy 106.009528 -347.979943) (xy 106.020492 -347.993449) (xy 106.027728 -347.998288)
			(xy 106.113072 -348.050358) (xy 106.139742 -348.05112) (xy 106.151426 -348.045024) (xy 106.178708 -348.031577)
			(xy 106.236476 -348.01255) (xy 106.29653 -348.002918) (xy 106.32694 -348.002352) (xy 106.354192 -348.002841)
			(xy 106.408141 -348.010603) (xy 106.460437 -348.025963) (xy 106.510014 -348.048609) (xy 106.555864 -348.078079)
			(xy 106.597054 -348.113774) (xy 106.632745 -348.154968) (xy 106.662211 -348.200821) (xy 106.684851 -348.250401)
			(xy 106.700206 -348.302698) (xy 106.707962 -348.356648) (xy 106.707962 -348.411152) (xy 106.700206 -348.465102)
			(xy 106.684851 -348.517399) (xy 106.662211 -348.566979) (xy 106.632745 -348.612832) (xy 106.597054 -348.654026)
			(xy 106.555864 -348.689721) (xy 106.510014 -348.719191) (xy 106.460437 -348.741837) (xy 106.408141 -348.757197)
			(xy 106.354192 -348.764959) (xy 106.32694 -348.765368) (xy 106.2982 -348.76485) (xy 106.24137 -348.756232)
			(xy 106.186476 -348.739185) (xy 106.134761 -348.714095) (xy 106.087395 -348.681531) (xy 106.066082 -348.662244)
			(xy 106.05897 -348.65564) (xy 106.041444 -348.648528) (xy 105.953052 -348.64802) (xy 105.935526 -348.654878)
			(xy 105.92816 -348.661228) (xy 105.906985 -348.679848) (xy 105.860181 -348.711288) (xy 105.809257 -348.735495)
			(xy 105.755324 -348.751941) (xy 105.699558 -348.760266) (xy 105.671366 -348.760796) (xy 105.644117 -348.760307)
			(xy 105.590173 -348.752547) (xy 105.537883 -348.737189) (xy 105.488311 -348.714545) (xy 105.442466 -348.685078)
			(xy 105.401281 -348.649386) (xy 105.365594 -348.608197) (xy 105.336132 -348.562348) (xy 105.313495 -348.512773)
			(xy 105.298143 -348.460482) (xy 105.290389 -348.406537) (xy 105.289858 -348.379288) (xy 105.290471 -348.348486)
			(xy 105.30041 -348.287689) (xy 105.319981 -348.229276) (xy 105.3338 -348.201742) (xy 105.336594 -348.196154)
			(xy 105.339388 -348.184216) (xy 105.339388 -347.083634) (xy 105.339871 -347.057545) (xy 105.348032 -347.00601)
			(xy 105.364159 -346.956387) (xy 105.387853 -346.9099) (xy 105.41853 -346.867694) (xy 105.43667 -346.848938)
			(xy 107.17149 -345.114118) (xy 107.178289 -345.106769) (xy 107.185993 -345.088306) (xy 107.186476 -345.078304)
			(xy 107.186476 -344.841576) (xy 107.185934 -344.831591) (xy 107.178212 -344.813167) (xy 107.17149 -344.805762)
			(xy 106.847386 -344.481658) (xy 106.840537 -344.474262) (xy 106.832804 -344.455662) (xy 106.8324 -344.44559)
			(xy 106.8324 -338.755482) (xy 106.831973 -338.745413) (xy 106.824254 -338.726814) (xy 106.817414 -338.719414)
			(xy 104.637586 -336.539586) (xy 104.630191 -336.532732) (xy 104.611592 -336.52499) (xy 104.601518 -336.5246)
			(xy 102.814882 -336.5246) (xy 102.804813 -336.524173) (xy 102.786214 -336.516454) (xy 102.778814 -336.509614)
			(xy 101.945186 -335.675986) (xy 101.938332 -335.668591) (xy 101.93059 -335.649992) (xy 101.9302 -335.639918)
			(xy 101.9302 -333.015082) (xy 101.929773 -333.005013) (xy 101.922054 -332.986414) (xy 101.915214 -332.979014)
			(xy 101.741986 -332.805786) (xy 101.734591 -332.798932) (xy 101.715992 -332.79119) (xy 101.705918 -332.7908)
			(xy 98.039682 -332.7908) (xy 98.029613 -332.791227) (xy 98.011014 -332.798946) (xy 98.003614 -332.805786)
			(xy 97.322386 -333.487014) (xy 97.315532 -333.494409) (xy 97.30779 -333.513008) (xy 97.3074 -333.523082)
			(xy 97.3074 -338.600267) (xy 102.427268 -338.600267) (xy 102.427268 -338.546969) (xy 102.435211 -338.494265)
			(xy 102.450921 -338.443335) (xy 102.474047 -338.395314) (xy 102.504071 -338.351277) (xy 102.540323 -338.312206)
			(xy 102.581994 -338.278975) (xy 102.628152 -338.252326) (xy 102.677766 -338.232854) (xy 102.729728 -338.220994)
			(xy 102.782878 -338.217011) (xy 102.836028 -338.220994) (xy 102.88799 -338.232854) (xy 102.937604 -338.252326)
			(xy 102.983762 -338.278975) (xy 103.025433 -338.312206) (xy 103.061685 -338.351277) (xy 103.091709 -338.395314)
			(xy 103.114835 -338.443335) (xy 103.130545 -338.494265) (xy 103.138488 -338.546969) (xy 103.138986 -338.573618)
			(xy 103.138488 -338.600267) (xy 103.409232 -338.600267) (xy 103.409232 -338.546969) (xy 103.417175 -338.494265)
			(xy 103.432885 -338.443335) (xy 103.456011 -338.395314) (xy 103.486035 -338.351277) (xy 103.522287 -338.312206)
			(xy 103.563958 -338.278975) (xy 103.610116 -338.252326) (xy 103.65973 -338.232854) (xy 103.711692 -338.220994)
			(xy 103.764842 -338.217011) (xy 103.817992 -338.220994) (xy 103.869954 -338.232854) (xy 103.919568 -338.252326)
			(xy 103.965726 -338.278975) (xy 104.007397 -338.312206) (xy 104.043649 -338.351277) (xy 104.073673 -338.395314)
			(xy 104.096799 -338.443335) (xy 104.112509 -338.494265) (xy 104.120452 -338.546969) (xy 104.12095 -338.573618)
			(xy 104.120452 -338.600267) (xy 104.112509 -338.652971) (xy 104.096799 -338.703901) (xy 104.073673 -338.751922)
			(xy 104.043649 -338.795959) (xy 104.007397 -338.83503) (xy 103.965726 -338.868261) (xy 103.919568 -338.89491)
			(xy 103.869954 -338.914382) (xy 103.817992 -338.926242) (xy 103.764842 -338.930226) (xy 103.711692 -338.926242)
			(xy 103.65973 -338.914382) (xy 103.610116 -338.89491) (xy 103.563958 -338.868261) (xy 103.522287 -338.83503)
			(xy 103.486035 -338.795959) (xy 103.456011 -338.751922) (xy 103.432885 -338.703901) (xy 103.417175 -338.652971)
			(xy 103.409232 -338.600267) (xy 103.138488 -338.600267) (xy 103.130545 -338.652971) (xy 103.114835 -338.703901)
			(xy 103.091709 -338.751922) (xy 103.061685 -338.795959) (xy 103.025433 -338.83503) (xy 102.983762 -338.868261)
			(xy 102.937604 -338.89491) (xy 102.88799 -338.914382) (xy 102.836028 -338.926242) (xy 102.782878 -338.930226)
			(xy 102.729728 -338.926242) (xy 102.677766 -338.914382) (xy 102.628152 -338.89491) (xy 102.581994 -338.868261)
			(xy 102.540323 -338.83503) (xy 102.504071 -338.795959) (xy 102.474047 -338.751922) (xy 102.450921 -338.703901)
			(xy 102.435211 -338.652971) (xy 102.427268 -338.600267) (xy 97.3074 -338.600267) (xy 97.3074 -343.446862)
			(xy 100.191568 -343.446862) (xy 100.195639 -343.39124) (xy 100.207765 -343.336803) (xy 100.227688 -343.284712)
			(xy 100.254984 -343.236077) (xy 100.28907 -343.191934) (xy 100.329219 -343.153225) (xy 100.374577 -343.120774)
			(xy 100.424177 -343.095273) (xy 100.476961 -343.077266) (xy 100.531804 -343.067136) (xy 100.587538 -343.065099)
			(xy 100.642975 -343.071199) (xy 100.696932 -343.085305) (xy 100.748261 -343.107117) (xy 100.795867 -343.136171)
			(xy 100.838735 -343.171846) (xy 100.875952 -343.213383) (xy 100.906725 -343.259896) (xy 100.924715 -343.298272)
			(xy 102.229666 -343.298272) (xy 102.23005 -343.272344) (xy 102.237062 -343.220964) (xy 102.250965 -343.171006)
			(xy 102.271504 -343.12339) (xy 102.298301 -343.078994) (xy 102.330862 -343.038635) (xy 102.368587 -343.003056)
			(xy 102.389432 -342.98763) (xy 102.396753 -342.981879) (xy 102.407045 -342.966384) (xy 102.409498 -342.957404)
			(xy 102.416356 -342.927178) (xy 102.418087 -342.9179) (xy 102.415357 -342.899239) (xy 102.411022 -342.890856)
			(xy 102.396715 -342.864886) (xy 102.374206 -342.810032) (xy 102.358983 -342.752727) (xy 102.351302 -342.693934)
			(xy 102.350824 -342.664288) (xy 102.351251 -342.634307) (xy 102.359082 -342.574858) (xy 102.374608 -342.516941)
			(xy 102.397565 -342.461547) (xy 102.427558 -342.409624) (xy 102.464074 -342.362063) (xy 102.506487 -342.319677)
			(xy 102.554072 -342.283192) (xy 102.606014 -342.253233) (xy 102.661423 -342.230313) (xy 102.719351 -342.214824)
			(xy 102.778804 -342.207031) (xy 102.808786 -342.20658) (xy 103.672386 -342.20658) (xy 103.702361 -342.207041)
			(xy 103.761799 -342.214862) (xy 103.819708 -342.230372) (xy 103.875098 -342.253306) (xy 103.927022 -342.283272)
			(xy 103.974591 -342.319758) (xy 104.016993 -342.362139) (xy 104.053502 -342.40969) (xy 104.083494 -342.461599)
			(xy 104.106455 -342.516978) (xy 104.121994 -342.574879) (xy 104.129845 -342.634313) (xy 104.130348 -342.664288)
			(xy 104.129853 -342.693931) (xy 104.122131 -342.752713) (xy 104.106903 -342.810011) (xy 104.084424 -342.864871)
			(xy 104.07015 -342.890856) (xy 104.065916 -342.899274) (xy 104.063174 -342.9179) (xy 104.064816 -342.927178)
			(xy 104.071674 -342.957404) (xy 104.07409 -342.9664) (xy 104.084393 -342.981903) (xy 104.09174 -342.98763)
			(xy 104.112578 -343.003064) (xy 104.150313 -343.038633) (xy 104.182879 -343.078988) (xy 104.209675 -343.123383)
			(xy 104.230208 -343.171001) (xy 104.244098 -343.220962) (xy 104.251088 -343.272344) (xy 104.251506 -343.298272)
			(xy 104.25102 -343.325523) (xy 104.243264 -343.379471) (xy 104.227909 -343.431766) (xy 104.205267 -343.481343)
			(xy 104.175801 -343.527193) (xy 104.14011 -343.568384) (xy 104.098919 -343.604075) (xy 104.053069 -343.633541)
			(xy 104.003492 -343.656183) (xy 103.951197 -343.671538) (xy 103.897249 -343.679294) (xy 103.842747 -343.679294)
			(xy 103.788799 -343.671538) (xy 103.736504 -343.656183) (xy 103.686927 -343.633541) (xy 103.641077 -343.604075)
			(xy 103.599886 -343.568384) (xy 103.564195 -343.527193) (xy 103.534729 -343.481343) (xy 103.512087 -343.431766)
			(xy 103.496732 -343.379471) (xy 103.488976 -343.325523) (xy 103.48849 -343.298272) (xy 103.48862 -343.283479)
			(xy 103.490913 -343.253981) (xy 103.493062 -343.239344) (xy 103.49484 -343.228422) (xy 103.488744 -343.207086)
			(xy 103.43134 -343.139776) (xy 103.423754 -343.131769) (xy 103.403747 -343.122542) (xy 103.392732 -343.121996)
			(xy 103.08844 -343.121996) (xy 103.077424 -343.122557) (xy 103.057407 -343.13176) (xy 103.049832 -343.139776)
			(xy 102.992428 -343.207086) (xy 102.986332 -343.228422) (xy 102.98811 -343.239344) (xy 102.990251 -343.253982)
			(xy 102.992539 -343.283479) (xy 102.992682 -343.298272) (xy 102.992196 -343.325523) (xy 102.98444 -343.379471)
			(xy 102.969085 -343.431766) (xy 102.946443 -343.481343) (xy 102.916977 -343.527193) (xy 102.881286 -343.568384)
			(xy 102.840095 -343.604075) (xy 102.794245 -343.633541) (xy 102.744668 -343.656183) (xy 102.692373 -343.671538)
			(xy 102.638425 -343.679294) (xy 102.583923 -343.679294) (xy 102.529975 -343.671538) (xy 102.47768 -343.656183)
			(xy 102.428103 -343.633541) (xy 102.382253 -343.604075) (xy 102.341062 -343.568384) (xy 102.305371 -343.527193)
			(xy 102.275905 -343.481343) (xy 102.253263 -343.431766) (xy 102.237908 -343.379471) (xy 102.230152 -343.325523)
			(xy 102.229666 -343.298272) (xy 100.924715 -343.298272) (xy 100.930397 -343.310393) (xy 100.946465 -343.3638)
			(xy 100.954585 -343.418976) (xy 100.955094 -343.446862) (xy 100.954585 -343.474748) (xy 100.946465 -343.529924)
			(xy 100.930397 -343.583331) (xy 100.906725 -343.633828) (xy 100.875952 -343.680341) (xy 100.838735 -343.721878)
			(xy 100.795867 -343.757553) (xy 100.748261 -343.786607) (xy 100.696932 -343.808419) (xy 100.642975 -343.822525)
			(xy 100.587538 -343.828625) (xy 100.531804 -343.826588) (xy 100.476961 -343.816458) (xy 100.424177 -343.798451)
			(xy 100.374577 -343.77295) (xy 100.329219 -343.740499) (xy 100.28907 -343.70179) (xy 100.254984 -343.657647)
			(xy 100.227688 -343.609012) (xy 100.207765 -343.556921) (xy 100.195639 -343.502484) (xy 100.191568 -343.446862)
			(xy 97.3074 -343.446862) (xy 97.3074 -345.228926) (xy 105.613452 -345.228926) (xy 105.617523 -345.173304)
			(xy 105.629649 -345.118867) (xy 105.649572 -345.066776) (xy 105.676868 -345.018141) (xy 105.710954 -344.973998)
			(xy 105.751103 -344.935289) (xy 105.796461 -344.902838) (xy 105.846061 -344.877337) (xy 105.898845 -344.85933)
			(xy 105.953688 -344.8492) (xy 106.009422 -344.847163) (xy 106.064859 -344.853263) (xy 106.118816 -344.867369)
			(xy 106.170145 -344.889181) (xy 106.217751 -344.918235) (xy 106.260619 -344.95391) (xy 106.297836 -344.995447)
			(xy 106.328609 -345.04196) (xy 106.352281 -345.092457) (xy 106.368349 -345.145864) (xy 106.376469 -345.20104)
			(xy 106.376978 -345.228926) (xy 106.376469 -345.256812) (xy 106.368349 -345.311988) (xy 106.352281 -345.365395)
			(xy 106.328609 -345.415892) (xy 106.297836 -345.462405) (xy 106.260619 -345.503942) (xy 106.217751 -345.539617)
			(xy 106.170145 -345.568671) (xy 106.118816 -345.590483) (xy 106.064859 -345.604589) (xy 106.009422 -345.610689)
			(xy 105.953688 -345.608652) (xy 105.898845 -345.598522) (xy 105.846061 -345.580515) (xy 105.796461 -345.555014)
			(xy 105.751103 -345.522563) (xy 105.710954 -345.483854) (xy 105.676868 -345.439711) (xy 105.649572 -345.391076)
			(xy 105.629649 -345.338985) (xy 105.617523 -345.284548) (xy 105.613452 -345.228926) (xy 97.3074 -345.228926)
			(xy 97.3074 -346.090494) (xy 104.845102 -346.090494) (xy 104.849173 -346.034872) (xy 104.861299 -345.980435)
			(xy 104.881222 -345.928344) (xy 104.908518 -345.879709) (xy 104.942604 -345.835566) (xy 104.982753 -345.796857)
			(xy 105.028111 -345.764406) (xy 105.077711 -345.738905) (xy 105.130495 -345.720898) (xy 105.185338 -345.710768)
			(xy 105.241072 -345.708731) (xy 105.296509 -345.714831) (xy 105.350466 -345.728937) (xy 105.401795 -345.750749)
			(xy 105.449401 -345.779803) (xy 105.492269 -345.815478) (xy 105.529486 -345.857015) (xy 105.560259 -345.903528)
			(xy 105.583931 -345.954025) (xy 105.599999 -346.007432) (xy 105.608119 -346.062608) (xy 105.608628 -346.090494)
			(xy 105.608119 -346.11838) (xy 105.599999 -346.173556) (xy 105.583931 -346.226963) (xy 105.560259 -346.27746)
			(xy 105.529486 -346.323973) (xy 105.492269 -346.36551) (xy 105.449401 -346.401185) (xy 105.401795 -346.430239)
			(xy 105.350466 -346.452051) (xy 105.296509 -346.466157) (xy 105.241072 -346.472257) (xy 105.185338 -346.47022)
			(xy 105.130495 -346.46009) (xy 105.077711 -346.442083) (xy 105.028111 -346.416582) (xy 104.982753 -346.384131)
			(xy 104.942604 -346.345422) (xy 104.908518 -346.301279) (xy 104.881222 -346.252644) (xy 104.861299 -346.200553)
			(xy 104.849173 -346.146116) (xy 104.845102 -346.090494) (xy 97.3074 -346.090494) (xy 97.3074 -346.855657)
			(xy 98.541219 -346.855657) (xy 98.541219 -346.801143) (xy 98.548978 -346.747184) (xy 98.564337 -346.694879)
			(xy 98.586984 -346.645292) (xy 98.616457 -346.599433) (xy 98.652158 -346.558235) (xy 98.693358 -346.522538)
			(xy 98.73922 -346.493068) (xy 98.788809 -346.470425) (xy 98.841116 -346.455071) (xy 98.895075 -346.447317)
			(xy 98.922332 -346.446856) (xy 98.948493 -346.447271) (xy 99.000326 -346.454411) (xy 99.050696 -346.468567)
			(xy 99.098661 -346.489472) (xy 99.121214 -346.502736) (xy 99.13112 -346.508832) (xy 99.153472 -346.511118)
			(xy 99.249484 -346.477844) (xy 99.265486 -346.462096) (xy 99.26955 -346.451174) (xy 99.280088 -346.424109)
			(xy 99.308219 -346.373297) (xy 99.343727 -346.327337) (xy 99.385793 -346.287291) (xy 99.433443 -346.254085)
			(xy 99.485576 -346.228486) (xy 99.540988 -346.211086) (xy 99.598396 -346.202287) (xy 99.627436 -346.201746)
			(xy 99.654682 -346.202327) (xy 99.70862 -346.210086) (xy 99.760904 -346.225443) (xy 99.81047 -346.248083)
			(xy 99.856311 -346.277547) (xy 99.897491 -346.313234) (xy 99.933175 -346.354418) (xy 99.962634 -346.400261)
			(xy 99.98527 -346.44983) (xy 100.000621 -346.502116) (xy 100.008376 -346.556054) (xy 100.008376 -346.610546)
			(xy 100.000621 -346.664484) (xy 99.98527 -346.71677) (xy 99.962634 -346.766339) (xy 99.933175 -346.812182)
			(xy 99.897491 -346.853366) (xy 99.856311 -346.889053) (xy 99.81047 -346.918517) (xy 99.760904 -346.941157)
			(xy 99.70862 -346.956514) (xy 99.654682 -346.964273) (xy 99.627436 -346.964762) (xy 99.601275 -346.964359)
			(xy 99.549442 -346.957214) (xy 99.499071 -346.943056) (xy 99.451107 -346.922147) (xy 99.428554 -346.908882)
			(xy 99.418648 -346.902786) (xy 99.396296 -346.9005) (xy 99.300284 -346.933774) (xy 99.284282 -346.949522)
			(xy 99.280218 -346.960444) (xy 99.269717 -346.987524) (xy 99.24158 -347.038337) (xy 99.206066 -347.084297)
			(xy 99.163995 -347.124341) (xy 99.11634 -347.157546) (xy 99.064202 -347.183142) (xy 99.008786 -347.200539)
			(xy 98.951373 -347.209333) (xy 98.922332 -347.209872) (xy 98.895075 -347.209483) (xy 98.841116 -347.201729)
			(xy 98.788809 -347.186375) (xy 98.73922 -347.163732) (xy 98.693358 -347.134262) (xy 98.652158 -347.098565)
			(xy 98.616457 -347.057367) (xy 98.586984 -347.011508) (xy 98.564337 -346.961921) (xy 98.548978 -346.909616)
			(xy 98.541219 -346.855657) (xy 97.3074 -346.855657) (xy 97.3074 -347.603318) (xy 97.307827 -347.613387)
			(xy 97.315546 -347.631986) (xy 97.322386 -347.639386) (xy 97.44465 -347.76165) (xy 98.47276 -347.76165)
			(xy 98.47276 -347.70715) (xy 98.480515 -347.653204) (xy 98.495869 -347.60091) (xy 98.518507 -347.551334)
			(xy 98.547971 -347.505484) (xy 98.583659 -347.464293) (xy 98.624845 -347.428599) (xy 98.670692 -347.39913)
			(xy 98.720265 -347.376486) (xy 98.772557 -347.361126) (xy 98.826502 -347.353363) (xy 98.853752 -347.352874)
			(xy 98.880655 -347.353314) (xy 98.933928 -347.360868) (xy 98.98561 -347.375834) (xy 99.034677 -347.397914)
			(xy 99.080154 -347.426671) (xy 99.121138 -347.461533) (xy 99.156817 -347.501808) (xy 99.186482 -347.546697)
			(xy 99.19843 -347.570806) (xy 99.204809 -347.583047) (xy 99.222891 -347.603882) (xy 99.245895 -347.619111)
			(xy 99.272138 -347.627621) (xy 99.299701 -347.628789) (xy 99.32657 -347.62253) (xy 99.350779 -347.609302)
			(xy 99.36099 -347.600016) (xy 99.382478 -347.579777) (xy 99.430575 -347.545557) (xy 99.483368 -347.519152)
			(xy 99.539597 -347.501192) (xy 99.597922 -347.492107) (xy 99.627436 -347.491558) (xy 99.654683 -347.492115)
			(xy 99.708622 -347.499875) (xy 99.760908 -347.515231) (xy 99.810476 -347.537873) (xy 99.856318 -347.567337)
			(xy 99.8975 -347.603026) (xy 99.933184 -347.644211) (xy 99.962645 -347.690056) (xy 99.985281 -347.739626)
			(xy 100.000633 -347.791913) (xy 100.008388 -347.845853) (xy 100.008388 -347.900347) (xy 100.000633 -347.954287)
			(xy 99.985281 -348.006574) (xy 99.962645 -348.056144) (xy 99.933184 -348.101989) (xy 99.8975 -348.143174)
			(xy 99.856318 -348.178863) (xy 99.810476 -348.208327) (xy 99.760908 -348.230969) (xy 99.708622 -348.246325)
			(xy 99.654683 -348.254085) (xy 99.627436 -348.254574) (xy 99.600534 -348.254117) (xy 99.547263 -348.246562)
			(xy 99.495582 -348.231597) (xy 99.446517 -348.209518) (xy 99.401041 -348.180764) (xy 99.360056 -348.145906)
			(xy 99.324376 -348.105634) (xy 99.294708 -348.060749) (xy 99.282758 -348.036642) (xy 99.276388 -348.024394)
			(xy 99.258307 -348.003551) (xy 99.235302 -347.988316) (xy 99.209056 -347.979804) (xy 99.181488 -347.978638)
			(xy 99.154616 -347.984903) (xy 99.130407 -347.998141) (xy 99.120198 -348.007432) (xy 99.098664 -348.02762)
			(xy 99.050581 -348.061849) (xy 98.9978 -348.088265) (xy 98.94158 -348.106236) (xy 98.883263 -348.115335)
			(xy 98.853752 -348.11589) (xy 98.826502 -348.115437) (xy 98.772557 -348.107674) (xy 98.720265 -348.092314)
			(xy 98.670692 -348.06967) (xy 98.624845 -348.040201) (xy 98.583659 -348.004507) (xy 98.547971 -347.963316)
			(xy 98.518507 -347.917466) (xy 98.495869 -347.86789) (xy 98.480515 -347.815596) (xy 98.47276 -347.76165)
			(xy 97.44465 -347.76165) (xy 99.426014 -349.743014) (xy 99.433409 -349.749868) (xy 99.452008 -349.75761)
			(xy 99.462082 -349.758) (xy 99.907598 -349.758) (xy 99.919014 -349.757537) (xy 99.939637 -349.747749)
			(xy 99.947222 -349.739204) (xy 99.965437 -349.717665) (xy 100.007131 -349.679671) (xy 100.053965 -349.648232)
			(xy 100.104919 -349.624032) (xy 100.158881 -349.607599) (xy 100.214674 -349.599292) (xy 100.271082 -349.599292)
			(xy 100.326875 -349.607599) (xy 100.380837 -349.624032) (xy 100.431791 -349.648232) (xy 100.478625 -349.679671)
			(xy 100.520319 -349.717665) (xy 100.538534 -349.739204) (xy 100.546205 -349.747634) (xy 100.566776 -349.757381)
			(xy 100.578158 -349.758) (xy 105.134918 -349.758) (xy 105.144987 -349.758427) (xy 105.163586 -349.766146)
			(xy 105.170986 -349.772986) (xy 105.395014 -349.997014) (xy 105.401868 -350.004409) (xy 105.40961 -350.023008)
			(xy 105.41 -350.033082) (xy 105.41 -353.572318) (xy 105.409573 -353.582387) (xy 105.401854 -353.600986)
			(xy 105.395014 -353.608386) (xy 104.867202 -354.136198) (xy 105.899202 -354.136198) (xy 105.903273 -354.080576)
			(xy 105.915399 -354.026139) (xy 105.935322 -353.974048) (xy 105.962618 -353.925413) (xy 105.996704 -353.88127)
			(xy 106.036853 -353.842561) (xy 106.082211 -353.81011) (xy 106.131811 -353.784609) (xy 106.184595 -353.766602)
			(xy 106.239438 -353.756472) (xy 106.295172 -353.754435) (xy 106.350609 -353.760535) (xy 106.404566 -353.774641)
			(xy 106.455895 -353.796453) (xy 106.503501 -353.825507) (xy 106.546369 -353.861182) (xy 106.583586 -353.902719)
			(xy 106.614359 -353.949232) (xy 106.638031 -353.999729) (xy 106.654099 -354.053136) (xy 106.662219 -354.108312)
			(xy 106.662728 -354.136198) (xy 106.662219 -354.164084) (xy 106.654099 -354.21926) (xy 106.638031 -354.272667)
			(xy 106.614359 -354.323164) (xy 106.583586 -354.369677) (xy 106.546369 -354.411214) (xy 106.503501 -354.446889)
			(xy 106.455895 -354.475943) (xy 106.404566 -354.497755) (xy 106.350609 -354.511861) (xy 106.295172 -354.517961)
			(xy 106.239438 -354.515924) (xy 106.184595 -354.505794) (xy 106.131811 -354.487787) (xy 106.082211 -354.462286)
			(xy 106.036853 -354.429835) (xy 105.996704 -354.391126) (xy 105.962618 -354.346983) (xy 105.935322 -354.298348)
			(xy 105.915399 -354.246257) (xy 105.903273 -354.19182) (xy 105.899202 -354.136198) (xy 104.867202 -354.136198)
			(xy 104.662986 -354.340414) (xy 104.656132 -354.347809) (xy 104.64839 -354.366408) (xy 104.648 -354.376482)
			(xy 104.648 -355.313996) (xy 106.055412 -355.313996) (xy 106.059483 -355.258374) (xy 106.071609 -355.203937)
			(xy 106.091532 -355.151846) (xy 106.118828 -355.103211) (xy 106.152914 -355.059068) (xy 106.193063 -355.020359)
			(xy 106.238421 -354.987908) (xy 106.288021 -354.962407) (xy 106.340805 -354.9444) (xy 106.395648 -354.93427)
			(xy 106.451382 -354.932233) (xy 106.506819 -354.938333) (xy 106.560776 -354.952439) (xy 106.612105 -354.974251)
			(xy 106.659711 -355.003305) (xy 106.702579 -355.03898) (xy 106.739796 -355.080517) (xy 106.770569 -355.12703)
			(xy 106.794241 -355.177527) (xy 106.810309 -355.230934) (xy 106.818429 -355.28611) (xy 106.818938 -355.313996)
			(xy 106.818429 -355.341882) (xy 106.810309 -355.397058) (xy 106.794241 -355.450465) (xy 106.770569 -355.500962)
			(xy 106.739796 -355.547475) (xy 106.702579 -355.589012) (xy 106.659711 -355.624687) (xy 106.612105 -355.653741)
			(xy 106.560776 -355.675553) (xy 106.506819 -355.689659) (xy 106.451382 -355.695759) (xy 106.395648 -355.693722)
			(xy 106.340805 -355.683592) (xy 106.288021 -355.665585) (xy 106.238421 -355.640084) (xy 106.193063 -355.607633)
			(xy 106.152914 -355.568924) (xy 106.118828 -355.524781) (xy 106.091532 -355.476146) (xy 106.071609 -355.424055)
			(xy 106.059483 -355.369618) (xy 106.055412 -355.313996) (xy 104.648 -355.313996) (xy 104.648 -360.049318)
			(xy 104.648427 -360.059387) (xy 104.656146 -360.077986) (xy 104.662986 -360.085386) (xy 105.064814 -360.487214)
			(xy 105.072209 -360.494068) (xy 105.090808 -360.50181) (xy 105.100882 -360.5022)
		)
		(stroke
			(width 0)
			(type solid)
		)
		(fill yes)
		(layer "In13.Cu")
		(net "P3V3")
	)
	(gr_poly
		(pts
			(xy 270.886682 -295.88714) (xy 271.01292 -295.88714) (xy 271.021048 -295.887394) (xy 271.828768 -295.887394)
			(xy 271.836896 -295.88714) (xy 271.96288 -295.88714) (xy 271.971008 -295.887394) (xy 272.778728 -295.887394)
			(xy 272.786856 -295.88714) (xy 273.8628 -295.88714) (xy 273.870928 -295.887394) (xy 274.678648 -295.887394)
			(xy 274.686776 -295.88714) (xy 275.76272 -295.88714) (xy 275.770848 -295.887394) (xy 276.578568 -295.887394)
			(xy 276.586696 -295.88714) (xy 276.712934 -295.88714) (xy 276.721062 -295.887394) (xy 277.528782 -295.887394)
			(xy 277.53691 -295.88714) (xy 277.662894 -295.88714) (xy 277.671022 -295.887394) (xy 278.478742 -295.887394)
			(xy 278.48687 -295.88714) (xy 278.612854 -295.88714) (xy 278.620982 -295.887394) (xy 278.62149 -295.887394)
			(xy 279.09393 -295.887394) (xy 279.103998 -295.886965) (xy 279.122594 -295.879242) (xy 279.129998 -295.872408)
			(xy 279.368504 -295.633902) (xy 279.37535 -295.626503) (xy 279.383085 -295.607906) (xy 279.38349 -295.597834)
			(xy 279.38349 -293.995094) (xy 279.383065 -293.985025) (xy 279.375348 -293.966423) (xy 279.368504 -293.959026)
			(xy 279.236932 -293.827454) (xy 279.228998 -293.820207) (xy 279.208936 -293.812566) (xy 279.187502 -293.813798)
			(xy 279.17775 -293.81831) (xy 279.177496 -293.81831) (xy 279.153783 -293.83006) (xy 279.103546 -293.846694)
			(xy 279.051302 -293.855114) (xy 279.024842 -293.855648) (xy 279.024588 -293.855648) (xy 279.001072 -293.855239)
			(xy 278.954514 -293.848579) (xy 278.909372 -293.835381) (xy 278.866559 -293.815912) (xy 278.846534 -293.803578)
			(xy 278.831548 -293.793926) (xy 278.796242 -293.797482) (xy 278.783034 -293.810436) (xy 278.775678 -293.817086)
			(xy 278.757378 -293.824673) (xy 278.747474 -293.825168) (xy 278.35225 -293.825168) (xy 278.342348 -293.824657)
			(xy 278.324043 -293.817086) (xy 278.31669 -293.810436) (xy 278.303482 -293.797482) (xy 278.268176 -293.793926)
			(xy 278.25319 -293.803578) (xy 278.233153 -293.81589) (xy 278.190338 -293.835348) (xy 278.145201 -293.848552)
			(xy 278.09865 -293.855239) (xy 278.075136 -293.855648) (xy 278.074628 -293.855648) (xy 278.051113 -293.855235)
			(xy 278.004559 -293.848567) (xy 277.959422 -293.835362) (xy 277.916614 -293.815888) (xy 277.896574 -293.803578)
			(xy 277.881588 -293.793926) (xy 277.846282 -293.797482) (xy 277.833074 -293.810436) (xy 277.825715 -293.817077)
			(xy 277.807414 -293.824642) (xy 277.797514 -293.825168) (xy 276.452076 -293.825168) (xy 276.44218 -293.824644)
			(xy 276.423894 -293.817054) (xy 276.416516 -293.810436) (xy 276.403308 -293.797482) (xy 276.368002 -293.793926)
			(xy 276.353016 -293.803578) (xy 276.332977 -293.815886) (xy 276.290161 -293.835334) (xy 276.245024 -293.848528)
			(xy 276.198475 -293.855204) (xy 276.174962 -293.855648) (xy 276.174454 -293.855648) (xy 276.150939 -293.855237)
			(xy 276.104383 -293.848572) (xy 276.059244 -293.83537) (xy 276.016434 -293.815898) (xy 275.9964 -293.803578)
			(xy 275.981414 -293.793926) (xy 275.946108 -293.797482) (xy 275.9329 -293.810436) (xy 275.925542 -293.817081)
			(xy 275.907242 -293.824655) (xy 275.89734 -293.825168) (xy 275.484844 -293.825168) (xy 275.48091 -293.8252)
			(xy 275.473127 -293.826353) (xy 275.46935 -293.827454) (xy 275.44776 -293.834566) (xy 275.44141 -293.838884)
			(xy 275.417388 -293.854811) (xy 275.365564 -293.88003) (xy 275.31054 -293.897181) (xy 275.253565 -293.905874)
			(xy 275.224748 -293.906448) (xy 275.195928 -293.905922) (xy 275.138944 -293.897243) (xy 275.08392 -293.880076)
			(xy 275.03211 -293.854814) (xy 275.008086 -293.838884) (xy 275.001736 -293.834566) (xy 274.980146 -293.827454)
			(xy 274.976366 -293.826369) (xy 274.968585 -293.82522) (xy 274.964652 -293.825168) (xy 274.552156 -293.825168)
			(xy 274.542254 -293.824658) (xy 274.523947 -293.817088) (xy 274.516596 -293.810436) (xy 274.503388 -293.797482)
			(xy 274.468082 -293.793926) (xy 274.453096 -293.803578) (xy 274.433059 -293.815891) (xy 274.390244 -293.835349)
			(xy 274.345107 -293.848554) (xy 274.298556 -293.855242) (xy 274.275042 -293.855648) (xy 274.274534 -293.855648)
			(xy 274.251019 -293.855235) (xy 274.204465 -293.848568) (xy 274.159327 -293.835364) (xy 274.116519 -293.81589)
			(xy 274.09648 -293.803578) (xy 274.081494 -293.793926) (xy 274.046188 -293.797482) (xy 274.03298 -293.810436)
			(xy 274.025621 -293.817078) (xy 274.00732 -293.824645) (xy 273.99742 -293.825168) (xy 273.602196 -293.825168)
			(xy 273.592298 -293.824647) (xy 273.574008 -293.817062) (xy 273.566636 -293.810436) (xy 273.553428 -293.797482)
			(xy 273.518122 -293.793926) (xy 273.503136 -293.803578) (xy 273.483098 -293.815887) (xy 273.440282 -293.835337)
			(xy 273.395145 -293.848535) (xy 273.348595 -293.855214) (xy 273.325082 -293.855648) (xy 273.324574 -293.855648)
			(xy 273.301058 -293.855238) (xy 273.254501 -293.848576) (xy 273.209361 -293.835377) (xy 273.166549 -293.815907)
			(xy 273.14652 -293.803578) (xy 273.131534 -293.793926) (xy 273.096228 -293.797482) (xy 273.08302 -293.810436)
			(xy 273.075663 -293.817084) (xy 273.057363 -293.824666) (xy 273.04746 -293.825168) (xy 272.652236 -293.825168)
			(xy 272.642335 -293.824654) (xy 272.624034 -293.81708) (xy 272.616676 -293.810436) (xy 272.603468 -293.797482)
			(xy 272.568162 -293.793926) (xy 272.553176 -293.803578) (xy 272.533138 -293.815889) (xy 272.490323 -293.835345)
			(xy 272.445186 -293.848548) (xy 272.398636 -293.855232) (xy 272.375122 -293.855648) (xy 272.374868 -293.855648)
			(xy 272.347124 -293.855081) (xy 272.292413 -293.845821) (xy 272.240013 -293.827567) (xy 272.191391 -293.80083)
			(xy 272.14791 -293.766358) (xy 272.110786 -293.725117) (xy 272.095468 -293.701978) (xy 272.088356 -293.693088)
			(xy 271.922748 -293.52748) (xy 271.912588 -293.51732) (xy 271.885156 -293.510462) (xy 271.771872 -293.546276)
			(xy 271.75333 -293.567358) (xy 271.75079 -293.581582) (xy 271.745908 -293.606835) (xy 271.729367 -293.655535)
			(xy 271.705486 -293.701087) (xy 271.67484 -293.742391) (xy 271.638168 -293.778453) (xy 271.596355 -293.808401)
			(xy 271.550409 -293.831515) (xy 271.501438 -293.847236) (xy 271.450624 -293.855185) (xy 271.424908 -293.855648)
			(xy 271.398919 -293.855139) (xy 271.347581 -293.84701) (xy 271.298147 -293.83095) (xy 271.251834 -293.807355)
			(xy 271.209781 -293.776806) (xy 271.173025 -293.740055) (xy 271.14247 -293.698007) (xy 271.118868 -293.651697)
			(xy 271.102801 -293.602265) (xy 271.094665 -293.550929) (xy 271.0942 -293.52494) (xy 271.094692 -293.499229)
			(xy 271.102659 -293.448427) (xy 271.11839 -293.399471) (xy 271.141507 -293.353538) (xy 271.171454 -293.311735)
			(xy 271.207509 -293.27507) (xy 271.248803 -293.244426) (xy 271.294341 -293.220541) (xy 271.343027 -293.20399)
			(xy 271.368266 -293.199058) (xy 271.38249 -293.196518) (xy 271.403572 -293.177976) (xy 271.435068 -293.078408)
			(xy 271.437459 -293.06942) (xy 271.436333 -293.050872) (xy 271.428665 -293.033945) (xy 271.422368 -293.0271)
			(xy 271.257776 -292.862508) (xy 271.253458 -292.858698) (xy 271.247108 -292.853618) (xy 271.245076 -292.852348)
			(xy 271.225791 -292.839389) (xy 271.190711 -292.808923) (xy 271.160239 -292.773847) (xy 271.147286 -292.754558)
			(xy 271.146016 -292.752526) (xy 271.140936 -292.746176) (xy 271.137126 -292.741858) (xy 270.972788 -292.57752)
			(xy 270.962628 -292.56736) (xy 270.935196 -292.560502) (xy 270.821912 -292.596316) (xy 270.80337 -292.617398)
			(xy 270.80083 -292.631622) (xy 270.795945 -292.656871) (xy 270.779399 -292.705562) (xy 270.755514 -292.751103)
			(xy 270.724865 -292.792397) (xy 270.688192 -292.828448) (xy 270.64638 -292.858386) (xy 270.600436 -292.881488)
			(xy 270.551469 -292.897199) (xy 270.500661 -292.905138) (xy 270.474948 -292.905688) (xy 270.448957 -292.905208)
			(xy 270.397614 -292.897083) (xy 270.348174 -292.881025) (xy 270.301856 -292.857429) (xy 270.259799 -292.826878)
			(xy 270.223041 -292.790122) (xy 270.192485 -292.748068) (xy 270.168886 -292.701752) (xy 270.152824 -292.652314)
			(xy 270.144694 -292.600971) (xy 270.14424 -292.57498) (xy 270.144729 -292.549266) (xy 270.15269 -292.498457)
			(xy 270.168417 -292.449492) (xy 270.19153 -292.40355) (xy 270.221474 -292.361737) (xy 270.257527 -292.325062)
			(xy 270.298821 -292.294407) (xy 270.34436 -292.27051) (xy 270.393049 -292.253947) (xy 270.418306 -292.249098)
			(xy 270.43253 -292.246558) (xy 270.453612 -292.228016) (xy 270.485108 -292.128448) (xy 270.487508 -292.119459)
			(xy 270.486393 -292.100903) (xy 270.478726 -292.083969) (xy 270.472408 -292.07714) (xy 270.307816 -291.912548)
			(xy 270.303498 -291.908738) (xy 270.297148 -291.903658) (xy 270.295116 -291.902388) (xy 270.275831 -291.889429)
			(xy 270.240752 -291.858962) (xy 270.210283 -291.823885) (xy 270.197326 -291.804598) (xy 270.196056 -291.802566)
			(xy 270.190976 -291.796216) (xy 270.187166 -291.791898) (xy 270.022574 -291.627306) (xy 270.012414 -291.617146)
			(xy 269.984982 -291.610288) (xy 269.871698 -291.646102) (xy 269.853156 -291.667184) (xy 269.850616 -291.681408)
			(xy 269.845732 -291.706657) (xy 269.829187 -291.755349) (xy 269.805302 -291.800891) (xy 269.774654 -291.842186)
			(xy 269.737981 -291.878237) (xy 269.696168 -291.908174) (xy 269.650224 -291.931276) (xy 269.601256 -291.946985)
			(xy 269.550447 -291.954922) (xy 269.524734 -291.955474) (xy 269.498744 -291.954993) (xy 269.447403 -291.946866)
			(xy 269.397966 -291.930807) (xy 269.351651 -291.90721) (xy 269.309598 -291.876658) (xy 269.272842 -291.839902)
			(xy 269.24229 -291.797849) (xy 269.218693 -291.751534) (xy 269.202634 -291.702097) (xy 269.194507 -291.650756)
			(xy 269.194026 -291.624766) (xy 269.194516 -291.599052) (xy 269.202479 -291.548244) (xy 269.218206 -291.49928)
			(xy 269.24132 -291.453339) (xy 269.271264 -291.411527) (xy 269.307317 -291.374852) (xy 269.34861 -291.344197)
			(xy 269.394148 -291.3203) (xy 269.442836 -291.303736) (xy 269.468092 -291.298884) (xy 269.482316 -291.296344)
			(xy 269.503398 -291.277802) (xy 269.534894 -291.178234) (xy 269.537292 -291.169246) (xy 269.536173 -291.150693)
			(xy 269.528501 -291.133764) (xy 269.522194 -291.126926) (xy 269.356586 -290.961318) (xy 269.347696 -290.954206)
			(xy 269.327369 -290.940818) (xy 269.290513 -290.909026) (xy 269.258715 -290.872176) (xy 269.245334 -290.851844)
			(xy 269.238222 -290.842954) (xy 269.072614 -290.677346) (xy 269.062454 -290.667186) (xy 269.035022 -290.660328)
			(xy 268.921738 -290.696142) (xy 268.903196 -290.717224) (xy 268.900656 -290.731448) (xy 268.895776 -290.756702)
			(xy 268.879238 -290.805403) (xy 268.855358 -290.850957) (xy 268.824713 -290.892263) (xy 268.78804 -290.928325)
			(xy 268.746226 -290.958273) (xy 268.700278 -290.981385) (xy 268.651306 -290.997103) (xy 268.600491 -291.005048)
			(xy 268.574774 -291.005514) (xy 268.548788 -291.005003) (xy 268.497456 -290.996869) (xy 268.448029 -290.980806)
			(xy 268.401723 -290.957208) (xy 268.359677 -290.926658) (xy 268.322929 -290.889907) (xy 268.292381 -290.84786)
			(xy 268.268787 -290.801553) (xy 268.252727 -290.752124) (xy 268.244596 -290.700792) (xy 268.244066 -290.674806)
			(xy 268.244561 -290.649096) (xy 268.252531 -290.598297) (xy 268.268265 -290.549342) (xy 268.291384 -290.503412)
			(xy 268.32133 -290.461611) (xy 268.357384 -290.424947) (xy 268.398675 -290.394303) (xy 268.444211 -290.370416)
			(xy 268.492895 -290.353863) (xy 268.518132 -290.348924) (xy 268.532356 -290.346384) (xy 268.553438 -290.327842)
			(xy 268.584934 -290.228274) (xy 268.587338 -290.219284) (xy 268.586232 -290.200722) (xy 268.578573 -290.183778)
			(xy 268.572234 -290.176966) (xy 268.406626 -290.011358) (xy 268.397736 -290.004246) (xy 268.377744 -289.991076)
			(xy 268.341418 -289.959896) (xy 268.309958 -289.923812) (xy 268.296644 -289.903916) (xy 268.295374 -289.901884)
			(xy 268.290294 -289.895534) (xy 268.286484 -289.891216) (xy 267.65377 -289.258502) (xy 267.647942 -289.252983)
			(xy 267.633699 -289.245602) (xy 267.62583 -289.244024) (xy 267.617702 -289.243516) (xy 264.376408 -289.243516)
			(xy 264.375392 -289.243516) (xy 264.363015 -289.244379) (xy 264.341326 -289.256369) (xy 264.33399 -289.266376)
			(xy 264.287254 -289.336734) (xy 264.280818 -289.347567) (xy 264.278439 -289.372619) (xy 264.282682 -289.384486)
			(xy 264.282682 -289.38474) (xy 264.292023 -289.408036) (xy 264.305208 -289.456465) (xy 264.311938 -289.506203)
			(xy 264.3124 -289.531298) (xy 264.3124 -289.536886) (xy 264.311604 -289.563923) (xy 264.303321 -289.617375)
			(xy 264.287573 -289.669121) (xy 264.264674 -289.718124) (xy 264.235083 -289.763402) (xy 264.199394 -289.804047)
			(xy 264.158323 -289.839244) (xy 264.112692 -289.868287) (xy 264.063416 -289.890594) (xy 264.011484 -289.905719)
			(xy 263.957937 -289.913357) (xy 263.930892 -289.913822) (xy 263.90208 -289.913296) (xy 263.845111 -289.904633)
			(xy 263.790091 -289.887506) (xy 263.738271 -289.862304) (xy 263.690827 -289.829599) (xy 263.648838 -289.790134)
			(xy 263.630664 -289.767772) (xy 263.620504 -289.754818) (xy 263.589516 -289.745674) (xy 263.483344 -289.78225)
			(xy 263.473559 -289.786174) (xy 263.458073 -289.800444) (xy 263.44961 -289.819727) (xy 263.449054 -289.830256)
			(xy 263.449054 -290.294314) (xy 265.820904 -290.294314) (xy 265.824975 -290.238692) (xy 265.837101 -290.184255)
			(xy 265.857024 -290.132164) (xy 265.88432 -290.083529) (xy 265.918406 -290.039386) (xy 265.958555 -290.000677)
			(xy 266.003913 -289.968226) (xy 266.053513 -289.942725) (xy 266.106297 -289.924718) (xy 266.16114 -289.914588)
			(xy 266.216874 -289.912551) (xy 266.272311 -289.918651) (xy 266.326268 -289.932757) (xy 266.377597 -289.954569)
			(xy 266.425203 -289.983623) (xy 266.468071 -290.019298) (xy 266.505288 -290.060835) (xy 266.536061 -290.107348)
			(xy 266.559733 -290.157845) (xy 266.575801 -290.211252) (xy 266.583921 -290.266428) (xy 266.58443 -290.294314)
			(xy 266.583921 -290.3222) (xy 266.575801 -290.377376) (xy 266.559733 -290.430783) (xy 266.536061 -290.48128)
			(xy 266.505288 -290.527793) (xy 266.468071 -290.56933) (xy 266.425203 -290.605005) (xy 266.377597 -290.634059)
			(xy 266.326268 -290.655871) (xy 266.272311 -290.669977) (xy 266.216874 -290.676077) (xy 266.16114 -290.67404)
			(xy 266.106297 -290.66391) (xy 266.053513 -290.645903) (xy 266.003913 -290.620402) (xy 265.958555 -290.587951)
			(xy 265.918406 -290.549242) (xy 265.88432 -290.505099) (xy 265.857024 -290.456464) (xy 265.837101 -290.404373)
			(xy 265.824975 -290.349936) (xy 265.820904 -290.294314) (xy 263.449054 -290.294314) (xy 263.449054 -291.624766)
			(xy 268.26897 -291.624766) (xy 268.27293 -291.575712) (xy 268.284707 -291.527928) (xy 268.303998 -291.482652)
			(xy 268.330301 -291.441056) (xy 268.362936 -291.404219) (xy 268.401057 -291.373094) (xy 268.443678 -291.348487)
			(xy 268.489694 -291.331035) (xy 268.537913 -291.321191) (xy 268.587088 -291.31921) (xy 268.635943 -291.325142)
			(xy 268.683214 -291.338834) (xy 268.727676 -291.359932) (xy 268.768179 -291.387888) (xy 268.803672 -291.42198)
			(xy 268.833237 -291.461324) (xy 268.856108 -291.504901) (xy 268.871692 -291.551582) (xy 268.879587 -291.600159)
			(xy 268.880082 -291.624766) (xy 268.879587 -291.649373) (xy 268.871692 -291.69795) (xy 268.856108 -291.744631)
			(xy 268.833237 -291.788208) (xy 268.803672 -291.827552) (xy 268.768179 -291.861644) (xy 268.727676 -291.8896)
			(xy 268.683214 -291.910698) (xy 268.635943 -291.92439) (xy 268.587088 -291.930322) (xy 268.537913 -291.928341)
			(xy 268.489694 -291.918497) (xy 268.443678 -291.901045) (xy 268.401057 -291.876438) (xy 268.362936 -291.845313)
			(xy 268.330301 -291.808476) (xy 268.303998 -291.76688) (xy 268.284707 -291.721604) (xy 268.27293 -291.67382)
			(xy 268.26897 -291.624766) (xy 263.449054 -291.624766) (xy 263.449054 -292.169088) (xy 263.449476 -292.179158)
			(xy 263.457194 -292.19776) (xy 263.46404 -292.205156) (xy 263.532874 -292.27399) (xy 263.540276 -292.280826)
			(xy 263.558874 -292.288535) (xy 263.568942 -292.288976) (xy 266.409678 -292.288976) (xy 266.419729 -292.289481)
			(xy 266.43829 -292.297202) (xy 266.445746 -292.303962) (xy 266.716764 -292.57498) (xy 268.26897 -292.57498)
			(xy 268.27293 -292.525926) (xy 268.284707 -292.478142) (xy 268.303998 -292.432866) (xy 268.330301 -292.39127)
			(xy 268.362936 -292.354433) (xy 268.401057 -292.323308) (xy 268.443678 -292.298701) (xy 268.489694 -292.281249)
			(xy 268.537913 -292.271405) (xy 268.587088 -292.269424) (xy 268.635943 -292.275356) (xy 268.683214 -292.289048)
			(xy 268.727676 -292.310146) (xy 268.768179 -292.338102) (xy 268.803672 -292.372194) (xy 268.833237 -292.411538)
			(xy 268.856108 -292.455115) (xy 268.871692 -292.501796) (xy 268.879587 -292.550373) (xy 268.880082 -292.57498)
			(xy 269.21893 -292.57498) (xy 269.22289 -292.525926) (xy 269.234667 -292.478142) (xy 269.253958 -292.432866)
			(xy 269.280261 -292.39127) (xy 269.312896 -292.354433) (xy 269.351017 -292.323308) (xy 269.393638 -292.298701)
			(xy 269.439654 -292.281249) (xy 269.487873 -292.271405) (xy 269.537048 -292.269424) (xy 269.585903 -292.275356)
			(xy 269.633174 -292.289048) (xy 269.677636 -292.310146) (xy 269.718139 -292.338102) (xy 269.753632 -292.372194)
			(xy 269.783197 -292.411538) (xy 269.806068 -292.455115) (xy 269.821652 -292.501796) (xy 269.829547 -292.550373)
			(xy 269.830042 -292.57498) (xy 269.829547 -292.599587) (xy 269.821652 -292.648164) (xy 269.806068 -292.694845)
			(xy 269.783197 -292.738422) (xy 269.753632 -292.777766) (xy 269.718139 -292.811858) (xy 269.677636 -292.839814)
			(xy 269.633174 -292.860912) (xy 269.585903 -292.874604) (xy 269.537048 -292.880536) (xy 269.487873 -292.878555)
			(xy 269.439654 -292.868711) (xy 269.393638 -292.851259) (xy 269.351017 -292.826652) (xy 269.312896 -292.795527)
			(xy 269.280261 -292.75869) (xy 269.253958 -292.717094) (xy 269.234667 -292.671818) (xy 269.22289 -292.624034)
			(xy 269.21893 -292.57498) (xy 268.880082 -292.57498) (xy 268.879587 -292.599587) (xy 268.871692 -292.648164)
			(xy 268.856108 -292.694845) (xy 268.833237 -292.738422) (xy 268.803672 -292.777766) (xy 268.768179 -292.811858)
			(xy 268.727676 -292.839814) (xy 268.683214 -292.860912) (xy 268.635943 -292.874604) (xy 268.587088 -292.880536)
			(xy 268.537913 -292.878555) (xy 268.489694 -292.868711) (xy 268.443678 -292.851259) (xy 268.401057 -292.826652)
			(xy 268.362936 -292.795527) (xy 268.330301 -292.75869) (xy 268.303998 -292.717094) (xy 268.284707 -292.671818)
			(xy 268.27293 -292.624034) (xy 268.26897 -292.57498) (xy 266.716764 -292.57498) (xy 267.666724 -293.52494)
			(xy 270.169144 -293.52494) (xy 270.173104 -293.475886) (xy 270.184881 -293.428102) (xy 270.204172 -293.382826)
			(xy 270.230475 -293.34123) (xy 270.26311 -293.304393) (xy 270.301231 -293.273268) (xy 270.343852 -293.248661)
			(xy 270.389868 -293.231209) (xy 270.438087 -293.221365) (xy 270.487262 -293.219384) (xy 270.536117 -293.225316)
			(xy 270.583388 -293.239008) (xy 270.62785 -293.260106) (xy 270.668353 -293.288062) (xy 270.703846 -293.322154)
			(xy 270.733411 -293.361498) (xy 270.756282 -293.405075) (xy 270.771866 -293.451756) (xy 270.779761 -293.500333)
			(xy 270.780256 -293.52494) (xy 270.779761 -293.549547) (xy 270.771866 -293.598124) (xy 270.756282 -293.644805)
			(xy 270.733411 -293.688382) (xy 270.703846 -293.727726) (xy 270.668353 -293.761818) (xy 270.62785 -293.789774)
			(xy 270.583388 -293.810872) (xy 270.536117 -293.824564) (xy 270.487262 -293.830496) (xy 270.438087 -293.828515)
			(xy 270.389868 -293.818671) (xy 270.343852 -293.801219) (xy 270.301231 -293.776612) (xy 270.26311 -293.745487)
			(xy 270.230475 -293.70865) (xy 270.204172 -293.667054) (xy 270.184881 -293.621778) (xy 270.173104 -293.573994)
			(xy 270.169144 -293.52494) (xy 267.666724 -293.52494) (xy 268.33195 -294.190166) (xy 268.340506 -294.198005)
			(xy 268.362398 -294.205631) (xy 268.385411 -294.202847) (xy 268.39545 -294.197024) (xy 268.415586 -294.184515)
			(xy 268.45868 -294.164765) (xy 268.504153 -294.151372) (xy 268.551072 -294.144612) (xy 268.574774 -294.144192)
			(xy 268.600765 -294.144673) (xy 268.652106 -294.152801) (xy 268.701544 -294.168861) (xy 268.747861 -294.192458)
			(xy 268.789916 -294.223009) (xy 268.826674 -294.259764) (xy 268.857229 -294.301817) (xy 268.880829 -294.348132)
			(xy 268.896893 -294.397568) (xy 268.905025 -294.448909) (xy 268.905482 -294.4749) (xy 269.21893 -294.4749)
			(xy 269.22289 -294.425846) (xy 269.234667 -294.378062) (xy 269.253958 -294.332786) (xy 269.280261 -294.29119)
			(xy 269.312896 -294.254353) (xy 269.351017 -294.223228) (xy 269.393638 -294.198621) (xy 269.439654 -294.181169)
			(xy 269.487873 -294.171325) (xy 269.537048 -294.169344) (xy 269.585903 -294.175276) (xy 269.633174 -294.188968)
			(xy 269.677636 -294.210066) (xy 269.718139 -294.238022) (xy 269.753632 -294.272114) (xy 269.783197 -294.311458)
			(xy 269.806068 -294.355035) (xy 269.821652 -294.401716) (xy 269.829547 -294.450293) (xy 269.830042 -294.4749)
			(xy 270.169144 -294.4749) (xy 270.173104 -294.425846) (xy 270.184881 -294.378062) (xy 270.204172 -294.332786)
			(xy 270.230475 -294.29119) (xy 270.26311 -294.254353) (xy 270.301231 -294.223228) (xy 270.343852 -294.198621)
			(xy 270.389868 -294.181169) (xy 270.438087 -294.171325) (xy 270.487262 -294.169344) (xy 270.536117 -294.175276)
			(xy 270.583388 -294.188968) (xy 270.62785 -294.210066) (xy 270.668353 -294.238022) (xy 270.703846 -294.272114)
			(xy 270.733411 -294.311458) (xy 270.756282 -294.355035) (xy 270.771866 -294.401716) (xy 270.779761 -294.450293)
			(xy 270.780256 -294.4749) (xy 273.019024 -294.4749) (xy 273.022984 -294.425846) (xy 273.034761 -294.378062)
			(xy 273.054052 -294.332786) (xy 273.080355 -294.29119) (xy 273.11299 -294.254353) (xy 273.151111 -294.223228)
			(xy 273.193732 -294.198621) (xy 273.239748 -294.181169) (xy 273.287967 -294.171325) (xy 273.337142 -294.169344)
			(xy 273.385997 -294.175276) (xy 273.433268 -294.188968) (xy 273.47773 -294.210066) (xy 273.518233 -294.238022)
			(xy 273.553726 -294.272114) (xy 273.583291 -294.311458) (xy 273.606162 -294.355035) (xy 273.621746 -294.401716)
			(xy 273.629641 -294.450293) (xy 273.630136 -294.4749) (xy 273.629641 -294.499507) (xy 273.629309 -294.501549)
			(xy 273.919178 -294.501549) (xy 273.919178 -294.448251) (xy 273.927121 -294.395547) (xy 273.942831 -294.344617)
			(xy 273.965957 -294.296596) (xy 273.995981 -294.252559) (xy 274.032233 -294.213488) (xy 274.073904 -294.180257)
			(xy 274.120062 -294.153608) (xy 274.169676 -294.134136) (xy 274.221638 -294.122276) (xy 274.274788 -294.118293)
			(xy 274.327938 -294.122276) (xy 274.3799 -294.134136) (xy 274.429514 -294.153608) (xy 274.475672 -294.180257)
			(xy 274.517343 -294.213488) (xy 274.553595 -294.252559) (xy 274.583619 -294.296596) (xy 274.606745 -294.344617)
			(xy 274.622455 -294.395547) (xy 274.630398 -294.448251) (xy 274.630896 -294.4749) (xy 274.918944 -294.4749)
			(xy 274.922904 -294.425846) (xy 274.934681 -294.378062) (xy 274.953972 -294.332786) (xy 274.980275 -294.29119)
			(xy 275.01291 -294.254353) (xy 275.051031 -294.223228) (xy 275.093652 -294.198621) (xy 275.139668 -294.181169)
			(xy 275.187887 -294.171325) (xy 275.237062 -294.169344) (xy 275.285917 -294.175276) (xy 275.333188 -294.188968)
			(xy 275.37765 -294.210066) (xy 275.418153 -294.238022) (xy 275.453646 -294.272114) (xy 275.483211 -294.311458)
			(xy 275.506082 -294.355035) (xy 275.521666 -294.401716) (xy 275.529561 -294.450293) (xy 275.530056 -294.4749)
			(xy 275.868904 -294.4749) (xy 275.872864 -294.425846) (xy 275.884641 -294.378062) (xy 275.903932 -294.332786)
			(xy 275.930235 -294.29119) (xy 275.96287 -294.254353) (xy 276.000991 -294.223228) (xy 276.043612 -294.198621)
			(xy 276.089628 -294.181169) (xy 276.137847 -294.171325) (xy 276.187022 -294.169344) (xy 276.235877 -294.175276)
			(xy 276.283148 -294.188968) (xy 276.32761 -294.210066) (xy 276.368113 -294.238022) (xy 276.403606 -294.272114)
			(xy 276.433171 -294.311458) (xy 276.456042 -294.355035) (xy 276.471626 -294.401716) (xy 276.479521 -294.450293)
			(xy 276.480016 -294.4749) (xy 276.819118 -294.4749) (xy 276.823078 -294.425846) (xy 276.834855 -294.378062)
			(xy 276.854146 -294.332786) (xy 276.880449 -294.29119) (xy 276.913084 -294.254353) (xy 276.951205 -294.223228)
			(xy 276.993826 -294.198621) (xy 277.039842 -294.181169) (xy 277.088061 -294.171325) (xy 277.137236 -294.169344)
			(xy 277.186091 -294.175276) (xy 277.233362 -294.188968) (xy 277.277824 -294.210066) (xy 277.318327 -294.238022)
			(xy 277.35382 -294.272114) (xy 277.383385 -294.311458) (xy 277.406256 -294.355035) (xy 277.42184 -294.401716)
			(xy 277.429735 -294.450293) (xy 277.43023 -294.4749) (xy 277.769078 -294.4749) (xy 277.773038 -294.425846)
			(xy 277.784815 -294.378062) (xy 277.804106 -294.332786) (xy 277.830409 -294.29119) (xy 277.863044 -294.254353)
			(xy 277.901165 -294.223228) (xy 277.943786 -294.198621) (xy 277.989802 -294.181169) (xy 278.038021 -294.171325)
			(xy 278.087196 -294.169344) (xy 278.136051 -294.175276) (xy 278.183322 -294.188968) (xy 278.227784 -294.210066)
			(xy 278.268287 -294.238022) (xy 278.30378 -294.272114) (xy 278.333345 -294.311458) (xy 278.356216 -294.355035)
			(xy 278.3718 -294.401716) (xy 278.379695 -294.450293) (xy 278.38019 -294.4749) (xy 278.379695 -294.499507)
			(xy 278.3718 -294.548084) (xy 278.356216 -294.594765) (xy 278.333345 -294.638342) (xy 278.30378 -294.677686)
			(xy 278.268287 -294.711778) (xy 278.227784 -294.739734) (xy 278.183322 -294.760832) (xy 278.136051 -294.774524)
			(xy 278.087196 -294.780456) (xy 278.038021 -294.778475) (xy 277.989802 -294.768631) (xy 277.943786 -294.751179)
			(xy 277.901165 -294.726572) (xy 277.863044 -294.695447) (xy 277.830409 -294.65861) (xy 277.804106 -294.617014)
			(xy 277.784815 -294.571738) (xy 277.773038 -294.523954) (xy 277.769078 -294.4749) (xy 277.43023 -294.4749)
			(xy 277.429735 -294.499507) (xy 277.42184 -294.548084) (xy 277.406256 -294.594765) (xy 277.383385 -294.638342)
			(xy 277.35382 -294.677686) (xy 277.318327 -294.711778) (xy 277.277824 -294.739734) (xy 277.233362 -294.760832)
			(xy 277.186091 -294.774524) (xy 277.137236 -294.780456) (xy 277.088061 -294.778475) (xy 277.039842 -294.768631)
			(xy 276.993826 -294.751179) (xy 276.951205 -294.726572) (xy 276.913084 -294.695447) (xy 276.880449 -294.65861)
			(xy 276.854146 -294.617014) (xy 276.834855 -294.571738) (xy 276.823078 -294.523954) (xy 276.819118 -294.4749)
			(xy 276.480016 -294.4749) (xy 276.479521 -294.499507) (xy 276.471626 -294.548084) (xy 276.456042 -294.594765)
			(xy 276.433171 -294.638342) (xy 276.403606 -294.677686) (xy 276.368113 -294.711778) (xy 276.32761 -294.739734)
			(xy 276.283148 -294.760832) (xy 276.235877 -294.774524) (xy 276.187022 -294.780456) (xy 276.137847 -294.778475)
			(xy 276.089628 -294.768631) (xy 276.043612 -294.751179) (xy 276.000991 -294.726572) (xy 275.96287 -294.695447)
			(xy 275.930235 -294.65861) (xy 275.903932 -294.617014) (xy 275.884641 -294.571738) (xy 275.872864 -294.523954)
			(xy 275.868904 -294.4749) (xy 275.530056 -294.4749) (xy 275.529561 -294.499507) (xy 275.521666 -294.548084)
			(xy 275.506082 -294.594765) (xy 275.483211 -294.638342) (xy 275.453646 -294.677686) (xy 275.418153 -294.711778)
			(xy 275.37765 -294.739734) (xy 275.333188 -294.760832) (xy 275.285917 -294.774524) (xy 275.237062 -294.780456)
			(xy 275.187887 -294.778475) (xy 275.139668 -294.768631) (xy 275.093652 -294.751179) (xy 275.051031 -294.726572)
			(xy 275.01291 -294.695447) (xy 274.980275 -294.65861) (xy 274.953972 -294.617014) (xy 274.934681 -294.571738)
			(xy 274.922904 -294.523954) (xy 274.918944 -294.4749) (xy 274.630896 -294.4749) (xy 274.630398 -294.501549)
			(xy 274.622455 -294.554253) (xy 274.606745 -294.605183) (xy 274.583619 -294.653204) (xy 274.553595 -294.697241)
			(xy 274.517343 -294.736312) (xy 274.475672 -294.769543) (xy 274.429514 -294.796192) (xy 274.3799 -294.815664)
			(xy 274.327938 -294.827524) (xy 274.274788 -294.831508) (xy 274.221638 -294.827524) (xy 274.169676 -294.815664)
			(xy 274.120062 -294.796192) (xy 274.073904 -294.769543) (xy 274.032233 -294.736312) (xy 273.995981 -294.697241)
			(xy 273.965957 -294.653204) (xy 273.942831 -294.605183) (xy 273.927121 -294.554253) (xy 273.919178 -294.501549)
			(xy 273.629309 -294.501549) (xy 273.621746 -294.548084) (xy 273.606162 -294.594765) (xy 273.583291 -294.638342)
			(xy 273.553726 -294.677686) (xy 273.518233 -294.711778) (xy 273.47773 -294.739734) (xy 273.433268 -294.760832)
			(xy 273.385997 -294.774524) (xy 273.337142 -294.780456) (xy 273.287967 -294.778475) (xy 273.239748 -294.768631)
			(xy 273.193732 -294.751179) (xy 273.151111 -294.726572) (xy 273.11299 -294.695447) (xy 273.080355 -294.65861)
			(xy 273.054052 -294.617014) (xy 273.034761 -294.571738) (xy 273.022984 -294.523954) (xy 273.019024 -294.4749)
			(xy 270.780256 -294.4749) (xy 270.779761 -294.499507) (xy 270.771866 -294.548084) (xy 270.756282 -294.594765)
			(xy 270.733411 -294.638342) (xy 270.703846 -294.677686) (xy 270.668353 -294.711778) (xy 270.62785 -294.739734)
			(xy 270.583388 -294.760832) (xy 270.536117 -294.774524) (xy 270.487262 -294.780456) (xy 270.438087 -294.778475)
			(xy 270.389868 -294.768631) (xy 270.343852 -294.751179) (xy 270.301231 -294.726572) (xy 270.26311 -294.695447)
			(xy 270.230475 -294.65861) (xy 270.204172 -294.617014) (xy 270.184881 -294.571738) (xy 270.173104 -294.523954)
			(xy 270.169144 -294.4749) (xy 269.830042 -294.4749) (xy 269.829547 -294.499507) (xy 269.821652 -294.548084)
			(xy 269.806068 -294.594765) (xy 269.783197 -294.638342) (xy 269.753632 -294.677686) (xy 269.718139 -294.711778)
			(xy 269.677636 -294.739734) (xy 269.633174 -294.760832) (xy 269.585903 -294.774524) (xy 269.537048 -294.780456)
			(xy 269.487873 -294.778475) (xy 269.439654 -294.768631) (xy 269.393638 -294.751179) (xy 269.351017 -294.726572)
			(xy 269.312896 -294.695447) (xy 269.280261 -294.65861) (xy 269.253958 -294.617014) (xy 269.234667 -294.571738)
			(xy 269.22289 -294.523954) (xy 269.21893 -294.4749) (xy 268.905482 -294.4749) (xy 268.905075 -294.498602)
			(xy 268.898308 -294.545522) (xy 268.884912 -294.590995) (xy 268.865162 -294.634089) (xy 268.85265 -294.654224)
			(xy 268.846874 -294.664271) (xy 268.84415 -294.687261) (xy 268.851724 -294.709139) (xy 268.859508 -294.717724)
			(xy 269.722346 -295.580562) (xy 269.727939 -295.586561) (xy 269.73531 -295.601202) (xy 269.736824 -295.609264)
			(xy 269.738094 -295.617392) (xy 269.74546 -295.632124) (xy 269.985744 -295.872408) (xy 269.993151 -295.8791)
			(xy 270.011587 -295.886701) (xy 270.021558 -295.88714) (xy 270.062706 -295.88714) (xy 270.070834 -295.887394)
			(xy 270.878554 -295.887394)
		)
		(stroke
			(width 0)
			(type solid)
		)
		(fill yes)
		(layer "In13.Cu")
		(net "PCEPLL4_VDDA18_PEX2")
	)
	(gr_poly
		(pts
			(xy 18.90014 -278.470868) (xy 18.910206 -278.470437) (xy 18.928797 -278.462709) (xy 18.936208 -278.455882)
			(xy 19.267932 -278.124158) (xy 19.271742 -278.114252) (xy 19.285064 -278.082345) (xy 19.319098 -278.022156)
			(xy 19.360972 -277.967133) (xy 19.385026 -277.942294) (xy 19.677634 -277.649432) (xy 19.684441 -277.642086)
			(xy 19.692159 -277.623623) (xy 19.69262 -277.613618) (xy 19.69262 -244.296692) (xy 19.693045 -244.286623)
			(xy 19.700764 -244.268022) (xy 19.707606 -244.260624) (xy 21.263102 -242.705128) (xy 21.270499 -242.698279)
			(xy 21.289098 -242.690541) (xy 21.29917 -242.690142) (xy 93.671644 -242.690142) (xy 93.681723 -242.689714)
			(xy 93.700321 -242.68194) (xy 93.714467 -242.66758) (xy 93.718634 -242.658392) (xy 93.759782 -242.55603)
			(xy 93.753178 -242.526058) (xy 93.741748 -242.515136) (xy 93.723507 -242.497071) (xy 93.691542 -242.456897)
			(xy 93.665249 -242.412803) (xy 93.645101 -242.365583) (xy 93.631461 -242.31609) (xy 93.624577 -242.265215)
			(xy 93.624146 -242.239546) (xy 93.624632 -242.212295) (xy 93.632388 -242.158347) (xy 93.647743 -242.106052)
			(xy 93.670385 -242.056475) (xy 93.699851 -242.010625) (xy 93.735542 -241.969434) (xy 93.776733 -241.933743)
			(xy 93.822583 -241.904277) (xy 93.87216 -241.881635) (xy 93.924455 -241.86628) (xy 93.978403 -241.858524)
			(xy 94.032905 -241.858524) (xy 94.086853 -241.86628) (xy 94.139148 -241.881635) (xy 94.188725 -241.904277)
			(xy 94.234575 -241.933743) (xy 94.275766 -241.969434) (xy 94.311457 -242.010625) (xy 94.340923 -242.056475)
			(xy 94.363565 -242.106052) (xy 94.37892 -242.158347) (xy 94.386676 -242.212295) (xy 94.387162 -242.239546)
			(xy 94.386748 -242.265217) (xy 94.379872 -242.316097) (xy 94.366238 -242.365596) (xy 94.34609 -242.41282)
			(xy 94.319793 -242.456916) (xy 94.287822 -242.49709) (xy 94.26956 -242.515136) (xy 94.25813 -242.526058)
			(xy 94.251526 -242.55603) (xy 94.292674 -242.658392) (xy 94.29686 -242.667565) (xy 94.31102 -242.681896)
			(xy 94.329592 -242.689705) (xy 94.339664 -242.690142) (xy 96.07169 -242.690142) (xy 96.079797 -242.689843)
			(xy 96.095205 -242.684793) (xy 96.101916 -242.680236) (xy 96.12665 -242.662717) (xy 96.180504 -242.63491)
			(xy 96.238079 -242.615975) (xy 96.297925 -242.606388) (xy 96.32823 -242.605814) (xy 96.355298 -242.60629)
			(xy 96.408889 -242.613949) (xy 96.460859 -242.62911) (xy 96.48571 -242.63985) (xy 96.500442 -242.646454)
			(xy 96.531176 -242.640866) (xy 97.109788 -242.062254) (xy 97.116629 -242.054854) (xy 97.124348 -242.036255)
			(xy 97.124774 -242.026186) (xy 97.124774 -240.011458) (xy 97.124343 -240.001392) (xy 97.116615 -239.982801)
			(xy 97.109788 -239.97539) (xy 94.96933 -237.834932) (xy 94.933262 -237.831376) (xy 94.918022 -237.841536)
			(xy 94.890121 -237.859372) (xy 94.829582 -237.886194) (xy 94.797626 -237.894876) (xy 94.788482 -237.897162)
			(xy 94.773496 -237.907322) (xy 94.724474 -237.977426) (xy 94.719902 -237.994952) (xy 94.720918 -238.00435)
			(xy 94.721961 -238.014478) (xy 94.723105 -238.034809) (xy 94.723204 -238.04499) (xy 94.722741 -238.072243)
			(xy 94.714986 -238.126195) (xy 94.69963 -238.178494) (xy 94.676988 -238.228075) (xy 94.647521 -238.273929)
			(xy 94.611827 -238.315123) (xy 94.570634 -238.350817) (xy 94.52478 -238.380285) (xy 94.475199 -238.402928)
			(xy 94.422901 -238.418284) (xy 94.368949 -238.426041) (xy 94.341696 -238.426498) (xy 94.309651 -238.425867)
			(xy 94.246455 -238.41521) (xy 94.185927 -238.394145) (xy 94.157546 -238.379254) (xy 94.149418 -238.374682)
			(xy 94.13113 -238.372142) (xy 94.047056 -238.390938) (xy 94.031816 -238.401098) (xy 94.026228 -238.408718)
			(xy 94.010796 -238.429375) (xy 93.975266 -238.466742) (xy 93.935026 -238.498982) (xy 93.89081 -238.525508)
			(xy 93.843423 -238.545836) (xy 93.793731 -238.559595) (xy 93.742637 -238.566535) (xy 93.716856 -238.56696)
			(xy 93.68961 -238.566471) (xy 93.635674 -238.55871) (xy 93.583391 -238.543353) (xy 93.533826 -238.520712)
			(xy 93.487987 -238.491249) (xy 93.446807 -238.455562) (xy 93.411125 -238.414378) (xy 93.381666 -238.368535)
			(xy 93.359031 -238.318967) (xy 93.34368 -238.266683) (xy 93.335926 -238.212746) (xy 93.335926 -238.158254)
			(xy 93.34368 -238.104317) (xy 93.359031 -238.052033) (xy 93.381666 -238.002465) (xy 93.411125 -237.956622)
			(xy 93.446807 -237.915438) (xy 93.487987 -237.879751) (xy 93.533826 -237.850288) (xy 93.583391 -237.827647)
			(xy 93.635674 -237.81229) (xy 93.68961 -237.804529) (xy 93.716856 -237.803944) (xy 93.7489 -237.804579)
			(xy 93.812092 -237.815245) (xy 93.872614 -237.836319) (xy 93.901006 -237.851188) (xy 93.909134 -237.85576)
			(xy 93.927422 -237.8583) (xy 94.011496 -237.839504) (xy 94.026736 -237.829344) (xy 94.032324 -237.821724)
			(xy 94.048393 -237.80023) (xy 94.085579 -237.761536) (xy 94.127822 -237.728437) (xy 94.174286 -237.701585)
			(xy 94.224055 -237.68151) (xy 94.250002 -237.674658) (xy 94.259146 -237.672372) (xy 94.274132 -237.662212)
			(xy 94.323154 -237.592108) (xy 94.327726 -237.574582) (xy 94.32671 -237.565184) (xy 94.325666 -237.555056)
			(xy 94.32452 -237.534725) (xy 94.324424 -237.524544) (xy 94.324424 -237.51159) (xy 94.316804 -237.492794)
			(xy 94.258892 -237.434374) (xy 94.251497 -237.427521) (xy 94.232898 -237.419778) (xy 94.222824 -237.419388)
			(xy 93.561154 -237.419388) (xy 93.533468 -237.441486) (xy 93.529658 -237.459012) (xy 93.523267 -237.48539)
			(xy 93.504031 -237.536141) (xy 93.477798 -237.583655) (xy 93.445098 -237.626971) (xy 93.406589 -237.665217)
			(xy 93.363049 -237.697621) (xy 93.315357 -237.723528) (xy 93.264476 -237.742415) (xy 93.211431 -237.753903)
			(xy 93.157294 -237.757758) (xy 93.103157 -237.753903) (xy 93.050112 -237.742415) (xy 92.999231 -237.723528)
			(xy 92.951539 -237.697621) (xy 92.907999 -237.665217) (xy 92.86949 -237.626971) (xy 92.83679 -237.583655)
			(xy 92.810557 -237.536141) (xy 92.791321 -237.48539) (xy 92.78493 -237.459012) (xy 92.78112 -237.441486)
			(xy 92.753434 -237.419388) (xy 71.148194 -237.419388) (xy 71.13826 -237.419865) (xy 71.119888 -237.427429)
			(xy 71.105778 -237.441417) (xy 71.101458 -237.450376) (xy 71.058786 -237.550198) (xy 71.064374 -237.580424)
			(xy 71.075042 -237.591346) (xy 71.094843 -237.6128) (xy 71.128359 -237.660602) (xy 71.154208 -237.712948)
			(xy 71.171787 -237.768618) (xy 71.180688 -237.826316) (xy 71.181214 -237.855506) (xy 71.180728 -237.882757)
			(xy 71.172972 -237.936705) (xy 71.157617 -237.989) (xy 71.134975 -238.038577) (xy 71.105509 -238.084427)
			(xy 71.069818 -238.125618) (xy 71.028627 -238.161309) (xy 70.982777 -238.190775) (xy 70.9332 -238.213417)
			(xy 70.880905 -238.228772) (xy 70.826957 -238.236528) (xy 70.772455 -238.236528) (xy 70.718507 -238.228772)
			(xy 70.666212 -238.213417) (xy 70.616635 -238.190775) (xy 70.570785 -238.161309) (xy 70.529594 -238.125618)
			(xy 70.493903 -238.084427) (xy 70.464437 -238.038577) (xy 70.441795 -237.989) (xy 70.42644 -237.936705)
			(xy 70.418684 -237.882757) (xy 70.418198 -237.855506) (xy 70.418752 -237.826317) (xy 70.427641 -237.768618)
			(xy 70.445212 -237.712947) (xy 70.471055 -237.6606) (xy 70.504568 -237.612798) (xy 70.52437 -237.591346)
			(xy 70.535038 -237.580424) (xy 70.540626 -237.550198) (xy 70.497954 -237.450376) (xy 70.493635 -237.44142)
			(xy 70.479512 -237.427451) (xy 70.461149 -237.419879) (xy 70.451218 -237.419388) (xy 17.914112 -237.419388)
			(xy 17.904041 -237.419808) (xy 17.885432 -237.427518) (xy 17.878044 -237.434374) (xy 16.451072 -238.861346)
			(xy 16.444225 -238.868743) (xy 16.436496 -238.887343) (xy 16.436086 -238.897414) (xy 16.436086 -240.318036)
			(xy 19.174206 -240.318036) (xy 19.174692 -240.290785) (xy 19.182448 -240.236837) (xy 19.197803 -240.184542)
			(xy 19.220445 -240.134965) (xy 19.249911 -240.089115) (xy 19.285602 -240.047924) (xy 19.326793 -240.012233)
			(xy 19.372643 -239.982767) (xy 19.42222 -239.960125) (xy 19.474515 -239.94477) (xy 19.528463 -239.937014)
			(xy 19.582965 -239.937014) (xy 19.636913 -239.94477) (xy 19.689208 -239.960125) (xy 19.738785 -239.982767)
			(xy 19.784635 -240.012233) (xy 19.825826 -240.047924) (xy 19.861517 -240.089115) (xy 19.890983 -240.134965)
			(xy 19.913625 -240.184542) (xy 19.92898 -240.236837) (xy 19.936736 -240.290785) (xy 19.936986 -240.304828)
			(xy 20.088604 -240.304828) (xy 20.092675 -240.249206) (xy 20.104801 -240.194769) (xy 20.124724 -240.142678)
			(xy 20.15202 -240.094043) (xy 20.186106 -240.0499) (xy 20.226255 -240.011191) (xy 20.271613 -239.97874)
			(xy 20.321213 -239.953239) (xy 20.373997 -239.935232) (xy 20.42884 -239.925102) (xy 20.484574 -239.923065)
			(xy 20.540011 -239.929165) (xy 20.593968 -239.943271) (xy 20.645297 -239.965083) (xy 20.692903 -239.994137)
			(xy 20.735771 -240.029812) (xy 20.772988 -240.071349) (xy 20.803761 -240.117862) (xy 20.827433 -240.168359)
			(xy 20.843501 -240.221766) (xy 20.851621 -240.276942) (xy 20.85213 -240.304828) (xy 20.851621 -240.332714)
			(xy 20.843501 -240.38789) (xy 20.836548 -240.411) (xy 68.223382 -240.411) (xy 68.227453 -240.355378)
			(xy 68.239579 -240.300941) (xy 68.259502 -240.24885) (xy 68.286798 -240.200215) (xy 68.320884 -240.156072)
			(xy 68.361033 -240.117363) (xy 68.406391 -240.084912) (xy 68.455991 -240.059411) (xy 68.508775 -240.041404)
			(xy 68.563618 -240.031274) (xy 68.619352 -240.029237) (xy 68.674789 -240.035337) (xy 68.728746 -240.049443)
			(xy 68.780075 -240.071255) (xy 68.827681 -240.100309) (xy 68.870549 -240.135984) (xy 68.907766 -240.177521)
			(xy 68.938539 -240.224034) (xy 68.962211 -240.274531) (xy 68.978279 -240.327938) (xy 68.986399 -240.383114)
			(xy 68.986908 -240.411) (xy 68.986399 -240.438886) (xy 68.978279 -240.494062) (xy 68.975529 -240.503202)
			(xy 92.046804 -240.503202) (xy 92.050875 -240.44758) (xy 92.063001 -240.393143) (xy 92.082924 -240.341052)
			(xy 92.11022 -240.292417) (xy 92.144306 -240.248274) (xy 92.184455 -240.209565) (xy 92.229813 -240.177114)
			(xy 92.279413 -240.151613) (xy 92.332197 -240.133606) (xy 92.38704 -240.123476) (xy 92.442774 -240.121439)
			(xy 92.498211 -240.127539) (xy 92.552168 -240.141645) (xy 92.603497 -240.163457) (xy 92.651103 -240.192511)
			(xy 92.693971 -240.228186) (xy 92.731188 -240.269723) (xy 92.754395 -240.3048) (xy 93.040781 -240.3048)
			(xy 93.044665 -240.248018) (xy 93.056245 -240.192294) (xy 93.075303 -240.138665) (xy 93.101487 -240.088131)
			(xy 93.134307 -240.041633) (xy 93.173154 -240.000036) (xy 93.217302 -239.964117) (xy 93.26593 -239.934543)
			(xy 93.318131 -239.911866) (xy 93.372935 -239.896508) (xy 93.429319 -239.888755) (xy 93.457776 -239.888268)
			(xy 93.477645 -239.888447) (xy 93.51721 -239.89214) (xy 93.53677 -239.895634) (xy 93.548962 -239.898174)
			(xy 93.57233 -239.891316) (xy 93.650308 -239.817148) (xy 93.658436 -239.794034) (xy 93.656658 -239.781588)
			(xy 93.654888 -239.768324) (xy 93.652984 -239.741629) (xy 93.652848 -239.728248) (xy 93.653304 -239.70099)
			(xy 93.661056 -239.647029) (xy 93.676409 -239.59472) (xy 93.69905 -239.545129) (xy 93.728519 -239.499265)
			(xy 93.764215 -239.458061) (xy 93.805412 -239.422358) (xy 93.851271 -239.392881) (xy 93.900859 -239.370231)
			(xy 93.953165 -239.354869) (xy 94.007125 -239.347108) (xy 94.06164 -239.347106) (xy 94.115601 -239.354862)
			(xy 94.167909 -239.370219) (xy 94.217498 -239.392865) (xy 94.26336 -239.422337) (xy 94.30456 -239.458037)
			(xy 94.34026 -239.499237) (xy 94.369733 -239.545098) (xy 94.392379 -239.594687) (xy 94.407737 -239.646995)
			(xy 94.415494 -239.700956) (xy 94.415492 -239.755471) (xy 94.407731 -239.809431) (xy 94.39237 -239.861738)
			(xy 94.369721 -239.911325) (xy 94.340244 -239.957185) (xy 94.304542 -239.998382) (xy 94.263339 -240.034079)
			(xy 94.217475 -240.063548) (xy 94.167884 -240.08619) (xy 94.115575 -240.101544) (xy 94.061614 -240.109296)
			(xy 94.034356 -240.109756) (xy 94.020975 -240.10963) (xy 93.99428 -240.107722) (xy 93.981016 -240.105946)
			(xy 93.96857 -240.104168) (xy 93.945456 -240.112296) (xy 93.871288 -240.190274) (xy 93.86443 -240.213642)
			(xy 93.86697 -240.225834) (xy 93.869141 -240.237495) (xy 93.872318 -240.261005) (xy 93.87332 -240.272824)
			(xy 93.874082 -240.283238) (xy 93.88348 -240.301526) (xy 93.956886 -240.361216) (xy 93.976698 -240.367058)
			(xy 93.987112 -240.365788) (xy 93.998874 -240.36439) (xy 94.022512 -240.362866) (xy 94.034356 -240.36274)
			(xy 94.061614 -240.363104) (xy 94.115577 -240.370857) (xy 94.167887 -240.386211) (xy 94.217479 -240.408854)
			(xy 94.263343 -240.438324) (xy 94.304546 -240.474023) (xy 94.340249 -240.515222) (xy 94.369725 -240.561083)
			(xy 94.392374 -240.610672) (xy 94.407734 -240.66298) (xy 94.415493 -240.716942) (xy 94.415493 -240.771458)
			(xy 94.407734 -240.82542) (xy 94.392374 -240.877728) (xy 94.369725 -240.927317) (xy 94.340249 -240.973178)
			(xy 94.304546 -241.014377) (xy 94.263343 -241.050076) (xy 94.217479 -241.079546) (xy 94.167887 -241.102189)
			(xy 94.115577 -241.117543) (xy 94.061614 -241.125296) (xy 94.034356 -241.125756) (xy 94.007143 -241.125181)
			(xy 93.953272 -241.117427) (xy 93.90105 -241.102098) (xy 93.851535 -241.079503) (xy 93.805734 -241.050102)
			(xy 93.764574 -241.014491) (xy 93.728893 -240.973394) (xy 93.699413 -240.927643) (xy 93.676733 -240.878167)
			(xy 93.661313 -240.825971) (xy 93.656912 -240.799112) (xy 93.655388 -240.788698) (xy 93.644466 -240.771172)
			(xy 93.567504 -240.716308) (xy 93.547438 -240.71199) (xy 93.537024 -240.714022) (xy 93.517402 -240.717531)
			(xy 93.477709 -240.721217) (xy 93.457776 -240.721388) (xy 93.429319 -240.720845) (xy 93.372935 -240.713092)
			(xy 93.318131 -240.697734) (xy 93.26593 -240.675057) (xy 93.217302 -240.645483) (xy 93.173154 -240.609564)
			(xy 93.134307 -240.567967) (xy 93.101487 -240.521469) (xy 93.075303 -240.470935) (xy 93.056245 -240.417306)
			(xy 93.044665 -240.361582) (xy 93.040781 -240.3048) (xy 92.754395 -240.3048) (xy 92.761961 -240.316236)
			(xy 92.785633 -240.366733) (xy 92.801701 -240.42014) (xy 92.809821 -240.475316) (xy 92.81033 -240.503202)
			(xy 92.809821 -240.531088) (xy 92.801701 -240.586264) (xy 92.785633 -240.639671) (xy 92.761961 -240.690168)
			(xy 92.731188 -240.736681) (xy 92.693971 -240.778218) (xy 92.651103 -240.813893) (xy 92.603497 -240.842947)
			(xy 92.552168 -240.864759) (xy 92.498211 -240.878865) (xy 92.442774 -240.884965) (xy 92.38704 -240.882928)
			(xy 92.332197 -240.872798) (xy 92.279413 -240.854791) (xy 92.229813 -240.82929) (xy 92.184455 -240.796839)
			(xy 92.144306 -240.75813) (xy 92.11022 -240.713987) (xy 92.082924 -240.665352) (xy 92.063001 -240.613261)
			(xy 92.050875 -240.558824) (xy 92.046804 -240.503202) (xy 68.975529 -240.503202) (xy 68.962211 -240.547469)
			(xy 68.938539 -240.597966) (xy 68.907766 -240.644479) (xy 68.870549 -240.686016) (xy 68.827681 -240.721691)
			(xy 68.780075 -240.750745) (xy 68.728746 -240.772557) (xy 68.674789 -240.786663) (xy 68.619352 -240.792763)
			(xy 68.563618 -240.790726) (xy 68.508775 -240.780596) (xy 68.455991 -240.762589) (xy 68.406391 -240.737088)
			(xy 68.361033 -240.704637) (xy 68.320884 -240.665928) (xy 68.286798 -240.621785) (xy 68.259502 -240.57315)
			(xy 68.239579 -240.521059) (xy 68.227453 -240.466622) (xy 68.223382 -240.411) (xy 20.836548 -240.411)
			(xy 20.827433 -240.441297) (xy 20.803761 -240.491794) (xy 20.772988 -240.538307) (xy 20.735771 -240.579844)
			(xy 20.692903 -240.615519) (xy 20.645297 -240.644573) (xy 20.593968 -240.666385) (xy 20.540011 -240.680491)
			(xy 20.484574 -240.686591) (xy 20.42884 -240.684554) (xy 20.373997 -240.674424) (xy 20.321213 -240.656417)
			(xy 20.271613 -240.630916) (xy 20.226255 -240.598465) (xy 20.186106 -240.559756) (xy 20.15202 -240.515613)
			(xy 20.124724 -240.466978) (xy 20.104801 -240.414887) (xy 20.092675 -240.36045) (xy 20.088604 -240.304828)
			(xy 19.936986 -240.304828) (xy 19.937222 -240.318036) (xy 19.936784 -240.345232) (xy 19.929097 -240.399078)
			(xy 19.913828 -240.451282) (xy 19.891286 -240.500783) (xy 19.861931 -240.546573) (xy 19.844512 -240.567464)
			(xy 19.836015 -240.578111) (xy 19.824331 -240.602702) (xy 19.819566 -240.629508) (xy 19.82206 -240.656619)
			(xy 19.831636 -240.682105) (xy 19.84761 -240.704151) (xy 19.868847 -240.721188) (xy 19.893833 -240.732001)
			(xy 19.90725 -240.734342) (xy 19.934252 -240.738602) (xy 19.986754 -240.753823) (xy 20.036546 -240.776381)
			(xy 20.08261 -240.805814) (xy 20.124 -240.84152) (xy 20.159872 -240.882768) (xy 20.189489 -240.928713)
			(xy 20.212246 -240.978415) (xy 20.227676 -241.030856) (xy 20.235464 -241.084962) (xy 20.235926 -241.112294)
			(xy 20.23544 -241.139545) (xy 20.227684 -241.193493) (xy 20.213266 -241.242596) (xy 96.119694 -241.242596)
			(xy 96.123765 -241.186974) (xy 96.135891 -241.132537) (xy 96.155814 -241.080446) (xy 96.18311 -241.031811)
			(xy 96.217196 -240.987668) (xy 96.257345 -240.948959) (xy 96.302703 -240.916508) (xy 96.352303 -240.891007)
			(xy 96.405087 -240.873) (xy 96.45993 -240.86287) (xy 96.515664 -240.860833) (xy 96.571101 -240.866933)
			(xy 96.625058 -240.881039) (xy 96.676387 -240.902851) (xy 96.723993 -240.931905) (xy 96.766861 -240.96758)
			(xy 96.804078 -241.009117) (xy 96.834851 -241.05563) (xy 96.858523 -241.106127) (xy 96.874591 -241.159534)
			(xy 96.882711 -241.21471) (xy 96.88322 -241.242596) (xy 96.882711 -241.270482) (xy 96.874591 -241.325658)
			(xy 96.858523 -241.379065) (xy 96.834851 -241.429562) (xy 96.804078 -241.476075) (xy 96.766861 -241.517612)
			(xy 96.723993 -241.553287) (xy 96.676387 -241.582341) (xy 96.625058 -241.604153) (xy 96.571101 -241.618259)
			(xy 96.515664 -241.624359) (xy 96.45993 -241.622322) (xy 96.405087 -241.612192) (xy 96.352303 -241.594185)
			(xy 96.302703 -241.568684) (xy 96.257345 -241.536233) (xy 96.217196 -241.497524) (xy 96.18311 -241.453381)
			(xy 96.155814 -241.404746) (xy 96.135891 -241.352655) (xy 96.123765 -241.298218) (xy 96.119694 -241.242596)
			(xy 20.213266 -241.242596) (xy 20.212329 -241.245788) (xy 20.189687 -241.295365) (xy 20.160221 -241.341215)
			(xy 20.12453 -241.382406) (xy 20.083339 -241.418097) (xy 20.037489 -241.447563) (xy 19.987912 -241.470205)
			(xy 19.935617 -241.48556) (xy 19.881669 -241.493316) (xy 19.827167 -241.493316) (xy 19.773219 -241.48556)
			(xy 19.720924 -241.470205) (xy 19.671347 -241.447563) (xy 19.625497 -241.418097) (xy 19.584306 -241.382406)
			(xy 19.548615 -241.341215) (xy 19.519149 -241.295365) (xy 19.496507 -241.245788) (xy 19.481152 -241.193493)
			(xy 19.473396 -241.139545) (xy 19.47291 -241.112294) (xy 19.473382 -241.085099) (xy 19.481063 -241.031256)
			(xy 19.496326 -240.979052) (xy 19.518859 -240.929551) (xy 19.548205 -240.883759) (xy 19.56562 -240.862866)
			(xy 19.574243 -240.85231) (xy 19.585933 -240.827695) (xy 19.590695 -240.800865) (xy 19.588189 -240.77373)
			(xy 19.578595 -240.748225) (xy 19.562594 -240.726167) (xy 19.541329 -240.709128) (xy 19.516313 -240.698321)
			(xy 19.502882 -240.695988) (xy 19.475876 -240.691752) (xy 19.423376 -240.676524) (xy 19.373586 -240.65396)
			(xy 19.327525 -240.624522) (xy 19.286137 -240.588813) (xy 19.250267 -240.547563) (xy 19.22065 -240.501617)
			(xy 19.197893 -240.451915) (xy 19.182461 -240.399474) (xy 19.17467 -240.345368) (xy 19.174206 -240.318036)
			(xy 16.436086 -240.318036) (xy 16.436086 -242.168934) (xy 19.00631 -242.168934) (xy 19.010381 -242.113312)
			(xy 19.022507 -242.058875) (xy 19.04243 -242.006784) (xy 19.069726 -241.958149) (xy 19.103812 -241.914006)
			(xy 19.143961 -241.875297) (xy 19.189319 -241.842846) (xy 19.238919 -241.817345) (xy 19.291703 -241.799338)
			(xy 19.346546 -241.789208) (xy 19.40228 -241.787171) (xy 19.457717 -241.793271) (xy 19.511674 -241.807377)
			(xy 19.563003 -241.829189) (xy 19.610609 -241.858243) (xy 19.653477 -241.893918) (xy 19.690694 -241.935455)
			(xy 19.721467 -241.981968) (xy 19.745139 -242.032465) (xy 19.761207 -242.085872) (xy 19.769327 -242.141048)
			(xy 19.769836 -242.168934) (xy 19.769327 -242.19682) (xy 19.761207 -242.251996) (xy 19.745139 -242.305403)
			(xy 19.721467 -242.3559) (xy 19.690694 -242.402413) (xy 19.653477 -242.44395) (xy 19.610609 -242.479625)
			(xy 19.563003 -242.508679) (xy 19.511674 -242.530491) (xy 19.457717 -242.544597) (xy 19.40228 -242.550697)
			(xy 19.346546 -242.54866) (xy 19.291703 -242.53853) (xy 19.238919 -242.520523) (xy 19.189319 -242.495022)
			(xy 19.143961 -242.462571) (xy 19.103812 -242.423862) (xy 19.069726 -242.379719) (xy 19.04243 -242.331084)
			(xy 19.022507 -242.278993) (xy 19.010381 -242.224556) (xy 19.00631 -242.168934) (xy 16.436086 -242.168934)
			(xy 16.436086 -267.500608) (xy 17.210784 -267.500608) (xy 17.214855 -267.444986) (xy 17.226981 -267.390549)
			(xy 17.246904 -267.338458) (xy 17.2742 -267.289823) (xy 17.308286 -267.24568) (xy 17.348435 -267.206971)
			(xy 17.393793 -267.17452) (xy 17.443393 -267.149019) (xy 17.496177 -267.131012) (xy 17.55102 -267.120882)
			(xy 17.606754 -267.118845) (xy 17.662191 -267.124945) (xy 17.716148 -267.139051) (xy 17.767477 -267.160863)
			(xy 17.815083 -267.189917) (xy 17.857951 -267.225592) (xy 17.895168 -267.267129) (xy 17.925941 -267.313642)
			(xy 17.949613 -267.364139) (xy 17.965681 -267.417546) (xy 17.973801 -267.472722) (xy 17.97431 -267.500608)
			(xy 17.973801 -267.528494) (xy 17.965681 -267.58367) (xy 17.949613 -267.637077) (xy 17.925941 -267.687574)
			(xy 17.895168 -267.734087) (xy 17.857951 -267.775624) (xy 17.815083 -267.811299) (xy 17.767477 -267.840353)
			(xy 17.716148 -267.862165) (xy 17.662191 -267.876271) (xy 17.606754 -267.882371) (xy 17.55102 -267.880334)
			(xy 17.496177 -267.870204) (xy 17.443393 -267.852197) (xy 17.393793 -267.826696) (xy 17.348435 -267.794245)
			(xy 17.308286 -267.755536) (xy 17.2742 -267.711393) (xy 17.246904 -267.662758) (xy 17.226981 -267.610667)
			(xy 17.214855 -267.55623) (xy 17.210784 -267.500608) (xy 16.436086 -267.500608) (xy 16.436086 -270.100806)
			(xy 17.238724 -270.100806) (xy 17.242795 -270.045184) (xy 17.254921 -269.990747) (xy 17.274844 -269.938656)
			(xy 17.30214 -269.890021) (xy 17.336226 -269.845878) (xy 17.376375 -269.807169) (xy 17.421733 -269.774718)
			(xy 17.471333 -269.749217) (xy 17.524117 -269.73121) (xy 17.57896 -269.72108) (xy 17.634694 -269.719043)
			(xy 17.690131 -269.725143) (xy 17.744088 -269.739249) (xy 17.795417 -269.761061) (xy 17.843023 -269.790115)
			(xy 17.885891 -269.82579) (xy 17.923108 -269.867327) (xy 17.953881 -269.91384) (xy 17.977553 -269.964337)
			(xy 17.993621 -270.017744) (xy 18.001741 -270.07292) (xy 18.00225 -270.100806) (xy 18.001741 -270.128692)
			(xy 17.993621 -270.183868) (xy 17.977553 -270.237275) (xy 17.953881 -270.287772) (xy 17.923108 -270.334285)
			(xy 17.885891 -270.375822) (xy 17.843023 -270.411497) (xy 17.795417 -270.440551) (xy 17.744088 -270.462363)
			(xy 17.690131 -270.476469) (xy 17.634694 -270.482569) (xy 17.57896 -270.480532) (xy 17.524117 -270.470402)
			(xy 17.471333 -270.452395) (xy 17.421733 -270.426894) (xy 17.376375 -270.394443) (xy 17.336226 -270.355734)
			(xy 17.30214 -270.311591) (xy 17.274844 -270.262956) (xy 17.254921 -270.210865) (xy 17.242795 -270.156428)
			(xy 17.238724 -270.100806) (xy 16.436086 -270.100806) (xy 16.436086 -272.200624) (xy 17.412968 -272.200624)
			(xy 17.417039 -272.145002) (xy 17.429165 -272.090565) (xy 17.449088 -272.038474) (xy 17.476384 -271.989839)
			(xy 17.51047 -271.945696) (xy 17.550619 -271.906987) (xy 17.595977 -271.874536) (xy 17.645577 -271.849035)
			(xy 17.698361 -271.831028) (xy 17.753204 -271.820898) (xy 17.808938 -271.818861) (xy 17.864375 -271.824961)
			(xy 17.918332 -271.839067) (xy 17.969661 -271.860879) (xy 18.017267 -271.889933) (xy 18.060135 -271.925608)
			(xy 18.097352 -271.967145) (xy 18.128125 -272.013658) (xy 18.151797 -272.064155) (xy 18.167865 -272.117562)
			(xy 18.175985 -272.172738) (xy 18.176494 -272.200624) (xy 18.175985 -272.22851) (xy 18.167865 -272.283686)
			(xy 18.151797 -272.337093) (xy 18.128125 -272.38759) (xy 18.097352 -272.434103) (xy 18.060135 -272.47564)
			(xy 18.017267 -272.511315) (xy 17.969661 -272.540369) (xy 17.918332 -272.562181) (xy 17.864375 -272.576287)
			(xy 17.808938 -272.582387) (xy 17.753204 -272.58035) (xy 17.698361 -272.57022) (xy 17.645577 -272.552213)
			(xy 17.595977 -272.526712) (xy 17.550619 -272.494261) (xy 17.51047 -272.455552) (xy 17.476384 -272.411409)
			(xy 17.449088 -272.362774) (xy 17.429165 -272.310683) (xy 17.417039 -272.256246) (xy 17.412968 -272.200624)
			(xy 16.436086 -272.200624) (xy 16.436086 -274.232624) (xy 17.412968 -274.232624) (xy 17.417039 -274.177002)
			(xy 17.429165 -274.122565) (xy 17.449088 -274.070474) (xy 17.476384 -274.021839) (xy 17.51047 -273.977696)
			(xy 17.550619 -273.938987) (xy 17.595977 -273.906536) (xy 17.645577 -273.881035) (xy 17.698361 -273.863028)
			(xy 17.753204 -273.852898) (xy 17.808938 -273.850861) (xy 17.864375 -273.856961) (xy 17.918332 -273.871067)
			(xy 17.969661 -273.892879) (xy 18.017267 -273.921933) (xy 18.060135 -273.957608) (xy 18.097352 -273.999145)
			(xy 18.128125 -274.045658) (xy 18.151797 -274.096155) (xy 18.167865 -274.149562) (xy 18.175985 -274.204738)
			(xy 18.176494 -274.232624) (xy 18.175985 -274.26051) (xy 18.167865 -274.315686) (xy 18.151797 -274.369093)
			(xy 18.128125 -274.41959) (xy 18.097352 -274.466103) (xy 18.060135 -274.50764) (xy 18.017267 -274.543315)
			(xy 17.969661 -274.572369) (xy 17.918332 -274.594181) (xy 17.864375 -274.608287) (xy 17.808938 -274.614387)
			(xy 17.753204 -274.61235) (xy 17.698361 -274.60222) (xy 17.645577 -274.584213) (xy 17.595977 -274.558712)
			(xy 17.550619 -274.526261) (xy 17.51047 -274.487552) (xy 17.476384 -274.443409) (xy 17.449088 -274.394774)
			(xy 17.429165 -274.342683) (xy 17.417039 -274.288246) (xy 17.412968 -274.232624) (xy 16.436086 -274.232624)
			(xy 16.436086 -275.321776) (xy 16.435649 -275.33184) (xy 16.427913 -275.350423) (xy 16.4211 -275.357844)
			(xy 16.126714 -275.65223) (xy 16.122904 -275.660612) (xy 16.111144 -275.685315) (xy 16.081601 -275.731363)
			(xy 16.045782 -275.772718) (xy 16.004422 -275.808531) (xy 15.958371 -275.838069) (xy 15.933674 -275.849842)
			(xy 15.925292 -275.853652) (xy 15.808198 -275.970746) (xy 15.800802 -275.977598) (xy 15.782203 -275.98534)
			(xy 15.77213 -275.985732) (xy 14.454124 -275.985732) (xy 14.444163 -275.986221) (xy 14.425744 -275.993814)
			(xy 14.41831 -276.000464) (xy 14.360398 -276.057868) (xy 14.352524 -276.075902) (xy 14.352524 -276.086316)
			(xy 14.351746 -276.113366) (xy 14.343494 -276.166847) (xy 14.327768 -276.218625) (xy 14.304884 -276.267663)
			(xy 14.275301 -276.312974) (xy 14.239612 -276.353651) (xy 14.198534 -276.388877) (xy 14.15289 -276.417946)
			(xy 14.103597 -276.440274) (xy 14.051644 -276.455412) (xy 13.998073 -276.463059) (xy 13.943959 -276.463059)
			(xy 13.890388 -276.455412) (xy 13.838435 -276.440274) (xy 13.789142 -276.417946) (xy 13.743498 -276.388877)
			(xy 13.70242 -276.353651) (xy 13.666731 -276.312974) (xy 13.637148 -276.267663) (xy 13.614264 -276.218625)
			(xy 13.598538 -276.166847) (xy 13.590286 -276.113366) (xy 13.589508 -276.086316) (xy 13.589508 -276.075902)
			(xy 13.581634 -276.057868) (xy 13.523722 -276.000464) (xy 13.516312 -275.99378) (xy 13.497876 -275.986196)
			(xy 13.487908 -275.985732) (xy 13.276072 -275.985732) (xy 13.266005 -275.986161) (xy 13.247411 -275.993886)
			(xy 13.240004 -276.000718) (xy 13.181838 -276.059646) (xy 13.174218 -276.078188) (xy 13.174472 -276.088602)
			(xy 13.174472 -276.093174) (xy 13.173986 -276.120425) (xy 13.16623 -276.174373) (xy 13.150875 -276.226668)
			(xy 13.128233 -276.276245) (xy 13.098767 -276.322095) (xy 13.063076 -276.363286) (xy 13.021885 -276.398977)
			(xy 12.976035 -276.428443) (xy 12.926458 -276.451085) (xy 12.874163 -276.46644) (xy 12.820215 -276.474196)
			(xy 12.765713 -276.474196) (xy 12.711765 -276.46644) (xy 12.65947 -276.451085) (xy 12.609893 -276.428443)
			(xy 12.564043 -276.398977) (xy 12.522852 -276.363286) (xy 12.487161 -276.322095) (xy 12.457695 -276.276245)
			(xy 12.435053 -276.226668) (xy 12.419698 -276.174373) (xy 12.411942 -276.120425) (xy 12.411456 -276.093174)
			(xy 12.411456 -276.088602) (xy 12.41171 -276.078188) (xy 12.40409 -276.059646) (xy 12.345924 -276.000718)
			(xy 12.338522 -275.993882) (xy 12.319924 -275.986172) (xy 12.309856 -275.985732) (xy 11.673586 -275.985732)
			(xy 11.645646 -276.008338) (xy 11.641836 -276.025864) (xy 11.635313 -276.053989) (xy 11.614936 -276.108006)
			(xy 11.586653 -276.158337) (xy 11.551111 -276.203833) (xy 11.509121 -276.243455) (xy 11.461641 -276.276299)
			(xy 11.409755 -276.301616) (xy 11.354648 -276.318828) (xy 11.297576 -276.327542) (xy 11.26871 -276.328124)
			(xy 11.247969 -276.32788) (xy 11.206728 -276.323428) (xy 11.186414 -276.319234) (xy 11.173714 -276.31644)
			(xy 11.148822 -276.323552) (xy 10.644632 -276.827742) (xy 10.637789 -276.835141) (xy 10.630065 -276.85374)
			(xy 10.629646 -276.86381) (xy 10.629646 -277.280624) (xy 15.393668 -277.280624) (xy 15.397739 -277.225002)
			(xy 15.409865 -277.170565) (xy 15.429788 -277.118474) (xy 15.457084 -277.069839) (xy 15.49117 -277.025696)
			(xy 15.531319 -276.986987) (xy 15.576677 -276.954536) (xy 15.626277 -276.929035) (xy 15.679061 -276.911028)
			(xy 15.733904 -276.900898) (xy 15.789638 -276.898861) (xy 15.845075 -276.904961) (xy 15.899032 -276.919067)
			(xy 15.950361 -276.940879) (xy 15.997967 -276.969933) (xy 16.040835 -277.005608) (xy 16.078052 -277.047145)
			(xy 16.108825 -277.093658) (xy 16.132497 -277.144155) (xy 16.148565 -277.197562) (xy 16.156685 -277.252738)
			(xy 16.157194 -277.280624) (xy 16.156685 -277.30851) (xy 16.148565 -277.363686) (xy 16.132497 -277.417093)
			(xy 16.108825 -277.46759) (xy 16.078052 -277.514103) (xy 16.040835 -277.55564) (xy 15.997967 -277.591315)
			(xy 15.950361 -277.620369) (xy 15.899032 -277.642181) (xy 15.845075 -277.656287) (xy 15.789638 -277.662387)
			(xy 15.733904 -277.66035) (xy 15.679061 -277.65022) (xy 15.626277 -277.632213) (xy 15.576677 -277.606712)
			(xy 15.531319 -277.574261) (xy 15.49117 -277.535552) (xy 15.457084 -277.491409) (xy 15.429788 -277.442774)
			(xy 15.409865 -277.390683) (xy 15.397739 -277.336246) (xy 15.393668 -277.280624) (xy 10.629646 -277.280624)
			(xy 10.629646 -278.171402) (xy 10.630071 -278.181471) (xy 10.637791 -278.200071) (xy 10.644632 -278.20747)
			(xy 10.893044 -278.455882) (xy 10.900444 -278.462724) (xy 10.919042 -278.470445) (xy 10.929112 -278.470868)
		)
		(stroke
			(width 0)
			(type solid)
		)
		(fill yes)
		(layer "In13.Cu")
		(net "P3V3_AUX")
	)
	(gr_poly
		(pts
			(xy 269.193264 -298.267628) (xy 269.194788 -298.247816) (xy 269.197404 -298.222001) (xy 269.209649 -298.171581)
			(xy 269.229615 -298.123692) (xy 269.256814 -298.079508) (xy 269.290578 -298.040112) (xy 269.330078 -298.00647)
			(xy 269.374347 -297.979408) (xy 269.422297 -297.95959) (xy 269.472754 -297.947501) (xy 269.52448 -297.943438)
			(xy 269.576206 -297.947501) (xy 269.626663 -297.95959) (xy 269.674613 -297.979408) (xy 269.718882 -298.00647)
			(xy 269.758382 -298.040112) (xy 269.792146 -298.079508) (xy 269.819345 -298.123692) (xy 269.839311 -298.171581)
			(xy 269.851556 -298.222001) (xy 269.854172 -298.247816) (xy 269.855696 -298.267628) (xy 269.884906 -298.294552)
			(xy 270.114268 -298.294552) (xy 270.143478 -298.267628) (xy 270.145002 -298.247816) (xy 270.147618 -298.222001)
			(xy 270.159863 -298.171581) (xy 270.179829 -298.123692) (xy 270.207028 -298.079508) (xy 270.240792 -298.040112)
			(xy 270.280292 -298.00647) (xy 270.324561 -297.979408) (xy 270.372511 -297.95959) (xy 270.422968 -297.947501)
			(xy 270.474694 -297.943438) (xy 270.52642 -297.947501) (xy 270.576877 -297.95959) (xy 270.624827 -297.979408)
			(xy 270.669096 -298.00647) (xy 270.708596 -298.040112) (xy 270.74236 -298.079508) (xy 270.769559 -298.123692)
			(xy 270.789525 -298.171581) (xy 270.80177 -298.222001) (xy 270.804386 -298.247816) (xy 270.80591 -298.267628)
			(xy 270.83512 -298.294552) (xy 271.064482 -298.294552) (xy 271.093692 -298.267628) (xy 271.095216 -298.247816)
			(xy 271.097832 -298.222001) (xy 271.110077 -298.171581) (xy 271.130043 -298.123692) (xy 271.157242 -298.079508)
			(xy 271.191006 -298.040112) (xy 271.230506 -298.00647) (xy 271.274775 -297.979408) (xy 271.322725 -297.95959)
			(xy 271.373182 -297.947501) (xy 271.424908 -297.943438) (xy 271.476634 -297.947501) (xy 271.527091 -297.95959)
			(xy 271.575041 -297.979408) (xy 271.61931 -298.00647) (xy 271.65881 -298.040112) (xy 271.692574 -298.079508)
			(xy 271.719773 -298.123692) (xy 271.739739 -298.171581) (xy 271.751984 -298.222001) (xy 271.7546 -298.247816)
			(xy 271.756124 -298.267628) (xy 271.785334 -298.294552) (xy 272.014442 -298.294552) (xy 272.043652 -298.267628)
			(xy 272.045176 -298.247816) (xy 272.047792 -298.222001) (xy 272.060037 -298.171581) (xy 272.080003 -298.123692)
			(xy 272.107202 -298.079508) (xy 272.140966 -298.040112) (xy 272.180466 -298.00647) (xy 272.224735 -297.979408)
			(xy 272.272685 -297.95959) (xy 272.323142 -297.947501) (xy 272.374868 -297.943438) (xy 272.426594 -297.947501)
			(xy 272.477051 -297.95959) (xy 272.525001 -297.979408) (xy 272.56927 -298.00647) (xy 272.60877 -298.040112)
			(xy 272.642534 -298.079508) (xy 272.669733 -298.123692) (xy 272.689699 -298.171581) (xy 272.701944 -298.222001)
			(xy 272.70456 -298.247816) (xy 272.706084 -298.267628) (xy 272.735294 -298.294552) (xy 272.964402 -298.294552)
			(xy 272.993612 -298.267628) (xy 272.995136 -298.247816) (xy 272.997752 -298.222001) (xy 273.009997 -298.171581)
			(xy 273.029963 -298.123692) (xy 273.057162 -298.079508) (xy 273.090926 -298.040112) (xy 273.130426 -298.00647)
			(xy 273.174695 -297.979408) (xy 273.222645 -297.95959) (xy 273.273102 -297.947501) (xy 273.324828 -297.943438)
			(xy 273.376554 -297.947501) (xy 273.427011 -297.95959) (xy 273.474961 -297.979408) (xy 273.51923 -298.00647)
			(xy 273.55873 -298.040112) (xy 273.592494 -298.079508) (xy 273.619693 -298.123692) (xy 273.639659 -298.171581)
			(xy 273.651904 -298.222001) (xy 273.65452 -298.247816) (xy 273.656044 -298.267628) (xy 273.685254 -298.294552)
			(xy 273.914362 -298.294552) (xy 273.943572 -298.267628) (xy 273.945096 -298.247816) (xy 273.947712 -298.222001)
			(xy 273.959957 -298.171581) (xy 273.979923 -298.123692) (xy 274.007122 -298.079508) (xy 274.040886 -298.040112)
			(xy 274.080386 -298.00647) (xy 274.124655 -297.979408) (xy 274.172605 -297.95959) (xy 274.223062 -297.947501)
			(xy 274.274788 -297.943438) (xy 274.326514 -297.947501) (xy 274.376971 -297.95959) (xy 274.424921 -297.979408)
			(xy 274.46919 -298.00647) (xy 274.50869 -298.040112) (xy 274.542454 -298.079508) (xy 274.569653 -298.123692)
			(xy 274.589619 -298.171581) (xy 274.601864 -298.222001) (xy 274.60448 -298.247816) (xy 274.606004 -298.267628)
			(xy 274.635214 -298.294552) (xy 275.814282 -298.294552) (xy 275.843492 -298.267628) (xy 275.845016 -298.247816)
			(xy 275.847632 -298.222001) (xy 275.859877 -298.171581) (xy 275.879843 -298.123692) (xy 275.907042 -298.079508)
			(xy 275.940806 -298.040112) (xy 275.980306 -298.00647) (xy 276.024575 -297.979408) (xy 276.072525 -297.95959)
			(xy 276.122982 -297.947501) (xy 276.174708 -297.943438) (xy 276.226434 -297.947501) (xy 276.276891 -297.95959)
			(xy 276.324841 -297.979408) (xy 276.36911 -298.00647) (xy 276.40861 -298.040112) (xy 276.442374 -298.079508)
			(xy 276.469573 -298.123692) (xy 276.489539 -298.171581) (xy 276.501784 -298.222001) (xy 276.5044 -298.247816)
			(xy 276.505924 -298.267628) (xy 276.535134 -298.294552) (xy 276.764496 -298.294552) (xy 276.793706 -298.267628)
			(xy 276.79523 -298.247816) (xy 276.797846 -298.222001) (xy 276.810091 -298.171581) (xy 276.830057 -298.123692)
			(xy 276.857256 -298.079508) (xy 276.89102 -298.040112) (xy 276.93052 -298.00647) (xy 276.974789 -297.979408)
			(xy 277.022739 -297.95959) (xy 277.073196 -297.947501) (xy 277.124922 -297.943438) (xy 277.176648 -297.947501)
			(xy 277.227105 -297.95959) (xy 277.275055 -297.979408) (xy 277.319324 -298.00647) (xy 277.358824 -298.040112)
			(xy 277.392588 -298.079508) (xy 277.419787 -298.123692) (xy 277.439753 -298.171581) (xy 277.451998 -298.222001)
			(xy 277.454614 -298.247816) (xy 277.456138 -298.267628) (xy 277.485348 -298.294552) (xy 277.714456 -298.294552)
			(xy 277.743666 -298.267628) (xy 277.74519 -298.247816) (xy 277.747806 -298.222001) (xy 277.760051 -298.171581)
			(xy 277.780017 -298.123692) (xy 277.807216 -298.079508) (xy 277.84098 -298.040112) (xy 277.88048 -298.00647)
			(xy 277.924749 -297.979408) (xy 277.972699 -297.95959) (xy 278.023156 -297.947501) (xy 278.074882 -297.943438)
			(xy 278.126608 -297.947501) (xy 278.177065 -297.95959) (xy 278.225015 -297.979408) (xy 278.269284 -298.00647)
			(xy 278.308784 -298.040112) (xy 278.342548 -298.079508) (xy 278.369747 -298.123692) (xy 278.389713 -298.171581)
			(xy 278.401958 -298.222001) (xy 278.404574 -298.247816) (xy 278.406098 -298.267628) (xy 278.435308 -298.294552)
			(xy 278.664416 -298.294552) (xy 278.693626 -298.267628) (xy 278.69515 -298.247816) (xy 278.697607 -298.223293)
			(xy 278.708861 -298.175311) (xy 278.727112 -298.129531) (xy 278.751956 -298.086968) (xy 278.782843 -298.048563)
			(xy 278.819088 -298.015169) (xy 278.859889 -297.987524) (xy 278.90434 -297.966242) (xy 278.951459 -297.951794)
			(xy 279.0002 -297.944499) (xy 279.024842 -297.944032) (xy 279.054317 -297.944698) (xy 279.112329 -297.955181)
			(xy 279.167567 -297.975773) (xy 279.193244 -297.99026) (xy 279.205182 -297.997118) (xy 279.23236 -297.997372)
			(xy 279.321006 -297.946826) (xy 279.328619 -297.942096) (xy 279.340181 -297.928417) (xy 279.346309 -297.911587)
			(xy 279.34666 -297.90263) (xy 279.34666 -296.74693) (xy 279.346304 -296.73798) (xy 279.340142 -296.721174)
			(xy 279.328591 -296.707499) (xy 279.321006 -296.702734) (xy 279.23236 -296.652188) (xy 279.204928 -296.652442)
			(xy 279.193244 -296.6593) (xy 279.167561 -296.673779) (xy 279.112328 -296.694384) (xy 279.054317 -296.704875)
			(xy 279.024842 -296.705528) (xy 278.99885 -296.705048) (xy 278.947505 -296.696922) (xy 278.898064 -296.680864)
			(xy 278.851743 -296.657269) (xy 278.809684 -296.626718) (xy 278.772923 -296.589963) (xy 278.742364 -296.54791)
			(xy 278.71876 -296.501594) (xy 278.702692 -296.452155) (xy 278.694557 -296.400812) (xy 278.694134 -296.37482)
			(xy 278.694643 -296.349316) (xy 278.702547 -296.298922) (xy 278.709882 -296.27449) (xy 278.713692 -296.262806)
			(xy 278.709882 -296.23893) (xy 278.654002 -296.16273) (xy 278.646906 -296.153726) (xy 278.626805 -296.142748)
			(xy 278.615394 -296.141648) (xy 278.48687 -296.141648) (xy 278.48433 -296.141648) (xy 278.47296 -296.142896)
			(xy 278.4529 -296.153827) (xy 278.445722 -296.16273) (xy 278.399748 -296.225722) (xy 278.395193 -296.232363)
			(xy 278.390147 -296.247647) (xy 278.389842 -296.255694) (xy 278.389842 -296.274236) (xy 278.391874 -296.281348)
			(xy 278.398236 -296.304192) (xy 278.405114 -296.351111) (xy 278.40559 -296.37482) (xy 278.40508 -296.400807)
			(xy 278.39695 -296.452142) (xy 278.380889 -296.501572) (xy 278.357293 -296.547882) (xy 278.326743 -296.58993)
			(xy 278.289992 -296.626681) (xy 278.247944 -296.657231) (xy 278.201634 -296.680827) (xy 278.152204 -296.696888)
			(xy 278.100869 -296.705018) (xy 278.048895 -296.705018) (xy 277.99756 -296.696888) (xy 277.94813 -296.680827)
			(xy 277.90182 -296.657231) (xy 277.859772 -296.626681) (xy 277.823021 -296.58993) (xy 277.792471 -296.547882)
			(xy 277.768875 -296.501572) (xy 277.752814 -296.452142) (xy 277.744684 -296.400807) (xy 277.744174 -296.37482)
			(xy 277.744683 -296.349316) (xy 277.752588 -296.298922) (xy 277.759922 -296.27449) (xy 277.763732 -296.262806)
			(xy 277.759922 -296.23893) (xy 277.704042 -296.16273) (xy 277.696948 -296.15372) (xy 277.676849 -296.142727)
			(xy 277.665434 -296.141648) (xy 277.53691 -296.141648) (xy 277.53437 -296.141648) (xy 277.523006 -296.142908)
			(xy 277.502966 -296.153852) (xy 277.495762 -296.16273) (xy 277.449788 -296.225722) (xy 277.44523 -296.232362)
			(xy 277.440179 -296.247646) (xy 277.439882 -296.255694) (xy 277.439882 -296.274236) (xy 277.441914 -296.281348)
			(xy 277.448275 -296.304192) (xy 277.455153 -296.351111) (xy 277.45563 -296.37482) (xy 277.45512 -296.400807)
			(xy 277.44699 -296.452142) (xy 277.430929 -296.501572) (xy 277.407333 -296.547882) (xy 277.376783 -296.58993)
			(xy 277.340032 -296.626681) (xy 277.297984 -296.657231) (xy 277.251674 -296.680827) (xy 277.202244 -296.696888)
			(xy 277.150909 -296.705018) (xy 277.098935 -296.705018) (xy 277.0476 -296.696888) (xy 276.99817 -296.680827)
			(xy 276.95186 -296.657231) (xy 276.909812 -296.626681) (xy 276.873061 -296.58993) (xy 276.842511 -296.547882)
			(xy 276.818915 -296.501572) (xy 276.802854 -296.452142) (xy 276.794724 -296.400807) (xy 276.794214 -296.37482)
			(xy 276.794723 -296.349316) (xy 276.802629 -296.298922) (xy 276.809962 -296.27449) (xy 276.813772 -296.262806)
			(xy 276.809962 -296.23893) (xy 276.754082 -296.16273) (xy 276.746984 -296.15373) (xy 276.726883 -296.14276)
			(xy 276.715474 -296.141648) (xy 276.586696 -296.141648) (xy 276.584156 -296.141648) (xy 276.572794 -296.14291)
			(xy 276.552758 -296.153858) (xy 276.545548 -296.16273) (xy 276.499574 -296.225722) (xy 276.495017 -296.232362)
			(xy 276.489968 -296.247646) (xy 276.489668 -296.255694) (xy 276.489668 -296.274236) (xy 276.4917 -296.281348)
			(xy 276.498062 -296.304192) (xy 276.504939 -296.351111) (xy 276.505416 -296.37482) (xy 276.504906 -296.400807)
			(xy 276.496776 -296.452142) (xy 276.480715 -296.501572) (xy 276.457119 -296.547882) (xy 276.426569 -296.58993)
			(xy 276.389818 -296.626681) (xy 276.34777 -296.657231) (xy 276.30146 -296.680827) (xy 276.25203 -296.696888)
			(xy 276.200695 -296.705018) (xy 276.148721 -296.705018) (xy 276.097386 -296.696888) (xy 276.047956 -296.680827)
			(xy 276.001646 -296.657231) (xy 275.959598 -296.626681) (xy 275.922847 -296.58993) (xy 275.892297 -296.547882)
			(xy 275.868701 -296.501572) (xy 275.85264 -296.452142) (xy 275.84451 -296.400807) (xy 275.844 -296.37482)
			(xy 275.844509 -296.349316) (xy 275.852415 -296.298922) (xy 275.859748 -296.27449) (xy 275.863558 -296.262806)
			(xy 275.859748 -296.23893) (xy 275.803868 -296.16273) (xy 275.796769 -296.153732) (xy 275.776668 -296.142767)
			(xy 275.76526 -296.141648) (xy 274.686776 -296.141648) (xy 274.684236 -296.141648) (xy 274.672876 -296.142914)
			(xy 274.652847 -296.153866) (xy 274.645628 -296.16273) (xy 274.599654 -296.225722) (xy 274.595099 -296.232363)
			(xy 274.590051 -296.247646) (xy 274.589748 -296.255694) (xy 274.589748 -296.274236) (xy 274.59178 -296.281348)
			(xy 274.598142 -296.304192) (xy 274.60502 -296.351111) (xy 274.605496 -296.37482) (xy 274.604986 -296.400807)
			(xy 274.596856 -296.452142) (xy 274.580795 -296.501572) (xy 274.557199 -296.547882) (xy 274.526649 -296.58993)
			(xy 274.489898 -296.626681) (xy 274.44785 -296.657231) (xy 274.40154 -296.680827) (xy 274.35211 -296.696888)
			(xy 274.300775 -296.705018) (xy 274.248801 -296.705018) (xy 274.197466 -296.696888) (xy 274.148036 -296.680827)
			(xy 274.101726 -296.657231) (xy 274.059678 -296.626681) (xy 274.022927 -296.58993) (xy 273.992377 -296.547882)
			(xy 273.968781 -296.501572) (xy 273.95272 -296.452142) (xy 273.94459 -296.400807) (xy 273.94408 -296.37482)
			(xy 273.944589 -296.349316) (xy 273.952494 -296.298922) (xy 273.959828 -296.27449) (xy 273.963638 -296.262806)
			(xy 273.959828 -296.23893) (xy 273.903948 -296.16273) (xy 273.896855 -296.153719) (xy 273.876756 -296.142723)
			(xy 273.86534 -296.141648) (xy 272.786856 -296.141648) (xy 272.784316 -296.141648) (xy 272.772947 -296.142899)
			(xy 272.752892 -296.153833) (xy 272.745708 -296.16273) (xy 272.699734 -296.225722) (xy 272.69518 -296.232364)
			(xy 272.690135 -296.247647) (xy 272.689828 -296.255694) (xy 272.689828 -296.274236) (xy 272.69186 -296.281348)
			(xy 272.698222 -296.304192) (xy 272.705101 -296.351111) (xy 272.705576 -296.37482) (xy 272.705066 -296.400807)
			(xy 272.696936 -296.452142) (xy 272.680875 -296.501572) (xy 272.657279 -296.547882) (xy 272.626729 -296.58993)
			(xy 272.589978 -296.626681) (xy 272.54793 -296.657231) (xy 272.50162 -296.680827) (xy 272.45219 -296.696888)
			(xy 272.400855 -296.705018) (xy 272.348881 -296.705018) (xy 272.297546 -296.696888) (xy 272.248116 -296.680827)
			(xy 272.201806 -296.657231) (xy 272.159758 -296.626681) (xy 272.123007 -296.58993) (xy 272.092457 -296.547882)
			(xy 272.068861 -296.501572) (xy 272.0528 -296.452142) (xy 272.04467 -296.400807) (xy 272.04416 -296.37482)
			(xy 272.044669 -296.349316) (xy 272.052574 -296.298922) (xy 272.059908 -296.27449) (xy 272.063718 -296.262806)
			(xy 272.059908 -296.23893) (xy 272.004028 -296.16273) (xy 271.996933 -296.153722) (xy 271.976834 -296.142735)
			(xy 271.96542 -296.141648) (xy 271.836896 -296.141648) (xy 271.834356 -296.141648) (xy 271.822994 -296.14291)
			(xy 271.802958 -296.153858) (xy 271.795748 -296.16273) (xy 271.749774 -296.225722) (xy 271.745217 -296.232362)
			(xy 271.740168 -296.247646) (xy 271.739868 -296.255694) (xy 271.739868 -296.274236) (xy 271.7419 -296.281348)
			(xy 271.748262 -296.304192) (xy 271.755139 -296.351111) (xy 271.755616 -296.37482) (xy 271.755106 -296.400807)
			(xy 271.746976 -296.452142) (xy 271.730915 -296.501572) (xy 271.707319 -296.547882) (xy 271.676769 -296.58993)
			(xy 271.640018 -296.626681) (xy 271.59797 -296.657231) (xy 271.55166 -296.680827) (xy 271.50223 -296.696888)
			(xy 271.450895 -296.705018) (xy 271.398921 -296.705018) (xy 271.347586 -296.696888) (xy 271.298156 -296.680827)
			(xy 271.251846 -296.657231) (xy 271.209798 -296.626681) (xy 271.173047 -296.58993) (xy 271.142497 -296.547882)
			(xy 271.118901 -296.501572) (xy 271.10284 -296.452142) (xy 271.09471 -296.400807) (xy 271.0942 -296.37482)
			(xy 271.094709 -296.349316) (xy 271.102615 -296.298922) (xy 271.109948 -296.27449) (xy 271.113758 -296.262806)
			(xy 271.109948 -296.23893) (xy 271.054068 -296.16273) (xy 271.046969 -296.153732) (xy 271.026868 -296.142767)
			(xy 271.01546 -296.141648) (xy 270.886682 -296.141648) (xy 270.884142 -296.141648) (xy 270.872782 -296.142913)
			(xy 270.852751 -296.153864) (xy 270.845534 -296.16273) (xy 270.79956 -296.225722) (xy 270.795004 -296.232363)
			(xy 270.789956 -296.247646) (xy 270.789654 -296.255694) (xy 270.789654 -296.274236) (xy 270.791686 -296.281348)
			(xy 270.798048 -296.304192) (xy 270.804926 -296.351111) (xy 270.805402 -296.37482) (xy 270.804892 -296.400807)
			(xy 270.796762 -296.452142) (xy 270.780701 -296.501572) (xy 270.757105 -296.547882) (xy 270.726555 -296.58993)
			(xy 270.689804 -296.626681) (xy 270.647756 -296.657231) (xy 270.601446 -296.680827) (xy 270.552016 -296.696888)
			(xy 270.500681 -296.705018) (xy 270.448707 -296.705018) (xy 270.397372 -296.696888) (xy 270.347942 -296.680827)
			(xy 270.301632 -296.657231) (xy 270.259584 -296.626681) (xy 270.222833 -296.58993) (xy 270.192283 -296.547882)
			(xy 270.168687 -296.501572) (xy 270.152626 -296.452142) (xy 270.144496 -296.400807) (xy 270.143986 -296.37482)
			(xy 270.144495 -296.349316) (xy 270.1524 -296.298922) (xy 270.159734 -296.27449) (xy 270.163544 -296.262806)
			(xy 270.159734 -296.23893) (xy 270.103854 -296.16273) (xy 270.096754 -296.153734) (xy 270.076652 -296.142775)
			(xy 270.065246 -296.141648) (xy 269.916148 -296.141648) (xy 269.910709 -296.141502) (xy 269.90008 -296.139189)
			(xy 269.895066 -296.137076) (xy 269.881604 -296.130726) (xy 269.852648 -296.13479) (xy 269.828264 -296.155364)
			(xy 269.820982 -296.162013) (xy 269.811713 -296.179396) (xy 269.81023 -296.189146) (xy 269.809468 -296.196766)
			(xy 269.812516 -296.211498) (xy 269.816072 -296.218356) (xy 269.828445 -296.242562) (xy 269.845986 -296.294014)
			(xy 269.854883 -296.34764) (xy 269.855442 -296.37482) (xy 269.854932 -296.400807) (xy 269.846802 -296.452142)
			(xy 269.830741 -296.501572) (xy 269.807145 -296.547882) (xy 269.776595 -296.58993) (xy 269.739844 -296.626681)
			(xy 269.697796 -296.657231) (xy 269.651486 -296.680827) (xy 269.602056 -296.696888) (xy 269.550721 -296.705018)
			(xy 269.498747 -296.705018) (xy 269.447412 -296.696888) (xy 269.397982 -296.680827) (xy 269.351672 -296.657231)
			(xy 269.309624 -296.626681) (xy 269.272873 -296.58993) (xy 269.242323 -296.547882) (xy 269.218727 -296.501572)
			(xy 269.202666 -296.452142) (xy 269.194536 -296.400807) (xy 269.194026 -296.37482) (xy 269.194491 -296.349394)
			(xy 269.202276 -296.29914) (xy 269.217664 -296.250672) (xy 269.240294 -296.205132) (xy 269.26963 -296.163595)
			(xy 269.304982 -296.12704) (xy 269.345514 -296.09633) (xy 269.390272 -296.072189) (xy 269.438198 -296.055188)
			(xy 269.488163 -296.045726) (xy 269.513558 -296.044366) (xy 269.528798 -296.043858) (xy 269.553436 -296.026586)
			(xy 269.593314 -295.925494) (xy 269.59731 -295.913431) (xy 269.594252 -295.888235) (xy 269.587472 -295.877488)
			(xy 269.584678 -295.873678) (xy 268.515592 -294.804592) (xy 268.503654 -294.797988) (xy 268.496796 -294.79621)
			(xy 268.471198 -294.789455) (xy 268.422401 -294.76893) (xy 268.37749 -294.740904) (xy 268.337609 -294.70609)
			(xy 268.303775 -294.665375) (xy 268.276848 -294.619797) (xy 268.257515 -294.570515) (xy 268.251432 -294.54475)
			(xy 268.249908 -294.537384) (xy 268.24305 -294.524684) (xy 266.304776 -292.586664) (xy 266.297379 -292.579815)
			(xy 266.27878 -292.572079) (xy 266.268708 -292.571678) (xy 264.410444 -292.571678) (xy 264.399698 -292.572163)
			(xy 264.380102 -292.580987) (xy 264.372598 -292.588696) (xy 264.322052 -292.645592) (xy 264.315232 -292.654011)
			(xy 264.308765 -292.67467) (xy 264.309606 -292.68547) (xy 264.310951 -292.697234) (xy 264.312347 -292.720873)
			(xy 264.3124 -292.732714) (xy 264.311913 -292.759964) (xy 264.304155 -292.81391) (xy 264.288799 -292.866203)
			(xy 264.266157 -292.915778) (xy 264.23669 -292.961626) (xy 264.200998 -293.002814) (xy 264.159808 -293.038503)
			(xy 264.113958 -293.067967) (xy 264.064382 -293.090606) (xy 264.012089 -293.10596) (xy 263.958142 -293.113715)
			(xy 263.930892 -293.114222) (xy 263.906272 -293.113832) (xy 263.85744 -293.107497) (xy 263.809827 -293.094944)
			(xy 263.786874 -293.086028) (xy 263.774936 -293.081202) (xy 263.750044 -293.083742) (xy 263.68502 -293.12743)
			(xy 263.680702 -293.126922) (xy 263.663938 -293.141908) (xy 263.656312 -293.149471) (xy 263.647507 -293.169031)
			(xy 263.64692 -293.179754) (xy 263.64692 -293.494714) (xy 265.820904 -293.494714) (xy 265.824975 -293.439092)
			(xy 265.837101 -293.384655) (xy 265.857024 -293.332564) (xy 265.88432 -293.283929) (xy 265.918406 -293.239786)
			(xy 265.958555 -293.201077) (xy 266.003913 -293.168626) (xy 266.053513 -293.143125) (xy 266.106297 -293.125118)
			(xy 266.16114 -293.114988) (xy 266.216874 -293.112951) (xy 266.272311 -293.119051) (xy 266.326268 -293.133157)
			(xy 266.377597 -293.154969) (xy 266.425203 -293.184023) (xy 266.468071 -293.219698) (xy 266.505288 -293.261235)
			(xy 266.536061 -293.307748) (xy 266.559733 -293.358245) (xy 266.575801 -293.411652) (xy 266.583921 -293.466828)
			(xy 266.58443 -293.494714) (xy 266.583921 -293.5226) (xy 266.575801 -293.577776) (xy 266.559733 -293.631183)
			(xy 266.536061 -293.68168) (xy 266.505288 -293.728193) (xy 266.468071 -293.76973) (xy 266.425203 -293.805405)
			(xy 266.377597 -293.834459) (xy 266.326268 -293.856271) (xy 266.272311 -293.870377) (xy 266.216874 -293.876477)
			(xy 266.16114 -293.87444) (xy 266.106297 -293.86431) (xy 266.053513 -293.846303) (xy 266.003913 -293.820802)
			(xy 265.958555 -293.788351) (xy 265.918406 -293.749642) (xy 265.88432 -293.705499) (xy 265.857024 -293.656864)
			(xy 265.837101 -293.604773) (xy 265.824975 -293.550336) (xy 265.820904 -293.494714) (xy 263.64692 -293.494714)
			(xy 263.64692 -295.207182) (xy 263.647359 -295.217245) (xy 263.655096 -295.235826) (xy 263.661906 -295.24325)
			(xy 263.8298 -295.411144) (xy 263.837196 -295.417997) (xy 263.855794 -295.42574) (xy 263.865868 -295.42613)
			(xy 265.406124 -295.42613) (xy 265.416192 -295.426558) (xy 265.434787 -295.434282) (xy 265.442192 -295.441116)
			(xy 265.75131 -295.750234) (xy 265.758161 -295.75763) (xy 265.765897 -295.776229) (xy 265.766296 -295.786302)
			(xy 265.766296 -296.288968) (xy 265.76639 -296.293987) (xy 265.768313 -296.303837) (xy 265.770106 -296.308526)
			(xy 265.776964 -296.324782) (xy 265.778275 -296.328154) (xy 265.780058 -296.335164) (xy 265.78052 -296.338752)
			(xy 265.782044 -296.352468) (xy 265.797538 -296.374312) (xy 265.895074 -296.418254) (xy 265.904168 -296.421851)
			(xy 265.923693 -296.422613) (xy 265.942091 -296.416035) (xy 265.949684 -296.409872) (xy 265.970727 -296.391835)
			(xy 266.017045 -296.361403) (xy 266.067281 -296.337997) (xy 266.120376 -296.32211) (xy 266.175212 -296.314076)
			(xy 266.202922 -296.313606) (xy 266.230171 -296.314094) (xy 266.284114 -296.321853) (xy 266.336405 -296.337209)
			(xy 266.385977 -296.35985) (xy 266.431823 -296.389316) (xy 266.473009 -296.425006) (xy 266.508697 -296.466195)
			(xy 266.53816 -296.512042) (xy 266.560799 -296.561616) (xy 266.576152 -296.613907) (xy 266.583908 -296.667851)
			(xy 266.583908 -296.722349) (xy 266.576152 -296.776293) (xy 266.560799 -296.828584) (xy 266.53816 -296.878158)
			(xy 266.508697 -296.924005) (xy 266.473009 -296.965194) (xy 266.431823 -297.000884) (xy 266.385977 -297.03035)
			(xy 266.336405 -297.052991) (xy 266.284114 -297.068347) (xy 266.230171 -297.076106) (xy 266.202922 -297.076622)
			(xy 266.175212 -297.076127) (xy 266.120375 -297.068105) (xy 266.067278 -297.052228) (xy 266.017039 -297.028829)
			(xy 265.970717 -296.998403) (xy 265.949684 -296.980356) (xy 265.938254 -296.97045) (xy 265.90879 -296.965878)
			(xy 265.810746 -297.010074) (xy 265.79703 -297.01617) (xy 265.780774 -297.041316) (xy 265.780774 -297.3248)
			(xy 267.633949 -297.3248) (xy 267.63812 -297.274461) (xy 267.650519 -297.225496) (xy 267.670808 -297.179238)
			(xy 267.698434 -297.136951) (xy 267.732643 -297.099787) (xy 267.772502 -297.068761) (xy 267.816923 -297.044718)
			(xy 267.864697 -297.028313) (xy 267.914518 -297.019996) (xy 267.939774 -297.019472) (xy 267.965169 -297.019983)
			(xy 268.015259 -297.028397) (xy 268.063266 -297.044981) (xy 268.107868 -297.069279) (xy 268.147837 -297.100619)
			(xy 268.165326 -297.11904) (xy 268.172946 -297.127168) (xy 268.192758 -297.135804) (xy 268.292072 -297.13301)
			(xy 268.31163 -297.123612) (xy 268.318742 -297.114976) (xy 268.334531 -297.096404) (xy 268.370664 -297.063685)
			(xy 268.411205 -297.036618) (xy 268.455277 -297.01579) (xy 268.501928 -297.00165) (xy 268.550147 -296.994504)
			(xy 268.57452 -296.994072) (xy 269.52448 -296.994072) (xy 269.550469 -296.994594) (xy 269.601807 -297.002722)
			(xy 269.651241 -297.018781) (xy 269.697554 -297.042377) (xy 269.739606 -297.072927) (xy 269.77636 -297.109679)
			(xy 269.806913 -297.151729) (xy 269.830511 -297.198041) (xy 269.846573 -297.247474) (xy 269.854705 -297.298811)
			(xy 269.854705 -297.32478) (xy 270.16889 -297.32478) (xy 270.17285 -297.275726) (xy 270.184627 -297.227942)
			(xy 270.203918 -297.182666) (xy 270.230221 -297.14107) (xy 270.262856 -297.104233) (xy 270.300977 -297.073108)
			(xy 270.343598 -297.048501) (xy 270.389614 -297.031049) (xy 270.437833 -297.021205) (xy 270.487008 -297.019224)
			(xy 270.535863 -297.025156) (xy 270.583134 -297.038848) (xy 270.627596 -297.059946) (xy 270.668099 -297.087902)
			(xy 270.703592 -297.121994) (xy 270.733157 -297.161338) (xy 270.756028 -297.204915) (xy 270.771612 -297.251596)
			(xy 270.779507 -297.300173) (xy 270.780002 -297.32478) (xy 271.119104 -297.32478) (xy 271.123064 -297.275726)
			(xy 271.134841 -297.227942) (xy 271.154132 -297.182666) (xy 271.180435 -297.14107) (xy 271.21307 -297.104233)
			(xy 271.251191 -297.073108) (xy 271.293812 -297.048501) (xy 271.339828 -297.031049) (xy 271.388047 -297.021205)
			(xy 271.437222 -297.019224) (xy 271.486077 -297.025156) (xy 271.533348 -297.038848) (xy 271.57781 -297.059946)
			(xy 271.618313 -297.087902) (xy 271.653806 -297.121994) (xy 271.683371 -297.161338) (xy 271.706242 -297.204915)
			(xy 271.721826 -297.251596) (xy 271.729721 -297.300173) (xy 271.730216 -297.32478) (xy 273.968984 -297.32478)
			(xy 273.972944 -297.275726) (xy 273.984721 -297.227942) (xy 274.004012 -297.182666) (xy 274.030315 -297.14107)
			(xy 274.06295 -297.104233) (xy 274.101071 -297.073108) (xy 274.143692 -297.048501) (xy 274.189708 -297.031049)
			(xy 274.237927 -297.021205) (xy 274.287102 -297.019224) (xy 274.335957 -297.025156) (xy 274.383228 -297.038848)
			(xy 274.42769 -297.059946) (xy 274.468193 -297.087902) (xy 274.503686 -297.121994) (xy 274.533251 -297.161338)
			(xy 274.556122 -297.204915) (xy 274.571706 -297.251596) (xy 274.579601 -297.300173) (xy 274.580096 -297.32478)
			(xy 275.868904 -297.32478) (xy 275.872864 -297.275726) (xy 275.884641 -297.227942) (xy 275.903932 -297.182666)
			(xy 275.930235 -297.14107) (xy 275.96287 -297.104233) (xy 276.000991 -297.073108) (xy 276.043612 -297.048501)
			(xy 276.089628 -297.031049) (xy 276.137847 -297.021205) (xy 276.187022 -297.019224) (xy 276.235877 -297.025156)
			(xy 276.283148 -297.038848) (xy 276.32761 -297.059946) (xy 276.368113 -297.087902) (xy 276.403606 -297.121994)
			(xy 276.433171 -297.161338) (xy 276.456042 -297.204915) (xy 276.471626 -297.251596) (xy 276.479521 -297.300173)
			(xy 276.480016 -297.32478) (xy 276.819118 -297.32478) (xy 276.823078 -297.275726) (xy 276.834855 -297.227942)
			(xy 276.854146 -297.182666) (xy 276.880449 -297.14107) (xy 276.913084 -297.104233) (xy 276.951205 -297.073108)
			(xy 276.993826 -297.048501) (xy 277.039842 -297.031049) (xy 277.088061 -297.021205) (xy 277.137236 -297.019224)
			(xy 277.186091 -297.025156) (xy 277.233362 -297.038848) (xy 277.277824 -297.059946) (xy 277.318327 -297.087902)
			(xy 277.35382 -297.121994) (xy 277.383385 -297.161338) (xy 277.406256 -297.204915) (xy 277.42184 -297.251596)
			(xy 277.429735 -297.300173) (xy 277.43023 -297.32478) (xy 277.769078 -297.32478) (xy 277.773038 -297.275726)
			(xy 277.784815 -297.227942) (xy 277.804106 -297.182666) (xy 277.830409 -297.14107) (xy 277.863044 -297.104233)
			(xy 277.901165 -297.073108) (xy 277.943786 -297.048501) (xy 277.989802 -297.031049) (xy 278.038021 -297.021205)
			(xy 278.087196 -297.019224) (xy 278.136051 -297.025156) (xy 278.183322 -297.038848) (xy 278.227784 -297.059946)
			(xy 278.268287 -297.087902) (xy 278.30378 -297.121994) (xy 278.333345 -297.161338) (xy 278.356216 -297.204915)
			(xy 278.3718 -297.251596) (xy 278.379695 -297.300173) (xy 278.38019 -297.32478) (xy 278.379695 -297.349387)
			(xy 278.3718 -297.397964) (xy 278.356216 -297.444645) (xy 278.333345 -297.488222) (xy 278.30378 -297.527566)
			(xy 278.268287 -297.561658) (xy 278.227784 -297.589614) (xy 278.183322 -297.610712) (xy 278.136051 -297.624404)
			(xy 278.087196 -297.630336) (xy 278.038021 -297.628355) (xy 277.989802 -297.618511) (xy 277.943786 -297.601059)
			(xy 277.901165 -297.576452) (xy 277.863044 -297.545327) (xy 277.830409 -297.50849) (xy 277.804106 -297.466894)
			(xy 277.784815 -297.421618) (xy 277.773038 -297.373834) (xy 277.769078 -297.32478) (xy 277.43023 -297.32478)
			(xy 277.429735 -297.349387) (xy 277.42184 -297.397964) (xy 277.406256 -297.444645) (xy 277.383385 -297.488222)
			(xy 277.35382 -297.527566) (xy 277.318327 -297.561658) (xy 277.277824 -297.589614) (xy 277.233362 -297.610712)
			(xy 277.186091 -297.624404) (xy 277.137236 -297.630336) (xy 277.088061 -297.628355) (xy 277.039842 -297.618511)
			(xy 276.993826 -297.601059) (xy 276.951205 -297.576452) (xy 276.913084 -297.545327) (xy 276.880449 -297.50849)
			(xy 276.854146 -297.466894) (xy 276.834855 -297.421618) (xy 276.823078 -297.373834) (xy 276.819118 -297.32478)
			(xy 276.480016 -297.32478) (xy 276.479521 -297.349387) (xy 276.471626 -297.397964) (xy 276.456042 -297.444645)
			(xy 276.433171 -297.488222) (xy 276.403606 -297.527566) (xy 276.368113 -297.561658) (xy 276.32761 -297.589614)
			(xy 276.283148 -297.610712) (xy 276.235877 -297.624404) (xy 276.187022 -297.630336) (xy 276.137847 -297.628355)
			(xy 276.089628 -297.618511) (xy 276.043612 -297.601059) (xy 276.000991 -297.576452) (xy 275.96287 -297.545327)
			(xy 275.930235 -297.50849) (xy 275.903932 -297.466894) (xy 275.884641 -297.421618) (xy 275.872864 -297.373834)
			(xy 275.868904 -297.32478) (xy 274.580096 -297.32478) (xy 274.579601 -297.349387) (xy 274.571706 -297.397964)
			(xy 274.556122 -297.444645) (xy 274.533251 -297.488222) (xy 274.503686 -297.527566) (xy 274.468193 -297.561658)
			(xy 274.42769 -297.589614) (xy 274.383228 -297.610712) (xy 274.335957 -297.624404) (xy 274.287102 -297.630336)
			(xy 274.237927 -297.628355) (xy 274.189708 -297.618511) (xy 274.143692 -297.601059) (xy 274.101071 -297.576452)
			(xy 274.06295 -297.545327) (xy 274.030315 -297.50849) (xy 274.004012 -297.466894) (xy 273.984721 -297.421618)
			(xy 273.972944 -297.373834) (xy 273.968984 -297.32478) (xy 271.730216 -297.32478) (xy 271.729721 -297.349387)
			(xy 271.721826 -297.397964) (xy 271.706242 -297.444645) (xy 271.683371 -297.488222) (xy 271.653806 -297.527566)
			(xy 271.618313 -297.561658) (xy 271.57781 -297.589614) (xy 271.533348 -297.610712) (xy 271.486077 -297.624404)
			(xy 271.437222 -297.630336) (xy 271.388047 -297.628355) (xy 271.339828 -297.618511) (xy 271.293812 -297.601059)
			(xy 271.251191 -297.576452) (xy 271.21307 -297.545327) (xy 271.180435 -297.50849) (xy 271.154132 -297.466894)
			(xy 271.134841 -297.421618) (xy 271.123064 -297.373834) (xy 271.119104 -297.32478) (xy 270.780002 -297.32478)
			(xy 270.779507 -297.349387) (xy 270.771612 -297.397964) (xy 270.756028 -297.444645) (xy 270.733157 -297.488222)
			(xy 270.703592 -297.527566) (xy 270.668099 -297.561658) (xy 270.627596 -297.589614) (xy 270.583134 -297.610712)
			(xy 270.535863 -297.624404) (xy 270.487008 -297.630336) (xy 270.437833 -297.628355) (xy 270.389614 -297.618511)
			(xy 270.343598 -297.601059) (xy 270.300977 -297.576452) (xy 270.262856 -297.545327) (xy 270.230221 -297.50849)
			(xy 270.203918 -297.466894) (xy 270.184627 -297.421618) (xy 270.17285 -297.373834) (xy 270.16889 -297.32478)
			(xy 269.854705 -297.32478) (xy 269.854705 -297.350789) (xy 269.846573 -297.402126) (xy 269.830511 -297.451559)
			(xy 269.806913 -297.497871) (xy 269.77636 -297.539921) (xy 269.739606 -297.576673) (xy 269.697554 -297.607223)
			(xy 269.651241 -297.630819) (xy 269.601807 -297.646878) (xy 269.550469 -297.655006) (xy 269.52448 -297.655488)
			(xy 268.57452 -297.655488) (xy 268.550146 -297.655084) (xy 268.501926 -297.647935) (xy 268.455276 -297.63379)
			(xy 268.411206 -297.612953) (xy 268.370669 -297.585877) (xy 268.334544 -297.553147) (xy 268.318742 -297.534584)
			(xy 268.31163 -297.525948) (xy 268.292072 -297.51655) (xy 268.192758 -297.513756) (xy 268.172946 -297.522392)
			(xy 268.165326 -297.53052) (xy 268.14784 -297.548945) (xy 268.107876 -297.580296) (xy 268.063274 -297.604598)
			(xy 268.015264 -297.62118) (xy 267.965171 -297.629585) (xy 267.939774 -297.630088) (xy 267.914518 -297.629604)
			(xy 267.864697 -297.621287) (xy 267.816923 -297.604882) (xy 267.772502 -297.580839) (xy 267.732643 -297.549813)
			(xy 267.698434 -297.512649) (xy 267.670808 -297.470362) (xy 267.650519 -297.424104) (xy 267.63812 -297.375139)
			(xy 267.633949 -297.3248) (xy 265.780774 -297.3248) (xy 265.780774 -297.997626) (xy 265.780659 -298.002722)
			(xy 265.778607 -298.012706) (xy 265.77671 -298.017438) (xy 265.770106 -298.032932) (xy 265.76831 -298.037619)
			(xy 265.766398 -298.047471) (xy 265.766296 -298.05249) (xy 265.766296 -298.118276) (xy 265.766733 -298.12834)
			(xy 265.774466 -298.146925) (xy 265.781282 -298.154344) (xy 265.906504 -298.279566) (xy 265.907012 -298.280074)
			(xy 265.914392 -298.286661) (xy 265.932691 -298.294122) (xy 265.942572 -298.294552) (xy 269.164054 -298.294552)
		)
		(stroke
			(width 0)
			(type solid)
		)
		(fill yes)
		(layer "In13.Cu")
		(net "PCEPLL2_VDDA18_PEX2")
	)
	(gr_poly
		(pts
			(xy 268.332712 -300.88078) (xy 268.33938 -300.880585) (xy 268.352254 -300.877112) (xy 268.358112 -300.873922)
			(xy 268.362938 -300.871128) (xy 268.36624 -300.868588) (xy 268.388486 -300.851179) (xy 268.437684 -300.823428)
			(xy 268.490882 -300.804441) (xy 268.546532 -300.79477) (xy 268.574774 -300.794166) (xy 268.588364 -300.794337)
			(xy 268.615449 -300.796628) (xy 268.628876 -300.798738) (xy 268.641068 -300.80077) (xy 268.663674 -300.793912)
			(xy 268.740128 -300.72076) (xy 268.748002 -300.698408) (xy 268.746732 -300.68647) (xy 268.745679 -300.677362)
			(xy 268.744537 -300.659062) (xy 268.744446 -300.649894) (xy 268.744917 -300.625902) (xy 268.752424 -300.578508)
			(xy 268.767251 -300.532872) (xy 268.789034 -300.490117) (xy 268.817237 -300.451295) (xy 268.851165 -300.417363)
			(xy 268.889983 -300.389155) (xy 268.932735 -300.367366) (xy 268.978369 -300.352533) (xy 269.025762 -300.34502)
			(xy 269.049754 -300.344586) (xy 269.063868 -300.344708) (xy 269.091981 -300.347253) (xy 269.105888 -300.349666)
			(xy 269.118588 -300.352206) (xy 269.14221 -300.34484) (xy 269.219426 -300.26737) (xy 269.226792 -300.243748)
			(xy 269.224506 -300.231302) (xy 269.22202 -300.217337) (xy 269.219347 -300.189097) (xy 269.219172 -300.174914)
			(xy 269.219694 -300.149659) (xy 269.228007 -300.099837) (xy 269.244408 -300.052063) (xy 269.268449 -300.00764)
			(xy 269.299473 -299.96778) (xy 269.336635 -299.93357) (xy 269.378921 -299.905944) (xy 269.425177 -299.885654)
			(xy 269.474142 -299.873254) (xy 269.52448 -299.869083) (xy 269.574818 -299.873254) (xy 269.623783 -299.885654)
			(xy 269.670039 -299.905944) (xy 269.712325 -299.93357) (xy 269.749487 -299.96778) (xy 269.780511 -300.00764)
			(xy 269.804552 -300.052063) (xy 269.820953 -300.099837) (xy 269.829266 -300.149659) (xy 269.829788 -300.174914)
			(xy 269.829601 -300.189096) (xy 269.826926 -300.217335) (xy 269.824454 -300.231302) (xy 269.822168 -300.243748)
			(xy 269.829534 -300.267624) (xy 269.90675 -300.34484) (xy 269.93088 -300.352206) (xy 269.943072 -300.34992)
			(xy 269.9571 -300.347429) (xy 269.985468 -300.344762) (xy 269.999714 -300.344586) (xy 270.013896 -300.344773)
			(xy 270.042135 -300.347448) (xy 270.056102 -300.34992) (xy 270.068548 -300.352206) (xy 270.09217 -300.34484)
			(xy 270.16964 -300.26737) (xy 270.177006 -300.243748) (xy 270.17472 -300.231302) (xy 270.172234 -300.217337)
			(xy 270.169561 -300.189097) (xy 270.169386 -300.174914) (xy 270.169908 -300.149659) (xy 270.178221 -300.099837)
			(xy 270.194622 -300.052063) (xy 270.218663 -300.00764) (xy 270.249687 -299.96778) (xy 270.286849 -299.93357)
			(xy 270.329135 -299.905944) (xy 270.375391 -299.885654) (xy 270.424356 -299.873254) (xy 270.474694 -299.869083)
			(xy 270.525032 -299.873254) (xy 270.573997 -299.885654) (xy 270.620253 -299.905944) (xy 270.662539 -299.93357)
			(xy 270.699701 -299.96778) (xy 270.730725 -300.00764) (xy 270.754766 -300.052063) (xy 270.771167 -300.099837)
			(xy 270.77948 -300.149659) (xy 270.780002 -300.174914) (xy 270.779815 -300.189096) (xy 270.77714 -300.217335)
			(xy 270.774668 -300.231302) (xy 270.772382 -300.243748) (xy 270.779748 -300.267624) (xy 270.856964 -300.34484)
			(xy 270.881094 -300.352206) (xy 270.893286 -300.34992) (xy 270.907314 -300.347425) (xy 270.935681 -300.34475)
			(xy 270.949928 -300.344586) (xy 270.964111 -300.344769) (xy 270.992351 -300.347436) (xy 271.006316 -300.34992)
			(xy 271.018762 -300.352206) (xy 271.042384 -300.34484) (xy 271.119854 -300.26737) (xy 271.12722 -300.243748)
			(xy 271.124934 -300.231302) (xy 271.122448 -300.217337) (xy 271.119775 -300.189097) (xy 271.1196 -300.174914)
			(xy 271.120122 -300.149659) (xy 271.128435 -300.099837) (xy 271.144836 -300.052063) (xy 271.168877 -300.00764)
			(xy 271.199901 -299.96778) (xy 271.237063 -299.93357) (xy 271.279349 -299.905944) (xy 271.325605 -299.885654)
			(xy 271.37457 -299.873254) (xy 271.424908 -299.869083) (xy 271.475246 -299.873254) (xy 271.524211 -299.885654)
			(xy 271.570467 -299.905944) (xy 271.612753 -299.93357) (xy 271.649915 -299.96778) (xy 271.680939 -300.00764)
			(xy 271.70498 -300.052063) (xy 271.721381 -300.099837) (xy 271.729694 -300.149659) (xy 271.730216 -300.174914)
			(xy 271.730029 -300.189096) (xy 271.727354 -300.217335) (xy 271.724882 -300.231302) (xy 271.722596 -300.243748)
			(xy 271.729962 -300.26737) (xy 271.807432 -300.34484) (xy 271.831054 -300.352206) (xy 271.8435 -300.34992)
			(xy 271.857465 -300.347434) (xy 271.885705 -300.344761) (xy 271.899888 -300.344586) (xy 271.91407 -300.344772)
			(xy 271.94231 -300.347444) (xy 271.956276 -300.34992) (xy 271.968722 -300.352206) (xy 271.992344 -300.34484)
			(xy 272.069814 -300.26737) (xy 272.07718 -300.243748) (xy 272.074894 -300.231302) (xy 272.072408 -300.217337)
			(xy 272.069735 -300.189097) (xy 272.06956 -300.174914) (xy 272.070082 -300.149659) (xy 272.078395 -300.099837)
			(xy 272.094796 -300.052063) (xy 272.118837 -300.00764) (xy 272.149861 -299.96778) (xy 272.187023 -299.93357)
			(xy 272.229309 -299.905944) (xy 272.275565 -299.885654) (xy 272.32453 -299.873254) (xy 272.374868 -299.869083)
			(xy 272.425206 -299.873254) (xy 272.474171 -299.885654) (xy 272.520427 -299.905944) (xy 272.562713 -299.93357)
			(xy 272.599875 -299.96778) (xy 272.630899 -300.00764) (xy 272.65494 -300.052063) (xy 272.671341 -300.099837)
			(xy 272.679654 -300.149659) (xy 272.680176 -300.174914) (xy 272.679989 -300.189096) (xy 272.677314 -300.217335)
			(xy 272.674842 -300.231302) (xy 272.672556 -300.243748) (xy 272.679922 -300.26737) (xy 272.757392 -300.34484)
			(xy 272.781014 -300.352206) (xy 272.79346 -300.34992) (xy 272.807425 -300.347437) (xy 272.835665 -300.344769)
			(xy 272.849848 -300.344586) (xy 272.864031 -300.34477) (xy 272.892271 -300.347439) (xy 272.906236 -300.34992)
			(xy 272.918682 -300.352206) (xy 272.942304 -300.34484) (xy 273.019774 -300.26737) (xy 273.02714 -300.243748)
			(xy 273.024854 -300.231302) (xy 273.022368 -300.217337) (xy 273.019694 -300.189097) (xy 273.01952 -300.174914)
			(xy 273.020042 -300.149659) (xy 273.028355 -300.099837) (xy 273.044756 -300.052063) (xy 273.068797 -300.00764)
			(xy 273.099821 -299.96778) (xy 273.136983 -299.93357) (xy 273.179269 -299.905944) (xy 273.225525 -299.885654)
			(xy 273.27449 -299.873254) (xy 273.324828 -299.869083) (xy 273.375166 -299.873254) (xy 273.424131 -299.885654)
			(xy 273.470387 -299.905944) (xy 273.512673 -299.93357) (xy 273.549835 -299.96778) (xy 273.580859 -300.00764)
			(xy 273.6049 -300.052063) (xy 273.621301 -300.099837) (xy 273.629614 -300.149659) (xy 273.630136 -300.174914)
			(xy 273.629949 -300.189096) (xy 273.627274 -300.217335) (xy 273.624802 -300.231302) (xy 273.622516 -300.243748)
			(xy 273.629882 -300.26737) (xy 273.707352 -300.34484) (xy 273.730974 -300.352206) (xy 273.74342 -300.34992)
			(xy 273.757385 -300.347435) (xy 273.785625 -300.344764) (xy 273.799808 -300.344586) (xy 273.823799 -300.345057)
			(xy 273.87119 -300.352564) (xy 273.916823 -300.367392) (xy 273.959575 -300.389176) (xy 273.998393 -300.41738)
			(xy 274.032322 -300.451308) (xy 274.060525 -300.490126) (xy 274.082308 -300.532878) (xy 274.097136 -300.578512)
			(xy 274.104643 -300.625903) (xy 274.105116 -300.649894) (xy 274.103338 -300.681644) (xy 274.102322 -300.692566)
			(xy 274.108926 -300.712886) (xy 274.166838 -300.777148) (xy 274.174384 -300.784653) (xy 274.193804 -300.7933)
			(xy 274.20443 -300.793912) (xy 274.275042 -300.793912) (xy 274.288632 -300.794083) (xy 274.315717 -300.796375)
			(xy 274.329144 -300.798484) (xy 274.341082 -300.800516) (xy 274.363688 -300.793404) (xy 274.440142 -300.720506)
			(xy 274.448016 -300.698154) (xy 274.446746 -300.686216) (xy 274.445698 -300.677172) (xy 274.444555 -300.658998)
			(xy 274.44446 -300.649894) (xy 274.444931 -300.625902) (xy 274.452438 -300.578509) (xy 274.467265 -300.532874)
			(xy 274.489049 -300.49012) (xy 274.517252 -300.451299) (xy 274.55118 -300.417368) (xy 274.589998 -300.389162)
			(xy 274.63275 -300.367375) (xy 274.678384 -300.352544) (xy 274.725776 -300.345033) (xy 274.749768 -300.344586)
			(xy 274.763951 -300.344771) (xy 274.79219 -300.347442) (xy 274.806156 -300.34992) (xy 274.818602 -300.352206)
			(xy 274.842224 -300.34484) (xy 274.919694 -300.26737) (xy 274.92706 -300.243748) (xy 274.924774 -300.231302)
			(xy 274.922288 -300.217337) (xy 274.919614 -300.189097) (xy 274.91944 -300.174914) (xy 274.919626 -300.160731)
			(xy 274.922298 -300.132492) (xy 274.924774 -300.118526) (xy 274.92706 -300.10608) (xy 274.919694 -300.082458)
			(xy 274.842224 -300.004988) (xy 274.818602 -299.997622) (xy 274.806156 -299.999908) (xy 274.792191 -300.002392)
			(xy 274.763951 -300.00506) (xy 274.749768 -300.005242) (xy 274.725777 -300.004769) (xy 274.678388 -299.997259)
			(xy 274.632756 -299.982429) (xy 274.590005 -299.960645) (xy 274.551188 -299.932441) (xy 274.51726 -299.898514)
			(xy 274.489056 -299.859697) (xy 274.467271 -299.816946) (xy 274.452441 -299.771314) (xy 274.444931 -299.723925)
			(xy 274.44446 -299.699934) (xy 274.444639 -299.685688) (xy 274.447313 -299.657321) (xy 274.449794 -299.643292)
			(xy 274.45208 -299.6311) (xy 274.444714 -299.60697) (xy 274.367498 -299.529754) (xy 274.343622 -299.522388)
			(xy 274.331176 -299.524674) (xy 274.317211 -299.527159) (xy 274.288971 -299.52983) (xy 274.274788 -299.530008)
			(xy 274.249967 -299.529521) (xy 274.20098 -299.521488) (xy 274.153938 -299.505636) (xy 274.11008 -299.482382)
			(xy 274.070562 -299.452339) (xy 274.036425 -299.416299) (xy 274.008568 -299.37521) (xy 273.987726 -299.330156)
			(xy 273.974447 -299.282324) (xy 273.969081 -299.232974) (xy 273.97177 -299.183405) (xy 273.982442 -299.134925)
			(xy 274.000818 -299.08881) (xy 274.026411 -299.046275) (xy 274.058549 -299.008441) (xy 274.096384 -298.976304)
			(xy 274.13892 -298.950712) (xy 274.185036 -298.932339) (xy 274.233517 -298.921668) (xy 274.283086 -298.918981)
			(xy 274.332436 -298.924349) (xy 274.380268 -298.93763) (xy 274.425321 -298.958474) (xy 274.466408 -298.986333)
			(xy 274.502447 -299.020471) (xy 274.532488 -299.05999) (xy 274.555741 -299.103849) (xy 274.571591 -299.150892)
			(xy 274.579622 -299.199879) (xy 274.580096 -299.2247) (xy 274.580093 -299.224954) (xy 275.868904 -299.224954)
			(xy 275.872864 -299.1759) (xy 275.884641 -299.128116) (xy 275.903932 -299.08284) (xy 275.930235 -299.041244)
			(xy 275.96287 -299.004407) (xy 276.000991 -298.973282) (xy 276.043612 -298.948675) (xy 276.089628 -298.931223)
			(xy 276.137847 -298.921379) (xy 276.187022 -298.919398) (xy 276.235877 -298.92533) (xy 276.283148 -298.939022)
			(xy 276.32761 -298.96012) (xy 276.368113 -298.988076) (xy 276.403606 -299.022168) (xy 276.433171 -299.061512)
			(xy 276.456042 -299.105089) (xy 276.471626 -299.15177) (xy 276.479521 -299.200347) (xy 276.480016 -299.224954)
			(xy 276.819118 -299.224954) (xy 276.823078 -299.1759) (xy 276.834855 -299.128116) (xy 276.854146 -299.08284)
			(xy 276.880449 -299.041244) (xy 276.913084 -299.004407) (xy 276.951205 -298.973282) (xy 276.993826 -298.948675)
			(xy 277.039842 -298.931223) (xy 277.088061 -298.921379) (xy 277.137236 -298.919398) (xy 277.186091 -298.92533)
			(xy 277.233362 -298.939022) (xy 277.277824 -298.96012) (xy 277.318327 -298.988076) (xy 277.35382 -299.022168)
			(xy 277.383385 -299.061512) (xy 277.406256 -299.105089) (xy 277.42184 -299.15177) (xy 277.429735 -299.200347)
			(xy 277.43023 -299.224954) (xy 277.769078 -299.224954) (xy 277.773038 -299.1759) (xy 277.784815 -299.128116)
			(xy 277.804106 -299.08284) (xy 277.830409 -299.041244) (xy 277.863044 -299.004407) (xy 277.901165 -298.973282)
			(xy 277.943786 -298.948675) (xy 277.989802 -298.931223) (xy 278.038021 -298.921379) (xy 278.087196 -298.919398)
			(xy 278.136051 -298.92533) (xy 278.183322 -298.939022) (xy 278.227784 -298.96012) (xy 278.268287 -298.988076)
			(xy 278.30378 -299.022168) (xy 278.333345 -299.061512) (xy 278.356216 -299.105089) (xy 278.3718 -299.15177)
			(xy 278.379695 -299.200347) (xy 278.38019 -299.224954) (xy 278.379695 -299.249561) (xy 278.3718 -299.298138)
			(xy 278.356216 -299.344819) (xy 278.333345 -299.388396) (xy 278.30378 -299.42774) (xy 278.268287 -299.461832)
			(xy 278.227784 -299.489788) (xy 278.183322 -299.510886) (xy 278.136051 -299.524578) (xy 278.087196 -299.53051)
			(xy 278.038021 -299.528529) (xy 277.989802 -299.518685) (xy 277.943786 -299.501233) (xy 277.901165 -299.476626)
			(xy 277.863044 -299.445501) (xy 277.830409 -299.408664) (xy 277.804106 -299.367068) (xy 277.784815 -299.321792)
			(xy 277.773038 -299.274008) (xy 277.769078 -299.224954) (xy 277.43023 -299.224954) (xy 277.429735 -299.249561)
			(xy 277.42184 -299.298138) (xy 277.406256 -299.344819) (xy 277.383385 -299.388396) (xy 277.35382 -299.42774)
			(xy 277.318327 -299.461832) (xy 277.277824 -299.489788) (xy 277.233362 -299.510886) (xy 277.186091 -299.524578)
			(xy 277.137236 -299.53051) (xy 277.088061 -299.528529) (xy 277.039842 -299.518685) (xy 276.993826 -299.501233)
			(xy 276.951205 -299.476626) (xy 276.913084 -299.445501) (xy 276.880449 -299.408664) (xy 276.854146 -299.367068)
			(xy 276.834855 -299.321792) (xy 276.823078 -299.274008) (xy 276.819118 -299.224954) (xy 276.480016 -299.224954)
			(xy 276.479521 -299.249561) (xy 276.471626 -299.298138) (xy 276.456042 -299.344819) (xy 276.433171 -299.388396)
			(xy 276.403606 -299.42774) (xy 276.368113 -299.461832) (xy 276.32761 -299.489788) (xy 276.283148 -299.510886)
			(xy 276.235877 -299.524578) (xy 276.187022 -299.53051) (xy 276.137847 -299.528529) (xy 276.089628 -299.518685)
			(xy 276.043612 -299.501233) (xy 276.000991 -299.476626) (xy 275.96287 -299.445501) (xy 275.930235 -299.408664)
			(xy 275.903932 -299.367068) (xy 275.884641 -299.321792) (xy 275.872864 -299.274008) (xy 275.868904 -299.224954)
			(xy 274.580093 -299.224954) (xy 274.579921 -299.238946) (xy 274.577253 -299.267314) (xy 274.574762 -299.281342)
			(xy 274.572476 -299.293534) (xy 274.579842 -299.317664) (xy 274.657058 -299.39488) (xy 274.680934 -299.402246)
			(xy 274.69338 -299.39996) (xy 274.707345 -299.397473) (xy 274.735585 -299.394798) (xy 274.749768 -299.394626)
			(xy 274.773762 -299.39507) (xy 274.821159 -299.402573) (xy 274.866799 -299.417399) (xy 274.909557 -299.439183)
			(xy 274.94838 -299.467389) (xy 274.982313 -299.501321) (xy 275.010518 -299.540145) (xy 275.032302 -299.582903)
			(xy 275.047128 -299.628543) (xy 275.05463 -299.67594) (xy 275.055076 -299.699934) (xy 275.054892 -299.714117)
			(xy 275.052225 -299.742357) (xy 275.049742 -299.756322) (xy 275.047456 -299.768768) (xy 275.054822 -299.79239)
			(xy 275.132292 -299.86986) (xy 275.155914 -299.877226) (xy 275.16836 -299.87494) (xy 275.182325 -299.872457)
			(xy 275.210565 -299.869789) (xy 275.224748 -299.869606) (xy 275.248736 -299.87008) (xy 275.296121 -299.877592)
			(xy 275.341748 -299.892424) (xy 275.384493 -299.914211) (xy 275.423304 -299.942415) (xy 275.457225 -299.976343)
			(xy 275.485422 -300.01516) (xy 275.5072 -300.057909) (xy 275.522022 -300.103539) (xy 275.529525 -300.150926)
			(xy 275.530056 -300.174914) (xy 275.529869 -300.189096) (xy 275.527195 -300.217335) (xy 275.524722 -300.231302)
			(xy 275.522436 -300.243748) (xy 275.529802 -300.26737) (xy 275.607272 -300.34484) (xy 275.630894 -300.352206)
			(xy 275.64334 -300.34992) (xy 275.657305 -300.347436) (xy 275.685545 -300.344767) (xy 275.699728 -300.344586)
			(xy 275.713911 -300.344769) (xy 275.742151 -300.347436) (xy 275.756116 -300.34992) (xy 275.768562 -300.352206)
			(xy 275.792184 -300.34484) (xy 275.869654 -300.26737) (xy 275.87702 -300.243748) (xy 275.874734 -300.231302)
			(xy 275.872248 -300.217337) (xy 275.869575 -300.189097) (xy 275.8694 -300.174914) (xy 275.869885 -300.150094)
			(xy 275.877913 -300.101107) (xy 275.893762 -300.054064) (xy 275.917012 -300.010205) (xy 275.947051 -299.970685)
			(xy 275.983089 -299.936546) (xy 276.024175 -299.908686) (xy 276.069226 -299.887841) (xy 276.117057 -299.874559)
			(xy 276.166406 -299.869189) (xy 276.215974 -299.871875) (xy 276.264455 -299.882544) (xy 276.31057 -299.900917)
			(xy 276.353106 -299.926507) (xy 276.390942 -299.958643) (xy 276.42308 -299.996476) (xy 276.448674 -300.03901)
			(xy 276.467049 -300.085124) (xy 276.477722 -300.133604) (xy 276.479963 -300.174914) (xy 276.819118 -300.174914)
			(xy 276.823078 -300.12586) (xy 276.834855 -300.078076) (xy 276.854146 -300.0328) (xy 276.880449 -299.991204)
			(xy 276.913084 -299.954367) (xy 276.951205 -299.923242) (xy 276.993826 -299.898635) (xy 277.039842 -299.881183)
			(xy 277.088061 -299.871339) (xy 277.137236 -299.869358) (xy 277.186091 -299.87529) (xy 277.233362 -299.888982)
			(xy 277.277824 -299.91008) (xy 277.318327 -299.938036) (xy 277.35382 -299.972128) (xy 277.383385 -300.011472)
			(xy 277.406256 -300.055049) (xy 277.42184 -300.10173) (xy 277.429735 -300.150307) (xy 277.43023 -300.174914)
			(xy 277.769078 -300.174914) (xy 277.773038 -300.12586) (xy 277.784815 -300.078076) (xy 277.804106 -300.0328)
			(xy 277.830409 -299.991204) (xy 277.863044 -299.954367) (xy 277.901165 -299.923242) (xy 277.943786 -299.898635)
			(xy 277.989802 -299.881183) (xy 278.038021 -299.871339) (xy 278.087196 -299.869358) (xy 278.136051 -299.87529)
			(xy 278.183322 -299.888982) (xy 278.227784 -299.91008) (xy 278.268287 -299.938036) (xy 278.30378 -299.972128)
			(xy 278.333345 -300.011472) (xy 278.356216 -300.055049) (xy 278.3718 -300.10173) (xy 278.379695 -300.150307)
			(xy 278.38019 -300.174914) (xy 278.379695 -300.199521) (xy 278.3718 -300.248098) (xy 278.356216 -300.294779)
			(xy 278.333345 -300.338356) (xy 278.30378 -300.3777) (xy 278.268287 -300.411792) (xy 278.227784 -300.439748)
			(xy 278.183322 -300.460846) (xy 278.136051 -300.474538) (xy 278.087196 -300.48047) (xy 278.038021 -300.478489)
			(xy 277.989802 -300.468645) (xy 277.943786 -300.451193) (xy 277.901165 -300.426586) (xy 277.863044 -300.395461)
			(xy 277.830409 -300.358624) (xy 277.804106 -300.317028) (xy 277.784815 -300.271752) (xy 277.773038 -300.223968)
			(xy 277.769078 -300.174914) (xy 277.43023 -300.174914) (xy 277.429735 -300.199521) (xy 277.42184 -300.248098)
			(xy 277.406256 -300.294779) (xy 277.383385 -300.338356) (xy 277.35382 -300.3777) (xy 277.318327 -300.411792)
			(xy 277.277824 -300.439748) (xy 277.233362 -300.460846) (xy 277.186091 -300.474538) (xy 277.137236 -300.48047)
			(xy 277.088061 -300.478489) (xy 277.039842 -300.468645) (xy 276.993826 -300.451193) (xy 276.951205 -300.426586)
			(xy 276.913084 -300.395461) (xy 276.880449 -300.358624) (xy 276.854146 -300.317028) (xy 276.834855 -300.271752)
			(xy 276.823078 -300.223968) (xy 276.819118 -300.174914) (xy 276.479963 -300.174914) (xy 276.480411 -300.183172)
			(xy 276.475046 -300.232521) (xy 276.461767 -300.280353) (xy 276.440925 -300.325406) (xy 276.413068 -300.366494)
			(xy 276.378932 -300.402534) (xy 276.339414 -300.432576) (xy 276.295556 -300.45583) (xy 276.248515 -300.471681)
			(xy 276.199528 -300.479713) (xy 276.174708 -300.480222) (xy 276.160526 -300.480036) (xy 276.132286 -300.477363)
			(xy 276.11832 -300.474888) (xy 276.105874 -300.472602) (xy 276.082252 -300.479968) (xy 276.004782 -300.557438)
			(xy 275.997416 -300.58106) (xy 275.999702 -300.593506) (xy 276.002187 -300.607471) (xy 276.00486 -300.635711)
			(xy 276.005036 -300.649894) (xy 276.004944 -300.659062) (xy 276.003801 -300.677362) (xy 276.00275 -300.68647)
			(xy 276.00148 -300.698408) (xy 276.009354 -300.72076) (xy 276.085808 -300.793912) (xy 276.108414 -300.80077)
			(xy 276.120606 -300.798738) (xy 276.134031 -300.796614) (xy 276.161117 -300.794327) (xy 276.174708 -300.794166)
			(xy 276.202904 -300.794785) (xy 276.258465 -300.804435) (xy 276.311591 -300.823354) (xy 276.360746 -300.850994)
			(xy 276.382988 -300.868334) (xy 276.386544 -300.871128) (xy 276.392386 -300.87443) (xy 276.39811 -300.877389)
			(xy 276.410583 -300.880605) (xy 276.417024 -300.88078) (xy 276.88286 -300.88078) (xy 276.889526 -300.880579)
			(xy 276.902394 -300.877095) (xy 276.90826 -300.873922) (xy 276.913086 -300.871128) (xy 276.916388 -300.868588)
			(xy 276.938636 -300.851183) (xy 276.987834 -300.823439) (xy 277.041032 -300.804459) (xy 277.096682 -300.794797)
			(xy 277.124922 -300.794166) (xy 277.153117 -300.794786) (xy 277.208678 -300.804439) (xy 277.261802 -300.823359)
			(xy 277.310956 -300.851) (xy 277.333202 -300.868334) (xy 277.336758 -300.871128) (xy 277.3426 -300.87443)
			(xy 277.348324 -300.877387) (xy 277.360797 -300.880599) (xy 277.367238 -300.88078) (xy 277.83282 -300.88078)
			(xy 277.839487 -300.880584) (xy 277.85236 -300.877109) (xy 277.85822 -300.873922) (xy 277.863046 -300.871128)
			(xy 277.866348 -300.868588) (xy 277.888595 -300.85118) (xy 277.937792 -300.82343) (xy 277.99099 -300.804444)
			(xy 278.046641 -300.794775) (xy 278.074882 -300.794166) (xy 278.103078 -300.794783) (xy 278.158642 -300.804429)
			(xy 278.21177 -300.823344) (xy 278.260929 -300.850982) (xy 278.283162 -300.868334) (xy 278.286718 -300.871128)
			(xy 278.29256 -300.87443) (xy 278.298283 -300.877392) (xy 278.310756 -300.880614) (xy 278.317198 -300.88078)
			(xy 278.78278 -300.88078) (xy 278.789449 -300.880589) (xy 278.802327 -300.877123) (xy 278.80818 -300.873922)
			(xy 278.813006 -300.871128) (xy 278.816308 -300.868588) (xy 278.838554 -300.851177) (xy 278.88775 -300.823421)
			(xy 278.940948 -300.804429) (xy 278.9966 -300.794753) (xy 279.024842 -300.794166) (xy 279.050208 -300.794669)
			(xy 279.100341 -300.802444) (xy 279.124664 -300.80966) (xy 279.138126 -300.813978) (xy 279.165558 -300.807374)
			(xy 279.218644 -300.754288) (xy 279.219152 -300.75378) (xy 279.225739 -300.7464) (xy 279.233202 -300.728102)
			(xy 279.23363 -300.71822) (xy 279.23363 -300.59376) (xy 279.233066 -300.582133) (xy 279.222894 -300.56122)
			(xy 279.214072 -300.553628) (xy 279.141174 -300.496986) (xy 279.118314 -300.492414) (xy 279.106884 -300.495208)
			(xy 279.086719 -300.500051) (xy 279.045577 -300.505268) (xy 279.024842 -300.505622) (xy 278.998849 -300.505142)
			(xy 278.947504 -300.497016) (xy 278.898061 -300.480956) (xy 278.85174 -300.45736) (xy 278.809681 -300.426807)
			(xy 278.77292 -300.390051) (xy 278.742362 -300.347995) (xy 278.71876 -300.301677) (xy 278.702694 -300.252237)
			(xy 278.694561 -300.200892) (xy 278.694561 -300.148908) (xy 278.702694 -300.097563) (xy 278.71876 -300.048123)
			(xy 278.742362 -300.001805) (xy 278.77292 -299.959749) (xy 278.809681 -299.922993) (xy 278.85174 -299.89244)
			(xy 278.898061 -299.868844) (xy 278.947504 -299.852784) (xy 278.998849 -299.844658) (xy 279.024842 -299.844206)
			(xy 279.045515 -299.844555) (xy 279.08653 -299.849775) (xy 279.10663 -299.85462) (xy 279.112458 -299.85593)
			(xy 279.124399 -299.856067) (xy 279.130252 -299.854874) (xy 279.141682 -299.852588) (xy 279.214072 -299.7962)
			(xy 279.222902 -299.788611) (xy 279.233083 -299.7677) (xy 279.23363 -299.756068) (xy 279.23363 -298.697142)
			(xy 279.233128 -298.68709) (xy 279.225413 -298.668523) (xy 279.218644 -298.661074) (xy 279.153874 -298.596304)
			(xy 279.127712 -298.589446) (xy 279.11425 -298.593256) (xy 279.092466 -298.598944) (xy 279.047861 -298.605069)
			(xy 279.02535 -298.605448) (xy 279.024588 -298.605448) (xy 278.995317 -298.604822) (xy 278.937687 -298.594525)
			(xy 278.882765 -298.574255) (xy 278.857202 -298.559982) (xy 278.851614 -298.55668) (xy 278.831294 -298.551092)
			(xy 278.817578 -298.54906) (xy 278.282146 -298.54906) (xy 278.26843 -298.551092) (xy 278.24811 -298.55668)
			(xy 278.242522 -298.559982) (xy 278.21696 -298.574261) (xy 278.162042 -298.594549) (xy 278.104409 -298.604849)
			(xy 278.075136 -298.605448) (xy 278.074628 -298.605448) (xy 278.045358 -298.604816) (xy 277.987733 -298.59451)
			(xy 277.932817 -298.574232) (xy 277.907242 -298.559982) (xy 277.901654 -298.55668) (xy 277.881334 -298.551092)
			(xy 277.867618 -298.54906) (xy 277.332186 -298.54906) (xy 277.31847 -298.551092) (xy 277.29815 -298.55668)
			(xy 277.292562 -298.559982) (xy 277.266999 -298.574257) (xy 277.21208 -298.594535) (xy 277.154448 -298.604824)
			(xy 277.125176 -298.605448) (xy 277.124668 -298.605448) (xy 277.095397 -298.60482) (xy 277.037769 -298.59452)
			(xy 276.982849 -298.574247) (xy 276.957282 -298.559982) (xy 276.951694 -298.55668) (xy 276.931374 -298.551092)
			(xy 276.917658 -298.54906) (xy 276.381972 -298.54906) (xy 276.368256 -298.551092) (xy 276.347936 -298.55668)
			(xy 276.342348 -298.559982) (xy 276.316785 -298.574256) (xy 276.261866 -298.594531) (xy 276.204234 -298.604818)
			(xy 276.174962 -298.605448) (xy 276.174454 -298.605448) (xy 276.145184 -298.604819) (xy 276.087556 -298.594517)
			(xy 276.032638 -298.574242) (xy 276.007068 -298.559982) (xy 276.00148 -298.55668) (xy 275.98116 -298.551092)
			(xy 275.967444 -298.54906) (xy 274.482052 -298.54906) (xy 274.468336 -298.551092) (xy 274.448016 -298.55668)
			(xy 274.442428 -298.559982) (xy 274.416865 -298.574254) (xy 274.361945 -298.594526) (xy 274.304313 -298.604809)
			(xy 274.275042 -298.605448) (xy 274.274534 -298.605448) (xy 274.245264 -298.604817) (xy 274.187638 -298.594512)
			(xy 274.132722 -298.574234) (xy 274.107148 -298.559982) (xy 274.10156 -298.55668) (xy 274.08124 -298.551092)
			(xy 274.067524 -298.54906) (xy 273.532092 -298.54906) (xy 273.518376 -298.551092) (xy 273.498056 -298.55668)
			(xy 273.492468 -298.559982) (xy 273.466905 -298.574257) (xy 273.411986 -298.594536) (xy 273.354354 -298.604826)
			(xy 273.325082 -298.605448) (xy 273.324574 -298.605448) (xy 273.295303 -298.60482) (xy 273.237674 -298.594521)
			(xy 273.182754 -298.574249) (xy 273.157188 -298.559982) (xy 273.1516 -298.55668) (xy 273.13128 -298.551092)
			(xy 273.117564 -298.54906) (xy 272.582132 -298.54906) (xy 272.568416 -298.551092) (xy 272.548096 -298.55668)
			(xy 272.542508 -298.559982) (xy 272.516946 -298.57426) (xy 272.462028 -298.594546) (xy 272.404395 -298.604843)
			(xy 272.375122 -298.605448) (xy 272.374614 -298.605448) (xy 272.345342 -298.604824) (xy 272.28771 -298.594531)
			(xy 272.232786 -298.574264) (xy 272.207228 -298.559982) (xy 272.20164 -298.55668) (xy 272.18132 -298.551092)
			(xy 272.167604 -298.54906) (xy 271.632172 -298.54906) (xy 271.618456 -298.551092) (xy 271.598136 -298.55668)
			(xy 271.592548 -298.559982) (xy 271.566985 -298.574256) (xy 271.512066 -298.594531) (xy 271.454434 -298.604818)
			(xy 271.425162 -298.605448) (xy 271.424654 -298.605448) (xy 271.395384 -298.604819) (xy 271.337756 -298.594517)
			(xy 271.282838 -298.574242) (xy 271.257268 -298.559982) (xy 271.25168 -298.55668) (xy 271.23136 -298.551092)
			(xy 271.217644 -298.54906) (xy 270.681958 -298.54906) (xy 270.668242 -298.551092) (xy 270.647922 -298.55668)
			(xy 270.642334 -298.559982) (xy 270.616771 -298.574255) (xy 270.561851 -298.594528) (xy 270.504219 -298.604812)
			(xy 270.474948 -298.605448) (xy 270.47444 -298.605448) (xy 270.44517 -298.604817) (xy 270.387543 -298.594513)
			(xy 270.332627 -298.574236) (xy 270.307054 -298.559982) (xy 270.301466 -298.55668) (xy 270.281146 -298.551092)
			(xy 270.26743 -298.54906) (xy 269.731744 -298.54906) (xy 269.718028 -298.551092) (xy 269.697708 -298.55668)
			(xy 269.69212 -298.559982) (xy 269.666558 -298.574261) (xy 269.61164 -298.594549) (xy 269.554007 -298.604848)
			(xy 269.524734 -298.605448) (xy 269.524226 -298.605448) (xy 269.494956 -298.604816) (xy 269.437331 -298.59451)
			(xy 269.382416 -298.574231) (xy 269.35684 -298.559982) (xy 269.351252 -298.55668) (xy 269.330932 -298.551092)
			(xy 269.317216 -298.54906) (xy 264.063734 -298.54906) (xy 264.05367 -298.549497) (xy 264.035089 -298.557235)
			(xy 264.027666 -298.564046) (xy 263.9949 -298.596812) (xy 263.99109 -298.60113) (xy 263.990328 -298.602146)
			(xy 263.983409 -298.611787) (xy 263.978387 -298.634951) (xy 263.980676 -298.646596) (xy 264.005822 -298.744386)
			(xy 264.024364 -298.763436) (xy 264.037572 -298.767246) (xy 264.063653 -298.775326) (xy 264.113366 -298.797906)
			(xy 264.159352 -298.827343) (xy 264.200673 -298.863033) (xy 264.236485 -298.904249) (xy 264.266056 -298.950148)
			(xy 264.288783 -298.999794) (xy 264.304201 -299.052173) (xy 264.311996 -299.106214) (xy 264.3124 -299.133514)
			(xy 264.311913 -299.160764) (xy 264.304155 -299.21471) (xy 264.301221 -299.2247) (xy 267.633969 -299.2247)
			(xy 267.63814 -299.174365) (xy 267.650538 -299.125402) (xy 267.670826 -299.079148) (xy 267.69845 -299.036863)
			(xy 267.732656 -298.999702) (xy 267.772513 -298.968678) (xy 267.816932 -298.944636) (xy 267.864702 -298.928233)
			(xy 267.91452 -298.919916) (xy 267.939774 -298.919392) (xy 267.96517 -298.919897) (xy 268.01526 -298.928312)
			(xy 268.063267 -298.944897) (xy 268.10787 -298.969196) (xy 268.147838 -299.000538) (xy 268.165326 -299.01896)
			(xy 268.172946 -299.027342) (xy 268.193012 -299.035724) (xy 268.292326 -299.033184) (xy 268.31163 -299.023786)
			(xy 268.318996 -299.014896) (xy 268.3348 -298.996366) (xy 268.370891 -298.963667) (xy 268.411384 -298.93661)
			(xy 268.455404 -298.915778) (xy 268.502001 -298.901621) (xy 268.55017 -298.894444) (xy 268.57452 -298.893992)
			(xy 269.52448 -298.893992) (xy 269.550487 -298.894566) (xy 269.60186 -298.9027) (xy 269.651328 -298.91877)
			(xy 269.697673 -298.942382) (xy 269.739754 -298.972953) (xy 269.776534 -299.009731) (xy 269.807108 -299.05181)
			(xy 269.830722 -299.098153) (xy 269.846796 -299.147621) (xy 269.854933 -299.198993) (xy 269.854933 -299.224954)
			(xy 270.16889 -299.224954) (xy 270.17285 -299.1759) (xy 270.184627 -299.128116) (xy 270.203918 -299.08284)
			(xy 270.230221 -299.041244) (xy 270.262856 -299.004407) (xy 270.300977 -298.973282) (xy 270.343598 -298.948675)
			(xy 270.389614 -298.931223) (xy 270.437833 -298.921379) (xy 270.487008 -298.919398) (xy 270.535863 -298.92533)
			(xy 270.583134 -298.939022) (xy 270.627596 -298.96012) (xy 270.668099 -298.988076) (xy 270.703592 -299.022168)
			(xy 270.733157 -299.061512) (xy 270.756028 -299.105089) (xy 270.771612 -299.15177) (xy 270.779507 -299.200347)
			(xy 270.780002 -299.224954) (xy 270.779507 -299.249561) (xy 270.779271 -299.251013) (xy 271.094376 -299.251013)
			(xy 271.094376 -299.198987) (xy 271.102514 -299.147601) (xy 271.118592 -299.098121) (xy 271.142212 -299.051765)
			(xy 271.172792 -299.009675) (xy 271.209581 -298.972887) (xy 271.251672 -298.942307) (xy 271.298028 -298.918689)
			(xy 271.347509 -298.902613) (xy 271.398895 -298.894475) (xy 271.424908 -298.893992) (xy 272.374868 -298.893992)
			(xy 272.400875 -298.894565) (xy 272.45225 -298.902697) (xy 272.50172 -298.918767) (xy 272.548067 -298.942378)
			(xy 272.590149 -298.972949) (xy 272.626931 -299.009727) (xy 272.657506 -299.051806) (xy 272.681121 -299.09815)
			(xy 272.697195 -299.147619) (xy 272.705333 -299.198993) (xy 272.705333 -299.224954) (xy 273.019024 -299.224954)
			(xy 273.022984 -299.1759) (xy 273.034761 -299.128116) (xy 273.054052 -299.08284) (xy 273.080355 -299.041244)
			(xy 273.11299 -299.004407) (xy 273.151111 -298.973282) (xy 273.193732 -298.948675) (xy 273.239748 -298.931223)
			(xy 273.287967 -298.921379) (xy 273.337142 -298.919398) (xy 273.385997 -298.92533) (xy 273.433268 -298.939022)
			(xy 273.47773 -298.96012) (xy 273.518233 -298.988076) (xy 273.553726 -299.022168) (xy 273.583291 -299.061512)
			(xy 273.606162 -299.105089) (xy 273.621746 -299.15177) (xy 273.629641 -299.200347) (xy 273.630136 -299.224954)
			(xy 273.629641 -299.249561) (xy 273.621746 -299.298138) (xy 273.606162 -299.344819) (xy 273.583291 -299.388396)
			(xy 273.553726 -299.42774) (xy 273.518233 -299.461832) (xy 273.47773 -299.489788) (xy 273.433268 -299.510886)
			(xy 273.385997 -299.524578) (xy 273.337142 -299.53051) (xy 273.287967 -299.528529) (xy 273.239748 -299.518685)
			(xy 273.193732 -299.501233) (xy 273.151111 -299.476626) (xy 273.11299 -299.445501) (xy 273.080355 -299.408664)
			(xy 273.054052 -299.367068) (xy 273.034761 -299.321792) (xy 273.022984 -299.274008) (xy 273.019024 -299.224954)
			(xy 272.705333 -299.224954) (xy 272.705333 -299.251007) (xy 272.697195 -299.302381) (xy 272.681121 -299.35185)
			(xy 272.657506 -299.398194) (xy 272.626931 -299.440273) (xy 272.590149 -299.477051) (xy 272.548067 -299.507622)
			(xy 272.50172 -299.531233) (xy 272.45225 -299.547303) (xy 272.400875 -299.555435) (xy 272.374868 -299.555916)
			(xy 271.424908 -299.555916) (xy 271.398895 -299.555525) (xy 271.347509 -299.547387) (xy 271.298028 -299.531311)
			(xy 271.251672 -299.507693) (xy 271.209581 -299.477113) (xy 271.172792 -299.440325) (xy 271.142212 -299.398235)
			(xy 271.118592 -299.351879) (xy 271.102514 -299.302399) (xy 271.094376 -299.251013) (xy 270.779271 -299.251013)
			(xy 270.771612 -299.298138) (xy 270.756028 -299.344819) (xy 270.733157 -299.388396) (xy 270.703592 -299.42774)
			(xy 270.668099 -299.461832) (xy 270.627596 -299.489788) (xy 270.583134 -299.510886) (xy 270.535863 -299.524578)
			(xy 270.487008 -299.53051) (xy 270.437833 -299.528529) (xy 270.389614 -299.518685) (xy 270.343598 -299.501233)
			(xy 270.300977 -299.476626) (xy 270.262856 -299.445501) (xy 270.230221 -299.408664) (xy 270.203918 -299.367068)
			(xy 270.184627 -299.321792) (xy 270.17285 -299.274008) (xy 270.16889 -299.224954) (xy 269.854933 -299.224954)
			(xy 269.854933 -299.251007) (xy 269.846796 -299.302379) (xy 269.830722 -299.351847) (xy 269.807108 -299.39819)
			(xy 269.776534 -299.440269) (xy 269.739754 -299.477047) (xy 269.697673 -299.507618) (xy 269.651328 -299.53123)
			(xy 269.60186 -299.5473) (xy 269.550487 -299.555434) (xy 269.52448 -299.555916) (xy 268.57452 -299.555916)
			(xy 268.550136 -299.555482) (xy 268.501899 -299.548309) (xy 268.455238 -299.534129) (xy 268.411165 -299.513251)
			(xy 268.370636 -299.486128) (xy 268.334529 -299.453346) (xy 268.318742 -299.434758) (xy 268.31163 -299.426122)
			(xy 268.292072 -299.41647) (xy 268.192758 -299.41393) (xy 268.172692 -299.422312) (xy 268.165072 -299.430694)
			(xy 268.147587 -299.44907) (xy 268.107657 -299.480344) (xy 268.063104 -299.504585) (xy 268.015157 -299.521125)
			(xy 267.965134 -299.529508) (xy 267.939774 -299.530008) (xy 267.91452 -299.529484) (xy 267.864702 -299.521167)
			(xy 267.816932 -299.504764) (xy 267.772513 -299.480722) (xy 267.732656 -299.449698) (xy 267.69845 -299.412537)
			(xy 267.670826 -299.370252) (xy 267.650538 -299.323998) (xy 267.63814 -299.275035) (xy 267.633969 -299.2247)
			(xy 264.301221 -299.2247) (xy 264.288799 -299.267003) (xy 264.266157 -299.316578) (xy 264.23669 -299.362426)
			(xy 264.200998 -299.403614) (xy 264.159808 -299.439303) (xy 264.113958 -299.468767) (xy 264.064382 -299.491406)
			(xy 264.012089 -299.50676) (xy 263.958142 -299.514515) (xy 263.930892 -299.515022) (xy 263.906549 -299.514641)
			(xy 263.858265 -299.5084) (xy 263.834626 -299.502576) (xy 263.834118 -299.502576) (xy 263.83107 -299.501814)
			(xy 263.81583 -299.499274) (xy 263.79551 -299.504608) (xy 263.787128 -299.510958) (xy 263.723374 -299.559726)
			(xy 263.714497 -299.567304) (xy 263.704158 -299.588203) (xy 263.703562 -299.599858) (xy 263.703562 -299.895514)
			(xy 265.820904 -299.895514) (xy 265.824975 -299.839892) (xy 265.837101 -299.785455) (xy 265.857024 -299.733364)
			(xy 265.88432 -299.684729) (xy 265.918406 -299.640586) (xy 265.958555 -299.601877) (xy 266.003913 -299.569426)
			(xy 266.053513 -299.543925) (xy 266.106297 -299.525918) (xy 266.16114 -299.515788) (xy 266.216874 -299.513751)
			(xy 266.272311 -299.519851) (xy 266.326268 -299.533957) (xy 266.377597 -299.555769) (xy 266.425203 -299.584823)
			(xy 266.468071 -299.620498) (xy 266.505288 -299.662035) (xy 266.536061 -299.708548) (xy 266.559733 -299.759045)
			(xy 266.575801 -299.812452) (xy 266.583921 -299.867628) (xy 266.58443 -299.895514) (xy 266.583921 -299.9234)
			(xy 266.575801 -299.978576) (xy 266.559733 -300.031983) (xy 266.536061 -300.08248) (xy 266.505288 -300.128993)
			(xy 266.468071 -300.17053) (xy 266.425203 -300.206205) (xy 266.377597 -300.235259) (xy 266.326268 -300.257071)
			(xy 266.272311 -300.271177) (xy 266.216874 -300.277277) (xy 266.16114 -300.27524) (xy 266.106297 -300.26511)
			(xy 266.053513 -300.247103) (xy 266.003913 -300.221602) (xy 265.958555 -300.189151) (xy 265.918406 -300.150442)
			(xy 265.88432 -300.106299) (xy 265.857024 -300.057664) (xy 265.837101 -300.005573) (xy 265.824975 -299.951136)
			(xy 265.820904 -299.895514) (xy 263.703562 -299.895514) (xy 263.703562 -300.60519) (xy 263.704034 -300.615062)
			(xy 263.711491 -300.633346) (xy 263.71804 -300.64075) (xy 263.718294 -300.641004) (xy 263.943084 -300.865794)
			(xy 263.943592 -300.866302) (xy 263.950973 -300.872884) (xy 263.969273 -300.880328) (xy 263.979152 -300.88078)
		)
		(stroke
			(width 0)
			(type solid)
		)
		(fill yes)
		(layer "In13.Cu")
		(net "PCEPLL1_VDDA18_PEX2")
	)
	(gr_poly
		(pts
			(xy 179.822348 -173.095412) (xy 179.832415 -173.094981) (xy 179.851008 -173.087255) (xy 179.858416 -173.080426)
			(xy 180.098954 -172.839888) (xy 180.105804 -172.832491) (xy 180.113541 -172.813893) (xy 180.11394 -172.80382)
			(xy 180.11394 -147.845526) (xy 180.113502 -147.835463) (xy 180.105762 -147.816884) (xy 180.098954 -147.809458)
			(xy 173.5328 -141.243304) (xy 173.525455 -141.236493) (xy 173.506993 -141.22876) (xy 173.496986 -141.228318)
			(xy 173.415452 -141.228064) (xy 173.397164 -141.23543) (xy 173.389798 -141.242542) (xy 173.368274 -141.262848)
			(xy 173.320121 -141.297234) (xy 173.267237 -141.323773) (xy 173.210889 -141.341831) (xy 173.152429 -141.350972)
			(xy 173.122844 -141.351508) (xy 173.095589 -141.351048) (xy 173.041633 -141.343296) (xy 172.98933 -141.327944)
			(xy 172.939745 -141.305304) (xy 172.893886 -141.275837) (xy 172.852688 -141.240143) (xy 172.81699 -141.198949)
			(xy 172.787518 -141.153094) (xy 172.764872 -141.103511) (xy 172.749514 -141.05121) (xy 172.741755 -140.997255)
			(xy 172.741336 -140.97) (xy 172.741893 -140.940416) (xy 172.751029 -140.881957) (xy 172.769082 -140.82561)
			(xy 172.795618 -140.772726) (xy 172.830001 -140.724573) (xy 172.850302 -140.703046) (xy 172.857414 -140.69568)
			(xy 172.86478 -140.677392) (xy 172.864526 -140.595858) (xy 172.863982 -140.585873) (xy 172.856261 -140.56745)
			(xy 172.84954 -140.560044) (xy 171.937426 -139.64793) (xy 171.930025 -139.641092) (xy 171.911426 -139.63338)
			(xy 171.901358 -139.632944) (xy 163.770056 -139.632944) (xy 163.760093 -139.633427) (xy 163.741667 -139.641014)
			(xy 163.734242 -139.647676) (xy 163.676076 -139.705334) (xy 163.668456 -139.723622) (xy 163.668456 -139.733782)
			(xy 163.667818 -139.76069) (xy 163.659899 -139.813927) (xy 163.64457 -139.865521) (xy 163.622136 -139.914446)
			(xy 163.593042 -139.959728) (xy 163.557867 -140.000467) (xy 163.5379 -140.018516) (xy 163.530026 -140.025628)
			(xy 163.520882 -140.04417) (xy 163.516818 -140.138658) (xy 163.52393 -140.157962) (xy 163.531296 -140.165582)
			(xy 163.55109 -140.187009) (xy 163.584596 -140.234756) (xy 163.610435 -140.287052) (xy 163.628005 -140.342673)
			(xy 163.636894 -140.400323) (xy 163.637468 -140.429488) (xy 163.636982 -140.456739) (xy 163.629226 -140.510687)
			(xy 163.613871 -140.562982) (xy 163.591229 -140.612559) (xy 163.561763 -140.658409) (xy 163.526072 -140.6996)
			(xy 163.484881 -140.735291) (xy 163.439031 -140.764757) (xy 163.438451 -140.765022) (xy 167.351456 -140.765022)
			(xy 167.352013 -140.736137) (xy 167.360699 -140.679024) (xy 167.377905 -140.623876) (xy 167.403238 -140.571957)
			(xy 167.436116 -140.524456) (xy 167.475787 -140.482461) (xy 167.521342 -140.446935) (xy 167.571737 -140.418692)
			(xy 167.625817 -140.398378) (xy 167.65397 -140.391896) (xy 167.664892 -140.389356) (xy 167.682418 -140.376656)
			(xy 167.730678 -140.289788) (xy 167.732202 -140.268198) (xy 167.728392 -140.257784) (xy 167.717718 -140.226272)
			(xy 167.706228 -140.160746) (xy 167.705532 -140.127482) (xy 167.706018 -140.100231) (xy 167.713774 -140.046283)
			(xy 167.729129 -139.993988) (xy 167.751771 -139.944411) (xy 167.781237 -139.898561) (xy 167.816928 -139.85737)
			(xy 167.858119 -139.821679) (xy 167.903969 -139.792213) (xy 167.953546 -139.769571) (xy 168.005841 -139.754216)
			(xy 168.059789 -139.74646) (xy 168.114291 -139.74646) (xy 168.168239 -139.754216) (xy 168.220534 -139.769571)
			(xy 168.270111 -139.792213) (xy 168.315961 -139.821679) (xy 168.357152 -139.85737) (xy 168.392843 -139.898561)
			(xy 168.422309 -139.944411) (xy 168.444951 -139.993988) (xy 168.460306 -140.046283) (xy 168.468062 -140.100231)
			(xy 168.468548 -140.127482) (xy 168.467991 -140.156367) (xy 168.459305 -140.21348) (xy 168.442099 -140.268628)
			(xy 168.416766 -140.320546) (xy 168.383887 -140.368047) (xy 168.344216 -140.410042) (xy 168.298662 -140.445568)
			(xy 168.248267 -140.473812) (xy 168.194187 -140.494126) (xy 168.166034 -140.500608) (xy 168.155112 -140.503148)
			(xy 168.137586 -140.515848) (xy 168.089326 -140.602716) (xy 168.087802 -140.624306) (xy 168.091612 -140.63472)
			(xy 168.102287 -140.666232) (xy 168.113777 -140.731758) (xy 168.114472 -140.765022) (xy 168.113986 -140.792273)
			(xy 168.10623 -140.846221) (xy 168.090875 -140.898516) (xy 168.068233 -140.948093) (xy 168.038767 -140.993943)
			(xy 168.003076 -141.035134) (xy 167.961885 -141.070825) (xy 167.916035 -141.100291) (xy 167.866458 -141.122933)
			(xy 167.814163 -141.138288) (xy 167.760215 -141.146044) (xy 167.705713 -141.146044) (xy 167.651765 -141.138288)
			(xy 167.59947 -141.122933) (xy 167.549893 -141.100291) (xy 167.504043 -141.070825) (xy 167.462852 -141.035134)
			(xy 167.427161 -140.993943) (xy 167.397695 -140.948093) (xy 167.375053 -140.898516) (xy 167.359698 -140.846221)
			(xy 167.351942 -140.792273) (xy 167.351456 -140.765022) (xy 163.438451 -140.765022) (xy 163.389454 -140.787399)
			(xy 163.337159 -140.802754) (xy 163.283211 -140.81051) (xy 163.228709 -140.81051) (xy 163.174761 -140.802754)
			(xy 163.122466 -140.787399) (xy 163.072889 -140.764757) (xy 163.027039 -140.735291) (xy 162.985848 -140.6996)
			(xy 162.950157 -140.658409) (xy 162.920691 -140.612559) (xy 162.898049 -140.562982) (xy 162.882694 -140.510687)
			(xy 162.874938 -140.456739) (xy 162.874452 -140.429488) (xy 162.87493 -140.402365) (xy 162.882617 -140.348667)
			(xy 162.897833 -140.296599) (xy 162.920273 -140.247212) (xy 162.949483 -140.201503) (xy 162.984873 -140.160392)
			(xy 163.005008 -140.142214) (xy 163.012882 -140.135102) (xy 163.022026 -140.11656) (xy 163.02609 -140.022072)
			(xy 163.018978 -140.002768) (xy 163.011612 -139.995148) (xy 162.991982 -139.973916) (xy 162.958708 -139.926626)
			(xy 162.932958 -139.874854) (xy 162.915321 -139.819787) (xy 162.906202 -139.762689) (xy 162.90544 -139.733782)
			(xy 162.90544 -139.723622) (xy 162.89782 -139.705334) (xy 162.839654 -139.647676) (xy 162.832246 -139.640986)
			(xy 162.81381 -139.633388) (xy 162.80384 -139.632944) (xy 155.328366 -139.632944) (xy 155.3183 -139.633375)
			(xy 155.299708 -139.641103) (xy 155.292298 -139.64793) (xy 153.910792 -141.029436) (xy 155.691076 -141.029436)
			(xy 155.695147 -140.973814) (xy 155.707273 -140.919377) (xy 155.727196 -140.867286) (xy 155.754492 -140.818651)
			(xy 155.788578 -140.774508) (xy 155.828727 -140.735799) (xy 155.874085 -140.703348) (xy 155.923685 -140.677847)
			(xy 155.976469 -140.65984) (xy 156.031312 -140.64971) (xy 156.087046 -140.647673) (xy 156.142483 -140.653773)
			(xy 156.19644 -140.667879) (xy 156.247769 -140.689691) (xy 156.295375 -140.718745) (xy 156.338243 -140.75442)
			(xy 156.37546 -140.795957) (xy 156.406233 -140.84247) (xy 156.429905 -140.892967) (xy 156.445973 -140.946374)
			(xy 156.454093 -141.00155) (xy 156.454602 -141.029436) (xy 156.454093 -141.057322) (xy 156.445973 -141.112498)
			(xy 156.429905 -141.165905) (xy 156.406233 -141.216402) (xy 156.37546 -141.262915) (xy 156.338243 -141.304452)
			(xy 156.295375 -141.340127) (xy 156.247769 -141.369181) (xy 156.19644 -141.390993) (xy 156.142483 -141.405099)
			(xy 156.087046 -141.411199) (xy 156.031312 -141.409162) (xy 155.976469 -141.399032) (xy 155.923685 -141.381025)
			(xy 155.874085 -141.355524) (xy 155.828727 -141.323073) (xy 155.788578 -141.284364) (xy 155.754492 -141.240221)
			(xy 155.727196 -141.191586) (xy 155.707273 -141.139495) (xy 155.695147 -141.085058) (xy 155.691076 -141.029436)
			(xy 153.910792 -141.029436) (xy 152.462738 -142.47749) (xy 152.455886 -142.484886) (xy 152.448142 -142.503484)
			(xy 152.447752 -142.513558) (xy 152.447752 -142.748762) (xy 155.618686 -142.748762) (xy 155.622757 -142.69314)
			(xy 155.634883 -142.638703) (xy 155.654806 -142.586612) (xy 155.682102 -142.537977) (xy 155.716188 -142.493834)
			(xy 155.756337 -142.455125) (xy 155.801695 -142.422674) (xy 155.851295 -142.397173) (xy 155.904079 -142.379166)
			(xy 155.958922 -142.369036) (xy 156.014656 -142.366999) (xy 156.070093 -142.373099) (xy 156.12405 -142.387205)
			(xy 156.175379 -142.409017) (xy 156.222985 -142.438071) (xy 156.265853 -142.473746) (xy 156.30307 -142.515283)
			(xy 156.333843 -142.561796) (xy 156.357515 -142.612293) (xy 156.373583 -142.6657) (xy 156.381703 -142.720876)
			(xy 156.382212 -142.748762) (xy 156.381703 -142.776648) (xy 156.373583 -142.831824) (xy 156.364949 -142.860522)
			(xy 162.733482 -142.860522) (xy 162.734003 -142.831839) (xy 162.742612 -142.775123) (xy 162.759608 -142.720333)
			(xy 162.784609 -142.668702) (xy 162.817053 -142.621392) (xy 162.856209 -142.579468) (xy 162.901196 -142.543873)
			(xy 162.951002 -142.515409) (xy 163.004505 -142.494716) (xy 163.060502 -142.48226) (xy 163.089082 -142.479776)
			(xy 163.103573 -142.478237) (xy 163.130875 -142.468089) (xy 163.154202 -142.450647) (xy 163.171658 -142.427331)
			(xy 163.181823 -142.400036) (xy 163.183316 -142.385542) (xy 163.185793 -142.356957) (xy 163.198223 -142.300946)
			(xy 163.218898 -142.247427) (xy 163.247353 -142.197607) (xy 163.282947 -142.152609) (xy 163.324877 -142.113447)
			(xy 163.372198 -142.081005) (xy 163.423842 -142.056013) (xy 163.478647 -142.039035) (xy 163.535375 -142.030454)
			(xy 163.564062 -142.029942) (xy 163.591316 -142.030391) (xy 163.64527 -142.038144) (xy 163.697571 -142.053498)
			(xy 163.747155 -142.076139) (xy 163.79301 -142.105608) (xy 163.834205 -142.141304) (xy 163.869899 -142.182499)
			(xy 163.899366 -142.228356) (xy 163.922007 -142.27794) (xy 163.937359 -142.330241) (xy 163.94511 -142.384196)
			(xy 163.94557 -142.41145) (xy 163.945067 -142.440132) (xy 163.93645 -142.496847) (xy 163.919447 -142.551634)
			(xy 163.895692 -142.60068) (xy 167.705532 -142.60068) (xy 167.705995 -142.573275) (xy 167.713846 -142.51903)
			(xy 167.729383 -142.466469) (xy 167.752287 -142.416674) (xy 167.782085 -142.370671) (xy 167.799766 -142.349728)
			(xy 167.805862 -142.342616) (xy 167.812212 -142.325598) (xy 167.812212 -142.24) (xy 167.805862 -142.222982)
			(xy 167.799766 -142.21587) (xy 167.782094 -142.194919) (xy 167.752298 -142.148918) (xy 167.729395 -142.099125)
			(xy 167.713859 -142.046565) (xy 167.706008 -141.992322) (xy 167.705532 -141.964918) (xy 167.706018 -141.937667)
			(xy 167.713774 -141.883719) (xy 167.729129 -141.831424) (xy 167.751771 -141.781847) (xy 167.781237 -141.735997)
			(xy 167.816928 -141.694806) (xy 167.858119 -141.659115) (xy 167.903969 -141.629649) (xy 167.953546 -141.607007)
			(xy 168.005841 -141.591652) (xy 168.059789 -141.583896) (xy 168.114291 -141.583896) (xy 168.168239 -141.591652)
			(xy 168.220534 -141.607007) (xy 168.270111 -141.629649) (xy 168.315961 -141.659115) (xy 168.357152 -141.694806)
			(xy 168.392843 -141.735997) (xy 168.422309 -141.781847) (xy 168.444951 -141.831424) (xy 168.460306 -141.883719)
			(xy 168.468062 -141.937667) (xy 168.468548 -141.964918) (xy 168.468089 -141.992323) (xy 168.460238 -142.046568)
			(xy 168.4447 -142.09913) (xy 168.421795 -142.148925) (xy 168.391996 -142.194927) (xy 168.374314 -142.21587)
			(xy 168.368218 -142.222982) (xy 168.361868 -142.24) (xy 168.361868 -142.325598) (xy 168.368218 -142.342616)
			(xy 168.374314 -142.349728) (xy 168.388877 -142.367) (xy 169.682666 -142.367) (xy 169.686737 -142.311378)
			(xy 169.698863 -142.256941) (xy 169.718786 -142.20485) (xy 169.746082 -142.156215) (xy 169.780168 -142.112072)
			(xy 169.820317 -142.073363) (xy 169.865675 -142.040912) (xy 169.915275 -142.015411) (xy 169.968059 -141.997404)
			(xy 170.022902 -141.987274) (xy 170.078636 -141.985237) (xy 170.134073 -141.991337) (xy 170.18803 -142.005443)
			(xy 170.239359 -142.027255) (xy 170.286965 -142.056309) (xy 170.329833 -142.091984) (xy 170.36705 -142.133521)
			(xy 170.397823 -142.180034) (xy 170.421495 -142.230531) (xy 170.437563 -142.283938) (xy 170.445683 -142.339114)
			(xy 170.446192 -142.367) (xy 170.445683 -142.394886) (xy 170.437563 -142.450062) (xy 170.421495 -142.503469)
			(xy 170.397823 -142.553966) (xy 170.36705 -142.600479) (xy 170.329833 -142.642016) (xy 170.286965 -142.677691)
			(xy 170.239359 -142.706745) (xy 170.18803 -142.728557) (xy 170.134073 -142.742663) (xy 170.078636 -142.748763)
			(xy 170.022902 -142.746726) (xy 169.968059 -142.736596) (xy 169.915275 -142.718589) (xy 169.865675 -142.693088)
			(xy 169.820317 -142.660637) (xy 169.780168 -142.621928) (xy 169.746082 -142.577785) (xy 169.718786 -142.52915)
			(xy 169.698863 -142.477059) (xy 169.686737 -142.422622) (xy 169.682666 -142.367) (xy 168.388877 -142.367)
			(xy 168.391982 -142.370682) (xy 168.421779 -142.416682) (xy 168.444683 -142.466474) (xy 168.460221 -142.519034)
			(xy 168.468072 -142.573276) (xy 168.468548 -142.60068) (xy 168.468062 -142.627931) (xy 168.460306 -142.681879)
			(xy 168.444951 -142.734174) (xy 168.422309 -142.783751) (xy 168.392843 -142.829601) (xy 168.357152 -142.870792)
			(xy 168.315961 -142.906483) (xy 168.270111 -142.935949) (xy 168.220534 -142.958591) (xy 168.168239 -142.973946)
			(xy 168.114291 -142.981702) (xy 168.059789 -142.981702) (xy 168.005841 -142.973946) (xy 167.953546 -142.958591)
			(xy 167.903969 -142.935949) (xy 167.858119 -142.906483) (xy 167.816928 -142.870792) (xy 167.781237 -142.829601)
			(xy 167.751771 -142.783751) (xy 167.729129 -142.734174) (xy 167.713774 -142.681879) (xy 167.706018 -142.627931)
			(xy 167.705532 -142.60068) (xy 163.895692 -142.60068) (xy 163.894441 -142.603262) (xy 163.861995 -142.65057)
			(xy 163.822838 -142.692492) (xy 163.777851 -142.728086) (xy 163.728046 -142.756552) (xy 163.674545 -142.777248)
			(xy 163.618549 -142.789709) (xy 163.58997 -142.792196) (xy 163.575463 -142.793633) (xy 163.548152 -142.803802)
			(xy 163.524822 -142.821268) (xy 163.507371 -142.844609) (xy 163.497219 -142.871926) (xy 163.495736 -142.88643)
			(xy 163.493282 -142.915018) (xy 163.480855 -142.971033) (xy 163.46018 -143.024555) (xy 163.431723 -143.074378)
			(xy 163.396127 -143.119378) (xy 163.354194 -143.158541) (xy 163.306869 -143.190982) (xy 163.25522 -143.215972)
			(xy 163.200411 -143.232946) (xy 163.143679 -143.241521) (xy 163.11499 -143.24203) (xy 163.08774 -143.241532)
			(xy 163.033793 -143.233774) (xy 162.9815 -143.218419) (xy 162.931924 -143.195778) (xy 162.886075 -143.166313)
			(xy 162.844886 -143.130623) (xy 162.809194 -143.089435) (xy 162.779727 -143.043586) (xy 162.757085 -142.994011)
			(xy 162.741728 -142.941718) (xy 162.733969 -142.887772) (xy 162.733482 -142.860522) (xy 156.364949 -142.860522)
			(xy 156.357515 -142.885231) (xy 156.333843 -142.935728) (xy 156.30307 -142.982241) (xy 156.265853 -143.023778)
			(xy 156.222985 -143.059453) (xy 156.175379 -143.088507) (xy 156.12405 -143.110319) (xy 156.070093 -143.124425)
			(xy 156.014656 -143.130525) (xy 155.958922 -143.128488) (xy 155.904079 -143.118358) (xy 155.851295 -143.100351)
			(xy 155.801695 -143.07485) (xy 155.756337 -143.042399) (xy 155.716188 -143.00369) (xy 155.682102 -142.959547)
			(xy 155.654806 -142.910912) (xy 155.634883 -142.858821) (xy 155.622757 -142.804384) (xy 155.618686 -142.748762)
			(xy 152.447752 -142.748762) (xy 152.447752 -151.045672) (xy 152.703022 -151.045672) (xy 152.703483 -151.01937)
			(xy 152.710727 -150.967267) (xy 152.725059 -150.916653) (xy 152.746208 -150.868488) (xy 152.773773 -150.823685)
			(xy 152.807232 -150.783093) (xy 152.845949 -150.747481) (xy 152.889191 -150.717526) (xy 152.936138 -150.693795)
			(xy 152.9859 -150.676738) (xy 153.011632 -150.671276) (xy 153.022046 -150.669244) (xy 153.03881 -150.65756)
			(xy 153.089864 -150.578058) (xy 153.09342 -150.557738) (xy 153.09088 -150.547578) (xy 153.085904 -150.525496)
			(xy 153.080551 -150.480549) (xy 153.080212 -150.457916) (xy 153.080669 -150.430927) (xy 153.088276 -150.377486)
			(xy 153.103339 -150.325652) (xy 153.125558 -150.276459) (xy 153.15449 -150.230888) (xy 153.189557 -150.189851)
			(xy 153.209498 -150.171658) (xy 153.217626 -150.164546) (xy 153.226516 -150.145496) (xy 153.228548 -150.048976)
			(xy 153.220674 -150.029672) (xy 153.2128 -150.022306) (xy 153.194604 -150.004278) (xy 153.162768 -149.96415)
			(xy 153.136586 -149.920124) (xy 153.116528 -149.872992) (xy 153.102957 -149.823599) (xy 153.096114 -149.772836)
			(xy 153.095706 -149.747224) (xy 153.096192 -149.719973) (xy 153.103948 -149.666025) (xy 153.119303 -149.61373)
			(xy 153.141945 -149.564153) (xy 153.171411 -149.518303) (xy 153.207102 -149.477112) (xy 153.248293 -149.441421)
			(xy 153.294143 -149.411955) (xy 153.34372 -149.389313) (xy 153.396015 -149.373958) (xy 153.449963 -149.366202)
			(xy 153.504465 -149.366202) (xy 153.558413 -149.373958) (xy 153.610708 -149.389313) (xy 153.660285 -149.411955)
			(xy 153.706135 -149.441421) (xy 153.747326 -149.477112) (xy 153.783017 -149.518303) (xy 153.812483 -149.564153)
			(xy 153.835125 -149.61373) (xy 153.85048 -149.666025) (xy 153.858236 -149.719973) (xy 153.858722 -149.747224)
			(xy 153.858246 -149.774213) (xy 153.850647 -149.827653) (xy 153.835589 -149.879488) (xy 153.813373 -149.928682)
			(xy 153.784443 -149.974253) (xy 153.749377 -150.01529) (xy 153.729436 -150.033482) (xy 153.721308 -150.040594)
			(xy 153.712418 -150.059644) (xy 153.710386 -150.156164) (xy 153.71826 -150.175468) (xy 153.726134 -150.182834)
			(xy 153.744288 -150.200902) (xy 153.776131 -150.24102) (xy 153.802321 -150.285037) (xy 153.822386 -150.332162)
			(xy 153.835965 -150.381548) (xy 153.842816 -150.432307) (xy 153.843228 -150.457916) (xy 153.842715 -150.484216)
			(xy 153.835475 -150.536315) (xy 153.821146 -150.586925) (xy 153.800002 -150.635088) (xy 153.772442 -150.67989)
			(xy 153.73899 -150.720481) (xy 153.700279 -150.756093) (xy 153.657044 -150.786051) (xy 153.610103 -150.809785)
			(xy 153.560348 -150.826847) (xy 153.534618 -150.832312) (xy 153.524204 -150.834344) (xy 153.50744 -150.846028)
			(xy 153.456386 -150.92553) (xy 153.45283 -150.94585) (xy 153.45537 -150.95601) (xy 153.456386 -150.960328)
			(xy 153.458672 -150.970234) (xy 153.470356 -150.986744) (xy 153.548842 -151.035766) (xy 153.568654 -151.039068)
			(xy 153.57856 -151.036528) (xy 153.599972 -151.031863) (xy 153.643515 -151.026898) (xy 153.665428 -151.026622)
			(xy 153.69268 -151.02705) (xy 153.746629 -151.03481) (xy 153.798925 -151.050169) (xy 153.848502 -151.072813)
			(xy 153.894353 -151.102283) (xy 153.935543 -151.137977) (xy 153.971234 -151.17917) (xy 154.0007 -151.225022)
			(xy 154.023341 -151.274602) (xy 154.038696 -151.326898) (xy 154.046452 -151.380848) (xy 154.046452 -151.435352)
			(xy 154.038696 -151.489302) (xy 154.023341 -151.541598) (xy 154.0007 -151.591178) (xy 153.971234 -151.63703)
			(xy 153.935543 -151.678223) (xy 153.894353 -151.713917) (xy 153.848502 -151.743387) (xy 153.798925 -151.766031)
			(xy 153.746629 -151.78139) (xy 153.69268 -151.78915) (xy 153.665428 -151.789638) (xy 153.647085 -151.789404)
			(xy 153.610572 -151.785842) (xy 153.59253 -151.782526) (xy 153.582624 -151.780748) (xy 153.56332 -151.784558)
			(xy 153.486866 -151.835612) (xy 153.47569 -151.851868) (xy 153.473658 -151.862028) (xy 153.47061 -151.875998)
			(xy 153.515314 -151.916384) (xy 153.521918 -151.921827) (xy 153.537678 -151.928464) (xy 153.554743 -151.929544)
			(xy 153.563066 -151.92756) (xy 153.587973 -151.921135) (xy 153.638947 -151.914249) (xy 153.664666 -151.913844)
			(xy 153.691923 -151.914319) (xy 153.745881 -151.922072) (xy 153.798188 -151.937426) (xy 153.847776 -151.960068)
			(xy 153.893637 -151.989538) (xy 153.934838 -152.025234) (xy 153.970538 -152.06643) (xy 154.000012 -152.112288)
			(xy 154.022659 -152.161874) (xy 154.038019 -152.214179) (xy 154.045779 -152.268137) (xy 154.045779 -152.32265)
			(xy 154.038022 -152.376608) (xy 154.022664 -152.428913) (xy 154.000018 -152.4785) (xy 153.970546 -152.524359)
			(xy 153.934847 -152.565557) (xy 153.893648 -152.601254) (xy 153.847788 -152.630725) (xy 153.7982 -152.653369)
			(xy 153.745895 -152.668725) (xy 153.691936 -152.67648) (xy 153.637423 -152.676478) (xy 153.583465 -152.668716)
			(xy 153.531161 -152.653355) (xy 153.481576 -152.630705) (xy 153.435719 -152.60123) (xy 153.394524 -152.565528)
			(xy 153.358829 -152.524326) (xy 153.329362 -152.478464) (xy 153.306721 -152.428874) (xy 153.291369 -152.376568)
			(xy 153.283618 -152.322609) (xy 153.283158 -152.295352) (xy 153.284174 -152.268428) (xy 153.284936 -152.256744)
			(xy 153.2763 -152.235154) (xy 153.199338 -152.165558) (xy 153.176986 -152.159208) (xy 153.165302 -152.16124)
			(xy 153.149111 -152.163868) (xy 153.116426 -152.166668) (xy 153.100024 -152.166828) (xy 153.072773 -152.166322)
			(xy 153.018824 -152.158569) (xy 152.966528 -152.143217) (xy 152.91695 -152.120579) (xy 152.871097 -152.091115)
			(xy 152.829905 -152.055426) (xy 152.794211 -152.014238) (xy 152.764742 -151.968389) (xy 152.742098 -151.918813)
			(xy 152.72674 -151.866519) (xy 152.718981 -151.812571) (xy 152.718516 -151.78532) (xy 152.719012 -151.758241)
			(xy 152.726664 -151.704626) (xy 152.741815 -151.652631) (xy 152.764163 -151.603298) (xy 152.793259 -151.55762)
			(xy 152.828518 -151.516512) (xy 152.848564 -151.4983) (xy 152.8572 -151.490934) (xy 152.86609 -151.470614)
			(xy 152.864058 -151.369776) (xy 152.854152 -151.349964) (xy 152.845262 -151.342852) (xy 152.823501 -151.324594)
			(xy 152.785028 -151.282806) (xy 152.753174 -151.235777) (xy 152.728644 -151.184546) (xy 152.71198 -151.130244)
			(xy 152.703549 -151.074072) (xy 152.703022 -151.045672) (xy 152.447752 -151.045672) (xy 152.447752 -154.327352)
			(xy 153.282648 -154.327352) (xy 153.286719 -154.27173) (xy 153.298845 -154.217293) (xy 153.318768 -154.165202)
			(xy 153.346064 -154.116567) (xy 153.38015 -154.072424) (xy 153.420299 -154.033715) (xy 153.465657 -154.001264)
			(xy 153.515257 -153.975763) (xy 153.568041 -153.957756) (xy 153.622884 -153.947626) (xy 153.678618 -153.945589)
			(xy 153.734055 -153.951689) (xy 153.788012 -153.965795) (xy 153.839341 -153.987607) (xy 153.886947 -154.016661)
			(xy 153.929815 -154.052336) (xy 153.967032 -154.093873) (xy 153.997805 -154.140386) (xy 154.021477 -154.190883)
			(xy 154.037545 -154.24429) (xy 154.045665 -154.299466) (xy 154.046174 -154.327352) (xy 154.045665 -154.355238)
			(xy 154.037545 -154.410414) (xy 154.021477 -154.463821) (xy 153.997805 -154.514318) (xy 153.967032 -154.560831)
			(xy 153.929815 -154.602368) (xy 153.886947 -154.638043) (xy 153.839341 -154.667097) (xy 153.788012 -154.688909)
			(xy 153.734055 -154.703015) (xy 153.678618 -154.709115) (xy 153.622884 -154.707078) (xy 153.568041 -154.696948)
			(xy 153.515257 -154.678941) (xy 153.465657 -154.65344) (xy 153.420299 -154.620989) (xy 153.38015 -154.58228)
			(xy 153.346064 -154.538137) (xy 153.318768 -154.489502) (xy 153.298845 -154.437411) (xy 153.286719 -154.382974)
			(xy 153.282648 -154.327352) (xy 152.447752 -154.327352) (xy 152.447752 -156.3624) (xy 153.290776 -156.3624)
			(xy 153.294847 -156.306778) (xy 153.306973 -156.252341) (xy 153.326896 -156.20025) (xy 153.354192 -156.151615)
			(xy 153.388278 -156.107472) (xy 153.428427 -156.068763) (xy 153.473785 -156.036312) (xy 153.523385 -156.010811)
			(xy 153.576169 -155.992804) (xy 153.631012 -155.982674) (xy 153.686746 -155.980637) (xy 153.742183 -155.986737)
			(xy 153.79614 -156.000843) (xy 153.847469 -156.022655) (xy 153.895075 -156.051709) (xy 153.902154 -156.0576)
			(xy 164.263576 -156.0576) (xy 164.267647 -156.001978) (xy 164.279773 -155.947541) (xy 164.299696 -155.89545)
			(xy 164.326992 -155.846815) (xy 164.361078 -155.802672) (xy 164.401227 -155.763963) (xy 164.446585 -155.731512)
			(xy 164.496185 -155.706011) (xy 164.548969 -155.688004) (xy 164.603812 -155.677874) (xy 164.659546 -155.675837)
			(xy 164.714983 -155.681937) (xy 164.76894 -155.696043) (xy 164.820269 -155.717855) (xy 164.867875 -155.746909)
			(xy 164.910743 -155.782584) (xy 164.94796 -155.824121) (xy 164.978733 -155.870634) (xy 165.002405 -155.921131)
			(xy 165.018473 -155.974538) (xy 165.026593 -156.029714) (xy 165.027102 -156.0576) (xy 165.026593 -156.085486)
			(xy 165.018473 -156.140662) (xy 165.002405 -156.194069) (xy 164.978733 -156.244566) (xy 164.94796 -156.291079)
			(xy 164.910743 -156.332616) (xy 164.867875 -156.368291) (xy 164.820269 -156.397345) (xy 164.76894 -156.419157)
			(xy 164.714983 -156.433263) (xy 164.659546 -156.439363) (xy 164.603812 -156.437326) (xy 164.548969 -156.427196)
			(xy 164.496185 -156.409189) (xy 164.446585 -156.383688) (xy 164.401227 -156.351237) (xy 164.361078 -156.312528)
			(xy 164.326992 -156.268385) (xy 164.299696 -156.21975) (xy 164.279773 -156.167659) (xy 164.267647 -156.113222)
			(xy 164.263576 -156.0576) (xy 153.902154 -156.0576) (xy 153.937943 -156.087384) (xy 153.97516 -156.128921)
			(xy 154.005933 -156.175434) (xy 154.029605 -156.225931) (xy 154.045673 -156.279338) (xy 154.053793 -156.334514)
			(xy 154.054302 -156.3624) (xy 154.053793 -156.390286) (xy 154.045673 -156.445462) (xy 154.029605 -156.498869)
			(xy 154.005933 -156.549366) (xy 153.97516 -156.595879) (xy 153.937943 -156.637416) (xy 153.895075 -156.673091)
			(xy 153.847469 -156.702145) (xy 153.79614 -156.723957) (xy 153.742183 -156.738063) (xy 153.686746 -156.744163)
			(xy 153.631012 -156.742126) (xy 153.576169 -156.731996) (xy 153.523385 -156.713989) (xy 153.473785 -156.688488)
			(xy 153.428427 -156.656037) (xy 153.388278 -156.617328) (xy 153.354192 -156.573185) (xy 153.326896 -156.52455)
			(xy 153.306973 -156.472459) (xy 153.294847 -156.418022) (xy 153.290776 -156.3624) (xy 152.447752 -156.3624)
			(xy 152.447752 -158.275274) (xy 152.44819 -158.285337) (xy 152.455929 -158.303917) (xy 152.462738 -158.311342)
			(xy 153.128218 -158.976822) (xy 153.135614 -158.983674) (xy 153.154213 -158.991414) (xy 153.164286 -158.991808)
			(xy 164.443918 -158.991808) (xy 164.453987 -158.991382) (xy 164.472588 -158.983664) (xy 164.479986 -158.976822)
			(xy 165.686232 -157.770576) (xy 165.693082 -157.763179) (xy 165.700818 -157.744581) (xy 165.701218 -157.734508)
			(xy 165.701218 -155.419552) (xy 165.700787 -155.409485) (xy 165.693062 -155.390892) (xy 165.686232 -155.383484)
			(xy 164.904674 -154.601926) (xy 164.897275 -154.595081) (xy 164.878677 -154.587352) (xy 164.868606 -154.58694)
			(xy 156.525976 -154.58694) (xy 156.515909 -154.586511) (xy 156.497317 -154.578784) (xy 156.489908 -154.571954)
			(xy 155.167584 -153.24963) (xy 155.16074 -153.242232) (xy 155.153017 -153.223632) (xy 155.152598 -153.213562)
			(xy 155.152598 -145.875248) (xy 155.153031 -145.865182) (xy 155.160758 -145.846591) (xy 155.167584 -145.83918)
			(xy 157.533086 -143.473678) (xy 157.540485 -143.466837) (xy 157.559085 -143.459121) (xy 157.569154 -143.458692)
			(xy 167.470328 -143.458692) (xy 167.479451 -143.458371) (xy 167.496564 -143.452058) (xy 167.510346 -143.44011)
			(xy 167.515032 -143.432276) (xy 167.528519 -143.4086) (xy 167.561179 -143.364986) (xy 167.599713 -143.326463)
			(xy 167.643336 -143.293815) (xy 167.69116 -143.267707) (xy 167.742213 -143.248669) (xy 167.795456 -143.237088)
			(xy 167.849804 -143.233202) (xy 167.904152 -143.237088) (xy 167.957395 -143.248669) (xy 168.008448 -143.267707)
			(xy 168.056272 -143.293815) (xy 168.099895 -143.326463) (xy 168.138429 -143.364986) (xy 168.171089 -143.4086)
			(xy 168.184576 -143.432276) (xy 168.189299 -143.440072) (xy 168.203098 -143.451962) (xy 168.220173 -143.458307)
			(xy 168.22928 -143.458692) (xy 168.848786 -143.458692) (xy 168.858849 -143.45913) (xy 168.877432 -143.466866)
			(xy 168.884854 -143.473678) (xy 169.683176 -144.272) (xy 172.486826 -144.272) (xy 172.490897 -144.216378)
			(xy 172.503023 -144.161941) (xy 172.522946 -144.10985) (xy 172.550242 -144.061215) (xy 172.584328 -144.017072)
			(xy 172.624477 -143.978363) (xy 172.669835 -143.945912) (xy 172.719435 -143.920411) (xy 172.772219 -143.902404)
			(xy 172.827062 -143.892274) (xy 172.882796 -143.890237) (xy 172.938233 -143.896337) (xy 172.99219 -143.910443)
			(xy 173.043519 -143.932255) (xy 173.091125 -143.961309) (xy 173.133993 -143.996984) (xy 173.17121 -144.038521)
			(xy 173.201983 -144.085034) (xy 173.225655 -144.135531) (xy 173.241723 -144.188938) (xy 173.249843 -144.244114)
			(xy 173.250352 -144.272) (xy 173.249843 -144.299886) (xy 173.241723 -144.355062) (xy 173.225655 -144.408469)
			(xy 173.201983 -144.458966) (xy 173.17121 -144.505479) (xy 173.133993 -144.547016) (xy 173.091125 -144.582691)
			(xy 173.043519 -144.611745) (xy 172.99219 -144.633557) (xy 172.938233 -144.647663) (xy 172.882796 -144.653763)
			(xy 172.827062 -144.651726) (xy 172.772219 -144.641596) (xy 172.719435 -144.623589) (xy 172.669835 -144.598088)
			(xy 172.624477 -144.565637) (xy 172.584328 -144.526928) (xy 172.550242 -144.482785) (xy 172.522946 -144.43415)
			(xy 172.503023 -144.382059) (xy 172.490897 -144.327622) (xy 172.486826 -144.272) (xy 169.683176 -144.272)
			(xy 176.582832 -151.171656) (xy 176.589677 -151.179054) (xy 176.597402 -151.197653) (xy 176.597818 -151.207724)
			(xy 176.597818 -157.045152) (xy 178.526438 -157.045152) (xy 178.530509 -156.98953) (xy 178.542635 -156.935093)
			(xy 178.562558 -156.883002) (xy 178.589854 -156.834367) (xy 178.62394 -156.790224) (xy 178.664089 -156.751515)
			(xy 178.709447 -156.719064) (xy 178.759047 -156.693563) (xy 178.811831 -156.675556) (xy 178.866674 -156.665426)
			(xy 178.922408 -156.663389) (xy 178.977845 -156.669489) (xy 179.031802 -156.683595) (xy 179.083131 -156.705407)
			(xy 179.130737 -156.734461) (xy 179.173605 -156.770136) (xy 179.210822 -156.811673) (xy 179.241595 -156.858186)
			(xy 179.265267 -156.908683) (xy 179.281335 -156.96209) (xy 179.289455 -157.017266) (xy 179.289964 -157.045152)
			(xy 179.289455 -157.073038) (xy 179.281335 -157.128214) (xy 179.265267 -157.181621) (xy 179.241595 -157.232118)
			(xy 179.210822 -157.278631) (xy 179.173605 -157.320168) (xy 179.130737 -157.355843) (xy 179.083131 -157.384897)
			(xy 179.031802 -157.406709) (xy 178.977845 -157.420815) (xy 178.922408 -157.426915) (xy 178.866674 -157.424878)
			(xy 178.811831 -157.414748) (xy 178.759047 -157.396741) (xy 178.709447 -157.37124) (xy 178.664089 -157.338789)
			(xy 178.62394 -157.30008) (xy 178.589854 -157.255937) (xy 178.562558 -157.207302) (xy 178.542635 -157.155211)
			(xy 178.530509 -157.100774) (xy 178.526438 -157.045152) (xy 176.597818 -157.045152) (xy 176.597818 -161.757868)
			(xy 177.459638 -161.757868) (xy 177.463709 -161.702246) (xy 177.475835 -161.647809) (xy 177.495758 -161.595718)
			(xy 177.523054 -161.547083) (xy 177.55714 -161.50294) (xy 177.597289 -161.464231) (xy 177.642647 -161.43178)
			(xy 177.692247 -161.406279) (xy 177.745031 -161.388272) (xy 177.799874 -161.378142) (xy 177.855608 -161.376105)
			(xy 177.911045 -161.382205) (xy 177.965002 -161.396311) (xy 178.016331 -161.418123) (xy 178.063937 -161.447177)
			(xy 178.106805 -161.482852) (xy 178.144022 -161.524389) (xy 178.174795 -161.570902) (xy 178.198467 -161.621399)
			(xy 178.214535 -161.674806) (xy 178.222655 -161.729982) (xy 178.223164 -161.757868) (xy 178.222655 -161.785754)
			(xy 178.214535 -161.84093) (xy 178.198467 -161.894337) (xy 178.174795 -161.944834) (xy 178.144022 -161.991347)
			(xy 178.106805 -162.032884) (xy 178.063937 -162.068559) (xy 178.039046 -162.08375) (xy 178.959762 -162.08375)
			(xy 178.963833 -162.028128) (xy 178.975959 -161.973691) (xy 178.995882 -161.9216) (xy 179.023178 -161.872965)
			(xy 179.057264 -161.828822) (xy 179.097413 -161.790113) (xy 179.142771 -161.757662) (xy 179.192371 -161.732161)
			(xy 179.245155 -161.714154) (xy 179.299998 -161.704024) (xy 179.355732 -161.701987) (xy 179.411169 -161.708087)
			(xy 179.465126 -161.722193) (xy 179.516455 -161.744005) (xy 179.564061 -161.773059) (xy 179.606929 -161.808734)
			(xy 179.644146 -161.850271) (xy 179.674919 -161.896784) (xy 179.698591 -161.947281) (xy 179.714659 -162.000688)
			(xy 179.722779 -162.055864) (xy 179.723288 -162.08375) (xy 179.722779 -162.111636) (xy 179.714659 -162.166812)
			(xy 179.698591 -162.220219) (xy 179.674919 -162.270716) (xy 179.644146 -162.317229) (xy 179.606929 -162.358766)
			(xy 179.564061 -162.394441) (xy 179.516455 -162.423495) (xy 179.465126 -162.445307) (xy 179.411169 -162.459413)
			(xy 179.355732 -162.465513) (xy 179.299998 -162.463476) (xy 179.245155 -162.453346) (xy 179.192371 -162.435339)
			(xy 179.142771 -162.409838) (xy 179.097413 -162.377387) (xy 179.057264 -162.338678) (xy 179.023178 -162.294535)
			(xy 178.995882 -162.2459) (xy 178.975959 -162.193809) (xy 178.963833 -162.139372) (xy 178.959762 -162.08375)
			(xy 178.039046 -162.08375) (xy 178.016331 -162.097613) (xy 177.965002 -162.119425) (xy 177.911045 -162.133531)
			(xy 177.855608 -162.139631) (xy 177.799874 -162.137594) (xy 177.745031 -162.127464) (xy 177.692247 -162.109457)
			(xy 177.642647 -162.083956) (xy 177.597289 -162.051505) (xy 177.55714 -162.012796) (xy 177.523054 -161.968653)
			(xy 177.495758 -161.920018) (xy 177.475835 -161.867927) (xy 177.463709 -161.81349) (xy 177.459638 -161.757868)
			(xy 176.597818 -161.757868) (xy 176.597818 -166.570406) (xy 178.787042 -166.570406) (xy 178.791113 -166.514784)
			(xy 178.803239 -166.460347) (xy 178.823162 -166.408256) (xy 178.850458 -166.359621) (xy 178.884544 -166.315478)
			(xy 178.924693 -166.276769) (xy 178.970051 -166.244318) (xy 179.019651 -166.218817) (xy 179.072435 -166.20081)
			(xy 179.127278 -166.19068) (xy 179.183012 -166.188643) (xy 179.238449 -166.194743) (xy 179.292406 -166.208849)
			(xy 179.343735 -166.230661) (xy 179.391341 -166.259715) (xy 179.434209 -166.29539) (xy 179.471426 -166.336927)
			(xy 179.502199 -166.38344) (xy 179.525871 -166.433937) (xy 179.541939 -166.487344) (xy 179.550059 -166.54252)
			(xy 179.550568 -166.570406) (xy 179.550059 -166.598292) (xy 179.541939 -166.653468) (xy 179.525871 -166.706875)
			(xy 179.502199 -166.757372) (xy 179.471426 -166.803885) (xy 179.434209 -166.845422) (xy 179.391341 -166.881097)
			(xy 179.343735 -166.910151) (xy 179.292406 -166.931963) (xy 179.238449 -166.946069) (xy 179.183012 -166.952169)
			(xy 179.127278 -166.950132) (xy 179.072435 -166.940002) (xy 179.019651 -166.921995) (xy 178.970051 -166.896494)
			(xy 178.924693 -166.864043) (xy 178.884544 -166.825334) (xy 178.850458 -166.781191) (xy 178.823162 -166.732556)
			(xy 178.803239 -166.680465) (xy 178.791113 -166.626028) (xy 178.787042 -166.570406) (xy 176.597818 -166.570406)
			(xy 176.597818 -168.94556) (xy 178.349908 -168.94556) (xy 178.353979 -168.889938) (xy 178.366105 -168.835501)
			(xy 178.386028 -168.78341) (xy 178.413324 -168.734775) (xy 178.44741 -168.690632) (xy 178.487559 -168.651923)
			(xy 178.532917 -168.619472) (xy 178.582517 -168.593971) (xy 178.635301 -168.575964) (xy 178.690144 -168.565834)
			(xy 178.745878 -168.563797) (xy 178.801315 -168.569897) (xy 178.855272 -168.584003) (xy 178.906601 -168.605815)
			(xy 178.954207 -168.634869) (xy 178.997075 -168.670544) (xy 179.034292 -168.712081) (xy 179.065065 -168.758594)
			(xy 179.088737 -168.809091) (xy 179.104805 -168.862498) (xy 179.112925 -168.917674) (xy 179.113434 -168.94556)
			(xy 179.112925 -168.973446) (xy 179.104805 -169.028622) (xy 179.088737 -169.082029) (xy 179.065065 -169.132526)
			(xy 179.034292 -169.179039) (xy 178.997075 -169.220576) (xy 178.954207 -169.256251) (xy 178.906601 -169.285305)
			(xy 178.855272 -169.307117) (xy 178.801315 -169.321223) (xy 178.745878 -169.327323) (xy 178.690144 -169.325286)
			(xy 178.635301 -169.315156) (xy 178.582517 -169.297149) (xy 178.532917 -169.271648) (xy 178.487559 -169.239197)
			(xy 178.44741 -169.200488) (xy 178.413324 -169.156345) (xy 178.386028 -169.10771) (xy 178.366105 -169.055619)
			(xy 178.353979 -169.001182) (xy 178.349908 -168.94556) (xy 176.597818 -168.94556) (xy 176.597818 -172.2628)
			(xy 176.598242 -172.27287) (xy 176.605958 -172.291473) (xy 176.612804 -172.298868) (xy 176.643284 -172.329348)
			(xy 177.147726 -172.329348) (xy 177.151797 -172.273726) (xy 177.163923 -172.219289) (xy 177.183846 -172.167198)
			(xy 177.211142 -172.118563) (xy 177.245228 -172.07442) (xy 177.285377 -172.035711) (xy 177.330735 -172.00326)
			(xy 177.380335 -171.977759) (xy 177.433119 -171.959752) (xy 177.487962 -171.949622) (xy 177.543696 -171.947585)
			(xy 177.599133 -171.953685) (xy 177.65309 -171.967791) (xy 177.704419 -171.989603) (xy 177.752025 -172.018657)
			(xy 177.794893 -172.054332) (xy 177.83211 -172.095869) (xy 177.862883 -172.142382) (xy 177.886555 -172.192879)
			(xy 177.902623 -172.246286) (xy 177.910743 -172.301462) (xy 177.911252 -172.329348) (xy 177.910743 -172.357234)
			(xy 177.902623 -172.41241) (xy 177.886555 -172.465817) (xy 177.862883 -172.516314) (xy 177.83211 -172.562827)
			(xy 177.794893 -172.604364) (xy 177.752025 -172.640039) (xy 177.704419 -172.669093) (xy 177.65309 -172.690905)
			(xy 177.599133 -172.705011) (xy 177.543696 -172.711111) (xy 177.487962 -172.709074) (xy 177.433119 -172.698944)
			(xy 177.380335 -172.680937) (xy 177.330735 -172.655436) (xy 177.285377 -172.622985) (xy 177.245228 -172.584276)
			(xy 177.211142 -172.540133) (xy 177.183846 -172.491498) (xy 177.163923 -172.439407) (xy 177.151797 -172.38497)
			(xy 177.147726 -172.329348) (xy 176.643284 -172.329348) (xy 177.394362 -173.080426) (xy 177.40176 -173.087271)
			(xy 177.420359 -173.094994) (xy 177.43043 -173.095412)
		)
		(stroke
			(width 0)
			(type solid)
		)
		(fill yes)
		(layer "In13.Cu")
		(net "P3V3_NIC2")
	)
	(gr_poly
		(pts
			(xy 272.941542 -293.56558) (xy 272.951348 -293.565071) (xy 272.969492 -293.557609) (xy 272.976848 -293.551102)
			(xy 272.979642 -293.548562) (xy 272.987516 -293.5478) (xy 272.993866 -293.54145) (xy 272.99412 -293.520368)
			(xy 272.994968 -293.494616) (xy 273.00366 -293.443832) (xy 273.020123 -293.39501) (xy 273.043957 -293.349331)
			(xy 273.074586 -293.307901) (xy 273.111269 -293.271721) (xy 273.153118 -293.241668) (xy 273.199122 -293.218468)
			(xy 273.248167 -293.202682) (xy 273.299067 -293.194692) (xy 273.350589 -293.194692) (xy 273.401489 -293.202682)
			(xy 273.450534 -293.218468) (xy 273.496538 -293.241668) (xy 273.538387 -293.271721) (xy 273.57507 -293.307901)
			(xy 273.605699 -293.349331) (xy 273.629533 -293.39501) (xy 273.645996 -293.443832) (xy 273.654688 -293.494616)
			(xy 273.655536 -293.520368) (xy 273.65579 -293.54145) (xy 273.66214 -293.5478) (xy 273.670014 -293.548562)
			(xy 273.672808 -293.551102) (xy 273.680131 -293.557661) (xy 273.698295 -293.565134) (xy 273.708114 -293.56558)
			(xy 273.891502 -293.56558) (xy 273.901311 -293.565078) (xy 273.919466 -293.557627) (xy 273.926808 -293.551102)
			(xy 273.929602 -293.548562) (xy 273.937476 -293.5478) (xy 273.943826 -293.54145) (xy 273.94408 -293.520368)
			(xy 273.944928 -293.494616) (xy 273.95362 -293.443832) (xy 273.970083 -293.39501) (xy 273.993917 -293.349331)
			(xy 274.024546 -293.307901) (xy 274.061229 -293.271721) (xy 274.103078 -293.241668) (xy 274.149082 -293.218468)
			(xy 274.198127 -293.202682) (xy 274.249027 -293.194692) (xy 274.300549 -293.194692) (xy 274.351449 -293.202682)
			(xy 274.400494 -293.218468) (xy 274.446498 -293.241668) (xy 274.488347 -293.271721) (xy 274.52503 -293.307901)
			(xy 274.555659 -293.349331) (xy 274.579493 -293.39501) (xy 274.595956 -293.443832) (xy 274.604648 -293.494616)
			(xy 274.605496 -293.520368) (xy 274.60575 -293.54145) (xy 274.6121 -293.5478) (xy 274.619974 -293.548562)
			(xy 274.622768 -293.551102) (xy 274.630094 -293.557652) (xy 274.648259 -293.565103) (xy 274.658074 -293.56558)
			(xy 274.797774 -293.56558) (xy 274.807674 -293.565065) (xy 274.825974 -293.557489) (xy 274.833334 -293.550848)
			(xy 274.835366 -293.54907) (xy 274.84324 -293.530782) (xy 274.84324 -293.520368) (xy 274.844035 -293.49333)
			(xy 274.852316 -293.439876) (xy 274.868063 -293.388128) (xy 274.890962 -293.339123) (xy 274.920552 -293.293842)
			(xy 274.95624 -293.253195) (xy 274.997312 -293.217996) (xy 275.042944 -293.188951) (xy 275.09222 -293.166641)
			(xy 275.144153 -293.151515) (xy 275.197702 -293.143876) (xy 275.251794 -293.143876) (xy 275.305343 -293.151515)
			(xy 275.357276 -293.166641) (xy 275.406552 -293.188951) (xy 275.452184 -293.217996) (xy 275.493256 -293.253195)
			(xy 275.528944 -293.293842) (xy 275.558534 -293.339123) (xy 275.581433 -293.388128) (xy 275.59718 -293.439876)
			(xy 275.605461 -293.49333) (xy 275.606256 -293.520368) (xy 275.606256 -293.520622) (xy 275.606826 -293.530546)
			(xy 275.614535 -293.548846) (xy 275.621242 -293.556182) (xy 275.623274 -293.55796) (xy 275.641562 -293.56558)
			(xy 275.791422 -293.56558) (xy 275.80123 -293.565074) (xy 275.819379 -293.557618) (xy 275.826728 -293.551102)
			(xy 275.829522 -293.548562) (xy 275.837396 -293.5478) (xy 275.843746 -293.54145) (xy 275.844 -293.520368)
			(xy 275.844848 -293.494616) (xy 275.85354 -293.443832) (xy 275.870003 -293.39501) (xy 275.893837 -293.349331)
			(xy 275.924466 -293.307901) (xy 275.961149 -293.271721) (xy 276.002998 -293.241668) (xy 276.049002 -293.218468)
			(xy 276.098047 -293.202682) (xy 276.148947 -293.194692) (xy 276.200469 -293.194692) (xy 276.251369 -293.202682)
			(xy 276.300414 -293.218468) (xy 276.346418 -293.241668) (xy 276.388267 -293.271721) (xy 276.42495 -293.307901)
			(xy 276.455579 -293.349331) (xy 276.479413 -293.39501) (xy 276.495876 -293.443832) (xy 276.504568 -293.494616)
			(xy 276.505416 -293.520368) (xy 276.50567 -293.54145) (xy 276.51202 -293.5478) (xy 276.519894 -293.548562)
			(xy 276.522688 -293.551102) (xy 276.530015 -293.557649) (xy 276.54818 -293.565093) (xy 276.557994 -293.56558)
			(xy 277.691596 -293.56558) (xy 277.701406 -293.565079) (xy 277.719562 -293.557629) (xy 277.726902 -293.551102)
			(xy 277.729696 -293.548562) (xy 277.73757 -293.5478) (xy 277.74392 -293.54145) (xy 277.744174 -293.520368)
			(xy 277.745022 -293.494616) (xy 277.753714 -293.443832) (xy 277.770177 -293.39501) (xy 277.794011 -293.349331)
			(xy 277.82464 -293.307901) (xy 277.861323 -293.271721) (xy 277.903172 -293.241668) (xy 277.949176 -293.218468)
			(xy 277.998221 -293.202682) (xy 278.049121 -293.194692) (xy 278.100643 -293.194692) (xy 278.151543 -293.202682)
			(xy 278.200588 -293.218468) (xy 278.246592 -293.241668) (xy 278.288441 -293.271721) (xy 278.325124 -293.307901)
			(xy 278.355753 -293.349331) (xy 278.379587 -293.39501) (xy 278.39605 -293.443832) (xy 278.404742 -293.494616)
			(xy 278.40559 -293.520368) (xy 278.405844 -293.54145) (xy 278.412194 -293.5478) (xy 278.420068 -293.548562)
			(xy 278.422862 -293.551102) (xy 278.430188 -293.557653) (xy 278.448352 -293.565106) (xy 278.458168 -293.56558)
			(xy 278.641556 -293.56558) (xy 278.651369 -293.565086) (xy 278.669535 -293.557646) (xy 278.676862 -293.551102)
			(xy 278.679656 -293.548562) (xy 278.68753 -293.5478) (xy 278.69388 -293.54145) (xy 278.694134 -293.520368)
			(xy 278.694979 -293.494615) (xy 278.703667 -293.443828) (xy 278.720126 -293.395004) (xy 278.743959 -293.349323)
			(xy 278.774588 -293.307891) (xy 278.811272 -293.27171) (xy 278.853124 -293.241657) (xy 278.89913 -293.218459)
			(xy 278.948178 -293.202676) (xy 278.99908 -293.194692) (xy 279.024842 -293.194232) (xy 279.04906 -293.194659)
			(xy 279.096977 -293.201733) (xy 279.143348 -293.215724) (xy 279.187182 -293.236332) (xy 279.227539 -293.263115)
			(xy 279.263555 -293.295502) (xy 279.27935 -293.313866) (xy 279.286208 -293.321994) (xy 279.295606 -293.32682)
			(xy 279.300453 -293.329113) (xy 279.310829 -293.331808) (xy 279.31618 -293.332154) (xy 279.390856 -293.33571)
			(xy 279.396444 -293.33571) (xy 279.405703 -293.334746) (xy 279.422637 -293.327053) (xy 279.429464 -293.320724)
			(xy 279.437338 -293.31285) (xy 279.440047 -293.310001) (xy 279.444648 -293.303627) (xy 279.446482 -293.30015)
			(xy 279.449065 -293.294723) (xy 279.451888 -293.283044) (xy 279.45207 -293.277036) (xy 279.45207 -292.129464)
			(xy 279.451904 -292.123454) (xy 279.449082 -292.111771) (xy 279.446482 -292.10635) (xy 279.44464 -292.102878)
			(xy 279.440043 -292.096503) (xy 279.437338 -292.09365) (xy 279.258776 -291.915088) (xy 279.250332 -291.907457)
			(xy 279.228934 -291.899792) (xy 279.206321 -291.902088) (xy 279.196292 -291.907468) (xy 279.176827 -291.918846)
			(xy 279.135469 -291.936795) (xy 279.092052 -291.948947) (xy 279.047385 -291.955077) (xy 279.024842 -291.955474)
			(xy 278.998689 -291.954974) (xy 278.947035 -291.946732) (xy 278.897322 -291.930464) (xy 278.850789 -291.906574)
			(xy 278.808596 -291.875659) (xy 278.771794 -291.838488) (xy 278.75611 -291.817552) (xy 278.751538 -291.811964)
			(xy 278.744591 -291.805274) (xy 278.727098 -291.797189) (xy 278.717502 -291.796216) (xy 278.385016 -291.796216)
			(xy 278.374684 -291.796707) (xy 278.355685 -291.804839) (xy 278.348186 -291.811964) (xy 278.343614 -291.817552)
			(xy 278.327973 -291.838529) (xy 278.291179 -291.875733) (xy 278.248985 -291.906675) (xy 278.202442 -291.930585)
			(xy 278.152715 -291.946864) (xy 278.101044 -291.955106) (xy 278.04872 -291.955106) (xy 277.997049 -291.946864)
			(xy 277.947322 -291.930585) (xy 277.900779 -291.906675) (xy 277.858585 -291.875733) (xy 277.821791 -291.838529)
			(xy 277.80615 -291.817552) (xy 277.801578 -291.811964) (xy 277.794634 -291.805268) (xy 277.777141 -291.79717)
			(xy 277.767542 -291.796216) (xy 277.435056 -291.796216) (xy 277.42472 -291.796699) (xy 277.405711 -291.804821)
			(xy 277.398226 -291.811964) (xy 277.393654 -291.817552) (xy 277.378013 -291.838529) (xy 277.341219 -291.875733)
			(xy 277.299025 -291.906675) (xy 277.252482 -291.930585) (xy 277.202755 -291.946864) (xy 277.151084 -291.955106)
			(xy 277.09876 -291.955106) (xy 277.047089 -291.946864) (xy 276.997362 -291.930585) (xy 276.950819 -291.906675)
			(xy 276.908625 -291.875733) (xy 276.871831 -291.838529) (xy 276.85619 -291.817552) (xy 276.851618 -291.811964)
			(xy 276.844676 -291.805262) (xy 276.827184 -291.797151) (xy 276.817582 -291.796216) (xy 276.484842 -291.796216)
			(xy 276.474508 -291.796702) (xy 276.455502 -291.804827) (xy 276.448012 -291.811964) (xy 276.44344 -291.817552)
			(xy 276.427799 -291.838529) (xy 276.391005 -291.875733) (xy 276.348811 -291.906675) (xy 276.302268 -291.930585)
			(xy 276.252541 -291.946864) (xy 276.20087 -291.955106) (xy 276.148546 -291.955106) (xy 276.096875 -291.946864)
			(xy 276.047148 -291.930585) (xy 276.000605 -291.906675) (xy 275.958411 -291.875733) (xy 275.921617 -291.838529)
			(xy 275.905976 -291.817552) (xy 275.901404 -291.811964) (xy 275.894461 -291.805264) (xy 275.876969 -291.797157)
			(xy 275.867368 -291.796216) (xy 275.534882 -291.796216) (xy 275.524544 -291.796694) (xy 275.505527 -291.804809)
			(xy 275.498052 -291.811964) (xy 275.49348 -291.817552) (xy 275.477839 -291.838529) (xy 275.441045 -291.875733)
			(xy 275.398851 -291.906675) (xy 275.352308 -291.930585) (xy 275.302581 -291.946864) (xy 275.25091 -291.955106)
			(xy 275.198586 -291.955106) (xy 275.146915 -291.946864) (xy 275.097188 -291.930585) (xy 275.050645 -291.906675)
			(xy 275.008451 -291.875733) (xy 274.971657 -291.838529) (xy 274.956016 -291.817552) (xy 274.951444 -291.811964)
			(xy 274.944498 -291.805273) (xy 274.927004 -291.797186) (xy 274.917408 -291.796216) (xy 274.584922 -291.796216)
			(xy 274.574589 -291.796705) (xy 274.555589 -291.804836) (xy 274.548092 -291.811964) (xy 274.54352 -291.817552)
			(xy 274.527879 -291.838529) (xy 274.491085 -291.875733) (xy 274.448891 -291.906675) (xy 274.402348 -291.930585)
			(xy 274.352621 -291.946864) (xy 274.30095 -291.955106) (xy 274.248626 -291.955106) (xy 274.196955 -291.946864)
			(xy 274.147228 -291.930585) (xy 274.100685 -291.906675) (xy 274.058491 -291.875733) (xy 274.021697 -291.838529)
			(xy 274.006056 -291.817552) (xy 274.001484 -291.811964) (xy 273.99454 -291.805267) (xy 273.977048 -291.797167)
			(xy 273.967448 -291.796216) (xy 273.837908 -291.796216) (xy 273.827837 -291.795795) (xy 273.809229 -291.788084)
			(xy 273.80184 -291.78123) (xy 273.77771 -291.7571) (xy 273.768807 -291.749152) (xy 273.746155 -291.741731)
			(xy 273.734276 -291.742876) (xy 273.653758 -291.754814) (xy 273.647917 -291.755852) (xy 273.63689 -291.760219)
			(xy 273.631914 -291.76345) (xy 273.62727 -291.766955) (xy 273.619581 -291.775682) (xy 273.616674 -291.780722)
			(xy 273.61642 -291.780976) (xy 273.603945 -291.803225) (xy 273.573216 -291.843935) (xy 273.536607 -291.879452)
			(xy 273.494984 -291.908934) (xy 273.449332 -291.931683) (xy 273.400731 -291.947162) (xy 273.350331 -291.955004)
			(xy 273.324828 -291.955474) (xy 273.298838 -291.954993) (xy 273.247498 -291.946865) (xy 273.198062 -291.930805)
			(xy 273.151748 -291.907208) (xy 273.109695 -291.876656) (xy 273.07294 -291.8399) (xy 273.042389 -291.797847)
			(xy 273.018793 -291.751532) (xy 273.002734 -291.702096) (xy 272.994607 -291.650756) (xy 272.99412 -291.624766)
			(xy 272.994585 -291.599274) (xy 273.002393 -291.54889) (xy 273.017836 -291.5003) (xy 273.040546 -291.454653)
			(xy 273.069988 -291.413029) (xy 273.105465 -291.376411) (xy 273.146138 -291.345667) (xy 273.168364 -291.333174)
			(xy 273.168872 -291.333174) (xy 273.168872 -291.33292) (xy 273.173914 -291.330017) (xy 273.182636 -291.322322)
			(xy 273.186144 -291.31768) (xy 273.189425 -291.312731) (xy 273.19379 -291.301691) (xy 273.19478 -291.295836)
			(xy 273.206718 -291.215318) (xy 273.207875 -291.203437) (xy 273.20045 -291.180784) (xy 273.192494 -291.171884)
			(xy 271.87779 -289.85718) (xy 271.868885 -289.849239) (xy 271.846235 -289.841829) (xy 271.834356 -289.842956)
			(xy 271.753838 -289.854894) (xy 271.747993 -289.855923) (xy 271.736955 -289.860275) (xy 271.731994 -289.86353)
			(xy 271.72735 -289.867035) (xy 271.719661 -289.875762) (xy 271.716754 -289.880802) (xy 271.7165 -289.881056)
			(xy 271.704025 -289.903305) (xy 271.673297 -289.944016) (xy 271.636688 -289.979532) (xy 271.595065 -290.009013)
			(xy 271.549412 -290.031762) (xy 271.500811 -290.047239) (xy 271.450411 -290.055078) (xy 271.424908 -290.055554)
			(xy 271.398919 -290.055045) (xy 271.347581 -290.046916) (xy 271.298146 -290.030856) (xy 271.251832 -290.007261)
			(xy 271.209779 -289.976713) (xy 271.173023 -289.939962) (xy 271.142467 -289.897914) (xy 271.118865 -289.851604)
			(xy 271.102797 -289.802172) (xy 271.094659 -289.750835) (xy 271.0942 -289.724846) (xy 271.094666 -289.699354)
			(xy 271.102477 -289.648972) (xy 271.11792 -289.600384) (xy 271.140632 -289.554738) (xy 271.170074 -289.513114)
			(xy 271.20555 -289.476497) (xy 271.246222 -289.445754) (xy 271.268444 -289.433254) (xy 271.268952 -289.433254)
			(xy 271.268952 -289.433) (xy 271.273994 -289.430097) (xy 271.282717 -289.422402) (xy 271.286224 -289.41776)
			(xy 271.289498 -289.412808) (xy 271.293852 -289.401767) (xy 271.29486 -289.395916) (xy 271.306798 -289.315398)
			(xy 271.30795 -289.303519) (xy 271.300517 -289.280874) (xy 271.292574 -289.271964) (xy 270.92783 -288.90722)
			(xy 270.918928 -288.899266) (xy 270.896275 -288.891832) (xy 270.884396 -288.892996) (xy 270.803878 -288.904934)
			(xy 270.798036 -288.90597) (xy 270.787008 -288.910335) (xy 270.782034 -288.91357) (xy 270.777384 -288.91707)
			(xy 270.76968 -288.925789) (xy 270.766794 -288.930842) (xy 270.76654 -288.931096) (xy 270.754064 -288.953344)
			(xy 270.723335 -288.994055) (xy 270.686725 -289.029571) (xy 270.645103 -289.059054) (xy 270.599451 -289.081804)
			(xy 270.550851 -289.097285) (xy 270.500451 -289.10513) (xy 270.474948 -289.105594) (xy 270.448957 -289.105114)
			(xy 270.397613 -289.096989) (xy 270.348173 -289.080931) (xy 270.301854 -289.057335) (xy 270.259797 -289.026784)
			(xy 270.223038 -288.990029) (xy 270.192482 -288.947975) (xy 270.168882 -288.901658) (xy 270.152819 -288.85222)
			(xy 270.144688 -288.800877) (xy 270.14424 -288.774886) (xy 270.144703 -288.749392) (xy 270.152508 -288.699004)
			(xy 270.167945 -288.650409) (xy 270.190652 -288.604755) (xy 270.220089 -288.563122) (xy 270.255562 -288.526496)
			(xy 270.296231 -288.495741) (xy 270.318484 -288.483294) (xy 270.318992 -288.483294) (xy 270.318992 -288.48304)
			(xy 270.324034 -288.480136) (xy 270.332755 -288.472441) (xy 270.336264 -288.4678) (xy 270.339546 -288.462851)
			(xy 270.343913 -288.451812) (xy 270.3449 -288.445956) (xy 270.356838 -288.365438) (xy 270.358 -288.353555)
			(xy 270.350584 -288.330894) (xy 270.342614 -288.322004) (xy 269.977616 -287.957006) (xy 269.968768 -287.949097)
			(xy 269.946253 -287.941683) (xy 269.934436 -287.942782) (xy 269.868904 -287.952434) (xy 269.85341 -287.95472)
			(xy 269.847704 -287.95571) (xy 269.836927 -287.959941) (xy 269.832074 -287.963102) (xy 269.827502 -287.966404)
			(xy 269.81912 -287.975548) (xy 269.816326 -287.981136) (xy 269.803853 -288.003387) (xy 269.773126 -288.044103)
			(xy 269.736518 -288.079624) (xy 269.694896 -288.109111) (xy 269.649243 -288.131864) (xy 269.60064 -288.147346)
			(xy 269.550238 -288.15519) (xy 269.524734 -288.155634) (xy 269.498742 -288.155153) (xy 269.447398 -288.147027)
			(xy 269.397957 -288.130968) (xy 269.351638 -288.107372) (xy 269.309579 -288.076821) (xy 269.272818 -288.040067)
			(xy 269.242259 -287.998014) (xy 269.218655 -287.951698) (xy 269.202587 -287.90226) (xy 269.194451 -287.850918)
			(xy 269.194026 -287.824926) (xy 269.194496 -287.799422) (xy 269.202322 -287.749018) (xy 269.217793 -287.700413)
			(xy 269.240543 -287.65476) (xy 269.270031 -287.613139) (xy 269.305558 -287.576539) (xy 269.346284 -287.545827)
			(xy 269.368524 -287.533334) (xy 269.37392 -287.530302) (xy 269.383172 -287.522084) (xy 269.386812 -287.517078)
			(xy 269.38986 -287.51276) (xy 269.393924 -287.502092) (xy 269.397226 -287.480756) (xy 269.406878 -287.415224)
			(xy 269.407973 -287.40341) (xy 269.400542 -287.380909) (xy 269.392654 -287.372044) (xy 269.027656 -287.007046)
			(xy 269.018812 -286.999124) (xy 268.996293 -286.991687) (xy 268.984476 -286.992822) (xy 268.918944 -287.002474)
			(xy 268.90345 -287.00476) (xy 268.897746 -287.005755) (xy 268.886973 -287.009993) (xy 268.882114 -287.013142)
			(xy 268.877542 -287.016444) (xy 268.86916 -287.025588) (xy 268.866366 -287.031176) (xy 268.85389 -287.053422)
			(xy 268.823159 -287.094128) (xy 268.786549 -287.129638) (xy 268.744925 -287.159113) (xy 268.699273 -287.181855)
			(xy 268.650673 -287.197327) (xy 268.600275 -287.20516) (xy 268.574774 -287.205674) (xy 268.548787 -287.205189)
			(xy 268.497454 -287.197054) (xy 268.448025 -287.180989) (xy 268.401718 -287.15739) (xy 268.359672 -287.126836)
			(xy 268.322925 -287.090082) (xy 268.292379 -287.048031) (xy 268.268788 -287.00172) (xy 268.252732 -286.952288)
			(xy 268.244606 -286.900953) (xy 268.244066 -286.874966) (xy 268.245336 -286.84601) (xy 268.245844 -286.839406)
			(xy 268.242542 -286.829754) (xy 268.240695 -286.824865) (xy 268.235315 -286.815908) (xy 268.231874 -286.811974)
			(xy 268.178788 -286.755078) (xy 268.171493 -286.748624) (xy 268.153465 -286.741295) (xy 268.143736 -286.740854)
			(xy 266.615418 -286.740854) (xy 266.606428 -286.741194) (xy 266.589553 -286.747395) (xy 266.575879 -286.759067)
			(xy 266.571222 -286.766762) (xy 266.549378 -286.805116) (xy 266.549378 -286.805624) (xy 266.527534 -286.844486)
			(xy 266.524458 -286.850439) (xy 266.521229 -286.86344) (xy 266.521184 -286.87014) (xy 266.521438 -286.883094)
			(xy 266.528804 -286.895286) (xy 266.541971 -286.917773) (xy 266.562753 -286.96556) (xy 266.576836 -287.01573)
			(xy 266.583956 -287.067351) (xy 266.58443 -287.093406) (xy 266.58443 -287.093914) (xy 266.583944 -287.121165)
			(xy 266.576188 -287.175113) (xy 266.560833 -287.227408) (xy 266.538191 -287.276985) (xy 266.508725 -287.322835)
			(xy 266.473034 -287.364026) (xy 266.431843 -287.399717) (xy 266.385993 -287.429183) (xy 266.336416 -287.451825)
			(xy 266.284121 -287.46718) (xy 266.230173 -287.474936) (xy 266.175671 -287.474936) (xy 266.121723 -287.46718)
			(xy 266.069428 -287.451825) (xy 266.019851 -287.429183) (xy 265.974001 -287.399717) (xy 265.93281 -287.364026)
			(xy 265.897119 -287.322835) (xy 265.867653 -287.276985) (xy 265.845011 -287.227408) (xy 265.829656 -287.175113)
			(xy 265.8219 -287.121165) (xy 265.821414 -287.093914) (xy 265.821414 -287.093406) (xy 265.821878 -287.067352)
			(xy 265.829009 -287.015732) (xy 265.843098 -286.965564) (xy 265.863883 -286.917779) (xy 265.87704 -286.895286)
			(xy 265.877294 -286.894778) (xy 265.880606 -286.888948) (xy 265.884343 -286.876075) (xy 265.88466 -286.869378)
			(xy 265.884914 -286.856424) (xy 265.856466 -286.805624) (xy 265.856466 -286.805116) (xy 265.834622 -286.766762)
			(xy 265.8299 -286.759121) (xy 265.816232 -286.747483) (xy 265.7994 -286.741245) (xy 265.790426 -286.740854)
			(xy 263.696958 -286.740854) (xy 263.686892 -286.741286) (xy 263.668304 -286.749017) (xy 263.66089 -286.75584)
			(xy 263.606026 -286.810704) (xy 263.599177 -286.818102) (xy 263.59144 -286.8367) (xy 263.59104 -286.846772)
			(xy 263.59104 -287.824926) (xy 268.26897 -287.824926) (xy 268.27293 -287.775872) (xy 268.284707 -287.728088)
			(xy 268.303998 -287.682812) (xy 268.330301 -287.641216) (xy 268.362936 -287.604379) (xy 268.401057 -287.573254)
			(xy 268.443678 -287.548647) (xy 268.489694 -287.531195) (xy 268.537913 -287.521351) (xy 268.587088 -287.51937)
			(xy 268.635943 -287.525302) (xy 268.683214 -287.538994) (xy 268.727676 -287.560092) (xy 268.768179 -287.588048)
			(xy 268.803672 -287.62214) (xy 268.833237 -287.661484) (xy 268.856108 -287.705061) (xy 268.871692 -287.751742)
			(xy 268.879587 -287.800319) (xy 268.880082 -287.824926) (xy 268.879587 -287.849533) (xy 268.871692 -287.89811)
			(xy 268.856108 -287.944791) (xy 268.833237 -287.988368) (xy 268.803672 -288.027712) (xy 268.768179 -288.061804)
			(xy 268.727676 -288.08976) (xy 268.683214 -288.110858) (xy 268.635943 -288.12455) (xy 268.587088 -288.130482)
			(xy 268.537913 -288.128501) (xy 268.489694 -288.118657) (xy 268.443678 -288.101205) (xy 268.401057 -288.076598)
			(xy 268.362936 -288.045473) (xy 268.330301 -288.008636) (xy 268.303998 -287.96704) (xy 268.284707 -287.921764)
			(xy 268.27293 -287.87398) (xy 268.26897 -287.824926) (xy 263.59104 -287.824926) (xy 263.59104 -288.764218)
			(xy 263.591468 -288.774286) (xy 263.591717 -288.774886) (xy 268.26897 -288.774886) (xy 268.27293 -288.725832)
			(xy 268.284707 -288.678048) (xy 268.303998 -288.632772) (xy 268.330301 -288.591176) (xy 268.362936 -288.554339)
			(xy 268.401057 -288.523214) (xy 268.443678 -288.498607) (xy 268.489694 -288.481155) (xy 268.537913 -288.471311)
			(xy 268.587088 -288.46933) (xy 268.635943 -288.475262) (xy 268.683214 -288.488954) (xy 268.727676 -288.510052)
			(xy 268.768179 -288.538008) (xy 268.803672 -288.5721) (xy 268.833237 -288.611444) (xy 268.856108 -288.655021)
			(xy 268.871692 -288.701702) (xy 268.879587 -288.750279) (xy 268.880082 -288.774886) (xy 269.21893 -288.774886)
			(xy 269.22289 -288.725832) (xy 269.234667 -288.678048) (xy 269.253958 -288.632772) (xy 269.280261 -288.591176)
			(xy 269.312896 -288.554339) (xy 269.351017 -288.523214) (xy 269.393638 -288.498607) (xy 269.439654 -288.481155)
			(xy 269.487873 -288.471311) (xy 269.537048 -288.46933) (xy 269.585903 -288.475262) (xy 269.633174 -288.488954)
			(xy 269.677636 -288.510052) (xy 269.718139 -288.538008) (xy 269.753632 -288.5721) (xy 269.783197 -288.611444)
			(xy 269.806068 -288.655021) (xy 269.821652 -288.701702) (xy 269.829547 -288.750279) (xy 269.830042 -288.774886)
			(xy 269.829547 -288.799493) (xy 269.821652 -288.84807) (xy 269.806068 -288.894751) (xy 269.783197 -288.938328)
			(xy 269.753632 -288.977672) (xy 269.718139 -289.011764) (xy 269.677636 -289.03972) (xy 269.633174 -289.060818)
			(xy 269.585903 -289.07451) (xy 269.537048 -289.080442) (xy 269.487873 -289.078461) (xy 269.439654 -289.068617)
			(xy 269.393638 -289.051165) (xy 269.351017 -289.026558) (xy 269.312896 -288.995433) (xy 269.280261 -288.958596)
			(xy 269.253958 -288.917) (xy 269.234667 -288.871724) (xy 269.22289 -288.82394) (xy 269.21893 -288.774886)
			(xy 268.880082 -288.774886) (xy 268.879587 -288.799493) (xy 268.871692 -288.84807) (xy 268.856108 -288.894751)
			(xy 268.833237 -288.938328) (xy 268.803672 -288.977672) (xy 268.768179 -289.011764) (xy 268.727676 -289.03972)
			(xy 268.683214 -289.060818) (xy 268.635943 -289.07451) (xy 268.587088 -289.080442) (xy 268.537913 -289.078461)
			(xy 268.489694 -289.068617) (xy 268.443678 -289.051165) (xy 268.401057 -289.026558) (xy 268.362936 -288.995433)
			(xy 268.330301 -288.958596) (xy 268.303998 -288.917) (xy 268.284707 -288.871724) (xy 268.27293 -288.82394)
			(xy 268.26897 -288.774886) (xy 263.591717 -288.774886) (xy 263.599191 -288.792882) (xy 263.606026 -288.800286)
			(xy 263.780016 -288.974276) (xy 263.787414 -288.981122) (xy 263.806013 -288.988855) (xy 263.816084 -288.989262)
			(xy 264.315194 -288.989262) (xy 264.32383 -288.9885) (xy 264.336244 -288.986477) (xy 264.361293 -288.984188)
			(xy 264.373868 -288.983928) (xy 267.616178 -288.983928) (xy 267.616686 -288.983928) (xy 267.628798 -288.983997)
			(xy 267.652955 -288.985774) (xy 267.664946 -288.987484) (xy 267.665962 -288.987484) (xy 267.675106 -288.989262)
			(xy 267.92555 -288.989262) (xy 267.935615 -288.989696) (xy 267.9542 -288.99743) (xy 267.961618 -289.004248)
			(xy 268.374114 -289.416744) (xy 268.379818 -289.422082) (xy 268.393656 -289.429315) (xy 268.401292 -289.430968)
			(xy 268.408912 -289.432238) (xy 268.424406 -289.430206) (xy 268.432026 -289.42665) (xy 268.454418 -289.416414)
			(xy 268.501475 -289.401944) (xy 268.550158 -289.394611) (xy 268.574774 -289.394138) (xy 268.600763 -289.394619)
			(xy 268.652102 -289.402748) (xy 268.701537 -289.418808) (xy 268.747851 -289.442405) (xy 268.789902 -289.472958)
			(xy 268.826655 -289.509713) (xy 268.857205 -289.551766) (xy 268.8808 -289.598081) (xy 268.896857 -289.647517)
			(xy 268.904982 -289.698857) (xy 268.905482 -289.724846) (xy 269.21893 -289.724846) (xy 269.22289 -289.675792)
			(xy 269.234667 -289.628008) (xy 269.253958 -289.582732) (xy 269.280261 -289.541136) (xy 269.312896 -289.504299)
			(xy 269.351017 -289.473174) (xy 269.393638 -289.448567) (xy 269.439654 -289.431115) (xy 269.487873 -289.421271)
			(xy 269.537048 -289.41929) (xy 269.585903 -289.425222) (xy 269.633174 -289.438914) (xy 269.677636 -289.460012)
			(xy 269.718139 -289.487968) (xy 269.753632 -289.52206) (xy 269.783197 -289.561404) (xy 269.806068 -289.604981)
			(xy 269.821652 -289.651662) (xy 269.829547 -289.700239) (xy 269.830042 -289.724846) (xy 270.169144 -289.724846)
			(xy 270.173104 -289.675792) (xy 270.184881 -289.628008) (xy 270.204172 -289.582732) (xy 270.230475 -289.541136)
			(xy 270.26311 -289.504299) (xy 270.301231 -289.473174) (xy 270.343852 -289.448567) (xy 270.389868 -289.431115)
			(xy 270.438087 -289.421271) (xy 270.487262 -289.41929) (xy 270.536117 -289.425222) (xy 270.583388 -289.438914)
			(xy 270.62785 -289.460012) (xy 270.668353 -289.487968) (xy 270.703846 -289.52206) (xy 270.733411 -289.561404)
			(xy 270.756282 -289.604981) (xy 270.771866 -289.651662) (xy 270.779761 -289.700239) (xy 270.780256 -289.724846)
			(xy 270.779761 -289.749453) (xy 270.771866 -289.79803) (xy 270.756282 -289.844711) (xy 270.733411 -289.888288)
			(xy 270.703846 -289.927632) (xy 270.668353 -289.961724) (xy 270.62785 -289.98968) (xy 270.583388 -290.010778)
			(xy 270.536117 -290.02447) (xy 270.487262 -290.030402) (xy 270.438087 -290.028421) (xy 270.389868 -290.018577)
			(xy 270.343852 -290.001125) (xy 270.301231 -289.976518) (xy 270.26311 -289.945393) (xy 270.230475 -289.908556)
			(xy 270.204172 -289.86696) (xy 270.184881 -289.821684) (xy 270.173104 -289.7739) (xy 270.169144 -289.724846)
			(xy 269.830042 -289.724846) (xy 269.829547 -289.749453) (xy 269.821652 -289.79803) (xy 269.806068 -289.844711)
			(xy 269.783197 -289.888288) (xy 269.753632 -289.927632) (xy 269.718139 -289.961724) (xy 269.677636 -289.98968)
			(xy 269.633174 -290.010778) (xy 269.585903 -290.02447) (xy 269.537048 -290.030402) (xy 269.487873 -290.028421)
			(xy 269.439654 -290.018577) (xy 269.393638 -290.001125) (xy 269.351017 -289.976518) (xy 269.312896 -289.945393)
			(xy 269.280261 -289.908556) (xy 269.253958 -289.86696) (xy 269.234667 -289.821684) (xy 269.22289 -289.7739)
			(xy 269.21893 -289.724846) (xy 268.905482 -289.724846) (xy 268.905012 -289.749462) (xy 268.897678 -289.798145)
			(xy 268.88321 -289.845204) (xy 268.87297 -289.867594) (xy 268.872716 -289.867848) (xy 268.869631 -289.875117)
			(xy 268.867553 -289.890763) (xy 268.868652 -289.898582) (xy 268.869922 -289.905948) (xy 268.877288 -289.919918)
			(xy 269.324074 -290.366704) (xy 269.329774 -290.37205) (xy 269.343609 -290.3793) (xy 269.351252 -290.380928)
			(xy 269.358872 -290.382198) (xy 269.374366 -290.380166) (xy 269.381986 -290.37661) (xy 269.404377 -290.36637)
			(xy 269.451434 -290.351891) (xy 269.500117 -290.344551) (xy 269.524734 -290.344098) (xy 269.550719 -290.34461)
			(xy 269.602049 -290.352745) (xy 269.651475 -290.368809) (xy 269.697779 -290.392407) (xy 269.739822 -290.422957)
			(xy 269.776569 -290.459708) (xy 269.807114 -290.501755) (xy 269.830706 -290.548062) (xy 269.846764 -290.59749)
			(xy 269.854893 -290.648821) (xy 269.855442 -290.674806) (xy 270.169144 -290.674806) (xy 270.173104 -290.625752)
			(xy 270.184881 -290.577968) (xy 270.204172 -290.532692) (xy 270.230475 -290.491096) (xy 270.26311 -290.454259)
			(xy 270.301231 -290.423134) (xy 270.343852 -290.398527) (xy 270.389868 -290.381075) (xy 270.438087 -290.371231)
			(xy 270.487262 -290.36925) (xy 270.536117 -290.375182) (xy 270.583388 -290.388874) (xy 270.62785 -290.409972)
			(xy 270.668353 -290.437928) (xy 270.703846 -290.47202) (xy 270.733411 -290.511364) (xy 270.756282 -290.554941)
			(xy 270.771866 -290.601622) (xy 270.779761 -290.650199) (xy 270.780256 -290.674806) (xy 270.779761 -290.699413)
			(xy 270.771866 -290.74799) (xy 270.756282 -290.794671) (xy 270.733411 -290.838248) (xy 270.703846 -290.877592)
			(xy 270.668353 -290.911684) (xy 270.62785 -290.93964) (xy 270.583388 -290.960738) (xy 270.536117 -290.97443)
			(xy 270.487262 -290.980362) (xy 270.438087 -290.978381) (xy 270.389868 -290.968537) (xy 270.343852 -290.951085)
			(xy 270.301231 -290.926478) (xy 270.26311 -290.895353) (xy 270.230475 -290.858516) (xy 270.204172 -290.81692)
			(xy 270.184881 -290.771644) (xy 270.173104 -290.72386) (xy 270.169144 -290.674806) (xy 269.855442 -290.674806)
			(xy 269.854967 -290.699421) (xy 269.847624 -290.748101) (xy 269.833147 -290.795154) (xy 269.82293 -290.817554)
			(xy 269.822676 -290.817808) (xy 269.819597 -290.825077) (xy 269.817535 -290.840721) (xy 269.818612 -290.848542)
			(xy 269.819882 -290.855908) (xy 269.827248 -290.869878) (xy 270.274034 -291.316664) (xy 270.279735 -291.32201)
			(xy 270.293569 -291.329261) (xy 270.301212 -291.330888) (xy 270.308832 -291.332158) (xy 270.324834 -291.330126)
			(xy 270.331946 -291.32657) (xy 270.354377 -291.31632) (xy 270.40152 -291.301839) (xy 270.45029 -291.294521)
			(xy 270.474948 -291.294058) (xy 270.500934 -291.294571) (xy 270.552264 -291.302707) (xy 270.601691 -291.318772)
			(xy 270.647996 -291.34237) (xy 270.69004 -291.37292) (xy 270.726789 -291.40967) (xy 270.757337 -291.451716)
			(xy 270.780933 -291.498022) (xy 270.796996 -291.547449) (xy 270.80513 -291.59878) (xy 270.805656 -291.624766)
			(xy 270.805203 -291.649425) (xy 270.797885 -291.698197) (xy 270.783406 -291.745342) (xy 270.773144 -291.767768)
			(xy 270.769588 -291.77488) (xy 270.767556 -291.790882) (xy 270.768826 -291.798502) (xy 270.77047 -291.80614)
			(xy 270.777713 -291.819974) (xy 270.78305 -291.82568) (xy 271.223994 -292.266624) (xy 271.229696 -292.271966)
			(xy 271.243533 -292.279207) (xy 271.251172 -292.280848) (xy 271.258792 -292.282118) (xy 271.274794 -292.280086)
			(xy 271.281906 -292.27653) (xy 271.304336 -292.266275) (xy 271.351478 -292.251786) (xy 271.400249 -292.244461)
			(xy 271.424908 -292.244018) (xy 271.450896 -292.244502) (xy 271.502232 -292.252634) (xy 271.551664 -292.268697)
			(xy 271.597974 -292.292296) (xy 271.640022 -292.322849) (xy 271.676773 -292.359603) (xy 271.707322 -292.401655)
			(xy 271.730916 -292.447967) (xy 271.746974 -292.497401) (xy 271.755101 -292.548738) (xy 271.755616 -292.574726)
			(xy 272.069064 -292.574726) (xy 272.073024 -292.525672) (xy 272.084801 -292.477888) (xy 272.104092 -292.432612)
			(xy 272.130395 -292.391016) (xy 272.16303 -292.354179) (xy 272.201151 -292.323054) (xy 272.243772 -292.298447)
			(xy 272.289788 -292.280995) (xy 272.338007 -292.271151) (xy 272.387182 -292.26917) (xy 272.436037 -292.275102)
			(xy 272.483308 -292.288794) (xy 272.52777 -292.309892) (xy 272.568273 -292.337848) (xy 272.603766 -292.37194)
			(xy 272.633331 -292.411284) (xy 272.656202 -292.454861) (xy 272.671786 -292.501542) (xy 272.679681 -292.550119)
			(xy 272.680176 -292.574726) (xy 272.680171 -292.57498) (xy 273.019024 -292.57498) (xy 273.022984 -292.525926)
			(xy 273.034761 -292.478142) (xy 273.054052 -292.432866) (xy 273.080355 -292.39127) (xy 273.11299 -292.354433)
			(xy 273.151111 -292.323308) (xy 273.193732 -292.298701) (xy 273.239748 -292.281249) (xy 273.287967 -292.271405)
			(xy 273.337142 -292.269424) (xy 273.385997 -292.275356) (xy 273.433268 -292.289048) (xy 273.47773 -292.310146)
			(xy 273.518233 -292.338102) (xy 273.553726 -292.372194) (xy 273.583291 -292.411538) (xy 273.606162 -292.455115)
			(xy 273.621746 -292.501796) (xy 273.629641 -292.550373) (xy 273.630136 -292.57498) (xy 273.629641 -292.599587)
			(xy 273.629309 -292.601629) (xy 273.919178 -292.601629) (xy 273.919178 -292.548331) (xy 273.927121 -292.495627)
			(xy 273.942831 -292.444697) (xy 273.965957 -292.396676) (xy 273.995981 -292.352639) (xy 274.032233 -292.313568)
			(xy 274.073904 -292.280337) (xy 274.120062 -292.253688) (xy 274.169676 -292.234216) (xy 274.221638 -292.222356)
			(xy 274.274788 -292.218373) (xy 274.327938 -292.222356) (xy 274.3799 -292.234216) (xy 274.429514 -292.253688)
			(xy 274.475672 -292.280337) (xy 274.517343 -292.313568) (xy 274.553595 -292.352639) (xy 274.583619 -292.396676)
			(xy 274.606745 -292.444697) (xy 274.622455 -292.495627) (xy 274.630398 -292.548331) (xy 274.630896 -292.57498)
			(xy 274.918944 -292.57498) (xy 274.922904 -292.525926) (xy 274.934681 -292.478142) (xy 274.953972 -292.432866)
			(xy 274.980275 -292.39127) (xy 275.01291 -292.354433) (xy 275.051031 -292.323308) (xy 275.093652 -292.298701)
			(xy 275.139668 -292.281249) (xy 275.187887 -292.271405) (xy 275.237062 -292.269424) (xy 275.285917 -292.275356)
			(xy 275.333188 -292.289048) (xy 275.37765 -292.310146) (xy 275.418153 -292.338102) (xy 275.453646 -292.372194)
			(xy 275.483211 -292.411538) (xy 275.506082 -292.455115) (xy 275.521666 -292.501796) (xy 275.529561 -292.550373)
			(xy 275.530056 -292.57498) (xy 275.868904 -292.57498) (xy 275.872864 -292.525926) (xy 275.884641 -292.478142)
			(xy 275.903932 -292.432866) (xy 275.930235 -292.39127) (xy 275.96287 -292.354433) (xy 276.000991 -292.323308)
			(xy 276.043612 -292.298701) (xy 276.089628 -292.281249) (xy 276.137847 -292.271405) (xy 276.187022 -292.269424)
			(xy 276.235877 -292.275356) (xy 276.283148 -292.289048) (xy 276.32761 -292.310146) (xy 276.368113 -292.338102)
			(xy 276.403606 -292.372194) (xy 276.433171 -292.411538) (xy 276.456042 -292.455115) (xy 276.471626 -292.501796)
			(xy 276.479521 -292.550373) (xy 276.480016 -292.57498) (xy 276.819118 -292.57498) (xy 276.823078 -292.525926)
			(xy 276.834855 -292.478142) (xy 276.854146 -292.432866) (xy 276.880449 -292.39127) (xy 276.913084 -292.354433)
			(xy 276.951205 -292.323308) (xy 276.993826 -292.298701) (xy 277.039842 -292.281249) (xy 277.088061 -292.271405)
			(xy 277.137236 -292.269424) (xy 277.186091 -292.275356) (xy 277.233362 -292.289048) (xy 277.277824 -292.310146)
			(xy 277.318327 -292.338102) (xy 277.35382 -292.372194) (xy 277.383385 -292.411538) (xy 277.406256 -292.455115)
			(xy 277.42184 -292.501796) (xy 277.429735 -292.550373) (xy 277.43023 -292.57498) (xy 277.769078 -292.57498)
			(xy 277.773038 -292.525926) (xy 277.784815 -292.478142) (xy 277.804106 -292.432866) (xy 277.830409 -292.39127)
			(xy 277.863044 -292.354433) (xy 277.901165 -292.323308) (xy 277.943786 -292.298701) (xy 277.989802 -292.281249)
			(xy 278.038021 -292.271405) (xy 278.087196 -292.269424) (xy 278.136051 -292.275356) (xy 278.183322 -292.289048)
			(xy 278.227784 -292.310146) (xy 278.268287 -292.338102) (xy 278.30378 -292.372194) (xy 278.333345 -292.411538)
			(xy 278.356216 -292.455115) (xy 278.3718 -292.501796) (xy 278.379695 -292.550373) (xy 278.38019 -292.57498)
			(xy 278.379695 -292.599587) (xy 278.3718 -292.648164) (xy 278.356216 -292.694845) (xy 278.333345 -292.738422)
			(xy 278.30378 -292.777766) (xy 278.268287 -292.811858) (xy 278.227784 -292.839814) (xy 278.183322 -292.860912)
			(xy 278.136051 -292.874604) (xy 278.087196 -292.880536) (xy 278.038021 -292.878555) (xy 277.989802 -292.868711)
			(xy 277.943786 -292.851259) (xy 277.901165 -292.826652) (xy 277.863044 -292.795527) (xy 277.830409 -292.75869)
			(xy 277.804106 -292.717094) (xy 277.784815 -292.671818) (xy 277.773038 -292.624034) (xy 277.769078 -292.57498)
			(xy 277.43023 -292.57498) (xy 277.429735 -292.599587) (xy 277.42184 -292.648164) (xy 277.406256 -292.694845)
			(xy 277.383385 -292.738422) (xy 277.35382 -292.777766) (xy 277.318327 -292.811858) (xy 277.277824 -292.839814)
			(xy 277.233362 -292.860912) (xy 277.186091 -292.874604) (xy 277.137236 -292.880536) (xy 277.088061 -292.878555)
			(xy 277.039842 -292.868711) (xy 276.993826 -292.851259) (xy 276.951205 -292.826652) (xy 276.913084 -292.795527)
			(xy 276.880449 -292.75869) (xy 276.854146 -292.717094) (xy 276.834855 -292.671818) (xy 276.823078 -292.624034)
			(xy 276.819118 -292.57498) (xy 276.480016 -292.57498) (xy 276.479521 -292.599587) (xy 276.471626 -292.648164)
			(xy 276.456042 -292.694845) (xy 276.433171 -292.738422) (xy 276.403606 -292.777766) (xy 276.368113 -292.811858)
			(xy 276.32761 -292.839814) (xy 276.283148 -292.860912) (xy 276.235877 -292.874604) (xy 276.187022 -292.880536)
			(xy 276.137847 -292.878555) (xy 276.089628 -292.868711) (xy 276.043612 -292.851259) (xy 276.000991 -292.826652)
			(xy 275.96287 -292.795527) (xy 275.930235 -292.75869) (xy 275.903932 -292.717094) (xy 275.884641 -292.671818)
			(xy 275.872864 -292.624034) (xy 275.868904 -292.57498) (xy 275.530056 -292.57498) (xy 275.529561 -292.599587)
			(xy 275.521666 -292.648164) (xy 275.506082 -292.694845) (xy 275.483211 -292.738422) (xy 275.453646 -292.777766)
			(xy 275.418153 -292.811858) (xy 275.37765 -292.839814) (xy 275.333188 -292.860912) (xy 275.285917 -292.874604)
			(xy 275.237062 -292.880536) (xy 275.187887 -292.878555) (xy 275.139668 -292.868711) (xy 275.093652 -292.851259)
			(xy 275.051031 -292.826652) (xy 275.01291 -292.795527) (xy 274.980275 -292.75869) (xy 274.953972 -292.717094)
			(xy 274.934681 -292.671818) (xy 274.922904 -292.624034) (xy 274.918944 -292.57498) (xy 274.630896 -292.57498)
			(xy 274.630398 -292.601629) (xy 274.622455 -292.654333) (xy 274.606745 -292.705263) (xy 274.583619 -292.753284)
			(xy 274.553595 -292.797321) (xy 274.517343 -292.836392) (xy 274.475672 -292.869623) (xy 274.429514 -292.896272)
			(xy 274.3799 -292.915744) (xy 274.327938 -292.927604) (xy 274.274788 -292.931588) (xy 274.221638 -292.927604)
			(xy 274.169676 -292.915744) (xy 274.120062 -292.896272) (xy 274.073904 -292.869623) (xy 274.032233 -292.836392)
			(xy 273.995981 -292.797321) (xy 273.965957 -292.753284) (xy 273.942831 -292.705263) (xy 273.927121 -292.654333)
			(xy 273.919178 -292.601629) (xy 273.629309 -292.601629) (xy 273.621746 -292.648164) (xy 273.606162 -292.694845)
			(xy 273.583291 -292.738422) (xy 273.553726 -292.777766) (xy 273.518233 -292.811858) (xy 273.47773 -292.839814)
			(xy 273.433268 -292.860912) (xy 273.385997 -292.874604) (xy 273.337142 -292.880536) (xy 273.287967 -292.878555)
			(xy 273.239748 -292.868711) (xy 273.193732 -292.851259) (xy 273.151111 -292.826652) (xy 273.11299 -292.795527)
			(xy 273.080355 -292.75869) (xy 273.054052 -292.717094) (xy 273.034761 -292.671818) (xy 273.022984 -292.624034)
			(xy 273.019024 -292.57498) (xy 272.680171 -292.57498) (xy 272.679681 -292.599333) (xy 272.671786 -292.64791)
			(xy 272.656202 -292.694591) (xy 272.633331 -292.738168) (xy 272.603766 -292.777512) (xy 272.568273 -292.811604)
			(xy 272.52777 -292.83956) (xy 272.483308 -292.860658) (xy 272.436037 -292.87435) (xy 272.387182 -292.880282)
			(xy 272.338007 -292.878301) (xy 272.289788 -292.868457) (xy 272.243772 -292.851005) (xy 272.201151 -292.826398)
			(xy 272.16303 -292.795273) (xy 272.130395 -292.758436) (xy 272.104092 -292.71684) (xy 272.084801 -292.671564)
			(xy 272.073024 -292.62378) (xy 272.069064 -292.574726) (xy 271.755616 -292.574726) (xy 271.755159 -292.599384)
			(xy 271.747834 -292.648153) (xy 271.73335 -292.695295) (xy 271.723104 -292.717728) (xy 271.719548 -292.72484)
			(xy 271.717516 -292.740842) (xy 271.718786 -292.748462) (xy 271.720437 -292.756097) (xy 271.727686 -292.769923)
			(xy 271.73301 -292.77564) (xy 272.174208 -293.216838) (xy 272.179911 -293.222178) (xy 272.193749 -293.229413)
			(xy 272.201386 -293.231062) (xy 272.209006 -293.232332) (xy 272.2245 -293.2303) (xy 272.23212 -293.226744)
			(xy 272.254512 -293.216508) (xy 272.301569 -293.202037) (xy 272.350252 -293.194704) (xy 272.374868 -293.194232)
			(xy 272.400625 -293.194729) (xy 272.451515 -293.202725) (xy 272.50055 -293.218515) (xy 272.546545 -293.241716)
			(xy 272.588386 -293.271767) (xy 272.625063 -293.307941) (xy 272.655688 -293.349363) (xy 272.679521 -293.395033)
			(xy 272.695985 -293.443846) (xy 272.704684 -293.494621) (xy 272.705576 -293.520368) (xy 272.70583 -293.54145)
			(xy 272.71218 -293.5478) (xy 272.720054 -293.548562) (xy 272.722848 -293.551102) (xy 272.730173 -293.557655)
			(xy 272.748337 -293.565113) (xy 272.758154 -293.56558)
		)
		(stroke
			(width 0)
			(type solid)
		)
		(fill yes)
		(layer "In13.Cu")
		(net "PCEPLL6_VDDA18_PEX2")
	)
	(gr_poly
		(pts
			(xy 295.800526 -172.772832) (xy 295.810595 -172.772405) (xy 295.829195 -172.764688) (xy 295.836594 -172.757846)
			(xy 295.987216 -172.607224) (xy 295.993996 -172.5998) (xy 296.001596 -172.581203) (xy 296.001948 -172.571156)
			(xy 296.001948 -172.02404) (xy 296.00248 -171.990751) (xy 296.011194 -171.924744) (xy 296.028452 -171.86044)
			(xy 296.053958 -171.79894) (xy 296.087276 -171.741297) (xy 296.127835 -171.688498) (xy 296.151046 -171.66463)
			(xy 296.199052 -171.61637) (xy 296.205863 -171.609025) (xy 296.213592 -171.590562) (xy 296.214038 -171.580556)
			(xy 296.214038 -147.845526) (xy 296.2136 -147.835463) (xy 296.205859 -147.816884) (xy 296.199052 -147.809458)
			(xy 289.632898 -141.243304) (xy 289.625553 -141.236493) (xy 289.607091 -141.228761) (xy 289.597084 -141.228318)
			(xy 289.51555 -141.228064) (xy 289.497262 -141.23543) (xy 289.489896 -141.242542) (xy 289.468372 -141.262848)
			(xy 289.420219 -141.297233) (xy 289.367335 -141.323773) (xy 289.310987 -141.34183) (xy 289.252527 -141.350971)
			(xy 289.222942 -141.351508) (xy 289.195687 -141.351048) (xy 289.141732 -141.343295) (xy 289.089429 -141.327943)
			(xy 289.039843 -141.305303) (xy 288.993985 -141.275836) (xy 288.952787 -141.240142) (xy 288.917089 -141.198949)
			(xy 288.887617 -141.153093) (xy 288.864972 -141.103511) (xy 288.849614 -141.051209) (xy 288.841855 -140.997255)
			(xy 288.841434 -140.97) (xy 288.841991 -140.940416) (xy 288.851127 -140.881957) (xy 288.869179 -140.82561)
			(xy 288.895716 -140.772726) (xy 288.930099 -140.724573) (xy 288.9504 -140.703046) (xy 288.957512 -140.69568)
			(xy 288.964878 -140.677392) (xy 288.964624 -140.595858) (xy 288.96408 -140.585873) (xy 288.956358 -140.56745)
			(xy 288.949638 -140.560044) (xy 288.037524 -139.64793) (xy 288.030123 -139.641092) (xy 288.011524 -139.633381)
			(xy 288.001456 -139.632944) (xy 279.870154 -139.632944) (xy 279.860191 -139.633428) (xy 279.841766 -139.641015)
			(xy 279.83434 -139.647676) (xy 279.776174 -139.705334) (xy 279.768554 -139.723622) (xy 279.768554 -139.733782)
			(xy 279.767916 -139.76069) (xy 279.759997 -139.813927) (xy 279.744668 -139.865521) (xy 279.722234 -139.914446)
			(xy 279.69314 -139.959728) (xy 279.657965 -140.000467) (xy 279.637998 -140.018516) (xy 279.630124 -140.025628)
			(xy 279.62098 -140.04417) (xy 279.616916 -140.138658) (xy 279.624028 -140.157962) (xy 279.631394 -140.165582)
			(xy 279.651189 -140.187009) (xy 279.684694 -140.234756) (xy 279.710534 -140.287052) (xy 279.728104 -140.342673)
			(xy 279.736993 -140.400323) (xy 279.737566 -140.429488) (xy 279.73708 -140.456739) (xy 279.729324 -140.510687)
			(xy 279.713969 -140.562982) (xy 279.691327 -140.612559) (xy 279.661861 -140.658409) (xy 279.62617 -140.6996)
			(xy 279.584979 -140.735291) (xy 279.539129 -140.764757) (xy 279.538549 -140.765022) (xy 283.451554 -140.765022)
			(xy 283.452113 -140.736137) (xy 283.460798 -140.679024) (xy 283.478005 -140.623876) (xy 283.503337 -140.571957)
			(xy 283.536215 -140.524456) (xy 283.575886 -140.482462) (xy 283.62144 -140.446936) (xy 283.671835 -140.418692)
			(xy 283.725915 -140.398378) (xy 283.754068 -140.391896) (xy 283.76499 -140.389356) (xy 283.782516 -140.376656)
			(xy 283.830776 -140.289788) (xy 283.8323 -140.268198) (xy 283.82849 -140.257784) (xy 283.817816 -140.226272)
			(xy 283.806326 -140.160746) (xy 283.80563 -140.127482) (xy 283.806116 -140.100231) (xy 283.813872 -140.046283)
			(xy 283.829227 -139.993988) (xy 283.851869 -139.944411) (xy 283.881335 -139.898561) (xy 283.917026 -139.85737)
			(xy 283.958217 -139.821679) (xy 284.004067 -139.792213) (xy 284.053644 -139.769571) (xy 284.105939 -139.754216)
			(xy 284.159887 -139.74646) (xy 284.214389 -139.74646) (xy 284.268337 -139.754216) (xy 284.320632 -139.769571)
			(xy 284.370209 -139.792213) (xy 284.416059 -139.821679) (xy 284.45725 -139.85737) (xy 284.492941 -139.898561)
			(xy 284.522407 -139.944411) (xy 284.545049 -139.993988) (xy 284.560404 -140.046283) (xy 284.56816 -140.100231)
			(xy 284.568646 -140.127482) (xy 284.568091 -140.156367) (xy 284.559405 -140.21348) (xy 284.542198 -140.268628)
			(xy 284.516865 -140.320547) (xy 284.483986 -140.368048) (xy 284.444315 -140.410042) (xy 284.39876 -140.445568)
			(xy 284.348366 -140.473812) (xy 284.294285 -140.494126) (xy 284.266132 -140.500608) (xy 284.25521 -140.503148)
			(xy 284.237684 -140.515848) (xy 284.189424 -140.602716) (xy 284.1879 -140.624306) (xy 284.19171 -140.63472)
			(xy 284.202385 -140.666232) (xy 284.213875 -140.731758) (xy 284.21457 -140.765022) (xy 284.214084 -140.792273)
			(xy 284.206328 -140.846221) (xy 284.190973 -140.898516) (xy 284.168331 -140.948093) (xy 284.138865 -140.993943)
			(xy 284.103174 -141.035134) (xy 284.061983 -141.070825) (xy 284.016133 -141.100291) (xy 283.966556 -141.122933)
			(xy 283.914261 -141.138288) (xy 283.860313 -141.146044) (xy 283.805811 -141.146044) (xy 283.751863 -141.138288)
			(xy 283.699568 -141.122933) (xy 283.649991 -141.100291) (xy 283.604141 -141.070825) (xy 283.56295 -141.035134)
			(xy 283.527259 -140.993943) (xy 283.497793 -140.948093) (xy 283.475151 -140.898516) (xy 283.459796 -140.846221)
			(xy 283.45204 -140.792273) (xy 283.451554 -140.765022) (xy 279.538549 -140.765022) (xy 279.489552 -140.787399)
			(xy 279.437257 -140.802754) (xy 279.383309 -140.81051) (xy 279.328807 -140.81051) (xy 279.274859 -140.802754)
			(xy 279.222564 -140.787399) (xy 279.172987 -140.764757) (xy 279.127137 -140.735291) (xy 279.085946 -140.6996)
			(xy 279.050255 -140.658409) (xy 279.020789 -140.612559) (xy 278.998147 -140.562982) (xy 278.982792 -140.510687)
			(xy 278.975036 -140.456739) (xy 278.97455 -140.429488) (xy 278.975028 -140.402365) (xy 278.982715 -140.348667)
			(xy 278.997931 -140.296599) (xy 279.020371 -140.247212) (xy 279.04958 -140.201502) (xy 279.084971 -140.160392)
			(xy 279.105106 -140.142214) (xy 279.11298 -140.135102) (xy 279.122124 -140.11656) (xy 279.126188 -140.022072)
			(xy 279.119076 -140.002768) (xy 279.11171 -139.995148) (xy 279.09208 -139.973916) (xy 279.058807 -139.926626)
			(xy 279.033056 -139.874854) (xy 279.01542 -139.819787) (xy 279.006301 -139.762689) (xy 279.005538 -139.733782)
			(xy 279.005538 -139.723622) (xy 278.997918 -139.705334) (xy 278.939752 -139.647676) (xy 278.932344 -139.640986)
			(xy 278.913908 -139.633389) (xy 278.903938 -139.632944) (xy 271.428464 -139.632944) (xy 271.418398 -139.633375)
			(xy 271.399807 -139.641104) (xy 271.392396 -139.64793) (xy 270.01089 -141.029436) (xy 271.791174 -141.029436)
			(xy 271.795245 -140.973814) (xy 271.807371 -140.919377) (xy 271.827294 -140.867286) (xy 271.85459 -140.818651)
			(xy 271.888676 -140.774508) (xy 271.928825 -140.735799) (xy 271.974183 -140.703348) (xy 272.023783 -140.677847)
			(xy 272.076567 -140.65984) (xy 272.13141 -140.64971) (xy 272.187144 -140.647673) (xy 272.242581 -140.653773)
			(xy 272.296538 -140.667879) (xy 272.347867 -140.689691) (xy 272.395473 -140.718745) (xy 272.438341 -140.75442)
			(xy 272.475558 -140.795957) (xy 272.506331 -140.84247) (xy 272.530003 -140.892967) (xy 272.546071 -140.946374)
			(xy 272.554191 -141.00155) (xy 272.5547 -141.029436) (xy 272.554191 -141.057322) (xy 272.546071 -141.112498)
			(xy 272.530003 -141.165905) (xy 272.506331 -141.216402) (xy 272.475558 -141.262915) (xy 272.438341 -141.304452)
			(xy 272.395473 -141.340127) (xy 272.347867 -141.369181) (xy 272.296538 -141.390993) (xy 272.242581 -141.405099)
			(xy 272.187144 -141.411199) (xy 272.13141 -141.409162) (xy 272.076567 -141.399032) (xy 272.023783 -141.381025)
			(xy 271.974183 -141.355524) (xy 271.928825 -141.323073) (xy 271.888676 -141.284364) (xy 271.85459 -141.240221)
			(xy 271.827294 -141.191586) (xy 271.807371 -141.139495) (xy 271.795245 -141.085058) (xy 271.791174 -141.029436)
			(xy 270.01089 -141.029436) (xy 268.562836 -142.47749) (xy 268.555984 -142.484886) (xy 268.54824 -142.503485)
			(xy 268.54785 -142.513558) (xy 268.54785 -142.748762) (xy 271.718784 -142.748762) (xy 271.722855 -142.69314)
			(xy 271.734981 -142.638703) (xy 271.754904 -142.586612) (xy 271.7822 -142.537977) (xy 271.816286 -142.493834)
			(xy 271.856435 -142.455125) (xy 271.901793 -142.422674) (xy 271.951393 -142.397173) (xy 272.004177 -142.379166)
			(xy 272.05902 -142.369036) (xy 272.114754 -142.366999) (xy 272.170191 -142.373099) (xy 272.224148 -142.387205)
			(xy 272.275477 -142.409017) (xy 272.323083 -142.438071) (xy 272.365951 -142.473746) (xy 272.403168 -142.515283)
			(xy 272.433941 -142.561796) (xy 272.457613 -142.612293) (xy 272.473681 -142.6657) (xy 272.481801 -142.720876)
			(xy 272.48231 -142.748762) (xy 272.481801 -142.776648) (xy 272.473681 -142.831824) (xy 272.465047 -142.860522)
			(xy 278.83358 -142.860522) (xy 278.834103 -142.831839) (xy 278.842712 -142.775123) (xy 278.859707 -142.720333)
			(xy 278.884708 -142.668702) (xy 278.917152 -142.621392) (xy 278.956308 -142.579468) (xy 279.001295 -142.543874)
			(xy 279.0511 -142.515409) (xy 279.104603 -142.494716) (xy 279.1606 -142.48226) (xy 279.18918 -142.479776)
			(xy 279.203671 -142.478235) (xy 279.230972 -142.468087) (xy 279.2543 -142.450647) (xy 279.271756 -142.427331)
			(xy 279.281921 -142.400036) (xy 279.283414 -142.385542) (xy 279.285893 -142.356958) (xy 279.298322 -142.300947)
			(xy 279.318998 -142.247428) (xy 279.347453 -142.197608) (xy 279.383047 -142.15261) (xy 279.424976 -142.113448)
			(xy 279.472296 -142.081005) (xy 279.523941 -142.056013) (xy 279.578745 -142.039035) (xy 279.635473 -142.030454)
			(xy 279.66416 -142.029942) (xy 279.691414 -142.030393) (xy 279.745368 -142.038145) (xy 279.797669 -142.053499)
			(xy 279.847253 -142.07614) (xy 279.893108 -142.105609) (xy 279.934303 -142.141304) (xy 279.969997 -142.1825)
			(xy 279.999464 -142.228356) (xy 280.022105 -142.27794) (xy 280.037457 -142.330242) (xy 280.045208 -142.384196)
			(xy 280.045668 -142.41145) (xy 280.045167 -142.440132) (xy 280.036549 -142.496847) (xy 280.019547 -142.551635)
			(xy 279.995792 -142.60068) (xy 283.80563 -142.60068) (xy 283.806093 -142.573275) (xy 283.813944 -142.51903)
			(xy 283.829482 -142.466469) (xy 283.852385 -142.416674) (xy 283.882183 -142.370671) (xy 283.899864 -142.349728)
			(xy 283.90596 -142.342616) (xy 283.91231 -142.325598) (xy 283.91231 -142.24) (xy 283.90596 -142.222982)
			(xy 283.899864 -142.21587) (xy 283.882192 -142.19492) (xy 283.852396 -142.148918) (xy 283.829493 -142.099125)
			(xy 283.813957 -142.046565) (xy 283.806106 -141.992322) (xy 283.80563 -141.964918) (xy 283.806116 -141.937667)
			(xy 283.813872 -141.883719) (xy 283.829227 -141.831424) (xy 283.851869 -141.781847) (xy 283.881335 -141.735997)
			(xy 283.917026 -141.694806) (xy 283.958217 -141.659115) (xy 284.004067 -141.629649) (xy 284.053644 -141.607007)
			(xy 284.105939 -141.591652) (xy 284.159887 -141.583896) (xy 284.214389 -141.583896) (xy 284.268337 -141.591652)
			(xy 284.320632 -141.607007) (xy 284.370209 -141.629649) (xy 284.416059 -141.659115) (xy 284.45725 -141.694806)
			(xy 284.492941 -141.735997) (xy 284.522407 -141.781847) (xy 284.545049 -141.831424) (xy 284.560404 -141.883719)
			(xy 284.56816 -141.937667) (xy 284.568646 -141.964918) (xy 284.568187 -141.992323) (xy 284.560336 -142.046568)
			(xy 284.544798 -142.09913) (xy 284.521893 -142.148925) (xy 284.492094 -142.194927) (xy 284.474412 -142.21587)
			(xy 284.468316 -142.222982) (xy 284.461966 -142.24) (xy 284.461966 -142.325598) (xy 284.468316 -142.342616)
			(xy 284.474412 -142.349728) (xy 284.488975 -142.367) (xy 285.782764 -142.367) (xy 285.786835 -142.311378)
			(xy 285.798961 -142.256941) (xy 285.818884 -142.20485) (xy 285.84618 -142.156215) (xy 285.880266 -142.112072)
			(xy 285.920415 -142.073363) (xy 285.965773 -142.040912) (xy 286.015373 -142.015411) (xy 286.068157 -141.997404)
			(xy 286.123 -141.987274) (xy 286.178734 -141.985237) (xy 286.234171 -141.991337) (xy 286.288128 -142.005443)
			(xy 286.339457 -142.027255) (xy 286.387063 -142.056309) (xy 286.429931 -142.091984) (xy 286.467148 -142.133521)
			(xy 286.497921 -142.180034) (xy 286.521593 -142.230531) (xy 286.537661 -142.283938) (xy 286.545781 -142.339114)
			(xy 286.54629 -142.367) (xy 286.545781 -142.394886) (xy 286.537661 -142.450062) (xy 286.521593 -142.503469)
			(xy 286.497921 -142.553966) (xy 286.467148 -142.600479) (xy 286.429931 -142.642016) (xy 286.387063 -142.677691)
			(xy 286.339457 -142.706745) (xy 286.288128 -142.728557) (xy 286.234171 -142.742663) (xy 286.178734 -142.748763)
			(xy 286.123 -142.746726) (xy 286.068157 -142.736596) (xy 286.015373 -142.718589) (xy 285.965773 -142.693088)
			(xy 285.920415 -142.660637) (xy 285.880266 -142.621928) (xy 285.84618 -142.577785) (xy 285.818884 -142.52915)
			(xy 285.798961 -142.477059) (xy 285.786835 -142.422622) (xy 285.782764 -142.367) (xy 284.488975 -142.367)
			(xy 284.492079 -142.370682) (xy 284.521877 -142.416682) (xy 284.544781 -142.466475) (xy 284.560319 -142.519034)
			(xy 284.56817 -142.573276) (xy 284.568646 -142.60068) (xy 284.56816 -142.627931) (xy 284.560404 -142.681879)
			(xy 284.545049 -142.734174) (xy 284.522407 -142.783751) (xy 284.492941 -142.829601) (xy 284.45725 -142.870792)
			(xy 284.416059 -142.906483) (xy 284.370209 -142.935949) (xy 284.320632 -142.958591) (xy 284.268337 -142.973946)
			(xy 284.214389 -142.981702) (xy 284.159887 -142.981702) (xy 284.105939 -142.973946) (xy 284.053644 -142.958591)
			(xy 284.004067 -142.935949) (xy 283.958217 -142.906483) (xy 283.917026 -142.870792) (xy 283.881335 -142.829601)
			(xy 283.851869 -142.783751) (xy 283.829227 -142.734174) (xy 283.813872 -142.681879) (xy 283.806116 -142.627931)
			(xy 283.80563 -142.60068) (xy 279.995792 -142.60068) (xy 279.994541 -142.603263) (xy 279.962094 -142.65057)
			(xy 279.922937 -142.692493) (xy 279.87795 -142.728087) (xy 279.828145 -142.756552) (xy 279.774643 -142.777248)
			(xy 279.718647 -142.789709) (xy 279.690068 -142.792196) (xy 279.675561 -142.793631) (xy 279.64825 -142.803801)
			(xy 279.62492 -142.821267) (xy 279.607469 -142.844608) (xy 279.597317 -142.871926) (xy 279.595834 -142.88643)
			(xy 279.593382 -142.915018) (xy 279.580955 -142.971033) (xy 279.560279 -143.024556) (xy 279.531823 -143.074379)
			(xy 279.496226 -143.119379) (xy 279.454293 -143.158541) (xy 279.406968 -143.190983) (xy 279.355318 -143.215973)
			(xy 279.300509 -143.232946) (xy 279.243777 -143.241521) (xy 279.215088 -143.24203) (xy 279.187837 -143.241533)
			(xy 279.133891 -143.233776) (xy 279.081598 -143.21842) (xy 279.032022 -143.195779) (xy 278.986173 -143.166314)
			(xy 278.944983 -143.130624) (xy 278.909292 -143.089435) (xy 278.879825 -143.043587) (xy 278.857183 -142.994011)
			(xy 278.841826 -142.941719) (xy 278.834067 -142.887773) (xy 278.83358 -142.860522) (xy 272.465047 -142.860522)
			(xy 272.457613 -142.885231) (xy 272.433941 -142.935728) (xy 272.403168 -142.982241) (xy 272.365951 -143.023778)
			(xy 272.323083 -143.059453) (xy 272.275477 -143.088507) (xy 272.224148 -143.110319) (xy 272.170191 -143.124425)
			(xy 272.114754 -143.130525) (xy 272.05902 -143.128488) (xy 272.004177 -143.118358) (xy 271.951393 -143.100351)
			(xy 271.901793 -143.07485) (xy 271.856435 -143.042399) (xy 271.816286 -143.00369) (xy 271.7822 -142.959547)
			(xy 271.754904 -142.910912) (xy 271.734981 -142.858821) (xy 271.722855 -142.804384) (xy 271.718784 -142.748762)
			(xy 268.54785 -142.748762) (xy 268.54785 -151.045672) (xy 268.80312 -151.045672) (xy 268.803583 -151.01937)
			(xy 268.810827 -150.967267) (xy 268.825159 -150.916654) (xy 268.846308 -150.868489) (xy 268.873873 -150.823685)
			(xy 268.907331 -150.783093) (xy 268.946048 -150.747482) (xy 268.989289 -150.717527) (xy 269.036236 -150.693795)
			(xy 269.085998 -150.676738) (xy 269.11173 -150.671276) (xy 269.122144 -150.669244) (xy 269.138908 -150.65756)
			(xy 269.189962 -150.578058) (xy 269.193518 -150.557738) (xy 269.190978 -150.547578) (xy 269.186002 -150.525496)
			(xy 269.180649 -150.480549) (xy 269.18031 -150.457916) (xy 269.180768 -150.430927) (xy 269.188374 -150.377487)
			(xy 269.203437 -150.325652) (xy 269.225657 -150.276459) (xy 269.254589 -150.230888) (xy 269.289655 -150.189851)
			(xy 269.309596 -150.171658) (xy 269.317724 -150.164546) (xy 269.326614 -150.145496) (xy 269.328646 -150.048976)
			(xy 269.320772 -150.029672) (xy 269.312898 -150.022306) (xy 269.294702 -150.004278) (xy 269.262866 -149.964151)
			(xy 269.236683 -149.920125) (xy 269.216626 -149.872992) (xy 269.203055 -149.823599) (xy 269.196212 -149.772836)
			(xy 269.195804 -149.747224) (xy 269.19629 -149.719973) (xy 269.204046 -149.666025) (xy 269.219401 -149.61373)
			(xy 269.242043 -149.564153) (xy 269.271509 -149.518303) (xy 269.3072 -149.477112) (xy 269.348391 -149.441421)
			(xy 269.394241 -149.411955) (xy 269.443818 -149.389313) (xy 269.496113 -149.373958) (xy 269.550061 -149.366202)
			(xy 269.604563 -149.366202) (xy 269.658511 -149.373958) (xy 269.710806 -149.389313) (xy 269.760383 -149.411955)
			(xy 269.806233 -149.441421) (xy 269.847424 -149.477112) (xy 269.883115 -149.518303) (xy 269.912581 -149.564153)
			(xy 269.935223 -149.61373) (xy 269.950578 -149.666025) (xy 269.958334 -149.719973) (xy 269.95882 -149.747224)
			(xy 269.958345 -149.774213) (xy 269.950745 -149.827653) (xy 269.935687 -149.879488) (xy 269.913471 -149.928682)
			(xy 269.884541 -149.974253) (xy 269.849475 -150.01529) (xy 269.829534 -150.033482) (xy 269.821406 -150.040594)
			(xy 269.812516 -150.059644) (xy 269.810484 -150.156164) (xy 269.818358 -150.175468) (xy 269.826232 -150.182834)
			(xy 269.844386 -150.200903) (xy 269.876229 -150.24102) (xy 269.902418 -150.285037) (xy 269.922483 -150.332162)
			(xy 269.936063 -150.381548) (xy 269.942914 -150.432307) (xy 269.943326 -150.457916) (xy 269.942815 -150.484216)
			(xy 269.935574 -150.536315) (xy 269.921246 -150.586926) (xy 269.900101 -150.635088) (xy 269.872541 -150.67989)
			(xy 269.839089 -150.720482) (xy 269.800378 -150.756094) (xy 269.757142 -150.786051) (xy 269.710202 -150.809785)
			(xy 269.660446 -150.826847) (xy 269.634716 -150.832312) (xy 269.624302 -150.834344) (xy 269.607538 -150.846028)
			(xy 269.556484 -150.92553) (xy 269.552928 -150.94585) (xy 269.555468 -150.95601) (xy 269.556484 -150.960328)
			(xy 269.55877 -150.970234) (xy 269.570454 -150.986744) (xy 269.64894 -151.035766) (xy 269.668752 -151.039068)
			(xy 269.678658 -151.036528) (xy 269.70007 -151.031863) (xy 269.743613 -151.026898) (xy 269.765526 -151.026622)
			(xy 269.792778 -151.02705) (xy 269.846727 -151.03481) (xy 269.899023 -151.050168) (xy 269.948601 -151.072813)
			(xy 269.994452 -151.102282) (xy 270.035642 -151.137976) (xy 270.071334 -151.179169) (xy 270.1008 -151.225022)
			(xy 270.123441 -151.274601) (xy 270.138796 -151.326898) (xy 270.146552 -151.380848) (xy 270.146552 -151.435352)
			(xy 270.138796 -151.489302) (xy 270.123441 -151.541599) (xy 270.1008 -151.591178) (xy 270.071334 -151.637031)
			(xy 270.035642 -151.678224) (xy 269.994452 -151.713918) (xy 269.948601 -151.743387) (xy 269.899023 -151.766032)
			(xy 269.846727 -151.78139) (xy 269.792778 -151.78915) (xy 269.765526 -151.789638) (xy 269.747183 -151.789405)
			(xy 269.71067 -151.785842) (xy 269.692628 -151.782526) (xy 269.682722 -151.780748) (xy 269.663418 -151.784558)
			(xy 269.586964 -151.835612) (xy 269.575788 -151.851868) (xy 269.573756 -151.862028) (xy 269.570708 -151.875998)
			(xy 269.615412 -151.916384) (xy 269.621969 -151.921891) (xy 269.637753 -151.92851) (xy 269.654837 -151.929561)
			(xy 269.663164 -151.92756) (xy 269.688071 -151.921135) (xy 269.739045 -151.914249) (xy 269.764764 -151.913844)
			(xy 269.792021 -151.914316) (xy 269.84598 -151.92207) (xy 269.898287 -151.937424) (xy 269.947875 -151.960066)
			(xy 269.993737 -151.989535) (xy 270.034938 -152.025231) (xy 270.070639 -152.066428) (xy 270.100113 -152.112286)
			(xy 270.122761 -152.161872) (xy 270.138121 -152.214177) (xy 270.14588 -152.268135) (xy 270.145882 -152.322649)
			(xy 270.138124 -152.376607) (xy 270.122766 -152.428913) (xy 270.100121 -152.4785) (xy 270.070648 -152.52436)
			(xy 270.034949 -152.565558) (xy 269.99375 -152.601256) (xy 269.947889 -152.630727) (xy 269.898302 -152.653371)
			(xy 269.845996 -152.668727) (xy 269.792037 -152.676482) (xy 269.737523 -152.67648) (xy 269.683565 -152.668718)
			(xy 269.631261 -152.653357) (xy 269.581675 -152.630707) (xy 269.535818 -152.601232) (xy 269.494623 -152.565529)
			(xy 269.458928 -152.524327) (xy 269.42946 -152.478465) (xy 269.40682 -152.428875) (xy 269.391467 -152.376568)
			(xy 269.383716 -152.322609) (xy 269.383256 -152.295352) (xy 269.384272 -152.268428) (xy 269.385034 -152.256744)
			(xy 269.376398 -152.235154) (xy 269.299436 -152.165558) (xy 269.277084 -152.159208) (xy 269.2654 -152.16124)
			(xy 269.249209 -152.163869) (xy 269.216524 -152.166668) (xy 269.200122 -152.166828) (xy 269.172871 -152.166324)
			(xy 269.118922 -152.158571) (xy 269.066626 -152.143219) (xy 269.017048 -152.12058) (xy 268.971195 -152.091116)
			(xy 268.930003 -152.055427) (xy 268.894309 -152.014238) (xy 268.86484 -151.968389) (xy 268.842196 -151.918813)
			(xy 268.826838 -151.866519) (xy 268.819079 -151.812571) (xy 268.818614 -151.78532) (xy 268.819111 -151.758241)
			(xy 268.826762 -151.704626) (xy 268.841914 -151.652631) (xy 268.864262 -151.603299) (xy 268.893357 -151.55762)
			(xy 268.928616 -151.516512) (xy 268.948662 -151.4983) (xy 268.957298 -151.490934) (xy 268.966188 -151.470614)
			(xy 268.964156 -151.369776) (xy 268.95425 -151.349964) (xy 268.94536 -151.342852) (xy 268.923598 -151.324594)
			(xy 268.885125 -151.282807) (xy 268.853272 -151.235777) (xy 268.828742 -151.184546) (xy 268.812078 -151.130244)
			(xy 268.803647 -151.074072) (xy 268.80312 -151.045672) (xy 268.54785 -151.045672) (xy 268.54785 -155.008326)
			(xy 269.19936 -155.008326) (xy 269.1999 -154.978824) (xy 269.209007 -154.920527) (xy 269.226977 -154.864326)
			(xy 269.253383 -154.81156) (xy 269.287594 -154.763487) (xy 269.328797 -154.721251) (xy 269.376008 -154.68586)
			(xy 269.401798 -154.671522) (xy 269.411196 -154.666442) (xy 269.42415 -154.650186) (xy 269.449042 -154.557984)
			(xy 269.445994 -154.537156) (xy 269.440406 -154.528266) (xy 269.426844 -154.505542) (xy 269.405479 -154.457127)
			(xy 269.391007 -154.406225) (xy 269.383704 -154.353812) (xy 269.383256 -154.327352) (xy 269.383742 -154.300101)
			(xy 269.391498 -154.246153) (xy 269.406853 -154.193858) (xy 269.429495 -154.144281) (xy 269.458961 -154.098431)
			(xy 269.494652 -154.05724) (xy 269.535843 -154.021549) (xy 269.581693 -153.992083) (xy 269.63127 -153.969441)
			(xy 269.683565 -153.954086) (xy 269.737513 -153.94633) (xy 269.792015 -153.94633) (xy 269.845963 -153.954086)
			(xy 269.898258 -153.969441) (xy 269.947835 -153.992083) (xy 269.993685 -154.021549) (xy 270.034876 -154.05724)
			(xy 270.070567 -154.098431) (xy 270.100033 -154.144281) (xy 270.122675 -154.193858) (xy 270.13803 -154.246153)
			(xy 270.145786 -154.300101) (xy 270.146272 -154.327352) (xy 270.145698 -154.356852) (xy 270.136595 -154.415147)
			(xy 270.118629 -154.471346) (xy 270.092229 -154.524111) (xy 270.058023 -154.572185) (xy 270.016827 -154.614422)
			(xy 269.969621 -154.649816) (xy 269.943834 -154.664156) (xy 269.934436 -154.669236) (xy 269.921482 -154.685492)
			(xy 269.89659 -154.777694) (xy 269.899638 -154.798522) (xy 269.905226 -154.807412) (xy 269.918773 -154.830145)
			(xy 269.940143 -154.878556) (xy 269.95462 -154.929455) (xy 269.961927 -154.981867) (xy 269.962376 -155.008326)
			(xy 269.961963 -155.033651) (xy 269.955244 -155.083853) (xy 269.941941 -155.132724) (xy 269.922288 -155.179406)
			(xy 269.89663 -155.223076) (xy 269.88135 -155.243276) (xy 269.875762 -155.250642) (xy 269.870174 -155.268422)
			(xy 269.875508 -155.354274) (xy 269.883128 -155.371038) (xy 269.889732 -155.377642) (xy 269.910531 -155.399277)
			(xy 269.945813 -155.447818) (xy 269.973057 -155.501288) (xy 269.991589 -155.558364) (xy 270.000951 -155.617639)
			(xy 270.001492 -155.647644) (xy 270.000871 -155.67854) (xy 269.990921 -155.739527) (xy 269.97127 -155.798111)
			(xy 269.942433 -155.852763) (xy 269.924276 -155.877768) (xy 269.917418 -155.886658) (xy 269.912846 -155.907994)
			(xy 269.933674 -156.005022) (xy 269.946628 -156.022548) (xy 269.956534 -156.027882) (xy 269.981806 -156.042402)
			(xy 270.001587 -156.0576) (xy 280.363674 -156.0576) (xy 280.367745 -156.001978) (xy 280.379871 -155.947541)
			(xy 280.399794 -155.89545) (xy 280.42709 -155.846815) (xy 280.461176 -155.802672) (xy 280.501325 -155.763963)
			(xy 280.546683 -155.731512) (xy 280.596283 -155.706011) (xy 280.649067 -155.688004) (xy 280.70391 -155.677874)
			(xy 280.759644 -155.675837) (xy 280.815081 -155.681937) (xy 280.869038 -155.696043) (xy 280.920367 -155.717855)
			(xy 280.967973 -155.746909) (xy 281.010841 -155.782584) (xy 281.048058 -155.824121) (xy 281.078831 -155.870634)
			(xy 281.102503 -155.921131) (xy 281.118571 -155.974538) (xy 281.126691 -156.029714) (xy 281.1272 -156.0576)
			(xy 281.126691 -156.085486) (xy 281.118571 -156.140662) (xy 281.102503 -156.194069) (xy 281.078831 -156.244566)
			(xy 281.048058 -156.291079) (xy 281.010841 -156.332616) (xy 280.967973 -156.368291) (xy 280.920367 -156.397345)
			(xy 280.869038 -156.419157) (xy 280.815081 -156.433263) (xy 280.759644 -156.439363) (xy 280.70391 -156.437326)
			(xy 280.649067 -156.427196) (xy 280.596283 -156.409189) (xy 280.546683 -156.383688) (xy 280.501325 -156.351237)
			(xy 280.461176 -156.312528) (xy 280.42709 -156.268385) (xy 280.399794 -156.21975) (xy 280.379871 -156.167659)
			(xy 280.367745 -156.113222) (xy 280.363674 -156.0576) (xy 270.001587 -156.0576) (xy 270.028022 -156.07791)
			(xy 270.068304 -156.120032) (xy 270.101713 -156.167787) (xy 270.127475 -156.220066) (xy 270.144989 -156.275654)
			(xy 270.153849 -156.333259) (xy 270.1544 -156.3624) (xy 270.153914 -156.389651) (xy 270.146158 -156.443599)
			(xy 270.130803 -156.495894) (xy 270.108161 -156.545471) (xy 270.078695 -156.591321) (xy 270.043004 -156.632512)
			(xy 270.001813 -156.668203) (xy 269.955963 -156.697669) (xy 269.906386 -156.720311) (xy 269.854091 -156.735666)
			(xy 269.800143 -156.743422) (xy 269.745641 -156.743422) (xy 269.691693 -156.735666) (xy 269.639398 -156.720311)
			(xy 269.589821 -156.697669) (xy 269.543971 -156.668203) (xy 269.50278 -156.632512) (xy 269.467089 -156.591321)
			(xy 269.437623 -156.545471) (xy 269.414981 -156.495894) (xy 269.399626 -156.443599) (xy 269.39187 -156.389651)
			(xy 269.391384 -156.3624) (xy 269.39198 -156.331503) (xy 269.401939 -156.270516) (xy 269.421597 -156.211931)
			(xy 269.450439 -156.15728) (xy 269.4686 -156.132276) (xy 269.475458 -156.123386) (xy 269.48003 -156.10205)
			(xy 269.459202 -156.005022) (xy 269.446248 -155.987496) (xy 269.436342 -155.982162) (xy 269.411063 -155.967652)
			(xy 269.364843 -155.932146) (xy 269.324559 -155.890024) (xy 269.291148 -155.842267) (xy 269.265388 -155.789985)
			(xy 269.247877 -155.734394) (xy 269.239023 -155.676786) (xy 269.238476 -155.647644) (xy 269.238916 -155.62232)
			(xy 269.245627 -155.572119) (xy 269.258923 -155.523247) (xy 269.278571 -155.476565) (xy 269.304224 -155.432895)
			(xy 269.319502 -155.412694) (xy 269.32509 -155.405328) (xy 269.330678 -155.387548) (xy 269.325344 -155.301696)
			(xy 269.317724 -155.284932) (xy 269.31112 -155.278328) (xy 269.290298 -155.256714) (xy 269.25502 -155.208166)
			(xy 269.227782 -155.154692) (xy 269.209256 -155.097611) (xy 269.199898 -155.038332) (xy 269.19936 -155.008326)
			(xy 268.54785 -155.008326) (xy 268.54785 -158.275274) (xy 268.548288 -158.285337) (xy 268.556027 -158.303917)
			(xy 268.562836 -158.311342) (xy 269.228316 -158.976822) (xy 269.235712 -158.983674) (xy 269.254311 -158.991415)
			(xy 269.264384 -158.991808) (xy 280.544016 -158.991808) (xy 280.554085 -158.991382) (xy 280.572686 -158.983665)
			(xy 280.580084 -158.976822) (xy 281.78633 -157.770576) (xy 281.79318 -157.76318) (xy 281.800917 -157.744581)
			(xy 281.801316 -157.734508) (xy 281.801316 -155.419552) (xy 281.800885 -155.409485) (xy 281.79316 -155.390892)
			(xy 281.78633 -155.383484) (xy 281.004772 -154.601926) (xy 280.997373 -154.595081) (xy 280.978775 -154.587353)
			(xy 280.968704 -154.58694) (xy 272.626074 -154.58694) (xy 272.616007 -154.586511) (xy 272.597415 -154.578783)
			(xy 272.590006 -154.571954) (xy 271.267682 -153.24963) (xy 271.260838 -153.242232) (xy 271.253116 -153.223632)
			(xy 271.252696 -153.213562) (xy 271.252696 -145.875248) (xy 271.253129 -145.865182) (xy 271.260856 -145.846591)
			(xy 271.267682 -145.83918) (xy 273.633184 -143.473678) (xy 273.640583 -143.466836) (xy 273.659183 -143.45912)
			(xy 273.669252 -143.458692) (xy 283.570426 -143.458692) (xy 283.579549 -143.458371) (xy 283.596662 -143.452059)
			(xy 283.610445 -143.440111) (xy 283.61513 -143.432276) (xy 283.628617 -143.4086) (xy 283.661277 -143.364986)
			(xy 283.699811 -143.326463) (xy 283.743434 -143.293815) (xy 283.791258 -143.267707) (xy 283.842311 -143.248669)
			(xy 283.895554 -143.237088) (xy 283.949902 -143.233202) (xy 284.00425 -143.237088) (xy 284.057493 -143.248669)
			(xy 284.108546 -143.267707) (xy 284.15637 -143.293815) (xy 284.199993 -143.326463) (xy 284.238527 -143.364986)
			(xy 284.271187 -143.4086) (xy 284.284674 -143.432276) (xy 284.289397 -143.440072) (xy 284.303196 -143.451963)
			(xy 284.32027 -143.458309) (xy 284.329378 -143.458692) (xy 284.948884 -143.458692) (xy 284.958948 -143.45913)
			(xy 284.977531 -143.466865) (xy 284.984952 -143.473678) (xy 285.783274 -144.272) (xy 288.586924 -144.272)
			(xy 288.590995 -144.216378) (xy 288.603121 -144.161941) (xy 288.623044 -144.10985) (xy 288.65034 -144.061215)
			(xy 288.684426 -144.017072) (xy 288.724575 -143.978363) (xy 288.769933 -143.945912) (xy 288.819533 -143.920411)
			(xy 288.872317 -143.902404) (xy 288.92716 -143.892274) (xy 288.982894 -143.890237) (xy 289.038331 -143.896337)
			(xy 289.092288 -143.910443) (xy 289.143617 -143.932255) (xy 289.191223 -143.961309) (xy 289.234091 -143.996984)
			(xy 289.271308 -144.038521) (xy 289.302081 -144.085034) (xy 289.325753 -144.135531) (xy 289.341821 -144.188938)
			(xy 289.349941 -144.244114) (xy 289.35045 -144.272) (xy 289.349941 -144.299886) (xy 289.341821 -144.355062)
			(xy 289.325753 -144.408469) (xy 289.302081 -144.458966) (xy 289.271308 -144.505479) (xy 289.234091 -144.547016)
			(xy 289.191223 -144.582691) (xy 289.143617 -144.611745) (xy 289.092288 -144.633557) (xy 289.038331 -144.647663)
			(xy 288.982894 -144.653763) (xy 288.92716 -144.651726) (xy 288.872317 -144.641596) (xy 288.819533 -144.623589)
			(xy 288.769933 -144.598088) (xy 288.724575 -144.565637) (xy 288.684426 -144.526928) (xy 288.65034 -144.482785)
			(xy 288.623044 -144.43415) (xy 288.603121 -144.382059) (xy 288.590995 -144.327622) (xy 288.586924 -144.272)
			(xy 285.783274 -144.272) (xy 292.68293 -151.171656) (xy 292.689775 -151.179054) (xy 292.6975 -151.197653)
			(xy 292.697916 -151.207724) (xy 292.697916 -157.045152) (xy 293.610536 -157.045152) (xy 293.614607 -156.98953)
			(xy 293.626733 -156.935093) (xy 293.646656 -156.883002) (xy 293.673952 -156.834367) (xy 293.708038 -156.790224)
			(xy 293.748187 -156.751515) (xy 293.793545 -156.719064) (xy 293.843145 -156.693563) (xy 293.895929 -156.675556)
			(xy 293.950772 -156.665426) (xy 294.006506 -156.663389) (xy 294.061943 -156.669489) (xy 294.1159 -156.683595)
			(xy 294.167229 -156.705407) (xy 294.214835 -156.734461) (xy 294.257703 -156.770136) (xy 294.29492 -156.811673)
			(xy 294.325693 -156.858186) (xy 294.349365 -156.908683) (xy 294.365433 -156.96209) (xy 294.373553 -157.017266)
			(xy 294.374062 -157.045152) (xy 294.626536 -157.045152) (xy 294.630607 -156.98953) (xy 294.642733 -156.935093)
			(xy 294.662656 -156.883002) (xy 294.689952 -156.834367) (xy 294.724038 -156.790224) (xy 294.764187 -156.751515)
			(xy 294.809545 -156.719064) (xy 294.859145 -156.693563) (xy 294.911929 -156.675556) (xy 294.966772 -156.665426)
			(xy 295.022506 -156.663389) (xy 295.077943 -156.669489) (xy 295.1319 -156.683595) (xy 295.183229 -156.705407)
			(xy 295.230835 -156.734461) (xy 295.273703 -156.770136) (xy 295.31092 -156.811673) (xy 295.341693 -156.858186)
			(xy 295.365365 -156.908683) (xy 295.381433 -156.96209) (xy 295.389553 -157.017266) (xy 295.390062 -157.045152)
			(xy 295.389553 -157.073038) (xy 295.381433 -157.128214) (xy 295.365365 -157.181621) (xy 295.341693 -157.232118)
			(xy 295.31092 -157.278631) (xy 295.273703 -157.320168) (xy 295.230835 -157.355843) (xy 295.183229 -157.384897)
			(xy 295.1319 -157.406709) (xy 295.077943 -157.420815) (xy 295.022506 -157.426915) (xy 294.966772 -157.424878)
			(xy 294.911929 -157.414748) (xy 294.859145 -157.396741) (xy 294.809545 -157.37124) (xy 294.764187 -157.338789)
			(xy 294.724038 -157.30008) (xy 294.689952 -157.255937) (xy 294.662656 -157.207302) (xy 294.642733 -157.155211)
			(xy 294.630607 -157.100774) (xy 294.626536 -157.045152) (xy 294.374062 -157.045152) (xy 294.373553 -157.073038)
			(xy 294.365433 -157.128214) (xy 294.349365 -157.181621) (xy 294.325693 -157.232118) (xy 294.29492 -157.278631)
			(xy 294.257703 -157.320168) (xy 294.214835 -157.355843) (xy 294.167229 -157.384897) (xy 294.1159 -157.406709)
			(xy 294.061943 -157.420815) (xy 294.006506 -157.426915) (xy 293.950772 -157.424878) (xy 293.895929 -157.414748)
			(xy 293.843145 -157.396741) (xy 293.793545 -157.37124) (xy 293.748187 -157.338789) (xy 293.708038 -157.30008)
			(xy 293.673952 -157.255937) (xy 293.646656 -157.207302) (xy 293.626733 -157.155211) (xy 293.614607 -157.100774)
			(xy 293.610536 -157.045152) (xy 292.697916 -157.045152) (xy 292.697916 -161.757868) (xy 293.559736 -161.757868)
			(xy 293.563807 -161.702246) (xy 293.575933 -161.647809) (xy 293.595856 -161.595718) (xy 293.623152 -161.547083)
			(xy 293.657238 -161.50294) (xy 293.697387 -161.464231) (xy 293.742745 -161.43178) (xy 293.792345 -161.406279)
			(xy 293.845129 -161.388272) (xy 293.899972 -161.378142) (xy 293.955706 -161.376105) (xy 294.011143 -161.382205)
			(xy 294.0651 -161.396311) (xy 294.116429 -161.418123) (xy 294.164035 -161.447177) (xy 294.206903 -161.482852)
			(xy 294.24412 -161.524389) (xy 294.274893 -161.570902) (xy 294.298565 -161.621399) (xy 294.314633 -161.674806)
			(xy 294.322753 -161.729982) (xy 294.323262 -161.757868) (xy 294.322753 -161.785754) (xy 294.314633 -161.84093)
			(xy 294.298565 -161.894337) (xy 294.274893 -161.944834) (xy 294.24412 -161.991347) (xy 294.206903 -162.032884)
			(xy 294.164035 -162.068559) (xy 294.139144 -162.08375) (xy 295.05986 -162.08375) (xy 295.063931 -162.028128)
			(xy 295.076057 -161.973691) (xy 295.09598 -161.9216) (xy 295.123276 -161.872965) (xy 295.157362 -161.828822)
			(xy 295.197511 -161.790113) (xy 295.242869 -161.757662) (xy 295.292469 -161.732161) (xy 295.345253 -161.714154)
			(xy 295.400096 -161.704024) (xy 295.45583 -161.701987) (xy 295.511267 -161.708087) (xy 295.565224 -161.722193)
			(xy 295.616553 -161.744005) (xy 295.664159 -161.773059) (xy 295.707027 -161.808734) (xy 295.744244 -161.850271)
			(xy 295.775017 -161.896784) (xy 295.798689 -161.947281) (xy 295.814757 -162.000688) (xy 295.822877 -162.055864)
			(xy 295.823386 -162.08375) (xy 295.822877 -162.111636) (xy 295.814757 -162.166812) (xy 295.798689 -162.220219)
			(xy 295.775017 -162.270716) (xy 295.744244 -162.317229) (xy 295.707027 -162.358766) (xy 295.664159 -162.394441)
			(xy 295.616553 -162.423495) (xy 295.565224 -162.445307) (xy 295.511267 -162.459413) (xy 295.45583 -162.465513)
			(xy 295.400096 -162.463476) (xy 295.345253 -162.453346) (xy 295.292469 -162.435339) (xy 295.242869 -162.409838)
			(xy 295.197511 -162.377387) (xy 295.157362 -162.338678) (xy 295.123276 -162.294535) (xy 295.09598 -162.2459)
			(xy 295.076057 -162.193809) (xy 295.063931 -162.139372) (xy 295.05986 -162.08375) (xy 294.139144 -162.08375)
			(xy 294.116429 -162.097613) (xy 294.0651 -162.119425) (xy 294.011143 -162.133531) (xy 293.955706 -162.139631)
			(xy 293.899972 -162.137594) (xy 293.845129 -162.127464) (xy 293.792345 -162.109457) (xy 293.742745 -162.083956)
			(xy 293.697387 -162.051505) (xy 293.657238 -162.012796) (xy 293.623152 -161.968653) (xy 293.595856 -161.920018)
			(xy 293.575933 -161.867927) (xy 293.563807 -161.81349) (xy 293.559736 -161.757868) (xy 292.697916 -161.757868)
			(xy 292.697916 -166.705534) (xy 294.327832 -166.705534) (xy 294.331903 -166.649912) (xy 294.344029 -166.595475)
			(xy 294.363952 -166.543384) (xy 294.391248 -166.494749) (xy 294.425334 -166.450606) (xy 294.465483 -166.411897)
			(xy 294.510841 -166.379446) (xy 294.560441 -166.353945) (xy 294.613225 -166.335938) (xy 294.668068 -166.325808)
			(xy 294.723802 -166.323771) (xy 294.779239 -166.329871) (xy 294.833196 -166.343977) (xy 294.884525 -166.365789)
			(xy 294.932131 -166.394843) (xy 294.974999 -166.430518) (xy 295.012216 -166.472055) (xy 295.042989 -166.518568)
			(xy 295.066661 -166.569065) (xy 295.082729 -166.622472) (xy 295.090849 -166.677648) (xy 295.091358 -166.705534)
			(xy 295.343832 -166.705534) (xy 295.347903 -166.649912) (xy 295.360029 -166.595475) (xy 295.379952 -166.543384)
			(xy 295.407248 -166.494749) (xy 295.441334 -166.450606) (xy 295.481483 -166.411897) (xy 295.526841 -166.379446)
			(xy 295.576441 -166.353945) (xy 295.629225 -166.335938) (xy 295.684068 -166.325808) (xy 295.739802 -166.323771)
			(xy 295.795239 -166.329871) (xy 295.849196 -166.343977) (xy 295.900525 -166.365789) (xy 295.948131 -166.394843)
			(xy 295.990999 -166.430518) (xy 296.028216 -166.472055) (xy 296.058989 -166.518568) (xy 296.082661 -166.569065)
			(xy 296.098729 -166.622472) (xy 296.106849 -166.677648) (xy 296.107358 -166.705534) (xy 296.106849 -166.73342)
			(xy 296.098729 -166.788596) (xy 296.082661 -166.842003) (xy 296.058989 -166.8925) (xy 296.028216 -166.939013)
			(xy 295.990999 -166.98055) (xy 295.948131 -167.016225) (xy 295.900525 -167.045279) (xy 295.849196 -167.067091)
			(xy 295.795239 -167.081197) (xy 295.739802 -167.087297) (xy 295.684068 -167.08526) (xy 295.629225 -167.07513)
			(xy 295.576441 -167.057123) (xy 295.526841 -167.031622) (xy 295.481483 -166.999171) (xy 295.441334 -166.960462)
			(xy 295.407248 -166.916319) (xy 295.379952 -166.867684) (xy 295.360029 -166.815593) (xy 295.347903 -166.761156)
			(xy 295.343832 -166.705534) (xy 295.091358 -166.705534) (xy 295.090849 -166.73342) (xy 295.082729 -166.788596)
			(xy 295.066661 -166.842003) (xy 295.042989 -166.8925) (xy 295.012216 -166.939013) (xy 294.974999 -166.98055)
			(xy 294.932131 -167.016225) (xy 294.884525 -167.045279) (xy 294.833196 -167.067091) (xy 294.779239 -167.081197)
			(xy 294.723802 -167.087297) (xy 294.668068 -167.08526) (xy 294.613225 -167.07513) (xy 294.560441 -167.057123)
			(xy 294.510841 -167.031622) (xy 294.465483 -166.999171) (xy 294.425334 -166.960462) (xy 294.391248 -166.916319)
			(xy 294.363952 -166.867684) (xy 294.344029 -166.815593) (xy 294.331903 -166.761156) (xy 294.327832 -166.705534)
			(xy 292.697916 -166.705534) (xy 292.697916 -168.94556) (xy 294.450006 -168.94556) (xy 294.454077 -168.889938)
			(xy 294.466203 -168.835501) (xy 294.486126 -168.78341) (xy 294.513422 -168.734775) (xy 294.547508 -168.690632)
			(xy 294.587657 -168.651923) (xy 294.633015 -168.619472) (xy 294.682615 -168.593971) (xy 294.735399 -168.575964)
			(xy 294.790242 -168.565834) (xy 294.845976 -168.563797) (xy 294.901413 -168.569897) (xy 294.95537 -168.584003)
			(xy 295.006699 -168.605815) (xy 295.054305 -168.634869) (xy 295.097173 -168.670544) (xy 295.13439 -168.712081)
			(xy 295.165163 -168.758594) (xy 295.188835 -168.809091) (xy 295.204903 -168.862498) (xy 295.213023 -168.917674)
			(xy 295.213532 -168.94556) (xy 295.213023 -168.973446) (xy 295.204903 -169.028622) (xy 295.188835 -169.082029)
			(xy 295.165163 -169.132526) (xy 295.13439 -169.179039) (xy 295.097173 -169.220576) (xy 295.054305 -169.256251)
			(xy 295.006699 -169.285305) (xy 294.95537 -169.307117) (xy 294.901413 -169.321223) (xy 294.845976 -169.327323)
			(xy 294.790242 -169.325286) (xy 294.735399 -169.315156) (xy 294.682615 -169.297149) (xy 294.633015 -169.271648)
			(xy 294.587657 -169.239197) (xy 294.547508 -169.200488) (xy 294.513422 -169.156345) (xy 294.486126 -169.10771)
			(xy 294.466203 -169.055619) (xy 294.454077 -169.001182) (xy 294.450006 -168.94556) (xy 292.697916 -168.94556)
			(xy 292.697916 -171.962826) (xy 292.698459 -171.972811) (xy 292.70618 -171.991235) (xy 292.712902 -171.99864)
			(xy 293.076376 -172.362368) (xy 293.083555 -172.36888) (xy 293.101372 -172.376474) (xy 293.120733 -172.376987)
			(xy 293.12997 -172.374052) (xy 293.230554 -172.336968) (xy 293.248334 -172.3136) (xy 293.249604 -172.298614)
			(xy 293.252421 -172.270313) (xy 293.265374 -172.214936) (xy 293.286402 -172.162095) (xy 293.315042 -172.112961)
			(xy 293.350657 -172.068623) (xy 293.392459 -172.030062) (xy 293.439522 -171.998133) (xy 293.490803 -171.973544)
			(xy 293.545166 -171.956839) (xy 293.601406 -171.948389) (xy 293.629842 -171.94784) (xy 293.657092 -171.948306)
			(xy 293.711035 -171.956068) (xy 293.763326 -171.971428) (xy 293.812897 -171.994074) (xy 293.858742 -172.023544)
			(xy 293.899925 -172.059238) (xy 293.93561 -172.10043) (xy 293.965069 -172.146282) (xy 293.987703 -172.195859)
			(xy 294.003051 -172.248153) (xy 294.0108 -172.302098) (xy 294.01135 -172.329348) (xy 294.01081 -172.359354)
			(xy 294.00145 -172.418631) (xy 293.982921 -172.47571) (xy 293.955682 -172.529182) (xy 293.920403 -172.577728)
			(xy 293.89959 -172.59935) (xy 293.888414 -172.610272) (xy 293.882572 -172.640244) (xy 293.924228 -172.741336)
			(xy 293.928442 -172.750461) (xy 293.942625 -172.764681) (xy 293.961176 -172.772376) (xy 293.971218 -172.772832)
		)
		(stroke
			(width 0)
			(type solid)
		)
		(fill yes)
		(layer "In13.Cu")
		(net "P3V3_NIC4")
	)
	(gr_poly
		(pts
			(xy 120.049544 -184.152032) (xy 120.059611 -184.151602) (xy 120.078207 -184.14388) (xy 120.085612 -184.137046)
			(xy 120.720358 -183.5023) (xy 120.727209 -183.494903) (xy 120.73495 -183.476305) (xy 120.735344 -183.466232)
			(xy 120.735344 -163.218368) (xy 120.734913 -163.208302) (xy 120.727185 -163.189711) (xy 120.720358 -163.1823)
			(xy 119.586248 -162.04819) (xy 119.579398 -162.040793) (xy 119.571659 -162.022195) (xy 119.571262 -162.012122)
			(xy 119.571262 -154.827224) (xy 119.571357 -154.822205) (xy 119.57328 -154.812355) (xy 119.575072 -154.807666)
			(xy 119.582438 -154.790394) (xy 119.584235 -154.785707) (xy 119.58615 -154.775855) (xy 119.586248 -154.770836)
			(xy 119.586248 -133.763004) (xy 119.586076 -133.756996) (xy 119.583245 -133.745317) (xy 119.58066 -133.73989)
			(xy 119.57882 -133.736416) (xy 119.574224 -133.730039) (xy 119.571516 -133.72719) (xy 119.258842 -133.414516)
			(xy 119.255992 -133.411809) (xy 119.249615 -133.407213) (xy 119.246142 -133.405372) (xy 119.240714 -133.402792)
			(xy 119.229035 -133.399973) (xy 119.223028 -133.399784) (xy 104.557068 -133.399784) (xy 104.551058 -133.399949)
			(xy 104.539373 -133.402768) (xy 104.533954 -133.405372) (xy 104.53048 -133.407212) (xy 104.524102 -133.411806)
			(xy 104.521254 -133.414516) (xy 103.471726 -134.464044) (xy 103.469023 -134.466897) (xy 103.464435 -134.473278)
			(xy 103.462582 -134.476744) (xy 103.46 -134.482171) (xy 103.457177 -134.493851) (xy 103.456994 -134.499858)
			(xy 103.456994 -139.03706) (xy 106.080052 -139.03706) (xy 106.080564 -139.008321) (xy 106.089192 -138.951494)
			(xy 106.106245 -138.896603) (xy 106.131339 -138.844892) (xy 106.163905 -138.797529) (xy 106.183176 -138.776202)
			(xy 106.18978 -138.769344) (xy 106.196892 -138.75131) (xy 106.196892 -138.66241) (xy 106.18978 -138.644376)
			(xy 106.183176 -138.637518) (xy 106.163893 -138.616202) (xy 106.131327 -138.568838) (xy 106.106236 -138.517123)
			(xy 106.089188 -138.46223) (xy 106.08057 -138.4054) (xy 106.080052 -138.37666) (xy 106.080538 -138.349409)
			(xy 106.088294 -138.295461) (xy 106.103649 -138.243166) (xy 106.126291 -138.193589) (xy 106.155757 -138.147739)
			(xy 106.191448 -138.106548) (xy 106.232639 -138.070857) (xy 106.278489 -138.041391) (xy 106.328066 -138.018749)
			(xy 106.380361 -138.003394) (xy 106.434309 -137.995638) (xy 106.488811 -137.995638) (xy 106.542759 -138.003394)
			(xy 106.595054 -138.018749) (xy 106.644631 -138.041391) (xy 106.690481 -138.070857) (xy 106.731672 -138.106548)
			(xy 106.767363 -138.147739) (xy 106.796829 -138.193589) (xy 106.819471 -138.243166) (xy 106.834826 -138.295461)
			(xy 106.842582 -138.349409) (xy 106.843068 -138.37666) (xy 106.842563 -138.405399) (xy 106.833933 -138.462227)
			(xy 106.816877 -138.517117) (xy 106.791782 -138.568828) (xy 106.759215 -138.616191) (xy 106.739944 -138.637518)
			(xy 106.73334 -138.644376) (xy 106.726228 -138.66241) (xy 106.726228 -138.75131) (xy 106.73334 -138.769344)
			(xy 106.739944 -138.776202) (xy 106.759193 -138.797548) (xy 106.791763 -138.844905) (xy 106.81686 -138.896611)
			(xy 106.833916 -138.951498) (xy 106.842544 -139.008322) (xy 106.843068 -139.03706) (xy 106.842617 -139.062965)
			(xy 106.835599 -139.114299) (xy 106.821702 -139.164211) (xy 106.80118 -139.211785) (xy 106.774411 -139.256145)
			(xy 106.758486 -139.276582) (xy 106.752749 -139.284343) (xy 106.747003 -139.30275) (xy 106.74731 -139.312396)
			(xy 106.752898 -139.381992) (xy 106.753985 -139.391424) (xy 106.76222 -139.408518) (xy 106.7689 -139.415266)
			(xy 106.769408 -139.415774) (xy 106.788658 -139.433887) (xy 106.822417 -139.474559) (xy 106.85024 -139.5195)
			(xy 106.871596 -139.56785) (xy 106.886076 -139.618685) (xy 106.893402 -139.671032) (xy 106.893868 -139.69746)
			(xy 106.893363 -139.726199) (xy 106.884733 -139.783027) (xy 106.867677 -139.837917) (xy 106.842582 -139.889628)
			(xy 106.810015 -139.936991) (xy 106.790744 -139.958318) (xy 106.78414 -139.965176) (xy 106.777028 -139.98321)
			(xy 106.777028 -140.07211) (xy 106.78414 -140.090144) (xy 106.790744 -140.097002) (xy 106.809977 -140.118362)
			(xy 106.842546 -140.165718) (xy 106.867642 -140.217424) (xy 106.884696 -140.27231) (xy 106.893323 -140.329134)
			(xy 106.893328 -140.386608) (xy 106.884709 -140.443433) (xy 106.867663 -140.498321) (xy 106.842575 -140.550031)
			(xy 106.810013 -140.597392) (xy 106.790744 -140.618718) (xy 106.78414 -140.625576) (xy 106.777028 -140.64361)
			(xy 106.777028 -140.73251) (xy 106.78414 -140.750544) (xy 106.790744 -140.757402) (xy 106.809993 -140.778748)
			(xy 106.842563 -140.826105) (xy 106.86766 -140.877811) (xy 106.884716 -140.932698) (xy 106.893344 -140.989522)
			(xy 106.893868 -141.01826) (xy 108.518452 -141.01826) (xy 108.518964 -140.989521) (xy 108.527592 -140.932694)
			(xy 108.544645 -140.877803) (xy 108.569739 -140.826092) (xy 108.602305 -140.778729) (xy 108.621576 -140.757402)
			(xy 108.62818 -140.750544) (xy 108.635292 -140.73251) (xy 108.635292 -140.64361) (xy 108.62818 -140.625576)
			(xy 108.621576 -140.618718) (xy 108.602268 -140.597425) (xy 108.569708 -140.550055) (xy 108.544622 -140.498337)
			(xy 108.527577 -140.443442) (xy 108.518959 -140.386611) (xy 108.518963 -140.329131) (xy 108.52759 -140.272301)
			(xy 108.544643 -140.217408) (xy 108.569737 -140.165694) (xy 108.602304 -140.11833) (xy 108.621576 -140.097002)
			(xy 108.62818 -140.090144) (xy 108.635292 -140.07211) (xy 108.635292 -139.98321) (xy 108.62818 -139.965176)
			(xy 108.621576 -139.958318) (xy 108.602293 -139.937002) (xy 108.569727 -139.889638) (xy 108.544636 -139.837923)
			(xy 108.527588 -139.78303) (xy 108.51897 -139.7262) (xy 108.518452 -139.69746) (xy 108.518993 -139.668544)
			(xy 108.527715 -139.611373) (xy 108.544967 -139.556173) (xy 108.570354 -139.504211) (xy 108.603295 -139.456677)
			(xy 108.643033 -139.41466) (xy 108.665518 -139.39647) (xy 108.674332 -139.388869) (xy 108.684511 -139.367964)
			(xy 108.685076 -139.356338) (xy 108.685076 -139.276582) (xy 108.684541 -139.264949) (xy 108.67435 -139.244039)
			(xy 108.665518 -139.23645) (xy 108.643062 -139.218226) (xy 108.603324 -139.176214) (xy 108.570382 -139.128686)
			(xy 108.544988 -139.076731) (xy 108.527726 -139.021539) (xy 108.518991 -138.964374) (xy 108.518452 -138.93546)
			(xy 108.518964 -138.906721) (xy 108.527592 -138.849894) (xy 108.544645 -138.795003) (xy 108.569739 -138.743292)
			(xy 108.602305 -138.695929) (xy 108.621576 -138.674602) (xy 108.62818 -138.667744) (xy 108.635292 -138.64971)
			(xy 108.635292 -138.56081) (xy 108.62818 -138.542776) (xy 108.621576 -138.535918) (xy 108.602293 -138.514602)
			(xy 108.569727 -138.467238) (xy 108.544636 -138.415523) (xy 108.527588 -138.36063) (xy 108.51897 -138.3038)
			(xy 108.518452 -138.27506) (xy 108.51894 -138.24781) (xy 108.526701 -138.193864) (xy 108.54206 -138.141572)
			(xy 108.564702 -138.091997) (xy 108.594169 -138.046149) (xy 108.62986 -138.00496) (xy 108.671049 -137.969269)
			(xy 108.716897 -137.939802) (xy 108.766472 -137.91716) (xy 108.818764 -137.901801) (xy 108.87271 -137.89404)
			(xy 108.89996 -137.893552) (xy 108.929295 -137.894104) (xy 108.987274 -137.903069) (xy 109.043197 -137.920808)
			(xy 109.095742 -137.946903) (xy 109.143671 -137.980739) (xy 109.165136 -138.00074) (xy 109.172502 -138.007852)
			(xy 109.190282 -138.014964) (xy 109.281214 -138.014964) (xy 109.298994 -138.007852) (xy 109.30636 -138.00074)
			(xy 109.327833 -137.980749) (xy 109.375767 -137.946923) (xy 109.42831 -137.920828) (xy 109.484228 -137.903079)
			(xy 109.542203 -137.894094) (xy 109.571536 -137.893552) (xy 109.598786 -137.894044) (xy 109.652732 -137.901805)
			(xy 109.705024 -137.917162) (xy 109.754599 -137.939805) (xy 109.800447 -137.969271) (xy 109.841636 -138.004962)
			(xy 109.877327 -138.04615) (xy 109.906793 -138.091998) (xy 109.929436 -138.141572) (xy 109.944795 -138.193864)
			(xy 109.952556 -138.24781) (xy 109.953044 -138.27506) (xy 109.952545 -138.3038) (xy 109.943915 -138.360628)
			(xy 109.926858 -138.415518) (xy 109.901761 -138.467229) (xy 109.869192 -138.514591) (xy 109.84992 -138.535918)
			(xy 109.843316 -138.542776) (xy 109.836204 -138.56081) (xy 109.836204 -138.64971) (xy 109.843316 -138.667744)
			(xy 109.84992 -138.674602) (xy 109.869165 -138.695952) (xy 109.901736 -138.743307) (xy 109.926834 -138.795013)
			(xy 109.943891 -138.849899) (xy 109.95252 -138.906722) (xy 109.953044 -138.93546) (xy 112.090708 -138.93546)
			(xy 112.091205 -138.90672) (xy 112.099834 -138.849891) (xy 112.11689 -138.795) (xy 112.141988 -138.743289)
			(xy 112.174559 -138.695928) (xy 112.193832 -138.674602) (xy 112.200436 -138.667744) (xy 112.207548 -138.64971)
			(xy 112.207548 -138.56081) (xy 112.200436 -138.542776) (xy 112.193832 -138.535918) (xy 112.174541 -138.514608)
			(xy 112.141978 -138.467241) (xy 112.116889 -138.415525) (xy 112.099844 -138.360631) (xy 112.091226 -138.3038)
			(xy 112.090708 -138.27506) (xy 112.091194 -138.247809) (xy 112.09895 -138.193861) (xy 112.114305 -138.141566)
			(xy 112.136947 -138.091989) (xy 112.166413 -138.046139) (xy 112.202104 -138.004948) (xy 112.243295 -137.969257)
			(xy 112.289145 -137.939791) (xy 112.338722 -137.917149) (xy 112.391017 -137.901794) (xy 112.444965 -137.894038)
			(xy 112.499467 -137.894038) (xy 112.553415 -137.901794) (xy 112.60571 -137.917149) (xy 112.655287 -137.939791)
			(xy 112.701137 -137.969257) (xy 112.742328 -138.004948) (xy 112.778019 -138.046139) (xy 112.807485 -138.091989)
			(xy 112.830127 -138.141566) (xy 112.845482 -138.193861) (xy 112.853238 -138.247809) (xy 112.853724 -138.27506)
			(xy 112.85323 -138.3038) (xy 112.844599 -138.360628) (xy 112.827542 -138.415519) (xy 112.802444 -138.46723)
			(xy 112.769873 -138.514592) (xy 112.7506 -138.535918) (xy 112.743996 -138.542776) (xy 112.736884 -138.56081)
			(xy 112.736884 -138.64971) (xy 112.743996 -138.667744) (xy 112.7506 -138.674602) (xy 112.769841 -138.695955)
			(xy 112.802414 -138.743309) (xy 112.827513 -138.795014) (xy 112.84457 -138.849899) (xy 112.853199 -138.906723)
			(xy 112.853724 -138.93546) (xy 112.85327 -138.960927) (xy 112.84647 -139.011406) (xy 112.833011 -139.060531)
			(xy 112.813134 -139.107427) (xy 112.787191 -139.15126) (xy 112.755645 -139.19125) (xy 112.737646 -139.209272)
			(xy 112.73007 -139.217369) (xy 112.72217 -139.238063) (xy 112.722406 -139.24915) (xy 112.727994 -139.32662)
			(xy 112.729248 -139.337683) (xy 112.739929 -139.357188) (xy 112.748568 -139.364212) (xy 112.772282 -139.382359)
			(xy 112.81434 -139.42474) (xy 112.849289 -139.473152) (xy 112.876276 -139.526413) (xy 112.894644 -139.583226)
			(xy 112.903944 -139.642206) (xy 112.904524 -139.67206) (xy 112.90403 -139.7008) (xy 112.895399 -139.757628)
			(xy 112.878342 -139.812519) (xy 112.853244 -139.86423) (xy 112.820673 -139.911592) (xy 112.8014 -139.932918)
			(xy 112.794796 -139.939776) (xy 112.787684 -139.95781) (xy 112.787684 -140.04671) (xy 112.794796 -140.064744)
			(xy 112.8014 -140.071602) (xy 112.82063 -140.092964) (xy 112.853195 -140.140321) (xy 112.878287 -140.192027)
			(xy 112.895339 -140.246912) (xy 112.903964 -140.303734) (xy 112.903969 -140.361207) (xy 112.895352 -140.418031)
			(xy 112.878308 -140.472919) (xy 112.853224 -140.524629) (xy 112.820667 -140.571991) (xy 112.8014 -140.593318)
			(xy 112.794796 -140.600176) (xy 112.787684 -140.61821) (xy 112.787684 -140.70711) (xy 112.794796 -140.725144)
			(xy 112.8014 -140.732002) (xy 112.820641 -140.753355) (xy 112.853214 -140.800709) (xy 112.878313 -140.852414)
			(xy 112.89537 -140.907299) (xy 112.903999 -140.964123) (xy 112.90406 -140.96746) (xy 114.529108 -140.96746)
			(xy 114.529605 -140.93872) (xy 114.538234 -140.881891) (xy 114.55529 -140.827) (xy 114.580388 -140.775289)
			(xy 114.612959 -140.727928) (xy 114.632232 -140.706602) (xy 114.638836 -140.699744) (xy 114.645948 -140.68171)
			(xy 114.645948 -140.59281) (xy 114.638836 -140.574776) (xy 114.632232 -140.567918) (xy 114.612921 -140.546626)
			(xy 114.580357 -140.499258) (xy 114.555267 -140.44754) (xy 114.538219 -140.392644) (xy 114.5296 -140.335812)
			(xy 114.529605 -140.27833) (xy 114.538232 -140.221499) (xy 114.555288 -140.166605) (xy 114.580386 -140.114892)
			(xy 114.612958 -140.067529) (xy 114.632232 -140.046202) (xy 114.638836 -140.039344) (xy 114.645948 -140.02131)
			(xy 114.645948 -139.93241) (xy 114.638836 -139.914376) (xy 114.632232 -139.907518) (xy 114.612941 -139.886208)
			(xy 114.580378 -139.838841) (xy 114.555289 -139.787125) (xy 114.538244 -139.732231) (xy 114.529626 -139.6754)
			(xy 114.529108 -139.64666) (xy 114.529546 -139.620345) (xy 114.536787 -139.568215) (xy 114.551111 -139.517572)
			(xy 114.572249 -139.469373) (xy 114.599801 -139.42453) (xy 114.633244 -139.383892) (xy 114.652298 -139.365736)
			(xy 114.659685 -139.358203) (xy 114.668218 -139.338931) (xy 114.668808 -139.328398) (xy 114.668808 -139.253722)
			(xy 114.668278 -139.243173) (xy 114.659743 -139.223877) (xy 114.652298 -139.216384) (xy 114.633241 -139.19823)
			(xy 114.599784 -139.1576) (xy 114.572226 -139.112759) (xy 114.551087 -139.064558) (xy 114.53677 -139.01391)
			(xy 114.529546 -138.961776) (xy 114.529108 -138.93546) (xy 114.529605 -138.90672) (xy 114.538234 -138.849891)
			(xy 114.55529 -138.795) (xy 114.580388 -138.743289) (xy 114.612959 -138.695928) (xy 114.632232 -138.674602)
			(xy 114.638836 -138.667744) (xy 114.645948 -138.64971) (xy 114.645948 -138.56081) (xy 114.638836 -138.542776)
			(xy 114.632232 -138.535918) (xy 114.612941 -138.514608) (xy 114.580378 -138.467241) (xy 114.555289 -138.415525)
			(xy 114.538244 -138.360631) (xy 114.529626 -138.3038) (xy 114.529108 -138.27506) (xy 114.529541 -138.247807)
			(xy 114.537303 -138.193857) (xy 114.552664 -138.14156) (xy 114.575311 -138.091981) (xy 114.604783 -138.04613)
			(xy 114.64048 -138.00494) (xy 114.681675 -137.969249) (xy 114.727531 -137.939784) (xy 114.777112 -137.917144)
			(xy 114.829411 -137.901791) (xy 114.883363 -137.894037) (xy 114.910616 -137.893552) (xy 114.93829 -137.894058)
			(xy 114.993059 -137.902052) (xy 115.046094 -137.917884) (xy 115.096283 -137.94122) (xy 115.142567 -137.971571)
			(xy 115.1636 -137.989564) (xy 115.170966 -137.996168) (xy 115.188746 -138.002518) (xy 115.278154 -137.999724)
			(xy 115.295934 -137.992104) (xy 115.302792 -137.985246) (xy 115.32441 -137.964521) (xy 115.372875 -137.929347)
			(xy 115.426241 -137.90218) (xy 115.483198 -137.883689) (xy 115.542344 -137.874327) (xy 115.572286 -137.87374)
			(xy 115.599541 -137.874169) (xy 115.653495 -137.881925) (xy 115.705797 -137.897281) (xy 115.75538 -137.919926)
			(xy 115.801236 -137.949397) (xy 115.84243 -137.985094) (xy 115.878124 -138.026292) (xy 115.90759 -138.07215)
			(xy 115.93023 -138.121735) (xy 115.945582 -138.174038) (xy 115.953334 -138.227993) (xy 115.953794 -138.255248)
			(xy 115.953301 -138.283988) (xy 115.944671 -138.340817) (xy 115.927614 -138.395708) (xy 115.902516 -138.447419)
			(xy 115.869944 -138.49478) (xy 115.85067 -138.516106) (xy 115.844066 -138.522964) (xy 115.836954 -138.540998)
			(xy 115.836954 -138.578844) (xy 118.705882 -138.578844) (xy 118.709953 -138.523222) (xy 118.722079 -138.468785)
			(xy 118.742002 -138.416694) (xy 118.769298 -138.368059) (xy 118.803384 -138.323916) (xy 118.843533 -138.285207)
			(xy 118.888891 -138.252756) (xy 118.938491 -138.227255) (xy 118.991275 -138.209248) (xy 119.046118 -138.199118)
			(xy 119.101852 -138.197081) (xy 119.157289 -138.203181) (xy 119.211246 -138.217287) (xy 119.262575 -138.239099)
			(xy 119.310181 -138.268153) (xy 119.353049 -138.303828) (xy 119.390266 -138.345365) (xy 119.421039 -138.391878)
			(xy 119.444711 -138.442375) (xy 119.460779 -138.495782) (xy 119.468899 -138.550958) (xy 119.469408 -138.578844)
			(xy 119.468899 -138.60673) (xy 119.460779 -138.661906) (xy 119.444711 -138.715313) (xy 119.421039 -138.76581)
			(xy 119.390266 -138.812323) (xy 119.353049 -138.85386) (xy 119.310181 -138.889535) (xy 119.262575 -138.918589)
			(xy 119.211246 -138.940401) (xy 119.157289 -138.954507) (xy 119.101852 -138.960607) (xy 119.046118 -138.95857)
			(xy 118.991275 -138.94844) (xy 118.938491 -138.930433) (xy 118.888891 -138.904932) (xy 118.843533 -138.872481)
			(xy 118.803384 -138.833772) (xy 118.769298 -138.789629) (xy 118.742002 -138.740994) (xy 118.722079 -138.688903)
			(xy 118.709953 -138.634466) (xy 118.705882 -138.578844) (xy 115.836954 -138.578844) (xy 115.836954 -138.629898)
			(xy 115.844066 -138.647932) (xy 115.85067 -138.65479) (xy 115.869965 -138.676096) (xy 115.902527 -138.723464)
			(xy 115.927615 -138.775181) (xy 115.94466 -138.830076) (xy 115.953277 -138.886908) (xy 115.953794 -138.915648)
			(xy 115.95336 -138.941963) (xy 115.946119 -138.994093) (xy 115.931793 -139.044737) (xy 115.910655 -139.092936)
			(xy 115.883102 -139.137778) (xy 115.849658 -139.178416) (xy 115.830604 -139.196572) (xy 115.823213 -139.204103)
			(xy 115.814683 -139.223376) (xy 115.814094 -139.23391) (xy 115.814094 -139.308586) (xy 115.814619 -139.319136)
			(xy 115.823157 -139.338431) (xy 115.830604 -139.345924) (xy 115.849665 -139.364074) (xy 115.883121 -139.404705)
			(xy 115.91068 -139.449547) (xy 115.931817 -139.497748) (xy 115.946133 -139.548397) (xy 115.953356 -139.600532)
			(xy 115.953794 -139.626848) (xy 115.953301 -139.655588) (xy 115.944671 -139.712417) (xy 115.927614 -139.767308)
			(xy 115.902516 -139.819019) (xy 115.869944 -139.86638) (xy 115.85067 -139.887706) (xy 115.844066 -139.894564)
			(xy 115.836954 -139.912598) (xy 115.836954 -140.001498) (xy 115.844066 -140.019532) (xy 115.85067 -140.02639)
			(xy 115.869989 -140.047675) (xy 115.902553 -140.095045) (xy 115.927642 -140.146763) (xy 115.944689 -140.20166)
			(xy 115.953307 -140.258494) (xy 115.953302 -140.315976) (xy 115.944673 -140.372808) (xy 115.927616 -140.427702)
			(xy 115.902518 -140.479416) (xy 115.869945 -140.526779) (xy 115.85067 -140.548106) (xy 115.844066 -140.554964)
			(xy 115.836954 -140.572998) (xy 115.836954 -140.661898) (xy 115.844066 -140.679932) (xy 115.85067 -140.68679)
			(xy 115.869965 -140.708096) (xy 115.902527 -140.755464) (xy 115.927615 -140.807181) (xy 115.94466 -140.862076)
			(xy 115.953277 -140.918908) (xy 115.953794 -140.947648) (xy 115.953367 -140.974901) (xy 115.945603 -141.028852)
			(xy 115.930241 -141.081148) (xy 115.907594 -141.130727) (xy 115.878121 -141.176577) (xy 115.842424 -141.217767)
			(xy 115.801228 -141.253458) (xy 115.755372 -141.282923) (xy 115.70579 -141.305563) (xy 115.653491 -141.320917)
			(xy 115.599539 -141.328671) (xy 115.572286 -141.329156) (xy 115.544612 -141.328647) (xy 115.489844 -141.320653)
			(xy 115.436808 -141.304822) (xy 115.38662 -141.281486) (xy 115.340335 -141.251136) (xy 115.319302 -141.233144)
			(xy 115.311936 -141.22654) (xy 115.294156 -141.22019) (xy 115.204748 -141.222984) (xy 115.186968 -141.230604)
			(xy 115.18011 -141.237462) (xy 115.158536 -141.258235) (xy 115.11006 -141.293403) (xy 115.056682 -141.32056)
			(xy 114.999716 -141.33904) (xy 114.940561 -141.348388) (xy 114.910616 -141.348968) (xy 114.883362 -141.34853)
			(xy 114.829408 -141.340774) (xy 114.777107 -141.325418) (xy 114.727524 -141.302774) (xy 114.681669 -141.273304)
			(xy 114.640475 -141.237608) (xy 114.604781 -141.196412) (xy 114.575314 -141.150555) (xy 114.552674 -141.10097)
			(xy 114.537321 -141.048669) (xy 114.529569 -140.994714) (xy 114.529108 -140.96746) (xy 112.90406 -140.96746)
			(xy 112.904524 -140.99286) (xy 112.904038 -141.020111) (xy 112.896282 -141.074059) (xy 112.880927 -141.126354)
			(xy 112.858285 -141.175931) (xy 112.828819 -141.221781) (xy 112.793128 -141.262972) (xy 112.751937 -141.298663)
			(xy 112.706087 -141.328129) (xy 112.65651 -141.350771) (xy 112.604215 -141.366126) (xy 112.550267 -141.373882)
			(xy 112.495765 -141.373882) (xy 112.441817 -141.366126) (xy 112.389522 -141.350771) (xy 112.339945 -141.328129)
			(xy 112.294095 -141.298663) (xy 112.252904 -141.262972) (xy 112.217213 -141.221781) (xy 112.187747 -141.175931)
			(xy 112.165105 -141.126354) (xy 112.14975 -141.074059) (xy 112.141994 -141.020111) (xy 112.141508 -140.99286)
			(xy 112.142005 -140.96412) (xy 112.150634 -140.907291) (xy 112.16769 -140.8524) (xy 112.192788 -140.800689)
			(xy 112.225359 -140.753328) (xy 112.244632 -140.732002) (xy 112.251236 -140.725144) (xy 112.258348 -140.70711)
			(xy 112.258348 -140.61821) (xy 112.251236 -140.600176) (xy 112.244632 -140.593318) (xy 112.225321 -140.572026)
			(xy 112.192757 -140.524658) (xy 112.167667 -140.47294) (xy 112.150619 -140.418044) (xy 112.142 -140.361212)
			(xy 112.142005 -140.30373) (xy 112.150632 -140.246899) (xy 112.167688 -140.192005) (xy 112.192786 -140.140292)
			(xy 112.225358 -140.092929) (xy 112.244632 -140.071602) (xy 112.251236 -140.064744) (xy 112.258348 -140.04671)
			(xy 112.258348 -139.95781) (xy 112.251236 -139.939776) (xy 112.244632 -139.932918) (xy 112.225341 -139.911608)
			(xy 112.192778 -139.864241) (xy 112.167689 -139.812525) (xy 112.150644 -139.757631) (xy 112.142026 -139.7008)
			(xy 112.141508 -139.67206) (xy 112.141965 -139.646593) (xy 112.148764 -139.596114) (xy 112.162221 -139.546989)
			(xy 112.182098 -139.500093) (xy 112.20804 -139.456259) (xy 112.239586 -139.41627) (xy 112.257586 -139.398248)
			(xy 112.265156 -139.390147) (xy 112.273059 -139.369456) (xy 112.272826 -139.35837) (xy 112.267238 -139.2809)
			(xy 112.265962 -139.269842) (xy 112.255296 -139.250335) (xy 112.246664 -139.243308) (xy 112.222945 -139.225168)
			(xy 112.18089 -139.182783) (xy 112.145944 -139.134369) (xy 112.118958 -139.081107) (xy 112.100591 -139.024294)
			(xy 112.091289 -138.965314) (xy 112.090708 -138.93546) (xy 109.953044 -138.93546) (xy 109.952518 -138.964377)
			(xy 109.943794 -139.021549) (xy 109.926539 -139.076748) (xy 109.901149 -139.128711) (xy 109.868205 -139.176245)
			(xy 109.828464 -139.218261) (xy 109.805978 -139.23645) (xy 109.7972 -139.244085) (xy 109.787001 -139.264965)
			(xy 109.78642 -139.276582) (xy 109.78642 -139.356338) (xy 109.786945 -139.367972) (xy 109.797143 -139.388882)
			(xy 109.805978 -139.39647) (xy 109.828443 -139.414684) (xy 109.86818 -139.456698) (xy 109.901122 -139.504228)
			(xy 109.926514 -139.556185) (xy 109.943774 -139.611379) (xy 109.952507 -139.668545) (xy 109.953044 -139.69746)
			(xy 109.952545 -139.7262) (xy 109.943915 -139.783028) (xy 109.926858 -139.837918) (xy 109.901761 -139.889629)
			(xy 109.869192 -139.936991) (xy 109.84992 -139.958318) (xy 109.843316 -139.965176) (xy 109.836204 -139.98321)
			(xy 109.836204 -140.07211) (xy 109.843316 -140.090144) (xy 109.84992 -140.097002) (xy 109.869149 -140.118364)
			(xy 109.901712 -140.165722) (xy 109.926803 -140.217428) (xy 109.943854 -140.272313) (xy 109.952479 -140.329135)
			(xy 109.952483 -140.386607) (xy 109.943867 -140.44343) (xy 109.926824 -140.498318) (xy 109.901741 -140.550028)
			(xy 109.869186 -140.59739) (xy 109.84992 -140.618718) (xy 109.843316 -140.625576) (xy 109.836204 -140.64361)
			(xy 109.836204 -140.73251) (xy 109.843316 -140.750544) (xy 109.84992 -140.757402) (xy 109.869165 -140.778752)
			(xy 109.901736 -140.826107) (xy 109.926834 -140.877813) (xy 109.943891 -140.932699) (xy 109.95252 -140.989522)
			(xy 109.953044 -141.01826) (xy 109.952508 -141.04551) (xy 109.944757 -141.099457) (xy 109.929408 -141.151751)
			(xy 109.906773 -141.201329) (xy 109.877312 -141.24718) (xy 109.841626 -141.288372) (xy 109.800441 -141.324067)
			(xy 109.754595 -141.353536) (xy 109.705022 -141.376181) (xy 109.652731 -141.391541) (xy 109.598786 -141.399302)
			(xy 109.571536 -141.399768) (xy 109.542202 -141.399213) (xy 109.484222 -141.390248) (xy 109.4283 -141.372509)
			(xy 109.375755 -141.346415) (xy 109.327825 -141.312581) (xy 109.30636 -141.29258) (xy 109.298994 -141.285468)
			(xy 109.281214 -141.278356) (xy 109.190282 -141.278356) (xy 109.172502 -141.285468) (xy 109.165136 -141.29258)
			(xy 109.143652 -141.312559) (xy 109.095723 -141.34639) (xy 109.043182 -141.372489) (xy 108.987266 -141.39024)
			(xy 108.929293 -141.399226) (xy 108.89996 -141.399768) (xy 108.872706 -141.399359) (xy 108.818753 -141.391596)
			(xy 108.766455 -141.376234) (xy 108.716875 -141.353585) (xy 108.671023 -141.324111) (xy 108.629832 -141.288412)
			(xy 108.594141 -141.247213) (xy 108.564676 -141.201355) (xy 108.542038 -141.15177) (xy 108.526687 -141.099468)
			(xy 108.518935 -141.045514) (xy 108.518452 -141.01826) (xy 106.893868 -141.01826) (xy 106.893382 -141.045511)
			(xy 106.885626 -141.099459) (xy 106.870271 -141.151754) (xy 106.847629 -141.201331) (xy 106.818163 -141.247181)
			(xy 106.782472 -141.288372) (xy 106.741281 -141.324063) (xy 106.695431 -141.353529) (xy 106.645854 -141.376171)
			(xy 106.593559 -141.391526) (xy 106.539611 -141.399282) (xy 106.485109 -141.399282) (xy 106.431161 -141.391526)
			(xy 106.378866 -141.376171) (xy 106.329289 -141.353529) (xy 106.283439 -141.324063) (xy 106.242248 -141.288372)
			(xy 106.206557 -141.247181) (xy 106.177091 -141.201331) (xy 106.154449 -141.151754) (xy 106.139094 -141.099459)
			(xy 106.131338 -141.045511) (xy 106.130852 -141.01826) (xy 106.131364 -140.989521) (xy 106.139992 -140.932694)
			(xy 106.157045 -140.877803) (xy 106.182139 -140.826092) (xy 106.214705 -140.778729) (xy 106.233976 -140.757402)
			(xy 106.24058 -140.750544) (xy 106.247692 -140.73251) (xy 106.247692 -140.64361) (xy 106.24058 -140.625576)
			(xy 106.233976 -140.618718) (xy 106.214668 -140.597425) (xy 106.182108 -140.550055) (xy 106.157022 -140.498337)
			(xy 106.139977 -140.443442) (xy 106.131359 -140.386611) (xy 106.131363 -140.329131) (xy 106.13999 -140.272301)
			(xy 106.157043 -140.217408) (xy 106.182137 -140.165694) (xy 106.214704 -140.11833) (xy 106.233976 -140.097002)
			(xy 106.24058 -140.090144) (xy 106.247692 -140.07211) (xy 106.247692 -139.98321) (xy 106.24058 -139.965176)
			(xy 106.233976 -139.958318) (xy 106.214693 -139.937002) (xy 106.182127 -139.889638) (xy 106.157036 -139.837923)
			(xy 106.139988 -139.78303) (xy 106.13137 -139.7262) (xy 106.130852 -139.69746) (xy 106.13131 -139.671555)
			(xy 106.138325 -139.620221) (xy 106.152221 -139.570309) (xy 106.172741 -139.522735) (xy 106.199509 -139.478375)
			(xy 106.215434 -139.457938) (xy 106.221153 -139.450166) (xy 106.226912 -139.431767) (xy 106.22661 -139.422124)
			(xy 106.221022 -139.352528) (xy 106.21992 -139.343099) (xy 106.211695 -139.326005) (xy 106.20502 -139.319254)
			(xy 106.204512 -139.318746) (xy 106.185276 -139.300619) (xy 106.151515 -139.259951) (xy 106.123689 -139.215013)
			(xy 106.102331 -139.166665) (xy 106.087848 -139.115832) (xy 106.080519 -139.063487) (xy 106.080052 -139.03706)
			(xy 103.456994 -139.03706) (xy 103.456994 -150.076916) (xy 103.456568 -150.086985) (xy 103.448849 -150.105584)
			(xy 103.442008 -150.112984) (xy 100.70592 -152.849072) (xy 100.699083 -152.856474) (xy 100.691371 -152.875072)
			(xy 100.690934 -152.88514) (xy 100.690934 -158.947612) (xy 107.304584 -158.947612) (xy 107.308655 -158.89199)
			(xy 107.320781 -158.837553) (xy 107.340704 -158.785462) (xy 107.368 -158.736827) (xy 107.402086 -158.692684)
			(xy 107.442235 -158.653975) (xy 107.487593 -158.621524) (xy 107.537193 -158.596023) (xy 107.589977 -158.578016)
			(xy 107.64482 -158.567886) (xy 107.700554 -158.565849) (xy 107.755991 -158.571949) (xy 107.809948 -158.586055)
			(xy 107.861277 -158.607867) (xy 107.908883 -158.636921) (xy 107.951751 -158.672596) (xy 107.988968 -158.714133)
			(xy 108.019741 -158.760646) (xy 108.043413 -158.811143) (xy 108.059481 -158.86455) (xy 108.067601 -158.919726)
			(xy 108.06811 -158.947612) (xy 108.067601 -158.975498) (xy 108.059481 -159.030674) (xy 108.043413 -159.084081)
			(xy 108.019741 -159.134578) (xy 107.988968 -159.181091) (xy 107.951751 -159.222628) (xy 107.908883 -159.258303)
			(xy 107.861277 -159.287357) (xy 107.809948 -159.309169) (xy 107.755991 -159.323275) (xy 107.700554 -159.329375)
			(xy 107.64482 -159.327338) (xy 107.589977 -159.317208) (xy 107.537193 -159.299201) (xy 107.487593 -159.2737)
			(xy 107.442235 -159.241249) (xy 107.402086 -159.20254) (xy 107.368 -159.158397) (xy 107.340704 -159.109762)
			(xy 107.320781 -159.057671) (xy 107.308655 -159.003234) (xy 107.304584 -158.947612) (xy 100.690934 -158.947612)
			(xy 100.690934 -159.681418) (xy 112.176558 -159.681418) (xy 112.180629 -159.625796) (xy 112.192755 -159.571359)
			(xy 112.212678 -159.519268) (xy 112.239974 -159.470633) (xy 112.27406 -159.42649) (xy 112.314209 -159.387781)
			(xy 112.359567 -159.35533) (xy 112.409167 -159.329829) (xy 112.461951 -159.311822) (xy 112.516794 -159.301692)
			(xy 112.572528 -159.299655) (xy 112.627965 -159.305755) (xy 112.681922 -159.319861) (xy 112.733251 -159.341673)
			(xy 112.780857 -159.370727) (xy 112.823725 -159.406402) (xy 112.860942 -159.447939) (xy 112.891715 -159.494452)
			(xy 112.915387 -159.544949) (xy 112.931455 -159.598356) (xy 112.939575 -159.653532) (xy 112.940084 -159.681418)
			(xy 112.939575 -159.709304) (xy 112.931455 -159.76448) (xy 112.915387 -159.817887) (xy 112.891715 -159.868384)
			(xy 112.860942 -159.914897) (xy 112.823725 -159.956434) (xy 112.780857 -159.992109) (xy 112.733251 -160.021163)
			(xy 112.681922 -160.042975) (xy 112.627965 -160.057081) (xy 112.572528 -160.063181) (xy 112.516794 -160.061144)
			(xy 112.461951 -160.051014) (xy 112.409167 -160.033007) (xy 112.359567 -160.007506) (xy 112.314209 -159.975055)
			(xy 112.27406 -159.936346) (xy 112.239974 -159.892203) (xy 112.212678 -159.843568) (xy 112.192755 -159.791477)
			(xy 112.180629 -159.73704) (xy 112.176558 -159.681418) (xy 100.690934 -159.681418) (xy 100.690934 -160.220406)
			(xy 113.389916 -160.220406) (xy 113.393987 -160.164784) (xy 113.406113 -160.110347) (xy 113.426036 -160.058256)
			(xy 113.453332 -160.009621) (xy 113.487418 -159.965478) (xy 113.527567 -159.926769) (xy 113.572925 -159.894318)
			(xy 113.622525 -159.868817) (xy 113.675309 -159.85081) (xy 113.730152 -159.84068) (xy 113.785886 -159.838643)
			(xy 113.841323 -159.844743) (xy 113.89528 -159.858849) (xy 113.946609 -159.880661) (xy 113.994215 -159.909715)
			(xy 114.037083 -159.94539) (xy 114.0743 -159.986927) (xy 114.105073 -160.03344) (xy 114.128745 -160.083937)
			(xy 114.144813 -160.137344) (xy 114.152933 -160.19252) (xy 114.153442 -160.220406) (xy 114.152933 -160.248292)
			(xy 114.144813 -160.303468) (xy 114.128745 -160.356875) (xy 114.105073 -160.407372) (xy 114.0743 -160.453885)
			(xy 114.058189 -160.471866) (xy 114.82019 -160.471866) (xy 114.824261 -160.416244) (xy 114.836387 -160.361807)
			(xy 114.85631 -160.309716) (xy 114.883606 -160.261081) (xy 114.917692 -160.216938) (xy 114.957841 -160.178229)
			(xy 115.003199 -160.145778) (xy 115.052799 -160.120277) (xy 115.105583 -160.10227) (xy 115.160426 -160.09214)
			(xy 115.21616 -160.090103) (xy 115.271597 -160.096203) (xy 115.325554 -160.110309) (xy 115.376883 -160.132121)
			(xy 115.424489 -160.161175) (xy 115.467357 -160.19685) (xy 115.504574 -160.238387) (xy 115.535347 -160.2849)
			(xy 115.559019 -160.335397) (xy 115.575087 -160.388804) (xy 115.583207 -160.44398) (xy 115.583716 -160.471866)
			(xy 115.583207 -160.499752) (xy 115.575087 -160.554928) (xy 115.559019 -160.608335) (xy 115.535347 -160.658832)
			(xy 115.504574 -160.705345) (xy 115.467357 -160.746882) (xy 115.424489 -160.782557) (xy 115.376883 -160.811611)
			(xy 115.325554 -160.833423) (xy 115.271597 -160.847529) (xy 115.21616 -160.853629) (xy 115.160426 -160.851592)
			(xy 115.105583 -160.841462) (xy 115.052799 -160.823455) (xy 115.003199 -160.797954) (xy 114.957841 -160.765503)
			(xy 114.917692 -160.726794) (xy 114.883606 -160.682651) (xy 114.85631 -160.634016) (xy 114.836387 -160.581925)
			(xy 114.824261 -160.527488) (xy 114.82019 -160.471866) (xy 114.058189 -160.471866) (xy 114.037083 -160.495422)
			(xy 113.994215 -160.531097) (xy 113.946609 -160.560151) (xy 113.89528 -160.581963) (xy 113.841323 -160.596069)
			(xy 113.785886 -160.602169) (xy 113.730152 -160.600132) (xy 113.675309 -160.590002) (xy 113.622525 -160.571995)
			(xy 113.572925 -160.546494) (xy 113.527567 -160.514043) (xy 113.487418 -160.475334) (xy 113.453332 -160.431191)
			(xy 113.426036 -160.382556) (xy 113.406113 -160.330465) (xy 113.393987 -160.276028) (xy 113.389916 -160.220406)
			(xy 100.690934 -160.220406) (xy 100.690934 -162.131502) (xy 111.67313 -162.131502) (xy 111.677201 -162.07588)
			(xy 111.689327 -162.021443) (xy 111.70925 -161.969352) (xy 111.736546 -161.920717) (xy 111.770632 -161.876574)
			(xy 111.810781 -161.837865) (xy 111.856139 -161.805414) (xy 111.905739 -161.779913) (xy 111.958523 -161.761906)
			(xy 112.013366 -161.751776) (xy 112.0691 -161.749739) (xy 112.124537 -161.755839) (xy 112.178494 -161.769945)
			(xy 112.229823 -161.791757) (xy 112.252954 -161.805874) (xy 113.226848 -161.805874) (xy 113.230919 -161.750252)
			(xy 113.243045 -161.695815) (xy 113.262968 -161.643724) (xy 113.290264 -161.595089) (xy 113.32435 -161.550946)
			(xy 113.364499 -161.512237) (xy 113.409857 -161.479786) (xy 113.459457 -161.454285) (xy 113.512241 -161.436278)
			(xy 113.567084 -161.426148) (xy 113.622818 -161.424111) (xy 113.678255 -161.430211) (xy 113.732212 -161.444317)
			(xy 113.783541 -161.466129) (xy 113.831147 -161.495183) (xy 113.874015 -161.530858) (xy 113.911232 -161.572395)
			(xy 113.942005 -161.618908) (xy 113.965677 -161.669405) (xy 113.981745 -161.722812) (xy 113.989865 -161.777988)
			(xy 113.990374 -161.805874) (xy 113.989865 -161.83376) (xy 113.981745 -161.888936) (xy 113.965677 -161.942343)
			(xy 113.942005 -161.99284) (xy 113.911232 -162.039353) (xy 113.874015 -162.08089) (xy 113.831147 -162.116565)
			(xy 113.81125 -162.128708) (xy 115.561108 -162.128708) (xy 115.565179 -162.073086) (xy 115.577305 -162.018649)
			(xy 115.597228 -161.966558) (xy 115.624524 -161.917923) (xy 115.65861 -161.87378) (xy 115.698759 -161.835071)
			(xy 115.744117 -161.80262) (xy 115.793717 -161.777119) (xy 115.846501 -161.759112) (xy 115.901344 -161.748982)
			(xy 115.957078 -161.746945) (xy 116.012515 -161.753045) (xy 116.066472 -161.767151) (xy 116.117801 -161.788963)
			(xy 116.165407 -161.818017) (xy 116.208275 -161.853692) (xy 116.245492 -161.895229) (xy 116.276265 -161.941742)
			(xy 116.299937 -161.992239) (xy 116.316005 -162.045646) (xy 116.324125 -162.100822) (xy 116.324634 -162.128708)
			(xy 116.324125 -162.156594) (xy 116.316005 -162.21177) (xy 116.299937 -162.265177) (xy 116.276265 -162.315674)
			(xy 116.245492 -162.362187) (xy 116.208275 -162.403724) (xy 116.165407 -162.439399) (xy 116.117801 -162.468453)
			(xy 116.066472 -162.490265) (xy 116.012515 -162.504371) (xy 115.957078 -162.510471) (xy 115.901344 -162.508434)
			(xy 115.846501 -162.498304) (xy 115.793717 -162.480297) (xy 115.744117 -162.454796) (xy 115.698759 -162.422345)
			(xy 115.65861 -162.383636) (xy 115.624524 -162.339493) (xy 115.597228 -162.290858) (xy 115.577305 -162.238767)
			(xy 115.565179 -162.18433) (xy 115.561108 -162.128708) (xy 113.81125 -162.128708) (xy 113.783541 -162.145619)
			(xy 113.732212 -162.167431) (xy 113.678255 -162.181537) (xy 113.622818 -162.187637) (xy 113.567084 -162.1856)
			(xy 113.512241 -162.17547) (xy 113.459457 -162.157463) (xy 113.409857 -162.131962) (xy 113.364499 -162.099511)
			(xy 113.32435 -162.060802) (xy 113.290264 -162.016659) (xy 113.262968 -161.968024) (xy 113.243045 -161.915933)
			(xy 113.230919 -161.861496) (xy 113.226848 -161.805874) (xy 112.252954 -161.805874) (xy 112.277429 -161.820811)
			(xy 112.320297 -161.856486) (xy 112.357514 -161.898023) (xy 112.388287 -161.944536) (xy 112.411959 -161.995033)
			(xy 112.428027 -162.04844) (xy 112.436147 -162.103616) (xy 112.436656 -162.131502) (xy 112.436147 -162.159388)
			(xy 112.428027 -162.214564) (xy 112.411959 -162.267971) (xy 112.388287 -162.318468) (xy 112.357514 -162.364981)
			(xy 112.320297 -162.406518) (xy 112.277429 -162.442193) (xy 112.229823 -162.471247) (xy 112.178494 -162.493059)
			(xy 112.124537 -162.507165) (xy 112.0691 -162.513265) (xy 112.013366 -162.511228) (xy 111.958523 -162.501098)
			(xy 111.905739 -162.483091) (xy 111.856139 -162.45759) (xy 111.810781 -162.425139) (xy 111.770632 -162.38643)
			(xy 111.736546 -162.342287) (xy 111.70925 -162.293652) (xy 111.689327 -162.241561) (xy 111.677201 -162.187124)
			(xy 111.67313 -162.131502) (xy 100.690934 -162.131502) (xy 100.690934 -163.41344) (xy 113.15268 -163.41344)
			(xy 113.156751 -163.357818) (xy 113.168877 -163.303381) (xy 113.1888 -163.25129) (xy 113.216096 -163.202655)
			(xy 113.250182 -163.158512) (xy 113.290331 -163.119803) (xy 113.335689 -163.087352) (xy 113.385289 -163.061851)
			(xy 113.438073 -163.043844) (xy 113.492916 -163.033714) (xy 113.54865 -163.031677) (xy 113.604087 -163.037777)
			(xy 113.658044 -163.051883) (xy 113.709373 -163.073695) (xy 113.756979 -163.102749) (xy 113.799847 -163.138424)
			(xy 113.837064 -163.179961) (xy 113.867837 -163.226474) (xy 113.891509 -163.276971) (xy 113.907577 -163.330378)
			(xy 113.915697 -163.385554) (xy 113.916206 -163.41344) (xy 113.915697 -163.441326) (xy 113.907577 -163.496502)
			(xy 113.891509 -163.549909) (xy 113.867837 -163.600406) (xy 113.837064 -163.646919) (xy 113.799847 -163.688456)
			(xy 113.756979 -163.724131) (xy 113.709373 -163.753185) (xy 113.658044 -163.774997) (xy 113.604087 -163.789103)
			(xy 113.54865 -163.795203) (xy 113.492916 -163.793166) (xy 113.438073 -163.783036) (xy 113.385289 -163.765029)
			(xy 113.335689 -163.739528) (xy 113.290331 -163.707077) (xy 113.250182 -163.668368) (xy 113.216096 -163.624225)
			(xy 113.1888 -163.57559) (xy 113.168877 -163.523499) (xy 113.156751 -163.469062) (xy 113.15268 -163.41344)
			(xy 100.690934 -163.41344) (xy 100.690934 -180.494686) (xy 100.691374 -180.504749) (xy 100.699114 -180.523327)
			(xy 100.70592 -180.530754) (xy 101.114635 -180.93944) (xy 107.97667 -180.93944) (xy 107.977165 -180.9107)
			(xy 107.985796 -180.853872) (xy 108.002853 -180.798981) (xy 108.027951 -180.74727) (xy 108.060521 -180.699908)
			(xy 108.079794 -180.678582) (xy 108.086398 -180.671724) (xy 108.09351 -180.65369) (xy 108.09351 -180.56479)
			(xy 108.086398 -180.546756) (xy 108.079794 -180.539898) (xy 108.060552 -180.518546) (xy 108.02798 -180.471192)
			(xy 108.002881 -180.419487) (xy 107.985824 -180.364601) (xy 107.977195 -180.307777) (xy 107.97667 -180.27904)
			(xy 107.977192 -180.251789) (xy 107.984943 -180.197841) (xy 108.000293 -180.145546) (xy 108.022929 -180.095968)
			(xy 108.052391 -180.050115) (xy 108.088079 -180.008923) (xy 108.129266 -179.973228) (xy 108.175113 -179.943759)
			(xy 108.224688 -179.921115) (xy 108.276981 -179.905757) (xy 108.330927 -179.897997) (xy 108.358178 -179.897532)
			(xy 108.383547 -179.897949) (xy 108.433837 -179.904672) (xy 108.482791 -179.918002) (xy 108.529547 -179.937705)
			(xy 108.573278 -179.963431) (xy 108.613213 -179.994728) (xy 108.631228 -180.012594) (xy 108.638551 -180.019352)
			(xy 108.656844 -180.027202) (xy 108.666788 -180.027834) (xy 108.74883 -180.02885) (xy 108.767118 -180.021738)
			(xy 108.774484 -180.014626) (xy 108.795961 -179.994638) (xy 108.843891 -179.960808) (xy 108.896434 -179.934711)
			(xy 108.952352 -179.916962) (xy 109.010327 -179.907978) (xy 109.03966 -179.907438) (xy 109.06703 -179.907918)
			(xy 109.121209 -179.915731) (xy 109.173712 -179.931216) (xy 109.223459 -179.954055) (xy 109.269426 -179.983778)
			(xy 109.290358 -180.001418) (xy 109.290612 -180.001672) (xy 109.297685 -180.007278) (xy 109.314612 -180.013511)
			(xy 109.323632 -180.013864) (xy 109.390688 -180.013864) (xy 109.399705 -180.013509) (xy 109.416622 -180.007261)
			(xy 109.423708 -180.001672) (xy 109.423708 -180.001418) (xy 109.423962 -180.001418) (xy 109.444895 -179.983777)
			(xy 109.490863 -179.954053) (xy 109.540609 -179.931207) (xy 109.593111 -179.915711) (xy 109.647289 -179.907882)
			(xy 109.702031 -179.907882) (xy 109.756209 -179.915711) (xy 109.808711 -179.931207) (xy 109.858457 -179.954053)
			(xy 109.904425 -179.983777) (xy 109.925358 -180.001418) (xy 109.925612 -180.001672) (xy 109.932685 -180.007278)
			(xy 109.949612 -180.013511) (xy 109.958632 -180.013864) (xy 110.025688 -180.013864) (xy 110.034705 -180.013509)
			(xy 110.051622 -180.007261) (xy 110.058708 -180.001672) (xy 110.058708 -180.001418) (xy 110.058962 -180.001418)
			(xy 110.079895 -179.983777) (xy 110.125863 -179.954053) (xy 110.175609 -179.931207) (xy 110.228111 -179.915711)
			(xy 110.282289 -179.907882) (xy 110.337031 -179.907882) (xy 110.391209 -179.915711) (xy 110.443711 -179.931207)
			(xy 110.493457 -179.954053) (xy 110.539425 -179.983777) (xy 110.560358 -180.001418) (xy 110.560612 -180.001672)
			(xy 110.567685 -180.007278) (xy 110.584612 -180.013511) (xy 110.593632 -180.013864) (xy 110.660688 -180.013864)
			(xy 110.669705 -180.013509) (xy 110.686622 -180.007261) (xy 110.693708 -180.001672) (xy 110.693708 -180.001418)
			(xy 110.693962 -180.001418) (xy 110.714895 -179.983777) (xy 110.760863 -179.954053) (xy 110.810609 -179.931207)
			(xy 110.863111 -179.915711) (xy 110.917289 -179.907882) (xy 110.972031 -179.907882) (xy 111.026209 -179.915711)
			(xy 111.078711 -179.931207) (xy 111.128457 -179.954053) (xy 111.174425 -179.983777) (xy 111.195358 -180.001418)
			(xy 111.195612 -180.001672) (xy 111.202685 -180.007278) (xy 111.219612 -180.013511) (xy 111.228632 -180.013864)
			(xy 111.295688 -180.013864) (xy 111.304705 -180.013509) (xy 111.321622 -180.007261) (xy 111.328708 -180.001672)
			(xy 111.328708 -180.001418) (xy 111.328962 -180.001418) (xy 111.3499 -179.983786) (xy 111.395871 -179.954073)
			(xy 111.445617 -179.931235) (xy 111.498116 -179.915742) (xy 111.552291 -179.907913) (xy 111.57966 -179.907438)
			(xy 111.606914 -179.907893) (xy 111.660868 -179.915645) (xy 111.713168 -179.930999) (xy 111.762751 -179.95364)
			(xy 111.808607 -179.983108) (xy 111.849801 -180.018803) (xy 111.885496 -180.059998) (xy 111.914963 -180.105854)
			(xy 111.937603 -180.155437) (xy 111.952956 -180.207738) (xy 111.960708 -180.261692) (xy 111.961168 -180.288946)
			(xy 111.960654 -180.317685) (xy 111.952026 -180.374512) (xy 111.934973 -180.429402) (xy 111.90988 -180.481114)
			(xy 111.877314 -180.528477) (xy 111.858044 -180.549804) (xy 111.85144 -180.556662) (xy 111.844328 -180.574696)
			(xy 111.844328 -180.663596) (xy 111.85144 -180.68163) (xy 111.858044 -180.688488) (xy 111.877334 -180.709799)
			(xy 111.909898 -180.757165) (xy 111.934987 -180.808881) (xy 111.952033 -180.863775) (xy 111.96065 -180.920606)
			(xy 111.961168 -180.949346) (xy 111.960765 -180.9766) (xy 111.953001 -181.030553) (xy 111.937638 -181.082852)
			(xy 111.914989 -181.132432) (xy 111.885514 -181.178284) (xy 111.849814 -181.219475) (xy 111.808615 -181.255165)
			(xy 111.762756 -181.28463) (xy 111.713171 -181.307268) (xy 111.660869 -181.322619) (xy 111.606914 -181.330371)
			(xy 111.57966 -181.330854) (xy 111.552291 -181.330364) (xy 111.498112 -181.322554) (xy 111.445609 -181.307071)
			(xy 111.395861 -181.284234) (xy 111.349894 -181.254514) (xy 111.328962 -181.236874) (xy 111.328708 -181.23662)
			(xy 111.32163 -181.231021) (xy 111.304706 -181.224784) (xy 111.295688 -181.224428) (xy 111.228632 -181.224428)
			(xy 111.219616 -181.224794) (xy 111.202699 -181.231035) (xy 111.195612 -181.23662) (xy 111.195358 -181.236874)
			(xy 111.174425 -181.254515) (xy 111.128457 -181.284239) (xy 111.078711 -181.307085) (xy 111.026209 -181.322581)
			(xy 110.972031 -181.33041) (xy 110.917289 -181.33041) (xy 110.863111 -181.322581) (xy 110.810609 -181.307085)
			(xy 110.760863 -181.284239) (xy 110.714895 -181.254515) (xy 110.693962 -181.236874) (xy 110.693708 -181.23662)
			(xy 110.68663 -181.231021) (xy 110.669706 -181.224784) (xy 110.660688 -181.224428) (xy 110.593632 -181.224428)
			(xy 110.584616 -181.224794) (xy 110.567699 -181.231035) (xy 110.560612 -181.23662) (xy 110.560612 -181.236874)
			(xy 110.560358 -181.236874) (xy 110.539425 -181.254515) (xy 110.493457 -181.284239) (xy 110.443711 -181.307085)
			(xy 110.391209 -181.322581) (xy 110.337031 -181.33041) (xy 110.282289 -181.33041) (xy 110.228111 -181.322581)
			(xy 110.175609 -181.307085) (xy 110.125863 -181.284239) (xy 110.079895 -181.254515) (xy 110.058962 -181.236874)
			(xy 110.058708 -181.23662) (xy 110.05163 -181.231021) (xy 110.034706 -181.224784) (xy 110.025688 -181.224428)
			(xy 109.958632 -181.224428) (xy 109.949616 -181.224794) (xy 109.932699 -181.231035) (xy 109.925612 -181.23662)
			(xy 109.925612 -181.236874) (xy 109.925358 -181.236874) (xy 109.904425 -181.254515) (xy 109.858457 -181.284239)
			(xy 109.808711 -181.307085) (xy 109.756209 -181.322581) (xy 109.702031 -181.33041) (xy 109.647289 -181.33041)
			(xy 109.593111 -181.322581) (xy 109.540609 -181.307085) (xy 109.490863 -181.284239) (xy 109.444895 -181.254515)
			(xy 109.423962 -181.236874) (xy 109.423708 -181.23662) (xy 109.41663 -181.231021) (xy 109.399706 -181.224784)
			(xy 109.390688 -181.224428) (xy 109.323632 -181.224428) (xy 109.314616 -181.224794) (xy 109.297699 -181.231035)
			(xy 109.290612 -181.23662) (xy 109.290612 -181.236874) (xy 109.290358 -181.236874) (xy 109.269412 -181.254495)
			(xy 109.223443 -181.284211) (xy 109.173699 -181.30705) (xy 109.121202 -181.322546) (xy 109.067028 -181.330378)
			(xy 109.03966 -181.330854) (xy 109.01429 -181.330482) (xy 108.963998 -181.32375) (xy 108.915042 -181.310411)
			(xy 108.868286 -181.290701) (xy 108.824556 -181.264966) (xy 108.784624 -181.233662) (xy 108.76661 -181.215792)
			(xy 108.75931 -181.209005) (xy 108.741 -181.201172) (xy 108.73105 -181.200552) (xy 108.649008 -181.199536)
			(xy 108.63072 -181.206648) (xy 108.623354 -181.21376) (xy 108.601875 -181.233744) (xy 108.553943 -181.267571)
			(xy 108.501401 -181.293668) (xy 108.445485 -181.311418) (xy 108.387511 -181.320405) (xy 108.358178 -181.320948)
			(xy 108.330928 -181.320443) (xy 108.276983 -181.312684) (xy 108.224691 -181.297328) (xy 108.175117 -181.274688)
			(xy 108.129268 -181.245223) (xy 108.088079 -181.209534) (xy 108.052388 -181.168346) (xy 108.022921 -181.122499)
			(xy 108.000278 -181.072926) (xy 107.98492 -181.020635) (xy 107.977158 -180.96669) (xy 107.97667 -180.93944)
			(xy 101.114635 -180.93944) (xy 104.302306 -184.126886) (xy 104.309704 -184.133733) (xy 104.328302 -184.141467)
			(xy 104.338374 -184.141872) (xy 107.436158 -184.141872) (xy 107.455195 -184.14218) (xy 107.493008 -184.146638)
			(xy 107.511596 -184.150762) (xy 107.517438 -184.152032)
		)
		(stroke
			(width 0)
			(type solid)
		)
		(fill yes)
		(layer "In13.Cu")
		(net "GND")
	)
	(gr_poly
		(pts
			(xy 63.722504 -173.095412) (xy 63.732574 -173.094989) (xy 63.751179 -173.087275) (xy 63.758572 -173.080426)
			(xy 63.99911 -172.839888) (xy 64.005964 -172.832493) (xy 64.013709 -172.813894) (xy 64.014096 -172.80382)
			(xy 64.014096 -162.00882) (xy 64.013731 -162.000027) (xy 64.007785 -161.983477) (xy 63.99659 -161.969916)
			(xy 63.989204 -161.965132) (xy 63.965061 -161.950332) (xy 63.921034 -161.914719) (xy 63.882759 -161.872986)
			(xy 63.851078 -161.826051) (xy 63.826687 -161.774946) (xy 63.810123 -161.720796) (xy 63.801751 -161.664791)
			(xy 63.801754 -161.608164) (xy 63.810133 -161.552161) (xy 63.826703 -161.498012) (xy 63.8511 -161.44691)
			(xy 63.882787 -161.399979) (xy 63.921067 -161.35825) (xy 63.965098 -161.322643) (xy 63.989204 -161.30778)
			(xy 63.996576 -161.302979) (xy 64.00777 -161.289425) (xy 64.013716 -161.272882) (xy 64.014096 -161.264092)
			(xy 64.014096 -147.845526) (xy 64.013659 -147.835462) (xy 64.005925 -147.816877) (xy 63.99911 -147.809458)
			(xy 57.432956 -141.243304) (xy 57.425609 -141.2365) (xy 57.407146 -141.228783) (xy 57.397142 -141.228318)
			(xy 57.315608 -141.228064) (xy 57.29732 -141.23543) (xy 57.289954 -141.242542) (xy 57.26843 -141.262845)
			(xy 57.220275 -141.297226) (xy 57.16739 -141.323759) (xy 57.111043 -141.34181) (xy 57.052584 -141.350945)
			(xy 57.023 -141.351508) (xy 56.995749 -141.351022) (xy 56.941801 -141.343266) (xy 56.889506 -141.327911)
			(xy 56.839929 -141.305269) (xy 56.794079 -141.275803) (xy 56.752888 -141.240112) (xy 56.717197 -141.198921)
			(xy 56.687731 -141.153071) (xy 56.665089 -141.103494) (xy 56.649734 -141.051199) (xy 56.641978 -140.997251)
			(xy 56.641492 -140.97) (xy 56.642049 -140.940415) (xy 56.651184 -140.881956) (xy 56.669235 -140.825608)
			(xy 56.695769 -140.772722) (xy 56.73015 -140.724566) (xy 56.750458 -140.703046) (xy 56.75757 -140.69568)
			(xy 56.764936 -140.677392) (xy 56.764682 -140.595858) (xy 56.764137 -140.585874) (xy 56.75641 -140.567455)
			(xy 56.749696 -140.560044) (xy 55.837582 -139.64793) (xy 55.830184 -139.641083) (xy 55.811586 -139.63335)
			(xy 55.801514 -139.632944) (xy 47.670212 -139.632944) (xy 47.660253 -139.633435) (xy 47.641838 -139.641033)
			(xy 47.634398 -139.647676) (xy 47.576232 -139.705334) (xy 47.568612 -139.723622) (xy 47.568612 -139.733782)
			(xy 47.567974 -139.76069) (xy 47.560055 -139.813926) (xy 47.544724 -139.865519) (xy 47.522288 -139.914442)
			(xy 47.493192 -139.959722) (xy 47.458015 -140.000458) (xy 47.438056 -140.018516) (xy 47.430182 -140.025628)
			(xy 47.421038 -140.04417) (xy 47.416974 -140.138658) (xy 47.424086 -140.157962) (xy 47.431452 -140.165582)
			(xy 47.451244 -140.18701) (xy 47.484745 -140.234759) (xy 47.51058 -140.287055) (xy 47.528147 -140.342676)
			(xy 47.537035 -140.400323) (xy 47.537624 -140.429488) (xy 47.537138 -140.456739) (xy 47.529382 -140.510687)
			(xy 47.514027 -140.562982) (xy 47.491385 -140.612559) (xy 47.461919 -140.658409) (xy 47.426228 -140.6996)
			(xy 47.385037 -140.735291) (xy 47.339187 -140.764757) (xy 47.338607 -140.765022) (xy 51.251612 -140.765022)
			(xy 51.252204 -140.736139) (xy 51.260888 -140.679029) (xy 51.278092 -140.623884) (xy 51.303421 -140.571967)
			(xy 51.336295 -140.524467) (xy 51.375961 -140.482472) (xy 51.421511 -140.446945) (xy 51.4719 -140.418699)
			(xy 51.525975 -140.39838) (xy 51.554126 -140.391896) (xy 51.565048 -140.389356) (xy 51.582574 -140.376656)
			(xy 51.630834 -140.289788) (xy 51.632358 -140.268198) (xy 51.628548 -140.257784) (xy 51.617872 -140.226273)
			(xy 51.606383 -140.160746) (xy 51.605688 -140.127482) (xy 51.606174 -140.100231) (xy 51.61393 -140.046283)
			(xy 51.629285 -139.993988) (xy 51.651927 -139.944411) (xy 51.681393 -139.898561) (xy 51.717084 -139.85737)
			(xy 51.758275 -139.821679) (xy 51.804125 -139.792213) (xy 51.853702 -139.769571) (xy 51.905997 -139.754216)
			(xy 51.959945 -139.74646) (xy 52.014447 -139.74646) (xy 52.068395 -139.754216) (xy 52.12069 -139.769571)
			(xy 52.170267 -139.792213) (xy 52.216117 -139.821679) (xy 52.257308 -139.85737) (xy 52.292999 -139.898561)
			(xy 52.322465 -139.944411) (xy 52.345107 -139.993988) (xy 52.360462 -140.046283) (xy 52.368218 -140.100231)
			(xy 52.368704 -140.127482) (xy 52.368182 -140.156369) (xy 52.359495 -140.213485) (xy 52.342286 -140.268635)
			(xy 52.31695 -140.320556) (xy 52.284067 -140.368058) (xy 52.244391 -140.410053) (xy 52.198831 -140.445578)
			(xy 52.148431 -140.473819) (xy 52.094346 -140.494129) (xy 52.06619 -140.500608) (xy 52.055268 -140.503148)
			(xy 52.037742 -140.515848) (xy 51.989482 -140.602716) (xy 51.987958 -140.624306) (xy 51.991768 -140.63472)
			(xy 52.002442 -140.666232) (xy 52.013933 -140.731758) (xy 52.014628 -140.765022) (xy 52.014142 -140.792273)
			(xy 52.006386 -140.846221) (xy 51.991031 -140.898516) (xy 51.968389 -140.948093) (xy 51.938923 -140.993943)
			(xy 51.903232 -141.035134) (xy 51.862041 -141.070825) (xy 51.816191 -141.100291) (xy 51.766614 -141.122933)
			(xy 51.714319 -141.138288) (xy 51.660371 -141.146044) (xy 51.605869 -141.146044) (xy 51.551921 -141.138288)
			(xy 51.499626 -141.122933) (xy 51.450049 -141.100291) (xy 51.404199 -141.070825) (xy 51.363008 -141.035134)
			(xy 51.327317 -140.993943) (xy 51.297851 -140.948093) (xy 51.275209 -140.898516) (xy 51.259854 -140.846221)
			(xy 51.252098 -140.792273) (xy 51.251612 -140.765022) (xy 47.338607 -140.765022) (xy 47.28961 -140.787399)
			(xy 47.237315 -140.802754) (xy 47.183367 -140.81051) (xy 47.128865 -140.81051) (xy 47.074917 -140.802754)
			(xy 47.022622 -140.787399) (xy 46.973045 -140.764757) (xy 46.927195 -140.735291) (xy 46.886004 -140.6996)
			(xy 46.850313 -140.658409) (xy 46.820847 -140.612559) (xy 46.798205 -140.562982) (xy 46.78285 -140.510687)
			(xy 46.775094 -140.456739) (xy 46.774608 -140.429488) (xy 46.775086 -140.402366) (xy 46.782774 -140.348668)
			(xy 46.797992 -140.296602) (xy 46.820434 -140.247218) (xy 46.849646 -140.201511) (xy 46.885041 -140.160404)
			(xy 46.905164 -140.142214) (xy 46.913038 -140.135102) (xy 46.922182 -140.11656) (xy 46.926246 -140.022072)
			(xy 46.919134 -140.002768) (xy 46.911768 -139.995148) (xy 46.892135 -139.973917) (xy 46.858857 -139.926629)
			(xy 46.833103 -139.874857) (xy 46.815463 -139.81979) (xy 46.806343 -139.76269) (xy 46.805596 -139.733782)
			(xy 46.805596 -139.723622) (xy 46.797976 -139.705334) (xy 46.73981 -139.647676) (xy 46.7324 -139.640993)
			(xy 46.713964 -139.633411) (xy 46.703996 -139.632944) (xy 39.228522 -139.632944) (xy 39.218459 -139.633383)
			(xy 39.199879 -139.641122) (xy 39.192454 -139.64793) (xy 37.810948 -141.029436) (xy 39.591232 -141.029436)
			(xy 39.595303 -140.973814) (xy 39.607429 -140.919377) (xy 39.627352 -140.867286) (xy 39.654648 -140.818651)
			(xy 39.688734 -140.774508) (xy 39.728883 -140.735799) (xy 39.774241 -140.703348) (xy 39.823841 -140.677847)
			(xy 39.876625 -140.65984) (xy 39.931468 -140.64971) (xy 39.987202 -140.647673) (xy 40.042639 -140.653773)
			(xy 40.096596 -140.667879) (xy 40.147925 -140.689691) (xy 40.195531 -140.718745) (xy 40.238399 -140.75442)
			(xy 40.275616 -140.795957) (xy 40.306389 -140.84247) (xy 40.330061 -140.892967) (xy 40.346129 -140.946374)
			(xy 40.354249 -141.00155) (xy 40.354758 -141.029436) (xy 40.354249 -141.057322) (xy 40.346129 -141.112498)
			(xy 40.330061 -141.165905) (xy 40.306389 -141.216402) (xy 40.275616 -141.262915) (xy 40.238399 -141.304452)
			(xy 40.195531 -141.340127) (xy 40.147925 -141.369181) (xy 40.096596 -141.390993) (xy 40.042639 -141.405099)
			(xy 39.987202 -141.411199) (xy 39.931468 -141.409162) (xy 39.876625 -141.399032) (xy 39.823841 -141.381025)
			(xy 39.774241 -141.355524) (xy 39.728883 -141.323073) (xy 39.688734 -141.284364) (xy 39.654648 -141.240221)
			(xy 39.627352 -141.191586) (xy 39.607429 -141.139495) (xy 39.595303 -141.085058) (xy 39.591232 -141.029436)
			(xy 37.810948 -141.029436) (xy 36.362894 -142.47749) (xy 36.356047 -142.484888) (xy 36.348309 -142.503486)
			(xy 36.347908 -142.513558) (xy 36.347908 -142.748762) (xy 39.518842 -142.748762) (xy 39.522913 -142.69314)
			(xy 39.535039 -142.638703) (xy 39.554962 -142.586612) (xy 39.582258 -142.537977) (xy 39.616344 -142.493834)
			(xy 39.656493 -142.455125) (xy 39.701851 -142.422674) (xy 39.751451 -142.397173) (xy 39.804235 -142.379166)
			(xy 39.859078 -142.369036) (xy 39.914812 -142.366999) (xy 39.970249 -142.373099) (xy 40.024206 -142.387205)
			(xy 40.075535 -142.409017) (xy 40.123141 -142.438071) (xy 40.166009 -142.473746) (xy 40.203226 -142.515283)
			(xy 40.233999 -142.561796) (xy 40.257671 -142.612293) (xy 40.273739 -142.6657) (xy 40.281859 -142.720876)
			(xy 40.282368 -142.748762) (xy 40.281859 -142.776648) (xy 40.273739 -142.831824) (xy 40.265105 -142.860522)
			(xy 46.633638 -142.860522) (xy 46.6342 -142.831841) (xy 46.642807 -142.775129) (xy 46.659801 -142.720342)
			(xy 46.684798 -142.668714) (xy 46.717238 -142.621405) (xy 46.756389 -142.579482) (xy 46.80137 -142.543887)
			(xy 46.851171 -142.51542) (xy 46.904668 -142.494724) (xy 46.96066 -142.482263) (xy 46.989238 -142.479776)
			(xy 47.003735 -142.478281) (xy 47.031037 -142.468119) (xy 47.054363 -142.450666) (xy 47.071817 -142.427341)
			(xy 47.08198 -142.400039) (xy 47.083472 -142.385542) (xy 47.085894 -142.356951) (xy 47.098326 -142.300935)
			(xy 47.119005 -142.247412) (xy 47.147466 -142.197589) (xy 47.183066 -142.152589) (xy 47.225002 -142.113427)
			(xy 47.27233 -142.080986) (xy 47.323982 -142.055997) (xy 47.378794 -142.039024) (xy 47.435528 -142.03045)
			(xy 47.464218 -142.029942) (xy 47.491474 -142.030338) (xy 47.54543 -142.038099) (xy 47.597732 -142.05346)
			(xy 47.647315 -142.076108) (xy 47.693171 -142.105583) (xy 47.734365 -142.141283) (xy 47.770058 -142.182484)
			(xy 47.799525 -142.228344) (xy 47.822164 -142.277932) (xy 47.837515 -142.330237) (xy 47.845267 -142.384194)
			(xy 47.845726 -142.41145) (xy 47.845264 -142.440134) (xy 47.836645 -142.496852) (xy 47.81964 -142.551643)
			(xy 47.795887 -142.60068) (xy 51.605688 -142.60068) (xy 51.606137 -142.573274) (xy 51.61399 -142.519029)
			(xy 51.629529 -142.466466) (xy 51.652436 -142.416671) (xy 51.682238 -142.37067) (xy 51.699922 -142.349728)
			(xy 51.706018 -142.342616) (xy 51.712368 -142.325598) (xy 51.712368 -142.24) (xy 51.706018 -142.222982)
			(xy 51.699922 -142.21587) (xy 51.682243 -142.194925) (xy 51.652449 -142.148922) (xy 51.629549 -142.099127)
			(xy 51.614014 -142.046566) (xy 51.606164 -141.992322) (xy 51.605688 -141.964918) (xy 51.606174 -141.937667)
			(xy 51.61393 -141.883719) (xy 51.629285 -141.831424) (xy 51.651927 -141.781847) (xy 51.681393 -141.735997)
			(xy 51.717084 -141.694806) (xy 51.758275 -141.659115) (xy 51.804125 -141.629649) (xy 51.853702 -141.607007)
			(xy 51.905997 -141.591652) (xy 51.959945 -141.583896) (xy 52.014447 -141.583896) (xy 52.068395 -141.591652)
			(xy 52.12069 -141.607007) (xy 52.170267 -141.629649) (xy 52.216117 -141.659115) (xy 52.257308 -141.694806)
			(xy 52.292999 -141.735997) (xy 52.322465 -141.781847) (xy 52.345107 -141.831424) (xy 52.360462 -141.883719)
			(xy 52.368218 -141.937667) (xy 52.368704 -141.964918) (xy 52.368256 -141.992324) (xy 52.360403 -142.04657)
			(xy 52.344863 -142.099132) (xy 52.321956 -142.148927) (xy 52.292154 -142.194928) (xy 52.27447 -142.21587)
			(xy 52.268374 -142.222982) (xy 52.262024 -142.24) (xy 52.262024 -142.325598) (xy 52.268374 -142.342616)
			(xy 52.27447 -142.349728) (xy 52.289045 -142.367) (xy 53.582822 -142.367) (xy 53.586893 -142.311378)
			(xy 53.599019 -142.256941) (xy 53.618942 -142.20485) (xy 53.646238 -142.156215) (xy 53.680324 -142.112072)
			(xy 53.720473 -142.073363) (xy 53.765831 -142.040912) (xy 53.815431 -142.015411) (xy 53.868215 -141.997404)
			(xy 53.923058 -141.987274) (xy 53.978792 -141.985237) (xy 54.034229 -141.991337) (xy 54.088186 -142.005443)
			(xy 54.139515 -142.027255) (xy 54.187121 -142.056309) (xy 54.229989 -142.091984) (xy 54.267206 -142.133521)
			(xy 54.297979 -142.180034) (xy 54.321651 -142.230531) (xy 54.337719 -142.283938) (xy 54.345839 -142.339114)
			(xy 54.346348 -142.367) (xy 54.345839 -142.394886) (xy 54.337719 -142.450062) (xy 54.321651 -142.503469)
			(xy 54.297979 -142.553966) (xy 54.267206 -142.600479) (xy 54.229989 -142.642016) (xy 54.187121 -142.677691)
			(xy 54.139515 -142.706745) (xy 54.088186 -142.728557) (xy 54.034229 -142.742663) (xy 53.978792 -142.748763)
			(xy 53.923058 -142.746726) (xy 53.868215 -142.736596) (xy 53.815431 -142.718589) (xy 53.765831 -142.693088)
			(xy 53.720473 -142.660637) (xy 53.680324 -142.621928) (xy 53.646238 -142.577785) (xy 53.618942 -142.52915)
			(xy 53.599019 -142.477059) (xy 53.586893 -142.422622) (xy 53.582822 -142.367) (xy 52.289045 -142.367)
			(xy 52.292146 -142.370675) (xy 52.321941 -142.416677) (xy 52.344842 -142.466472) (xy 52.360378 -142.519033)
			(xy 52.368228 -142.573276) (xy 52.368704 -142.60068) (xy 52.368218 -142.627931) (xy 52.360462 -142.681879)
			(xy 52.345107 -142.734174) (xy 52.322465 -142.783751) (xy 52.292999 -142.829601) (xy 52.257308 -142.870792)
			(xy 52.216117 -142.906483) (xy 52.170267 -142.935949) (xy 52.12069 -142.958591) (xy 52.068395 -142.973946)
			(xy 52.014447 -142.981702) (xy 51.959945 -142.981702) (xy 51.905997 -142.973946) (xy 51.853702 -142.958591)
			(xy 51.804125 -142.935949) (xy 51.758275 -142.906483) (xy 51.717084 -142.870792) (xy 51.681393 -142.829601)
			(xy 51.651927 -142.783751) (xy 51.629285 -142.734174) (xy 51.61393 -142.681879) (xy 51.606174 -142.627931)
			(xy 51.605688 -142.60068) (xy 47.795887 -142.60068) (xy 47.794631 -142.603274) (xy 47.76218 -142.650583)
			(xy 47.723018 -142.692506) (xy 47.678025 -142.7281) (xy 47.628215 -142.756563) (xy 47.574708 -142.777256)
			(xy 47.518707 -142.789712) (xy 47.490126 -142.792196) (xy 47.475625 -142.793677) (xy 47.448315 -142.803832)
			(xy 47.424983 -142.821286) (xy 47.40753 -142.844618) (xy 47.397376 -142.871929) (xy 47.395892 -142.88643)
			(xy 47.393383 -142.915011) (xy 47.380958 -142.971021) (xy 47.360287 -143.02454) (xy 47.331835 -143.07436)
			(xy 47.296245 -143.119358) (xy 47.254319 -143.15852) (xy 47.207001 -143.190964) (xy 47.15536 -143.215956)
			(xy 47.100558 -143.232935) (xy 47.043832 -143.241517) (xy 47.015146 -143.24203) (xy 46.987895 -143.241502)
			(xy 46.933948 -143.233752) (xy 46.881653 -143.218403) (xy 46.832074 -143.195767) (xy 46.786222 -143.166306)
			(xy 46.745029 -143.130619) (xy 46.709335 -143.089433) (xy 46.679865 -143.043586) (xy 46.657221 -142.994011)
			(xy 46.641863 -142.941719) (xy 46.634103 -142.887773) (xy 46.633638 -142.860522) (xy 40.265105 -142.860522)
			(xy 40.257671 -142.885231) (xy 40.233999 -142.935728) (xy 40.203226 -142.982241) (xy 40.166009 -143.023778)
			(xy 40.123141 -143.059453) (xy 40.075535 -143.088507) (xy 40.024206 -143.110319) (xy 39.970249 -143.124425)
			(xy 39.914812 -143.130525) (xy 39.859078 -143.128488) (xy 39.804235 -143.118358) (xy 39.751451 -143.100351)
			(xy 39.701851 -143.07485) (xy 39.656493 -143.042399) (xy 39.616344 -143.00369) (xy 39.582258 -142.959547)
			(xy 39.554962 -142.910912) (xy 39.535039 -142.858821) (xy 39.522913 -142.804384) (xy 39.518842 -142.748762)
			(xy 36.347908 -142.748762) (xy 36.347908 -151.045672) (xy 36.603178 -151.045672) (xy 36.603675 -151.019372)
			(xy 36.610917 -150.967272) (xy 36.625248 -150.916661) (xy 36.646394 -150.868498) (xy 36.673955 -150.823696)
			(xy 36.707409 -150.783104) (xy 36.746122 -150.747492) (xy 36.789359 -150.717536) (xy 36.836301 -150.693802)
			(xy 36.886058 -150.676741) (xy 36.911788 -150.671276) (xy 36.922202 -150.669244) (xy 36.938966 -150.65756)
			(xy 36.99002 -150.578058) (xy 36.993576 -150.557738) (xy 36.991036 -150.547578) (xy 36.986059 -150.525497)
			(xy 36.980707 -150.480549) (xy 36.980368 -150.457916) (xy 36.980806 -150.430926) (xy 36.988414 -150.377484)
			(xy 37.00348 -150.325649) (xy 37.025703 -150.276455) (xy 37.054639 -150.230885) (xy 37.08971 -150.18985)
			(xy 37.109654 -150.171658) (xy 37.117782 -150.164546) (xy 37.126672 -150.145496) (xy 37.128704 -150.048976)
			(xy 37.12083 -150.029672) (xy 37.112956 -150.022306) (xy 37.094771 -150.004268) (xy 37.062931 -149.964144)
			(xy 37.036746 -149.92012) (xy 37.016687 -149.872989) (xy 37.003114 -149.823598) (xy 36.99627 -149.772835)
			(xy 36.995862 -149.747224) (xy 36.996348 -149.719973) (xy 37.004104 -149.666025) (xy 37.019459 -149.61373)
			(xy 37.042101 -149.564153) (xy 37.071567 -149.518303) (xy 37.107258 -149.477112) (xy 37.148449 -149.441421)
			(xy 37.194299 -149.411955) (xy 37.243876 -149.389313) (xy 37.296171 -149.373958) (xy 37.350119 -149.366202)
			(xy 37.404621 -149.366202) (xy 37.458569 -149.373958) (xy 37.510864 -149.389313) (xy 37.560441 -149.411955)
			(xy 37.606291 -149.441421) (xy 37.647482 -149.477112) (xy 37.683173 -149.518303) (xy 37.712639 -149.564153)
			(xy 37.735281 -149.61373) (xy 37.750636 -149.666025) (xy 37.758392 -149.719973) (xy 37.758878 -149.747224)
			(xy 37.758384 -149.774212) (xy 37.750785 -149.827651) (xy 37.735729 -149.879485) (xy 37.713517 -149.928678)
			(xy 37.684592 -149.97425) (xy 37.649531 -150.015288) (xy 37.629592 -150.033482) (xy 37.621464 -150.040594)
			(xy 37.612574 -150.059644) (xy 37.610542 -150.156164) (xy 37.618416 -150.175468) (xy 37.62629 -150.182834)
			(xy 37.644455 -150.200892) (xy 37.676295 -150.241013) (xy 37.702481 -150.285032) (xy 37.722544 -150.332159)
			(xy 37.736122 -150.381546) (xy 37.742972 -150.432306) (xy 37.743384 -150.457916) (xy 37.742907 -150.484217)
			(xy 37.735665 -150.536319) (xy 37.721334 -150.586933) (xy 37.700187 -150.635097) (xy 37.672624 -150.679901)
			(xy 37.639167 -150.720493) (xy 37.600452 -150.756104) (xy 37.557212 -150.78606) (xy 37.510266 -150.809792)
			(xy 37.460506 -150.826849) (xy 37.434774 -150.832312) (xy 37.42436 -150.834344) (xy 37.407596 -150.846028)
			(xy 37.356542 -150.92553) (xy 37.352986 -150.94585) (xy 37.355526 -150.95601) (xy 37.356542 -150.960328)
			(xy 37.358828 -150.970234) (xy 37.370512 -150.986744) (xy 37.448998 -151.035766) (xy 37.46881 -151.039068)
			(xy 37.478716 -151.036528) (xy 37.50013 -151.03187) (xy 37.543671 -151.026901) (xy 37.565584 -151.026622)
			(xy 37.59284 -151.027024) (xy 37.646797 -151.03478) (xy 37.699101 -151.050135) (xy 37.748687 -151.072779)
			(xy 37.794546 -151.102249) (xy 37.835743 -151.137945) (xy 37.871442 -151.179142) (xy 37.900913 -151.224999)
			(xy 37.923559 -151.274584) (xy 37.938917 -151.326888) (xy 37.946675 -151.380844) (xy 37.946675 -151.435356)
			(xy 37.938917 -151.489312) (xy 37.923559 -151.541616) (xy 37.900913 -151.591201) (xy 37.871442 -151.637058)
			(xy 37.835743 -151.678255) (xy 37.794546 -151.713951) (xy 37.748687 -151.743421) (xy 37.699101 -151.766065)
			(xy 37.646797 -151.78142) (xy 37.59284 -151.789176) (xy 37.565584 -151.789638) (xy 37.547241 -151.789411)
			(xy 37.510728 -151.785844) (xy 37.492686 -151.782526) (xy 37.48278 -151.780748) (xy 37.463476 -151.784558)
			(xy 37.387022 -151.835612) (xy 37.375846 -151.851868) (xy 37.373814 -151.862028) (xy 37.370766 -151.875998)
			(xy 37.41547 -151.916384) (xy 37.422047 -151.921864) (xy 37.437821 -151.92849) (xy 37.454897 -151.929554)
			(xy 37.463222 -151.92756) (xy 37.488126 -151.921124) (xy 37.539103 -151.914245) (xy 37.564822 -151.913844)
			(xy 37.592074 -151.914379) (xy 37.646022 -151.922139) (xy 37.698316 -151.937497) (xy 37.747893 -151.960142)
			(xy 37.793742 -151.989612) (xy 37.834931 -152.025307) (xy 37.87062 -152.0665) (xy 37.900083 -152.112353)
			(xy 37.922721 -152.161933) (xy 37.938072 -152.21423) (xy 37.945825 -152.268179) (xy 37.945821 -152.322682)
			(xy 37.938059 -152.37663) (xy 37.9227 -152.428925) (xy 37.900054 -152.478501) (xy 37.870583 -152.524349)
			(xy 37.834887 -152.565537) (xy 37.793693 -152.601225) (xy 37.747839 -152.630687) (xy 37.698259 -152.653324)
			(xy 37.645962 -152.668674) (xy 37.592012 -152.676426) (xy 37.537509 -152.67642) (xy 37.483561 -152.668658)
			(xy 37.431267 -152.653297) (xy 37.381692 -152.63065) (xy 37.335844 -152.601178) (xy 37.294657 -152.565481)
			(xy 37.25897 -152.524286) (xy 37.229508 -152.478431) (xy 37.206873 -152.428851) (xy 37.191524 -152.376553)
			(xy 37.183774 -152.322604) (xy 37.183314 -152.295352) (xy 37.18433 -152.268428) (xy 37.185092 -152.256744)
			(xy 37.176456 -152.235154) (xy 37.099494 -152.165558) (xy 37.077142 -152.159208) (xy 37.065458 -152.16124)
			(xy 37.049268 -152.163874) (xy 37.016582 -152.16667) (xy 37.00018 -152.166828) (xy 36.972929 -152.166341)
			(xy 36.918983 -152.158582) (xy 36.866689 -152.143226) (xy 36.817113 -152.120583) (xy 36.771264 -152.091117)
			(xy 36.730074 -152.055426) (xy 36.694383 -152.014236) (xy 36.664917 -151.968387) (xy 36.642274 -151.918811)
			(xy 36.626918 -151.866517) (xy 36.619159 -151.812571) (xy 36.618672 -151.78532) (xy 36.619149 -151.75824)
			(xy 36.626802 -151.704624) (xy 36.641956 -151.652627) (xy 36.664307 -151.603294) (xy 36.693407 -151.557616)
			(xy 36.728672 -151.51651) (xy 36.74872 -151.4983) (xy 36.757356 -151.490934) (xy 36.766246 -151.470614)
			(xy 36.764214 -151.369776) (xy 36.754308 -151.349964) (xy 36.745418 -151.342852) (xy 36.723648 -151.324604)
			(xy 36.685177 -151.282813) (xy 36.653326 -151.235782) (xy 36.628798 -151.184549) (xy 36.612135 -151.130246)
			(xy 36.603705 -151.074073) (xy 36.603178 -151.045672) (xy 36.347908 -151.045672) (xy 36.347908 -154.327352)
			(xy 37.182804 -154.327352) (xy 37.186875 -154.27173) (xy 37.199001 -154.217293) (xy 37.218924 -154.165202)
			(xy 37.24622 -154.116567) (xy 37.280306 -154.072424) (xy 37.320455 -154.033715) (xy 37.365813 -154.001264)
			(xy 37.415413 -153.975763) (xy 37.468197 -153.957756) (xy 37.52304 -153.947626) (xy 37.578774 -153.945589)
			(xy 37.634211 -153.951689) (xy 37.688168 -153.965795) (xy 37.739497 -153.987607) (xy 37.787103 -154.016661)
			(xy 37.829971 -154.052336) (xy 37.867188 -154.093873) (xy 37.897961 -154.140386) (xy 37.921633 -154.190883)
			(xy 37.937701 -154.24429) (xy 37.945821 -154.299466) (xy 37.94633 -154.327352) (xy 37.945821 -154.355238)
			(xy 37.937701 -154.410414) (xy 37.921633 -154.463821) (xy 37.897961 -154.514318) (xy 37.867188 -154.560831)
			(xy 37.829971 -154.602368) (xy 37.787103 -154.638043) (xy 37.739497 -154.667097) (xy 37.688168 -154.688909)
			(xy 37.634211 -154.703015) (xy 37.578774 -154.709115) (xy 37.52304 -154.707078) (xy 37.468197 -154.696948)
			(xy 37.415413 -154.678941) (xy 37.365813 -154.65344) (xy 37.320455 -154.620989) (xy 37.280306 -154.58228)
			(xy 37.24622 -154.538137) (xy 37.218924 -154.489502) (xy 37.199001 -154.437411) (xy 37.186875 -154.382974)
			(xy 37.182804 -154.327352) (xy 36.347908 -154.327352) (xy 36.347908 -156.3624) (xy 37.190932 -156.3624)
			(xy 37.195003 -156.306778) (xy 37.207129 -156.252341) (xy 37.227052 -156.20025) (xy 37.254348 -156.151615)
			(xy 37.288434 -156.107472) (xy 37.328583 -156.068763) (xy 37.373941 -156.036312) (xy 37.423541 -156.010811)
			(xy 37.476325 -155.992804) (xy 37.531168 -155.982674) (xy 37.586902 -155.980637) (xy 37.642339 -155.986737)
			(xy 37.696296 -156.000843) (xy 37.747625 -156.022655) (xy 37.795231 -156.051709) (xy 37.80231 -156.0576)
			(xy 48.163732 -156.0576) (xy 48.167803 -156.001978) (xy 48.179929 -155.947541) (xy 48.199852 -155.89545)
			(xy 48.227148 -155.846815) (xy 48.261234 -155.802672) (xy 48.301383 -155.763963) (xy 48.346741 -155.731512)
			(xy 48.396341 -155.706011) (xy 48.449125 -155.688004) (xy 48.503968 -155.677874) (xy 48.559702 -155.675837)
			(xy 48.615139 -155.681937) (xy 48.669096 -155.696043) (xy 48.720425 -155.717855) (xy 48.768031 -155.746909)
			(xy 48.810899 -155.782584) (xy 48.848116 -155.824121) (xy 48.878889 -155.870634) (xy 48.902561 -155.921131)
			(xy 48.918629 -155.974538) (xy 48.926749 -156.029714) (xy 48.927258 -156.0576) (xy 48.926749 -156.085486)
			(xy 48.918629 -156.140662) (xy 48.902561 -156.194069) (xy 48.878889 -156.244566) (xy 48.848116 -156.291079)
			(xy 48.810899 -156.332616) (xy 48.768031 -156.368291) (xy 48.720425 -156.397345) (xy 48.669096 -156.419157)
			(xy 48.615139 -156.433263) (xy 48.559702 -156.439363) (xy 48.503968 -156.437326) (xy 48.449125 -156.427196)
			(xy 48.396341 -156.409189) (xy 48.346741 -156.383688) (xy 48.301383 -156.351237) (xy 48.261234 -156.312528)
			(xy 48.227148 -156.268385) (xy 48.199852 -156.21975) (xy 48.179929 -156.167659) (xy 48.167803 -156.113222)
			(xy 48.163732 -156.0576) (xy 37.80231 -156.0576) (xy 37.838099 -156.087384) (xy 37.875316 -156.128921)
			(xy 37.906089 -156.175434) (xy 37.929761 -156.225931) (xy 37.945829 -156.279338) (xy 37.953949 -156.334514)
			(xy 37.954458 -156.3624) (xy 37.953949 -156.390286) (xy 37.945829 -156.445462) (xy 37.929761 -156.498869)
			(xy 37.906089 -156.549366) (xy 37.875316 -156.595879) (xy 37.838099 -156.637416) (xy 37.795231 -156.673091)
			(xy 37.747625 -156.702145) (xy 37.696296 -156.723957) (xy 37.642339 -156.738063) (xy 37.586902 -156.744163)
			(xy 37.531168 -156.742126) (xy 37.476325 -156.731996) (xy 37.423541 -156.713989) (xy 37.373941 -156.688488)
			(xy 37.328583 -156.656037) (xy 37.288434 -156.617328) (xy 37.254348 -156.573185) (xy 37.227052 -156.52455)
			(xy 37.207129 -156.472459) (xy 37.195003 -156.418022) (xy 37.190932 -156.3624) (xy 36.347908 -156.3624)
			(xy 36.347908 -158.275274) (xy 36.348345 -158.285338) (xy 36.356079 -158.303922) (xy 36.362894 -158.311342)
			(xy 37.028374 -158.976822) (xy 37.035773 -158.983665) (xy 37.054372 -158.991385) (xy 37.064442 -158.991808)
			(xy 48.344074 -158.991808) (xy 48.354138 -158.991372) (xy 48.372724 -158.983639) (xy 48.380142 -158.976822)
			(xy 49.586388 -157.770576) (xy 49.593232 -157.763177) (xy 49.60096 -157.744579) (xy 49.601374 -157.734508)
			(xy 49.601374 -155.419552) (xy 49.600942 -155.409486) (xy 49.593212 -155.390897) (xy 49.586388 -155.383484)
			(xy 48.80483 -154.601926) (xy 48.797429 -154.595088) (xy 48.77883 -154.587375) (xy 48.768762 -154.58694)
			(xy 40.426132 -154.58694) (xy 40.416069 -154.586503) (xy 40.397488 -154.578764) (xy 40.390064 -154.571954)
			(xy 39.06774 -153.24963) (xy 39.0609 -153.24223) (xy 39.053185 -153.223631) (xy 39.052754 -153.213562)
			(xy 39.052754 -145.875248) (xy 39.053188 -145.865183) (xy 39.060922 -145.846598) (xy 39.06774 -145.83918)
			(xy 41.433242 -143.473678) (xy 41.440639 -143.46683) (xy 41.459238 -143.459098) (xy 41.46931 -143.458692)
			(xy 51.370484 -143.458692) (xy 51.379601 -143.458362) (xy 51.396699 -143.452036) (xy 51.410465 -143.440085)
			(xy 51.415188 -143.432276) (xy 51.428675 -143.4086) (xy 51.461335 -143.364986) (xy 51.499869 -143.326463)
			(xy 51.543492 -143.293815) (xy 51.591316 -143.267707) (xy 51.642369 -143.248669) (xy 51.695612 -143.237088)
			(xy 51.74996 -143.233202) (xy 51.804308 -143.237088) (xy 51.857551 -143.248669) (xy 51.908604 -143.267707)
			(xy 51.956428 -143.293815) (xy 52.000051 -143.326463) (xy 52.038585 -143.364986) (xy 52.071245 -143.4086)
			(xy 52.084732 -143.432276) (xy 52.089453 -143.440077) (xy 52.10325 -143.451979) (xy 52.120326 -143.458338)
			(xy 52.129436 -143.458692) (xy 52.748942 -143.458692) (xy 52.759009 -143.459122) (xy 52.777603 -143.466847)
			(xy 52.78501 -143.473678) (xy 53.583332 -144.272) (xy 56.386982 -144.272) (xy 56.391053 -144.216378)
			(xy 56.403179 -144.161941) (xy 56.423102 -144.10985) (xy 56.450398 -144.061215) (xy 56.484484 -144.017072)
			(xy 56.524633 -143.978363) (xy 56.569991 -143.945912) (xy 56.619591 -143.920411) (xy 56.672375 -143.902404)
			(xy 56.727218 -143.892274) (xy 56.782952 -143.890237) (xy 56.838389 -143.896337) (xy 56.892346 -143.910443)
			(xy 56.943675 -143.932255) (xy 56.991281 -143.961309) (xy 57.034149 -143.996984) (xy 57.071366 -144.038521)
			(xy 57.102139 -144.085034) (xy 57.125811 -144.135531) (xy 57.141879 -144.188938) (xy 57.149999 -144.244114)
			(xy 57.150508 -144.272) (xy 57.149999 -144.299886) (xy 57.141879 -144.355062) (xy 57.125811 -144.408469)
			(xy 57.102139 -144.458966) (xy 57.071366 -144.505479) (xy 57.034149 -144.547016) (xy 56.991281 -144.582691)
			(xy 56.943675 -144.611745) (xy 56.892346 -144.633557) (xy 56.838389 -144.647663) (xy 56.782952 -144.653763)
			(xy 56.727218 -144.651726) (xy 56.672375 -144.641596) (xy 56.619591 -144.623589) (xy 56.569991 -144.598088)
			(xy 56.524633 -144.565637) (xy 56.484484 -144.526928) (xy 56.450398 -144.482785) (xy 56.423102 -144.43415)
			(xy 56.403179 -144.382059) (xy 56.391053 -144.327622) (xy 56.386982 -144.272) (xy 53.583332 -144.272)
			(xy 60.482988 -151.171656) (xy 60.489827 -151.179057) (xy 60.497543 -151.197655) (xy 60.497974 -151.207724)
			(xy 60.497974 -152.274524) (xy 62.441074 -152.274524) (xy 62.44156 -152.247273) (xy 62.449316 -152.193325)
			(xy 62.464671 -152.14103) (xy 62.487313 -152.091453) (xy 62.516779 -152.045603) (xy 62.55247 -152.004412)
			(xy 62.593661 -151.968721) (xy 62.639511 -151.939255) (xy 62.689088 -151.916613) (xy 62.741383 -151.901258)
			(xy 62.795331 -151.893502) (xy 62.849833 -151.893502) (xy 62.903781 -151.901258) (xy 62.956076 -151.916613)
			(xy 63.005653 -151.939255) (xy 63.051503 -151.968721) (xy 63.092694 -152.004412) (xy 63.128385 -152.045603)
			(xy 63.157851 -152.091453) (xy 63.180493 -152.14103) (xy 63.195848 -152.193325) (xy 63.203604 -152.247273)
			(xy 63.20409 -152.274524) (xy 63.203482 -152.304133) (xy 63.194323 -152.362639) (xy 63.176245 -152.41903)
			(xy 63.149679 -152.471955) (xy 63.115264 -152.520146) (xy 63.073823 -152.562448) (xy 63.05042 -152.580594)
			(xy 63.039161 -152.589653) (xy 63.021796 -152.612735) (xy 63.011585 -152.639753) (xy 63.009343 -152.66855)
			(xy 63.015251 -152.696824) (xy 63.028836 -152.722314) (xy 63.049012 -152.742983) (xy 63.061342 -152.75052)
			(xy 63.086206 -152.765154) (xy 63.131631 -152.80072) (xy 63.171187 -152.842717) (xy 63.203973 -152.890188)
			(xy 63.229243 -152.942051) (xy 63.246421 -152.997127) (xy 63.255117 -153.05416) (xy 63.255652 -153.083006)
			(xy 63.255166 -153.110257) (xy 63.24741 -153.164205) (xy 63.232055 -153.2165) (xy 63.209413 -153.266077)
			(xy 63.179947 -153.311927) (xy 63.144256 -153.353118) (xy 63.103065 -153.388809) (xy 63.057215 -153.418275)
			(xy 63.007638 -153.440917) (xy 62.955343 -153.456272) (xy 62.901395 -153.464028) (xy 62.846893 -153.464028)
			(xy 62.792945 -153.456272) (xy 62.74065 -153.440917) (xy 62.691073 -153.418275) (xy 62.645223 -153.388809)
			(xy 62.604032 -153.353118) (xy 62.568341 -153.311927) (xy 62.538875 -153.266077) (xy 62.516233 -153.2165)
			(xy 62.500878 -153.164205) (xy 62.493122 -153.110257) (xy 62.492636 -153.083006) (xy 62.493183 -153.053395)
			(xy 62.502353 -152.994886) (xy 62.520443 -152.938493) (xy 62.54702 -152.885568) (xy 62.581446 -152.837379)
			(xy 62.622898 -152.79508) (xy 62.646306 -152.776936) (xy 62.65753 -152.767837) (xy 62.67489 -152.744764)
			(xy 62.6851 -152.717755) (xy 62.687345 -152.688968) (xy 62.681444 -152.660702) (xy 62.66787 -152.635217)
			(xy 62.647707 -152.614548) (xy 62.635384 -152.60701) (xy 62.610495 -152.592415) (xy 62.565068 -152.556844)
			(xy 62.525513 -152.514841) (xy 62.492728 -152.467364) (xy 62.467463 -152.415493) (xy 62.450291 -152.360411)
			(xy 62.441604 -152.303372) (xy 62.441074 -152.274524) (xy 60.497974 -152.274524) (xy 60.497974 -156.480002)
			(xy 61.07811 -156.480002) (xy 61.078596 -156.452751) (xy 61.086352 -156.398803) (xy 61.101707 -156.346508)
			(xy 61.124349 -156.296931) (xy 61.153815 -156.251081) (xy 61.189506 -156.20989) (xy 61.230697 -156.174199)
			(xy 61.276547 -156.144733) (xy 61.326124 -156.122091) (xy 61.378419 -156.106736) (xy 61.432367 -156.09898)
			(xy 61.486869 -156.09898) (xy 61.540817 -156.106736) (xy 61.593112 -156.122091) (xy 61.642689 -156.144733)
			(xy 61.688539 -156.174199) (xy 61.72973 -156.20989) (xy 61.765421 -156.251081) (xy 61.794887 -156.296931)
			(xy 61.817529 -156.346508) (xy 61.832884 -156.398803) (xy 61.84064 -156.452751) (xy 61.841126 -156.480002)
			(xy 61.840883 -156.500418) (xy 61.836554 -156.541019) (xy 61.83249 -156.561028) (xy 61.830458 -156.570426)
			(xy 61.833252 -156.589222) (xy 61.87821 -156.665422) (xy 61.893196 -156.677106) (xy 61.90234 -156.6799)
			(xy 61.92818 -156.688131) (xy 61.97739 -156.710921) (xy 62.022877 -156.740451) (xy 62.063721 -156.776127)
			(xy 62.099101 -156.817228) (xy 62.128303 -156.862926) (xy 62.150737 -156.9123) (xy 62.165952 -156.964353)
			(xy 62.17364 -157.018036) (xy 62.17412 -157.045152) (xy 62.426594 -157.045152) (xy 62.430665 -156.98953)
			(xy 62.442791 -156.935093) (xy 62.462714 -156.883002) (xy 62.49001 -156.834367) (xy 62.524096 -156.790224)
			(xy 62.564245 -156.751515) (xy 62.609603 -156.719064) (xy 62.659203 -156.693563) (xy 62.711987 -156.675556)
			(xy 62.76683 -156.665426) (xy 62.822564 -156.663389) (xy 62.878001 -156.669489) (xy 62.931958 -156.683595)
			(xy 62.983287 -156.705407) (xy 63.030893 -156.734461) (xy 63.073761 -156.770136) (xy 63.110978 -156.811673)
			(xy 63.141751 -156.858186) (xy 63.165423 -156.908683) (xy 63.181491 -156.96209) (xy 63.189611 -157.017266)
			(xy 63.19012 -157.045152) (xy 63.189611 -157.073038) (xy 63.181491 -157.128214) (xy 63.165423 -157.181621)
			(xy 63.141751 -157.232118) (xy 63.110978 -157.278631) (xy 63.073761 -157.320168) (xy 63.030893 -157.355843)
			(xy 62.983287 -157.384897) (xy 62.931958 -157.406709) (xy 62.878001 -157.420815) (xy 62.822564 -157.426915)
			(xy 62.76683 -157.424878) (xy 62.711987 -157.414748) (xy 62.659203 -157.396741) (xy 62.609603 -157.37124)
			(xy 62.564245 -157.338789) (xy 62.524096 -157.30008) (xy 62.49001 -157.255937) (xy 62.462714 -157.207302)
			(xy 62.442791 -157.155211) (xy 62.430665 -157.100774) (xy 62.426594 -157.045152) (xy 62.17412 -157.045152)
			(xy 62.173634 -157.072403) (xy 62.165878 -157.126351) (xy 62.150523 -157.178646) (xy 62.127881 -157.228223)
			(xy 62.098415 -157.274073) (xy 62.062724 -157.315264) (xy 62.021533 -157.350955) (xy 61.975683 -157.380421)
			(xy 61.926106 -157.403063) (xy 61.873811 -157.418418) (xy 61.819863 -157.426174) (xy 61.765361 -157.426174)
			(xy 61.711413 -157.418418) (xy 61.659118 -157.403063) (xy 61.609541 -157.380421) (xy 61.563691 -157.350955)
			(xy 61.5225 -157.315264) (xy 61.486809 -157.274073) (xy 61.457343 -157.228223) (xy 61.434701 -157.178646)
			(xy 61.419346 -157.126351) (xy 61.41159 -157.072403) (xy 61.411104 -157.045152) (xy 61.411355 -157.024736)
			(xy 61.415679 -156.984135) (xy 61.41974 -156.964126) (xy 61.421772 -156.954728) (xy 61.418978 -156.935932)
			(xy 61.37402 -156.859732) (xy 61.359034 -156.848048) (xy 61.34989 -156.845254) (xy 61.324042 -156.837045)
			(xy 61.274829 -156.814255) (xy 61.22934 -156.784724) (xy 61.188494 -156.749046) (xy 61.153114 -156.707942)
			(xy 61.123913 -156.66224) (xy 61.101481 -156.612863) (xy 61.08627 -156.560806) (xy 61.078587 -156.507119)
			(xy 61.07811 -156.480002) (xy 60.497974 -156.480002) (xy 60.497974 -159.595312) (xy 60.641228 -159.595312)
			(xy 60.645299 -159.53969) (xy 60.657425 -159.485253) (xy 60.677348 -159.433162) (xy 60.704644 -159.384527)
			(xy 60.73873 -159.340384) (xy 60.778879 -159.301675) (xy 60.824237 -159.269224) (xy 60.873837 -159.243723)
			(xy 60.926621 -159.225716) (xy 60.981464 -159.215586) (xy 61.037198 -159.213549) (xy 61.092635 -159.219649)
			(xy 61.146592 -159.233755) (xy 61.197921 -159.255567) (xy 61.245527 -159.284621) (xy 61.288395 -159.320296)
			(xy 61.325612 -159.361833) (xy 61.356385 -159.408346) (xy 61.380057 -159.458843) (xy 61.396125 -159.51225)
			(xy 61.404245 -159.567426) (xy 61.404754 -159.595312) (xy 61.404245 -159.623198) (xy 61.396125 -159.678374)
			(xy 61.380057 -159.731781) (xy 61.356385 -159.782278) (xy 61.325612 -159.828791) (xy 61.288395 -159.870328)
			(xy 61.245527 -159.906003) (xy 61.197921 -159.935057) (xy 61.146592 -159.956869) (xy 61.092635 -159.970975)
			(xy 61.037198 -159.977075) (xy 60.981464 -159.975038) (xy 60.926621 -159.964908) (xy 60.873837 -159.946901)
			(xy 60.824237 -159.9214) (xy 60.778879 -159.888949) (xy 60.73873 -159.85024) (xy 60.704644 -159.806097)
			(xy 60.677348 -159.757462) (xy 60.657425 -159.705371) (xy 60.645299 -159.650934) (xy 60.641228 -159.595312)
			(xy 60.497974 -159.595312) (xy 60.497974 -162.140953) (xy 60.854277 -162.140953) (xy 60.854277 -162.086447)
			(xy 60.862035 -162.032496) (xy 60.877392 -161.980198) (xy 60.900036 -161.930619) (xy 60.929505 -161.884767)
			(xy 60.965201 -161.843575) (xy 61.006395 -161.807884) (xy 61.05225 -161.778418) (xy 61.101832 -161.755779)
			(xy 61.154131 -161.740427) (xy 61.208083 -161.732675) (xy 61.235336 -161.732214) (xy 61.254894 -161.732722)
			(xy 61.268025 -161.733015) (xy 61.293727 -161.727638) (xy 61.317198 -161.715867) (xy 61.336879 -161.698485)
			(xy 61.351459 -161.676648) (xy 61.359971 -161.651808) (xy 61.36132 -161.638742) (xy 61.364017 -161.610324)
			(xy 61.376762 -161.554684) (xy 61.397651 -161.501562) (xy 61.426218 -161.452144) (xy 61.461827 -161.407532)
			(xy 61.503683 -161.36872) (xy 61.550853 -161.336576) (xy 61.602284 -161.311814) (xy 61.656829 -161.294989)
			(xy 61.713272 -161.286475) (xy 61.741812 -161.285936) (xy 61.769066 -161.286335) (xy 61.823018 -161.294094)
			(xy 61.875318 -161.309451) (xy 61.924899 -161.332096) (xy 61.970753 -161.361566) (xy 62.011947 -161.397262)
			(xy 62.047641 -161.438456) (xy 62.07711 -161.484311) (xy 62.099753 -161.533893) (xy 62.115109 -161.586193)
			(xy 62.122866 -161.640146) (xy 62.122866 -161.694654) (xy 62.115109 -161.748607) (xy 62.099753 -161.800907)
			(xy 62.07711 -161.850489) (xy 62.047641 -161.896344) (xy 62.011947 -161.937538) (xy 61.970753 -161.973234)
			(xy 61.924899 -162.002704) (xy 61.875318 -162.025349) (xy 61.823018 -162.040706) (xy 61.769066 -162.048465)
			(xy 61.741812 -162.048952) (xy 61.722254 -162.048444) (xy 61.709124 -162.048227) (xy 61.68343 -162.053591)
			(xy 61.659963 -162.065347) (xy 61.640283 -162.082714) (xy 61.639591 -162.08375) (xy 62.859918 -162.08375)
			(xy 62.863989 -162.028128) (xy 62.876115 -161.973691) (xy 62.896038 -161.9216) (xy 62.923334 -161.872965)
			(xy 62.95742 -161.828822) (xy 62.997569 -161.790113) (xy 63.042927 -161.757662) (xy 63.092527 -161.732161)
			(xy 63.145311 -161.714154) (xy 63.200154 -161.704024) (xy 63.255888 -161.701987) (xy 63.311325 -161.708087)
			(xy 63.365282 -161.722193) (xy 63.416611 -161.744005) (xy 63.464217 -161.773059) (xy 63.507085 -161.808734)
			(xy 63.544302 -161.850271) (xy 63.575075 -161.896784) (xy 63.598747 -161.947281) (xy 63.614815 -162.000688)
			(xy 63.622935 -162.055864) (xy 63.623444 -162.08375) (xy 63.622935 -162.111636) (xy 63.614815 -162.166812)
			(xy 63.598747 -162.220219) (xy 63.575075 -162.270716) (xy 63.544302 -162.317229) (xy 63.507085 -162.358766)
			(xy 63.464217 -162.394441) (xy 63.416611 -162.423495) (xy 63.365282 -162.445307) (xy 63.311325 -162.459413)
			(xy 63.255888 -162.465513) (xy 63.200154 -162.463476) (xy 63.145311 -162.453346) (xy 63.092527 -162.435339)
			(xy 63.042927 -162.409838) (xy 62.997569 -162.377387) (xy 62.95742 -162.338678) (xy 62.923334 -162.294535)
			(xy 62.896038 -162.2459) (xy 62.876115 -162.193809) (xy 62.863989 -162.139372) (xy 62.859918 -162.08375)
			(xy 61.639591 -162.08375) (xy 61.625699 -162.104537) (xy 61.617182 -162.129364) (xy 61.615828 -162.142424)
			(xy 61.613153 -162.170845) (xy 61.600411 -162.226489) (xy 61.579523 -162.279614) (xy 61.550954 -162.329036)
			(xy 61.515343 -162.37365) (xy 61.473483 -162.412462) (xy 61.42631 -162.444607) (xy 61.374874 -162.469366)
			(xy 61.320325 -162.486187) (xy 61.263878 -162.494695) (xy 61.235336 -162.49523) (xy 61.208083 -162.494725)
			(xy 61.154131 -162.486973) (xy 61.101832 -162.471621) (xy 61.05225 -162.448982) (xy 61.006395 -162.419516)
			(xy 60.965201 -162.383825) (xy 60.929505 -162.342633) (xy 60.900036 -162.296781) (xy 60.877392 -162.247202)
			(xy 60.862035 -162.194904) (xy 60.854277 -162.140953) (xy 60.497974 -162.140953) (xy 60.497974 -163.350702)
			(xy 60.627258 -163.350702) (xy 60.631329 -163.29508) (xy 60.643455 -163.240643) (xy 60.663378 -163.188552)
			(xy 60.690674 -163.139917) (xy 60.72476 -163.095774) (xy 60.764909 -163.057065) (xy 60.810267 -163.024614)
			(xy 60.859867 -162.999113) (xy 60.912651 -162.981106) (xy 60.967494 -162.970976) (xy 61.023228 -162.968939)
			(xy 61.078665 -162.975039) (xy 61.132622 -162.989145) (xy 61.183951 -163.010957) (xy 61.231557 -163.040011)
			(xy 61.274425 -163.075686) (xy 61.311642 -163.117223) (xy 61.342415 -163.163736) (xy 61.366087 -163.214233)
			(xy 61.382155 -163.26764) (xy 61.390275 -163.322816) (xy 61.390784 -163.350702) (xy 61.390275 -163.378588)
			(xy 61.382155 -163.433764) (xy 61.366087 -163.487171) (xy 61.342415 -163.537668) (xy 61.311642 -163.584181)
			(xy 61.274425 -163.625718) (xy 61.231557 -163.661393) (xy 61.183951 -163.690447) (xy 61.132622 -163.712259)
			(xy 61.078665 -163.726365) (xy 61.023228 -163.732465) (xy 60.967494 -163.730428) (xy 60.912651 -163.720298)
			(xy 60.859867 -163.702291) (xy 60.810267 -163.67679) (xy 60.764909 -163.644339) (xy 60.72476 -163.60563)
			(xy 60.690674 -163.561487) (xy 60.663378 -163.512852) (xy 60.643455 -163.460761) (xy 60.631329 -163.406324)
			(xy 60.627258 -163.350702) (xy 60.497974 -163.350702) (xy 60.497974 -166.705534) (xy 62.12789 -166.705534)
			(xy 62.131961 -166.649912) (xy 62.144087 -166.595475) (xy 62.16401 -166.543384) (xy 62.191306 -166.494749)
			(xy 62.225392 -166.450606) (xy 62.265541 -166.411897) (xy 62.310899 -166.379446) (xy 62.360499 -166.353945)
			(xy 62.413283 -166.335938) (xy 62.468126 -166.325808) (xy 62.52386 -166.323771) (xy 62.579297 -166.329871)
			(xy 62.633254 -166.343977) (xy 62.684583 -166.365789) (xy 62.732189 -166.394843) (xy 62.775057 -166.430518)
			(xy 62.812274 -166.472055) (xy 62.843047 -166.518568) (xy 62.866719 -166.569065) (xy 62.882787 -166.622472)
			(xy 62.890907 -166.677648) (xy 62.891416 -166.705534) (xy 63.14389 -166.705534) (xy 63.147961 -166.649912)
			(xy 63.160087 -166.595475) (xy 63.18001 -166.543384) (xy 63.207306 -166.494749) (xy 63.241392 -166.450606)
			(xy 63.281541 -166.411897) (xy 63.326899 -166.379446) (xy 63.376499 -166.353945) (xy 63.429283 -166.335938)
			(xy 63.484126 -166.325808) (xy 63.53986 -166.323771) (xy 63.595297 -166.329871) (xy 63.649254 -166.343977)
			(xy 63.700583 -166.365789) (xy 63.748189 -166.394843) (xy 63.791057 -166.430518) (xy 63.828274 -166.472055)
			(xy 63.859047 -166.518568) (xy 63.882719 -166.569065) (xy 63.898787 -166.622472) (xy 63.906907 -166.677648)
			(xy 63.907416 -166.705534) (xy 63.906907 -166.73342) (xy 63.898787 -166.788596) (xy 63.882719 -166.842003)
			(xy 63.859047 -166.8925) (xy 63.828274 -166.939013) (xy 63.791057 -166.98055) (xy 63.748189 -167.016225)
			(xy 63.700583 -167.045279) (xy 63.649254 -167.067091) (xy 63.595297 -167.081197) (xy 63.53986 -167.087297)
			(xy 63.484126 -167.08526) (xy 63.429283 -167.07513) (xy 63.376499 -167.057123) (xy 63.326899 -167.031622)
			(xy 63.281541 -166.999171) (xy 63.241392 -166.960462) (xy 63.207306 -166.916319) (xy 63.18001 -166.867684)
			(xy 63.160087 -166.815593) (xy 63.147961 -166.761156) (xy 63.14389 -166.705534) (xy 62.891416 -166.705534)
			(xy 62.890907 -166.73342) (xy 62.882787 -166.788596) (xy 62.866719 -166.842003) (xy 62.843047 -166.8925)
			(xy 62.812274 -166.939013) (xy 62.775057 -166.98055) (xy 62.732189 -167.016225) (xy 62.684583 -167.045279)
			(xy 62.633254 -167.067091) (xy 62.579297 -167.081197) (xy 62.52386 -167.087297) (xy 62.468126 -167.08526)
			(xy 62.413283 -167.07513) (xy 62.360499 -167.057123) (xy 62.310899 -167.031622) (xy 62.265541 -166.999171)
			(xy 62.225392 -166.960462) (xy 62.191306 -166.916319) (xy 62.16401 -166.867684) (xy 62.144087 -166.815593)
			(xy 62.131961 -166.761156) (xy 62.12789 -166.705534) (xy 60.497974 -166.705534) (xy 60.497974 -168.94556)
			(xy 62.250064 -168.94556) (xy 62.254135 -168.889938) (xy 62.266261 -168.835501) (xy 62.286184 -168.78341)
			(xy 62.31348 -168.734775) (xy 62.347566 -168.690632) (xy 62.387715 -168.651923) (xy 62.433073 -168.619472)
			(xy 62.482673 -168.593971) (xy 62.535457 -168.575964) (xy 62.5903 -168.565834) (xy 62.646034 -168.563797)
			(xy 62.701471 -168.569897) (xy 62.755428 -168.584003) (xy 62.806757 -168.605815) (xy 62.854363 -168.634869)
			(xy 62.897231 -168.670544) (xy 62.934448 -168.712081) (xy 62.965221 -168.758594) (xy 62.988893 -168.809091)
			(xy 63.004961 -168.862498) (xy 63.013081 -168.917674) (xy 63.01359 -168.94556) (xy 63.013081 -168.973446)
			(xy 63.004961 -169.028622) (xy 62.988893 -169.082029) (xy 62.965221 -169.132526) (xy 62.934448 -169.179039)
			(xy 62.897231 -169.220576) (xy 62.854363 -169.256251) (xy 62.806757 -169.285305) (xy 62.755428 -169.307117)
			(xy 62.701471 -169.321223) (xy 62.646034 -169.327323) (xy 62.5903 -169.325286) (xy 62.535457 -169.315156)
			(xy 62.482673 -169.297149) (xy 62.433073 -169.271648) (xy 62.387715 -169.239197) (xy 62.347566 -169.200488)
			(xy 62.31348 -169.156345) (xy 62.286184 -169.10771) (xy 62.266261 -169.055619) (xy 62.254135 -169.001182)
			(xy 62.250064 -168.94556) (xy 60.497974 -168.94556) (xy 60.497974 -172.2628) (xy 60.498396 -172.272871)
			(xy 60.506108 -172.291478) (xy 60.51296 -172.298868) (xy 60.54344 -172.329348) (xy 61.047882 -172.329348)
			(xy 61.051953 -172.273726) (xy 61.064079 -172.219289) (xy 61.084002 -172.167198) (xy 61.111298 -172.118563)
			(xy 61.145384 -172.07442) (xy 61.185533 -172.035711) (xy 61.230891 -172.00326) (xy 61.280491 -171.977759)
			(xy 61.333275 -171.959752) (xy 61.388118 -171.949622) (xy 61.443852 -171.947585) (xy 61.499289 -171.953685)
			(xy 61.553246 -171.967791) (xy 61.604575 -171.989603) (xy 61.652181 -172.018657) (xy 61.695049 -172.054332)
			(xy 61.732266 -172.095869) (xy 61.763039 -172.142382) (xy 61.786711 -172.192879) (xy 61.802779 -172.246286)
			(xy 61.810899 -172.301462) (xy 61.811408 -172.329348) (xy 61.810899 -172.357234) (xy 61.802779 -172.41241)
			(xy 61.786711 -172.465817) (xy 61.763039 -172.516314) (xy 61.732266 -172.562827) (xy 61.695049 -172.604364)
			(xy 61.652181 -172.640039) (xy 61.604575 -172.669093) (xy 61.553246 -172.690905) (xy 61.499289 -172.705011)
			(xy 61.443852 -172.711111) (xy 61.388118 -172.709074) (xy 61.333275 -172.698944) (xy 61.280491 -172.680937)
			(xy 61.230891 -172.655436) (xy 61.185533 -172.622985) (xy 61.145384 -172.584276) (xy 61.111298 -172.540133)
			(xy 61.084002 -172.491498) (xy 61.064079 -172.439407) (xy 61.051953 -172.38497) (xy 61.047882 -172.329348)
			(xy 60.54344 -172.329348) (xy 61.294518 -173.080426) (xy 61.301914 -173.087278) (xy 61.320513 -173.095017)
			(xy 61.330586 -173.095412)
		)
		(stroke
			(width 0)
			(type solid)
		)
		(fill yes)
		(layer "In13.Cu")
		(net "P3V3_NIC0")
	)
	(gr_poly
		(pts
			(xy 281.667204 -416.687254) (xy 281.677083 -416.686798) (xy 281.69539 -416.679364) (xy 281.702764 -416.672776)
			(xy 281.703018 -416.672522) (xy 282.551124 -415.824416) (xy 282.551632 -415.823908) (xy 282.55821 -415.816526)
			(xy 282.56565 -415.798226) (xy 282.56611 -415.788348) (xy 282.56611 -385.393946) (xy 282.565677 -385.38388)
			(xy 282.55795 -385.365289) (xy 282.551124 -385.357878) (xy 281.340306 -384.14706) (xy 281.332911 -384.140206)
			(xy 281.314312 -384.13246) (xy 281.304238 -384.132074) (xy 275.803106 -384.132074) (xy 275.793035 -384.132495)
			(xy 275.774426 -384.140205) (xy 275.767038 -384.14706) (xy 273.644868 -386.26923) (xy 273.638019 -386.276627)
			(xy 273.630285 -386.295226) (xy 273.629882 -386.305298) (xy 273.629882 -386.951982) (xy 274.822664 -386.951982)
			(xy 274.826735 -386.89636) (xy 274.838861 -386.841923) (xy 274.858784 -386.789832) (xy 274.88608 -386.741197)
			(xy 274.920166 -386.697054) (xy 274.960315 -386.658345) (xy 275.005673 -386.625894) (xy 275.055273 -386.600393)
			(xy 275.108057 -386.582386) (xy 275.1629 -386.572256) (xy 275.218634 -386.570219) (xy 275.274071 -386.576319)
			(xy 275.328028 -386.590425) (xy 275.379357 -386.612237) (xy 275.426963 -386.641291) (xy 275.469831 -386.676966)
			(xy 275.507048 -386.718503) (xy 275.537821 -386.765016) (xy 275.561493 -386.815513) (xy 275.577561 -386.86892)
			(xy 275.585681 -386.924096) (xy 275.58619 -386.951982) (xy 275.585681 -386.979868) (xy 275.577561 -387.035044)
			(xy 275.561493 -387.088451) (xy 275.537821 -387.138948) (xy 275.507048 -387.185461) (xy 275.469831 -387.226998)
			(xy 275.426963 -387.262673) (xy 275.379357 -387.291727) (xy 275.328028 -387.313539) (xy 275.274071 -387.327645)
			(xy 275.218634 -387.333745) (xy 275.1629 -387.331708) (xy 275.108057 -387.321578) (xy 275.055273 -387.303571)
			(xy 275.005673 -387.27807) (xy 274.960315 -387.245619) (xy 274.920166 -387.20691) (xy 274.88608 -387.162767)
			(xy 274.858784 -387.114132) (xy 274.838861 -387.062041) (xy 274.826735 -387.007604) (xy 274.822664 -386.951982)
			(xy 273.629882 -386.951982) (xy 273.629882 -387.7818) (xy 278.200102 -387.7818) (xy 278.204173 -387.726178)
			(xy 278.216299 -387.671741) (xy 278.236222 -387.61965) (xy 278.263518 -387.571015) (xy 278.297604 -387.526872)
			(xy 278.337753 -387.488163) (xy 278.383111 -387.455712) (xy 278.432711 -387.430211) (xy 278.485495 -387.412204)
			(xy 278.540338 -387.402074) (xy 278.596072 -387.400037) (xy 278.651509 -387.406137) (xy 278.705466 -387.420243)
			(xy 278.756795 -387.442055) (xy 278.804401 -387.471109) (xy 278.847269 -387.506784) (xy 278.884486 -387.548321)
			(xy 278.915259 -387.594834) (xy 278.938931 -387.645331) (xy 278.954999 -387.698738) (xy 278.963119 -387.753914)
			(xy 278.963628 -387.7818) (xy 278.963119 -387.809686) (xy 278.954999 -387.864862) (xy 278.938931 -387.918269)
			(xy 278.915259 -387.968766) (xy 278.884486 -388.015279) (xy 278.847269 -388.056816) (xy 278.804401 -388.092491)
			(xy 278.756795 -388.121545) (xy 278.705466 -388.143357) (xy 278.651509 -388.157463) (xy 278.596072 -388.163563)
			(xy 278.540338 -388.161526) (xy 278.485495 -388.151396) (xy 278.432711 -388.133389) (xy 278.383111 -388.107888)
			(xy 278.337753 -388.075437) (xy 278.297604 -388.036728) (xy 278.263518 -387.992585) (xy 278.236222 -387.94395)
			(xy 278.216299 -387.891859) (xy 278.204173 -387.837422) (xy 278.200102 -387.7818) (xy 273.629882 -387.7818)
			(xy 273.629882 -388.5184) (xy 274.953982 -388.5184) (xy 274.958053 -388.462778) (xy 274.970179 -388.408341)
			(xy 274.990102 -388.35625) (xy 275.017398 -388.307615) (xy 275.051484 -388.263472) (xy 275.091633 -388.224763)
			(xy 275.136991 -388.192312) (xy 275.186591 -388.166811) (xy 275.239375 -388.148804) (xy 275.294218 -388.138674)
			(xy 275.349952 -388.136637) (xy 275.405389 -388.142737) (xy 275.459346 -388.156843) (xy 275.510675 -388.178655)
			(xy 275.558281 -388.207709) (xy 275.601149 -388.243384) (xy 275.638366 -388.284921) (xy 275.644619 -388.294372)
			(xy 276.866348 -388.294372) (xy 276.870419 -388.23875) (xy 276.882545 -388.184313) (xy 276.902468 -388.132222)
			(xy 276.929764 -388.083587) (xy 276.96385 -388.039444) (xy 277.003999 -388.000735) (xy 277.049357 -387.968284)
			(xy 277.098957 -387.942783) (xy 277.151741 -387.924776) (xy 277.206584 -387.914646) (xy 277.262318 -387.912609)
			(xy 277.317755 -387.918709) (xy 277.371712 -387.932815) (xy 277.423041 -387.954627) (xy 277.470647 -387.983681)
			(xy 277.513515 -388.019356) (xy 277.550732 -388.060893) (xy 277.581505 -388.107406) (xy 277.605177 -388.157903)
			(xy 277.621245 -388.21131) (xy 277.629365 -388.266486) (xy 277.629874 -388.294372) (xy 277.629365 -388.322258)
			(xy 277.621245 -388.377434) (xy 277.605177 -388.430841) (xy 277.581505 -388.481338) (xy 277.550732 -388.527851)
			(xy 277.513515 -388.569388) (xy 277.470647 -388.605063) (xy 277.423041 -388.634117) (xy 277.371712 -388.655929)
			(xy 277.317755 -388.670035) (xy 277.262318 -388.676135) (xy 277.206584 -388.674098) (xy 277.151741 -388.663968)
			(xy 277.098957 -388.645961) (xy 277.049357 -388.62046) (xy 277.003999 -388.588009) (xy 276.96385 -388.5493)
			(xy 276.929764 -388.505157) (xy 276.902468 -388.456522) (xy 276.882545 -388.404431) (xy 276.870419 -388.349994)
			(xy 276.866348 -388.294372) (xy 275.644619 -388.294372) (xy 275.669139 -388.331434) (xy 275.692811 -388.381931)
			(xy 275.708879 -388.435338) (xy 275.716999 -388.490514) (xy 275.717508 -388.5184) (xy 275.716999 -388.546286)
			(xy 275.708879 -388.601462) (xy 275.692811 -388.654869) (xy 275.669139 -388.705366) (xy 275.638366 -388.751879)
			(xy 275.601149 -388.793416) (xy 275.563133 -388.825053) (xy 278.851055 -388.825053) (xy 278.851055 -388.770547)
			(xy 278.858812 -388.716595) (xy 278.874169 -388.664297) (xy 278.896812 -388.614717) (xy 278.92628 -388.568863)
			(xy 278.961975 -388.52767) (xy 279.003168 -388.491977) (xy 279.049022 -388.462509) (xy 279.098603 -388.439867)
			(xy 279.150901 -388.424511) (xy 279.204853 -388.416755) (xy 279.232106 -388.416292) (xy 279.259411 -388.416814)
			(xy 279.313463 -388.424608) (xy 279.365853 -388.440024) (xy 279.415513 -388.462745) (xy 279.461429 -388.492309)
			(xy 279.502665 -388.528113) (xy 279.538381 -388.569425) (xy 279.567847 -388.615405) (xy 279.579578 -388.640066)
			(xy 279.583546 -388.647897) (xy 279.595748 -388.6605) (xy 279.603454 -388.664704) (xy 279.630886 -388.678166)
			(xy 279.638995 -388.681643) (xy 279.656529 -388.683471) (xy 279.665176 -388.681722) (xy 279.687559 -388.676603)
			(xy 279.733149 -388.671127) (xy 279.756108 -388.6708) (xy 279.783359 -388.67127) (xy 279.837307 -388.679028)
			(xy 279.889602 -388.694384) (xy 279.93918 -388.717026) (xy 279.98503 -388.746493) (xy 280.02622 -388.782186)
			(xy 280.061912 -388.823376) (xy 280.091378 -388.869227) (xy 280.114019 -388.918805) (xy 280.129374 -388.9711)
			(xy 280.13713 -389.025049) (xy 280.13713 -389.079551) (xy 280.129374 -389.1335) (xy 280.114019 -389.185795)
			(xy 280.091378 -389.235373) (xy 280.061912 -389.281224) (xy 280.02622 -389.322414) (xy 279.98503 -389.358107)
			(xy 279.93918 -389.387574) (xy 279.889602 -389.410216) (xy 279.837307 -389.425572) (xy 279.783359 -389.43333)
			(xy 279.756108 -389.433816) (xy 279.728801 -389.433362) (xy 279.674746 -389.425556) (xy 279.622355 -389.41013)
			(xy 279.572695 -389.387398) (xy 279.526779 -389.357825) (xy 279.485544 -389.322013) (xy 279.44983 -389.280692)
			(xy 279.420366 -389.234706) (xy 279.408636 -389.210042) (xy 279.404691 -389.202198) (xy 279.392472 -389.189604)
			(xy 279.38476 -389.185404) (xy 279.357328 -389.171942) (xy 279.349217 -389.168472) (xy 279.331685 -389.166639)
			(xy 279.323038 -389.168386) (xy 279.300654 -389.173503) (xy 279.255065 -389.17898) (xy 279.232106 -389.179308)
			(xy 279.204853 -389.178845) (xy 279.150901 -389.171089) (xy 279.098603 -389.155733) (xy 279.049022 -389.133091)
			(xy 279.003168 -389.103623) (xy 278.961975 -389.06793) (xy 278.92628 -389.026737) (xy 278.896812 -388.980883)
			(xy 278.874169 -388.931303) (xy 278.858812 -388.879005) (xy 278.851055 -388.825053) (xy 275.563133 -388.825053)
			(xy 275.558281 -388.829091) (xy 275.510675 -388.858145) (xy 275.459346 -388.879957) (xy 275.405389 -388.894063)
			(xy 275.349952 -388.900163) (xy 275.294218 -388.898126) (xy 275.239375 -388.887996) (xy 275.186591 -388.869989)
			(xy 275.136991 -388.844488) (xy 275.091633 -388.812037) (xy 275.051484 -388.773328) (xy 275.017398 -388.729185)
			(xy 274.990102 -388.68055) (xy 274.970179 -388.628459) (xy 274.958053 -388.574022) (xy 274.953982 -388.5184)
			(xy 273.629882 -388.5184) (xy 273.629882 -390.018854) (xy 278.201055 -390.018854) (xy 278.201055 -389.964346)
			(xy 278.208813 -389.910394) (xy 278.22417 -389.858094) (xy 278.246814 -389.808513) (xy 278.276284 -389.762659)
			(xy 278.31198 -389.721465) (xy 278.353175 -389.685772) (xy 278.39903 -389.656304) (xy 278.448613 -389.633663)
			(xy 278.500913 -389.618309) (xy 278.554866 -389.610554) (xy 278.58212 -389.610092) (xy 278.611125 -389.610639)
			(xy 278.668465 -389.619437) (xy 278.723812 -389.636812) (xy 278.775892 -389.662365) (xy 278.823505 -389.695505)
			(xy 278.865553 -389.73547) (xy 278.901068 -389.781339) (xy 278.915622 -389.806434) (xy 278.922788 -389.818597)
			(xy 278.942696 -389.838604) (xy 278.967316 -389.852404) (xy 278.994772 -389.858943) (xy 279.022969 -389.857725)
			(xy 279.049759 -389.848841) (xy 279.073097 -389.832968) (xy 279.0825 -389.822436) (xy 279.100747 -389.801537)
			(xy 279.142193 -389.764661) (xy 279.188545 -389.734181) (xy 279.238825 -389.710739) (xy 279.291971 -389.69483)
			(xy 279.346862 -389.686791) (xy 279.3746 -389.686292) (xy 279.401851 -389.686778) (xy 279.455799 -389.694534)
			(xy 279.508094 -389.709889) (xy 279.557671 -389.732531) (xy 279.603521 -389.761997) (xy 279.644712 -389.797688)
			(xy 279.680403 -389.838879) (xy 279.709869 -389.884729) (xy 279.732511 -389.934306) (xy 279.747866 -389.986601)
			(xy 279.755622 -390.040549) (xy 279.755622 -390.095051) (xy 279.747866 -390.148999) (xy 279.732511 -390.201294)
			(xy 279.709869 -390.250871) (xy 279.680403 -390.296721) (xy 279.644712 -390.337912) (xy 279.603521 -390.373603)
			(xy 279.557671 -390.403069) (xy 279.508094 -390.425711) (xy 279.455799 -390.441066) (xy 279.401851 -390.448822)
			(xy 279.3746 -390.449308) (xy 279.345595 -390.448745) (xy 279.288257 -390.43995) (xy 279.232909 -390.422578)
			(xy 279.18083 -390.397028) (xy 279.133217 -390.36389) (xy 279.091168 -390.323927) (xy 279.055653 -390.27806)
			(xy 279.041098 -390.252966) (xy 279.033905 -390.240821) (xy 279.014003 -390.220815) (xy 278.989388 -390.207015)
			(xy 278.961938 -390.200473) (xy 278.933745 -390.201689) (xy 278.906959 -390.210568) (xy 278.883623 -390.226435)
			(xy 278.87422 -390.236964) (xy 278.856016 -390.257901) (xy 278.814561 -390.294774) (xy 278.7682 -390.32525)
			(xy 278.717911 -390.348686) (xy 278.664758 -390.364586) (xy 278.609861 -390.372615) (xy 278.58212 -390.373108)
			(xy 278.554866 -390.372646) (xy 278.500913 -390.364891) (xy 278.448613 -390.349537) (xy 278.39903 -390.326896)
			(xy 278.353175 -390.297428) (xy 278.31198 -390.261735) (xy 278.276284 -390.220541) (xy 278.246814 -390.174687)
			(xy 278.22417 -390.125106) (xy 278.208813 -390.072806) (xy 278.201055 -390.018854) (xy 273.629882 -390.018854)
			(xy 273.629882 -392.320018) (xy 279.4668 -392.320018) (xy 279.470871 -392.264396) (xy 279.482997 -392.209959)
			(xy 279.50292 -392.157868) (xy 279.530216 -392.109233) (xy 279.564302 -392.06509) (xy 279.604451 -392.026381)
			(xy 279.649809 -391.99393) (xy 279.699409 -391.968429) (xy 279.752193 -391.950422) (xy 279.807036 -391.940292)
			(xy 279.86277 -391.938255) (xy 279.918207 -391.944355) (xy 279.972164 -391.958461) (xy 280.023493 -391.980273)
			(xy 280.071099 -392.009327) (xy 280.113967 -392.045002) (xy 280.151184 -392.086539) (xy 280.181957 -392.133052)
			(xy 280.205629 -392.183549) (xy 280.221697 -392.236956) (xy 280.229817 -392.292132) (xy 280.230326 -392.320018)
			(xy 280.229817 -392.347904) (xy 280.221697 -392.40308) (xy 280.205629 -392.456487) (xy 280.181957 -392.506984)
			(xy 280.151184 -392.553497) (xy 280.113967 -392.595034) (xy 280.071099 -392.630709) (xy 280.023493 -392.659763)
			(xy 279.972164 -392.681575) (xy 279.918207 -392.695681) (xy 279.86277 -392.701781) (xy 279.807036 -392.699744)
			(xy 279.752193 -392.689614) (xy 279.699409 -392.671607) (xy 279.649809 -392.646106) (xy 279.604451 -392.613655)
			(xy 279.564302 -392.574946) (xy 279.530216 -392.530803) (xy 279.50292 -392.482168) (xy 279.482997 -392.430077)
			(xy 279.470871 -392.37564) (xy 279.4668 -392.320018) (xy 273.629882 -392.320018) (xy 273.629882 -392.7602)
			(xy 276.865332 -392.7602) (xy 276.869403 -392.704578) (xy 276.881529 -392.650141) (xy 276.901452 -392.59805)
			(xy 276.928748 -392.549415) (xy 276.962834 -392.505272) (xy 277.002983 -392.466563) (xy 277.048341 -392.434112)
			(xy 277.097941 -392.408611) (xy 277.150725 -392.390604) (xy 277.205568 -392.380474) (xy 277.261302 -392.378437)
			(xy 277.316739 -392.384537) (xy 277.370696 -392.398643) (xy 277.422025 -392.420455) (xy 277.469631 -392.449509)
			(xy 277.512499 -392.485184) (xy 277.549716 -392.526721) (xy 277.580489 -392.573234) (xy 277.604161 -392.623731)
			(xy 277.620229 -392.677138) (xy 277.628079 -392.730482) (xy 278.6667 -392.730482) (xy 278.670771 -392.67486)
			(xy 278.682897 -392.620423) (xy 278.70282 -392.568332) (xy 278.730116 -392.519697) (xy 278.764202 -392.475554)
			(xy 278.804351 -392.436845) (xy 278.849709 -392.404394) (xy 278.899309 -392.378893) (xy 278.952093 -392.360886)
			(xy 279.006936 -392.350756) (xy 279.06267 -392.348719) (xy 279.118107 -392.354819) (xy 279.172064 -392.368925)
			(xy 279.223393 -392.390737) (xy 279.270999 -392.419791) (xy 279.313867 -392.455466) (xy 279.351084 -392.497003)
			(xy 279.381857 -392.543516) (xy 279.405529 -392.594013) (xy 279.421597 -392.64742) (xy 279.429717 -392.702596)
			(xy 279.430226 -392.730482) (xy 279.429717 -392.758368) (xy 279.421597 -392.813544) (xy 279.405529 -392.866951)
			(xy 279.381857 -392.917448) (xy 279.351084 -392.963961) (xy 279.313867 -393.005498) (xy 279.270999 -393.041173)
			(xy 279.223393 -393.070227) (xy 279.172064 -393.092039) (xy 279.118107 -393.106145) (xy 279.06267 -393.112245)
			(xy 279.006936 -393.110208) (xy 278.952093 -393.100078) (xy 278.899309 -393.082071) (xy 278.849709 -393.05657)
			(xy 278.804351 -393.024119) (xy 278.764202 -392.98541) (xy 278.730116 -392.941267) (xy 278.70282 -392.892632)
			(xy 278.682897 -392.840541) (xy 278.670771 -392.786104) (xy 278.6667 -392.730482) (xy 277.628079 -392.730482)
			(xy 277.628349 -392.732314) (xy 277.628858 -392.7602) (xy 277.628349 -392.788086) (xy 277.620229 -392.843262)
			(xy 277.604161 -392.896669) (xy 277.580489 -392.947166) (xy 277.549716 -392.993679) (xy 277.512499 -393.035216)
			(xy 277.469631 -393.070891) (xy 277.422025 -393.099945) (xy 277.370696 -393.121757) (xy 277.316739 -393.135863)
			(xy 277.261302 -393.141963) (xy 277.205568 -393.139926) (xy 277.150725 -393.129796) (xy 277.097941 -393.111789)
			(xy 277.048341 -393.086288) (xy 277.002983 -393.053837) (xy 276.962834 -393.015128) (xy 276.928748 -392.970985)
			(xy 276.901452 -392.92235) (xy 276.881529 -392.870259) (xy 276.869403 -392.815822) (xy 276.865332 -392.7602)
			(xy 273.629882 -392.7602) (xy 273.629882 -394.2588) (xy 277.951182 -394.2588) (xy 277.955253 -394.203178)
			(xy 277.967379 -394.148741) (xy 277.987302 -394.09665) (xy 278.014598 -394.048015) (xy 278.048684 -394.003872)
			(xy 278.088833 -393.965163) (xy 278.134191 -393.932712) (xy 278.183791 -393.907211) (xy 278.236575 -393.889204)
			(xy 278.291418 -393.879074) (xy 278.347152 -393.877037) (xy 278.402589 -393.883137) (xy 278.456546 -393.897243)
			(xy 278.507875 -393.919055) (xy 278.555481 -393.948109) (xy 278.598349 -393.983784) (xy 278.635566 -394.025321)
			(xy 278.666339 -394.071834) (xy 278.690011 -394.122331) (xy 278.706079 -394.175738) (xy 278.714199 -394.230914)
			(xy 278.714708 -394.2588) (xy 278.714199 -394.286686) (xy 278.706079 -394.341862) (xy 278.690011 -394.395269)
			(xy 278.666339 -394.445766) (xy 278.635566 -394.492279) (xy 278.598349 -394.533816) (xy 278.555481 -394.569491)
			(xy 278.507875 -394.598545) (xy 278.456546 -394.620357) (xy 278.402589 -394.634463) (xy 278.347152 -394.640563)
			(xy 278.291418 -394.638526) (xy 278.236575 -394.628396) (xy 278.183791 -394.610389) (xy 278.134191 -394.584888)
			(xy 278.088833 -394.552437) (xy 278.048684 -394.513728) (xy 278.014598 -394.469585) (xy 277.987302 -394.42095)
			(xy 277.967379 -394.368859) (xy 277.955253 -394.314422) (xy 277.951182 -394.2588) (xy 273.629882 -394.2588)
			(xy 273.629882 -396.5702) (xy 276.876508 -396.5702) (xy 276.880579 -396.514578) (xy 276.892705 -396.460141)
			(xy 276.912628 -396.40805) (xy 276.939924 -396.359415) (xy 276.97401 -396.315272) (xy 277.014159 -396.276563)
			(xy 277.059517 -396.244112) (xy 277.109117 -396.218611) (xy 277.161901 -396.200604) (xy 277.216744 -396.190474)
			(xy 277.272478 -396.188437) (xy 277.327915 -396.194537) (xy 277.381872 -396.208643) (xy 277.433201 -396.230455)
			(xy 277.480807 -396.259509) (xy 277.523675 -396.295184) (xy 277.560892 -396.336721) (xy 277.591665 -396.383234)
			(xy 277.615337 -396.433731) (xy 277.631405 -396.487138) (xy 277.639525 -396.542314) (xy 277.640034 -396.5702)
			(xy 277.639525 -396.598086) (xy 277.631405 -396.653262) (xy 277.615337 -396.706669) (xy 277.591665 -396.757166)
			(xy 277.560892 -396.803679) (xy 277.523675 -396.845216) (xy 277.52075 -396.84765) (xy 278.070068 -396.84765)
			(xy 278.070068 -396.79315) (xy 278.077823 -396.739205) (xy 278.093177 -396.686912) (xy 278.115815 -396.637337)
			(xy 278.145278 -396.591487) (xy 278.180966 -396.550297) (xy 278.222152 -396.514604) (xy 278.267998 -396.485136)
			(xy 278.317571 -396.462492) (xy 278.369862 -396.447133) (xy 278.423806 -396.439371) (xy 278.451056 -396.438882)
			(xy 278.477946 -396.439303) (xy 278.531197 -396.446833) (xy 278.582864 -396.461765) (xy 278.631922 -396.483801)
			(xy 278.677401 -396.512507) (xy 278.698198 -396.52956) (xy 278.710241 -396.539032) (xy 278.73842 -396.551018)
			(xy 278.768884 -396.554123) (xy 278.798902 -396.548066) (xy 278.82578 -396.533393) (xy 278.847107 -396.511418)
			(xy 278.86097 -396.484113) (xy 278.86406 -396.469108) (xy 278.869043 -396.442799) (xy 278.885286 -396.39178)
			(xy 278.908503 -396.343532) (xy 278.938236 -396.299004) (xy 278.973903 -396.259071) (xy 279.014803 -396.224516)
			(xy 279.060132 -396.196019) (xy 279.109 -396.174138) (xy 279.160447 -396.159305) (xy 279.213463 -396.15181)
			(xy 279.240234 -396.151354) (xy 279.267481 -396.151919) (xy 279.32142 -396.159678) (xy 279.373705 -396.175035)
			(xy 279.423273 -396.197675) (xy 279.469114 -396.22714) (xy 279.510296 -396.262828) (xy 279.545981 -396.304013)
			(xy 279.575441 -396.349857) (xy 279.598077 -396.399427) (xy 279.613429 -396.451714) (xy 279.621184 -396.505653)
			(xy 279.621184 -396.560147) (xy 279.613429 -396.614086) (xy 279.598077 -396.666373) (xy 279.575441 -396.715943)
			(xy 279.545981 -396.761787) (xy 279.510296 -396.802972) (xy 279.469114 -396.83866) (xy 279.423273 -396.868125)
			(xy 279.373705 -396.890765) (xy 279.32142 -396.906122) (xy 279.267481 -396.913881) (xy 279.240234 -396.91437)
			(xy 279.213344 -396.913942) (xy 279.160094 -396.906412) (xy 279.108428 -396.891481) (xy 279.059369 -396.869446)
			(xy 279.01389 -396.840743) (xy 278.993092 -396.823692) (xy 278.981041 -396.814236) (xy 278.952865 -396.802259)
			(xy 278.922406 -396.79916) (xy 278.892395 -396.805216) (xy 278.865522 -396.819884) (xy 278.844195 -396.841849)
			(xy 278.830325 -396.869143) (xy 278.82723 -396.884144) (xy 278.822295 -396.910462) (xy 278.806045 -396.961483)
			(xy 278.782822 -397.00973) (xy 278.753082 -397.054257) (xy 278.717409 -397.09419) (xy 278.676504 -397.128743)
			(xy 278.63117 -397.157239) (xy 278.582298 -397.179118) (xy 278.530848 -397.193949) (xy 278.477829 -397.201442)
			(xy 278.451056 -397.201898) (xy 278.423806 -397.201429) (xy 278.369862 -397.193667) (xy 278.317571 -397.178308)
			(xy 278.267998 -397.155664) (xy 278.222152 -397.126196) (xy 278.180966 -397.090503) (xy 278.145278 -397.049313)
			(xy 278.115815 -397.003463) (xy 278.093177 -396.953888) (xy 278.077823 -396.901595) (xy 278.070068 -396.84765)
			(xy 277.52075 -396.84765) (xy 277.480807 -396.880891) (xy 277.433201 -396.909945) (xy 277.381872 -396.931757)
			(xy 277.327915 -396.945863) (xy 277.272478 -396.951963) (xy 277.216744 -396.949926) (xy 277.161901 -396.939796)
			(xy 277.109117 -396.921789) (xy 277.059517 -396.896288) (xy 277.014159 -396.863837) (xy 276.97401 -396.825128)
			(xy 276.939924 -396.780985) (xy 276.912628 -396.73235) (xy 276.892705 -396.680259) (xy 276.880579 -396.625822)
			(xy 276.876508 -396.5702) (xy 273.629882 -396.5702) (xy 273.629882 -397.933672) (xy 279.755598 -397.933672)
			(xy 279.759669 -397.87805) (xy 279.771795 -397.823613) (xy 279.791718 -397.771522) (xy 279.819014 -397.722887)
			(xy 279.8531 -397.678744) (xy 279.893249 -397.640035) (xy 279.938607 -397.607584) (xy 279.988207 -397.582083)
			(xy 280.040991 -397.564076) (xy 280.095834 -397.553946) (xy 280.151568 -397.551909) (xy 280.207005 -397.558009)
			(xy 280.260962 -397.572115) (xy 280.312291 -397.593927) (xy 280.359897 -397.622981) (xy 280.402765 -397.658656)
			(xy 280.439982 -397.700193) (xy 280.470755 -397.746706) (xy 280.494427 -397.797203) (xy 280.510495 -397.85061)
			(xy 280.518615 -397.905786) (xy 280.519124 -397.933672) (xy 280.518615 -397.961558) (xy 280.510495 -398.016734)
			(xy 280.494427 -398.070141) (xy 280.470755 -398.120638) (xy 280.439982 -398.167151) (xy 280.402765 -398.208688)
			(xy 280.359897 -398.244363) (xy 280.312291 -398.273417) (xy 280.260962 -398.295229) (xy 280.207005 -398.309335)
			(xy 280.151568 -398.315435) (xy 280.095834 -398.313398) (xy 280.040991 -398.303268) (xy 279.988207 -398.285261)
			(xy 279.938607 -398.25976) (xy 279.893249 -398.227309) (xy 279.8531 -398.1886) (xy 279.819014 -398.144457)
			(xy 279.791718 -398.095822) (xy 279.771795 -398.043731) (xy 279.759669 -397.989294) (xy 279.755598 -397.933672)
			(xy 273.629882 -397.933672) (xy 273.629882 -401.173188) (xy 277.11984 -401.173188) (xy 277.123911 -401.117566)
			(xy 277.136037 -401.063129) (xy 277.15596 -401.011038) (xy 277.183256 -400.962403) (xy 277.217342 -400.91826)
			(xy 277.257491 -400.879551) (xy 277.302849 -400.8471) (xy 277.352449 -400.821599) (xy 277.405233 -400.803592)
			(xy 277.460076 -400.793462) (xy 277.51581 -400.791425) (xy 277.571247 -400.797525) (xy 277.625204 -400.811631)
			(xy 277.676533 -400.833443) (xy 277.724139 -400.862497) (xy 277.767007 -400.898172) (xy 277.804224 -400.939709)
			(xy 277.834997 -400.986222) (xy 277.858669 -401.036719) (xy 277.874737 -401.090126) (xy 277.882857 -401.145302)
			(xy 277.882884 -401.146772) (xy 279.138886 -401.146772) (xy 279.142957 -401.09115) (xy 279.155083 -401.036713)
			(xy 279.175006 -400.984622) (xy 279.202302 -400.935987) (xy 279.236388 -400.891844) (xy 279.276537 -400.853135)
			(xy 279.321895 -400.820684) (xy 279.371495 -400.795183) (xy 279.424279 -400.777176) (xy 279.479122 -400.767046)
			(xy 279.534856 -400.765009) (xy 279.590293 -400.771109) (xy 279.64425 -400.785215) (xy 279.695579 -400.807027)
			(xy 279.743185 -400.836081) (xy 279.786053 -400.871756) (xy 279.82327 -400.913293) (xy 279.854043 -400.959806)
			(xy 279.877715 -401.010303) (xy 279.893783 -401.06371) (xy 279.901903 -401.118886) (xy 279.902412 -401.146772)
			(xy 279.901903 -401.174658) (xy 279.893783 -401.229834) (xy 279.877715 -401.283241) (xy 279.854043 -401.333738)
			(xy 279.82327 -401.380251) (xy 279.786053 -401.421788) (xy 279.743185 -401.457463) (xy 279.695579 -401.486517)
			(xy 279.64425 -401.508329) (xy 279.590293 -401.522435) (xy 279.534856 -401.528535) (xy 279.479122 -401.526498)
			(xy 279.424279 -401.516368) (xy 279.371495 -401.498361) (xy 279.321895 -401.47286) (xy 279.276537 -401.440409)
			(xy 279.236388 -401.4017) (xy 279.202302 -401.357557) (xy 279.175006 -401.308922) (xy 279.155083 -401.256831)
			(xy 279.142957 -401.202394) (xy 279.138886 -401.146772) (xy 277.882884 -401.146772) (xy 277.883366 -401.173188)
			(xy 277.882857 -401.201074) (xy 277.874737 -401.25625) (xy 277.858669 -401.309657) (xy 277.834997 -401.360154)
			(xy 277.804224 -401.406667) (xy 277.767007 -401.448204) (xy 277.724139 -401.483879) (xy 277.676533 -401.512933)
			(xy 277.625204 -401.534745) (xy 277.571247 -401.548851) (xy 277.51581 -401.554951) (xy 277.460076 -401.552914)
			(xy 277.405233 -401.542784) (xy 277.352449 -401.524777) (xy 277.302849 -401.499276) (xy 277.257491 -401.466825)
			(xy 277.217342 -401.428116) (xy 277.183256 -401.383973) (xy 277.15596 -401.335338) (xy 277.136037 -401.283247)
			(xy 277.123911 -401.22881) (xy 277.11984 -401.173188) (xy 273.629882 -401.173188) (xy 273.629882 -402.738082)
			(xy 277.421084 -402.738082) (xy 277.425155 -402.68246) (xy 277.437281 -402.628023) (xy 277.457204 -402.575932)
			(xy 277.4845 -402.527297) (xy 277.518586 -402.483154) (xy 277.558735 -402.444445) (xy 277.604093 -402.411994)
			(xy 277.653693 -402.386493) (xy 277.706477 -402.368486) (xy 277.76132 -402.358356) (xy 277.817054 -402.356319)
			(xy 277.872491 -402.362419) (xy 277.926448 -402.376525) (xy 277.977777 -402.398337) (xy 278.025383 -402.427391)
			(xy 278.068251 -402.463066) (xy 278.105468 -402.504603) (xy 278.136241 -402.551116) (xy 278.159913 -402.601613)
			(xy 278.175981 -402.65502) (xy 278.184101 -402.710196) (xy 278.18461 -402.738082) (xy 278.184101 -402.765968)
			(xy 278.175981 -402.821144) (xy 278.159913 -402.874551) (xy 278.136241 -402.925048) (xy 278.105468 -402.971561)
			(xy 278.068251 -403.013098) (xy 278.025383 -403.048773) (xy 277.977777 -403.077827) (xy 277.926448 -403.099639)
			(xy 277.872491 -403.113745) (xy 277.817054 -403.119845) (xy 277.76132 -403.117808) (xy 277.706477 -403.107678)
			(xy 277.653693 -403.089671) (xy 277.604093 -403.06417) (xy 277.558735 -403.031719) (xy 277.518586 -402.99301)
			(xy 277.4845 -402.948867) (xy 277.457204 -402.900232) (xy 277.437281 -402.848141) (xy 277.425155 -402.793704)
			(xy 277.421084 -402.738082) (xy 273.629882 -402.738082) (xy 273.629882 -403.46249) (xy 276.597108 -403.46249)
			(xy 276.601179 -403.406868) (xy 276.613305 -403.352431) (xy 276.633228 -403.30034) (xy 276.660524 -403.251705)
			(xy 276.69461 -403.207562) (xy 276.734759 -403.168853) (xy 276.780117 -403.136402) (xy 276.829717 -403.110901)
			(xy 276.882501 -403.092894) (xy 276.937344 -403.082764) (xy 276.993078 -403.080727) (xy 277.048515 -403.086827)
			(xy 277.102472 -403.100933) (xy 277.153801 -403.122745) (xy 277.201407 -403.151799) (xy 277.244275 -403.187474)
			(xy 277.281492 -403.229011) (xy 277.312265 -403.275524) (xy 277.335937 -403.326021) (xy 277.343753 -403.352)
			(xy 279.077164 -403.352) (xy 279.081235 -403.296378) (xy 279.093361 -403.241941) (xy 279.113284 -403.18985)
			(xy 279.14058 -403.141215) (xy 279.174666 -403.097072) (xy 279.214815 -403.058363) (xy 279.260173 -403.025912)
			(xy 279.309773 -403.000411) (xy 279.362557 -402.982404) (xy 279.4174 -402.972274) (xy 279.473134 -402.970237)
			(xy 279.528571 -402.976337) (xy 279.582528 -402.990443) (xy 279.633857 -403.012255) (xy 279.681463 -403.041309)
			(xy 279.724331 -403.076984) (xy 279.761548 -403.118521) (xy 279.792321 -403.165034) (xy 279.815993 -403.215531)
			(xy 279.832061 -403.268938) (xy 279.840181 -403.324114) (xy 279.84069 -403.352) (xy 279.840181 -403.379886)
			(xy 279.832061 -403.435062) (xy 279.815993 -403.488469) (xy 279.792321 -403.538966) (xy 279.761548 -403.585479)
			(xy 279.724331 -403.627016) (xy 279.681463 -403.662691) (xy 279.633857 -403.691745) (xy 279.582528 -403.713557)
			(xy 279.528571 -403.727663) (xy 279.473134 -403.733763) (xy 279.4174 -403.731726) (xy 279.362557 -403.721596)
			(xy 279.309773 -403.703589) (xy 279.260173 -403.678088) (xy 279.214815 -403.645637) (xy 279.174666 -403.606928)
			(xy 279.14058 -403.562785) (xy 279.113284 -403.51415) (xy 279.093361 -403.462059) (xy 279.081235 -403.407622)
			(xy 279.077164 -403.352) (xy 277.343753 -403.352) (xy 277.352005 -403.379428) (xy 277.360125 -403.434604)
			(xy 277.360634 -403.46249) (xy 277.360125 -403.490376) (xy 277.352005 -403.545552) (xy 277.335937 -403.598959)
			(xy 277.312265 -403.649456) (xy 277.281492 -403.695969) (xy 277.244275 -403.737506) (xy 277.201407 -403.773181)
			(xy 277.153801 -403.802235) (xy 277.102472 -403.824047) (xy 277.048515 -403.838153) (xy 276.993078 -403.844253)
			(xy 276.937344 -403.842216) (xy 276.882501 -403.832086) (xy 276.829717 -403.814079) (xy 276.780117 -403.788578)
			(xy 276.734759 -403.756127) (xy 276.69461 -403.717418) (xy 276.660524 -403.673275) (xy 276.633228 -403.62464)
			(xy 276.613305 -403.572549) (xy 276.601179 -403.518112) (xy 276.597108 -403.46249) (xy 273.629882 -403.46249)
			(xy 273.629882 -404.674324) (xy 274.928582 -404.674324) (xy 274.932653 -404.618702) (xy 274.944779 -404.564265)
			(xy 274.964702 -404.512174) (xy 274.991998 -404.463539) (xy 275.026084 -404.419396) (xy 275.066233 -404.380687)
			(xy 275.111591 -404.348236) (xy 275.161191 -404.322735) (xy 275.213975 -404.304728) (xy 275.268818 -404.294598)
			(xy 275.324552 -404.292561) (xy 275.379989 -404.298661) (xy 275.433946 -404.312767) (xy 275.485275 -404.334579)
			(xy 275.532881 -404.363633) (xy 275.575749 -404.399308) (xy 275.612966 -404.440845) (xy 275.643739 -404.487358)
			(xy 275.667411 -404.537855) (xy 275.683479 -404.591262) (xy 275.691599 -404.646438) (xy 275.692108 -404.674324)
			(xy 280.535124 -404.674324) (xy 280.539195 -404.618702) (xy 280.551321 -404.564265) (xy 280.571244 -404.512174)
			(xy 280.59854 -404.463539) (xy 280.632626 -404.419396) (xy 280.672775 -404.380687) (xy 280.718133 -404.348236)
			(xy 280.767733 -404.322735) (xy 280.820517 -404.304728) (xy 280.87536 -404.294598) (xy 280.931094 -404.292561)
			(xy 280.986531 -404.298661) (xy 281.040488 -404.312767) (xy 281.091817 -404.334579) (xy 281.139423 -404.363633)
			(xy 281.182291 -404.399308) (xy 281.219508 -404.440845) (xy 281.250281 -404.487358) (xy 281.273953 -404.537855)
			(xy 281.290021 -404.591262) (xy 281.298141 -404.646438) (xy 281.29865 -404.674324) (xy 281.298141 -404.70221)
			(xy 281.290021 -404.757386) (xy 281.273953 -404.810793) (xy 281.250281 -404.86129) (xy 281.219508 -404.907803)
			(xy 281.182291 -404.94934) (xy 281.139423 -404.985015) (xy 281.091817 -405.014069) (xy 281.040488 -405.035881)
			(xy 280.986531 -405.049987) (xy 280.931094 -405.056087) (xy 280.87536 -405.05405) (xy 280.820517 -405.04392)
			(xy 280.767733 -405.025913) (xy 280.718133 -405.000412) (xy 280.672775 -404.967961) (xy 280.632626 -404.929252)
			(xy 280.59854 -404.885109) (xy 280.571244 -404.836474) (xy 280.551321 -404.784383) (xy 280.539195 -404.729946)
			(xy 280.535124 -404.674324) (xy 275.692108 -404.674324) (xy 275.691599 -404.70221) (xy 275.683479 -404.757386)
			(xy 275.667411 -404.810793) (xy 275.643739 -404.86129) (xy 275.612966 -404.907803) (xy 275.575749 -404.94934)
			(xy 275.532881 -404.985015) (xy 275.485275 -405.014069) (xy 275.433946 -405.035881) (xy 275.379989 -405.049987)
			(xy 275.324552 -405.056087) (xy 275.268818 -405.05405) (xy 275.213975 -405.04392) (xy 275.161191 -405.025913)
			(xy 275.111591 -405.000412) (xy 275.066233 -404.967961) (xy 275.026084 -404.929252) (xy 274.991998 -404.885109)
			(xy 274.964702 -404.836474) (xy 274.944779 -404.784383) (xy 274.932653 -404.729946) (xy 274.928582 -404.674324)
			(xy 273.629882 -404.674324) (xy 273.629882 -406.147016) (xy 275.691598 -406.147016) (xy 275.695669 -406.091394)
			(xy 275.707795 -406.036957) (xy 275.727718 -405.984866) (xy 275.755014 -405.936231) (xy 275.7891 -405.892088)
			(xy 275.829249 -405.853379) (xy 275.874607 -405.820928) (xy 275.924207 -405.795427) (xy 275.976991 -405.77742)
			(xy 276.031834 -405.76729) (xy 276.087568 -405.765253) (xy 276.143005 -405.771353) (xy 276.196962 -405.785459)
			(xy 276.248291 -405.807271) (xy 276.295897 -405.836325) (xy 276.338765 -405.872) (xy 276.375982 -405.913537)
			(xy 276.406755 -405.96005) (xy 276.430427 -406.010547) (xy 276.446495 -406.063954) (xy 276.454615 -406.11913)
			(xy 276.455124 -406.147016) (xy 276.454615 -406.174902) (xy 276.446495 -406.230078) (xy 276.430427 -406.283485)
			(xy 276.426531 -406.291796) (xy 277.437594 -406.291796) (xy 277.441665 -406.236174) (xy 277.453791 -406.181737)
			(xy 277.473714 -406.129646) (xy 277.50101 -406.081011) (xy 277.535096 -406.036868) (xy 277.575245 -405.998159)
			(xy 277.620603 -405.965708) (xy 277.670203 -405.940207) (xy 277.722987 -405.9222) (xy 277.77783 -405.91207)
			(xy 277.833564 -405.910033) (xy 277.889001 -405.916133) (xy 277.942958 -405.930239) (xy 277.994287 -405.952051)
			(xy 278.041893 -405.981105) (xy 278.084761 -406.01678) (xy 278.121978 -406.058317) (xy 278.152751 -406.10483)
			(xy 278.176423 -406.155327) (xy 278.192491 -406.208734) (xy 278.200611 -406.26391) (xy 278.20112 -406.291796)
			(xy 278.200611 -406.319682) (xy 278.192491 -406.374858) (xy 278.176423 -406.428265) (xy 278.152751 -406.478762)
			(xy 278.121978 -406.525275) (xy 278.084761 -406.566812) (xy 278.041893 -406.602487) (xy 277.994287 -406.631541)
			(xy 277.942958 -406.653353) (xy 277.889001 -406.667459) (xy 277.833564 -406.673559) (xy 277.77783 -406.671522)
			(xy 277.722987 -406.661392) (xy 277.670203 -406.643385) (xy 277.620603 -406.617884) (xy 277.575245 -406.585433)
			(xy 277.535096 -406.546724) (xy 277.50101 -406.502581) (xy 277.473714 -406.453946) (xy 277.453791 -406.401855)
			(xy 277.441665 -406.347418) (xy 277.437594 -406.291796) (xy 276.426531 -406.291796) (xy 276.406755 -406.333982)
			(xy 276.375982 -406.380495) (xy 276.338765 -406.422032) (xy 276.295897 -406.457707) (xy 276.248291 -406.486761)
			(xy 276.196962 -406.508573) (xy 276.143005 -406.522679) (xy 276.087568 -406.528779) (xy 276.031834 -406.526742)
			(xy 275.976991 -406.516612) (xy 275.924207 -406.498605) (xy 275.874607 -406.473104) (xy 275.829249 -406.440653)
			(xy 275.7891 -406.401944) (xy 275.755014 -406.357801) (xy 275.727718 -406.309166) (xy 275.707795 -406.257075)
			(xy 275.695669 -406.202638) (xy 275.691598 -406.147016) (xy 273.629882 -406.147016) (xy 273.629882 -406.943052)
			(xy 278.739598 -406.943052) (xy 278.743669 -406.88743) (xy 278.755795 -406.832993) (xy 278.775718 -406.780902)
			(xy 278.803014 -406.732267) (xy 278.8371 -406.688124) (xy 278.877249 -406.649415) (xy 278.922607 -406.616964)
			(xy 278.972207 -406.591463) (xy 279.024991 -406.573456) (xy 279.079834 -406.563326) (xy 279.135568 -406.561289)
			(xy 279.191005 -406.567389) (xy 279.244962 -406.581495) (xy 279.296291 -406.603307) (xy 279.343897 -406.632361)
			(xy 279.386765 -406.668036) (xy 279.423982 -406.709573) (xy 279.454755 -406.756086) (xy 279.478427 -406.806583)
			(xy 279.494495 -406.85999) (xy 279.502615 -406.915166) (xy 279.503124 -406.943052) (xy 279.502615 -406.970938)
			(xy 279.494495 -407.026114) (xy 279.478427 -407.079521) (xy 279.454755 -407.130018) (xy 279.423982 -407.176531)
			(xy 279.386765 -407.218068) (xy 279.343897 -407.253743) (xy 279.296291 -407.282797) (xy 279.244962 -407.304609)
			(xy 279.191005 -407.318715) (xy 279.135568 -407.324815) (xy 279.079834 -407.322778) (xy 279.024991 -407.312648)
			(xy 278.972207 -407.294641) (xy 278.922607 -407.26914) (xy 278.877249 -407.236689) (xy 278.8371 -407.19798)
			(xy 278.803014 -407.153837) (xy 278.775718 -407.105202) (xy 278.755795 -407.053111) (xy 278.743669 -406.998674)
			(xy 278.739598 -406.943052) (xy 273.629882 -406.943052) (xy 273.629882 -408.165046) (xy 275.975316 -408.165046)
			(xy 275.979387 -408.109424) (xy 275.991513 -408.054987) (xy 276.011436 -408.002896) (xy 276.038732 -407.954261)
			(xy 276.072818 -407.910118) (xy 276.112967 -407.871409) (xy 276.158325 -407.838958) (xy 276.207925 -407.813457)
			(xy 276.260709 -407.79545) (xy 276.315552 -407.78532) (xy 276.371286 -407.783283) (xy 276.426723 -407.789383)
			(xy 276.48068 -407.803489) (xy 276.532009 -407.825301) (xy 276.579615 -407.854355) (xy 276.622483 -407.89003)
			(xy 276.6597 -407.931567) (xy 276.690473 -407.97808) (xy 276.714145 -408.028577) (xy 276.730213 -408.081984)
			(xy 276.735073 -408.115008) (xy 280.953462 -408.115008) (xy 280.957533 -408.059386) (xy 280.969659 -408.004949)
			(xy 280.989582 -407.952858) (xy 281.016878 -407.904223) (xy 281.050964 -407.86008) (xy 281.091113 -407.821371)
			(xy 281.136471 -407.78892) (xy 281.186071 -407.763419) (xy 281.238855 -407.745412) (xy 281.293698 -407.735282)
			(xy 281.349432 -407.733245) (xy 281.404869 -407.739345) (xy 281.458826 -407.753451) (xy 281.510155 -407.775263)
			(xy 281.557761 -407.804317) (xy 281.600629 -407.839992) (xy 281.637846 -407.881529) (xy 281.668619 -407.928042)
			(xy 281.692291 -407.978539) (xy 281.708359 -408.031946) (xy 281.716479 -408.087122) (xy 281.716988 -408.115008)
			(xy 281.716479 -408.142894) (xy 281.708359 -408.19807) (xy 281.692291 -408.251477) (xy 281.668619 -408.301974)
			(xy 281.637846 -408.348487) (xy 281.600629 -408.390024) (xy 281.557761 -408.425699) (xy 281.510155 -408.454753)
			(xy 281.458826 -408.476565) (xy 281.404869 -408.490671) (xy 281.349432 -408.496771) (xy 281.293698 -408.494734)
			(xy 281.238855 -408.484604) (xy 281.186071 -408.466597) (xy 281.136471 -408.441096) (xy 281.091113 -408.408645)
			(xy 281.050964 -408.369936) (xy 281.016878 -408.325793) (xy 280.989582 -408.277158) (xy 280.969659 -408.225067)
			(xy 280.957533 -408.17063) (xy 280.953462 -408.115008) (xy 276.735073 -408.115008) (xy 276.738333 -408.13716)
			(xy 276.738842 -408.165046) (xy 276.738333 -408.192932) (xy 276.730213 -408.248108) (xy 276.714145 -408.301515)
			(xy 276.690473 -408.352012) (xy 276.6597 -408.398525) (xy 276.622483 -408.440062) (xy 276.579615 -408.475737)
			(xy 276.532009 -408.504791) (xy 276.48068 -408.526603) (xy 276.426723 -408.540709) (xy 276.371286 -408.546809)
			(xy 276.315552 -408.544772) (xy 276.260709 -408.534642) (xy 276.207925 -408.516635) (xy 276.158325 -408.491134)
			(xy 276.112967 -408.458683) (xy 276.072818 -408.419974) (xy 276.038732 -408.375831) (xy 276.011436 -408.327196)
			(xy 275.991513 -408.275105) (xy 275.979387 -408.220668) (xy 275.975316 -408.165046) (xy 273.629882 -408.165046)
			(xy 273.629882 -410.136086) (xy 279.512266 -410.136086) (xy 279.516337 -410.080464) (xy 279.528463 -410.026027)
			(xy 279.548386 -409.973936) (xy 279.575682 -409.925301) (xy 279.609768 -409.881158) (xy 279.649917 -409.842449)
			(xy 279.695275 -409.809998) (xy 279.744875 -409.784497) (xy 279.797659 -409.76649) (xy 279.852502 -409.75636)
			(xy 279.908236 -409.754323) (xy 279.963673 -409.760423) (xy 280.01763 -409.774529) (xy 280.068959 -409.796341)
			(xy 280.116565 -409.825395) (xy 280.159433 -409.86107) (xy 280.19665 -409.902607) (xy 280.227423 -409.94912)
			(xy 280.251095 -409.999617) (xy 280.267163 -410.053024) (xy 280.275283 -410.1082) (xy 280.275792 -410.136086)
			(xy 280.275283 -410.163972) (xy 280.267163 -410.219148) (xy 280.251095 -410.272555) (xy 280.227423 -410.323052)
			(xy 280.19665 -410.369565) (xy 280.159433 -410.411102) (xy 280.116565 -410.446777) (xy 280.068959 -410.475831)
			(xy 280.01763 -410.497643) (xy 279.963673 -410.511749) (xy 279.908236 -410.517849) (xy 279.852502 -410.515812)
			(xy 279.797659 -410.505682) (xy 279.744875 -410.487675) (xy 279.695275 -410.462174) (xy 279.649917 -410.429723)
			(xy 279.609768 -410.391014) (xy 279.575682 -410.346871) (xy 279.548386 -410.298236) (xy 279.528463 -410.246145)
			(xy 279.516337 -410.191708) (xy 279.512266 -410.136086) (xy 273.629882 -410.136086) (xy 273.629882 -410.82341)
			(xy 276.66772 -410.82341) (xy 276.671791 -410.767788) (xy 276.683917 -410.713351) (xy 276.70384 -410.66126)
			(xy 276.731136 -410.612625) (xy 276.765222 -410.568482) (xy 276.805371 -410.529773) (xy 276.850729 -410.497322)
			(xy 276.900329 -410.471821) (xy 276.953113 -410.453814) (xy 277.007956 -410.443684) (xy 277.06369 -410.441647)
			(xy 277.119127 -410.447747) (xy 277.173084 -410.461853) (xy 277.224413 -410.483665) (xy 277.272019 -410.512719)
			(xy 277.314887 -410.548394) (xy 277.352104 -410.589931) (xy 277.382877 -410.636444) (xy 277.406549 -410.686941)
			(xy 277.422617 -410.740348) (xy 277.430737 -410.795524) (xy 277.431246 -410.82341) (xy 277.430737 -410.851296)
			(xy 277.422617 -410.906472) (xy 277.406549 -410.959879) (xy 277.382877 -411.010376) (xy 277.352104 -411.056889)
			(xy 277.314887 -411.098426) (xy 277.272019 -411.134101) (xy 277.224413 -411.163155) (xy 277.173084 -411.184967)
			(xy 277.119127 -411.199073) (xy 277.06369 -411.205173) (xy 277.007956 -411.203136) (xy 276.953113 -411.193006)
			(xy 276.900329 -411.174999) (xy 276.850729 -411.149498) (xy 276.805371 -411.117047) (xy 276.765222 -411.078338)
			(xy 276.731136 -411.034195) (xy 276.70384 -410.98556) (xy 276.683917 -410.933469) (xy 276.671791 -410.879032)
			(xy 276.66772 -410.82341) (xy 273.629882 -410.82341) (xy 273.629882 -413.587438) (xy 276.501604 -413.587438)
			(xy 276.505675 -413.531816) (xy 276.517801 -413.477379) (xy 276.537724 -413.425288) (xy 276.56502 -413.376653)
			(xy 276.599106 -413.33251) (xy 276.639255 -413.293801) (xy 276.684613 -413.26135) (xy 276.734213 -413.235849)
			(xy 276.786997 -413.217842) (xy 276.84184 -413.207712) (xy 276.897574 -413.205675) (xy 276.953011 -413.211775)
			(xy 277.006968 -413.225881) (xy 277.058297 -413.247693) (xy 277.105903 -413.276747) (xy 277.148771 -413.312422)
			(xy 277.185988 -413.353959) (xy 277.216761 -413.400472) (xy 277.240433 -413.450969) (xy 277.251535 -413.48787)
			(xy 278.240996 -413.48787) (xy 278.245067 -413.432248) (xy 278.257193 -413.377811) (xy 278.277116 -413.32572)
			(xy 278.304412 -413.277085) (xy 278.338498 -413.232942) (xy 278.378647 -413.194233) (xy 278.424005 -413.161782)
			(xy 278.473605 -413.136281) (xy 278.526389 -413.118274) (xy 278.581232 -413.108144) (xy 278.636966 -413.106107)
			(xy 278.692403 -413.112207) (xy 278.74636 -413.126313) (xy 278.797689 -413.148125) (xy 278.845295 -413.177179)
			(xy 278.888163 -413.212854) (xy 278.92538 -413.254391) (xy 278.956153 -413.300904) (xy 278.979825 -413.351401)
			(xy 278.995893 -413.404808) (xy 279.004013 -413.459984) (xy 279.004522 -413.48787) (xy 279.004013 -413.515756)
			(xy 278.995893 -413.570932) (xy 278.979825 -413.624339) (xy 278.956153 -413.674836) (xy 278.92538 -413.721349)
			(xy 278.888163 -413.762886) (xy 278.845295 -413.798561) (xy 278.797689 -413.827615) (xy 278.74636 -413.849427)
			(xy 278.692403 -413.863533) (xy 278.636966 -413.869633) (xy 278.581232 -413.867596) (xy 278.526389 -413.857466)
			(xy 278.473605 -413.839459) (xy 278.424005 -413.813958) (xy 278.378647 -413.781507) (xy 278.338498 -413.742798)
			(xy 278.304412 -413.698655) (xy 278.277116 -413.65002) (xy 278.257193 -413.597929) (xy 278.245067 -413.543492)
			(xy 278.240996 -413.48787) (xy 277.251535 -413.48787) (xy 277.256501 -413.504376) (xy 277.264621 -413.559552)
			(xy 277.26513 -413.587438) (xy 277.264621 -413.615324) (xy 277.256501 -413.6705) (xy 277.240433 -413.723907)
			(xy 277.216761 -413.774404) (xy 277.185988 -413.820917) (xy 277.148771 -413.862454) (xy 277.127327 -413.8803)
			(xy 280.408378 -413.8803) (xy 280.412449 -413.824678) (xy 280.424575 -413.770241) (xy 280.444498 -413.71815)
			(xy 280.471794 -413.669515) (xy 280.50588 -413.625372) (xy 280.546029 -413.586663) (xy 280.591387 -413.554212)
			(xy 280.640987 -413.528711) (xy 280.693771 -413.510704) (xy 280.748614 -413.500574) (xy 280.804348 -413.498537)
			(xy 280.859785 -413.504637) (xy 280.913742 -413.518743) (xy 280.965071 -413.540555) (xy 281.012677 -413.569609)
			(xy 281.055545 -413.605284) (xy 281.092762 -413.646821) (xy 281.123535 -413.693334) (xy 281.147207 -413.743831)
			(xy 281.163275 -413.797238) (xy 281.171395 -413.852414) (xy 281.171904 -413.8803) (xy 281.171395 -413.908186)
			(xy 281.163275 -413.963362) (xy 281.147207 -414.016769) (xy 281.123535 -414.067266) (xy 281.092762 -414.113779)
			(xy 281.055545 -414.155316) (xy 281.012677 -414.190991) (xy 280.965071 -414.220045) (xy 280.913742 -414.241857)
			(xy 280.859785 -414.255963) (xy 280.804348 -414.262063) (xy 280.748614 -414.260026) (xy 280.693771 -414.249896)
			(xy 280.640987 -414.231889) (xy 280.591387 -414.206388) (xy 280.546029 -414.173937) (xy 280.50588 -414.135228)
			(xy 280.471794 -414.091085) (xy 280.444498 -414.04245) (xy 280.424575 -413.990359) (xy 280.412449 -413.935922)
			(xy 280.408378 -413.8803) (xy 277.127327 -413.8803) (xy 277.105903 -413.898129) (xy 277.058297 -413.927183)
			(xy 277.006968 -413.948995) (xy 276.953011 -413.963101) (xy 276.897574 -413.969201) (xy 276.84184 -413.967164)
			(xy 276.786997 -413.957034) (xy 276.734213 -413.939027) (xy 276.684613 -413.913526) (xy 276.639255 -413.881075)
			(xy 276.599106 -413.842366) (xy 276.56502 -413.798223) (xy 276.537724 -413.749588) (xy 276.517801 -413.697497)
			(xy 276.505675 -413.64306) (xy 276.501604 -413.587438) (xy 273.629882 -413.587438) (xy 273.629882 -415.440622)
			(xy 273.630309 -415.450691) (xy 273.638027 -415.469291) (xy 273.644868 -415.47669) (xy 274.27428 -416.106102)
			(xy 276.344378 -416.106102) (xy 276.348449 -416.05048) (xy 276.360575 -415.996043) (xy 276.380498 -415.943952)
			(xy 276.407794 -415.895317) (xy 276.44188 -415.851174) (xy 276.482029 -415.812465) (xy 276.527387 -415.780014)
			(xy 276.576987 -415.754513) (xy 276.629771 -415.736506) (xy 276.684614 -415.726376) (xy 276.740348 -415.724339)
			(xy 276.795785 -415.730439) (xy 276.849742 -415.744545) (xy 276.901071 -415.766357) (xy 276.948677 -415.795411)
			(xy 276.991545 -415.831086) (xy 277.028762 -415.872623) (xy 277.059535 -415.919136) (xy 277.083207 -415.969633)
			(xy 277.089113 -415.989262) (xy 278.376378 -415.989262) (xy 278.380449 -415.93364) (xy 278.392575 -415.879203)
			(xy 278.412498 -415.827112) (xy 278.439794 -415.778477) (xy 278.47388 -415.734334) (xy 278.514029 -415.695625)
			(xy 278.559387 -415.663174) (xy 278.608987 -415.637673) (xy 278.661771 -415.619666) (xy 278.716614 -415.609536)
			(xy 278.772348 -415.607499) (xy 278.827785 -415.613599) (xy 278.881742 -415.627705) (xy 278.933071 -415.649517)
			(xy 278.980677 -415.678571) (xy 279.023545 -415.714246) (xy 279.060762 -415.755783) (xy 279.091535 -415.802296)
			(xy 279.115207 -415.852793) (xy 279.131275 -415.9062) (xy 279.139395 -415.961376) (xy 279.139904 -415.989262)
			(xy 279.139395 -416.017148) (xy 279.131275 -416.072324) (xy 279.115207 -416.125731) (xy 279.099047 -416.160204)
			(xy 280.408378 -416.160204) (xy 280.412449 -416.104582) (xy 280.424575 -416.050145) (xy 280.444498 -415.998054)
			(xy 280.471794 -415.949419) (xy 280.50588 -415.905276) (xy 280.546029 -415.866567) (xy 280.591387 -415.834116)
			(xy 280.640987 -415.808615) (xy 280.693771 -415.790608) (xy 280.748614 -415.780478) (xy 280.804348 -415.778441)
			(xy 280.859785 -415.784541) (xy 280.913742 -415.798647) (xy 280.965071 -415.820459) (xy 281.012677 -415.849513)
			(xy 281.055545 -415.885188) (xy 281.092762 -415.926725) (xy 281.123535 -415.973238) (xy 281.147207 -416.023735)
			(xy 281.163275 -416.077142) (xy 281.171395 -416.132318) (xy 281.171904 -416.160204) (xy 281.171395 -416.18809)
			(xy 281.163275 -416.243266) (xy 281.147207 -416.296673) (xy 281.123535 -416.34717) (xy 281.092762 -416.393683)
			(xy 281.055545 -416.43522) (xy 281.012677 -416.470895) (xy 280.965071 -416.499949) (xy 280.913742 -416.521761)
			(xy 280.859785 -416.535867) (xy 280.804348 -416.541967) (xy 280.748614 -416.53993) (xy 280.693771 -416.5298)
			(xy 280.640987 -416.511793) (xy 280.591387 -416.486292) (xy 280.546029 -416.453841) (xy 280.50588 -416.415132)
			(xy 280.471794 -416.370989) (xy 280.444498 -416.322354) (xy 280.424575 -416.270263) (xy 280.412449 -416.215826)
			(xy 280.408378 -416.160204) (xy 279.099047 -416.160204) (xy 279.091535 -416.176228) (xy 279.060762 -416.222741)
			(xy 279.023545 -416.264278) (xy 278.980677 -416.299953) (xy 278.933071 -416.329007) (xy 278.881742 -416.350819)
			(xy 278.827785 -416.364925) (xy 278.772348 -416.371025) (xy 278.716614 -416.368988) (xy 278.661771 -416.358858)
			(xy 278.608987 -416.340851) (xy 278.559387 -416.31535) (xy 278.514029 -416.282899) (xy 278.47388 -416.24419)
			(xy 278.439794 -416.200047) (xy 278.412498 -416.151412) (xy 278.392575 -416.099321) (xy 278.380449 -416.044884)
			(xy 278.376378 -415.989262) (xy 277.089113 -415.989262) (xy 277.099275 -416.02304) (xy 277.107395 -416.078216)
			(xy 277.107904 -416.106102) (xy 277.107395 -416.133988) (xy 277.099275 -416.189164) (xy 277.083207 -416.242571)
			(xy 277.059535 -416.293068) (xy 277.028762 -416.339581) (xy 276.991545 -416.381118) (xy 276.948677 -416.416793)
			(xy 276.901071 -416.445847) (xy 276.849742 -416.467659) (xy 276.795785 -416.481765) (xy 276.740348 -416.487865)
			(xy 276.684614 -416.485828) (xy 276.629771 -416.475698) (xy 276.576987 -416.457691) (xy 276.527387 -416.43219)
			(xy 276.482029 -416.399739) (xy 276.44188 -416.36103) (xy 276.407794 -416.316887) (xy 276.380498 -416.268252)
			(xy 276.360575 -416.216161) (xy 276.348449 -416.161724) (xy 276.344378 -416.106102) (xy 274.27428 -416.106102)
			(xy 274.840446 -416.672268) (xy 274.840954 -416.672776) (xy 274.848336 -416.679356) (xy 274.866635 -416.686802)
			(xy 274.876514 -416.687254)
		)
		(stroke
			(width 0)
			(type solid)
		)
		(fill yes)
		(layer "In13.Cu")
		(net "P3V3_AUX")
	)
	(gr_poly
		(pts
			(xy 281.192224 -289.1917) (xy 281.202292 -289.191272) (xy 281.22089 -289.183552) (xy 281.228292 -289.176714)
			(xy 281.398726 -289.00628) (xy 281.402282 -289.000184) (xy 281.411178 -288.985015) (xy 281.431935 -288.956626)
			(xy 281.443684 -288.943542) (xy 281.449867 -288.936283) (xy 281.456777 -288.918527) (xy 281.457146 -288.908998)
			(xy 281.457146 -288.640774) (xy 281.456742 -288.631256) (xy 281.449814 -288.613524) (xy 281.443684 -288.60623)
			(xy 281.428549 -288.589244) (xy 281.402953 -288.551633) (xy 281.383208 -288.510648) (xy 281.369747 -288.467191)
			(xy 281.362869 -288.42222) (xy 281.362404 -288.399474) (xy 281.362404 -288.200338) (xy 281.362854 -288.177587)
			(xy 281.369679 -288.1326) (xy 281.383122 -288.089129) (xy 281.402884 -288.048143) (xy 281.428526 -288.010553)
			(xy 281.443684 -287.993582) (xy 281.449873 -287.986325) (xy 281.456797 -287.968569) (xy 281.457146 -287.959038)
			(xy 281.457146 -287.690814) (xy 281.456749 -287.681293) (xy 281.449831 -287.663552) (xy 281.443684 -287.65627)
			(xy 281.428552 -287.639283) (xy 281.402964 -287.601671) (xy 281.383226 -287.560684) (xy 281.369775 -287.517228)
			(xy 281.362905 -287.472258) (xy 281.362404 -287.449514) (xy 281.362404 -287.250378) (xy 281.362851 -287.227626)
			(xy 281.36967 -287.182636) (xy 281.383109 -287.139161) (xy 281.402868 -287.098171) (xy 281.428507 -287.060577)
			(xy 281.443684 -287.043622) (xy 281.449879 -287.036367) (xy 281.456817 -287.018611) (xy 281.457146 -287.009078)
			(xy 281.457146 -286.740854) (xy 281.456755 -286.73133) (xy 281.449848 -286.713579) (xy 281.443684 -286.70631)
			(xy 281.42855 -286.689324) (xy 281.402957 -286.651712) (xy 281.383214 -286.610727) (xy 281.369756 -286.56727)
			(xy 281.362881 -286.522299) (xy 281.362404 -286.499554) (xy 281.362404 -286.300164) (xy 281.362852 -286.277413)
			(xy 281.369673 -286.232423) (xy 281.383114 -286.18895) (xy 281.402874 -286.147961) (xy 281.428513 -286.110369)
			(xy 281.443684 -286.093408) (xy 281.449877 -286.086152) (xy 281.45681 -286.068396) (xy 281.457146 -286.058864)
			(xy 281.457146 -285.79064) (xy 281.456753 -285.781117) (xy 281.449842 -285.76337) (xy 281.443684 -285.756096)
			(xy 281.428551 -285.739109) (xy 281.402959 -285.701498) (xy 281.383218 -285.660512) (xy 281.369763 -285.617055)
			(xy 281.362889 -285.572085) (xy 281.362404 -285.54934) (xy 281.362404 -285.350204) (xy 281.362856 -285.327454)
			(xy 281.369686 -285.282469) (xy 281.383133 -285.239002) (xy 281.402898 -285.198019) (xy 281.428542 -285.160433)
			(xy 281.443684 -285.143448) (xy 281.449868 -285.136189) (xy 281.45678 -285.118433) (xy 281.457146 -285.108904)
			(xy 281.457146 -284.84068) (xy 281.456743 -284.831162) (xy 281.449816 -284.813428) (xy 281.443684 -284.806136)
			(xy 281.428549 -284.78915) (xy 281.402952 -284.75154) (xy 281.383206 -284.710554) (xy 281.369745 -284.667097)
			(xy 281.362865 -284.622126) (xy 281.362404 -284.59938) (xy 281.362404 -284.400244) (xy 281.362854 -284.377493)
			(xy 281.369677 -284.332505) (xy 281.38312 -284.289034) (xy 281.402882 -284.248047) (xy 281.428523 -284.210457)
			(xy 281.443684 -284.193488) (xy 281.449874 -284.186231) (xy 281.4568 -284.168475) (xy 281.457146 -284.158944)
			(xy 281.457146 -283.89072) (xy 281.45675 -283.881199) (xy 281.449834 -283.863456) (xy 281.443684 -283.856176)
			(xy 281.428552 -283.839189) (xy 281.402963 -283.801577) (xy 281.383225 -283.760591) (xy 281.369772 -283.717134)
			(xy 281.362902 -283.672164) (xy 281.362404 -283.64942) (xy 281.362404 -283.450284) (xy 281.362851 -283.427532)
			(xy 281.369669 -283.382541) (xy 281.383107 -283.339066) (xy 281.402865 -283.298075) (xy 281.428504 -283.260481)
			(xy 281.443684 -283.243528) (xy 281.44988 -283.236273) (xy 281.45682 -283.218517) (xy 281.457146 -283.208984)
			(xy 281.457146 -282.94076) (xy 281.456739 -282.931243) (xy 281.449808 -282.913514) (xy 281.443684 -282.906216)
			(xy 281.42855 -282.88923) (xy 281.402956 -282.851619) (xy 281.383212 -282.810633) (xy 281.369754 -282.767176)
			(xy 281.362877 -282.722205) (xy 281.362404 -282.69946) (xy 281.362404 -282.500324) (xy 281.362855 -282.477574)
			(xy 281.369681 -282.432587) (xy 281.383126 -282.389118) (xy 281.40289 -282.348133) (xy 281.428532 -282.310545)
			(xy 281.443684 -282.293568) (xy 281.449871 -282.28631) (xy 281.45679 -282.268554) (xy 281.457146 -282.259024)
			(xy 281.457146 -282.054554) (xy 281.456834 -282.045198) (xy 281.450178 -282.027715) (xy 281.444192 -282.020518)
			(xy 281.39263 -281.96286) (xy 281.37612 -281.954478) (xy 281.366468 -281.953462) (xy 281.341854 -281.95028)
			(xy 281.294043 -281.936973) (xy 281.249013 -281.91611) (xy 281.207949 -281.88824) (xy 281.171932 -281.854096)
			(xy 281.141911 -281.814578) (xy 281.118674 -281.770726) (xy 281.102835 -281.723693) (xy 281.094809 -281.674718)
			(xy 281.094809 -281.625089) (xy 281.102833 -281.576114) (xy 281.118672 -281.529081) (xy 281.141907 -281.485228)
			(xy 281.171928 -281.445709) (xy 281.207944 -281.411565) (xy 281.249007 -281.383694) (xy 281.294036 -281.36283)
			(xy 281.341847 -281.349521) (xy 281.366468 -281.346402) (xy 281.37612 -281.345386) (xy 281.39263 -281.337004)
			(xy 281.444192 -281.279346) (xy 281.450092 -281.272099) (xy 281.456731 -281.254646) (xy 281.457146 -281.24531)
			(xy 281.457146 -281.12593) (xy 281.456748 -281.116647) (xy 281.450108 -281.099312) (xy 281.444192 -281.092148)
			(xy 281.392122 -281.03449) (xy 281.375612 -281.026108) (xy 281.36596 -281.025092) (xy 281.340879 -281.021996)
			(xy 281.292025 -281.009073) (xy 281.245739 -280.988791) (xy 281.203123 -280.961634) (xy 281.165188 -280.928247)
			(xy 281.132839 -280.889424) (xy 281.106844 -280.846088) (xy 281.087821 -280.799271) (xy 281.076223 -280.750086)
			(xy 281.072326 -280.699702) (xy 281.076223 -280.649318) (xy 281.08782 -280.600133) (xy 281.106842 -280.553315)
			(xy 281.132837 -280.509979) (xy 281.165186 -280.471156) (xy 281.20312 -280.437768) (xy 281.245736 -280.410611)
			(xy 281.292022 -280.390329) (xy 281.340875 -280.377405) (xy 281.36596 -280.374344) (xy 281.375612 -280.373328)
			(xy 281.392122 -280.364946) (xy 281.444192 -280.307288) (xy 281.450065 -280.300097) (xy 281.456716 -280.282779)
			(xy 281.457146 -280.273506) (xy 281.457146 -280.175716) (xy 281.456745 -280.166434) (xy 281.450102 -280.149102)
			(xy 281.444192 -280.141934) (xy 281.392122 -280.084276) (xy 281.375612 -280.075894) (xy 281.36596 -280.074878)
			(xy 281.34088 -280.071782) (xy 281.292028 -280.058859) (xy 281.245745 -280.038578) (xy 281.20313 -280.011422)
			(xy 281.165197 -279.978036) (xy 281.13285 -279.939214) (xy 281.106856 -279.895881) (xy 281.087834 -279.849065)
			(xy 281.076237 -279.799882) (xy 281.07234 -279.7495) (xy 281.076237 -279.699119) (xy 281.087834 -279.649935)
			(xy 281.106855 -279.60312) (xy 281.132849 -279.559786) (xy 281.165197 -279.520965) (xy 281.203129 -279.487579)
			(xy 281.245744 -279.460422) (xy 281.292027 -279.440141) (xy 281.340879 -279.427218) (xy 281.36596 -279.42413)
			(xy 281.375612 -279.423114) (xy 281.392122 -279.414732) (xy 281.444192 -279.357074) (xy 281.450063 -279.349883)
			(xy 281.456709 -279.332565) (xy 281.457146 -279.323292) (xy 281.457146 -279.20442) (xy 281.456828 -279.195066)
			(xy 281.450164 -279.177592) (xy 281.444192 -279.170384) (xy 281.39263 -279.112726) (xy 281.37612 -279.104344)
			(xy 281.366468 -279.103328) (xy 281.341857 -279.100146) (xy 281.294051 -279.086839) (xy 281.249026 -279.065978)
			(xy 281.207968 -279.038111) (xy 281.171955 -279.003971) (xy 281.141938 -278.964457) (xy 281.118704 -278.920609)
			(xy 281.102867 -278.873581) (xy 281.094843 -278.824611) (xy 281.094843 -278.774988) (xy 281.102867 -278.726019)
			(xy 281.118705 -278.678991) (xy 281.141938 -278.635143) (xy 281.171956 -278.595629) (xy 281.207968 -278.561489)
			(xy 281.249027 -278.533622) (xy 281.294052 -278.51276) (xy 281.341857 -278.499454) (xy 281.366468 -278.496268)
			(xy 281.37612 -278.495252) (xy 281.39263 -278.48687) (xy 281.444192 -278.429212) (xy 281.450101 -278.421968)
			(xy 281.456762 -278.404516) (xy 281.457146 -278.395176) (xy 281.457146 -278.25446) (xy 281.456835 -278.245104)
			(xy 281.450181 -278.227619) (xy 281.444192 -278.220424) (xy 281.39263 -278.162766) (xy 281.37612 -278.154384)
			(xy 281.366468 -278.153368) (xy 281.341853 -278.150186) (xy 281.294041 -278.136879) (xy 281.24901 -278.116015)
			(xy 281.207946 -278.088145) (xy 281.171928 -278.054001) (xy 281.141906 -278.014482) (xy 281.118669 -277.970629)
			(xy 281.102829 -277.923595) (xy 281.094803 -277.874619) (xy 281.094803 -277.824989) (xy 281.102827 -277.776013)
			(xy 281.118666 -277.728979) (xy 281.141902 -277.685125) (xy 281.171923 -277.645605) (xy 281.207939 -277.61146)
			(xy 281.249003 -277.583589) (xy 281.294034 -277.562724) (xy 281.341845 -277.549416) (xy 281.366468 -277.546308)
			(xy 281.37612 -277.545292) (xy 281.39263 -277.53691) (xy 281.444192 -277.479252) (xy 281.450093 -277.472005)
			(xy 281.456734 -277.454553) (xy 281.457146 -277.445216) (xy 281.457146 -277.3045) (xy 281.456825 -277.295148)
			(xy 281.450155 -277.277678) (xy 281.444192 -277.270464) (xy 281.39263 -277.212806) (xy 281.37612 -277.204424)
			(xy 281.366468 -277.203408) (xy 281.341858 -277.200226) (xy 281.294056 -277.18692) (xy 281.249034 -277.16606)
			(xy 281.207978 -277.138194) (xy 281.171969 -277.104056) (xy 281.141953 -277.064544) (xy 281.118722 -277.020699)
			(xy 281.102886 -276.973674) (xy 281.094863 -276.924707) (xy 281.094863 -276.875088) (xy 281.102887 -276.826121)
			(xy 281.118724 -276.779097) (xy 281.141956 -276.735252) (xy 281.171972 -276.695741) (xy 281.207982 -276.661603)
			(xy 281.249039 -276.633738) (xy 281.294061 -276.612878) (xy 281.341863 -276.599574) (xy 281.366468 -276.596348)
			(xy 281.37612 -276.595332) (xy 281.39263 -276.58695) (xy 281.444192 -276.529292) (xy 281.450099 -276.522047)
			(xy 281.456753 -276.504594) (xy 281.457146 -276.495256) (xy 281.457146 -276.37613) (xy 281.456748 -276.366847)
			(xy 281.450108 -276.349512) (xy 281.444192 -276.342348) (xy 281.392122 -276.28469) (xy 281.375612 -276.276308)
			(xy 281.36596 -276.275292) (xy 281.340879 -276.272196) (xy 281.292025 -276.259273) (xy 281.245739 -276.238991)
			(xy 281.203123 -276.211834) (xy 281.165188 -276.178447) (xy 281.132839 -276.139624) (xy 281.106844 -276.096288)
			(xy 281.087821 -276.049471) (xy 281.076223 -276.000286) (xy 281.072326 -275.949902) (xy 281.076223 -275.899518)
			(xy 281.08782 -275.850333) (xy 281.106842 -275.803515) (xy 281.132837 -275.760179) (xy 281.165186 -275.721356)
			(xy 281.20312 -275.687968) (xy 281.245736 -275.660811) (xy 281.292022 -275.640529) (xy 281.340875 -275.627605)
			(xy 281.36596 -275.624544) (xy 281.375612 -275.623528) (xy 281.392122 -275.615146) (xy 281.444192 -275.557488)
			(xy 281.450065 -275.550297) (xy 281.456716 -275.532979) (xy 281.457146 -275.523706) (xy 281.457146 -275.42617)
			(xy 281.456737 -275.416891) (xy 281.450083 -275.39957) (xy 281.444192 -275.392388) (xy 281.392122 -275.33473)
			(xy 281.375612 -275.326348) (xy 281.36596 -275.325332) (xy 281.340884 -275.322236) (xy 281.292039 -275.309314)
			(xy 281.245762 -275.289035) (xy 281.203154 -275.261882) (xy 281.165227 -275.2285) (xy 281.132884 -275.189684)
			(xy 281.106895 -275.146356) (xy 281.087877 -275.099547) (xy 281.076282 -275.05037) (xy 281.072387 -274.999996)
			(xy 281.076283 -274.949621) (xy 281.087879 -274.900445) (xy 281.106899 -274.853637) (xy 281.13289 -274.810309)
			(xy 281.165233 -274.771494) (xy 281.203161 -274.738113) (xy 281.24577 -274.710961) (xy 281.292047 -274.690683)
			(xy 281.340892 -274.677763) (xy 281.36596 -274.674584) (xy 281.375612 -274.673568) (xy 281.392122 -274.665186)
			(xy 281.444192 -274.607528) (xy 281.450056 -274.600334) (xy 281.456686 -274.583016) (xy 281.457146 -274.573746)
			(xy 281.457146 -274.454366) (xy 281.456836 -274.445009) (xy 281.450184 -274.427523) (xy 281.444192 -274.42033)
			(xy 281.39263 -274.362672) (xy 281.37612 -274.35429) (xy 281.366468 -274.353274) (xy 281.341853 -274.350092)
			(xy 281.29404 -274.336785) (xy 281.249008 -274.315921) (xy 281.207943 -274.28805) (xy 281.171924 -274.253905)
			(xy 281.141901 -274.214386) (xy 281.118664 -274.170532) (xy 281.102824 -274.123497) (xy 281.094798 -274.07452)
			(xy 281.094797 -274.02489) (xy 281.102821 -273.975912) (xy 281.11866 -273.928877) (xy 281.141896 -273.885022)
			(xy 281.171918 -273.845502) (xy 281.207935 -273.811356) (xy 281.249 -273.783484) (xy 281.294031 -273.762619)
			(xy 281.341844 -273.74931) (xy 281.366468 -273.746214) (xy 281.37612 -273.745198) (xy 281.39263 -273.736816)
			(xy 281.444192 -273.679158) (xy 281.450094 -273.671911) (xy 281.456736 -273.654459) (xy 281.457146 -273.645122)
			(xy 281.457146 -273.504406) (xy 281.456826 -273.495053) (xy 281.450158 -273.477582) (xy 281.444192 -273.47037)
			(xy 281.39263 -273.412712) (xy 281.37612 -273.40433) (xy 281.366468 -273.403314) (xy 281.341858 -273.400132)
			(xy 281.294055 -273.386826) (xy 281.249032 -273.365965) (xy 281.207975 -273.338099) (xy 281.171965 -273.30396)
			(xy 281.141948 -273.264448) (xy 281.118717 -273.220602) (xy 281.10288 -273.173576) (xy 281.094857 -273.124609)
			(xy 281.094857 -273.074988) (xy 281.102881 -273.026021) (xy 281.118718 -272.978995) (xy 281.14195 -272.935149)
			(xy 281.171967 -272.895637) (xy 281.207978 -272.861499) (xy 281.249035 -272.833633) (xy 281.294058 -272.812773)
			(xy 281.341861 -272.799468) (xy 281.366468 -272.796254) (xy 281.37612 -272.795238) (xy 281.39263 -272.786856)
			(xy 281.444192 -272.729198) (xy 281.450099 -272.721953) (xy 281.456756 -272.704501) (xy 281.457146 -272.695162)
			(xy 281.457146 -271.855692) (xy 281.456745 -271.846173) (xy 281.449822 -271.828436) (xy 281.443684 -271.821148)
			(xy 281.427113 -271.802514) (xy 281.399656 -271.760891) (xy 281.379351 -271.715349) (xy 281.372564 -271.691354)
			(xy 281.370786 -271.68475) (xy 281.364182 -271.67332) (xy 280.333958 -270.643096) (xy 280.326557 -270.636257)
			(xy 280.307959 -270.628538) (xy 280.29789 -270.62811) (xy 272.58899 -270.62811) (xy 272.578921 -270.628535)
			(xy 272.56032 -270.636253) (xy 272.552922 -270.643096) (xy 272.39341 -270.802608) (xy 272.386564 -270.810007)
			(xy 272.378831 -270.828605) (xy 272.378424 -270.838676) (xy 272.378424 -272.097246) (xy 272.378856 -272.107312)
			(xy 272.386585 -272.125902) (xy 272.39341 -272.133314) (xy 272.395188 -272.135092) (xy 276.317964 -272.135092)
			(xy 276.345904 -272.111978) (xy 276.349206 -272.09369) (xy 276.354253 -272.069274) (xy 276.371215 -272.022395)
			(xy 276.395566 -271.978894) (xy 276.42666 -271.939925) (xy 276.46367 -271.906524) (xy 276.505614 -271.879579)
			(xy 276.551378 -271.859804) (xy 276.599746 -271.847725) (xy 276.649434 -271.843662) (xy 276.699122 -271.847725)
			(xy 276.74749 -271.859804) (xy 276.793254 -271.879579) (xy 276.835198 -271.906524) (xy 276.872208 -271.939925)
			(xy 276.903302 -271.978894) (xy 276.927653 -272.022395) (xy 276.944615 -272.069274) (xy 276.949662 -272.09369)
			(xy 276.952964 -272.111978) (xy 276.980904 -272.135092) (xy 278.218138 -272.135092) (xy 278.246078 -272.111978)
			(xy 278.24938 -272.09369) (xy 278.254112 -272.070626) (xy 278.269724 -272.026209) (xy 278.291971 -271.984716)
			(xy 278.320324 -271.94713) (xy 278.354112 -271.914343) (xy 278.392533 -271.887133) (xy 278.434676 -271.866144)
			(xy 278.479542 -271.851874) (xy 278.526067 -271.844662) (xy 278.549608 -271.844262) (xy 278.5736 -271.844733)
			(xy 278.620992 -271.85224) (xy 278.666627 -271.867068) (xy 278.709381 -271.888851) (xy 278.748201 -271.917054)
			(xy 278.782131 -271.950982) (xy 278.810337 -271.9898) (xy 278.832124 -272.032553) (xy 278.846955 -272.078186)
			(xy 278.854465 -272.125578) (xy 278.854916 -272.14957) (xy 280.143724 -272.14957) (xy 280.147684 -272.100516)
			(xy 280.159461 -272.052732) (xy 280.178752 -272.007456) (xy 280.205055 -271.96586) (xy 280.23769 -271.929023)
			(xy 280.275811 -271.897898) (xy 280.318432 -271.873291) (xy 280.364448 -271.855839) (xy 280.412667 -271.845995)
			(xy 280.461842 -271.844014) (xy 280.510697 -271.849946) (xy 280.557968 -271.863638) (xy 280.60243 -271.884736)
			(xy 280.642933 -271.912692) (xy 280.678426 -271.946784) (xy 280.707991 -271.986128) (xy 280.730862 -272.029705)
			(xy 280.746446 -272.076386) (xy 280.754341 -272.124963) (xy 280.754836 -272.14957) (xy 280.754341 -272.174177)
			(xy 280.746446 -272.222754) (xy 280.730862 -272.269435) (xy 280.707991 -272.313012) (xy 280.678426 -272.352356)
			(xy 280.642933 -272.386448) (xy 280.60243 -272.414404) (xy 280.557968 -272.435502) (xy 280.510697 -272.449194)
			(xy 280.461842 -272.455126) (xy 280.412667 -272.453145) (xy 280.364448 -272.443301) (xy 280.318432 -272.425849)
			(xy 280.275811 -272.401242) (xy 280.23769 -272.370117) (xy 280.205055 -272.33328) (xy 280.178752 -272.291684)
			(xy 280.159461 -272.246408) (xy 280.147684 -272.198624) (xy 280.143724 -272.14957) (xy 278.854916 -272.14957)
			(xy 278.854493 -272.172531) (xy 278.847613 -272.217934) (xy 278.834032 -272.261802) (xy 278.824436 -272.282666)
			(xy 278.817324 -272.297398) (xy 278.822658 -272.329402) (xy 279.31999 -272.826734) (xy 279.351994 -272.832068)
			(xy 279.366726 -272.824956) (xy 279.387572 -272.815314) (xy 279.431442 -272.801713) (xy 279.476857 -272.79486)
			(xy 279.499822 -272.794476) (xy 279.523813 -272.794948) (xy 279.571203 -272.802457) (xy 279.616835 -272.817286)
			(xy 279.659585 -272.839071) (xy 279.698402 -272.867274) (xy 279.73233 -272.901202) (xy 279.760533 -272.94002)
			(xy 279.782316 -272.982771) (xy 279.797144 -273.028403) (xy 279.804652 -273.075793) (xy 279.80513 -273.099784)
			(xy 279.804688 -273.123129) (xy 279.804324 -273.125492) (xy 280.123134 -273.125492) (xy 280.123134 -273.074076)
			(xy 280.131177 -273.023294) (xy 280.147065 -272.974395) (xy 280.170408 -272.928583) (xy 280.200629 -272.886987)
			(xy 280.236985 -272.850631) (xy 280.278581 -272.82041) (xy 280.324393 -272.797067) (xy 280.373292 -272.781179)
			(xy 280.424074 -272.773136) (xy 280.47549 -272.773136) (xy 280.526272 -272.781179) (xy 280.575171 -272.797067)
			(xy 280.620983 -272.82041) (xy 280.662579 -272.850631) (xy 280.698935 -272.886987) (xy 280.729156 -272.928583)
			(xy 280.752499 -272.974395) (xy 280.768387 -273.023294) (xy 280.77643 -273.074076) (xy 280.776934 -273.099784)
			(xy 280.77643 -273.125492) (xy 280.768387 -273.176274) (xy 280.752499 -273.225173) (xy 280.729156 -273.270985)
			(xy 280.698935 -273.312581) (xy 280.662579 -273.348937) (xy 280.620983 -273.379158) (xy 280.575171 -273.402501)
			(xy 280.526272 -273.418389) (xy 280.47549 -273.426432) (xy 280.424074 -273.426432) (xy 280.373292 -273.418389)
			(xy 280.324393 -273.402501) (xy 280.278581 -273.379158) (xy 280.236985 -273.348937) (xy 280.200629 -273.312581)
			(xy 280.170408 -273.270985) (xy 280.147065 -273.225173) (xy 280.131177 -273.176274) (xy 280.123134 -273.125492)
			(xy 279.804324 -273.125492) (xy 279.797583 -273.169274) (xy 279.783534 -273.2138) (xy 279.762871 -273.255667)
			(xy 279.736075 -273.293901) (xy 279.70377 -273.32761) (xy 279.66671 -273.356008) (xy 279.625758 -273.378432)
			(xy 279.603962 -273.386804) (xy 279.588976 -273.392138) (xy 279.570688 -273.418554) (xy 279.570688 -273.730974)
			(xy 279.588976 -273.75739) (xy 279.603962 -273.762724) (xy 279.6272 -273.771682) (xy 279.670633 -273.796046)
			(xy 279.709537 -273.827135) (xy 279.742878 -273.864127) (xy 279.769774 -273.906039) (xy 279.789511 -273.951761)
			(xy 279.801566 -274.00008) (xy 279.805618 -274.049715) (xy 279.803514 -274.075452) (xy 280.123134 -274.075452)
			(xy 280.123134 -274.024036) (xy 280.131177 -273.973254) (xy 280.147065 -273.924355) (xy 280.170408 -273.878543)
			(xy 280.200629 -273.836947) (xy 280.236985 -273.800591) (xy 280.278581 -273.77037) (xy 280.324393 -273.747027)
			(xy 280.373292 -273.731139) (xy 280.424074 -273.723096) (xy 280.47549 -273.723096) (xy 280.526272 -273.731139)
			(xy 280.575171 -273.747027) (xy 280.620983 -273.77037) (xy 280.662579 -273.800591) (xy 280.698935 -273.836947)
			(xy 280.729156 -273.878543) (xy 280.752499 -273.924355) (xy 280.768387 -273.973254) (xy 280.77643 -274.024036)
			(xy 280.776934 -274.049744) (xy 280.77643 -274.075452) (xy 280.768387 -274.126234) (xy 280.752499 -274.175133)
			(xy 280.729156 -274.220945) (xy 280.698935 -274.262541) (xy 280.662579 -274.298897) (xy 280.620983 -274.329118)
			(xy 280.575171 -274.352461) (xy 280.526272 -274.368349) (xy 280.47549 -274.376392) (xy 280.424074 -274.376392)
			(xy 280.373292 -274.368349) (xy 280.324393 -274.352461) (xy 280.278581 -274.329118) (xy 280.236985 -274.298897)
			(xy 280.200629 -274.262541) (xy 280.170408 -274.220945) (xy 280.147065 -274.175133) (xy 280.131177 -274.126234)
			(xy 280.123134 -274.075452) (xy 279.803514 -274.075452) (xy 279.801561 -274.099349) (xy 279.789502 -274.147667)
			(xy 279.76976 -274.193387) (xy 279.74286 -274.235297) (xy 279.709515 -274.272285) (xy 279.670608 -274.303371)
			(xy 279.627173 -274.32773) (xy 279.603962 -274.336764) (xy 279.588976 -274.342098) (xy 279.570688 -274.368514)
			(xy 279.570688 -274.658582) (xy 279.589484 -274.684998) (xy 279.604978 -274.690332) (xy 279.628888 -274.698978)
			(xy 279.673906 -274.722606) (xy 279.714725 -274.752915) (xy 279.750364 -274.789174) (xy 279.779963 -274.830511)
			(xy 279.80281 -274.87593) (xy 279.818355 -274.924337) (xy 279.826223 -274.974566) (xy 279.826224 -274.999958)
			(xy 280.143978 -274.999958) (xy 280.147938 -274.950904) (xy 280.159715 -274.90312) (xy 280.179006 -274.857844)
			(xy 280.205309 -274.816248) (xy 280.237944 -274.779411) (xy 280.276065 -274.748286) (xy 280.318686 -274.723679)
			(xy 280.364702 -274.706227) (xy 280.412921 -274.696383) (xy 280.462096 -274.694402) (xy 280.510951 -274.700334)
			(xy 280.558222 -274.714026) (xy 280.602684 -274.735124) (xy 280.643187 -274.76308) (xy 280.67868 -274.797172)
			(xy 280.708245 -274.836516) (xy 280.731116 -274.880093) (xy 280.7467 -274.926774) (xy 280.754595 -274.975351)
			(xy 280.75509 -274.999958) (xy 280.754595 -275.024565) (xy 280.7467 -275.073142) (xy 280.731116 -275.119823)
			(xy 280.708245 -275.1634) (xy 280.67868 -275.202744) (xy 280.643187 -275.236836) (xy 280.602684 -275.264792)
			(xy 280.558222 -275.28589) (xy 280.510951 -275.299582) (xy 280.462096 -275.305514) (xy 280.412921 -275.303533)
			(xy 280.364702 -275.293689) (xy 280.318686 -275.276237) (xy 280.276065 -275.25163) (xy 280.237944 -275.220505)
			(xy 280.205309 -275.183668) (xy 280.179006 -275.142072) (xy 280.159715 -275.096796) (xy 280.147938 -275.049012)
			(xy 280.143978 -274.999958) (xy 279.826224 -274.999958) (xy 279.826226 -275.025407) (xy 279.818361 -275.075637)
			(xy 279.80282 -275.124045) (xy 279.779977 -275.169465) (xy 279.750381 -275.210805) (xy 279.714745 -275.247067)
			(xy 279.673928 -275.277379) (xy 279.628913 -275.301011) (xy 279.604978 -275.309584) (xy 279.589484 -275.314918)
			(xy 279.570688 -275.341334) (xy 279.570688 -275.608542) (xy 279.589484 -275.634958) (xy 279.604978 -275.640292)
			(xy 279.628884 -275.648938) (xy 279.673892 -275.672565) (xy 279.714702 -275.702871) (xy 279.750333 -275.739126)
			(xy 279.779924 -275.780457) (xy 279.802765 -275.825869) (xy 279.818304 -275.874269) (xy 279.826168 -275.924489)
			(xy 279.826167 -275.949918) (xy 280.143978 -275.949918) (xy 280.147938 -275.900864) (xy 280.159715 -275.85308)
			(xy 280.179006 -275.807804) (xy 280.205309 -275.766208) (xy 280.237944 -275.729371) (xy 280.276065 -275.698246)
			(xy 280.318686 -275.673639) (xy 280.364702 -275.656187) (xy 280.412921 -275.646343) (xy 280.462096 -275.644362)
			(xy 280.510951 -275.650294) (xy 280.558222 -275.663986) (xy 280.602684 -275.685084) (xy 280.643187 -275.71304)
			(xy 280.67868 -275.747132) (xy 280.708245 -275.786476) (xy 280.731116 -275.830053) (xy 280.7467 -275.876734)
			(xy 280.754595 -275.925311) (xy 280.75509 -275.949918) (xy 280.754595 -275.974525) (xy 280.7467 -276.023102)
			(xy 280.731116 -276.069783) (xy 280.708245 -276.11336) (xy 280.67868 -276.152704) (xy 280.643187 -276.186796)
			(xy 280.602684 -276.214752) (xy 280.558222 -276.23585) (xy 280.510951 -276.249542) (xy 280.462096 -276.255474)
			(xy 280.412921 -276.253493) (xy 280.364702 -276.243649) (xy 280.318686 -276.226197) (xy 280.276065 -276.20159)
			(xy 280.237944 -276.170465) (xy 280.205309 -276.133628) (xy 280.179006 -276.092032) (xy 280.159715 -276.046756)
			(xy 280.147938 -275.998972) (xy 280.143978 -275.949918) (xy 279.826167 -275.949918) (xy 279.826167 -275.975322)
			(xy 279.818302 -276.025543) (xy 279.802761 -276.073941) (xy 279.779918 -276.119353) (xy 279.750325 -276.160683)
			(xy 279.714694 -276.196937) (xy 279.673882 -276.227242) (xy 279.628873 -276.250867) (xy 279.604978 -276.259544)
			(xy 279.589484 -276.264878) (xy 279.570688 -276.291294) (xy 279.570688 -276.581108) (xy 279.588976 -276.607524)
			(xy 279.603962 -276.612858) (xy 279.627205 -276.621816) (xy 279.67065 -276.646181) (xy 279.709563 -276.677274)
			(xy 279.742914 -276.714271) (xy 279.769819 -276.75619) (xy 279.789563 -276.80192) (xy 279.801624 -276.850248)
			(xy 279.805679 -276.899878) (xy 280.143978 -276.899878) (xy 280.147938 -276.850824) (xy 280.159715 -276.80304)
			(xy 280.179006 -276.757764) (xy 280.205309 -276.716168) (xy 280.237944 -276.679331) (xy 280.276065 -276.648206)
			(xy 280.318686 -276.623599) (xy 280.364702 -276.606147) (xy 280.412921 -276.596303) (xy 280.462096 -276.594322)
			(xy 280.510951 -276.600254) (xy 280.558222 -276.613946) (xy 280.602684 -276.635044) (xy 280.643187 -276.663)
			(xy 280.67868 -276.697092) (xy 280.708245 -276.736436) (xy 280.731116 -276.780013) (xy 280.7467 -276.826694)
			(xy 280.754595 -276.875271) (xy 280.75509 -276.899878) (xy 280.754595 -276.924485) (xy 280.7467 -276.973062)
			(xy 280.731116 -277.019743) (xy 280.708245 -277.06332) (xy 280.67868 -277.102664) (xy 280.643187 -277.136756)
			(xy 280.602684 -277.164712) (xy 280.558222 -277.18581) (xy 280.510951 -277.199502) (xy 280.462096 -277.205434)
			(xy 280.412921 -277.203453) (xy 280.364702 -277.193609) (xy 280.318686 -277.176157) (xy 280.276065 -277.15155)
			(xy 280.237944 -277.120425) (xy 280.205309 -277.083588) (xy 280.179006 -277.041992) (xy 280.159715 -276.996716)
			(xy 280.147938 -276.948932) (xy 280.143978 -276.899878) (xy 279.805679 -276.899878) (xy 279.80568 -276.899892)
			(xy 279.801626 -276.949537) (xy 279.789568 -276.997866) (xy 279.769826 -277.043597) (xy 279.742924 -277.085517)
			(xy 279.709574 -277.122515) (xy 279.670662 -277.15361) (xy 279.627219 -277.177978) (xy 279.603962 -277.186898)
			(xy 279.588976 -277.192232) (xy 279.570688 -277.218648) (xy 279.570688 -277.531068) (xy 279.588976 -277.557484)
			(xy 279.603962 -277.562818) (xy 279.6272 -277.571776) (xy 279.670635 -277.59614) (xy 279.709539 -277.62723)
			(xy 279.742882 -277.664222) (xy 279.769778 -277.706135) (xy 279.789516 -277.751857) (xy 279.801571 -277.800177)
			(xy 279.805623 -277.849813) (xy 279.80352 -277.875546) (xy 280.123134 -277.875546) (xy 280.123134 -277.82413)
			(xy 280.131177 -277.773348) (xy 280.147065 -277.724449) (xy 280.170408 -277.678637) (xy 280.200629 -277.637041)
			(xy 280.236985 -277.600685) (xy 280.278581 -277.570464) (xy 280.324393 -277.547121) (xy 280.373292 -277.531233)
			(xy 280.424074 -277.52319) (xy 280.47549 -277.52319) (xy 280.526272 -277.531233) (xy 280.575171 -277.547121)
			(xy 280.620983 -277.570464) (xy 280.662579 -277.600685) (xy 280.698935 -277.637041) (xy 280.729156 -277.678637)
			(xy 280.752499 -277.724449) (xy 280.768387 -277.773348) (xy 280.77643 -277.82413) (xy 280.776934 -277.849838)
			(xy 280.77643 -277.875546) (xy 280.768387 -277.926328) (xy 280.752499 -277.975227) (xy 280.729156 -278.021039)
			(xy 280.698935 -278.062635) (xy 280.662579 -278.098991) (xy 280.620983 -278.129212) (xy 280.575171 -278.152555)
			(xy 280.526272 -278.168443) (xy 280.47549 -278.176486) (xy 280.424074 -278.176486) (xy 280.373292 -278.168443)
			(xy 280.324393 -278.152555) (xy 280.278581 -278.129212) (xy 280.236985 -278.098991) (xy 280.200629 -278.062635)
			(xy 280.170408 -278.021039) (xy 280.147065 -277.975227) (xy 280.131177 -277.926328) (xy 280.123134 -277.875546)
			(xy 279.80352 -277.875546) (xy 279.801567 -277.899448) (xy 279.789508 -277.947767) (xy 279.769766 -277.993488)
			(xy 279.742866 -278.035399) (xy 279.70952 -278.072388) (xy 279.670613 -278.103475) (xy 279.627177 -278.127834)
			(xy 279.603962 -278.136858) (xy 279.588976 -278.142192) (xy 279.570688 -278.168608) (xy 279.570688 -278.481028)
			(xy 279.588976 -278.507444) (xy 279.603962 -278.512778) (xy 279.627204 -278.521736) (xy 279.670644 -278.546101)
			(xy 279.709555 -278.577193) (xy 279.742903 -278.614188) (xy 279.769805 -278.656105) (xy 279.789547 -278.701832)
			(xy 279.801606 -278.750158) (xy 279.805661 -278.799799) (xy 279.803561 -278.825506) (xy 280.123134 -278.825506)
			(xy 280.123134 -278.77409) (xy 280.131177 -278.723308) (xy 280.147065 -278.674409) (xy 280.170408 -278.628597)
			(xy 280.200629 -278.587001) (xy 280.236985 -278.550645) (xy 280.278581 -278.520424) (xy 280.324393 -278.497081)
			(xy 280.373292 -278.481193) (xy 280.424074 -278.47315) (xy 280.47549 -278.47315) (xy 280.526272 -278.481193)
			(xy 280.575171 -278.497081) (xy 280.620983 -278.520424) (xy 280.662579 -278.550645) (xy 280.698935 -278.587001)
			(xy 280.729156 -278.628597) (xy 280.752499 -278.674409) (xy 280.768387 -278.723308) (xy 280.77643 -278.77409)
			(xy 280.776934 -278.799798) (xy 280.77643 -278.825506) (xy 280.768387 -278.876288) (xy 280.752499 -278.925187)
			(xy 280.729156 -278.970999) (xy 280.698935 -279.012595) (xy 280.662579 -279.048951) (xy 280.620983 -279.079172)
			(xy 280.575171 -279.102515) (xy 280.526272 -279.118403) (xy 280.47549 -279.126446) (xy 280.424074 -279.126446)
			(xy 280.373292 -279.118403) (xy 280.324393 -279.102515) (xy 280.278581 -279.079172) (xy 280.236985 -279.048951)
			(xy 280.200629 -279.012595) (xy 280.170408 -278.970999) (xy 280.147065 -278.925187) (xy 280.131177 -278.876288)
			(xy 280.123134 -278.825506) (xy 279.803561 -278.825506) (xy 279.801606 -278.849441) (xy 279.789547 -278.897766)
			(xy 279.769806 -278.943494) (xy 279.742904 -278.985411) (xy 279.709556 -279.022406) (xy 279.670646 -279.053498)
			(xy 279.627205 -279.077863) (xy 279.603962 -279.086818) (xy 279.588976 -279.092152) (xy 279.570688 -279.118568)
			(xy 279.570688 -279.408128) (xy 279.589484 -279.434544) (xy 279.604978 -279.439878) (xy 279.628885 -279.448524)
			(xy 279.673895 -279.472151) (xy 279.714708 -279.502458) (xy 279.75034 -279.538714) (xy 279.779933 -279.580047)
			(xy 279.802775 -279.62546) (xy 279.818316 -279.673861) (xy 279.826181 -279.724084) (xy 279.826181 -279.749758)
			(xy 280.143978 -279.749758) (xy 280.147938 -279.700704) (xy 280.159715 -279.65292) (xy 280.179006 -279.607644)
			(xy 280.205309 -279.566048) (xy 280.237944 -279.529211) (xy 280.276065 -279.498086) (xy 280.318686 -279.473479)
			(xy 280.364702 -279.456027) (xy 280.412921 -279.446183) (xy 280.462096 -279.444202) (xy 280.510951 -279.450134)
			(xy 280.558222 -279.463826) (xy 280.602684 -279.484924) (xy 280.643187 -279.51288) (xy 280.67868 -279.546972)
			(xy 280.708245 -279.586316) (xy 280.731116 -279.629893) (xy 280.7467 -279.676574) (xy 280.754595 -279.725151)
			(xy 280.75509 -279.749758) (xy 280.754595 -279.774365) (xy 280.7467 -279.822942) (xy 280.731116 -279.869623)
			(xy 280.708245 -279.9132) (xy 280.67868 -279.952544) (xy 280.643187 -279.986636) (xy 280.602684 -280.014592)
			(xy 280.558222 -280.03569) (xy 280.510951 -280.049382) (xy 280.462096 -280.055314) (xy 280.412921 -280.053333)
			(xy 280.364702 -280.043489) (xy 280.318686 -280.026037) (xy 280.276065 -280.00143) (xy 280.237944 -279.970305)
			(xy 280.205309 -279.933468) (xy 280.179006 -279.891872) (xy 280.159715 -279.846596) (xy 280.147938 -279.798812)
			(xy 280.143978 -279.749758) (xy 279.826181 -279.749758) (xy 279.826181 -279.774919) (xy 279.818316 -279.825141)
			(xy 279.802775 -279.873542) (xy 279.779932 -279.918956) (xy 279.750338 -279.960288) (xy 279.714706 -279.996544)
			(xy 279.673893 -280.02685) (xy 279.628882 -280.050477) (xy 279.604978 -280.05913) (xy 279.589484 -280.064464)
			(xy 279.570688 -280.09088) (xy 279.570688 -280.358342) (xy 279.589484 -280.384758) (xy 279.604978 -280.390092)
			(xy 279.628884 -280.398738) (xy 279.673892 -280.422365) (xy 279.714702 -280.452671) (xy 279.750333 -280.488926)
			(xy 279.779924 -280.530257) (xy 279.802765 -280.575669) (xy 279.818304 -280.624069) (xy 279.826168 -280.674289)
			(xy 279.826167 -280.699718) (xy 280.143978 -280.699718) (xy 280.147938 -280.650664) (xy 280.159715 -280.60288)
			(xy 280.179006 -280.557604) (xy 280.205309 -280.516008) (xy 280.237944 -280.479171) (xy 280.276065 -280.448046)
			(xy 280.318686 -280.423439) (xy 280.364702 -280.405987) (xy 280.412921 -280.396143) (xy 280.462096 -280.394162)
			(xy 280.510951 -280.400094) (xy 280.558222 -280.413786) (xy 280.602684 -280.434884) (xy 280.643187 -280.46284)
			(xy 280.67868 -280.496932) (xy 280.708245 -280.536276) (xy 280.731116 -280.579853) (xy 280.7467 -280.626534)
			(xy 280.754595 -280.675111) (xy 280.75509 -280.699718) (xy 280.754595 -280.724325) (xy 280.7467 -280.772902)
			(xy 280.731116 -280.819583) (xy 280.708245 -280.86316) (xy 280.67868 -280.902504) (xy 280.643187 -280.936596)
			(xy 280.602684 -280.964552) (xy 280.558222 -280.98565) (xy 280.510951 -280.999342) (xy 280.462096 -281.005274)
			(xy 280.412921 -281.003293) (xy 280.364702 -280.993449) (xy 280.318686 -280.975997) (xy 280.276065 -280.95139)
			(xy 280.237944 -280.920265) (xy 280.205309 -280.883428) (xy 280.179006 -280.841832) (xy 280.159715 -280.796556)
			(xy 280.147938 -280.748772) (xy 280.143978 -280.699718) (xy 279.826167 -280.699718) (xy 279.826167 -280.725122)
			(xy 279.818302 -280.775343) (xy 279.802761 -280.823741) (xy 279.779918 -280.869153) (xy 279.750325 -280.910483)
			(xy 279.714694 -280.946737) (xy 279.673882 -280.977042) (xy 279.628873 -281.000667) (xy 279.604978 -281.009344)
			(xy 279.589484 -281.014678) (xy 279.570688 -281.041094) (xy 279.570688 -281.331162) (xy 279.588976 -281.357578)
			(xy 279.603962 -281.362912) (xy 279.627201 -281.37187) (xy 279.670636 -281.396234) (xy 279.709542 -281.427324)
			(xy 279.742885 -281.464317) (xy 279.769782 -281.50623) (xy 279.789521 -281.551954) (xy 279.801576 -281.600274)
			(xy 279.805629 -281.649911) (xy 279.805627 -281.649932) (xy 280.143978 -281.649932) (xy 280.147938 -281.600878)
			(xy 280.159715 -281.553094) (xy 280.179006 -281.507818) (xy 280.205309 -281.466222) (xy 280.237944 -281.429385)
			(xy 280.276065 -281.39826) (xy 280.318686 -281.373653) (xy 280.364702 -281.356201) (xy 280.412921 -281.346357)
			(xy 280.462096 -281.344376) (xy 280.510951 -281.350308) (xy 280.558222 -281.364) (xy 280.602684 -281.385098)
			(xy 280.643187 -281.413054) (xy 280.67868 -281.447146) (xy 280.708245 -281.48649) (xy 280.731116 -281.530067)
			(xy 280.7467 -281.576748) (xy 280.754595 -281.625325) (xy 280.75509 -281.649932) (xy 280.754595 -281.674539)
			(xy 280.7467 -281.723116) (xy 280.731116 -281.769797) (xy 280.708245 -281.813374) (xy 280.67868 -281.852718)
			(xy 280.643187 -281.88681) (xy 280.602684 -281.914766) (xy 280.558222 -281.935864) (xy 280.510951 -281.949556)
			(xy 280.462096 -281.955488) (xy 280.412921 -281.953507) (xy 280.364702 -281.943663) (xy 280.318686 -281.926211)
			(xy 280.276065 -281.901604) (xy 280.237944 -281.870479) (xy 280.205309 -281.833642) (xy 280.179006 -281.792046)
			(xy 280.159715 -281.74677) (xy 280.147938 -281.698986) (xy 280.143978 -281.649932) (xy 279.805627 -281.649932)
			(xy 279.801572 -281.699547) (xy 279.789514 -281.747867) (xy 279.769772 -281.793589) (xy 279.742872 -281.835501)
			(xy 279.709526 -281.872491) (xy 279.670618 -281.903578) (xy 279.627181 -281.927939) (xy 279.603962 -281.936952)
			(xy 279.588976 -281.942286) (xy 279.570688 -281.968702) (xy 279.570688 -282.802838) (xy 279.571093 -282.813094)
			(xy 279.579037 -282.831998) (xy 279.593788 -282.846242) (xy 279.6032 -282.850336) (xy 279.706578 -282.88996)
			(xy 279.737058 -282.882594) (xy 279.747726 -282.87091) (xy 279.76523 -282.852183) (xy 279.805353 -282.820284)
			(xy 279.850243 -282.79554) (xy 279.898636 -282.778647) (xy 279.949173 -282.77008) (xy 279.974802 -282.769564)
			(xy 280.00006 -282.770086) (xy 280.049886 -282.778401) (xy 280.097664 -282.794803) (xy 280.14209 -282.818846)
			(xy 280.181953 -282.849873) (xy 280.216166 -282.887038) (xy 280.243795 -282.929328) (xy 280.264087 -282.975588)
			(xy 280.276488 -283.024557) (xy 280.280657 -283.074872) (xy 280.618958 -283.074872) (xy 280.622918 -283.025818)
			(xy 280.634695 -282.978034) (xy 280.653986 -282.932758) (xy 280.680289 -282.891162) (xy 280.712924 -282.854325)
			(xy 280.751045 -282.8232) (xy 280.793666 -282.798593) (xy 280.839682 -282.781141) (xy 280.887901 -282.771297)
			(xy 280.937076 -282.769316) (xy 280.985931 -282.775248) (xy 281.033202 -282.78894) (xy 281.077664 -282.810038)
			(xy 281.118167 -282.837994) (xy 281.15366 -282.872086) (xy 281.183225 -282.91143) (xy 281.206096 -282.955007)
			(xy 281.22168 -283.001688) (xy 281.229575 -283.050265) (xy 281.23007 -283.074872) (xy 281.229575 -283.099479)
			(xy 281.22168 -283.148056) (xy 281.206096 -283.194737) (xy 281.183225 -283.238314) (xy 281.15366 -283.277658)
			(xy 281.118167 -283.31175) (xy 281.077664 -283.339706) (xy 281.033202 -283.360804) (xy 280.985931 -283.374496)
			(xy 280.937076 -283.380428) (xy 280.887901 -283.378447) (xy 280.839682 -283.368603) (xy 280.793666 -283.351151)
			(xy 280.751045 -283.326544) (xy 280.712924 -283.295419) (xy 280.680289 -283.258582) (xy 280.653986 -283.216986)
			(xy 280.634695 -283.17171) (xy 280.622918 -283.123926) (xy 280.618958 -283.074872) (xy 280.280657 -283.074872)
			(xy 280.280659 -283.0749) (xy 280.276488 -283.125243) (xy 280.264087 -283.174212) (xy 280.243795 -283.220472)
			(xy 280.216166 -283.262762) (xy 280.181953 -283.299927) (xy 280.14209 -283.330954) (xy 280.097664 -283.354997)
			(xy 280.049886 -283.371399) (xy 280.00006 -283.379714) (xy 279.974802 -283.38018) (xy 279.949173 -283.379655)
			(xy 279.898637 -283.37109) (xy 279.850243 -283.354199) (xy 279.805352 -283.329458) (xy 279.765227 -283.297563)
			(xy 279.747726 -283.278834) (xy 279.737058 -283.26715) (xy 279.706578 -283.259784) (xy 279.6032 -283.299408)
			(xy 279.593818 -283.303544) (xy 279.579114 -283.317806) (xy 279.571113 -283.336664) (xy 279.570688 -283.346906)
			(xy 279.570688 -283.752798) (xy 279.571086 -283.763058) (xy 279.579022 -283.781975) (xy 279.593772 -283.796232)
			(xy 279.6032 -283.800296) (xy 279.706578 -283.83992) (xy 279.737058 -283.832554) (xy 279.747726 -283.82087)
			(xy 279.765231 -283.802145) (xy 279.805355 -283.77025) (xy 279.850245 -283.74551) (xy 279.898638 -283.728619)
			(xy 279.949174 -283.720053) (xy 279.974802 -283.719524) (xy 280.000055 -283.720046) (xy 280.049871 -283.728359)
			(xy 280.097639 -283.744758) (xy 280.142057 -283.768796) (xy 280.181913 -283.799817) (xy 280.216119 -283.836975)
			(xy 280.243742 -283.879256) (xy 280.26403 -283.925508) (xy 280.276428 -283.974467) (xy 280.280599 -284.0248)
			(xy 280.280596 -284.024832) (xy 280.618958 -284.024832) (xy 280.622918 -283.975778) (xy 280.634695 -283.927994)
			(xy 280.653986 -283.882718) (xy 280.680289 -283.841122) (xy 280.712924 -283.804285) (xy 280.751045 -283.77316)
			(xy 280.793666 -283.748553) (xy 280.839682 -283.731101) (xy 280.887901 -283.721257) (xy 280.937076 -283.719276)
			(xy 280.985931 -283.725208) (xy 281.033202 -283.7389) (xy 281.077664 -283.759998) (xy 281.118167 -283.787954)
			(xy 281.15366 -283.822046) (xy 281.183225 -283.86139) (xy 281.206096 -283.904967) (xy 281.22168 -283.951648)
			(xy 281.229575 -284.000225) (xy 281.23007 -284.024832) (xy 281.229575 -284.049439) (xy 281.22168 -284.098016)
			(xy 281.206096 -284.144697) (xy 281.183225 -284.188274) (xy 281.15366 -284.227618) (xy 281.118167 -284.26171)
			(xy 281.077664 -284.289666) (xy 281.033202 -284.310764) (xy 280.985931 -284.324456) (xy 280.937076 -284.330388)
			(xy 280.887901 -284.328407) (xy 280.839682 -284.318563) (xy 280.793666 -284.301111) (xy 280.751045 -284.276504)
			(xy 280.712924 -284.245379) (xy 280.680289 -284.208542) (xy 280.653986 -284.166946) (xy 280.634695 -284.12167)
			(xy 280.622918 -284.073886) (xy 280.618958 -284.024832) (xy 280.280596 -284.024832) (xy 280.276428 -284.075133)
			(xy 280.26403 -284.124092) (xy 280.243742 -284.170344) (xy 280.216119 -284.212625) (xy 280.181913 -284.249783)
			(xy 280.142057 -284.280804) (xy 280.097639 -284.304842) (xy 280.049871 -284.321241) (xy 280.000055 -284.329554)
			(xy 279.974802 -284.33014) (xy 279.949174 -284.329615) (xy 279.898639 -284.321049) (xy 279.850246 -284.304156)
			(xy 279.805357 -284.279413) (xy 279.765235 -284.247516) (xy 279.747726 -284.228794) (xy 279.737058 -284.21711)
			(xy 279.706578 -284.209744) (xy 279.6032 -284.249368) (xy 279.593825 -284.253507) (xy 279.579138 -284.267772)
			(xy 279.571158 -284.286629) (xy 279.570688 -284.296866) (xy 279.570688 -284.702758) (xy 279.571097 -284.713012)
			(xy 279.579045 -284.731909) (xy 279.593796 -284.746147) (xy 279.6032 -284.750256) (xy 279.706578 -284.78988)
			(xy 279.737058 -284.782514) (xy 279.747726 -284.77083) (xy 279.76523 -284.752102) (xy 279.805352 -284.720201)
			(xy 279.850241 -284.695455) (xy 279.898635 -284.678561) (xy 279.949173 -284.669994) (xy 279.974802 -284.669484)
			(xy 280.000058 -284.670006) (xy 280.049881 -284.67832) (xy 280.097655 -284.694721) (xy 280.142079 -284.718763)
			(xy 280.18194 -284.749788) (xy 280.21615 -284.78695) (xy 280.243778 -284.829237) (xy 280.264068 -284.875495)
			(xy 280.276468 -284.924461) (xy 280.280638 -284.974792) (xy 280.618958 -284.974792) (xy 280.622918 -284.925738)
			(xy 280.634695 -284.877954) (xy 280.653986 -284.832678) (xy 280.680289 -284.791082) (xy 280.712924 -284.754245)
			(xy 280.751045 -284.72312) (xy 280.793666 -284.698513) (xy 280.839682 -284.681061) (xy 280.887901 -284.671217)
			(xy 280.937076 -284.669236) (xy 280.985931 -284.675168) (xy 281.033202 -284.68886) (xy 281.077664 -284.709958)
			(xy 281.118167 -284.737914) (xy 281.15366 -284.772006) (xy 281.183225 -284.81135) (xy 281.206096 -284.854927)
			(xy 281.22168 -284.901608) (xy 281.229575 -284.950185) (xy 281.23007 -284.974792) (xy 281.229575 -284.999399)
			(xy 281.22168 -285.047976) (xy 281.206096 -285.094657) (xy 281.183225 -285.138234) (xy 281.15366 -285.177578)
			(xy 281.118167 -285.21167) (xy 281.077664 -285.239626) (xy 281.033202 -285.260724) (xy 280.985931 -285.274416)
			(xy 280.937076 -285.280348) (xy 280.887901 -285.278367) (xy 280.839682 -285.268523) (xy 280.793666 -285.251071)
			(xy 280.751045 -285.226464) (xy 280.712924 -285.195339) (xy 280.680289 -285.158502) (xy 280.653986 -285.116906)
			(xy 280.634695 -285.07163) (xy 280.622918 -285.023846) (xy 280.618958 -284.974792) (xy 280.280638 -284.974792)
			(xy 280.280639 -284.9748) (xy 280.276468 -285.025139) (xy 280.264068 -285.074105) (xy 280.243778 -285.120363)
			(xy 280.21615 -285.16265) (xy 280.18194 -285.199812) (xy 280.142079 -285.230837) (xy 280.097655 -285.254879)
			(xy 280.049881 -285.27128) (xy 280.000058 -285.279594) (xy 279.974802 -285.2801) (xy 279.949173 -285.279575)
			(xy 279.898637 -285.27101) (xy 279.850242 -285.25412) (xy 279.80535 -285.229381) (xy 279.765224 -285.197487)
			(xy 279.747726 -285.178754) (xy 279.737058 -285.16707) (xy 279.706578 -285.159704) (xy 279.6032 -285.199328)
			(xy 279.593821 -285.203465) (xy 279.579122 -285.217728) (xy 279.571129 -285.236586) (xy 279.570688 -285.246826)
			(xy 279.570688 -285.652718) (xy 279.571089 -285.662976) (xy 279.579029 -285.681887) (xy 279.59378 -285.696137)
			(xy 279.6032 -285.700216) (xy 279.706578 -285.73984) (xy 279.737058 -285.732474) (xy 279.747726 -285.72079)
			(xy 279.765231 -285.702064) (xy 279.805354 -285.670167) (xy 279.850244 -285.645425) (xy 279.898637 -285.628533)
			(xy 279.949174 -285.619967) (xy 279.974802 -285.619444) (xy 280.000061 -285.619965) (xy 280.049891 -285.628281)
			(xy 280.097672 -285.644684) (xy 280.142101 -285.668729) (xy 280.181967 -285.699758) (xy 280.216182 -285.736926)
			(xy 280.243813 -285.779218) (xy 280.264106 -285.825481) (xy 280.276508 -285.874454) (xy 280.280676 -285.924752)
			(xy 280.618958 -285.924752) (xy 280.622918 -285.875698) (xy 280.634695 -285.827914) (xy 280.653986 -285.782638)
			(xy 280.680289 -285.741042) (xy 280.712924 -285.704205) (xy 280.751045 -285.67308) (xy 280.793666 -285.648473)
			(xy 280.839682 -285.631021) (xy 280.887901 -285.621177) (xy 280.937076 -285.619196) (xy 280.985931 -285.625128)
			(xy 281.033202 -285.63882) (xy 281.077664 -285.659918) (xy 281.118167 -285.687874) (xy 281.15366 -285.721966)
			(xy 281.183225 -285.76131) (xy 281.206096 -285.804887) (xy 281.22168 -285.851568) (xy 281.229575 -285.900145)
			(xy 281.23007 -285.924752) (xy 281.229575 -285.949359) (xy 281.22168 -285.997936) (xy 281.206096 -286.044617)
			(xy 281.183225 -286.088194) (xy 281.15366 -286.127538) (xy 281.118167 -286.16163) (xy 281.077664 -286.189586)
			(xy 281.033202 -286.210684) (xy 280.985931 -286.224376) (xy 280.937076 -286.230308) (xy 280.887901 -286.228327)
			(xy 280.839682 -286.218483) (xy 280.793666 -286.201031) (xy 280.751045 -286.176424) (xy 280.712924 -286.145299)
			(xy 280.680289 -286.108462) (xy 280.653986 -286.066866) (xy 280.634695 -286.02159) (xy 280.622918 -285.973806)
			(xy 280.618958 -285.924752) (xy 280.280676 -285.924752) (xy 280.28068 -285.9248) (xy 280.276508 -285.975146)
			(xy 280.264106 -286.024119) (xy 280.243813 -286.070382) (xy 280.216182 -286.112674) (xy 280.181967 -286.149842)
			(xy 280.142101 -286.180871) (xy 280.097672 -286.204916) (xy 280.049891 -286.221319) (xy 280.000061 -286.229635)
			(xy 279.974802 -286.23006) (xy 279.949174 -286.229535) (xy 279.898638 -286.220969) (xy 279.850244 -286.204078)
			(xy 279.805355 -286.179336) (xy 279.765231 -286.14744) (xy 279.747726 -286.128714) (xy 279.737058 -286.11703)
			(xy 279.706578 -286.109664) (xy 279.6032 -286.149288) (xy 279.593816 -286.153423) (xy 279.579107 -286.167684)
			(xy 279.571099 -286.186543) (xy 279.570688 -286.196786) (xy 279.570688 -286.602932) (xy 279.571092 -286.613189)
			(xy 279.579035 -286.632094) (xy 279.593785 -286.646341) (xy 279.6032 -286.65043) (xy 279.706578 -286.690054)
			(xy 279.737058 -286.682688) (xy 279.747726 -286.671004) (xy 279.76523 -286.652277) (xy 279.805353 -286.620379)
			(xy 279.850243 -286.595636) (xy 279.898637 -286.578743) (xy 279.949173 -286.570176) (xy 279.974802 -286.569658)
			(xy 280.00006 -286.57018) (xy 280.049887 -286.578495) (xy 280.097666 -286.594898) (xy 280.142093 -286.618941)
			(xy 280.181958 -286.649969) (xy 280.216171 -286.687134) (xy 280.243801 -286.729425) (xy 280.264093 -286.775686)
			(xy 280.276493 -286.824656) (xy 280.280662 -286.874966) (xy 280.618958 -286.874966) (xy 280.622918 -286.825912)
			(xy 280.634695 -286.778128) (xy 280.653986 -286.732852) (xy 280.680289 -286.691256) (xy 280.712924 -286.654419)
			(xy 280.751045 -286.623294) (xy 280.793666 -286.598687) (xy 280.839682 -286.581235) (xy 280.887901 -286.571391)
			(xy 280.937076 -286.56941) (xy 280.985931 -286.575342) (xy 281.033202 -286.589034) (xy 281.077664 -286.610132)
			(xy 281.118167 -286.638088) (xy 281.15366 -286.67218) (xy 281.183225 -286.711524) (xy 281.206096 -286.755101)
			(xy 281.22168 -286.801782) (xy 281.229575 -286.850359) (xy 281.23007 -286.874966) (xy 281.229575 -286.899573)
			(xy 281.22168 -286.94815) (xy 281.206096 -286.994831) (xy 281.183225 -287.038408) (xy 281.15366 -287.077752)
			(xy 281.118167 -287.111844) (xy 281.077664 -287.1398) (xy 281.033202 -287.160898) (xy 280.985931 -287.17459)
			(xy 280.937076 -287.180522) (xy 280.887901 -287.178541) (xy 280.839682 -287.168697) (xy 280.793666 -287.151245)
			(xy 280.751045 -287.126638) (xy 280.712924 -287.095513) (xy 280.680289 -287.058676) (xy 280.653986 -287.01708)
			(xy 280.634695 -286.971804) (xy 280.622918 -286.92402) (xy 280.618958 -286.874966) (xy 280.280662 -286.874966)
			(xy 280.280665 -286.875) (xy 280.276493 -286.925344) (xy 280.264093 -286.974314) (xy 280.243801 -287.020575)
			(xy 280.216171 -287.062866) (xy 280.181958 -287.100031) (xy 280.142093 -287.131059) (xy 280.097666 -287.155102)
			(xy 280.049887 -287.171505) (xy 280.00006 -287.17982) (xy 279.974802 -287.180274) (xy 279.949174 -287.179749)
			(xy 279.898637 -287.171183) (xy 279.850244 -287.154293) (xy 279.805353 -287.129551) (xy 279.765229 -287.097656)
			(xy 279.747726 -287.078928) (xy 279.737058 -287.067244) (xy 279.706578 -287.059878) (xy 279.6032 -287.099502)
			(xy 279.593818 -287.103637) (xy 279.579112 -287.1179) (xy 279.571109 -287.136758) (xy 279.570688 -287.147)
			(xy 279.570688 -287.552892) (xy 279.571085 -287.563153) (xy 279.579019 -287.582072) (xy 279.593769 -287.596331)
			(xy 279.6032 -287.60039) (xy 279.706578 -287.640014) (xy 279.737058 -287.632648) (xy 279.747726 -287.620964)
			(xy 279.765229 -287.602234) (xy 279.805349 -287.57033) (xy 279.850239 -287.545581) (xy 279.898634 -287.528685)
			(xy 279.949172 -287.520117) (xy 279.974802 -287.519618) (xy 280.000055 -287.52014) (xy 280.049872 -287.528453)
			(xy 280.097642 -287.544853) (xy 280.142061 -287.568891) (xy 280.181917 -287.599913) (xy 280.216124 -287.637071)
			(xy 280.243748 -287.679353) (xy 280.264036 -287.725606) (xy 280.276434 -287.774566) (xy 280.280605 -287.8249)
			(xy 280.280603 -287.824926) (xy 280.618958 -287.824926) (xy 280.622918 -287.775872) (xy 280.634695 -287.728088)
			(xy 280.653986 -287.682812) (xy 280.680289 -287.641216) (xy 280.712924 -287.604379) (xy 280.751045 -287.573254)
			(xy 280.793666 -287.548647) (xy 280.839682 -287.531195) (xy 280.887901 -287.521351) (xy 280.937076 -287.51937)
			(xy 280.985931 -287.525302) (xy 281.033202 -287.538994) (xy 281.077664 -287.560092) (xy 281.118167 -287.588048)
			(xy 281.15366 -287.62214) (xy 281.183225 -287.661484) (xy 281.206096 -287.705061) (xy 281.22168 -287.751742)
			(xy 281.229575 -287.800319) (xy 281.23007 -287.824926) (xy 281.229575 -287.849533) (xy 281.22168 -287.89811)
			(xy 281.206096 -287.944791) (xy 281.183225 -287.988368) (xy 281.15366 -288.027712) (xy 281.118167 -288.061804)
			(xy 281.077664 -288.08976) (xy 281.033202 -288.110858) (xy 280.985931 -288.12455) (xy 280.937076 -288.130482)
			(xy 280.887901 -288.128501) (xy 280.839682 -288.118657) (xy 280.793666 -288.101205) (xy 280.751045 -288.076598)
			(xy 280.712924 -288.045473) (xy 280.680289 -288.008636) (xy 280.653986 -287.96704) (xy 280.634695 -287.921764)
			(xy 280.622918 -287.87398) (xy 280.618958 -287.824926) (xy 280.280603 -287.824926) (xy 280.276434 -287.875234)
			(xy 280.264036 -287.924194) (xy 280.243748 -287.970447) (xy 280.216124 -288.012729) (xy 280.181917 -288.049887)
			(xy 280.142061 -288.080909) (xy 280.097642 -288.104947) (xy 280.049872 -288.121347) (xy 280.000055 -288.12966)
			(xy 279.974802 -288.130234) (xy 279.949174 -288.129709) (xy 279.898639 -288.121142) (xy 279.850246 -288.10425)
			(xy 279.805358 -288.079507) (xy 279.765237 -288.047609) (xy 279.747726 -288.028888) (xy 279.737058 -288.017204)
			(xy 279.706578 -288.009838) (xy 279.6032 -288.049462) (xy 279.593824 -288.0536) (xy 279.579135 -288.067866)
			(xy 279.571153 -288.086722) (xy 279.570688 -288.09696) (xy 279.570688 -288.381694) (xy 279.570151 -288.391682)
			(xy 279.562438 -288.410114) (xy 279.555702 -288.417508) (xy 279.520904 -288.45256) (xy 279.514102 -288.459908)
			(xy 279.506391 -288.478371) (xy 279.505918 -288.488374) (xy 279.505918 -288.764218) (xy 279.506345 -288.774286)
			(xy 279.514066 -288.792884) (xy 279.520904 -288.800286) (xy 279.586436 -288.865818) (xy 279.593779 -288.872632)
			(xy 279.612243 -288.880364) (xy 279.62225 -288.880804) (xy 279.623012 -288.880804) (xy 279.633018 -288.880314)
			(xy 279.651507 -288.872652) (xy 279.665657 -288.8585) (xy 279.673315 -288.84001) (xy 279.673812 -288.830004)
			(xy 279.673812 -288.82594) (xy 279.67305 -288.82213) (xy 279.671356 -288.810393) (xy 279.669577 -288.786744)
			(xy 279.669494 -288.774886) (xy 279.670016 -288.749631) (xy 279.678329 -288.699809) (xy 279.69473 -288.652035)
			(xy 279.718771 -288.607612) (xy 279.749795 -288.567752) (xy 279.786957 -288.533542) (xy 279.829243 -288.505916)
			(xy 279.875499 -288.485626) (xy 279.924464 -288.473226) (xy 279.974802 -288.469055) (xy 280.02514 -288.473226)
			(xy 280.074105 -288.485626) (xy 280.120361 -288.505916) (xy 280.162647 -288.533542) (xy 280.199809 -288.567752)
			(xy 280.230833 -288.607612) (xy 280.254874 -288.652035) (xy 280.271275 -288.699809) (xy 280.279588 -288.749631)
			(xy 280.28011 -288.774886) (xy 280.279624 -288.799717) (xy 280.271584 -288.848722) (xy 280.255713 -288.895779)
			(xy 280.232431 -288.939645) (xy 280.202353 -288.97916) (xy 280.166272 -289.013283) (xy 280.125141 -289.041113)
			(xy 280.102818 -289.052) (xy 280.093319 -289.056887) (xy 280.079246 -289.072933) (xy 280.07564 -289.082988)
			(xy 280.065734 -289.11423) (xy 280.06307 -289.124471) (xy 280.065437 -289.145474) (xy 280.070306 -289.15487)
			(xy 280.07564 -289.164776) (xy 280.082244 -289.177222) (xy 280.10612 -289.1917)
		)
		(stroke
			(width 0)
			(type solid)
		)
		(fill yes)
		(layer "In13.Cu")
		(net "P1V8_VDDA_PEX2")
	)
	(gr_poly
		(pts
			(xy 267.599922 -303.919128) (xy 267.610706 -303.918638) (xy 267.630385 -303.909811) (xy 267.644735 -303.893708)
			(xy 267.648436 -303.883568) (xy 267.65607 -303.860583) (xy 267.677579 -303.817192) (xy 267.705676 -303.777746)
			(xy 267.739655 -303.743238) (xy 267.778662 -303.714534) (xy 267.821716 -303.692358) (xy 267.867734 -303.677266)
			(xy 267.915559 -303.669638) (xy 267.939774 -303.669192) (xy 267.965134 -303.669692) (xy 268.015157 -303.678075)
			(xy 268.063104 -303.694615) (xy 268.107657 -303.718856) (xy 268.147587 -303.75013) (xy 268.165072 -303.768506)
			(xy 268.165326 -303.76876) (xy 268.165834 -303.769268) (xy 268.173547 -303.776795) (xy 268.193414 -303.785095)
			(xy 268.204188 -303.78527) (xy 268.292072 -303.782984) (xy 268.31163 -303.773332) (xy 268.318742 -303.764696)
			(xy 268.334557 -303.746108) (xy 268.370714 -303.71333) (xy 268.411289 -303.68621) (xy 268.455402 -303.665334)
			(xy 268.5021 -303.651155) (xy 268.550373 -303.643978) (xy 268.574774 -303.643538) (xy 268.645132 -303.643538)
			(xy 268.655786 -303.643071) (xy 268.675238 -303.634372) (xy 268.682724 -303.626774) (xy 268.740636 -303.562512)
			(xy 268.74724 -303.542192) (xy 268.74597 -303.531524) (xy 268.744446 -303.499774) (xy 268.744968 -303.474519)
			(xy 268.753281 -303.424697) (xy 268.769682 -303.376923) (xy 268.793723 -303.3325) (xy 268.824747 -303.29264)
			(xy 268.861909 -303.25843) (xy 268.904195 -303.230804) (xy 268.950451 -303.210514) (xy 268.999416 -303.198114)
			(xy 269.049754 -303.193943) (xy 269.100092 -303.198114) (xy 269.149057 -303.210514) (xy 269.195313 -303.230804)
			(xy 269.237599 -303.25843) (xy 269.274761 -303.29264) (xy 269.305785 -303.3325) (xy 269.329826 -303.376923)
			(xy 269.346227 -303.424697) (xy 269.35454 -303.474519) (xy 269.355062 -303.499774) (xy 269.353538 -303.531524)
			(xy 269.352268 -303.542192) (xy 269.358872 -303.562512) (xy 269.416784 -303.626774) (xy 269.424328 -303.634284)
			(xy 269.443748 -303.642947) (xy 269.454376 -303.643538) (xy 269.456154 -303.643538) (xy 269.456154 -303.643792)
			(xy 269.524734 -303.643792) (xy 269.538388 -303.643953) (xy 269.565601 -303.646239) (xy 269.57909 -303.648364)
			(xy 269.591028 -303.650396) (xy 269.613634 -303.643284) (xy 269.690088 -303.570386) (xy 269.697962 -303.548034)
			(xy 269.696438 -303.536096) (xy 269.695448 -303.527049) (xy 269.694428 -303.508875) (xy 269.694406 -303.499774)
			(xy 269.694928 -303.474519) (xy 269.703241 -303.424697) (xy 269.719642 -303.376923) (xy 269.743683 -303.3325)
			(xy 269.774707 -303.29264) (xy 269.811869 -303.25843) (xy 269.854155 -303.230804) (xy 269.900411 -303.210514)
			(xy 269.949376 -303.198114) (xy 269.999714 -303.193943) (xy 270.050052 -303.198114) (xy 270.099017 -303.210514)
			(xy 270.145273 -303.230804) (xy 270.187559 -303.25843) (xy 270.224721 -303.29264) (xy 270.255745 -303.3325)
			(xy 270.279786 -303.376923) (xy 270.296187 -303.424697) (xy 270.3045 -303.474519) (xy 270.305022 -303.499774)
			(xy 270.30493 -303.508942) (xy 270.303788 -303.527242) (xy 270.302736 -303.53635) (xy 270.301466 -303.548288)
			(xy 270.30934 -303.57064) (xy 270.385794 -303.643538) (xy 270.4084 -303.65065) (xy 270.420338 -303.648618)
			(xy 270.443161 -303.645146) (xy 270.489306 -303.643873) (xy 270.512286 -303.646078) (xy 270.52397 -303.647602)
			(xy 270.54556 -303.639982) (xy 270.618204 -303.567592) (xy 270.626078 -303.546002) (xy 270.624808 -303.534318)
			(xy 270.622776 -303.499774) (xy 270.62328 -303.474066) (xy 270.631323 -303.423284) (xy 270.647211 -303.374385)
			(xy 270.670554 -303.328573) (xy 270.700775 -303.286977) (xy 270.737131 -303.250621) (xy 270.778727 -303.2204)
			(xy 270.824539 -303.197057) (xy 270.873438 -303.181169) (xy 270.92422 -303.173126) (xy 270.975636 -303.173126)
			(xy 271.026418 -303.181169) (xy 271.075317 -303.197057) (xy 271.121129 -303.2204) (xy 271.162725 -303.250621)
			(xy 271.199081 -303.286977) (xy 271.229302 -303.328573) (xy 271.252645 -303.374385) (xy 271.268533 -303.423284)
			(xy 271.276576 -303.474066) (xy 271.27708 -303.499774) (xy 271.275048 -303.534572) (xy 271.273778 -303.546256)
			(xy 271.281398 -303.567846) (xy 271.354296 -303.640236) (xy 271.375886 -303.647856) (xy 271.38757 -303.646332)
			(xy 271.396874 -303.645362) (xy 271.415554 -303.644343) (xy 271.424908 -303.6443) (xy 271.434262 -303.644343)
			(xy 271.452942 -303.64536) (xy 271.462246 -303.646332) (xy 271.47393 -303.647856) (xy 271.49552 -303.640236)
			(xy 271.568418 -303.567846) (xy 271.576038 -303.546256) (xy 271.574768 -303.534572) (xy 271.572736 -303.499774)
			(xy 271.57324 -303.474066) (xy 271.581283 -303.423284) (xy 271.597171 -303.374385) (xy 271.620514 -303.328573)
			(xy 271.650735 -303.286977) (xy 271.687091 -303.250621) (xy 271.728687 -303.2204) (xy 271.774499 -303.197057)
			(xy 271.823398 -303.181169) (xy 271.87418 -303.173126) (xy 271.925596 -303.173126) (xy 271.976378 -303.181169)
			(xy 272.025277 -303.197057) (xy 272.071089 -303.2204) (xy 272.112685 -303.250621) (xy 272.149041 -303.286977)
			(xy 272.179262 -303.328573) (xy 272.202605 -303.374385) (xy 272.218493 -303.423284) (xy 272.226536 -303.474066)
			(xy 272.22704 -303.499774) (xy 272.225008 -303.534572) (xy 272.223738 -303.546256) (xy 272.231358 -303.567846)
			(xy 272.304256 -303.640236) (xy 272.325846 -303.647856) (xy 272.33753 -303.646332) (xy 272.346834 -303.645362)
			(xy 272.365514 -303.644344) (xy 272.374868 -303.6443) (xy 272.388522 -303.644462) (xy 272.415735 -303.646751)
			(xy 272.429224 -303.648872) (xy 272.441162 -303.650904) (xy 272.463768 -303.643792) (xy 272.540222 -303.57064)
			(xy 272.548096 -303.548542) (xy 272.546826 -303.53635) (xy 272.54577 -303.527243) (xy 272.544624 -303.508942)
			(xy 272.54454 -303.499774) (xy 272.545062 -303.474519) (xy 272.553375 -303.424697) (xy 272.569776 -303.376923)
			(xy 272.593817 -303.3325) (xy 272.624841 -303.29264) (xy 272.662003 -303.25843) (xy 272.704289 -303.230804)
			(xy 272.750545 -303.210514) (xy 272.79951 -303.198114) (xy 272.849848 -303.193943) (xy 272.900186 -303.198114)
			(xy 272.949151 -303.210514) (xy 272.995407 -303.230804) (xy 273.037693 -303.25843) (xy 273.074855 -303.29264)
			(xy 273.105879 -303.3325) (xy 273.12992 -303.376923) (xy 273.146321 -303.424697) (xy 273.154634 -303.474519)
			(xy 273.155156 -303.499774) (xy 273.155057 -303.508878) (xy 273.153912 -303.527051) (xy 273.15287 -303.536096)
			(xy 273.1516 -303.548288) (xy 273.159474 -303.57064) (xy 273.235928 -303.643538) (xy 273.258534 -303.65065)
			(xy 273.270472 -303.648618) (xy 273.293235 -303.64519) (xy 273.339249 -303.643915) (xy 273.362166 -303.646078)
			(xy 273.37385 -303.647602) (xy 273.39544 -303.639982) (xy 273.468084 -303.567592) (xy 273.475958 -303.546002)
			(xy 273.474688 -303.534318) (xy 273.472656 -303.499774) (xy 273.47316 -303.474066) (xy 273.481203 -303.423284)
			(xy 273.497091 -303.374385) (xy 273.520434 -303.328573) (xy 273.550655 -303.286977) (xy 273.587011 -303.250621)
			(xy 273.628607 -303.2204) (xy 273.674419 -303.197057) (xy 273.723318 -303.181169) (xy 273.7741 -303.173126)
			(xy 273.825516 -303.173126) (xy 273.876298 -303.181169) (xy 273.925197 -303.197057) (xy 273.971009 -303.2204)
			(xy 274.012605 -303.250621) (xy 274.048961 -303.286977) (xy 274.079182 -303.328573) (xy 274.102525 -303.374385)
			(xy 274.118413 -303.423284) (xy 274.126456 -303.474066) (xy 274.12696 -303.499774) (xy 274.124928 -303.534318)
			(xy 274.123658 -303.546002) (xy 274.131532 -303.567592) (xy 274.204176 -303.639982) (xy 274.225766 -303.647602)
			(xy 274.23745 -303.646078) (xy 274.256074 -303.644223) (xy 274.293502 -303.644223) (xy 274.312126 -303.646078)
			(xy 274.32381 -303.647602) (xy 274.3454 -303.639982) (xy 274.418044 -303.567592) (xy 274.425918 -303.546002)
			(xy 274.424648 -303.534318) (xy 274.422616 -303.499774) (xy 274.42312 -303.474066) (xy 274.431163 -303.423284)
			(xy 274.447051 -303.374385) (xy 274.470394 -303.328573) (xy 274.500615 -303.286977) (xy 274.536971 -303.250621)
			(xy 274.578567 -303.2204) (xy 274.624379 -303.197057) (xy 274.673278 -303.181169) (xy 274.72406 -303.173126)
			(xy 274.775476 -303.173126) (xy 274.826258 -303.181169) (xy 274.875157 -303.197057) (xy 274.920969 -303.2204)
			(xy 274.962565 -303.250621) (xy 274.998921 -303.286977) (xy 275.029142 -303.328573) (xy 275.052485 -303.374385)
			(xy 275.068373 -303.423284) (xy 275.076416 -303.474066) (xy 275.07692 -303.499774) (xy 275.074888 -303.534318)
			(xy 275.073618 -303.546002) (xy 275.081492 -303.567592) (xy 275.154136 -303.639982) (xy 275.175726 -303.647602)
			(xy 275.18741 -303.646078) (xy 275.210327 -303.643909) (xy 275.256342 -303.645185) (xy 275.279104 -303.648618)
			(xy 275.291042 -303.65065) (xy 275.313648 -303.643538) (xy 275.390102 -303.57064) (xy 275.397976 -303.548288)
			(xy 275.396706 -303.536096) (xy 275.395658 -303.527052) (xy 275.394516 -303.508878) (xy 275.39442 -303.499774)
			(xy 275.394942 -303.474519) (xy 275.403255 -303.424697) (xy 275.419656 -303.376923) (xy 275.443697 -303.3325)
			(xy 275.474721 -303.29264) (xy 275.511883 -303.25843) (xy 275.554169 -303.230804) (xy 275.600425 -303.210514)
			(xy 275.64939 -303.198114) (xy 275.699728 -303.193943) (xy 275.750066 -303.198114) (xy 275.799031 -303.210514)
			(xy 275.845287 -303.230804) (xy 275.887573 -303.25843) (xy 275.924735 -303.29264) (xy 275.955759 -303.3325)
			(xy 275.9798 -303.376923) (xy 275.996201 -303.424697) (xy 276.004514 -303.474519) (xy 276.005036 -303.499774)
			(xy 276.004937 -303.508878) (xy 276.003792 -303.527051) (xy 276.00275 -303.536096) (xy 276.00148 -303.548288)
			(xy 276.009354 -303.57064) (xy 276.085808 -303.643538) (xy 276.108414 -303.65065) (xy 276.120352 -303.648618)
			(xy 276.13384 -303.646485) (xy 276.161053 -303.644193) (xy 276.174708 -303.644046) (xy 276.183344 -303.644046)
			(xy 276.183598 -303.6443) (xy 276.245066 -303.6443) (xy 276.255754 -303.643728) (xy 276.275297 -303.635059)
			(xy 276.282912 -303.627536) (xy 276.34057 -303.563274) (xy 276.347174 -303.542954) (xy 276.346158 -303.532032)
			(xy 276.34438 -303.499774) (xy 276.344902 -303.474519) (xy 276.353215 -303.424697) (xy 276.369616 -303.376923)
			(xy 276.393657 -303.3325) (xy 276.424681 -303.29264) (xy 276.461843 -303.25843) (xy 276.504129 -303.230804)
			(xy 276.550385 -303.210514) (xy 276.59935 -303.198114) (xy 276.649688 -303.193943) (xy 276.700026 -303.198114)
			(xy 276.748991 -303.210514) (xy 276.795247 -303.230804) (xy 276.837533 -303.25843) (xy 276.874695 -303.29264)
			(xy 276.905719 -303.3325) (xy 276.92976 -303.376923) (xy 276.946161 -303.424697) (xy 276.954474 -303.474519)
			(xy 276.954996 -303.499774) (xy 276.953218 -303.532032) (xy 276.952202 -303.542954) (xy 276.958806 -303.563274)
			(xy 277.016464 -303.627536) (xy 277.023978 -303.635205) (xy 277.043583 -303.643906) (xy 277.05431 -303.6443)
			(xy 277.116032 -303.6443) (xy 277.116286 -303.644046) (xy 277.124922 -303.644046) (xy 277.138576 -303.644206)
			(xy 277.165789 -303.646492) (xy 277.179278 -303.648618) (xy 277.191216 -303.65065) (xy 277.213822 -303.643538)
			(xy 277.290276 -303.57064) (xy 277.29815 -303.548288) (xy 277.29688 -303.536096) (xy 277.295832 -303.527052)
			(xy 277.29469 -303.508878) (xy 277.294594 -303.499774) (xy 277.295116 -303.474519) (xy 277.303429 -303.424697)
			(xy 277.31983 -303.376923) (xy 277.343871 -303.3325) (xy 277.374895 -303.29264) (xy 277.412057 -303.25843)
			(xy 277.454343 -303.230804) (xy 277.500599 -303.210514) (xy 277.549564 -303.198114) (xy 277.599902 -303.193943)
			(xy 277.65024 -303.198114) (xy 277.699205 -303.210514) (xy 277.745461 -303.230804) (xy 277.787747 -303.25843)
			(xy 277.824909 -303.29264) (xy 277.855933 -303.3325) (xy 277.879974 -303.376923) (xy 277.896375 -303.424697)
			(xy 277.904688 -303.474519) (xy 277.90521 -303.499774) (xy 277.905111 -303.508878) (xy 277.903966 -303.527051)
			(xy 277.902924 -303.536096) (xy 277.901654 -303.548288) (xy 277.909528 -303.57064) (xy 277.985982 -303.643538)
			(xy 278.008588 -303.65065) (xy 278.020526 -303.648618) (xy 278.046949 -303.644732) (xy 278.100353 -303.64453)
			(xy 278.153095 -303.65291) (xy 278.203806 -303.669654) (xy 278.251169 -303.694327) (xy 278.293953 -303.726289)
			(xy 278.331047 -303.764708) (xy 278.361487 -303.808588) (xy 278.384482 -303.856787) (xy 278.392382 -303.882298)
			(xy 278.392382 -303.882806) (xy 278.392636 -303.883568) (xy 278.396335 -303.89371) (xy 278.410673 -303.909823)
			(xy 278.430364 -303.918624) (xy 278.44115 -303.919128) (xy 278.658574 -303.919128) (xy 278.669352 -303.918629)
			(xy 278.689013 -303.90979) (xy 278.703346 -303.893689) (xy 278.707088 -303.883568) (xy 278.707342 -303.882806)
			(xy 278.707342 -303.882298) (xy 278.714792 -303.85837) (xy 278.735902 -303.812921) (xy 278.763628 -303.771177)
			(xy 278.797335 -303.734095) (xy 278.836251 -303.702523) (xy 278.879486 -303.677184) (xy 278.926048 -303.658659)
			(xy 278.974873 -303.647371) (xy 279.024842 -303.64358) (xy 279.074811 -303.647371) (xy 279.123636 -303.658659)
			(xy 279.170198 -303.677184) (xy 279.213433 -303.702523) (xy 279.252349 -303.734095) (xy 279.286056 -303.771177)
			(xy 279.313782 -303.812921) (xy 279.334892 -303.85837) (xy 279.342342 -303.882298) (xy 279.342342 -303.882806)
			(xy 279.342596 -303.883568) (xy 279.346293 -303.893715) (xy 279.360629 -303.909839) (xy 279.380321 -303.918655)
			(xy 279.39111 -303.919128) (xy 279.608534 -303.919128) (xy 279.619317 -303.918636) (xy 279.638992 -303.909806)
			(xy 279.653337 -303.893704) (xy 279.657048 -303.883568) (xy 279.657302 -303.882806) (xy 279.657302 -303.882298)
			(xy 279.664752 -303.85837) (xy 279.685862 -303.812921) (xy 279.713588 -303.771177) (xy 279.747295 -303.734095)
			(xy 279.786211 -303.702523) (xy 279.829446 -303.677184) (xy 279.876008 -303.658659) (xy 279.924833 -303.647371)
			(xy 279.974802 -303.64358) (xy 280.024771 -303.647371) (xy 280.073596 -303.658659) (xy 280.120158 -303.677184)
			(xy 280.163393 -303.702523) (xy 280.202309 -303.734095) (xy 280.236016 -303.771177) (xy 280.263742 -303.812921)
			(xy 280.284852 -303.85837) (xy 280.292302 -303.882298) (xy 280.292302 -303.882806) (xy 280.292556 -303.883568)
			(xy 280.296251 -303.893719) (xy 280.310585 -303.909854) (xy 280.330278 -303.918685) (xy 280.34107 -303.919128)
			(xy 280.558494 -303.919128) (xy 280.569269 -303.918625) (xy 280.588924 -303.909783) (xy 280.60325 -303.893682)
			(xy 280.607008 -303.883568) (xy 280.607262 -303.882806) (xy 280.607262 -303.882298) (xy 280.61522 -303.856887)
			(xy 280.63811 -303.808813) (xy 280.668405 -303.765026) (xy 280.705325 -303.726659) (xy 280.747914 -303.694703)
			(xy 280.795073 -303.669982) (xy 280.845583 -303.653136) (xy 280.898139 -303.644599) (xy 280.924762 -303.644046)
			(xy 280.949921 -303.644542) (xy 280.999653 -303.652209) (xy 281.047652 -303.667312) (xy 281.092814 -303.689503)
			(xy 281.113738 -303.703482) (xy 281.123391 -303.709645) (xy 281.145959 -303.713408) (xy 281.16792 -303.706985)
			(xy 281.17673 -303.699672) (xy 281.177746 -303.698656) (xy 281.267408 -303.608994) (xy 281.267916 -303.608486)
			(xy 281.274508 -303.601109) (xy 281.281978 -303.582809) (xy 281.282394 -303.572926) (xy 281.282394 -303.373282)
			(xy 281.28202 -303.363913) (xy 281.275369 -303.346399) (xy 281.262857 -303.332455) (xy 281.254708 -303.327816)
			(xy 281.254454 -303.327816) (xy 281.160728 -303.280318) (xy 281.13228 -303.282604) (xy 281.120596 -303.29124)
			(xy 281.099183 -303.306375) (xy 281.052574 -303.330393) (xy 281.002755 -303.346746) (xy 280.950979 -303.355023)
			(xy 280.924762 -303.355502) (xy 280.898777 -303.35499) (xy 280.847448 -303.346854) (xy 280.798024 -303.33079)
			(xy 280.75172 -303.307193) (xy 280.709678 -303.276643) (xy 280.672932 -303.239893) (xy 280.642387 -303.197847)
			(xy 280.618795 -303.151541) (xy 280.602737 -303.102115) (xy 280.594607 -303.050785) (xy 280.594607 -302.998815)
			(xy 280.602737 -302.947485) (xy 280.618795 -302.898059) (xy 280.642387 -302.851753) (xy 280.672932 -302.809707)
			(xy 280.709678 -302.772957) (xy 280.75172 -302.742407) (xy 280.798024 -302.71881) (xy 280.847448 -302.702746)
			(xy 280.898777 -302.69461) (xy 280.924762 -302.694086) (xy 280.950976 -302.694592) (xy 281.002747 -302.702876)
			(xy 281.052561 -302.719228) (xy 281.09917 -302.743236) (xy 281.120596 -302.758348) (xy 281.13228 -302.766984)
			(xy 281.160728 -302.76927) (xy 281.254454 -302.721772) (xy 281.262699 -302.717224) (xy 281.275341 -302.703285)
			(xy 281.282082 -302.685716) (xy 281.282394 -302.676306) (xy 281.282394 -301.473362) (xy 281.282016 -301.463995)
			(xy 281.275362 -301.446486) (xy 281.262849 -301.432549) (xy 281.254708 -301.427896) (xy 281.254454 -301.427896)
			(xy 281.160728 -301.380398) (xy 281.13228 -301.382684) (xy 281.120596 -301.39132) (xy 281.099183 -301.406456)
			(xy 281.052574 -301.430475) (xy 281.002756 -301.446829) (xy 280.950979 -301.455107) (xy 280.924762 -301.455582)
			(xy 280.898779 -301.45507) (xy 280.847453 -301.446935) (xy 280.798031 -301.430872) (xy 280.751731 -301.407276)
			(xy 280.709691 -301.376728) (xy 280.672947 -301.33998) (xy 280.642404 -301.297937) (xy 280.618813 -301.251633)
			(xy 280.602756 -301.20221) (xy 280.594627 -301.150883) (xy 280.594627 -301.098917) (xy 280.602756 -301.04759)
			(xy 280.618813 -300.998167) (xy 280.642404 -300.951863) (xy 280.672947 -300.90982) (xy 280.709691 -300.873072)
			(xy 280.751731 -300.842524) (xy 280.798031 -300.818928) (xy 280.847453 -300.802865) (xy 280.898779 -300.79473)
			(xy 280.924762 -300.794166) (xy 280.950976 -300.794672) (xy 281.002747 -300.802956) (xy 281.052561 -300.819306)
			(xy 281.099171 -300.843313) (xy 281.120596 -300.858428) (xy 281.13228 -300.867064) (xy 281.160728 -300.86935)
			(xy 281.254454 -300.821852) (xy 281.262697 -300.817303) (xy 281.275333 -300.803363) (xy 281.282067 -300.785795)
			(xy 281.282394 -300.776386) (xy 281.282394 -300.523402) (xy 281.282023 -300.514031) (xy 281.275377 -300.496511)
			(xy 281.262866 -300.482562) (xy 281.254708 -300.477936) (xy 281.254454 -300.477936) (xy 281.160728 -300.430438)
			(xy 281.13228 -300.432724) (xy 281.120596 -300.44136) (xy 281.099183 -300.456494) (xy 281.052573 -300.480511)
			(xy 281.002755 -300.496863) (xy 280.950979 -300.505139) (xy 280.924762 -300.505622) (xy 280.898776 -300.50511)
			(xy 280.847444 -300.496974) (xy 280.798016 -300.480909) (xy 280.75171 -300.45731) (xy 280.709665 -300.426758)
			(xy 280.672917 -300.390006) (xy 280.64237 -300.347958) (xy 280.618777 -300.301649) (xy 280.602717 -300.252219)
			(xy 280.594587 -300.200886) (xy 280.594587 -300.148914) (xy 280.602717 -300.097581) (xy 280.618777 -300.048151)
			(xy 280.64237 -300.001842) (xy 280.672917 -299.959794) (xy 280.709665 -299.923042) (xy 280.75171 -299.89249)
			(xy 280.798016 -299.868891) (xy 280.847444 -299.852826) (xy 280.898776 -299.84469) (xy 280.924762 -299.844206)
			(xy 280.950976 -299.844712) (xy 281.002746 -299.852997) (xy 281.05256 -299.869349) (xy 281.099168 -299.893358)
			(xy 281.120596 -299.908468) (xy 281.13228 -299.917104) (xy 281.160728 -299.91939) (xy 281.254454 -299.871892)
			(xy 281.26269 -299.86734) (xy 281.27531 -299.853397) (xy 281.282024 -299.835831) (xy 281.282394 -299.826426)
			(xy 281.282394 -299.573442) (xy 281.282013 -299.564077) (xy 281.275354 -299.546574) (xy 281.26284 -299.532642)
			(xy 281.254708 -299.527976) (xy 281.254454 -299.527976) (xy 281.160728 -299.480478) (xy 281.13228 -299.482764)
			(xy 281.120596 -299.4914) (xy 281.099182 -299.506532) (xy 281.052572 -299.530546) (xy 281.002754 -299.546896)
			(xy 280.950978 -299.555172) (xy 280.924762 -299.555662) (xy 280.89878 -299.555149) (xy 280.847458 -299.547015)
			(xy 280.798039 -299.530953) (xy 280.751741 -299.507358) (xy 280.709704 -299.476812) (xy 280.672963 -299.440067)
			(xy 280.642422 -299.398026) (xy 280.618832 -299.351726) (xy 280.602776 -299.302305) (xy 280.594648 -299.250982)
			(xy 280.594648 -299.199018) (xy 280.602776 -299.147695) (xy 280.618832 -299.098274) (xy 280.642422 -299.051974)
			(xy 280.672963 -299.009933) (xy 280.709704 -298.973188) (xy 280.751741 -298.942642) (xy 280.798039 -298.919047)
			(xy 280.847458 -298.902985) (xy 280.89878 -298.894851) (xy 280.924762 -298.894246) (xy 280.92527 -298.894246)
			(xy 280.950045 -298.894745) (xy 280.999022 -298.902275) (xy 281.022806 -298.909232) (xy 281.030172 -298.911518)
			(xy 281.041348 -298.911518) (xy 281.05135 -298.911031) (xy 281.069845 -298.903407) (xy 281.084053 -298.889324)
			(xy 281.088338 -298.880276) (xy 281.094434 -298.865798) (xy 281.088338 -298.835826) (xy 281.009344 -298.756578)
			(xy 281.00909 -298.756324) (xy 281.006042 -298.753276) (xy 280.97226 -298.719494) (xy 280.965148 -298.712128)
			(xy 280.946352 -298.704508) (xy 279.538938 -298.704508) (xy 279.528912 -298.704921) (xy 279.510384 -298.712584)
			(xy 279.496201 -298.726758) (xy 279.488527 -298.745282) (xy 279.488138 -298.755308) (xy 279.488138 -299.224954)
			(xy 279.668998 -299.224954) (xy 279.672958 -299.1759) (xy 279.684735 -299.128116) (xy 279.704026 -299.08284)
			(xy 279.730329 -299.041244) (xy 279.762964 -299.004407) (xy 279.801085 -298.973282) (xy 279.843706 -298.948675)
			(xy 279.889722 -298.931223) (xy 279.937941 -298.921379) (xy 279.987116 -298.919398) (xy 280.035971 -298.92533)
			(xy 280.083242 -298.939022) (xy 280.127704 -298.96012) (xy 280.168207 -298.988076) (xy 280.2037 -299.022168)
			(xy 280.233265 -299.061512) (xy 280.256136 -299.105089) (xy 280.27172 -299.15177) (xy 280.279615 -299.200347)
			(xy 280.28011 -299.224954) (xy 280.279615 -299.249561) (xy 280.27172 -299.298138) (xy 280.256136 -299.344819)
			(xy 280.233265 -299.388396) (xy 280.2037 -299.42774) (xy 280.168207 -299.461832) (xy 280.127704 -299.489788)
			(xy 280.083242 -299.510886) (xy 280.035971 -299.524578) (xy 279.987116 -299.53051) (xy 279.937941 -299.528529)
			(xy 279.889722 -299.518685) (xy 279.843706 -299.501233) (xy 279.801085 -299.476626) (xy 279.762964 -299.445501)
			(xy 279.730329 -299.408664) (xy 279.704026 -299.367068) (xy 279.684735 -299.321792) (xy 279.672958 -299.274008)
			(xy 279.668998 -299.224954) (xy 279.488138 -299.224954) (xy 279.488138 -300.82363) (xy 279.487593 -300.833614)
			(xy 279.479866 -300.852032) (xy 279.473152 -300.859444) (xy 279.44191 -300.890686) (xy 279.401524 -300.931326)
			(xy 279.398476 -300.934374) (xy 279.356312 -300.976538) (xy 279.34947 -300.983938) (xy 279.341748 -301.002536)
			(xy 279.341326 -301.012606) (xy 279.341326 -301.02937) (xy 279.343104 -301.036228) (xy 279.348846 -301.057941)
			(xy 279.355087 -301.102419) (xy 279.35555 -301.124874) (xy 279.668998 -301.124874) (xy 279.672958 -301.07582)
			(xy 279.684735 -301.028036) (xy 279.704026 -300.98276) (xy 279.730329 -300.941164) (xy 279.762964 -300.904327)
			(xy 279.801085 -300.873202) (xy 279.843706 -300.848595) (xy 279.889722 -300.831143) (xy 279.937941 -300.821299)
			(xy 279.987116 -300.819318) (xy 280.035971 -300.82525) (xy 280.083242 -300.838942) (xy 280.127704 -300.86004)
			(xy 280.168207 -300.887996) (xy 280.2037 -300.922088) (xy 280.233265 -300.961432) (xy 280.256136 -301.005009)
			(xy 280.27172 -301.05169) (xy 280.279615 -301.100267) (xy 280.28011 -301.124874) (xy 280.279615 -301.149481)
			(xy 280.27172 -301.198058) (xy 280.256136 -301.244739) (xy 280.233265 -301.288316) (xy 280.2037 -301.32766)
			(xy 280.168207 -301.361752) (xy 280.127704 -301.389708) (xy 280.083242 -301.410806) (xy 280.035971 -301.424498)
			(xy 279.987116 -301.43043) (xy 279.937941 -301.428449) (xy 279.889722 -301.418605) (xy 279.843706 -301.401153)
			(xy 279.801085 -301.376546) (xy 279.762964 -301.345421) (xy 279.730329 -301.308584) (xy 279.704026 -301.266988)
			(xy 279.684735 -301.221712) (xy 279.672958 -301.173928) (xy 279.668998 -301.124874) (xy 279.35555 -301.124874)
			(xy 279.355042 -301.150864) (xy 279.346915 -301.202204) (xy 279.330857 -301.251641) (xy 279.307263 -301.297957)
			(xy 279.276715 -301.340012) (xy 279.239964 -301.376771) (xy 279.197915 -301.407328) (xy 279.151603 -301.430931)
			(xy 279.10217 -301.446999) (xy 279.050832 -301.455137) (xy 279.024842 -301.455582) (xy 278.99893 -301.455082)
			(xy 278.947738 -301.447003) (xy 278.898434 -301.431039) (xy 278.852224 -301.407578) (xy 278.810239 -301.377195)
			(xy 278.773508 -301.340635) (xy 278.742931 -301.298793) (xy 278.719254 -301.252693) (xy 278.70306 -301.203463)
			(xy 278.698452 -301.17796) (xy 278.695404 -301.159418) (xy 278.66721 -301.135288) (xy 278.432514 -301.135288)
			(xy 278.40432 -301.159418) (xy 278.401272 -301.17796) (xy 278.396608 -301.203592) (xy 278.380284 -301.253065)
			(xy 278.356401 -301.299365) (xy 278.325551 -301.341346) (xy 278.288498 -301.377968) (xy 278.246159 -301.408324)
			(xy 278.199582 -301.431663) (xy 278.149921 -301.447408) (xy 278.098406 -301.455167) (xy 278.046311 -301.45475)
			(xy 278.020526 -301.45101) (xy 278.008588 -301.449232) (xy 277.985982 -301.45609) (xy 277.909528 -301.528988)
			(xy 277.901654 -301.55134) (xy 277.902924 -301.563532) (xy 277.903974 -301.572576) (xy 277.90512 -301.59075)
			(xy 277.90521 -301.599854) (xy 277.904688 -301.625109) (xy 277.896375 -301.674931) (xy 277.879974 -301.722705)
			(xy 277.855933 -301.767128) (xy 277.824909 -301.806988) (xy 277.787747 -301.841198) (xy 277.745461 -301.868824)
			(xy 277.699205 -301.889114) (xy 277.65024 -301.901514) (xy 277.599902 -301.905685) (xy 277.549564 -301.901514)
			(xy 277.500599 -301.889114) (xy 277.454343 -301.868824) (xy 277.412057 -301.841198) (xy 277.374895 -301.806988)
			(xy 277.343871 -301.767128) (xy 277.31983 -301.722705) (xy 277.303429 -301.674931) (xy 277.295116 -301.625109)
			(xy 277.294594 -301.599854) (xy 277.294692 -301.59075) (xy 277.295836 -301.572577) (xy 277.29688 -301.563532)
			(xy 277.29815 -301.55134) (xy 277.290276 -301.528988) (xy 277.213822 -301.45609) (xy 277.191216 -301.449232)
			(xy 277.179278 -301.45101) (xy 277.152176 -301.454949) (xy 277.097414 -301.454949) (xy 277.070312 -301.45101)
			(xy 277.058374 -301.448978) (xy 277.035768 -301.45609) (xy 276.959314 -301.528988) (xy 276.95144 -301.55134)
			(xy 276.95271 -301.563532) (xy 276.95376 -301.572576) (xy 276.954906 -301.59075) (xy 276.954996 -301.599854)
			(xy 276.954474 -301.625109) (xy 276.946161 -301.674931) (xy 276.92976 -301.722705) (xy 276.905719 -301.767128)
			(xy 276.874695 -301.806988) (xy 276.837533 -301.841198) (xy 276.795247 -301.868824) (xy 276.748991 -301.889114)
			(xy 276.700026 -301.901514) (xy 276.649688 -301.905685) (xy 276.59935 -301.901514) (xy 276.550385 -301.889114)
			(xy 276.504129 -301.868824) (xy 276.461843 -301.841198) (xy 276.424681 -301.806988) (xy 276.393657 -301.767128)
			(xy 276.369616 -301.722705) (xy 276.353215 -301.674931) (xy 276.344902 -301.625109) (xy 276.34438 -301.599854)
			(xy 276.344478 -301.59075) (xy 276.345622 -301.572577) (xy 276.346666 -301.563532) (xy 276.347936 -301.55134)
			(xy 276.340062 -301.528988) (xy 276.263608 -301.45609) (xy 276.241002 -301.449232) (xy 276.229064 -301.45101)
			(xy 276.202026 -301.454947) (xy 276.14739 -301.454947) (xy 276.120352 -301.45101) (xy 276.108414 -301.449232)
			(xy 276.085808 -301.45609) (xy 276.009354 -301.528988) (xy 276.00148 -301.55134) (xy 276.00275 -301.563532)
			(xy 276.0038 -301.572576) (xy 276.004946 -301.59075) (xy 276.005036 -301.599854) (xy 276.004514 -301.625109)
			(xy 275.996201 -301.674931) (xy 275.9798 -301.722705) (xy 275.955759 -301.767128) (xy 275.924735 -301.806988)
			(xy 275.887573 -301.841198) (xy 275.845287 -301.868824) (xy 275.799031 -301.889114) (xy 275.750066 -301.901514)
			(xy 275.699728 -301.905685) (xy 275.64939 -301.901514) (xy 275.600425 -301.889114) (xy 275.554169 -301.868824)
			(xy 275.511883 -301.841198) (xy 275.474721 -301.806988) (xy 275.443697 -301.767128) (xy 275.419656 -301.722705)
			(xy 275.403255 -301.674931) (xy 275.394942 -301.625109) (xy 275.39442 -301.599854) (xy 275.394518 -301.59075)
			(xy 275.395662 -301.572577) (xy 275.396706 -301.563532) (xy 275.397976 -301.55134) (xy 275.390102 -301.528988)
			(xy 275.313648 -301.45609) (xy 275.291042 -301.449232) (xy 275.279104 -301.45101) (xy 275.256341 -301.454433)
			(xy 275.210328 -301.455703) (xy 275.18741 -301.45355) (xy 275.175726 -301.45228) (xy 275.154136 -301.459646)
			(xy 275.081492 -301.532036) (xy 275.073618 -301.553626) (xy 275.074888 -301.56531) (xy 275.07692 -301.599854)
			(xy 275.076416 -301.625562) (xy 275.068373 -301.676344) (xy 275.052485 -301.725243) (xy 275.029142 -301.771055)
			(xy 274.998921 -301.812651) (xy 274.962565 -301.849007) (xy 274.920969 -301.879228) (xy 274.875157 -301.902571)
			(xy 274.826258 -301.918459) (xy 274.775476 -301.926502) (xy 274.72406 -301.926502) (xy 274.673278 -301.918459)
			(xy 274.624379 -301.902571) (xy 274.578567 -301.879228) (xy 274.536971 -301.849007) (xy 274.500615 -301.812651)
			(xy 274.470394 -301.771055) (xy 274.447051 -301.725243) (xy 274.431163 -301.676344) (xy 274.42312 -301.625562)
			(xy 274.422616 -301.599854) (xy 274.424648 -301.56531) (xy 274.425918 -301.55388) (xy 274.418044 -301.53229)
			(xy 274.3454 -301.4599) (xy 274.32381 -301.452534) (xy 274.312126 -301.453804) (xy 274.302822 -301.454772)
			(xy 274.284142 -301.455789) (xy 274.274788 -301.455836) (xy 274.226274 -301.455836) (xy 274.215618 -301.456301)
			(xy 274.196162 -301.464995) (xy 274.188682 -301.4726) (xy 274.13077 -301.536354) (xy 274.124166 -301.556674)
			(xy 274.125182 -301.567596) (xy 274.12696 -301.599854) (xy 274.126456 -301.625562) (xy 274.118413 -301.676344)
			(xy 274.102525 -301.725243) (xy 274.079182 -301.771055) (xy 274.048961 -301.812651) (xy 274.012605 -301.849007)
			(xy 273.971009 -301.879228) (xy 273.925197 -301.902571) (xy 273.876298 -301.918459) (xy 273.825516 -301.926502)
			(xy 273.7741 -301.926502) (xy 273.723318 -301.918459) (xy 273.674419 -301.902571) (xy 273.628607 -301.879228)
			(xy 273.587011 -301.849007) (xy 273.550655 -301.812651) (xy 273.520434 -301.771055) (xy 273.497091 -301.725243)
			(xy 273.481203 -301.676344) (xy 273.47316 -301.625562) (xy 273.472656 -301.599854) (xy 273.474434 -301.567596)
			(xy 273.47545 -301.556674) (xy 273.468846 -301.536354) (xy 273.410934 -301.4726) (xy 273.403389 -301.46509)
			(xy 273.38397 -301.456425) (xy 273.373342 -301.455836) (xy 273.324828 -301.455836) (xy 273.311174 -301.455674)
			(xy 273.283962 -301.453384) (xy 273.270472 -301.451264) (xy 273.258534 -301.449232) (xy 273.235928 -301.456344)
			(xy 273.159474 -301.529242) (xy 273.1516 -301.551594) (xy 273.153124 -301.563532) (xy 273.154114 -301.572579)
			(xy 273.155131 -301.590753) (xy 273.155156 -301.599854) (xy 273.154634 -301.625109) (xy 273.146321 -301.674931)
			(xy 273.12992 -301.722705) (xy 273.105879 -301.767128) (xy 273.074855 -301.806988) (xy 273.037693 -301.841198)
			(xy 272.995407 -301.868824) (xy 272.949151 -301.889114) (xy 272.900186 -301.901514) (xy 272.849848 -301.905685)
			(xy 272.79951 -301.901514) (xy 272.750545 -301.889114) (xy 272.704289 -301.868824) (xy 272.662003 -301.841198)
			(xy 272.624841 -301.806988) (xy 272.593817 -301.767128) (xy 272.569776 -301.722705) (xy 272.553375 -301.674931)
			(xy 272.545062 -301.625109) (xy 272.54454 -301.599854) (xy 272.544638 -301.59075) (xy 272.545782 -301.572577)
			(xy 272.546826 -301.563532) (xy 272.548096 -301.55134) (xy 272.540222 -301.528988) (xy 272.463768 -301.45609)
			(xy 272.441162 -301.449232) (xy 272.429224 -301.45101) (xy 272.406461 -301.454434) (xy 272.360448 -301.455707)
			(xy 272.33753 -301.45355) (xy 272.325846 -301.45228) (xy 272.304256 -301.459646) (xy 272.231612 -301.532036)
			(xy 272.223738 -301.553626) (xy 272.225008 -301.56531) (xy 272.22704 -301.599854) (xy 272.226536 -301.625562)
			(xy 272.218493 -301.676344) (xy 272.202605 -301.725243) (xy 272.179262 -301.771055) (xy 272.149041 -301.812651)
			(xy 272.112685 -301.849007) (xy 272.071089 -301.879228) (xy 272.025277 -301.902571) (xy 271.976378 -301.918459)
			(xy 271.925596 -301.926502) (xy 271.87418 -301.926502) (xy 271.823398 -301.918459) (xy 271.774499 -301.902571)
			(xy 271.728687 -301.879228) (xy 271.687091 -301.849007) (xy 271.650735 -301.812651) (xy 271.620514 -301.771055)
			(xy 271.597171 -301.725243) (xy 271.581283 -301.676344) (xy 271.57324 -301.625562) (xy 271.572736 -301.599854)
			(xy 271.574768 -301.565564) (xy 271.575784 -301.55388) (xy 271.568164 -301.53229) (xy 271.49552 -301.460154)
			(xy 271.473676 -301.452788) (xy 271.462246 -301.454058) (xy 271.452942 -301.455027) (xy 271.434262 -301.456045)
			(xy 271.424908 -301.45609) (xy 271.376394 -301.45609) (xy 271.365735 -301.45655) (xy 271.346268 -301.465233)
			(xy 271.338802 -301.472854) (xy 271.28089 -301.536608) (xy 271.274286 -301.556928) (xy 271.275302 -301.567596)
			(xy 271.27708 -301.599854) (xy 271.276576 -301.625562) (xy 271.268533 -301.676344) (xy 271.252645 -301.725243)
			(xy 271.229302 -301.771055) (xy 271.199081 -301.812651) (xy 271.162725 -301.849007) (xy 271.121129 -301.879228)
			(xy 271.075317 -301.902571) (xy 271.026418 -301.918459) (xy 270.975636 -301.926502) (xy 270.92422 -301.926502)
			(xy 270.873438 -301.918459) (xy 270.824539 -301.902571) (xy 270.778727 -301.879228) (xy 270.737131 -301.849007)
			(xy 270.700775 -301.812651) (xy 270.670554 -301.771055) (xy 270.647211 -301.725243) (xy 270.631323 -301.676344)
			(xy 270.62328 -301.625562) (xy 270.622776 -301.599854) (xy 270.624554 -301.567596) (xy 270.62557 -301.556674)
			(xy 270.618966 -301.536354) (xy 270.561054 -301.4726) (xy 270.55351 -301.465087) (xy 270.534092 -301.456414)
			(xy 270.523462 -301.455836) (xy 270.474948 -301.455836) (xy 270.461294 -301.455675) (xy 270.434081 -301.453386)
			(xy 270.420592 -301.451264) (xy 270.4084 -301.449232) (xy 270.385794 -301.456344) (xy 270.30934 -301.529242)
			(xy 270.301466 -301.551594) (xy 270.302736 -301.563532) (xy 270.303786 -301.572576) (xy 270.304932 -301.59075)
			(xy 270.305022 -301.599854) (xy 270.3045 -301.625109) (xy 270.296187 -301.674931) (xy 270.279786 -301.722705)
			(xy 270.255745 -301.767128) (xy 270.224721 -301.806988) (xy 270.187559 -301.841198) (xy 270.145273 -301.868824)
			(xy 270.099017 -301.889114) (xy 270.050052 -301.901514) (xy 269.999714 -301.905685) (xy 269.949376 -301.901514)
			(xy 269.900411 -301.889114) (xy 269.854155 -301.868824) (xy 269.811869 -301.841198) (xy 269.774707 -301.806988)
			(xy 269.743683 -301.767128) (xy 269.719642 -301.722705) (xy 269.703241 -301.674931) (xy 269.694928 -301.625109)
			(xy 269.694406 -301.599854) (xy 269.694504 -301.59075) (xy 269.695648 -301.572577) (xy 269.696692 -301.563532)
			(xy 269.697962 -301.55134) (xy 269.690088 -301.528988) (xy 269.613634 -301.45609) (xy 269.591028 -301.449232)
			(xy 269.57909 -301.45101) (xy 269.552052 -301.454947) (xy 269.497416 -301.454947) (xy 269.470378 -301.45101)
			(xy 269.45844 -301.449232) (xy 269.435834 -301.45609) (xy 269.35938 -301.528988) (xy 269.351506 -301.55134)
			(xy 269.352776 -301.563532) (xy 269.353826 -301.572576) (xy 269.354972 -301.59075) (xy 269.355062 -301.599854)
			(xy 269.35454 -301.625109) (xy 269.346227 -301.674931) (xy 269.329826 -301.722705) (xy 269.305785 -301.767128)
			(xy 269.274761 -301.806988) (xy 269.237599 -301.841198) (xy 269.195313 -301.868824) (xy 269.149057 -301.889114)
			(xy 269.100092 -301.901514) (xy 269.049754 -301.905685) (xy 268.999416 -301.901514) (xy 268.950451 -301.889114)
			(xy 268.904195 -301.868824) (xy 268.861909 -301.841198) (xy 268.824747 -301.806988) (xy 268.793723 -301.767128)
			(xy 268.769682 -301.722705) (xy 268.753281 -301.674931) (xy 268.744968 -301.625109) (xy 268.744446 -301.599854)
			(xy 268.744544 -301.59075) (xy 268.745688 -301.572577) (xy 268.746732 -301.563532) (xy 268.748002 -301.55134)
			(xy 268.740128 -301.528988) (xy 268.663674 -301.45609) (xy 268.641068 -301.449232) (xy 268.62913 -301.45101)
			(xy 268.603356 -301.454808) (xy 268.551261 -301.455204) (xy 268.499748 -301.447427) (xy 268.450092 -301.431669)
			(xy 268.40352 -301.408321) (xy 268.361186 -301.37796) (xy 268.324135 -301.341336) (xy 268.293285 -301.299357)
			(xy 268.269398 -301.253059) (xy 268.253065 -301.203589) (xy 268.248384 -301.17796) (xy 268.245336 -301.159418)
			(xy 268.217142 -301.135288) (xy 263.873742 -301.135288) (xy 263.863751 -301.134758) (xy 263.845309 -301.127054)
			(xy 263.837928 -301.120302) (xy 263.806686 -301.08906) (xy 263.766046 -301.048674) (xy 263.765538 -301.048166)
			(xy 263.762998 -301.045626) (xy 263.538716 -300.821344) (xy 263.535922 -300.81855) (xy 263.535414 -300.818042)
			(xy 263.495282 -300.777656) (xy 263.46404 -300.746414) (xy 263.457223 -300.739071) (xy 263.449479 -300.720609)
			(xy 263.449054 -300.7106) (xy 263.449054 -298.803822) (xy 263.449589 -298.793834) (xy 263.457303 -298.775401)
			(xy 263.46404 -298.768008) (xy 263.809734 -298.422314) (xy 263.810242 -298.421552) (xy 263.813544 -298.41825)
			(xy 263.813798 -298.417996) (xy 263.84758 -298.384214) (xy 263.85012 -298.381674) (xy 263.850628 -298.381166)
			(xy 263.891268 -298.34078) (xy 263.92251 -298.309538) (xy 263.92915 -298.303416) (xy 263.945545 -298.29587)
			(xy 263.954514 -298.294806) (xy 263.963658 -298.294044) (xy 263.980168 -298.286424) (xy 263.992106 -298.274486)
			(xy 263.999517 -298.267804) (xy 264.017953 -298.260226) (xy 264.02792 -298.259754) (xy 265.158982 -298.259754)
			(xy 265.169045 -298.259315) (xy 265.187623 -298.251574) (xy 265.19505 -298.244768) (xy 265.51128 -297.928538)
			(xy 265.511788 -297.92803) (xy 265.518364 -297.920646) (xy 265.525803 -297.902348) (xy 265.526266 -297.89247)
			(xy 265.526266 -296.450512) (xy 265.525844 -296.440442) (xy 265.518129 -296.421837) (xy 265.51128 -296.414444)
			(xy 265.301222 -296.204386) (xy 265.29411 -296.19702) (xy 265.275314 -296.1894) (xy 264.235184 -296.1894)
			(xy 264.225218 -296.189877) (xy 264.20678 -296.197452) (xy 264.19937 -296.204132) (xy 264.179793 -296.222858)
			(xy 264.136301 -296.255155) (xy 264.088676 -296.280975) (xy 264.037879 -296.299798) (xy 263.984929 -296.311246)
			(xy 263.930892 -296.315087) (xy 263.876855 -296.311246) (xy 263.823905 -296.299798) (xy 263.773108 -296.280975)
			(xy 263.725483 -296.255155) (xy 263.681991 -296.222858) (xy 263.662414 -296.204132) (xy 263.655007 -296.197442)
			(xy 263.63657 -296.18985) (xy 263.6266 -296.1894) (xy 262.504428 -296.1894) (xy 262.494364 -296.189836)
			(xy 262.475778 -296.197569) (xy 262.46836 -296.204386) (xy 262.07593 -296.596816) (xy 262.068564 -296.603928)
			(xy 262.060944 -296.622724) (xy 262.060944 -302.550068) (xy 267.793736 -302.550068) (xy 267.797696 -302.501014)
			(xy 267.809473 -302.45323) (xy 267.828764 -302.407954) (xy 267.855067 -302.366358) (xy 267.887702 -302.329521)
			(xy 267.925823 -302.298396) (xy 267.968444 -302.273789) (xy 268.01446 -302.256337) (xy 268.062679 -302.246493)
			(xy 268.111854 -302.244512) (xy 268.160709 -302.250444) (xy 268.20798 -302.264136) (xy 268.252442 -302.285234)
			(xy 268.292945 -302.31319) (xy 268.328438 -302.347282) (xy 268.358003 -302.386626) (xy 268.380874 -302.430203)
			(xy 268.396458 -302.476884) (xy 268.404353 -302.525461) (xy 268.404848 -302.550068) (xy 268.404353 -302.574675)
			(xy 268.404215 -302.575522) (xy 268.723106 -302.575522) (xy 268.723106 -302.524106) (xy 268.731149 -302.473324)
			(xy 268.747037 -302.424425) (xy 268.77038 -302.378613) (xy 268.800601 -302.337017) (xy 268.836957 -302.300661)
			(xy 268.878553 -302.27044) (xy 268.924365 -302.247097) (xy 268.973264 -302.231209) (xy 269.024046 -302.223166)
			(xy 269.075462 -302.223166) (xy 269.126244 -302.231209) (xy 269.175143 -302.247097) (xy 269.220955 -302.27044)
			(xy 269.262551 -302.300661) (xy 269.298907 -302.337017) (xy 269.329128 -302.378613) (xy 269.352471 -302.424425)
			(xy 269.368359 -302.473324) (xy 269.376402 -302.524106) (xy 269.376906 -302.549814) (xy 269.376402 -302.575522)
			(xy 269.673066 -302.575522) (xy 269.673066 -302.524106) (xy 269.681109 -302.473324) (xy 269.696997 -302.424425)
			(xy 269.72034 -302.378613) (xy 269.750561 -302.337017) (xy 269.786917 -302.300661) (xy 269.828513 -302.27044)
			(xy 269.874325 -302.247097) (xy 269.923224 -302.231209) (xy 269.974006 -302.223166) (xy 270.025422 -302.223166)
			(xy 270.076204 -302.231209) (xy 270.125103 -302.247097) (xy 270.170915 -302.27044) (xy 270.212511 -302.300661)
			(xy 270.248867 -302.337017) (xy 270.279088 -302.378613) (xy 270.302431 -302.424425) (xy 270.318319 -302.473324)
			(xy 270.326362 -302.524106) (xy 270.326866 -302.549814) (xy 270.644124 -302.549814) (xy 270.648084 -302.50076)
			(xy 270.659861 -302.452976) (xy 270.679152 -302.4077) (xy 270.705455 -302.366104) (xy 270.73809 -302.329267)
			(xy 270.776211 -302.298142) (xy 270.818832 -302.273535) (xy 270.864848 -302.256083) (xy 270.913067 -302.246239)
			(xy 270.962242 -302.244258) (xy 271.011097 -302.25019) (xy 271.058368 -302.263882) (xy 271.10283 -302.28498)
			(xy 271.143333 -302.312936) (xy 271.178826 -302.347028) (xy 271.208391 -302.386372) (xy 271.231262 -302.429949)
			(xy 271.246846 -302.47663) (xy 271.254741 -302.525207) (xy 271.255236 -302.549814) (xy 271.594084 -302.549814)
			(xy 271.598044 -302.50076) (xy 271.609821 -302.452976) (xy 271.629112 -302.4077) (xy 271.655415 -302.366104)
			(xy 271.68805 -302.329267) (xy 271.726171 -302.298142) (xy 271.768792 -302.273535) (xy 271.814808 -302.256083)
			(xy 271.863027 -302.246239) (xy 271.912202 -302.244258) (xy 271.961057 -302.25019) (xy 272.008328 -302.263882)
			(xy 272.05279 -302.28498) (xy 272.093293 -302.312936) (xy 272.128786 -302.347028) (xy 272.158351 -302.386372)
			(xy 272.181222 -302.429949) (xy 272.196806 -302.47663) (xy 272.204701 -302.525207) (xy 272.205196 -302.549814)
			(xy 272.544044 -302.549814) (xy 272.548004 -302.50076) (xy 272.559781 -302.452976) (xy 272.579072 -302.4077)
			(xy 272.605375 -302.366104) (xy 272.63801 -302.329267) (xy 272.676131 -302.298142) (xy 272.718752 -302.273535)
			(xy 272.764768 -302.256083) (xy 272.812987 -302.246239) (xy 272.862162 -302.244258) (xy 272.911017 -302.25019)
			(xy 272.958288 -302.263882) (xy 273.00275 -302.28498) (xy 273.043253 -302.312936) (xy 273.078746 -302.347028)
			(xy 273.108311 -302.386372) (xy 273.131182 -302.429949) (xy 273.146766 -302.47663) (xy 273.154661 -302.525207)
			(xy 273.155156 -302.549814) (xy 273.494004 -302.549814) (xy 273.497964 -302.50076) (xy 273.509741 -302.452976)
			(xy 273.529032 -302.4077) (xy 273.555335 -302.366104) (xy 273.58797 -302.329267) (xy 273.626091 -302.298142)
			(xy 273.668712 -302.273535) (xy 273.714728 -302.256083) (xy 273.762947 -302.246239) (xy 273.812122 -302.244258)
			(xy 273.860977 -302.25019) (xy 273.908248 -302.263882) (xy 273.95271 -302.28498) (xy 273.993213 -302.312936)
			(xy 274.028706 -302.347028) (xy 274.058271 -302.386372) (xy 274.081142 -302.429949) (xy 274.096726 -302.47663)
			(xy 274.104621 -302.525207) (xy 274.105116 -302.549814) (xy 274.443964 -302.549814) (xy 274.447924 -302.50076)
			(xy 274.459701 -302.452976) (xy 274.478992 -302.4077) (xy 274.505295 -302.366104) (xy 274.53793 -302.329267)
			(xy 274.576051 -302.298142) (xy 274.618672 -302.273535) (xy 274.664688 -302.256083) (xy 274.712907 -302.246239)
			(xy 274.762082 -302.244258) (xy 274.810937 -302.25019) (xy 274.858208 -302.263882) (xy 274.90267 -302.28498)
			(xy 274.943173 -302.312936) (xy 274.978666 -302.347028) (xy 275.008231 -302.386372) (xy 275.031102 -302.429949)
			(xy 275.046686 -302.47663) (xy 275.054581 -302.525207) (xy 275.055076 -302.549814) (xy 275.054581 -302.574421)
			(xy 275.054402 -302.575522) (xy 275.37308 -302.575522) (xy 275.37308 -302.524106) (xy 275.381123 -302.473324)
			(xy 275.397011 -302.424425) (xy 275.420354 -302.378613) (xy 275.450575 -302.337017) (xy 275.486931 -302.300661)
			(xy 275.528527 -302.27044) (xy 275.574339 -302.247097) (xy 275.623238 -302.231209) (xy 275.67402 -302.223166)
			(xy 275.725436 -302.223166) (xy 275.776218 -302.231209) (xy 275.825117 -302.247097) (xy 275.870929 -302.27044)
			(xy 275.912525 -302.300661) (xy 275.948881 -302.337017) (xy 275.979102 -302.378613) (xy 276.002445 -302.424425)
			(xy 276.018333 -302.473324) (xy 276.026376 -302.524106) (xy 276.02688 -302.549814) (xy 276.026376 -302.575522)
			(xy 276.32304 -302.575522) (xy 276.32304 -302.524106) (xy 276.331083 -302.473324) (xy 276.346971 -302.424425)
			(xy 276.370314 -302.378613) (xy 276.400535 -302.337017) (xy 276.436891 -302.300661) (xy 276.478487 -302.27044)
			(xy 276.524299 -302.247097) (xy 276.573198 -302.231209) (xy 276.62398 -302.223166) (xy 276.675396 -302.223166)
			(xy 276.726178 -302.231209) (xy 276.775077 -302.247097) (xy 276.820889 -302.27044) (xy 276.862485 -302.300661)
			(xy 276.898841 -302.337017) (xy 276.929062 -302.378613) (xy 276.952405 -302.424425) (xy 276.968293 -302.473324)
			(xy 276.976336 -302.524106) (xy 276.97684 -302.549814) (xy 277.294098 -302.549814) (xy 277.298058 -302.50076)
			(xy 277.309835 -302.452976) (xy 277.329126 -302.4077) (xy 277.355429 -302.366104) (xy 277.388064 -302.329267)
			(xy 277.426185 -302.298142) (xy 277.468806 -302.273535) (xy 277.514822 -302.256083) (xy 277.563041 -302.246239)
			(xy 277.612216 -302.244258) (xy 277.661071 -302.25019) (xy 277.708342 -302.263882) (xy 277.752804 -302.28498)
			(xy 277.793307 -302.312936) (xy 277.8288 -302.347028) (xy 277.858365 -302.386372) (xy 277.881236 -302.429949)
			(xy 277.89682 -302.47663) (xy 277.904715 -302.525207) (xy 277.90521 -302.549814) (xy 277.904715 -302.574421)
			(xy 277.89682 -302.622998) (xy 277.881236 -302.669679) (xy 277.858365 -302.713256) (xy 277.8288 -302.7526)
			(xy 277.793307 -302.786692) (xy 277.752804 -302.814648) (xy 277.708342 -302.835746) (xy 277.661071 -302.849438)
			(xy 277.612216 -302.85537) (xy 277.563041 -302.853389) (xy 277.514822 -302.843545) (xy 277.468806 -302.826093)
			(xy 277.426185 -302.801486) (xy 277.388064 -302.770361) (xy 277.355429 -302.733524) (xy 277.329126 -302.691928)
			(xy 277.309835 -302.646652) (xy 277.298058 -302.598868) (xy 277.294098 -302.549814) (xy 276.97684 -302.549814)
			(xy 276.976336 -302.575522) (xy 276.968293 -302.626304) (xy 276.952405 -302.675203) (xy 276.929062 -302.721015)
			(xy 276.898841 -302.762611) (xy 276.862485 -302.798967) (xy 276.820889 -302.829188) (xy 276.775077 -302.852531)
			(xy 276.726178 -302.868419) (xy 276.675396 -302.876462) (xy 276.62398 -302.876462) (xy 276.573198 -302.868419)
			(xy 276.524299 -302.852531) (xy 276.478487 -302.829188) (xy 276.436891 -302.798967) (xy 276.400535 -302.762611)
			(xy 276.370314 -302.721015) (xy 276.346971 -302.675203) (xy 276.331083 -302.626304) (xy 276.32304 -302.575522)
			(xy 276.026376 -302.575522) (xy 276.018333 -302.626304) (xy 276.002445 -302.675203) (xy 275.979102 -302.721015)
			(xy 275.948881 -302.762611) (xy 275.912525 -302.798967) (xy 275.870929 -302.829188) (xy 275.825117 -302.852531)
			(xy 275.776218 -302.868419) (xy 275.725436 -302.876462) (xy 275.67402 -302.876462) (xy 275.623238 -302.868419)
			(xy 275.574339 -302.852531) (xy 275.528527 -302.829188) (xy 275.486931 -302.798967) (xy 275.450575 -302.762611)
			(xy 275.420354 -302.721015) (xy 275.397011 -302.675203) (xy 275.381123 -302.626304) (xy 275.37308 -302.575522)
			(xy 275.054402 -302.575522) (xy 275.046686 -302.622998) (xy 275.031102 -302.669679) (xy 275.008231 -302.713256)
			(xy 274.978666 -302.7526) (xy 274.943173 -302.786692) (xy 274.90267 -302.814648) (xy 274.858208 -302.835746)
			(xy 274.810937 -302.849438) (xy 274.762082 -302.85537) (xy 274.712907 -302.853389) (xy 274.664688 -302.843545)
			(xy 274.618672 -302.826093) (xy 274.576051 -302.801486) (xy 274.53793 -302.770361) (xy 274.505295 -302.733524)
			(xy 274.478992 -302.691928) (xy 274.459701 -302.646652) (xy 274.447924 -302.598868) (xy 274.443964 -302.549814)
			(xy 274.105116 -302.549814) (xy 274.104621 -302.574421) (xy 274.096726 -302.622998) (xy 274.081142 -302.669679)
			(xy 274.058271 -302.713256) (xy 274.028706 -302.7526) (xy 273.993213 -302.786692) (xy 273.95271 -302.814648)
			(xy 273.908248 -302.835746) (xy 273.860977 -302.849438) (xy 273.812122 -302.85537) (xy 273.762947 -302.853389)
			(xy 273.714728 -302.843545) (xy 273.668712 -302.826093) (xy 273.626091 -302.801486) (xy 273.58797 -302.770361)
			(xy 273.555335 -302.733524) (xy 273.529032 -302.691928) (xy 273.509741 -302.646652) (xy 273.497964 -302.598868)
			(xy 273.494004 -302.549814) (xy 273.155156 -302.549814) (xy 273.154661 -302.574421) (xy 273.146766 -302.622998)
			(xy 273.131182 -302.669679) (xy 273.108311 -302.713256) (xy 273.078746 -302.7526) (xy 273.043253 -302.786692)
			(xy 273.00275 -302.814648) (xy 272.958288 -302.835746) (xy 272.911017 -302.849438) (xy 272.862162 -302.85537)
			(xy 272.812987 -302.853389) (xy 272.764768 -302.843545) (xy 272.718752 -302.826093) (xy 272.676131 -302.801486)
			(xy 272.63801 -302.770361) (xy 272.605375 -302.733524) (xy 272.579072 -302.691928) (xy 272.559781 -302.646652)
			(xy 272.548004 -302.598868) (xy 272.544044 -302.549814) (xy 272.205196 -302.549814) (xy 272.204701 -302.574421)
			(xy 272.196806 -302.622998) (xy 272.181222 -302.669679) (xy 272.158351 -302.713256) (xy 272.128786 -302.7526)
			(xy 272.093293 -302.786692) (xy 272.05279 -302.814648) (xy 272.008328 -302.835746) (xy 271.961057 -302.849438)
			(xy 271.912202 -302.85537) (xy 271.863027 -302.853389) (xy 271.814808 -302.843545) (xy 271.768792 -302.826093)
			(xy 271.726171 -302.801486) (xy 271.68805 -302.770361) (xy 271.655415 -302.733524) (xy 271.629112 -302.691928)
			(xy 271.609821 -302.646652) (xy 271.598044 -302.598868) (xy 271.594084 -302.549814) (xy 271.255236 -302.549814)
			(xy 271.254741 -302.574421) (xy 271.246846 -302.622998) (xy 271.231262 -302.669679) (xy 271.208391 -302.713256)
			(xy 271.178826 -302.7526) (xy 271.143333 -302.786692) (xy 271.10283 -302.814648) (xy 271.058368 -302.835746)
			(xy 271.011097 -302.849438) (xy 270.962242 -302.85537) (xy 270.913067 -302.853389) (xy 270.864848 -302.843545)
			(xy 270.818832 -302.826093) (xy 270.776211 -302.801486) (xy 270.73809 -302.770361) (xy 270.705455 -302.733524)
			(xy 270.679152 -302.691928) (xy 270.659861 -302.646652) (xy 270.648084 -302.598868) (xy 270.644124 -302.549814)
			(xy 270.326866 -302.549814) (xy 270.326362 -302.575522) (xy 270.318319 -302.626304) (xy 270.302431 -302.675203)
			(xy 270.279088 -302.721015) (xy 270.248867 -302.762611) (xy 270.212511 -302.798967) (xy 270.170915 -302.829188)
			(xy 270.125103 -302.852531) (xy 270.076204 -302.868419) (xy 270.025422 -302.876462) (xy 269.974006 -302.876462)
			(xy 269.923224 -302.868419) (xy 269.874325 -302.852531) (xy 269.828513 -302.829188) (xy 269.786917 -302.798967)
			(xy 269.750561 -302.762611) (xy 269.72034 -302.721015) (xy 269.696997 -302.675203) (xy 269.681109 -302.626304)
			(xy 269.673066 -302.575522) (xy 269.376402 -302.575522) (xy 269.368359 -302.626304) (xy 269.352471 -302.675203)
			(xy 269.329128 -302.721015) (xy 269.298907 -302.762611) (xy 269.262551 -302.798967) (xy 269.220955 -302.829188)
			(xy 269.175143 -302.852531) (xy 269.126244 -302.868419) (xy 269.075462 -302.876462) (xy 269.024046 -302.876462)
			(xy 268.973264 -302.868419) (xy 268.924365 -302.852531) (xy 268.878553 -302.829188) (xy 268.836957 -302.798967)
			(xy 268.800601 -302.762611) (xy 268.77038 -302.721015) (xy 268.747037 -302.675203) (xy 268.731149 -302.626304)
			(xy 268.723106 -302.575522) (xy 268.404215 -302.575522) (xy 268.396458 -302.623252) (xy 268.380874 -302.669933)
			(xy 268.358003 -302.71351) (xy 268.328438 -302.752854) (xy 268.292945 -302.786946) (xy 268.252442 -302.814902)
			(xy 268.20798 -302.836) (xy 268.160709 -302.849692) (xy 268.111854 -302.855624) (xy 268.062679 -302.853643)
			(xy 268.01446 -302.843799) (xy 267.968444 -302.826347) (xy 267.925823 -302.80174) (xy 267.887702 -302.770615)
			(xy 267.855067 -302.733778) (xy 267.828764 -302.692182) (xy 267.809473 -302.646906) (xy 267.797696 -302.599122)
			(xy 267.793736 -302.550068) (xy 262.060944 -302.550068) (xy 262.060944 -303.024794) (xy 278.719038 -303.024794)
			(xy 278.722998 -302.97574) (xy 278.734775 -302.927956) (xy 278.754066 -302.88268) (xy 278.780369 -302.841084)
			(xy 278.813004 -302.804247) (xy 278.851125 -302.773122) (xy 278.893746 -302.748515) (xy 278.939762 -302.731063)
			(xy 278.987981 -302.721219) (xy 279.037156 -302.719238) (xy 279.086011 -302.72517) (xy 279.133282 -302.738862)
			(xy 279.177744 -302.75996) (xy 279.218247 -302.787916) (xy 279.25374 -302.822008) (xy 279.283305 -302.861352)
			(xy 279.306176 -302.904929) (xy 279.32176 -302.95161) (xy 279.329655 -303.000187) (xy 279.33015 -303.024794)
			(xy 279.668998 -303.024794) (xy 279.672958 -302.97574) (xy 279.684735 -302.927956) (xy 279.704026 -302.88268)
			(xy 279.730329 -302.841084) (xy 279.762964 -302.804247) (xy 279.801085 -302.773122) (xy 279.843706 -302.748515)
			(xy 279.889722 -302.731063) (xy 279.937941 -302.721219) (xy 279.987116 -302.719238) (xy 280.035971 -302.72517)
			(xy 280.083242 -302.738862) (xy 280.127704 -302.75996) (xy 280.168207 -302.787916) (xy 280.2037 -302.822008)
			(xy 280.233265 -302.861352) (xy 280.256136 -302.904929) (xy 280.27172 -302.95161) (xy 280.279615 -303.000187)
			(xy 280.28011 -303.024794) (xy 280.279615 -303.049401) (xy 280.27172 -303.097978) (xy 280.256136 -303.144659)
			(xy 280.233265 -303.188236) (xy 280.2037 -303.22758) (xy 280.168207 -303.261672) (xy 280.127704 -303.289628)
			(xy 280.083242 -303.310726) (xy 280.035971 -303.324418) (xy 279.987116 -303.33035) (xy 279.937941 -303.328369)
			(xy 279.889722 -303.318525) (xy 279.843706 -303.301073) (xy 279.801085 -303.276466) (xy 279.762964 -303.245341)
			(xy 279.730329 -303.208504) (xy 279.704026 -303.166908) (xy 279.684735 -303.121632) (xy 279.672958 -303.073848)
			(xy 279.668998 -303.024794) (xy 279.33015 -303.024794) (xy 279.329655 -303.049401) (xy 279.32176 -303.097978)
			(xy 279.306176 -303.144659) (xy 279.283305 -303.188236) (xy 279.25374 -303.22758) (xy 279.218247 -303.261672)
			(xy 279.177744 -303.289628) (xy 279.133282 -303.310726) (xy 279.086011 -303.324418) (xy 279.037156 -303.33035)
			(xy 278.987981 -303.328369) (xy 278.939762 -303.318525) (xy 278.893746 -303.301073) (xy 278.851125 -303.276466)
			(xy 278.813004 -303.245341) (xy 278.780369 -303.208504) (xy 278.754066 -303.166908) (xy 278.734775 -303.121632)
			(xy 278.722998 -303.073848) (xy 278.719038 -303.024794) (xy 262.060944 -303.024794) (xy 262.060944 -303.556162)
			(xy 262.061411 -303.566037) (xy 262.068859 -303.584329) (xy 262.075422 -303.591722) (xy 262.075676 -303.591976)
			(xy 262.387842 -303.904142) (xy 262.38835 -303.90465) (xy 262.395731 -303.911233) (xy 262.41403 -303.918685)
			(xy 262.42391 -303.919128)
		)
		(stroke
			(width 0)
			(type solid)
		)
		(fill yes)
		(layer "In13.Cu")
		(net "PCEPLL0_VDDA18_PEX2")
	)
	(gr_poly
		(pts
			(xy 45.487336 -292.800532) (xy 45.499362 -292.799861) (xy 45.520824 -292.788998) (xy 45.528484 -292.779704)
			(xy 45.576744 -292.71341) (xy 45.583305 -292.703321) (xy 45.587133 -292.679595) (xy 45.58411 -292.667944)
			(xy 45.577339 -292.645303) (xy 45.570074 -292.598608) (xy 45.569632 -292.57498) (xy 45.570154 -292.549725)
			(xy 45.578467 -292.499903) (xy 45.594868 -292.452129) (xy 45.618909 -292.407706) (xy 45.649933 -292.367846)
			(xy 45.687095 -292.333636) (xy 45.729381 -292.30601) (xy 45.775637 -292.28572) (xy 45.824602 -292.27332)
			(xy 45.87494 -292.269149) (xy 45.925278 -292.27332) (xy 45.974243 -292.28572) (xy 46.020499 -292.30601)
			(xy 46.062785 -292.333636) (xy 46.099947 -292.367846) (xy 46.130971 -292.407706) (xy 46.155012 -292.452129)
			(xy 46.171413 -292.499903) (xy 46.179726 -292.549725) (xy 46.180248 -292.57498) (xy 46.179804 -292.598608)
			(xy 46.17253 -292.6453) (xy 46.16577 -292.667944) (xy 46.16274 -292.679589) (xy 46.166601 -292.703304)
			(xy 46.173136 -292.71341) (xy 46.221396 -292.779704) (xy 46.229017 -292.789047) (xy 46.250502 -292.799911)
			(xy 46.262544 -292.800532) (xy 46.87443 -292.800532) (xy 46.884498 -292.800104) (xy 46.903098 -292.792386)
			(xy 46.910498 -292.785546) (xy 47.021242 -292.674802) (xy 47.028095 -292.667406) (xy 47.03584 -292.648808)
			(xy 47.036228 -292.638734) (xy 47.036228 -291.066474) (xy 47.035636 -291.054717) (xy 47.025174 -291.033661)
			(xy 47.016162 -291.026088) (xy 46.951392 -290.977066) (xy 46.941728 -290.970531) (xy 46.918837 -290.966151)
			(xy 46.90745 -290.968684) (xy 46.907196 -290.968684) (xy 46.88704 -290.974015) (xy 46.845745 -290.979755)
			(xy 46.8249 -290.980114) (xy 46.799644 -290.979592) (xy 46.749821 -290.971278) (xy 46.702047 -290.954877)
			(xy 46.657623 -290.930836) (xy 46.617762 -290.899812) (xy 46.583552 -290.862649) (xy 46.555924 -290.820362)
			(xy 46.535634 -290.774105) (xy 46.523234 -290.725139) (xy 46.519063 -290.6748) (xy 46.523234 -290.624461)
			(xy 46.535634 -290.575495) (xy 46.555924 -290.529238) (xy 46.583552 -290.486951) (xy 46.617762 -290.449788)
			(xy 46.657623 -290.418764) (xy 46.702047 -290.394723) (xy 46.749821 -290.378322) (xy 46.799644 -290.370008)
			(xy 46.8249 -290.369498) (xy 46.84568 -290.3699) (xy 46.886844 -290.375633) (xy 46.906942 -290.380928)
			(xy 46.90745 -290.380928) (xy 46.918839 -290.383463) (xy 46.941734 -290.379094) (xy 46.951392 -290.372546)
			(xy 47.016162 -290.323524) (xy 47.025139 -290.315926) (xy 47.035579 -290.294882) (xy 47.036228 -290.283138)
			(xy 47.036228 -290.116514) (xy 47.035623 -290.104764) (xy 47.025147 -290.083728) (xy 47.016162 -290.076128)
			(xy 46.951392 -290.027106) (xy 46.941729 -290.020567) (xy 46.918836 -290.016184) (xy 46.90745 -290.018724)
			(xy 46.907196 -290.018724) (xy 46.88704 -290.024054) (xy 46.845745 -290.029793) (xy 46.8249 -290.030154)
			(xy 46.799641 -290.029633) (xy 46.749812 -290.021318) (xy 46.70203 -290.004914) (xy 46.657601 -289.98087)
			(xy 46.617735 -289.949841) (xy 46.58352 -289.912674) (xy 46.555889 -289.870382) (xy 46.535596 -289.824118)
			(xy 46.523194 -289.775146) (xy 46.519023 -289.7248) (xy 46.523194 -289.674454) (xy 46.535596 -289.625482)
			(xy 46.555889 -289.579218) (xy 46.58352 -289.536926) (xy 46.617735 -289.499759) (xy 46.657601 -289.46873)
			(xy 46.70203 -289.444686) (xy 46.749812 -289.428282) (xy 46.799641 -289.419967) (xy 46.8249 -289.419538)
			(xy 46.84568 -289.419941) (xy 46.886844 -289.425674) (xy 46.906942 -289.430968) (xy 46.90745 -289.430968)
			(xy 46.91884 -289.433502) (xy 46.941735 -289.429136) (xy 46.951392 -289.422586) (xy 47.016162 -289.373564)
			(xy 47.025146 -289.365969) (xy 47.035602 -289.344925) (xy 47.036228 -289.333178) (xy 47.036228 -289.166554)
			(xy 47.035631 -289.154799) (xy 47.025165 -289.13375) (xy 47.016162 -289.126168) (xy 46.951392 -289.077146)
			(xy 46.941727 -289.070613) (xy 46.918837 -289.066235) (xy 46.90745 -289.068764) (xy 46.907196 -289.068764)
			(xy 46.88704 -289.074095) (xy 46.845745 -289.079835) (xy 46.8249 -289.080194) (xy 46.799646 -289.079672)
			(xy 46.749826 -289.071359) (xy 46.702055 -289.054959) (xy 46.657634 -289.03092) (xy 46.617776 -288.999897)
			(xy 46.583567 -288.962737) (xy 46.555942 -288.920453) (xy 46.535653 -288.874199) (xy 46.523254 -288.825236)
			(xy 46.519083 -288.7749) (xy 46.523254 -288.724564) (xy 46.535653 -288.675601) (xy 46.555942 -288.629347)
			(xy 46.583567 -288.587063) (xy 46.617776 -288.549903) (xy 46.657634 -288.51888) (xy 46.702055 -288.494841)
			(xy 46.749826 -288.478441) (xy 46.799646 -288.470128) (xy 46.8249 -288.469578) (xy 46.84568 -288.46998)
			(xy 46.886844 -288.475713) (xy 46.906942 -288.481008) (xy 46.90745 -288.481008) (xy 46.918839 -288.483543)
			(xy 46.941733 -288.479172) (xy 46.951392 -288.472626) (xy 47.016162 -288.423604) (xy 47.025136 -288.416005)
			(xy 47.035568 -288.394961) (xy 47.036228 -288.383218) (xy 47.036228 -288.216594) (xy 47.03564 -288.204835)
			(xy 47.025183 -288.183772) (xy 47.016162 -288.176208) (xy 46.951392 -288.127186) (xy 46.941728 -288.120649)
			(xy 46.918837 -288.116268) (xy 46.90745 -288.118804) (xy 46.907196 -288.118804) (xy 46.88704 -288.124134)
			(xy 46.845745 -288.129874) (xy 46.8249 -288.130234) (xy 46.799643 -288.129712) (xy 46.749817 -288.121398)
			(xy 46.702039 -288.104996) (xy 46.657612 -288.080953) (xy 46.617749 -288.049926) (xy 46.583536 -288.012761)
			(xy 46.555907 -287.970472) (xy 46.535615 -287.924212) (xy 46.523214 -287.875242) (xy 46.519043 -287.8249)
			(xy 46.523214 -287.774558) (xy 46.535615 -287.725588) (xy 46.555907 -287.679328) (xy 46.583536 -287.637039)
			(xy 46.617749 -287.599874) (xy 46.657612 -287.568847) (xy 46.702039 -287.544804) (xy 46.749817 -287.528402)
			(xy 46.799643 -287.520088) (xy 46.8249 -287.519618) (xy 46.84568 -287.52002) (xy 46.886844 -287.525754)
			(xy 46.906942 -287.531048) (xy 46.90745 -287.531048) (xy 46.91884 -287.533583) (xy 46.941734 -287.529214)
			(xy 46.951392 -287.522666) (xy 47.016162 -287.473644) (xy 47.025142 -287.466048) (xy 47.035591 -287.445004)
			(xy 47.036228 -287.433258) (xy 47.036228 -287.266634) (xy 47.035627 -287.254882) (xy 47.025156 -287.233839)
			(xy 47.016162 -287.226248) (xy 46.951392 -287.177226) (xy 46.941729 -287.170685) (xy 46.918836 -287.1663)
			(xy 46.90745 -287.168844) (xy 46.907196 -287.168844) (xy 46.88704 -287.174174) (xy 46.845745 -287.179913)
			(xy 46.8249 -287.180274) (xy 46.799647 -287.179753) (xy 46.749831 -287.17144) (xy 46.702063 -287.155041)
			(xy 46.657645 -287.131003) (xy 46.617789 -287.099982) (xy 46.583583 -287.062824) (xy 46.55596 -287.020543)
			(xy 46.535672 -286.974292) (xy 46.523274 -286.925333) (xy 46.519103 -286.875) (xy 46.523274 -286.824667)
			(xy 46.535672 -286.775708) (xy 46.55596 -286.729457) (xy 46.583583 -286.687176) (xy 46.617789 -286.650018)
			(xy 46.657645 -286.618997) (xy 46.702063 -286.594959) (xy 46.749831 -286.57856) (xy 46.799647 -286.570247)
			(xy 46.8249 -286.569658) (xy 46.84568 -286.57006) (xy 46.886844 -286.575793) (xy 46.906942 -286.581088)
			(xy 46.90745 -286.581088) (xy 46.91884 -286.583622) (xy 46.941736 -286.579256) (xy 46.951392 -286.572706)
			(xy 47.016162 -286.523684) (xy 47.025149 -286.51609) (xy 47.035614 -286.495047) (xy 47.036228 -286.483298)
			(xy 47.036228 -286.31642) (xy 47.035624 -286.304669) (xy 47.02515 -286.283631) (xy 47.016162 -286.276034)
			(xy 46.951392 -286.227012) (xy 46.941729 -286.220472) (xy 46.918836 -286.216089) (xy 46.90745 -286.21863)
			(xy 46.907196 -286.21863) (xy 46.88704 -286.22396) (xy 46.845745 -286.229699) (xy 46.8249 -286.23006)
			(xy 46.799649 -286.229539) (xy 46.749835 -286.221226) (xy 46.702068 -286.204828) (xy 46.657653 -286.180791)
			(xy 46.617799 -286.149772) (xy 46.583594 -286.112616) (xy 46.555972 -286.070337) (xy 46.535685 -286.024088)
			(xy 46.523287 -285.97513) (xy 46.519117 -285.9248) (xy 46.523287 -285.87447) (xy 46.535685 -285.825512)
			(xy 46.555972 -285.779263) (xy 46.583594 -285.736984) (xy 46.617799 -285.699828) (xy 46.657653 -285.668809)
			(xy 46.702068 -285.644772) (xy 46.749835 -285.628374) (xy 46.799649 -285.620061) (xy 46.8249 -285.619444)
			(xy 46.84568 -285.619847) (xy 46.886844 -285.62558) (xy 46.906942 -285.630874) (xy 46.90745 -285.630874)
			(xy 46.91884 -285.633408) (xy 46.941735 -285.629042) (xy 46.951392 -285.622492) (xy 47.016162 -285.57347)
			(xy 47.025146 -285.565875) (xy 47.035606 -285.544832) (xy 47.036228 -285.533084) (xy 47.036228 -285.36646)
			(xy 47.035633 -285.354705) (xy 47.025168 -285.333653) (xy 47.016162 -285.326074) (xy 46.951392 -285.277052)
			(xy 46.941727 -285.270519) (xy 46.918837 -285.26614) (xy 46.90745 -285.26867) (xy 46.907196 -285.26867)
			(xy 46.88704 -285.274001) (xy 46.845745 -285.279741) (xy 46.8249 -285.2801) (xy 46.799645 -285.279578)
			(xy 46.749825 -285.271265) (xy 46.702052 -285.254865) (xy 46.657631 -285.230825) (xy 46.617772 -285.199801)
			(xy 46.583563 -285.16264) (xy 46.555937 -285.120356) (xy 46.535647 -285.074101) (xy 46.523248 -285.025137)
			(xy 46.519077 -284.9748) (xy 46.523248 -284.924463) (xy 46.535647 -284.875499) (xy 46.555937 -284.829244)
			(xy 46.583563 -284.78696) (xy 46.617772 -284.749799) (xy 46.657631 -284.718775) (xy 46.702052 -284.694735)
			(xy 46.749825 -284.678335) (xy 46.799645 -284.670022) (xy 46.8249 -284.669484) (xy 46.848714 -284.669939)
			(xy 46.895766 -284.677328) (xy 46.941103 -284.691927) (xy 46.962568 -284.70225) (xy 46.967902 -284.705044)
			(xy 46.979332 -284.707838) (xy 46.985428 -284.707838) (xy 46.995435 -284.707346) (xy 47.013923 -284.699683)
			(xy 47.028077 -284.685532) (xy 47.035744 -284.667045) (xy 47.036228 -284.657038) (xy 47.036228 -284.606492)
			(xy 47.035804 -284.596422) (xy 47.028091 -284.577817) (xy 47.021242 -284.570424) (xy 46.78299 -284.332172)
			(xy 46.77029 -284.325314) (xy 46.762924 -284.32379) (xy 46.738076 -284.31809) (xy 46.690587 -284.299556)
			(xy 46.64683 -284.273401) (xy 46.608018 -284.240352) (xy 46.59122 -284.221174) (xy 46.583577 -284.213005)
			(xy 46.56328 -284.203662) (xy 46.552104 -284.20314) (xy 46.147736 -284.20314) (xy 46.136561 -284.203657)
			(xy 46.116265 -284.213007) (xy 46.10862 -284.221174) (xy 46.092683 -284.239398) (xy 46.056064 -284.271061)
			(xy 46.014909 -284.29655) (xy 45.970247 -284.315226) (xy 45.923198 -284.326623) (xy 45.87494 -284.330453)
			(xy 45.826682 -284.326623) (xy 45.779633 -284.315226) (xy 45.734971 -284.29655) (xy 45.693816 -284.271061)
			(xy 45.657197 -284.239398) (xy 45.64126 -284.221174) (xy 45.63362 -284.212998) (xy 45.613323 -284.203639)
			(xy 45.602144 -284.20314) (xy 45.197776 -284.20314) (xy 45.186606 -284.203669) (xy 45.16633 -284.213035)
			(xy 45.15866 -284.221174) (xy 45.142723 -284.239398) (xy 45.106104 -284.271061) (xy 45.064949 -284.29655)
			(xy 45.020287 -284.315226) (xy 44.973238 -284.326623) (xy 44.92498 -284.330453) (xy 44.876722 -284.326623)
			(xy 44.829673 -284.315226) (xy 44.785011 -284.29655) (xy 44.743856 -284.271061) (xy 44.707237 -284.239398)
			(xy 44.6913 -284.221174) (xy 44.683662 -284.212991) (xy 44.663366 -284.203617) (xy 44.652184 -284.20314)
			(xy 41.397682 -284.20314) (xy 41.386512 -284.203667) (xy 41.366233 -284.213032) (xy 41.358566 -284.221174)
			(xy 41.342629 -284.239398) (xy 41.30601 -284.271061) (xy 41.264855 -284.29655) (xy 41.220193 -284.315226)
			(xy 41.173144 -284.326623) (xy 41.124886 -284.330453) (xy 41.076628 -284.326623) (xy 41.029579 -284.315226)
			(xy 40.984917 -284.29655) (xy 40.943762 -284.271061) (xy 40.907143 -284.239398) (xy 40.891206 -284.221174)
			(xy 40.883568 -284.21299) (xy 40.863272 -284.203613) (xy 40.85209 -284.20314) (xy 40.447722 -284.20314)
			(xy 40.436548 -284.203659) (xy 40.416257 -284.213014) (xy 40.408606 -284.221174) (xy 40.392669 -284.239398)
			(xy 40.35605 -284.271061) (xy 40.314895 -284.29655) (xy 40.270233 -284.315226) (xy 40.223184 -284.326623)
			(xy 40.174926 -284.330453) (xy 40.126668 -284.326623) (xy 40.079619 -284.315226) (xy 40.034957 -284.29655)
			(xy 39.993802 -284.271061) (xy 39.957183 -284.239398) (xy 39.941246 -284.221174) (xy 39.933605 -284.213)
			(xy 39.913308 -284.203647) (xy 39.90213 -284.20314) (xy 39.497762 -284.20314) (xy 39.486584 -284.203651)
			(xy 39.466281 -284.212996) (xy 39.458646 -284.221174) (xy 39.442709 -284.239398) (xy 39.40609 -284.271061)
			(xy 39.364935 -284.29655) (xy 39.320273 -284.315226) (xy 39.273224 -284.326623) (xy 39.224966 -284.330453)
			(xy 39.176708 -284.326623) (xy 39.129659 -284.315226) (xy 39.084997 -284.29655) (xy 39.043842 -284.271061)
			(xy 39.007223 -284.239398) (xy 38.991286 -284.221174) (xy 38.983647 -284.212994) (xy 38.963351 -284.203625)
			(xy 38.95217 -284.20314) (xy 38.547802 -284.20314) (xy 38.53663 -284.203663) (xy 38.516345 -284.213023)
			(xy 38.508686 -284.221174) (xy 38.492749 -284.239398) (xy 38.45613 -284.271061) (xy 38.414975 -284.29655)
			(xy 38.370313 -284.315226) (xy 38.323264 -284.326623) (xy 38.275006 -284.330453) (xy 38.226748 -284.326623)
			(xy 38.179699 -284.315226) (xy 38.135037 -284.29655) (xy 38.093882 -284.271061) (xy 38.057263 -284.239398)
			(xy 38.041326 -284.221174) (xy 38.033683 -284.213004) (xy 38.013387 -284.203659) (xy 38.00221 -284.20314)
			(xy 37.597588 -284.20314) (xy 37.586417 -284.203666) (xy 37.566137 -284.213029) (xy 37.558472 -284.221174)
			(xy 37.542535 -284.239398) (xy 37.505916 -284.271061) (xy 37.464761 -284.29655) (xy 37.420099 -284.315226)
			(xy 37.37305 -284.326623) (xy 37.324792 -284.330453) (xy 37.276534 -284.326623) (xy 37.229485 -284.315226)
			(xy 37.184823 -284.29655) (xy 37.143668 -284.271061) (xy 37.107049 -284.239398) (xy 37.091112 -284.221174)
			(xy 37.083469 -284.213006) (xy 37.063172 -284.203666) (xy 37.051996 -284.20314) (xy 36.647628 -284.20314)
			(xy 36.636453 -284.203658) (xy 36.616161 -284.213011) (xy 36.608512 -284.221174) (xy 36.592575 -284.239398)
			(xy 36.555956 -284.271061) (xy 36.514801 -284.29655) (xy 36.470139 -284.315226) (xy 36.42309 -284.326623)
			(xy 36.374832 -284.330453) (xy 36.326574 -284.326623) (xy 36.279525 -284.315226) (xy 36.234863 -284.29655)
			(xy 36.193708 -284.271061) (xy 36.157089 -284.239398) (xy 36.141152 -284.221174) (xy 36.133511 -284.212999)
			(xy 36.113214 -284.203644) (xy 36.102036 -284.20314) (xy 34.24174 -284.20314) (xy 34.234326 -284.203389)
			(xy 34.22012 -284.207639) (xy 34.2138 -284.211522) (xy 34.191256 -284.22595) (xy 34.142964 -284.249029)
			(xy 34.091917 -284.265123) (xy 34.039121 -284.273915) (xy 34.012378 -284.275022) (xy 34.002654 -284.275707)
			(xy 33.984769 -284.283423) (xy 33.97758 -284.290008) (xy 33.476438 -284.79115) (xy 33.469039 -284.797992)
			(xy 33.45044 -284.805712) (xy 33.44037 -284.806136) (xy 32.174942 -284.806136) (xy 32.164877 -284.80657)
			(xy 32.146291 -284.814304) (xy 32.138874 -284.821122) (xy 31.985204 -284.974792) (xy 36.069028 -284.974792)
			(xy 36.072988 -284.925738) (xy 36.084765 -284.877954) (xy 36.104056 -284.832678) (xy 36.130359 -284.791082)
			(xy 36.162994 -284.754245) (xy 36.201115 -284.72312) (xy 36.243736 -284.698513) (xy 36.289752 -284.681061)
			(xy 36.337971 -284.671217) (xy 36.387146 -284.669236) (xy 36.436001 -284.675168) (xy 36.483272 -284.68886)
			(xy 36.527734 -284.709958) (xy 36.568237 -284.737914) (xy 36.60373 -284.772006) (xy 36.633295 -284.81135)
			(xy 36.656166 -284.854927) (xy 36.67175 -284.901608) (xy 36.679645 -284.950185) (xy 36.68014 -284.974792)
			(xy 37.018988 -284.974792) (xy 37.022948 -284.925738) (xy 37.034725 -284.877954) (xy 37.054016 -284.832678)
			(xy 37.080319 -284.791082) (xy 37.112954 -284.754245) (xy 37.151075 -284.72312) (xy 37.193696 -284.698513)
			(xy 37.239712 -284.681061) (xy 37.287931 -284.671217) (xy 37.337106 -284.669236) (xy 37.385961 -284.675168)
			(xy 37.433232 -284.68886) (xy 37.477694 -284.709958) (xy 37.518197 -284.737914) (xy 37.55369 -284.772006)
			(xy 37.583255 -284.81135) (xy 37.606126 -284.854927) (xy 37.62171 -284.901608) (xy 37.629605 -284.950185)
			(xy 37.6301 -284.974792) (xy 37.969202 -284.974792) (xy 37.973162 -284.925738) (xy 37.984939 -284.877954)
			(xy 38.00423 -284.832678) (xy 38.030533 -284.791082) (xy 38.063168 -284.754245) (xy 38.101289 -284.72312)
			(xy 38.14391 -284.698513) (xy 38.189926 -284.681061) (xy 38.238145 -284.671217) (xy 38.28732 -284.669236)
			(xy 38.336175 -284.675168) (xy 38.383446 -284.68886) (xy 38.427908 -284.709958) (xy 38.468411 -284.737914)
			(xy 38.503904 -284.772006) (xy 38.533469 -284.81135) (xy 38.55634 -284.854927) (xy 38.571924 -284.901608)
			(xy 38.579819 -284.950185) (xy 38.580314 -284.974792) (xy 38.919162 -284.974792) (xy 38.923122 -284.925738)
			(xy 38.934899 -284.877954) (xy 38.95419 -284.832678) (xy 38.980493 -284.791082) (xy 39.013128 -284.754245)
			(xy 39.051249 -284.72312) (xy 39.09387 -284.698513) (xy 39.139886 -284.681061) (xy 39.188105 -284.671217)
			(xy 39.23728 -284.669236) (xy 39.286135 -284.675168) (xy 39.333406 -284.68886) (xy 39.377868 -284.709958)
			(xy 39.418371 -284.737914) (xy 39.453864 -284.772006) (xy 39.483429 -284.81135) (xy 39.5063 -284.854927)
			(xy 39.521884 -284.901608) (xy 39.529779 -284.950185) (xy 39.530274 -284.974792) (xy 39.869122 -284.974792)
			(xy 39.873082 -284.925738) (xy 39.884859 -284.877954) (xy 39.90415 -284.832678) (xy 39.930453 -284.791082)
			(xy 39.963088 -284.754245) (xy 40.001209 -284.72312) (xy 40.04383 -284.698513) (xy 40.089846 -284.681061)
			(xy 40.138065 -284.671217) (xy 40.18724 -284.669236) (xy 40.236095 -284.675168) (xy 40.283366 -284.68886)
			(xy 40.327828 -284.709958) (xy 40.368331 -284.737914) (xy 40.403824 -284.772006) (xy 40.433389 -284.81135)
			(xy 40.45626 -284.854927) (xy 40.471844 -284.901608) (xy 40.479739 -284.950185) (xy 40.480234 -284.974792)
			(xy 40.819082 -284.974792) (xy 40.823042 -284.925738) (xy 40.834819 -284.877954) (xy 40.85411 -284.832678)
			(xy 40.880413 -284.791082) (xy 40.913048 -284.754245) (xy 40.951169 -284.72312) (xy 40.99379 -284.698513)
			(xy 41.039806 -284.681061) (xy 41.088025 -284.671217) (xy 41.1372 -284.669236) (xy 41.186055 -284.675168)
			(xy 41.233326 -284.68886) (xy 41.277788 -284.709958) (xy 41.318291 -284.737914) (xy 41.353784 -284.772006)
			(xy 41.383349 -284.81135) (xy 41.40622 -284.854927) (xy 41.421804 -284.901608) (xy 41.429699 -284.950185)
			(xy 41.430194 -284.974792) (xy 42.719002 -284.974792) (xy 42.722962 -284.925738) (xy 42.734739 -284.877954)
			(xy 42.75403 -284.832678) (xy 42.780333 -284.791082) (xy 42.812968 -284.754245) (xy 42.851089 -284.72312)
			(xy 42.89371 -284.698513) (xy 42.939726 -284.681061) (xy 42.987945 -284.671217) (xy 43.03712 -284.669236)
			(xy 43.085975 -284.675168) (xy 43.133246 -284.68886) (xy 43.177708 -284.709958) (xy 43.218211 -284.737914)
			(xy 43.253704 -284.772006) (xy 43.283269 -284.81135) (xy 43.30614 -284.854927) (xy 43.321724 -284.901608)
			(xy 43.329619 -284.950185) (xy 43.330114 -284.974792) (xy 44.619176 -284.974792) (xy 44.623136 -284.925738)
			(xy 44.634913 -284.877954) (xy 44.654204 -284.832678) (xy 44.680507 -284.791082) (xy 44.713142 -284.754245)
			(xy 44.751263 -284.72312) (xy 44.793884 -284.698513) (xy 44.8399 -284.681061) (xy 44.888119 -284.671217)
			(xy 44.937294 -284.669236) (xy 44.986149 -284.675168) (xy 45.03342 -284.68886) (xy 45.077882 -284.709958)
			(xy 45.118385 -284.737914) (xy 45.153878 -284.772006) (xy 45.183443 -284.81135) (xy 45.206314 -284.854927)
			(xy 45.221898 -284.901608) (xy 45.229793 -284.950185) (xy 45.230288 -284.974792) (xy 45.569136 -284.974792)
			(xy 45.573096 -284.925738) (xy 45.584873 -284.877954) (xy 45.604164 -284.832678) (xy 45.630467 -284.791082)
			(xy 45.663102 -284.754245) (xy 45.701223 -284.72312) (xy 45.743844 -284.698513) (xy 45.78986 -284.681061)
			(xy 45.838079 -284.671217) (xy 45.887254 -284.669236) (xy 45.936109 -284.675168) (xy 45.98338 -284.68886)
			(xy 46.027842 -284.709958) (xy 46.068345 -284.737914) (xy 46.103838 -284.772006) (xy 46.133403 -284.81135)
			(xy 46.156274 -284.854927) (xy 46.171858 -284.901608) (xy 46.179753 -284.950185) (xy 46.180248 -284.974792)
			(xy 46.179753 -284.999399) (xy 46.171858 -285.047976) (xy 46.156274 -285.094657) (xy 46.133403 -285.138234)
			(xy 46.103838 -285.177578) (xy 46.068345 -285.21167) (xy 46.027842 -285.239626) (xy 45.98338 -285.260724)
			(xy 45.936109 -285.274416) (xy 45.887254 -285.280348) (xy 45.838079 -285.278367) (xy 45.78986 -285.268523)
			(xy 45.743844 -285.251071) (xy 45.701223 -285.226464) (xy 45.663102 -285.195339) (xy 45.630467 -285.158502)
			(xy 45.604164 -285.116906) (xy 45.584873 -285.07163) (xy 45.573096 -285.023846) (xy 45.569136 -284.974792)
			(xy 45.230288 -284.974792) (xy 45.229793 -284.999399) (xy 45.221898 -285.047976) (xy 45.206314 -285.094657)
			(xy 45.183443 -285.138234) (xy 45.153878 -285.177578) (xy 45.118385 -285.21167) (xy 45.077882 -285.239626)
			(xy 45.03342 -285.260724) (xy 44.986149 -285.274416) (xy 44.937294 -285.280348) (xy 44.888119 -285.278367)
			(xy 44.8399 -285.268523) (xy 44.793884 -285.251071) (xy 44.751263 -285.226464) (xy 44.713142 -285.195339)
			(xy 44.680507 -285.158502) (xy 44.654204 -285.116906) (xy 44.634913 -285.07163) (xy 44.623136 -285.023846)
			(xy 44.619176 -284.974792) (xy 43.330114 -284.974792) (xy 43.329619 -284.999399) (xy 43.321724 -285.047976)
			(xy 43.30614 -285.094657) (xy 43.283269 -285.138234) (xy 43.253704 -285.177578) (xy 43.218211 -285.21167)
			(xy 43.177708 -285.239626) (xy 43.133246 -285.260724) (xy 43.085975 -285.274416) (xy 43.03712 -285.280348)
			(xy 42.987945 -285.278367) (xy 42.939726 -285.268523) (xy 42.89371 -285.251071) (xy 42.851089 -285.226464)
			(xy 42.812968 -285.195339) (xy 42.780333 -285.158502) (xy 42.75403 -285.116906) (xy 42.734739 -285.07163)
			(xy 42.722962 -285.023846) (xy 42.719002 -284.974792) (xy 41.430194 -284.974792) (xy 41.429699 -284.999399)
			(xy 41.421804 -285.047976) (xy 41.40622 -285.094657) (xy 41.383349 -285.138234) (xy 41.353784 -285.177578)
			(xy 41.318291 -285.21167) (xy 41.277788 -285.239626) (xy 41.233326 -285.260724) (xy 41.186055 -285.274416)
			(xy 41.1372 -285.280348) (xy 41.088025 -285.278367) (xy 41.039806 -285.268523) (xy 40.99379 -285.251071)
			(xy 40.951169 -285.226464) (xy 40.913048 -285.195339) (xy 40.880413 -285.158502) (xy 40.85411 -285.116906)
			(xy 40.834819 -285.07163) (xy 40.823042 -285.023846) (xy 40.819082 -284.974792) (xy 40.480234 -284.974792)
			(xy 40.479739 -284.999399) (xy 40.471844 -285.047976) (xy 40.45626 -285.094657) (xy 40.433389 -285.138234)
			(xy 40.403824 -285.177578) (xy 40.368331 -285.21167) (xy 40.327828 -285.239626) (xy 40.283366 -285.260724)
			(xy 40.236095 -285.274416) (xy 40.18724 -285.280348) (xy 40.138065 -285.278367) (xy 40.089846 -285.268523)
			(xy 40.04383 -285.251071) (xy 40.001209 -285.226464) (xy 39.963088 -285.195339) (xy 39.930453 -285.158502)
			(xy 39.90415 -285.116906) (xy 39.884859 -285.07163) (xy 39.873082 -285.023846) (xy 39.869122 -284.974792)
			(xy 39.530274 -284.974792) (xy 39.529779 -284.999399) (xy 39.521884 -285.047976) (xy 39.5063 -285.094657)
			(xy 39.483429 -285.138234) (xy 39.453864 -285.177578) (xy 39.418371 -285.21167) (xy 39.377868 -285.239626)
			(xy 39.333406 -285.260724) (xy 39.286135 -285.274416) (xy 39.23728 -285.280348) (xy 39.188105 -285.278367)
			(xy 39.139886 -285.268523) (xy 39.09387 -285.251071) (xy 39.051249 -285.226464) (xy 39.013128 -285.195339)
			(xy 38.980493 -285.158502) (xy 38.95419 -285.116906) (xy 38.934899 -285.07163) (xy 38.923122 -285.023846)
			(xy 38.919162 -284.974792) (xy 38.580314 -284.974792) (xy 38.579819 -284.999399) (xy 38.571924 -285.047976)
			(xy 38.55634 -285.094657) (xy 38.533469 -285.138234) (xy 38.503904 -285.177578) (xy 38.468411 -285.21167)
			(xy 38.427908 -285.239626) (xy 38.383446 -285.260724) (xy 38.336175 -285.274416) (xy 38.28732 -285.280348)
			(xy 38.238145 -285.278367) (xy 38.189926 -285.268523) (xy 38.14391 -285.251071) (xy 38.101289 -285.226464)
			(xy 38.063168 -285.195339) (xy 38.030533 -285.158502) (xy 38.00423 -285.116906) (xy 37.984939 -285.07163)
			(xy 37.973162 -285.023846) (xy 37.969202 -284.974792) (xy 37.6301 -284.974792) (xy 37.629605 -284.999399)
			(xy 37.62171 -285.047976) (xy 37.606126 -285.094657) (xy 37.583255 -285.138234) (xy 37.55369 -285.177578)
			(xy 37.518197 -285.21167) (xy 37.477694 -285.239626) (xy 37.433232 -285.260724) (xy 37.385961 -285.274416)
			(xy 37.337106 -285.280348) (xy 37.287931 -285.278367) (xy 37.239712 -285.268523) (xy 37.193696 -285.251071)
			(xy 37.151075 -285.226464) (xy 37.112954 -285.195339) (xy 37.080319 -285.158502) (xy 37.054016 -285.116906)
			(xy 37.034725 -285.07163) (xy 37.022948 -285.023846) (xy 37.018988 -284.974792) (xy 36.68014 -284.974792)
			(xy 36.679645 -284.999399) (xy 36.67175 -285.047976) (xy 36.656166 -285.094657) (xy 36.633295 -285.138234)
			(xy 36.60373 -285.177578) (xy 36.568237 -285.21167) (xy 36.527734 -285.239626) (xy 36.483272 -285.260724)
			(xy 36.436001 -285.274416) (xy 36.387146 -285.280348) (xy 36.337971 -285.278367) (xy 36.289752 -285.268523)
			(xy 36.243736 -285.251071) (xy 36.201115 -285.226464) (xy 36.162994 -285.195339) (xy 36.130359 -285.158502)
			(xy 36.104056 -285.116906) (xy 36.084765 -285.07163) (xy 36.072988 -285.023846) (xy 36.069028 -284.974792)
			(xy 31.985204 -284.974792) (xy 31.4452 -285.514796) (xy 31.438353 -285.522194) (xy 31.430617 -285.540792)
			(xy 31.430214 -285.550864) (xy 31.430214 -285.891732) (xy 31.430526 -285.900217) (xy 31.436084 -285.916249)
			(xy 31.446607 -285.929562) (xy 31.453582 -285.934404) (xy 31.525464 -285.980886) (xy 31.53653 -285.987155)
			(xy 31.561862 -285.989028) (xy 31.573724 -285.984442) (xy 31.598534 -285.973715) (xy 31.650421 -285.958573)
			(xy 31.703925 -285.950901) (xy 31.73095 -285.950406) (xy 31.758204 -285.950866) (xy 31.812159 -285.958617)
			(xy 31.86446 -285.973968) (xy 31.914045 -285.996607) (xy 31.959903 -286.026072) (xy 32.0011 -286.061765)
			(xy 32.036798 -286.102957) (xy 32.066269 -286.148811) (xy 32.088915 -286.198393) (xy 32.104273 -286.250693)
			(xy 32.112031 -286.304646) (xy 32.112031 -286.359154) (xy 32.104273 -286.413107) (xy 32.088915 -286.465407)
			(xy 32.066269 -286.514989) (xy 32.036798 -286.560843) (xy 32.0011 -286.602035) (xy 31.959903 -286.637728)
			(xy 31.914045 -286.667193) (xy 31.86446 -286.689832) (xy 31.812159 -286.705183) (xy 31.758204 -286.712934)
			(xy 31.73095 -286.713422) (xy 31.703966 -286.712922) (xy 31.650547 -286.705246) (xy 31.598744 -286.69011)
			(xy 31.573978 -286.679386) (xy 31.57347 -286.679386) (xy 31.561786 -286.674052) (xy 31.536386 -286.676084)
			(xy 31.453582 -286.729424) (xy 31.446621 -286.734278) (xy 31.436129 -286.747603) (xy 31.430544 -286.763617)
			(xy 31.430214 -286.772096) (xy 31.430214 -287.25876) (xy 31.430648 -287.268825) (xy 31.43838 -287.287412)
			(xy 31.4452 -287.294828) (xy 31.449772 -287.2994) (xy 31.457135 -287.306228) (xy 31.475646 -287.313971)
			(xy 31.495712 -287.31402) (xy 31.505144 -287.310576) (xy 32.222948 -287.012888) (xy 32.268287 -286.994791)
			(xy 32.361723 -286.966488) (xy 32.457474 -286.947436) (xy 32.554627 -286.937818) (xy 32.60344 -286.937196)
			(xy 32.737298 -286.937196) (xy 32.746414 -286.936863) (xy 32.763509 -286.930535) (xy 32.777272 -286.918584)
			(xy 32.782002 -286.91078) (xy 32.796481 -286.885458) (xy 32.831936 -286.839142) (xy 32.874031 -286.798767)
			(xy 32.921786 -286.765275) (xy 32.974085 -286.739448) (xy 33.029708 -286.721889) (xy 33.087356 -286.713007)
			(xy 33.11652 -286.712406) (xy 33.142574 -286.712851) (xy 33.194196 -286.719942) (xy 33.244374 -286.73399)
			(xy 33.292174 -286.754733) (xy 33.336708 -286.781787) (xy 33.377147 -286.814647) (xy 33.412741 -286.852703)
			(xy 33.428178 -286.873696) (xy 33.435057 -286.882445) (xy 33.454351 -286.893489) (xy 33.476502 -286.895377)
			(xy 33.497387 -286.887758) (xy 33.505648 -286.8803) (xy 33.878266 -286.507682) (xy 33.909366 -286.47723)
			(xy 33.976027 -286.421253) (xy 34.047313 -286.371297) (xy 34.122681 -286.327745) (xy 34.201558 -286.290926)
			(xy 34.283344 -286.261121) (xy 34.367416 -286.238557) (xy 34.453134 -286.223406) (xy 34.539847 -286.215783)
			(xy 34.58337 -286.215328) (xy 35.575748 -286.215328) (xy 35.620668 -286.215859) (xy 35.710138 -286.224009)
			(xy 35.798513 -286.240166) (xy 35.88508 -286.2642) (xy 35.927284 -286.27959) (xy 35.936174 -286.282892)
			(xy 36.058856 -286.282892) (xy 36.068394 -286.282436) (xy 36.086122 -286.275377) (xy 36.100072 -286.262357)
			(xy 36.104576 -286.253936) (xy 36.1442 -286.170878) (xy 36.147929 -286.162124) (xy 36.149296 -286.143158)
			(xy 36.143691 -286.124988) (xy 36.138104 -286.117284) (xy 36.13785 -286.11703) (xy 36.121843 -286.0965)
			(xy 36.096341 -286.051121) (xy 36.078908 -286.002073) (xy 36.070051 -285.950779) (xy 36.069524 -285.924752)
			(xy 36.070046 -285.899497) (xy 36.078359 -285.849675) (xy 36.09476 -285.801901) (xy 36.118801 -285.757478)
			(xy 36.149825 -285.717618) (xy 36.186987 -285.683408) (xy 36.229273 -285.655782) (xy 36.275529 -285.635492)
			(xy 36.324494 -285.623092) (xy 36.374832 -285.618921) (xy 36.42517 -285.623092) (xy 36.474135 -285.635492)
			(xy 36.520391 -285.655782) (xy 36.562677 -285.683408) (xy 36.599839 -285.717618) (xy 36.630863 -285.757478)
			(xy 36.654904 -285.801901) (xy 36.671305 -285.849675) (xy 36.679618 -285.899497) (xy 36.68014 -285.924752)
			(xy 36.679571 -285.950744) (xy 36.670682 -286.001965) (xy 36.653254 -286.050943) (xy 36.62779 -286.096266)
			(xy 36.611814 -286.116776) (xy 36.61156 -286.117284) (xy 36.60591 -286.124957) (xy 36.600262 -286.143142)
			(xy 36.601683 -286.162131) (xy 36.605464 -286.170878) (xy 36.645088 -286.253936) (xy 36.649541 -286.262396)
			(xy 36.663488 -286.275452) (xy 36.681256 -286.28247) (xy 36.690808 -286.282892) (xy 37.008816 -286.282892)
			(xy 37.018358 -286.282443) (xy 37.036097 -286.275392) (xy 37.050059 -286.262374) (xy 37.054536 -286.253936)
			(xy 37.09416 -286.170878) (xy 37.097891 -286.162124) (xy 37.099259 -286.143158) (xy 37.09365 -286.124989)
			(xy 37.088064 -286.117284) (xy 37.08781 -286.11703) (xy 37.071805 -286.0965) (xy 37.046306 -286.05112)
			(xy 37.028876 -286.002072) (xy 37.020019 -285.950778) (xy 37.019484 -285.924752) (xy 37.020006 -285.899497)
			(xy 37.028319 -285.849675) (xy 37.04472 -285.801901) (xy 37.068761 -285.757478) (xy 37.099785 -285.717618)
			(xy 37.136947 -285.683408) (xy 37.179233 -285.655782) (xy 37.225489 -285.635492) (xy 37.274454 -285.623092)
			(xy 37.324792 -285.618921) (xy 37.37513 -285.623092) (xy 37.424095 -285.635492) (xy 37.470351 -285.655782)
			(xy 37.512637 -285.683408) (xy 37.549799 -285.717618) (xy 37.580823 -285.757478) (xy 37.604864 -285.801901)
			(xy 37.621265 -285.849675) (xy 37.629578 -285.899497) (xy 37.6301 -285.924752) (xy 37.629531 -285.950744)
			(xy 37.620641 -286.001964) (xy 37.603211 -286.050941) (xy 37.577745 -286.096261) (xy 37.561774 -286.116776)
			(xy 37.56152 -286.117284) (xy 37.555864 -286.124956) (xy 37.55021 -286.143142) (xy 37.551633 -286.162134)
			(xy 37.555424 -286.170878) (xy 37.595048 -286.253936) (xy 37.5995 -286.2624) (xy 37.613444 -286.275467)
			(xy 37.631213 -286.282498) (xy 37.640768 -286.282892) (xy 37.95903 -286.282892) (xy 37.968571 -286.282441)
			(xy 37.986306 -286.275387) (xy 38.000263 -286.262368) (xy 38.00475 -286.253936) (xy 38.044374 -286.170878)
			(xy 38.048104 -286.162124) (xy 38.049472 -286.143158) (xy 38.043864 -286.124988) (xy 38.038278 -286.117284)
			(xy 38.038024 -286.11703) (xy 38.022019 -286.0965) (xy 37.996519 -286.05112) (xy 37.979087 -286.002073)
			(xy 37.97023 -285.950778) (xy 37.969698 -285.924752) (xy 37.97022 -285.899497) (xy 37.978533 -285.849675)
			(xy 37.994934 -285.801901) (xy 38.018975 -285.757478) (xy 38.049999 -285.717618) (xy 38.087161 -285.683408)
			(xy 38.129447 -285.655782) (xy 38.175703 -285.635492) (xy 38.224668 -285.623092) (xy 38.275006 -285.618921)
			(xy 38.325344 -285.623092) (xy 38.374309 -285.635492) (xy 38.420565 -285.655782) (xy 38.462851 -285.683408)
			(xy 38.500013 -285.717618) (xy 38.531037 -285.757478) (xy 38.555078 -285.801901) (xy 38.571479 -285.849675)
			(xy 38.579792 -285.899497) (xy 38.580314 -285.924752) (xy 38.919162 -285.924752) (xy 38.923122 -285.875698)
			(xy 38.934899 -285.827914) (xy 38.95419 -285.782638) (xy 38.980493 -285.741042) (xy 39.013128 -285.704205)
			(xy 39.051249 -285.67308) (xy 39.09387 -285.648473) (xy 39.139886 -285.631021) (xy 39.188105 -285.621177)
			(xy 39.23728 -285.619196) (xy 39.286135 -285.625128) (xy 39.333406 -285.63882) (xy 39.377868 -285.659918)
			(xy 39.418371 -285.687874) (xy 39.453864 -285.721966) (xy 39.483429 -285.76131) (xy 39.5063 -285.804887)
			(xy 39.521884 -285.851568) (xy 39.529779 -285.900145) (xy 39.530274 -285.924752) (xy 39.869122 -285.924752)
			(xy 39.873082 -285.875698) (xy 39.884859 -285.827914) (xy 39.90415 -285.782638) (xy 39.930453 -285.741042)
			(xy 39.963088 -285.704205) (xy 40.001209 -285.67308) (xy 40.04383 -285.648473) (xy 40.089846 -285.631021)
			(xy 40.138065 -285.621177) (xy 40.18724 -285.619196) (xy 40.236095 -285.625128) (xy 40.283366 -285.63882)
			(xy 40.327828 -285.659918) (xy 40.368331 -285.687874) (xy 40.403824 -285.721966) (xy 40.433389 -285.76131)
			(xy 40.45626 -285.804887) (xy 40.471844 -285.851568) (xy 40.479739 -285.900145) (xy 40.480234 -285.924752)
			(xy 40.479739 -285.949359) (xy 40.471844 -285.997936) (xy 40.45626 -286.044617) (xy 40.433389 -286.088194)
			(xy 40.403824 -286.127538) (xy 40.368331 -286.16163) (xy 40.327828 -286.189586) (xy 40.283366 -286.210684)
			(xy 40.236095 -286.224376) (xy 40.18724 -286.230308) (xy 40.138065 -286.228327) (xy 40.089846 -286.218483)
			(xy 40.04383 -286.201031) (xy 40.001209 -286.176424) (xy 39.963088 -286.145299) (xy 39.930453 -286.108462)
			(xy 39.90415 -286.066866) (xy 39.884859 -286.02159) (xy 39.873082 -285.973806) (xy 39.869122 -285.924752)
			(xy 39.530274 -285.924752) (xy 39.529779 -285.949359) (xy 39.521884 -285.997936) (xy 39.5063 -286.044617)
			(xy 39.483429 -286.088194) (xy 39.453864 -286.127538) (xy 39.418371 -286.16163) (xy 39.377868 -286.189586)
			(xy 39.333406 -286.210684) (xy 39.286135 -286.224376) (xy 39.23728 -286.230308) (xy 39.188105 -286.228327)
			(xy 39.139886 -286.218483) (xy 39.09387 -286.201031) (xy 39.051249 -286.176424) (xy 39.013128 -286.145299)
			(xy 38.980493 -286.108462) (xy 38.95419 -286.066866) (xy 38.934899 -286.02159) (xy 38.923122 -285.973806)
			(xy 38.919162 -285.924752) (xy 38.580314 -285.924752) (xy 38.579744 -285.951242) (xy 38.570597 -286.003425)
			(xy 38.552586 -286.053249) (xy 38.526251 -286.09922) (xy 38.492381 -286.139959) (xy 38.451992 -286.174245)
			(xy 38.429438 -286.18815) (xy 38.421943 -286.192903) (xy 38.41059 -286.206532) (xy 38.404584 -286.223222)
			(xy 38.404292 -286.232092) (xy 38.404779 -286.242101) (xy 38.412437 -286.260597) (xy 38.426589 -286.274754)
			(xy 38.445083 -286.282418) (xy 38.455092 -286.282892) (xy 38.569138 -286.282892) (xy 38.611523 -286.283368)
			(xy 38.695969 -286.29078) (xy 38.779448 -286.305517) (xy 38.861327 -286.327469) (xy 38.940983 -286.356468)
			(xy 39.01781 -286.392294) (xy 39.091226 -286.434674) (xy 39.160673 -286.483287) (xy 39.225622 -286.537763)
			(xy 39.255954 -286.567372) (xy 39.260018 -286.57169) (xy 39.285579 -286.575187) (xy 39.335099 -286.589645)
			(xy 39.381481 -286.612228) (xy 39.402766 -286.626808) (xy 39.409395 -286.631219) (xy 39.424528 -286.636142)
			(xy 39.432484 -286.63646) (xy 39.967408 -286.63646) (xy 39.975344 -286.63619) (xy 39.990471 -286.631395)
			(xy 39.997126 -286.627062) (xy 40.01648 -286.613664) (xy 40.058454 -286.592362) (xy 40.080692 -286.584644)
			(xy 40.086534 -286.582612) (xy 40.096694 -286.576516) (xy 40.105584 -286.567372) (xy 40.135887 -286.537731)
			(xy 40.200834 -286.483248) (xy 40.270281 -286.434631) (xy 40.3437 -286.392249) (xy 40.420532 -286.356425)
			(xy 40.500194 -286.327432) (xy 40.582078 -286.305489) (xy 40.665563 -286.290765) (xy 40.750013 -286.28337)
			(xy 40.7924 -286.282892) (xy 40.80891 -286.282892) (xy 40.818453 -286.282444) (xy 40.836194 -286.275394)
			(xy 40.850157 -286.262376) (xy 40.85463 -286.253936) (xy 40.894254 -286.170878) (xy 40.897985 -286.162124)
			(xy 40.899353 -286.143158) (xy 40.893744 -286.124989) (xy 40.888158 -286.117284) (xy 40.887904 -286.11703)
			(xy 40.871899 -286.0965) (xy 40.846401 -286.05112) (xy 40.828971 -286.002072) (xy 40.820114 -285.950778)
			(xy 40.819578 -285.924752) (xy 40.8201 -285.899497) (xy 40.828413 -285.849675) (xy 40.844814 -285.801901)
			(xy 40.868855 -285.757478) (xy 40.899879 -285.717618) (xy 40.937041 -285.683408) (xy 40.979327 -285.655782)
			(xy 41.025583 -285.635492) (xy 41.074548 -285.623092) (xy 41.124886 -285.618921) (xy 41.175224 -285.623092)
			(xy 41.224189 -285.635492) (xy 41.270445 -285.655782) (xy 41.312731 -285.683408) (xy 41.349893 -285.717618)
			(xy 41.380917 -285.757478) (xy 41.404958 -285.801901) (xy 41.421359 -285.849675) (xy 41.429672 -285.899497)
			(xy 41.430194 -285.924752) (xy 44.619176 -285.924752) (xy 44.623136 -285.875698) (xy 44.634913 -285.827914)
			(xy 44.654204 -285.782638) (xy 44.680507 -285.741042) (xy 44.713142 -285.704205) (xy 44.751263 -285.67308)
			(xy 44.793884 -285.648473) (xy 44.8399 -285.631021) (xy 44.888119 -285.621177) (xy 44.937294 -285.619196)
			(xy 44.986149 -285.625128) (xy 45.03342 -285.63882) (xy 45.077882 -285.659918) (xy 45.118385 -285.687874)
			(xy 45.153878 -285.721966) (xy 45.183443 -285.76131) (xy 45.206314 -285.804887) (xy 45.221898 -285.851568)
			(xy 45.229793 -285.900145) (xy 45.230288 -285.924752) (xy 45.569136 -285.924752) (xy 45.573096 -285.875698)
			(xy 45.584873 -285.827914) (xy 45.604164 -285.782638) (xy 45.630467 -285.741042) (xy 45.663102 -285.704205)
			(xy 45.701223 -285.67308) (xy 45.743844 -285.648473) (xy 45.78986 -285.631021) (xy 45.838079 -285.621177)
			(xy 45.887254 -285.619196) (xy 45.936109 -285.625128) (xy 45.98338 -285.63882) (xy 46.027842 -285.659918)
			(xy 46.068345 -285.687874) (xy 46.103838 -285.721966) (xy 46.133403 -285.76131) (xy 46.156274 -285.804887)
			(xy 46.171858 -285.851568) (xy 46.179753 -285.900145) (xy 46.180248 -285.924752) (xy 46.179753 -285.949359)
			(xy 46.171858 -285.997936) (xy 46.156274 -286.044617) (xy 46.133403 -286.088194) (xy 46.103838 -286.127538)
			(xy 46.068345 -286.16163) (xy 46.027842 -286.189586) (xy 45.98338 -286.210684) (xy 45.936109 -286.224376)
			(xy 45.887254 -286.230308) (xy 45.838079 -286.228327) (xy 45.78986 -286.218483) (xy 45.743844 -286.201031)
			(xy 45.701223 -286.176424) (xy 45.663102 -286.145299) (xy 45.630467 -286.108462) (xy 45.604164 -286.066866)
			(xy 45.584873 -286.02159) (xy 45.573096 -285.973806) (xy 45.569136 -285.924752) (xy 45.230288 -285.924752)
			(xy 45.229793 -285.949359) (xy 45.221898 -285.997936) (xy 45.206314 -286.044617) (xy 45.183443 -286.088194)
			(xy 45.153878 -286.127538) (xy 45.118385 -286.16163) (xy 45.077882 -286.189586) (xy 45.03342 -286.210684)
			(xy 44.986149 -286.224376) (xy 44.937294 -286.230308) (xy 44.888119 -286.228327) (xy 44.8399 -286.218483)
			(xy 44.793884 -286.201031) (xy 44.751263 -286.176424) (xy 44.713142 -286.145299) (xy 44.680507 -286.108462)
			(xy 44.654204 -286.066866) (xy 44.634913 -286.02159) (xy 44.623136 -285.973806) (xy 44.619176 -285.924752)
			(xy 41.430194 -285.924752) (xy 41.429624 -285.951241) (xy 41.420477 -286.003424) (xy 41.402465 -286.053247)
			(xy 41.376129 -286.099217) (xy 41.342258 -286.139954) (xy 41.301868 -286.174238) (xy 41.279318 -286.18815)
			(xy 41.271813 -286.192897) (xy 41.260442 -286.206522) (xy 41.254427 -286.223218) (xy 41.254172 -286.232092)
			(xy 41.254658 -286.242103) (xy 41.262315 -286.260602) (xy 41.276468 -286.274764) (xy 41.294962 -286.282435)
			(xy 41.304972 -286.282892) (xy 41.419018 -286.282892) (xy 41.461403 -286.283367) (xy 41.54585 -286.290777)
			(xy 41.62933 -286.305513) (xy 41.71121 -286.327464) (xy 41.790867 -286.356461) (xy 41.867696 -286.392286)
			(xy 41.941113 -286.434666) (xy 42.010561 -286.483278) (xy 42.075511 -286.537753) (xy 42.105834 -286.567372)
			(xy 42.109898 -286.57169) (xy 42.13546 -286.575185) (xy 42.184981 -286.589641) (xy 42.231366 -286.612221)
			(xy 42.252646 -286.626808) (xy 42.259274 -286.631222) (xy 42.274408 -286.636151) (xy 42.282364 -286.63646)
			(xy 42.81678 -286.63646) (xy 42.824747 -286.636197) (xy 42.839906 -286.631289) (xy 42.846498 -286.626808)
			(xy 42.866101 -286.613283) (xy 42.908618 -286.591831) (xy 42.953949 -286.577234) (xy 43.000995 -286.569846)
			(xy 43.048617 -286.569846) (xy 43.095663 -286.577234) (xy 43.140994 -286.591831) (xy 43.183511 -286.613283)
			(xy 43.203114 -286.626808) (xy 43.209745 -286.631213) (xy 43.224878 -286.636122) (xy 43.232832 -286.63646)
			(xy 43.76674 -286.63646) (xy 43.774704 -286.636188) (xy 43.789852 -286.631265) (xy 43.796458 -286.626808)
			(xy 43.81606 -286.613281) (xy 43.858576 -286.591827) (xy 43.903907 -286.577231) (xy 43.950954 -286.569849)
			(xy 43.974766 -286.569404) (xy 43.999825 -286.569907) (xy 44.04927 -286.57809) (xy 44.096713 -286.594241)
			(xy 44.140881 -286.617926) (xy 44.180585 -286.64851) (xy 44.214758 -286.685169) (xy 44.242484 -286.726919)
			(xy 44.263015 -286.772638) (xy 44.269914 -286.796734) (xy 44.271692 -286.803338) (xy 44.278296 -286.814768)
			(xy 44.338494 -286.874966) (xy 44.619176 -286.874966) (xy 44.623136 -286.825912) (xy 44.634913 -286.778128)
			(xy 44.654204 -286.732852) (xy 44.680507 -286.691256) (xy 44.713142 -286.654419) (xy 44.751263 -286.623294)
			(xy 44.793884 -286.598687) (xy 44.8399 -286.581235) (xy 44.888119 -286.571391) (xy 44.937294 -286.56941)
			(xy 44.986149 -286.575342) (xy 45.03342 -286.589034) (xy 45.077882 -286.610132) (xy 45.118385 -286.638088)
			(xy 45.153878 -286.67218) (xy 45.183443 -286.711524) (xy 45.206314 -286.755101) (xy 45.221898 -286.801782)
			(xy 45.229793 -286.850359) (xy 45.230288 -286.874966) (xy 45.569136 -286.874966) (xy 45.573096 -286.825912)
			(xy 45.584873 -286.778128) (xy 45.604164 -286.732852) (xy 45.630467 -286.691256) (xy 45.663102 -286.654419)
			(xy 45.701223 -286.623294) (xy 45.743844 -286.598687) (xy 45.78986 -286.581235) (xy 45.838079 -286.571391)
			(xy 45.887254 -286.56941) (xy 45.936109 -286.575342) (xy 45.98338 -286.589034) (xy 46.027842 -286.610132)
			(xy 46.068345 -286.638088) (xy 46.103838 -286.67218) (xy 46.133403 -286.711524) (xy 46.156274 -286.755101)
			(xy 46.171858 -286.801782) (xy 46.179753 -286.850359) (xy 46.180248 -286.874966) (xy 46.179753 -286.899573)
			(xy 46.171858 -286.94815) (xy 46.156274 -286.994831) (xy 46.133403 -287.038408) (xy 46.103838 -287.077752)
			(xy 46.068345 -287.111844) (xy 46.027842 -287.1398) (xy 45.98338 -287.160898) (xy 45.936109 -287.17459)
			(xy 45.887254 -287.180522) (xy 45.838079 -287.178541) (xy 45.78986 -287.168697) (xy 45.743844 -287.151245)
			(xy 45.701223 -287.126638) (xy 45.663102 -287.095513) (xy 45.630467 -287.058676) (xy 45.604164 -287.01708)
			(xy 45.584873 -286.971804) (xy 45.573096 -286.92402) (xy 45.569136 -286.874966) (xy 45.230288 -286.874966)
			(xy 45.229793 -286.899573) (xy 45.221898 -286.94815) (xy 45.206314 -286.994831) (xy 45.183443 -287.038408)
			(xy 45.153878 -287.077752) (xy 45.118385 -287.111844) (xy 45.077882 -287.1398) (xy 45.03342 -287.160898)
			(xy 44.986149 -287.17459) (xy 44.937294 -287.180522) (xy 44.888119 -287.178541) (xy 44.8399 -287.168697)
			(xy 44.793884 -287.151245) (xy 44.751263 -287.126638) (xy 44.713142 -287.095513) (xy 44.680507 -287.058676)
			(xy 44.654204 -287.01708) (xy 44.634913 -286.971804) (xy 44.623136 -286.92402) (xy 44.619176 -286.874966)
			(xy 44.338494 -286.874966) (xy 44.849288 -287.38576) (xy 44.856126 -287.393161) (xy 44.863841 -287.411759)
			(xy 44.864274 -287.421828) (xy 44.864274 -287.429702) (xy 44.870878 -287.446974) (xy 44.923202 -287.504632)
			(xy 44.929718 -287.51127) (xy 44.946265 -287.519732) (xy 44.95546 -287.521142) (xy 44.955714 -287.521142)
			(xy 44.980486 -287.524146) (xy 45.028654 -287.537171) (xy 45.074063 -287.557856) (xy 45.115503 -287.58565)
			(xy 45.151872 -287.619813) (xy 45.182202 -287.659434) (xy 45.205686 -287.703461) (xy 45.221697 -287.75072)
			(xy 45.229811 -287.799954) (xy 45.22981 -287.824926) (xy 45.569136 -287.824926) (xy 45.573096 -287.775872)
			(xy 45.584873 -287.728088) (xy 45.604164 -287.682812) (xy 45.630467 -287.641216) (xy 45.663102 -287.604379)
			(xy 45.701223 -287.573254) (xy 45.743844 -287.548647) (xy 45.78986 -287.531195) (xy 45.838079 -287.521351)
			(xy 45.887254 -287.51937) (xy 45.936109 -287.525302) (xy 45.98338 -287.538994) (xy 46.027842 -287.560092)
			(xy 46.068345 -287.588048) (xy 46.103838 -287.62214) (xy 46.133403 -287.661484) (xy 46.156274 -287.705061)
			(xy 46.171858 -287.751742) (xy 46.179753 -287.800319) (xy 46.180248 -287.824926) (xy 46.179753 -287.849533)
			(xy 46.171858 -287.89811) (xy 46.156274 -287.944791) (xy 46.133403 -287.988368) (xy 46.103838 -288.027712)
			(xy 46.068345 -288.061804) (xy 46.027842 -288.08976) (xy 45.98338 -288.110858) (xy 45.936109 -288.12455)
			(xy 45.887254 -288.130482) (xy 45.838079 -288.128501) (xy 45.78986 -288.118657) (xy 45.743844 -288.101205)
			(xy 45.701223 -288.076598) (xy 45.663102 -288.045473) (xy 45.630467 -288.008636) (xy 45.604164 -287.96704)
			(xy 45.584873 -287.921764) (xy 45.573096 -287.87398) (xy 45.569136 -287.824926) (xy 45.22981 -287.824926)
			(xy 45.22981 -287.849852) (xy 45.221696 -287.899085) (xy 45.205684 -287.946344) (xy 45.182199 -287.99037)
			(xy 45.151869 -288.029991) (xy 45.115499 -288.064153) (xy 45.074058 -288.091946) (xy 45.028649 -288.11263)
			(xy 44.980481 -288.125655) (xy 44.955714 -288.12871) (xy 44.95546 -288.12871) (xy 44.946268 -288.130131)
			(xy 44.929717 -288.138584) (xy 44.923202 -288.14522) (xy 44.877482 -288.195766) (xy 44.871517 -288.202992)
			(xy 44.864738 -288.220444) (xy 44.864274 -288.229802) (xy 44.864274 -288.382964) (xy 44.868338 -288.392616)
			(xy 44.876436 -288.411891) (xy 44.891172 -288.451021) (xy 44.897802 -288.470848) (xy 44.92498 -288.469578)
			(xy 44.95024 -288.470069) (xy 45.000071 -288.478382) (xy 45.047855 -288.494783) (xy 45.092287 -288.518826)
			(xy 45.132155 -288.549854) (xy 45.166372 -288.587022) (xy 45.194005 -288.629315) (xy 45.2143 -288.675579)
			(xy 45.226702 -288.724553) (xy 45.230873 -288.774886) (xy 45.569136 -288.774886) (xy 45.573096 -288.725832)
			(xy 45.584873 -288.678048) (xy 45.604164 -288.632772) (xy 45.630467 -288.591176) (xy 45.663102 -288.554339)
			(xy 45.701223 -288.523214) (xy 45.743844 -288.498607) (xy 45.78986 -288.481155) (xy 45.838079 -288.471311)
			(xy 45.887254 -288.46933) (xy 45.936109 -288.475262) (xy 45.98338 -288.488954) (xy 46.027842 -288.510052)
			(xy 46.068345 -288.538008) (xy 46.103838 -288.5721) (xy 46.133403 -288.611444) (xy 46.156274 -288.655021)
			(xy 46.171858 -288.701702) (xy 46.179753 -288.750279) (xy 46.180248 -288.774886) (xy 46.179753 -288.799493)
			(xy 46.171858 -288.84807) (xy 46.156274 -288.894751) (xy 46.133403 -288.938328) (xy 46.103838 -288.977672)
			(xy 46.068345 -289.011764) (xy 46.027842 -289.03972) (xy 45.98338 -289.060818) (xy 45.936109 -289.07451)
			(xy 45.887254 -289.080442) (xy 45.838079 -289.078461) (xy 45.78986 -289.068617) (xy 45.743844 -289.051165)
			(xy 45.701223 -289.026558) (xy 45.663102 -288.995433) (xy 45.630467 -288.958596) (xy 45.604164 -288.917)
			(xy 45.584873 -288.871724) (xy 45.573096 -288.82394) (xy 45.569136 -288.774886) (xy 45.230873 -288.774886)
			(xy 45.230874 -288.7749) (xy 45.226702 -288.825247) (xy 45.2143 -288.874221) (xy 45.194005 -288.920485)
			(xy 45.166372 -288.962778) (xy 45.132155 -288.999946) (xy 45.092287 -289.030974) (xy 45.047855 -289.055017)
			(xy 45.000071 -289.071418) (xy 44.95024 -289.079731) (xy 44.92498 -289.080194) (xy 44.897802 -289.078924)
			(xy 44.891178 -289.098754) (xy 44.876441 -289.137883) (xy 44.868338 -289.157156) (xy 44.864274 -289.166808)
			(xy 44.864274 -289.31997) (xy 44.864635 -289.32935) (xy 44.871421 -289.346838) (xy 44.877482 -289.354006)
			(xy 44.923202 -289.404552) (xy 44.929719 -289.411188) (xy 44.946266 -289.419646) (xy 44.95546 -289.421062)
			(xy 44.955714 -289.421062) (xy 44.980485 -289.424066) (xy 45.028649 -289.437091) (xy 45.074055 -289.457775)
			(xy 45.115492 -289.485567) (xy 45.151859 -289.519727) (xy 45.182187 -289.559347) (xy 45.205668 -289.603371)
			(xy 45.221678 -289.650627) (xy 45.229791 -289.699857) (xy 45.22979 -289.724846) (xy 45.569136 -289.724846)
			(xy 45.573096 -289.675792) (xy 45.584873 -289.628008) (xy 45.604164 -289.582732) (xy 45.630467 -289.541136)
			(xy 45.663102 -289.504299) (xy 45.701223 -289.473174) (xy 45.743844 -289.448567) (xy 45.78986 -289.431115)
			(xy 45.838079 -289.421271) (xy 45.887254 -289.41929) (xy 45.936109 -289.425222) (xy 45.98338 -289.438914)
			(xy 46.027842 -289.460012) (xy 46.068345 -289.487968) (xy 46.103838 -289.52206) (xy 46.133403 -289.561404)
			(xy 46.156274 -289.604981) (xy 46.171858 -289.651662) (xy 46.179753 -289.700239) (xy 46.180248 -289.724846)
			(xy 46.179753 -289.749453) (xy 46.171858 -289.79803) (xy 46.156274 -289.844711) (xy 46.133403 -289.888288)
			(xy 46.103838 -289.927632) (xy 46.068345 -289.961724) (xy 46.027842 -289.98968) (xy 45.98338 -290.010778)
			(xy 45.936109 -290.02447) (xy 45.887254 -290.030402) (xy 45.838079 -290.028421) (xy 45.78986 -290.018577)
			(xy 45.743844 -290.001125) (xy 45.701223 -289.976518) (xy 45.663102 -289.945393) (xy 45.630467 -289.908556)
			(xy 45.604164 -289.86696) (xy 45.584873 -289.821684) (xy 45.573096 -289.7739) (xy 45.569136 -289.724846)
			(xy 45.22979 -289.724846) (xy 45.22979 -289.749752) (xy 45.221676 -289.798982) (xy 45.205664 -289.846238)
			(xy 45.182182 -289.890261) (xy 45.151853 -289.92988) (xy 45.115485 -289.964039) (xy 45.074047 -289.99183)
			(xy 45.028641 -290.012512) (xy 44.980476 -290.025536) (xy 44.955714 -290.02863) (xy 44.95546 -290.02863)
			(xy 44.946269 -290.030051) (xy 44.92972 -290.038507) (xy 44.923202 -290.04514) (xy 44.877482 -290.095686)
			(xy 44.87152 -290.102913) (xy 44.864747 -290.120365) (xy 44.864274 -290.129722) (xy 44.864274 -290.26993)
			(xy 44.864628 -290.279313) (xy 44.871404 -290.29681) (xy 44.877482 -290.303966) (xy 44.923202 -290.354512)
			(xy 44.929717 -290.361152) (xy 44.946264 -290.369618) (xy 44.95546 -290.371022) (xy 44.955714 -290.371022)
			(xy 44.980488 -290.374026) (xy 45.028659 -290.387052) (xy 45.07407 -290.407738) (xy 45.115514 -290.435533)
			(xy 45.151886 -290.469698) (xy 45.182218 -290.509322) (xy 45.205703 -290.553351) (xy 45.221716 -290.600613)
			(xy 45.22983 -290.64985) (xy 45.22983 -290.674806) (xy 45.569136 -290.674806) (xy 45.573096 -290.625752)
			(xy 45.584873 -290.577968) (xy 45.604164 -290.532692) (xy 45.630467 -290.491096) (xy 45.663102 -290.454259)
			(xy 45.701223 -290.423134) (xy 45.743844 -290.398527) (xy 45.78986 -290.381075) (xy 45.838079 -290.371231)
			(xy 45.887254 -290.36925) (xy 45.936109 -290.375182) (xy 45.98338 -290.388874) (xy 46.027842 -290.409972)
			(xy 46.068345 -290.437928) (xy 46.103838 -290.47202) (xy 46.133403 -290.511364) (xy 46.156274 -290.554941)
			(xy 46.171858 -290.601622) (xy 46.179753 -290.650199) (xy 46.180248 -290.674806) (xy 46.179753 -290.699413)
			(xy 46.171858 -290.74799) (xy 46.156274 -290.794671) (xy 46.133403 -290.838248) (xy 46.103838 -290.877592)
			(xy 46.068345 -290.911684) (xy 46.027842 -290.93964) (xy 45.98338 -290.960738) (xy 45.936109 -290.97443)
			(xy 45.887254 -290.980362) (xy 45.838079 -290.978381) (xy 45.78986 -290.968537) (xy 45.743844 -290.951085)
			(xy 45.701223 -290.926478) (xy 45.663102 -290.895353) (xy 45.630467 -290.858516) (xy 45.604164 -290.81692)
			(xy 45.584873 -290.771644) (xy 45.573096 -290.72386) (xy 45.569136 -290.674806) (xy 45.22983 -290.674806)
			(xy 45.22983 -290.699751) (xy 45.221716 -290.748988) (xy 45.205703 -290.79625) (xy 45.182217 -290.840279)
			(xy 45.151885 -290.879903) (xy 45.115513 -290.914067) (xy 45.074069 -290.941862) (xy 45.028658 -290.962548)
			(xy 44.980487 -290.975574) (xy 44.955714 -290.97859) (xy 44.95546 -290.97859) (xy 44.946268 -290.98001)
			(xy 44.929714 -290.988461) (xy 44.923202 -290.9951) (xy 44.877482 -291.045646) (xy 44.871529 -291.052876)
			(xy 44.864776 -291.070328) (xy 44.864274 -291.079682) (xy 44.864274 -291.21989) (xy 44.864639 -291.229269)
			(xy 44.87143 -291.246752) (xy 44.877482 -291.253926) (xy 44.923202 -291.304472) (xy 44.92972 -291.311106)
			(xy 44.946268 -291.319561) (xy 44.95546 -291.320982) (xy 44.955714 -291.320982) (xy 44.980491 -291.323985)
			(xy 45.028669 -291.337013) (xy 45.074087 -291.357701) (xy 45.115536 -291.385499) (xy 45.151913 -291.419668)
			(xy 45.18225 -291.459297) (xy 45.205738 -291.503331) (xy 45.221754 -291.550599) (xy 45.22987 -291.599843)
			(xy 45.22987 -291.624766) (xy 45.569136 -291.624766) (xy 45.573096 -291.575712) (xy 45.584873 -291.527928)
			(xy 45.604164 -291.482652) (xy 45.630467 -291.441056) (xy 45.663102 -291.404219) (xy 45.701223 -291.373094)
			(xy 45.743844 -291.348487) (xy 45.78986 -291.331035) (xy 45.838079 -291.321191) (xy 45.887254 -291.31921)
			(xy 45.936109 -291.325142) (xy 45.98338 -291.338834) (xy 46.027842 -291.359932) (xy 46.068345 -291.387888)
			(xy 46.103838 -291.42198) (xy 46.133403 -291.461324) (xy 46.156274 -291.504901) (xy 46.171858 -291.551582)
			(xy 46.179753 -291.600159) (xy 46.180248 -291.624766) (xy 46.179753 -291.649373) (xy 46.171858 -291.69795)
			(xy 46.156274 -291.744631) (xy 46.133403 -291.788208) (xy 46.103838 -291.827552) (xy 46.068345 -291.861644)
			(xy 46.027842 -291.8896) (xy 45.98338 -291.910698) (xy 45.936109 -291.92439) (xy 45.887254 -291.930322)
			(xy 45.838079 -291.928341) (xy 45.78986 -291.918497) (xy 45.743844 -291.901045) (xy 45.701223 -291.876438)
			(xy 45.663102 -291.845313) (xy 45.630467 -291.808476) (xy 45.604164 -291.76688) (xy 45.584873 -291.721604)
			(xy 45.573096 -291.67382) (xy 45.569136 -291.624766) (xy 45.22987 -291.624766) (xy 45.229871 -291.64975)
			(xy 45.221756 -291.698994) (xy 45.205741 -291.746262) (xy 45.182253 -291.790298) (xy 45.151917 -291.829927)
			(xy 45.115541 -291.864096) (xy 45.074093 -291.891896) (xy 45.028675 -291.912585) (xy 44.980498 -291.925613)
			(xy 44.955714 -291.92855) (xy 44.95546 -291.92855) (xy 44.946269 -291.929972) (xy 44.929723 -291.93843)
			(xy 44.923202 -291.94506) (xy 44.877482 -291.995606) (xy 44.871523 -292.002834) (xy 44.864757 -292.020286)
			(xy 44.864274 -292.029642) (xy 44.864274 -292.170104) (xy 44.864641 -292.179482) (xy 44.871436 -292.196961)
			(xy 44.877482 -292.20414) (xy 44.923202 -292.254686) (xy 44.929721 -292.261319) (xy 44.946268 -292.269771)
			(xy 44.95546 -292.271196) (xy 44.955714 -292.271196) (xy 44.980486 -292.2742) (xy 45.028652 -292.287228)
			(xy 45.074059 -292.307916) (xy 45.115496 -292.335713) (xy 45.15186 -292.369879) (xy 45.182184 -292.409505)
			(xy 45.205659 -292.453535) (xy 45.221661 -292.500796) (xy 45.229763 -292.550031) (xy 45.230288 -292.57498)
			(xy 45.229843 -292.598607) (xy 45.222568 -292.645299) (xy 45.21581 -292.667944) (xy 45.21278 -292.679588)
			(xy 45.216643 -292.703303) (xy 45.223176 -292.71341) (xy 45.271436 -292.779704) (xy 45.279053 -292.789057)
			(xy 45.300537 -292.799946) (xy 45.312584 -292.800532)
		)
		(stroke
			(width 0)
			(type solid)
		)
		(fill yes)
		(layer "In13.Cu")
		(net "PCEPLL6_VDDA18_PEX0")
	)
	(gr_poly
		(pts
			(xy 280.278586 -291.975032) (xy 280.288636 -291.974525) (xy 280.307196 -291.966803) (xy 280.314654 -291.960046)
			(xy 280.403808 -291.870892) (xy 280.410652 -291.863493) (xy 280.418383 -291.844895) (xy 280.418794 -291.834824)
			(xy 280.418794 -289.86988) (xy 280.418367 -289.859812) (xy 280.410647 -289.841213) (xy 280.403808 -289.833812)
			(xy 280.374344 -289.804348) (xy 280.36691 -289.797632) (xy 280.34841 -289.789996) (xy 280.328396 -289.789996)
			(xy 280.309896 -289.797632) (xy 280.302462 -289.804348) (xy 280.298144 -289.80892) (xy 280.292048 -289.818826)
			(xy 280.290016 -289.824922) (xy 280.281641 -289.84968) (xy 280.258196 -289.896388) (xy 280.227696 -289.938828)
			(xy 280.190901 -289.975942) (xy 280.148726 -290.006807) (xy 280.102222 -290.030654) (xy 280.052545 -290.04689)
			(xy 280.000933 -290.05511) (xy 279.974802 -290.055554) (xy 279.948813 -290.055045) (xy 279.897476 -290.046915)
			(xy 279.848042 -290.030854) (xy 279.801729 -290.007259) (xy 279.759677 -289.97671) (xy 279.722921 -289.93996)
			(xy 279.692366 -289.897912) (xy 279.668764 -289.851602) (xy 279.652697 -289.802171) (xy 279.644559 -289.750835)
			(xy 279.644094 -289.724846) (xy 279.644559 -289.69938) (xy 279.652356 -289.649048) (xy 279.667773 -289.600506)
			(xy 279.690446 -289.554898) (xy 279.719839 -289.513304) (xy 279.755259 -289.476704) (xy 279.795868 -289.445964)
			(xy 279.818084 -289.433508) (xy 279.818592 -289.433508) (xy 279.818592 -289.433254) (xy 279.828632 -289.427051)
			(xy 279.842146 -289.407733) (xy 279.8445 -289.39617) (xy 279.856438 -289.315398) (xy 279.85755 -289.303577)
			(xy 279.850149 -289.281048) (xy 279.842214 -289.272218) (xy 279.72004 -289.150044) (xy 279.712928 -289.142678)
			(xy 279.694132 -289.135058) (xy 275.711412 -289.135058) (xy 275.701342 -289.134636) (xy 275.682738 -289.12692)
			(xy 275.675344 -289.120072) (xy 275.582634 -289.027362) (xy 275.575776 -289.02025) (xy 275.557996 -289.01263)
			(xy 275.54809 -289.012376) (xy 275.478748 -289.01009) (xy 275.473952 -289.010042) (xy 275.464484 -289.011569)
			(xy 275.459952 -289.013138) (xy 275.450808 -289.01644) (xy 275.443442 -289.02279) (xy 275.425241 -289.038305)
			(xy 275.385208 -289.064472) (xy 275.341821 -289.084593) (xy 275.295986 -289.098247) (xy 275.248661 -289.10515)
			(xy 275.224748 -289.105594) (xy 275.198757 -289.105114) (xy 275.147413 -289.096989) (xy 275.097973 -289.080931)
			(xy 275.051654 -289.057335) (xy 275.009597 -289.026784) (xy 274.972838 -288.990029) (xy 274.942282 -288.947975)
			(xy 274.918682 -288.901658) (xy 274.902619 -288.85222) (xy 274.894488 -288.800877) (xy 274.89404 -288.774886)
			(xy 274.89448 -288.75101) (xy 274.901384 -288.703759) (xy 274.915003 -288.657989) (xy 274.935055 -288.61465)
			(xy 274.961123 -288.57464) (xy 274.97659 -288.556446) (xy 274.976844 -288.556192) (xy 274.983194 -288.548826)
			(xy 274.986496 -288.539682) (xy 274.988012 -288.535136) (xy 274.989544 -288.525678) (xy 274.989544 -288.520886)
			(xy 274.987258 -288.451544) (xy 274.987004 -288.441638) (xy 274.979384 -288.423858) (xy 274.972272 -288.417)
			(xy 273.682714 -287.127442) (xy 273.675856 -287.12033) (xy 273.658076 -287.11271) (xy 273.64817 -287.112456)
			(xy 273.578828 -287.11017) (xy 273.574032 -287.110124) (xy 273.564566 -287.111657) (xy 273.560032 -287.113218)
			(xy 273.550888 -287.11652) (xy 273.543522 -287.12287) (xy 273.525321 -287.138387) (xy 273.485288 -287.164557)
			(xy 273.441902 -287.184683) (xy 273.396067 -287.198345) (xy 273.348742 -287.205257) (xy 273.324828 -287.205674)
			(xy 273.298838 -287.205193) (xy 273.247498 -287.197065) (xy 273.198062 -287.181005) (xy 273.151748 -287.157408)
			(xy 273.109695 -287.126856) (xy 273.07294 -287.0901) (xy 273.042389 -287.048047) (xy 273.018793 -287.001732)
			(xy 273.002734 -286.952296) (xy 272.994607 -286.900956) (xy 272.99412 -286.874966) (xy 272.994562 -286.85109)
			(xy 273.001468 -286.80384) (xy 273.015088 -286.758072) (xy 273.035141 -286.714734) (xy 273.06121 -286.674725)
			(xy 273.07667 -286.656526) (xy 273.076924 -286.656272) (xy 273.083274 -286.648906) (xy 273.086576 -286.639762)
			(xy 273.08809 -286.635216) (xy 273.08962 -286.625758) (xy 273.089624 -286.620966) (xy 273.087338 -286.551624)
			(xy 273.087084 -286.541718) (xy 273.079464 -286.523938) (xy 273.072352 -286.51708) (xy 272.7325 -286.177228)
			(xy 272.725407 -286.170761) (xy 272.707784 -286.163192) (xy 272.69821 -286.162496) (xy 272.618962 -286.159956)
			(xy 272.600928 -286.16656) (xy 272.593562 -286.17291) (xy 272.575343 -286.188387) (xy 272.535291 -286.21448)
			(xy 272.4919 -286.23454) (xy 272.446075 -286.248148) (xy 272.398769 -286.255021) (xy 272.374868 -286.25546)
			(xy 272.348882 -286.254974) (xy 272.29755 -286.246839) (xy 272.248123 -286.230773) (xy 272.201817 -286.207173)
			(xy 272.159774 -286.176619) (xy 272.123029 -286.139865) (xy 272.092485 -286.097814) (xy 272.068896 -286.051503)
			(xy 272.052842 -286.002072) (xy 272.044719 -285.950738) (xy 272.04416 -285.924752) (xy 272.044577 -285.900849)
			(xy 272.051448 -285.853539) (xy 272.065055 -285.80771) (xy 272.085115 -285.764315) (xy 272.11121 -285.724259)
			(xy 272.12671 -285.706058) (xy 272.13306 -285.698692) (xy 272.139664 -285.680658) (xy 272.137124 -285.60141)
			(xy 272.136437 -285.591833) (xy 272.128874 -285.574201) (xy 272.122392 -285.56712) (xy 271.78254 -285.227268)
			(xy 271.775451 -285.220791) (xy 271.757828 -285.213202) (xy 271.74825 -285.212536) (xy 271.669002 -285.209996)
			(xy 271.650968 -285.2166) (xy 271.643602 -285.22295) (xy 271.625383 -285.238427) (xy 271.585331 -285.264523)
			(xy 271.541941 -285.284585) (xy 271.496116 -285.298196) (xy 271.44881 -285.305074) (xy 271.424908 -285.3055)
			(xy 271.398919 -285.305017) (xy 271.347579 -285.296887) (xy 271.298144 -285.280826) (xy 271.251831 -285.257228)
			(xy 271.209779 -285.226676) (xy 271.173024 -285.189921) (xy 271.142472 -285.147869) (xy 271.118874 -285.101556)
			(xy 271.102813 -285.052121) (xy 271.094683 -285.000781) (xy 271.0942 -284.974792) (xy 271.094621 -284.95089)
			(xy 271.101499 -284.903583) (xy 271.115111 -284.857758) (xy 271.135173 -284.814367) (xy 271.161269 -284.774314)
			(xy 271.17675 -284.756098) (xy 271.1831 -284.748732) (xy 271.189704 -284.730698) (xy 271.187164 -284.65145)
			(xy 271.186468 -284.641877) (xy 271.178895 -284.624256) (xy 271.172432 -284.61716) (xy 270.83258 -284.277308)
			(xy 270.82549 -284.270836) (xy 270.807865 -284.263261) (xy 270.79829 -284.262576) (xy 270.719042 -284.260036)
			(xy 270.701008 -284.26664) (xy 270.693642 -284.27299) (xy 270.675425 -284.288472) (xy 270.635375 -284.314577)
			(xy 270.591985 -284.334648) (xy 270.54616 -284.348268) (xy 270.498851 -284.355153) (xy 270.474948 -284.35554)
			(xy 270.448955 -284.35506) (xy 270.397609 -284.346935) (xy 270.348166 -284.330878) (xy 270.301844 -284.307283)
			(xy 270.259783 -284.276732) (xy 270.22302 -284.239978) (xy 270.192459 -284.197924) (xy 270.168853 -284.151608)
			(xy 270.152783 -284.102169) (xy 270.144646 -284.050825) (xy 270.14424 -284.024832) (xy 270.144658 -284.000929)
			(xy 270.151532 -283.95362) (xy 270.165141 -283.907792) (xy 270.185201 -283.864399) (xy 270.211297 -283.824344)
			(xy 270.22679 -283.806138) (xy 270.23314 -283.798772) (xy 270.239744 -283.780738) (xy 270.237204 -283.70149)
			(xy 270.236513 -283.691915) (xy 270.228943 -283.67429) (xy 270.222472 -283.6672) (xy 269.93596 -283.380688)
			(xy 269.928848 -283.373322) (xy 269.910052 -283.365702) (xy 269.688564 -283.365702) (xy 269.677642 -283.368242)
			(xy 269.672054 -283.371036) (xy 269.649083 -283.381923) (xy 269.600634 -283.397308) (xy 269.550404 -283.405114)
			(xy 269.524988 -283.40558) (xy 269.52448 -283.40558) (xy 269.499062 -283.405117) (xy 269.448827 -283.397333)
			(xy 269.40038 -283.381937) (xy 269.377414 -283.371036) (xy 269.371826 -283.368242) (xy 269.360904 -283.365702)
			(xy 268.738604 -283.365702) (xy 268.727682 -283.368242) (xy 268.722094 -283.371036) (xy 268.699122 -283.381919)
			(xy 268.650672 -283.397295) (xy 268.600443 -283.405092) (xy 268.575028 -283.40558) (xy 268.57452 -283.40558)
			(xy 268.549102 -283.40512) (xy 268.498864 -283.397342) (xy 268.450414 -283.381951) (xy 268.427454 -283.371036)
			(xy 268.421866 -283.368242) (xy 268.410944 -283.365702) (xy 264.256012 -283.365702) (xy 264.245108 -283.36616)
			(xy 264.225232 -283.375116) (xy 264.217658 -283.382974) (xy 264.199471 -283.403019) (xy 264.15841 -283.43828)
			(xy 264.112777 -283.467382) (xy 264.063487 -283.489739) (xy 264.011531 -283.504903) (xy 263.957954 -283.512568)
			(xy 263.930892 -283.513022) (xy 263.913584 -283.512805) (xy 263.879113 -283.509627) (xy 263.862058 -283.506672)
			(xy 263.849612 -283.504386) (xy 263.82599 -283.511752) (xy 263.641332 -283.69641) (xy 263.634484 -283.703808)
			(xy 263.626748 -283.722406) (xy 263.626346 -283.732478) (xy 263.626346 -283.893514) (xy 265.820904 -283.893514)
			(xy 265.824975 -283.837892) (xy 265.837101 -283.783455) (xy 265.857024 -283.731364) (xy 265.88432 -283.682729)
			(xy 265.918406 -283.638586) (xy 265.958555 -283.599877) (xy 266.003913 -283.567426) (xy 266.053513 -283.541925)
			(xy 266.106297 -283.523918) (xy 266.16114 -283.513788) (xy 266.216874 -283.511751) (xy 266.272311 -283.517851)
			(xy 266.326268 -283.531957) (xy 266.377597 -283.553769) (xy 266.425203 -283.582823) (xy 266.468071 -283.618498)
			(xy 266.505288 -283.660035) (xy 266.536061 -283.706548) (xy 266.559733 -283.757045) (xy 266.575801 -283.810452)
			(xy 266.583921 -283.865628) (xy 266.58443 -283.893514) (xy 266.583921 -283.9214) (xy 266.575801 -283.976576)
			(xy 266.561283 -284.024832) (xy 268.26897 -284.024832) (xy 268.27293 -283.975778) (xy 268.284707 -283.927994)
			(xy 268.303998 -283.882718) (xy 268.330301 -283.841122) (xy 268.362936 -283.804285) (xy 268.401057 -283.77316)
			(xy 268.443678 -283.748553) (xy 268.489694 -283.731101) (xy 268.537913 -283.721257) (xy 268.587088 -283.719276)
			(xy 268.635943 -283.725208) (xy 268.683214 -283.7389) (xy 268.727676 -283.759998) (xy 268.768179 -283.787954)
			(xy 268.803672 -283.822046) (xy 268.833237 -283.86139) (xy 268.856108 -283.904967) (xy 268.871692 -283.951648)
			(xy 268.879587 -284.000225) (xy 268.880082 -284.024832) (xy 269.21893 -284.024832) (xy 269.22289 -283.975778)
			(xy 269.234667 -283.927994) (xy 269.253958 -283.882718) (xy 269.280261 -283.841122) (xy 269.312896 -283.804285)
			(xy 269.351017 -283.77316) (xy 269.393638 -283.748553) (xy 269.439654 -283.731101) (xy 269.487873 -283.721257)
			(xy 269.537048 -283.719276) (xy 269.585903 -283.725208) (xy 269.633174 -283.7389) (xy 269.677636 -283.759998)
			(xy 269.718139 -283.787954) (xy 269.753632 -283.822046) (xy 269.783197 -283.86139) (xy 269.806068 -283.904967)
			(xy 269.821652 -283.951648) (xy 269.829547 -284.000225) (xy 269.830042 -284.024832) (xy 269.829547 -284.049439)
			(xy 269.821652 -284.098016) (xy 269.806068 -284.144697) (xy 269.783197 -284.188274) (xy 269.753632 -284.227618)
			(xy 269.718139 -284.26171) (xy 269.677636 -284.289666) (xy 269.633174 -284.310764) (xy 269.585903 -284.324456)
			(xy 269.537048 -284.330388) (xy 269.487873 -284.328407) (xy 269.439654 -284.318563) (xy 269.393638 -284.301111)
			(xy 269.351017 -284.276504) (xy 269.312896 -284.245379) (xy 269.280261 -284.208542) (xy 269.253958 -284.166946)
			(xy 269.234667 -284.12167) (xy 269.22289 -284.073886) (xy 269.21893 -284.024832) (xy 268.880082 -284.024832)
			(xy 268.879587 -284.049439) (xy 268.871692 -284.098016) (xy 268.856108 -284.144697) (xy 268.833237 -284.188274)
			(xy 268.803672 -284.227618) (xy 268.768179 -284.26171) (xy 268.727676 -284.289666) (xy 268.683214 -284.310764)
			(xy 268.635943 -284.324456) (xy 268.587088 -284.330388) (xy 268.537913 -284.328407) (xy 268.489694 -284.318563)
			(xy 268.443678 -284.301111) (xy 268.401057 -284.276504) (xy 268.362936 -284.245379) (xy 268.330301 -284.208542)
			(xy 268.303998 -284.166946) (xy 268.284707 -284.12167) (xy 268.27293 -284.073886) (xy 268.26897 -284.024832)
			(xy 266.561283 -284.024832) (xy 266.559733 -284.029983) (xy 266.536061 -284.08048) (xy 266.505288 -284.126993)
			(xy 266.468071 -284.16853) (xy 266.425203 -284.204205) (xy 266.377597 -284.233259) (xy 266.326268 -284.255071)
			(xy 266.272311 -284.269177) (xy 266.216874 -284.275277) (xy 266.16114 -284.27324) (xy 266.106297 -284.26311)
			(xy 266.053513 -284.245103) (xy 266.003913 -284.219602) (xy 265.958555 -284.187151) (xy 265.918406 -284.148442)
			(xy 265.88432 -284.104299) (xy 265.857024 -284.055664) (xy 265.837101 -284.003573) (xy 265.824975 -283.949136)
			(xy 265.820904 -283.893514) (xy 263.626346 -283.893514) (xy 263.626346 -284.974792) (xy 268.26897 -284.974792)
			(xy 268.27293 -284.925738) (xy 268.284707 -284.877954) (xy 268.303998 -284.832678) (xy 268.330301 -284.791082)
			(xy 268.362936 -284.754245) (xy 268.401057 -284.72312) (xy 268.443678 -284.698513) (xy 268.489694 -284.681061)
			(xy 268.537913 -284.671217) (xy 268.587088 -284.669236) (xy 268.635943 -284.675168) (xy 268.683214 -284.68886)
			(xy 268.727676 -284.709958) (xy 268.768179 -284.737914) (xy 268.803672 -284.772006) (xy 268.833237 -284.81135)
			(xy 268.856108 -284.854927) (xy 268.871692 -284.901608) (xy 268.879587 -284.950185) (xy 268.880082 -284.974792)
			(xy 269.21893 -284.974792) (xy 269.22289 -284.925738) (xy 269.234667 -284.877954) (xy 269.253958 -284.832678)
			(xy 269.280261 -284.791082) (xy 269.312896 -284.754245) (xy 269.351017 -284.72312) (xy 269.393638 -284.698513)
			(xy 269.439654 -284.681061) (xy 269.487873 -284.671217) (xy 269.537048 -284.669236) (xy 269.585903 -284.675168)
			(xy 269.633174 -284.68886) (xy 269.677636 -284.709958) (xy 269.718139 -284.737914) (xy 269.753632 -284.772006)
			(xy 269.783197 -284.81135) (xy 269.806068 -284.854927) (xy 269.821652 -284.901608) (xy 269.829547 -284.950185)
			(xy 269.830042 -284.974792) (xy 270.169144 -284.974792) (xy 270.173104 -284.925738) (xy 270.184881 -284.877954)
			(xy 270.204172 -284.832678) (xy 270.230475 -284.791082) (xy 270.26311 -284.754245) (xy 270.301231 -284.72312)
			(xy 270.343852 -284.698513) (xy 270.389868 -284.681061) (xy 270.438087 -284.671217) (xy 270.487262 -284.669236)
			(xy 270.536117 -284.675168) (xy 270.583388 -284.68886) (xy 270.62785 -284.709958) (xy 270.668353 -284.737914)
			(xy 270.703846 -284.772006) (xy 270.733411 -284.81135) (xy 270.756282 -284.854927) (xy 270.771866 -284.901608)
			(xy 270.779761 -284.950185) (xy 270.780256 -284.974792) (xy 270.779761 -284.999399) (xy 270.771866 -285.047976)
			(xy 270.756282 -285.094657) (xy 270.733411 -285.138234) (xy 270.703846 -285.177578) (xy 270.668353 -285.21167)
			(xy 270.62785 -285.239626) (xy 270.583388 -285.260724) (xy 270.536117 -285.274416) (xy 270.487262 -285.280348)
			(xy 270.438087 -285.278367) (xy 270.389868 -285.268523) (xy 270.343852 -285.251071) (xy 270.301231 -285.226464)
			(xy 270.26311 -285.195339) (xy 270.230475 -285.158502) (xy 270.204172 -285.116906) (xy 270.184881 -285.07163)
			(xy 270.173104 -285.023846) (xy 270.169144 -284.974792) (xy 269.830042 -284.974792) (xy 269.829547 -284.999399)
			(xy 269.821652 -285.047976) (xy 269.806068 -285.094657) (xy 269.783197 -285.138234) (xy 269.753632 -285.177578)
			(xy 269.718139 -285.21167) (xy 269.677636 -285.239626) (xy 269.633174 -285.260724) (xy 269.585903 -285.274416)
			(xy 269.537048 -285.280348) (xy 269.487873 -285.278367) (xy 269.439654 -285.268523) (xy 269.393638 -285.251071)
			(xy 269.351017 -285.226464) (xy 269.312896 -285.195339) (xy 269.280261 -285.158502) (xy 269.253958 -285.116906)
			(xy 269.234667 -285.07163) (xy 269.22289 -285.023846) (xy 269.21893 -284.974792) (xy 268.880082 -284.974792)
			(xy 268.879587 -284.999399) (xy 268.871692 -285.047976) (xy 268.856108 -285.094657) (xy 268.833237 -285.138234)
			(xy 268.803672 -285.177578) (xy 268.768179 -285.21167) (xy 268.727676 -285.239626) (xy 268.683214 -285.260724)
			(xy 268.635943 -285.274416) (xy 268.587088 -285.280348) (xy 268.537913 -285.278367) (xy 268.489694 -285.268523)
			(xy 268.443678 -285.251071) (xy 268.401057 -285.226464) (xy 268.362936 -285.195339) (xy 268.330301 -285.158502)
			(xy 268.303998 -285.116906) (xy 268.284707 -285.07163) (xy 268.27293 -285.023846) (xy 268.26897 -284.974792)
			(xy 263.626346 -284.974792) (xy 263.626346 -285.653988) (xy 263.626768 -285.664058) (xy 263.634485 -285.682661)
			(xy 263.641332 -285.690056) (xy 263.894316 -285.94304) (xy 263.913366 -285.95066) (xy 263.92378 -285.950406)
			(xy 263.950892 -285.950376) (xy 264.004697 -285.957047) (xy 264.057015 -285.971268) (xy 264.106793 -285.992751)
			(xy 264.153029 -286.021064) (xy 264.194792 -286.055636) (xy 264.231241 -286.095773) (xy 264.261641 -286.140664)
			(xy 264.28538 -286.189407) (xy 264.294112 -286.215074) (xy 264.299192 -286.231076) (xy 264.325862 -286.25038)
			(xy 268.205204 -286.25038) (xy 268.21419 -286.250035) (xy 268.231052 -286.243825) (xy 268.244707 -286.232143)
			(xy 268.2494 -286.224472) (xy 268.292834 -286.147764) (xy 268.296928 -286.139742) (xy 268.299747 -286.121967)
			(xy 268.29621 -286.10432) (xy 268.291818 -286.096456) (xy 268.276841 -286.070438) (xy 268.255543 -286.014317)
			(xy 268.24472 -285.955274) (xy 268.244066 -285.92526) (xy 268.244066 -285.924752) (xy 268.244576 -285.898765)
			(xy 268.252706 -285.84743) (xy 268.268767 -285.798) (xy 268.292363 -285.75169) (xy 268.322913 -285.709642)
			(xy 268.359664 -285.672891) (xy 268.401712 -285.642341) (xy 268.448022 -285.618745) (xy 268.497452 -285.602684)
			(xy 268.548787 -285.594554) (xy 268.600761 -285.594554) (xy 268.652096 -285.602684) (xy 268.701526 -285.618745)
			(xy 268.747836 -285.642341) (xy 268.789884 -285.672891) (xy 268.826635 -285.709642) (xy 268.857185 -285.75169)
			(xy 268.880781 -285.798) (xy 268.896842 -285.84743) (xy 268.904972 -285.898765) (xy 268.905482 -285.924752)
			(xy 269.21893 -285.924752) (xy 269.22289 -285.875698) (xy 269.234667 -285.827914) (xy 269.253958 -285.782638)
			(xy 269.280261 -285.741042) (xy 269.312896 -285.704205) (xy 269.351017 -285.67308) (xy 269.393638 -285.648473)
			(xy 269.439654 -285.631021) (xy 269.487873 -285.621177) (xy 269.537048 -285.619196) (xy 269.585903 -285.625128)
			(xy 269.633174 -285.63882) (xy 269.677636 -285.659918) (xy 269.718139 -285.687874) (xy 269.753632 -285.721966)
			(xy 269.783197 -285.76131) (xy 269.806068 -285.804887) (xy 269.821652 -285.851568) (xy 269.829547 -285.900145)
			(xy 269.830042 -285.924752) (xy 270.169144 -285.924752) (xy 270.173104 -285.875698) (xy 270.184881 -285.827914)
			(xy 270.204172 -285.782638) (xy 270.230475 -285.741042) (xy 270.26311 -285.704205) (xy 270.301231 -285.67308)
			(xy 270.343852 -285.648473) (xy 270.389868 -285.631021) (xy 270.438087 -285.621177) (xy 270.487262 -285.619196)
			(xy 270.536117 -285.625128) (xy 270.583388 -285.63882) (xy 270.62785 -285.659918) (xy 270.668353 -285.687874)
			(xy 270.703846 -285.721966) (xy 270.733411 -285.76131) (xy 270.756282 -285.804887) (xy 270.771866 -285.851568)
			(xy 270.779761 -285.900145) (xy 270.780256 -285.924752) (xy 271.119104 -285.924752) (xy 271.123064 -285.875698)
			(xy 271.134841 -285.827914) (xy 271.154132 -285.782638) (xy 271.180435 -285.741042) (xy 271.21307 -285.704205)
			(xy 271.251191 -285.67308) (xy 271.293812 -285.648473) (xy 271.339828 -285.631021) (xy 271.388047 -285.621177)
			(xy 271.437222 -285.619196) (xy 271.486077 -285.625128) (xy 271.533348 -285.63882) (xy 271.57781 -285.659918)
			(xy 271.618313 -285.687874) (xy 271.653806 -285.721966) (xy 271.683371 -285.76131) (xy 271.706242 -285.804887)
			(xy 271.721826 -285.851568) (xy 271.729721 -285.900145) (xy 271.730216 -285.924752) (xy 271.729721 -285.949359)
			(xy 271.721826 -285.997936) (xy 271.706242 -286.044617) (xy 271.683371 -286.088194) (xy 271.653806 -286.127538)
			(xy 271.618313 -286.16163) (xy 271.57781 -286.189586) (xy 271.533348 -286.210684) (xy 271.486077 -286.224376)
			(xy 271.437222 -286.230308) (xy 271.388047 -286.228327) (xy 271.339828 -286.218483) (xy 271.293812 -286.201031)
			(xy 271.251191 -286.176424) (xy 271.21307 -286.145299) (xy 271.180435 -286.108462) (xy 271.154132 -286.066866)
			(xy 271.134841 -286.02159) (xy 271.123064 -285.973806) (xy 271.119104 -285.924752) (xy 270.780256 -285.924752)
			(xy 270.779761 -285.949359) (xy 270.771866 -285.997936) (xy 270.756282 -286.044617) (xy 270.733411 -286.088194)
			(xy 270.703846 -286.127538) (xy 270.668353 -286.16163) (xy 270.62785 -286.189586) (xy 270.583388 -286.210684)
			(xy 270.536117 -286.224376) (xy 270.487262 -286.230308) (xy 270.438087 -286.228327) (xy 270.389868 -286.218483)
			(xy 270.343852 -286.201031) (xy 270.301231 -286.176424) (xy 270.26311 -286.145299) (xy 270.230475 -286.108462)
			(xy 270.204172 -286.066866) (xy 270.184881 -286.02159) (xy 270.173104 -285.973806) (xy 270.169144 -285.924752)
			(xy 269.830042 -285.924752) (xy 269.829547 -285.949359) (xy 269.821652 -285.997936) (xy 269.806068 -286.044617)
			(xy 269.783197 -286.088194) (xy 269.753632 -286.127538) (xy 269.718139 -286.16163) (xy 269.677636 -286.189586)
			(xy 269.633174 -286.210684) (xy 269.585903 -286.224376) (xy 269.537048 -286.230308) (xy 269.487873 -286.228327)
			(xy 269.439654 -286.218483) (xy 269.393638 -286.201031) (xy 269.351017 -286.176424) (xy 269.312896 -286.145299)
			(xy 269.280261 -286.108462) (xy 269.253958 -286.066866) (xy 269.234667 -286.02159) (xy 269.22289 -285.973806)
			(xy 269.21893 -285.924752) (xy 268.905482 -285.924752) (xy 268.905016 -285.950122) (xy 268.897258 -286.000264)
			(xy 268.881931 -286.048633) (xy 268.859396 -286.094093) (xy 268.830181 -286.135578) (xy 268.794973 -286.172113)
			(xy 268.754596 -286.202841) (xy 268.732508 -286.215328) (xy 268.721586 -286.22117) (xy 268.708124 -286.240474)
			(xy 268.694662 -286.333184) (xy 268.693576 -286.345089) (xy 268.701139 -286.367734) (xy 268.70914 -286.376618)
			(xy 268.804136 -286.471614) (xy 268.811479 -286.478428) (xy 268.829942 -286.486161) (xy 268.83995 -286.4866)
			(xy 268.845792 -286.4866) (xy 268.85576 -286.487073) (xy 268.874204 -286.494642) (xy 268.881606 -286.501332)
			(xy 269.090902 -286.710628) (xy 269.099363 -286.718177) (xy 269.120726 -286.725694) (xy 269.13205 -286.725106)
			(xy 269.210536 -286.716978) (xy 269.216179 -286.716193) (xy 269.226946 -286.712474) (xy 269.231872 -286.709612)
			(xy 269.236572 -286.70661) (xy 269.244646 -286.69892) (xy 269.247874 -286.694372) (xy 269.247874 -286.694118)
			(xy 269.263308 -286.671521) (xy 269.300362 -286.63126) (xy 269.343537 -286.597645) (xy 269.391656 -286.571595)
			(xy 269.443406 -286.55382) (xy 269.497375 -286.544804) (xy 269.524734 -286.544258) (xy 269.55072 -286.54477)
			(xy 269.602053 -286.552905) (xy 269.651481 -286.568968) (xy 269.697788 -286.592565) (xy 269.739835 -286.623115)
			(xy 269.776585 -286.659865) (xy 269.807135 -286.701912) (xy 269.830732 -286.748219) (xy 269.846795 -286.797647)
			(xy 269.85493 -286.84898) (xy 269.855442 -286.874966) (xy 270.169144 -286.874966) (xy 270.173104 -286.825912)
			(xy 270.184881 -286.778128) (xy 270.204172 -286.732852) (xy 270.230475 -286.691256) (xy 270.26311 -286.654419)
			(xy 270.301231 -286.623294) (xy 270.343852 -286.598687) (xy 270.389868 -286.581235) (xy 270.438087 -286.571391)
			(xy 270.487262 -286.56941) (xy 270.536117 -286.575342) (xy 270.583388 -286.589034) (xy 270.62785 -286.610132)
			(xy 270.668353 -286.638088) (xy 270.703846 -286.67218) (xy 270.733411 -286.711524) (xy 270.756282 -286.755101)
			(xy 270.771866 -286.801782) (xy 270.779761 -286.850359) (xy 270.780256 -286.874966) (xy 271.119104 -286.874966)
			(xy 271.123064 -286.825912) (xy 271.134841 -286.778128) (xy 271.154132 -286.732852) (xy 271.180435 -286.691256)
			(xy 271.21307 -286.654419) (xy 271.251191 -286.623294) (xy 271.293812 -286.598687) (xy 271.339828 -286.581235)
			(xy 271.388047 -286.571391) (xy 271.437222 -286.56941) (xy 271.486077 -286.575342) (xy 271.533348 -286.589034)
			(xy 271.57781 -286.610132) (xy 271.618313 -286.638088) (xy 271.653806 -286.67218) (xy 271.683371 -286.711524)
			(xy 271.706242 -286.755101) (xy 271.721826 -286.801782) (xy 271.729721 -286.850359) (xy 271.730216 -286.874966)
			(xy 272.069064 -286.874966) (xy 272.073024 -286.825912) (xy 272.084801 -286.778128) (xy 272.104092 -286.732852)
			(xy 272.130395 -286.691256) (xy 272.16303 -286.654419) (xy 272.201151 -286.623294) (xy 272.243772 -286.598687)
			(xy 272.289788 -286.581235) (xy 272.338007 -286.571391) (xy 272.387182 -286.56941) (xy 272.436037 -286.575342)
			(xy 272.483308 -286.589034) (xy 272.52777 -286.610132) (xy 272.568273 -286.638088) (xy 272.603766 -286.67218)
			(xy 272.633331 -286.711524) (xy 272.656202 -286.755101) (xy 272.671786 -286.801782) (xy 272.679681 -286.850359)
			(xy 272.680176 -286.874966) (xy 272.679681 -286.899573) (xy 272.671786 -286.94815) (xy 272.656202 -286.994831)
			(xy 272.633331 -287.038408) (xy 272.603766 -287.077752) (xy 272.568273 -287.111844) (xy 272.52777 -287.1398)
			(xy 272.483308 -287.160898) (xy 272.436037 -287.17459) (xy 272.387182 -287.180522) (xy 272.338007 -287.178541)
			(xy 272.289788 -287.168697) (xy 272.243772 -287.151245) (xy 272.201151 -287.126638) (xy 272.16303 -287.095513)
			(xy 272.130395 -287.058676) (xy 272.104092 -287.01708) (xy 272.084801 -286.971804) (xy 272.073024 -286.92402)
			(xy 272.069064 -286.874966) (xy 271.730216 -286.874966) (xy 271.729721 -286.899573) (xy 271.721826 -286.94815)
			(xy 271.706242 -286.994831) (xy 271.683371 -287.038408) (xy 271.653806 -287.077752) (xy 271.618313 -287.111844)
			(xy 271.57781 -287.1398) (xy 271.533348 -287.160898) (xy 271.486077 -287.17459) (xy 271.437222 -287.180522)
			(xy 271.388047 -287.178541) (xy 271.339828 -287.168697) (xy 271.293812 -287.151245) (xy 271.251191 -287.126638)
			(xy 271.21307 -287.095513) (xy 271.180435 -287.058676) (xy 271.154132 -287.01708) (xy 271.134841 -286.971804)
			(xy 271.123064 -286.92402) (xy 271.119104 -286.874966) (xy 270.780256 -286.874966) (xy 270.779761 -286.899573)
			(xy 270.771866 -286.94815) (xy 270.756282 -286.994831) (xy 270.733411 -287.038408) (xy 270.703846 -287.077752)
			(xy 270.668353 -287.111844) (xy 270.62785 -287.1398) (xy 270.583388 -287.160898) (xy 270.536117 -287.17459)
			(xy 270.487262 -287.180522) (xy 270.438087 -287.178541) (xy 270.389868 -287.168697) (xy 270.343852 -287.151245)
			(xy 270.301231 -287.126638) (xy 270.26311 -287.095513) (xy 270.230475 -287.058676) (xy 270.204172 -287.01708)
			(xy 270.184881 -286.971804) (xy 270.173104 -286.92402) (xy 270.169144 -286.874966) (xy 269.855442 -286.874966)
			(xy 269.85491 -286.902328) (xy 269.845906 -286.956305) (xy 269.828137 -287.008064) (xy 269.80209 -287.056191)
			(xy 269.768474 -287.099372) (xy 269.728207 -287.136429) (xy 269.705582 -287.151826) (xy 269.705328 -287.151826)
			(xy 269.700774 -287.155047) (xy 269.693087 -287.163125) (xy 269.690088 -287.167828) (xy 269.687193 -287.172739)
			(xy 269.683469 -287.183512) (xy 269.682722 -287.189164) (xy 269.674594 -287.26765) (xy 269.673324 -287.27908)
			(xy 269.680944 -287.30067) (xy 270.041116 -287.660588) (xy 270.0496 -287.66825) (xy 270.071103 -287.675913)
			(xy 270.082518 -287.67532) (xy 270.171926 -287.665922) (xy 270.191484 -287.653984) (xy 270.197834 -287.644332)
			(xy 270.213281 -287.621711) (xy 270.250368 -287.581405) (xy 270.293581 -287.547751) (xy 270.341743 -287.521666)
			(xy 270.393541 -287.503863) (xy 270.447562 -287.494825) (xy 270.474948 -287.494218) (xy 270.500932 -287.494731)
			(xy 270.552259 -287.502868) (xy 270.601682 -287.518933) (xy 270.647983 -287.542532) (xy 270.690022 -287.573083)
			(xy 270.726765 -287.609834) (xy 270.757307 -287.651881) (xy 270.780895 -287.698187) (xy 270.796949 -287.747613)
			(xy 270.805075 -287.798942) (xy 270.805656 -287.824926) (xy 273.019024 -287.824926) (xy 273.022984 -287.775872)
			(xy 273.034761 -287.728088) (xy 273.054052 -287.682812) (xy 273.080355 -287.641216) (xy 273.11299 -287.604379)
			(xy 273.151111 -287.573254) (xy 273.193732 -287.548647) (xy 273.239748 -287.531195) (xy 273.287967 -287.521351)
			(xy 273.337142 -287.51937) (xy 273.385997 -287.525302) (xy 273.433268 -287.538994) (xy 273.47773 -287.560092)
			(xy 273.518233 -287.588048) (xy 273.553726 -287.62214) (xy 273.583291 -287.661484) (xy 273.606162 -287.705061)
			(xy 273.621746 -287.751742) (xy 273.629641 -287.800319) (xy 273.630136 -287.824926) (xy 273.629641 -287.849533)
			(xy 273.621746 -287.89811) (xy 273.606162 -287.944791) (xy 273.583291 -287.988368) (xy 273.553726 -288.027712)
			(xy 273.518233 -288.061804) (xy 273.47773 -288.08976) (xy 273.433268 -288.110858) (xy 273.385997 -288.12455)
			(xy 273.337142 -288.130482) (xy 273.287967 -288.128501) (xy 273.239748 -288.118657) (xy 273.193732 -288.101205)
			(xy 273.151111 -288.076598) (xy 273.11299 -288.045473) (xy 273.080355 -288.008636) (xy 273.054052 -287.96704)
			(xy 273.034761 -287.921764) (xy 273.022984 -287.87398) (xy 273.019024 -287.824926) (xy 270.805656 -287.824926)
			(xy 270.805126 -287.85232) (xy 270.79611 -287.906361) (xy 270.778312 -287.958178) (xy 270.75222 -288.006354)
			(xy 270.718545 -288.049572) (xy 270.67821 -288.08665) (xy 270.655542 -288.10204) (xy 270.64589 -288.10839)
			(xy 270.633952 -288.127948) (xy 270.624554 -288.217356) (xy 270.623978 -288.228771) (xy 270.631627 -288.250275)
			(xy 270.639286 -288.258758) (xy 270.991076 -288.610548) (xy 270.999566 -288.618191) (xy 271.021065 -288.62582)
			(xy 271.032478 -288.62528) (xy 271.121886 -288.615882) (xy 271.141444 -288.603944) (xy 271.147794 -288.594292)
			(xy 271.163238 -288.571666) (xy 271.20032 -288.531348) (xy 271.243531 -288.497682) (xy 271.291694 -288.471587)
			(xy 271.343494 -288.453774) (xy 271.39752 -288.444728) (xy 271.424908 -288.444178) (xy 271.450895 -288.444688)
			(xy 271.50223 -288.45282) (xy 271.55166 -288.468881) (xy 271.597969 -288.492477) (xy 271.640018 -288.523027)
			(xy 271.676769 -288.559778) (xy 271.70732 -288.601826) (xy 271.730917 -288.648135) (xy 271.746979 -288.697565)
			(xy 271.755111 -288.748899) (xy 271.755616 -288.774886) (xy 272.069064 -288.774886) (xy 272.073024 -288.725832)
			(xy 272.084801 -288.678048) (xy 272.104092 -288.632772) (xy 272.130395 -288.591176) (xy 272.16303 -288.554339)
			(xy 272.201151 -288.523214) (xy 272.243772 -288.498607) (xy 272.289788 -288.481155) (xy 272.338007 -288.471311)
			(xy 272.387182 -288.46933) (xy 272.436037 -288.475262) (xy 272.483308 -288.488954) (xy 272.52777 -288.510052)
			(xy 272.568273 -288.538008) (xy 272.603766 -288.5721) (xy 272.633331 -288.611444) (xy 272.656202 -288.655021)
			(xy 272.671786 -288.701702) (xy 272.679681 -288.750279) (xy 272.680176 -288.774886) (xy 273.019024 -288.774886)
			(xy 273.022984 -288.725832) (xy 273.034761 -288.678048) (xy 273.054052 -288.632772) (xy 273.080355 -288.591176)
			(xy 273.11299 -288.554339) (xy 273.151111 -288.523214) (xy 273.193732 -288.498607) (xy 273.239748 -288.481155)
			(xy 273.287967 -288.471311) (xy 273.337142 -288.46933) (xy 273.385997 -288.475262) (xy 273.433268 -288.488954)
			(xy 273.47773 -288.510052) (xy 273.518233 -288.538008) (xy 273.553726 -288.5721) (xy 273.583291 -288.611444)
			(xy 273.606162 -288.655021) (xy 273.621746 -288.701702) (xy 273.629641 -288.750279) (xy 273.630136 -288.774886)
			(xy 273.968984 -288.774886) (xy 273.972944 -288.725832) (xy 273.984721 -288.678048) (xy 274.004012 -288.632772)
			(xy 274.030315 -288.591176) (xy 274.06295 -288.554339) (xy 274.101071 -288.523214) (xy 274.143692 -288.498607)
			(xy 274.189708 -288.481155) (xy 274.237927 -288.471311) (xy 274.287102 -288.46933) (xy 274.335957 -288.475262)
			(xy 274.383228 -288.488954) (xy 274.42769 -288.510052) (xy 274.468193 -288.538008) (xy 274.503686 -288.5721)
			(xy 274.533251 -288.611444) (xy 274.556122 -288.655021) (xy 274.571706 -288.701702) (xy 274.579601 -288.750279)
			(xy 274.580096 -288.774886) (xy 274.579601 -288.799493) (xy 274.571706 -288.84807) (xy 274.556122 -288.894751)
			(xy 274.533251 -288.938328) (xy 274.503686 -288.977672) (xy 274.468193 -289.011764) (xy 274.42769 -289.03972)
			(xy 274.383228 -289.060818) (xy 274.335957 -289.07451) (xy 274.287102 -289.080442) (xy 274.237927 -289.078461)
			(xy 274.189708 -289.068617) (xy 274.143692 -289.051165) (xy 274.101071 -289.026558) (xy 274.06295 -288.995433)
			(xy 274.030315 -288.958596) (xy 274.004012 -288.917) (xy 273.984721 -288.871724) (xy 273.972944 -288.82394)
			(xy 273.968984 -288.774886) (xy 273.630136 -288.774886) (xy 273.629641 -288.799493) (xy 273.621746 -288.84807)
			(xy 273.606162 -288.894751) (xy 273.583291 -288.938328) (xy 273.553726 -288.977672) (xy 273.518233 -289.011764)
			(xy 273.47773 -289.03972) (xy 273.433268 -289.060818) (xy 273.385997 -289.07451) (xy 273.337142 -289.080442)
			(xy 273.287967 -289.078461) (xy 273.239748 -289.068617) (xy 273.193732 -289.051165) (xy 273.151111 -289.026558)
			(xy 273.11299 -288.995433) (xy 273.080355 -288.958596) (xy 273.054052 -288.917) (xy 273.034761 -288.871724)
			(xy 273.022984 -288.82394) (xy 273.019024 -288.774886) (xy 272.680176 -288.774886) (xy 272.679681 -288.799493)
			(xy 272.671786 -288.84807) (xy 272.656202 -288.894751) (xy 272.633331 -288.938328) (xy 272.603766 -288.977672)
			(xy 272.568273 -289.011764) (xy 272.52777 -289.03972) (xy 272.483308 -289.060818) (xy 272.436037 -289.07451)
			(xy 272.387182 -289.080442) (xy 272.338007 -289.078461) (xy 272.289788 -289.068617) (xy 272.243772 -289.051165)
			(xy 272.201151 -289.026558) (xy 272.16303 -288.995433) (xy 272.130395 -288.958596) (xy 272.104092 -288.917)
			(xy 272.084801 -288.871724) (xy 272.073024 -288.82394) (xy 272.069064 -288.774886) (xy 271.755616 -288.774886)
			(xy 271.755081 -288.802277) (xy 271.746056 -288.856311) (xy 271.728251 -288.908119) (xy 271.702151 -288.956285)
			(xy 271.668472 -288.999492) (xy 271.628133 -289.036559) (xy 271.605502 -289.052) (xy 271.59585 -289.05835)
			(xy 271.583912 -289.077908) (xy 271.574514 -289.167316) (xy 271.57395 -289.178726) (xy 271.581612 -289.200216)
			(xy 271.589246 -289.208718) (xy 271.941036 -289.560508) (xy 271.949522 -289.568164) (xy 271.971024 -289.575815)
			(xy 271.982438 -289.57524) (xy 272.071846 -289.565842) (xy 272.091404 -289.553904) (xy 272.097754 -289.544252)
			(xy 272.113201 -289.521631) (xy 272.150287 -289.481325) (xy 272.1935 -289.447671) (xy 272.241663 -289.421588)
			(xy 272.293461 -289.403786) (xy 272.347482 -289.394751) (xy 272.374868 -289.394138) (xy 272.400858 -289.394619)
			(xy 272.452197 -289.402746) (xy 272.501633 -289.418806) (xy 272.547948 -289.442403) (xy 272.59 -289.472956)
			(xy 272.626754 -289.509711) (xy 272.657304 -289.551764) (xy 272.680899 -289.59808) (xy 272.696957 -289.647516)
			(xy 272.705082 -289.698856) (xy 272.705576 -289.724846) (xy 273.019024 -289.724846) (xy 273.022984 -289.675792)
			(xy 273.034761 -289.628008) (xy 273.054052 -289.582732) (xy 273.080355 -289.541136) (xy 273.11299 -289.504299)
			(xy 273.151111 -289.473174) (xy 273.193732 -289.448567) (xy 273.239748 -289.431115) (xy 273.287967 -289.421271)
			(xy 273.337142 -289.41929) (xy 273.385997 -289.425222) (xy 273.433268 -289.438914) (xy 273.47773 -289.460012)
			(xy 273.518233 -289.487968) (xy 273.553726 -289.52206) (xy 273.583291 -289.561404) (xy 273.606162 -289.604981)
			(xy 273.621746 -289.651662) (xy 273.629641 -289.700239) (xy 273.630136 -289.724846) (xy 273.968984 -289.724846)
			(xy 273.972944 -289.675792) (xy 273.984721 -289.628008) (xy 274.004012 -289.582732) (xy 274.030315 -289.541136)
			(xy 274.06295 -289.504299) (xy 274.101071 -289.473174) (xy 274.143692 -289.448567) (xy 274.189708 -289.431115)
			(xy 274.237927 -289.421271) (xy 274.287102 -289.41929) (xy 274.335957 -289.425222) (xy 274.383228 -289.438914)
			(xy 274.42769 -289.460012) (xy 274.468193 -289.487968) (xy 274.503686 -289.52206) (xy 274.533251 -289.561404)
			(xy 274.556122 -289.604981) (xy 274.571706 -289.651662) (xy 274.579601 -289.700239) (xy 274.580096 -289.724846)
			(xy 274.918944 -289.724846) (xy 274.922904 -289.675792) (xy 274.934681 -289.628008) (xy 274.953972 -289.582732)
			(xy 274.980275 -289.541136) (xy 275.01291 -289.504299) (xy 275.051031 -289.473174) (xy 275.093652 -289.448567)
			(xy 275.139668 -289.431115) (xy 275.187887 -289.421271) (xy 275.237062 -289.41929) (xy 275.285917 -289.425222)
			(xy 275.333188 -289.438914) (xy 275.37765 -289.460012) (xy 275.418153 -289.487968) (xy 275.453646 -289.52206)
			(xy 275.483211 -289.561404) (xy 275.506082 -289.604981) (xy 275.521666 -289.651662) (xy 275.529561 -289.700239)
			(xy 275.530056 -289.724846) (xy 275.868904 -289.724846) (xy 275.872864 -289.675792) (xy 275.884641 -289.628008)
			(xy 275.903932 -289.582732) (xy 275.930235 -289.541136) (xy 275.96287 -289.504299) (xy 276.000991 -289.473174)
			(xy 276.043612 -289.448567) (xy 276.089628 -289.431115) (xy 276.137847 -289.421271) (xy 276.187022 -289.41929)
			(xy 276.235877 -289.425222) (xy 276.283148 -289.438914) (xy 276.32761 -289.460012) (xy 276.368113 -289.487968)
			(xy 276.403606 -289.52206) (xy 276.433171 -289.561404) (xy 276.456042 -289.604981) (xy 276.471626 -289.651662)
			(xy 276.479521 -289.700239) (xy 276.480016 -289.724846) (xy 276.819118 -289.724846) (xy 276.823078 -289.675792)
			(xy 276.834855 -289.628008) (xy 276.854146 -289.582732) (xy 276.880449 -289.541136) (xy 276.913084 -289.504299)
			(xy 276.951205 -289.473174) (xy 276.993826 -289.448567) (xy 277.039842 -289.431115) (xy 277.088061 -289.421271)
			(xy 277.137236 -289.41929) (xy 277.186091 -289.425222) (xy 277.233362 -289.438914) (xy 277.277824 -289.460012)
			(xy 277.318327 -289.487968) (xy 277.35382 -289.52206) (xy 277.383385 -289.561404) (xy 277.406256 -289.604981)
			(xy 277.42184 -289.651662) (xy 277.429735 -289.700239) (xy 277.43023 -289.724846) (xy 277.769078 -289.724846)
			(xy 277.773038 -289.675792) (xy 277.784815 -289.628008) (xy 277.804106 -289.582732) (xy 277.830409 -289.541136)
			(xy 277.863044 -289.504299) (xy 277.901165 -289.473174) (xy 277.943786 -289.448567) (xy 277.989802 -289.431115)
			(xy 278.038021 -289.421271) (xy 278.087196 -289.41929) (xy 278.136051 -289.425222) (xy 278.183322 -289.438914)
			(xy 278.227784 -289.460012) (xy 278.268287 -289.487968) (xy 278.30378 -289.52206) (xy 278.333345 -289.561404)
			(xy 278.356216 -289.604981) (xy 278.3718 -289.651662) (xy 278.379695 -289.700239) (xy 278.38019 -289.724846)
			(xy 278.719038 -289.724846) (xy 278.722998 -289.675792) (xy 278.734775 -289.628008) (xy 278.754066 -289.582732)
			(xy 278.780369 -289.541136) (xy 278.813004 -289.504299) (xy 278.851125 -289.473174) (xy 278.893746 -289.448567)
			(xy 278.939762 -289.431115) (xy 278.987981 -289.421271) (xy 279.037156 -289.41929) (xy 279.086011 -289.425222)
			(xy 279.133282 -289.438914) (xy 279.177744 -289.460012) (xy 279.218247 -289.487968) (xy 279.25374 -289.52206)
			(xy 279.283305 -289.561404) (xy 279.306176 -289.604981) (xy 279.32176 -289.651662) (xy 279.329655 -289.700239)
			(xy 279.33015 -289.724846) (xy 279.329655 -289.749453) (xy 279.32176 -289.79803) (xy 279.306176 -289.844711)
			(xy 279.283305 -289.888288) (xy 279.25374 -289.927632) (xy 279.218247 -289.961724) (xy 279.177744 -289.98968)
			(xy 279.133282 -290.010778) (xy 279.086011 -290.02447) (xy 279.037156 -290.030402) (xy 278.987981 -290.028421)
			(xy 278.939762 -290.018577) (xy 278.893746 -290.001125) (xy 278.851125 -289.976518) (xy 278.813004 -289.945393)
			(xy 278.780369 -289.908556) (xy 278.754066 -289.86696) (xy 278.734775 -289.821684) (xy 278.722998 -289.7739)
			(xy 278.719038 -289.724846) (xy 278.38019 -289.724846) (xy 278.379695 -289.749453) (xy 278.3718 -289.79803)
			(xy 278.356216 -289.844711) (xy 278.333345 -289.888288) (xy 278.30378 -289.927632) (xy 278.268287 -289.961724)
			(xy 278.227784 -289.98968) (xy 278.183322 -290.010778) (xy 278.136051 -290.02447) (xy 278.087196 -290.030402)
			(xy 278.038021 -290.028421) (xy 277.989802 -290.018577) (xy 277.943786 -290.001125) (xy 277.901165 -289.976518)
			(xy 277.863044 -289.945393) (xy 277.830409 -289.908556) (xy 277.804106 -289.86696) (xy 277.784815 -289.821684)
			(xy 277.773038 -289.7739) (xy 277.769078 -289.724846) (xy 277.43023 -289.724846) (xy 277.429735 -289.749453)
			(xy 277.42184 -289.79803) (xy 277.406256 -289.844711) (xy 277.383385 -289.888288) (xy 277.35382 -289.927632)
			(xy 277.318327 -289.961724) (xy 277.277824 -289.98968) (xy 277.233362 -290.010778) (xy 277.186091 -290.02447)
			(xy 277.137236 -290.030402) (xy 277.088061 -290.028421) (xy 277.039842 -290.018577) (xy 276.993826 -290.001125)
			(xy 276.951205 -289.976518) (xy 276.913084 -289.945393) (xy 276.880449 -289.908556) (xy 276.854146 -289.86696)
			(xy 276.834855 -289.821684) (xy 276.823078 -289.7739) (xy 276.819118 -289.724846) (xy 276.480016 -289.724846)
			(xy 276.479521 -289.749453) (xy 276.471626 -289.79803) (xy 276.456042 -289.844711) (xy 276.433171 -289.888288)
			(xy 276.403606 -289.927632) (xy 276.368113 -289.961724) (xy 276.32761 -289.98968) (xy 276.283148 -290.010778)
			(xy 276.235877 -290.02447) (xy 276.187022 -290.030402) (xy 276.137847 -290.028421) (xy 276.089628 -290.018577)
			(xy 276.043612 -290.001125) (xy 276.000991 -289.976518) (xy 275.96287 -289.945393) (xy 275.930235 -289.908556)
			(xy 275.903932 -289.86696) (xy 275.884641 -289.821684) (xy 275.872864 -289.7739) (xy 275.868904 -289.724846)
			(xy 275.530056 -289.724846) (xy 275.529561 -289.749453) (xy 275.521666 -289.79803) (xy 275.506082 -289.844711)
			(xy 275.483211 -289.888288) (xy 275.453646 -289.927632) (xy 275.418153 -289.961724) (xy 275.37765 -289.98968)
			(xy 275.333188 -290.010778) (xy 275.285917 -290.02447) (xy 275.237062 -290.030402) (xy 275.187887 -290.028421)
			(xy 275.139668 -290.018577) (xy 275.093652 -290.001125) (xy 275.051031 -289.976518) (xy 275.01291 -289.945393)
			(xy 274.980275 -289.908556) (xy 274.953972 -289.86696) (xy 274.934681 -289.821684) (xy 274.922904 -289.7739)
			(xy 274.918944 -289.724846) (xy 274.580096 -289.724846) (xy 274.579601 -289.749453) (xy 274.571706 -289.79803)
			(xy 274.556122 -289.844711) (xy 274.533251 -289.888288) (xy 274.503686 -289.927632) (xy 274.468193 -289.961724)
			(xy 274.42769 -289.98968) (xy 274.383228 -290.010778) (xy 274.335957 -290.02447) (xy 274.287102 -290.030402)
			(xy 274.237927 -290.028421) (xy 274.189708 -290.018577) (xy 274.143692 -290.001125) (xy 274.101071 -289.976518)
			(xy 274.06295 -289.945393) (xy 274.030315 -289.908556) (xy 274.004012 -289.86696) (xy 273.984721 -289.821684)
			(xy 273.972944 -289.7739) (xy 273.968984 -289.724846) (xy 273.630136 -289.724846) (xy 273.629641 -289.749453)
			(xy 273.621746 -289.79803) (xy 273.606162 -289.844711) (xy 273.583291 -289.888288) (xy 273.553726 -289.927632)
			(xy 273.518233 -289.961724) (xy 273.47773 -289.98968) (xy 273.433268 -290.010778) (xy 273.385997 -290.02447)
			(xy 273.337142 -290.030402) (xy 273.287967 -290.028421) (xy 273.239748 -290.018577) (xy 273.193732 -290.001125)
			(xy 273.151111 -289.976518) (xy 273.11299 -289.945393) (xy 273.080355 -289.908556) (xy 273.054052 -289.86696)
			(xy 273.034761 -289.821684) (xy 273.022984 -289.7739) (xy 273.019024 -289.724846) (xy 272.705576 -289.724846)
			(xy 272.705044 -289.752238) (xy 272.696024 -289.806275) (xy 272.678221 -289.858086) (xy 272.652123 -289.906255)
			(xy 272.618443 -289.949464) (xy 272.578103 -289.986531) (xy 272.555462 -290.00196) (xy 272.54581 -290.00831)
			(xy 272.533872 -290.027868) (xy 272.524474 -290.117276) (xy 272.523902 -290.128689) (xy 272.531559 -290.150185)
			(xy 272.539206 -290.158678) (xy 272.890996 -290.510468) (xy 272.899478 -290.518136) (xy 272.920983 -290.52581)
			(xy 272.932398 -290.5252) (xy 273.021806 -290.515802) (xy 273.041364 -290.503864) (xy 273.047714 -290.494212)
			(xy 273.063158 -290.471586) (xy 273.100239 -290.431268) (xy 273.143451 -290.397603) (xy 273.191613 -290.371509)
			(xy 273.243414 -290.353697) (xy 273.29744 -290.344654) (xy 273.324828 -290.344098) (xy 273.350814 -290.34461)
			(xy 273.402144 -290.352744) (xy 273.451571 -290.368807) (xy 273.497876 -290.392405) (xy 273.53992 -290.422955)
			(xy 273.576667 -290.459706) (xy 273.607213 -290.501753) (xy 273.630806 -290.548061) (xy 273.646864 -290.597489)
			(xy 273.654993 -290.64882) (xy 273.655536 -290.674806) (xy 273.968984 -290.674806) (xy 273.972944 -290.625752)
			(xy 273.984721 -290.577968) (xy 274.004012 -290.532692) (xy 274.030315 -290.491096) (xy 274.06295 -290.454259)
			(xy 274.101071 -290.423134) (xy 274.143692 -290.398527) (xy 274.189708 -290.381075) (xy 274.237927 -290.371231)
			(xy 274.287102 -290.36925) (xy 274.335957 -290.375182) (xy 274.383228 -290.388874) (xy 274.42769 -290.409972)
			(xy 274.468193 -290.437928) (xy 274.503686 -290.47202) (xy 274.533251 -290.511364) (xy 274.556122 -290.554941)
			(xy 274.571706 -290.601622) (xy 274.579601 -290.650199) (xy 274.580096 -290.674806) (xy 274.918944 -290.674806)
			(xy 274.922904 -290.625752) (xy 274.934681 -290.577968) (xy 274.953972 -290.532692) (xy 274.980275 -290.491096)
			(xy 275.01291 -290.454259) (xy 275.051031 -290.423134) (xy 275.093652 -290.398527) (xy 275.139668 -290.381075)
			(xy 275.187887 -290.371231) (xy 275.237062 -290.36925) (xy 275.285917 -290.375182) (xy 275.333188 -290.388874)
			(xy 275.37765 -290.409972) (xy 275.418153 -290.437928) (xy 275.453646 -290.47202) (xy 275.483211 -290.511364)
			(xy 275.506082 -290.554941) (xy 275.521666 -290.601622) (xy 275.529561 -290.650199) (xy 275.530056 -290.674806)
			(xy 275.868904 -290.674806) (xy 275.872864 -290.625752) (xy 275.884641 -290.577968) (xy 275.903932 -290.532692)
			(xy 275.930235 -290.491096) (xy 275.96287 -290.454259) (xy 276.000991 -290.423134) (xy 276.043612 -290.398527)
			(xy 276.089628 -290.381075) (xy 276.137847 -290.371231) (xy 276.187022 -290.36925) (xy 276.235877 -290.375182)
			(xy 276.283148 -290.388874) (xy 276.32761 -290.409972) (xy 276.368113 -290.437928) (xy 276.403606 -290.47202)
			(xy 276.433171 -290.511364) (xy 276.456042 -290.554941) (xy 276.471626 -290.601622) (xy 276.479521 -290.650199)
			(xy 276.480016 -290.674806) (xy 276.819118 -290.674806) (xy 276.823078 -290.625752) (xy 276.834855 -290.577968)
			(xy 276.854146 -290.532692) (xy 276.880449 -290.491096) (xy 276.913084 -290.454259) (xy 276.951205 -290.423134)
			(xy 276.993826 -290.398527) (xy 277.039842 -290.381075) (xy 277.088061 -290.371231) (xy 277.137236 -290.36925)
			(xy 277.186091 -290.375182) (xy 277.233362 -290.388874) (xy 277.277824 -290.409972) (xy 277.318327 -290.437928)
			(xy 277.35382 -290.47202) (xy 277.383385 -290.511364) (xy 277.406256 -290.554941) (xy 277.42184 -290.601622)
			(xy 277.429735 -290.650199) (xy 277.43023 -290.674806) (xy 277.769078 -290.674806) (xy 277.773038 -290.625752)
			(xy 277.784815 -290.577968) (xy 277.804106 -290.532692) (xy 277.830409 -290.491096) (xy 277.863044 -290.454259)
			(xy 277.901165 -290.423134) (xy 277.943786 -290.398527) (xy 277.989802 -290.381075) (xy 278.038021 -290.371231)
			(xy 278.087196 -290.36925) (xy 278.136051 -290.375182) (xy 278.183322 -290.388874) (xy 278.227784 -290.409972)
			(xy 278.268287 -290.437928) (xy 278.30378 -290.47202) (xy 278.333345 -290.511364) (xy 278.356216 -290.554941)
			(xy 278.3718 -290.601622) (xy 278.379695 -290.650199) (xy 278.38019 -290.674806) (xy 278.719038 -290.674806)
			(xy 278.722998 -290.625752) (xy 278.734775 -290.577968) (xy 278.754066 -290.532692) (xy 278.780369 -290.491096)
			(xy 278.813004 -290.454259) (xy 278.851125 -290.423134) (xy 278.893746 -290.398527) (xy 278.939762 -290.381075)
			(xy 278.987981 -290.371231) (xy 279.037156 -290.36925) (xy 279.086011 -290.375182) (xy 279.133282 -290.388874)
			(xy 279.177744 -290.409972) (xy 279.218247 -290.437928) (xy 279.25374 -290.47202) (xy 279.283305 -290.511364)
			(xy 279.306176 -290.554941) (xy 279.32176 -290.601622) (xy 279.329655 -290.650199) (xy 279.33015 -290.674806)
			(xy 279.668998 -290.674806) (xy 279.672958 -290.625752) (xy 279.684735 -290.577968) (xy 279.704026 -290.532692)
			(xy 279.730329 -290.491096) (xy 279.762964 -290.454259) (xy 279.801085 -290.423134) (xy 279.843706 -290.398527)
			(xy 279.889722 -290.381075) (xy 279.937941 -290.371231) (xy 279.987116 -290.36925) (xy 280.035971 -290.375182)
			(xy 280.083242 -290.388874) (xy 280.127704 -290.409972) (xy 280.168207 -290.437928) (xy 280.2037 -290.47202)
			(xy 280.233265 -290.511364) (xy 280.256136 -290.554941) (xy 280.27172 -290.601622) (xy 280.279615 -290.650199)
			(xy 280.28011 -290.674806) (xy 280.279615 -290.699413) (xy 280.27172 -290.74799) (xy 280.256136 -290.794671)
			(xy 280.233265 -290.838248) (xy 280.2037 -290.877592) (xy 280.168207 -290.911684) (xy 280.127704 -290.93964)
			(xy 280.083242 -290.960738) (xy 280.035971 -290.97443) (xy 279.987116 -290.980362) (xy 279.937941 -290.978381)
			(xy 279.889722 -290.968537) (xy 279.843706 -290.951085) (xy 279.801085 -290.926478) (xy 279.762964 -290.895353)
			(xy 279.730329 -290.858516) (xy 279.704026 -290.81692) (xy 279.684735 -290.771644) (xy 279.672958 -290.72386)
			(xy 279.668998 -290.674806) (xy 279.33015 -290.674806) (xy 279.329655 -290.699413) (xy 279.32176 -290.74799)
			(xy 279.306176 -290.794671) (xy 279.283305 -290.838248) (xy 279.25374 -290.877592) (xy 279.218247 -290.911684)
			(xy 279.177744 -290.93964) (xy 279.133282 -290.960738) (xy 279.086011 -290.97443) (xy 279.037156 -290.980362)
			(xy 278.987981 -290.978381) (xy 278.939762 -290.968537) (xy 278.893746 -290.951085) (xy 278.851125 -290.926478)
			(xy 278.813004 -290.895353) (xy 278.780369 -290.858516) (xy 278.754066 -290.81692) (xy 278.734775 -290.771644)
			(xy 278.722998 -290.72386) (xy 278.719038 -290.674806) (xy 278.38019 -290.674806) (xy 278.379695 -290.699413)
			(xy 278.3718 -290.74799) (xy 278.356216 -290.794671) (xy 278.333345 -290.838248) (xy 278.30378 -290.877592)
			(xy 278.268287 -290.911684) (xy 278.227784 -290.93964) (xy 278.183322 -290.960738) (xy 278.136051 -290.97443)
			(xy 278.087196 -290.980362) (xy 278.038021 -290.978381) (xy 277.989802 -290.968537) (xy 277.943786 -290.951085)
			(xy 277.901165 -290.926478) (xy 277.863044 -290.895353) (xy 277.830409 -290.858516) (xy 277.804106 -290.81692)
			(xy 277.784815 -290.771644) (xy 277.773038 -290.72386) (xy 277.769078 -290.674806) (xy 277.43023 -290.674806)
			(xy 277.429735 -290.699413) (xy 277.42184 -290.74799) (xy 277.406256 -290.794671) (xy 277.383385 -290.838248)
			(xy 277.35382 -290.877592) (xy 277.318327 -290.911684) (xy 277.277824 -290.93964) (xy 277.233362 -290.960738)
			(xy 277.186091 -290.97443) (xy 277.137236 -290.980362) (xy 277.088061 -290.978381) (xy 277.039842 -290.968537)
			(xy 276.993826 -290.951085) (xy 276.951205 -290.926478) (xy 276.913084 -290.895353) (xy 276.880449 -290.858516)
			(xy 276.854146 -290.81692) (xy 276.834855 -290.771644) (xy 276.823078 -290.72386) (xy 276.819118 -290.674806)
			(xy 276.480016 -290.674806) (xy 276.479521 -290.699413) (xy 276.471626 -290.74799) (xy 276.456042 -290.794671)
			(xy 276.433171 -290.838248) (xy 276.403606 -290.877592) (xy 276.368113 -290.911684) (xy 276.32761 -290.93964)
			(xy 276.283148 -290.960738) (xy 276.235877 -290.97443) (xy 276.187022 -290.980362) (xy 276.137847 -290.978381)
			(xy 276.089628 -290.968537) (xy 276.043612 -290.951085) (xy 276.000991 -290.926478) (xy 275.96287 -290.895353)
			(xy 275.930235 -290.858516) (xy 275.903932 -290.81692) (xy 275.884641 -290.771644) (xy 275.872864 -290.72386)
			(xy 275.868904 -290.674806) (xy 275.530056 -290.674806) (xy 275.529561 -290.699413) (xy 275.521666 -290.74799)
			(xy 275.506082 -290.794671) (xy 275.483211 -290.838248) (xy 275.453646 -290.877592) (xy 275.418153 -290.911684)
			(xy 275.37765 -290.93964) (xy 275.333188 -290.960738) (xy 275.285917 -290.97443) (xy 275.237062 -290.980362)
			(xy 275.187887 -290.978381) (xy 275.139668 -290.968537) (xy 275.093652 -290.951085) (xy 275.051031 -290.926478)
			(xy 275.01291 -290.895353) (xy 274.980275 -290.858516) (xy 274.953972 -290.81692) (xy 274.934681 -290.771644)
			(xy 274.922904 -290.72386) (xy 274.918944 -290.674806) (xy 274.580096 -290.674806) (xy 274.579601 -290.699413)
			(xy 274.571706 -290.74799) (xy 274.556122 -290.794671) (xy 274.533251 -290.838248) (xy 274.503686 -290.877592)
			(xy 274.468193 -290.911684) (xy 274.42769 -290.93964) (xy 274.383228 -290.960738) (xy 274.335957 -290.97443)
			(xy 274.287102 -290.980362) (xy 274.237927 -290.978381) (xy 274.189708 -290.968537) (xy 274.143692 -290.951085)
			(xy 274.101071 -290.926478) (xy 274.06295 -290.895353) (xy 274.030315 -290.858516) (xy 274.004012 -290.81692)
			(xy 273.984721 -290.771644) (xy 273.972944 -290.72386) (xy 273.968984 -290.674806) (xy 273.655536 -290.674806)
			(xy 273.655007 -290.702201) (xy 273.645994 -290.756243) (xy 273.628198 -290.808062) (xy 273.602106 -290.856239)
			(xy 273.568431 -290.899458) (xy 273.528095 -290.936536) (xy 273.505422 -290.95192) (xy 273.49577 -290.95827)
			(xy 273.483832 -290.977828) (xy 273.474434 -291.067236) (xy 273.473853 -291.078653) (xy 273.481494 -291.100165)
			(xy 273.489166 -291.108638) (xy 273.840956 -291.460428) (xy 273.849444 -291.468078) (xy 273.870944 -291.475717)
			(xy 273.882358 -291.47516) (xy 273.971766 -291.465762) (xy 273.991324 -291.453824) (xy 273.997674 -291.444172)
			(xy 274.013118 -291.421546) (xy 274.050201 -291.381228) (xy 274.093412 -291.347562) (xy 274.141574 -291.321466)
			(xy 274.193374 -291.30365) (xy 274.247399 -291.294602) (xy 274.274788 -291.294058) (xy 274.299854 -291.294521)
			(xy 274.349411 -291.302087) (xy 274.397258 -291.317047) (xy 274.442298 -291.33906) (xy 274.483499 -291.367619)
			(xy 274.519917 -291.402071) (xy 274.550716 -291.441625) (xy 274.575191 -291.485376) (xy 274.584414 -291.508688)
			(xy 274.586954 -291.516054) (xy 274.596606 -291.528246) (xy 274.60321 -291.532818) (xy 274.609664 -291.536922)
			(xy 274.624268 -291.54144) (xy 274.631912 -291.541708) (xy 274.867624 -291.541708) (xy 274.875268 -291.541446)
			(xy 274.88987 -291.536919) (xy 274.896326 -291.532818) (xy 274.90293 -291.528246) (xy 274.912582 -291.516054)
			(xy 274.915122 -291.508688) (xy 274.924341 -291.485368) (xy 274.948801 -291.441596) (xy 274.979591 -291.402019)
			(xy 275.016005 -291.367546) (xy 275.057207 -291.338969) (xy 275.102253 -291.316941) (xy 275.150109 -291.301969)
			(xy 275.199676 -291.294396) (xy 275.24982 -291.294396) (xy 275.299387 -291.301969) (xy 275.347243 -291.316941)
			(xy 275.392289 -291.338969) (xy 275.433491 -291.367546) (xy 275.469905 -291.402019) (xy 275.500695 -291.441596)
			(xy 275.525155 -291.485368) (xy 275.534374 -291.508688) (xy 275.536914 -291.516054) (xy 275.546566 -291.528246)
			(xy 275.55317 -291.532818) (xy 275.559622 -291.536927) (xy 275.574227 -291.541456) (xy 275.581872 -291.541708)
			(xy 275.817584 -291.541708) (xy 275.82523 -291.541452) (xy 275.839838 -291.536934) (xy 275.846286 -291.532818)
			(xy 275.85289 -291.528246) (xy 275.862542 -291.516054) (xy 275.865082 -291.508688) (xy 275.874301 -291.485368)
			(xy 275.898761 -291.441596) (xy 275.929551 -291.402019) (xy 275.965965 -291.367546) (xy 276.007167 -291.338969)
			(xy 276.052213 -291.316941) (xy 276.100069 -291.301969) (xy 276.149636 -291.294396) (xy 276.19978 -291.294396)
			(xy 276.249347 -291.301969) (xy 276.297203 -291.316941) (xy 276.342249 -291.338969) (xy 276.383451 -291.367546)
			(xy 276.419865 -291.402019) (xy 276.450655 -291.441596) (xy 276.475115 -291.485368) (xy 276.484334 -291.508688)
			(xy 276.486874 -291.516054) (xy 276.496526 -291.528246) (xy 276.50313 -291.532818) (xy 276.509584 -291.53692)
			(xy 276.524189 -291.541431) (xy 276.531832 -291.541708) (xy 276.767798 -291.541708) (xy 276.775443 -291.54145)
			(xy 276.790049 -291.536929) (xy 276.7965 -291.532818) (xy 276.803104 -291.528246) (xy 276.812756 -291.516054)
			(xy 276.815296 -291.508688) (xy 276.824515 -291.485368) (xy 276.848975 -291.441596) (xy 276.879765 -291.402019)
			(xy 276.916179 -291.367546) (xy 276.957381 -291.338969) (xy 277.002427 -291.316941) (xy 277.050283 -291.301969)
			(xy 277.09985 -291.294396) (xy 277.149994 -291.294396) (xy 277.199561 -291.301969) (xy 277.247417 -291.316941)
			(xy 277.292463 -291.338969) (xy 277.333665 -291.367546) (xy 277.370079 -291.402019) (xy 277.400869 -291.441596)
			(xy 277.425329 -291.485368) (xy 277.434548 -291.508688) (xy 277.437088 -291.516054) (xy 277.44674 -291.528246)
			(xy 277.453344 -291.532818) (xy 277.459795 -291.536931) (xy 277.4744 -291.541467) (xy 277.482046 -291.541708)
			(xy 277.717758 -291.541708) (xy 277.725405 -291.541456) (xy 277.740018 -291.536944) (xy 277.74646 -291.532818)
			(xy 277.753064 -291.528246) (xy 277.762716 -291.516054) (xy 277.765256 -291.508688) (xy 277.774475 -291.485368)
			(xy 277.798935 -291.441596) (xy 277.829725 -291.402019) (xy 277.866139 -291.367546) (xy 277.907341 -291.338969)
			(xy 277.952387 -291.316941) (xy 278.000243 -291.301969) (xy 278.04981 -291.294396) (xy 278.099954 -291.294396)
			(xy 278.149521 -291.301969) (xy 278.197377 -291.316941) (xy 278.242423 -291.338969) (xy 278.283625 -291.367546)
			(xy 278.320039 -291.402019) (xy 278.350829 -291.441596) (xy 278.375289 -291.485368) (xy 278.384508 -291.508688)
			(xy 278.387048 -291.516054) (xy 278.3967 -291.528246) (xy 278.403304 -291.532818) (xy 278.409757 -291.536923)
			(xy 278.424362 -291.541442) (xy 278.432006 -291.541708) (xy 278.667718 -291.541708) (xy 278.675362 -291.541447)
			(xy 278.689965 -291.536921) (xy 278.69642 -291.532818) (xy 278.703024 -291.528246) (xy 278.712676 -291.516054)
			(xy 278.715216 -291.508688) (xy 278.724449 -291.485382) (xy 278.748929 -291.441638) (xy 278.779731 -291.402089)
			(xy 278.816148 -291.367641) (xy 278.857346 -291.339083) (xy 278.902383 -291.31707) (xy 278.950225 -291.302105)
			(xy 278.999778 -291.294532) (xy 279.024842 -291.294058) (xy 279.050828 -291.294571) (xy 279.102159 -291.302706)
			(xy 279.151587 -291.31877) (xy 279.197893 -291.342368) (xy 279.239938 -291.372918) (xy 279.276687 -291.409668)
			(xy 279.307236 -291.451714) (xy 279.330833 -291.498021) (xy 279.346896 -291.547448) (xy 279.35503 -291.59878)
			(xy 279.35555 -291.624766) (xy 279.35555 -291.6301) (xy 279.355296 -291.64026) (xy 279.362916 -291.65931)
			(xy 279.663652 -291.960046) (xy 279.671051 -291.96689) (xy 279.68965 -291.974614) (xy 279.69972 -291.975032)
		)
		(stroke
			(width 0)
			(type solid)
		)
		(fill yes)
		(layer "In13.Cu")
		(net "PCEPLL7_VDDA18_PEX2")
	)
	(gr_poly
		(pts
			(xy 47.390558 -292.810184) (xy 47.402714 -292.80948) (xy 47.42432 -292.798331) (xy 47.43196 -292.788848)
			(xy 47.487078 -292.711124) (xy 47.490634 -292.686994) (xy 47.48657 -292.67531) (xy 47.478629 -292.650991)
			(xy 47.470067 -292.600557) (xy 47.469552 -292.57498) (xy 47.470074 -292.549725) (xy 47.478387 -292.499903)
			(xy 47.494788 -292.452129) (xy 47.518829 -292.407706) (xy 47.549853 -292.367846) (xy 47.587015 -292.333636)
			(xy 47.629301 -292.30601) (xy 47.675557 -292.28572) (xy 47.724522 -292.27332) (xy 47.77486 -292.269149)
			(xy 47.825198 -292.27332) (xy 47.874163 -292.28572) (xy 47.920419 -292.30601) (xy 47.962705 -292.333636)
			(xy 47.999867 -292.367846) (xy 48.030891 -292.407706) (xy 48.054932 -292.452129) (xy 48.071333 -292.499903)
			(xy 48.079646 -292.549725) (xy 48.080168 -292.57498) (xy 48.079622 -292.600555) (xy 48.071062 -292.650984)
			(xy 48.06315 -292.67531) (xy 48.059086 -292.686994) (xy 48.062642 -292.711124) (xy 48.11776 -292.788848)
			(xy 48.125381 -292.798347) (xy 48.147003 -292.809475) (xy 48.159162 -292.810184) (xy 48.340518 -292.810184)
			(xy 48.352679 -292.809489) (xy 48.374299 -292.79835) (xy 48.38192 -292.788848) (xy 48.437292 -292.711124)
			(xy 48.440594 -292.686994) (xy 48.43653 -292.675056) (xy 48.428592 -292.650736) (xy 48.420037 -292.600303)
			(xy 48.419512 -292.574726) (xy 48.419956 -292.550732) (xy 48.42746 -292.503335) (xy 48.442286 -292.457695)
			(xy 48.464071 -292.414936) (xy 48.492276 -292.376113) (xy 48.526208 -292.34218) (xy 48.565031 -292.313974)
			(xy 48.607789 -292.292189) (xy 48.653429 -292.277361) (xy 48.700826 -292.269857) (xy 48.72482 -292.269418)
			(xy 48.743818 -292.269708) (xy 48.781519 -292.274424) (xy 48.800004 -292.278816) (xy 48.811434 -292.281864)
			(xy 48.834294 -292.277038) (xy 48.906938 -292.220396) (xy 48.915775 -292.212808) (xy 48.925981 -292.191899)
			(xy 48.926496 -292.180264) (xy 48.926496 -292.019228) (xy 48.925925 -292.007605) (xy 48.91574 -291.986708)
			(xy 48.906938 -291.979096) (xy 48.834294 -291.922454) (xy 48.811434 -291.917628) (xy 48.800004 -291.920676)
			(xy 48.78152 -291.925072) (xy 48.743818 -291.92978) (xy 48.72482 -291.930074) (xy 48.699564 -291.929583)
			(xy 48.649741 -291.921272) (xy 48.601965 -291.904873) (xy 48.55754 -291.880834) (xy 48.517677 -291.849811)
			(xy 48.483465 -291.812649) (xy 48.455837 -291.770363) (xy 48.435546 -291.724106) (xy 48.423145 -291.675139)
			(xy 48.418974 -291.6248) (xy 48.423145 -291.574461) (xy 48.435546 -291.525494) (xy 48.455837 -291.479237)
			(xy 48.483465 -291.436951) (xy 48.517677 -291.399789) (xy 48.55754 -291.368766) (xy 48.601965 -291.344727)
			(xy 48.649741 -291.328328) (xy 48.699564 -291.320017) (xy 48.72482 -291.319458) (xy 48.743817 -291.319748)
			(xy 48.781519 -291.324465) (xy 48.800004 -291.328856) (xy 48.811434 -291.331904) (xy 48.834294 -291.327078)
			(xy 48.906938 -291.270436) (xy 48.915765 -291.262844) (xy 48.925946 -291.241935) (xy 48.926496 -291.230304)
			(xy 48.926496 -291.069268) (xy 48.925933 -291.057641) (xy 48.915758 -291.036731) (xy 48.906938 -291.029136)
			(xy 48.834294 -290.972494) (xy 48.811434 -290.967668) (xy 48.800004 -290.970716) (xy 48.78152 -290.975111)
			(xy 48.743818 -290.979819) (xy 48.72482 -290.980114) (xy 48.699561 -290.979623) (xy 48.649731 -290.971311)
			(xy 48.601949 -290.95491) (xy 48.557518 -290.930868) (xy 48.51765 -290.89984) (xy 48.483434 -290.862673)
			(xy 48.455802 -290.820382) (xy 48.435508 -290.774119) (xy 48.423106 -290.725146) (xy 48.418934 -290.6748)
			(xy 48.423106 -290.624454) (xy 48.435508 -290.575481) (xy 48.455802 -290.529218) (xy 48.483434 -290.486927)
			(xy 48.51765 -290.44976) (xy 48.557518 -290.418732) (xy 48.601949 -290.39469) (xy 48.649731 -290.378289)
			(xy 48.699561 -290.369977) (xy 48.72482 -290.369498) (xy 48.743817 -290.369788) (xy 48.781518 -290.374505)
			(xy 48.800004 -290.378896) (xy 48.811434 -290.381944) (xy 48.834294 -290.377118) (xy 48.906938 -290.320476)
			(xy 48.915772 -290.312887) (xy 48.925969 -290.291977) (xy 48.926496 -290.280344) (xy 48.926496 -290.119308)
			(xy 48.925921 -290.107687) (xy 48.915731 -290.086797) (xy 48.906938 -290.079176) (xy 48.834294 -290.022534)
			(xy 48.811434 -290.017708) (xy 48.800004 -290.020756) (xy 48.78152 -290.025152) (xy 48.743818 -290.029861)
			(xy 48.72482 -290.030154) (xy 48.699557 -290.029663) (xy 48.649721 -290.021349) (xy 48.601932 -290.004946)
			(xy 48.557496 -289.980901) (xy 48.517623 -289.94987) (xy 48.483402 -289.912698) (xy 48.455767 -289.870401)
			(xy 48.43547 -289.824132) (xy 48.423067 -289.775153) (xy 48.418894 -289.7248) (xy 48.423067 -289.674447)
			(xy 48.43547 -289.625468) (xy 48.455767 -289.579199) (xy 48.483402 -289.536902) (xy 48.517623 -289.49973)
			(xy 48.557496 -289.468699) (xy 48.601932 -289.444654) (xy 48.649721 -289.42825) (xy 48.699557 -289.419937)
			(xy 48.72482 -289.419538) (xy 48.743817 -289.419828) (xy 48.781519 -289.424544) (xy 48.800004 -289.428936)
			(xy 48.811434 -289.431984) (xy 48.834294 -289.427158) (xy 48.906938 -289.370516) (xy 48.915762 -289.362923)
			(xy 48.925935 -289.342013) (xy 48.926496 -289.330384) (xy 48.926496 -289.169348) (xy 48.925929 -289.157723)
			(xy 48.915749 -289.136819) (xy 48.906938 -289.129216) (xy 48.834294 -289.072574) (xy 48.811434 -289.067748)
			(xy 48.800004 -289.070796) (xy 48.78152 -289.075192) (xy 48.743818 -289.0799) (xy 48.72482 -289.080194)
			(xy 48.699562 -289.079703) (xy 48.649736 -289.071391) (xy 48.601957 -289.054992) (xy 48.557529 -289.030951)
			(xy 48.517664 -288.999925) (xy 48.48345 -288.962761) (xy 48.455819 -288.920472) (xy 48.435527 -288.874212)
			(xy 48.423126 -288.825243) (xy 48.418954 -288.7749) (xy 48.423126 -288.724557) (xy 48.435527 -288.675588)
			(xy 48.455819 -288.629328) (xy 48.48345 -288.587039) (xy 48.517664 -288.549875) (xy 48.557529 -288.518849)
			(xy 48.601957 -288.494808) (xy 48.649736 -288.478409) (xy 48.699562 -288.470097) (xy 48.72482 -288.469578)
			(xy 48.743817 -288.469868) (xy 48.781519 -288.474585) (xy 48.800004 -288.478976) (xy 48.811434 -288.482024)
			(xy 48.834294 -288.477198) (xy 48.906938 -288.420556) (xy 48.915768 -288.412966) (xy 48.925958 -288.392056)
			(xy 48.926496 -288.380424) (xy 48.926496 -288.219388) (xy 48.925917 -288.20777) (xy 48.915722 -288.186886)
			(xy 48.906938 -288.179256) (xy 48.834294 -288.122614) (xy 48.811434 -288.117788) (xy 48.800004 -288.120836)
			(xy 48.78152 -288.125231) (xy 48.743818 -288.129939) (xy 48.72482 -288.130234) (xy 48.699559 -288.129743)
			(xy 48.649726 -288.12143) (xy 48.601941 -288.105028) (xy 48.557507 -288.080984) (xy 48.517637 -288.049955)
			(xy 48.483418 -288.012786) (xy 48.455784 -287.970491) (xy 48.435489 -287.924225) (xy 48.423086 -287.875249)
			(xy 48.418914 -287.8249) (xy 48.423086 -287.774551) (xy 48.435489 -287.725575) (xy 48.455784 -287.679309)
			(xy 48.483418 -287.637014) (xy 48.517637 -287.599845) (xy 48.557507 -287.568816) (xy 48.601941 -287.544772)
			(xy 48.649726 -287.52837) (xy 48.699559 -287.520057) (xy 48.72482 -287.519618) (xy 48.743818 -287.519908)
			(xy 48.781519 -287.524624) (xy 48.800004 -287.529016) (xy 48.811434 -287.532064) (xy 48.834294 -287.527238)
			(xy 48.906938 -287.470596) (xy 48.915775 -287.463008) (xy 48.925981 -287.442099) (xy 48.926496 -287.430464)
			(xy 48.926496 -287.269428) (xy 48.925925 -287.257805) (xy 48.91574 -287.236908) (xy 48.906938 -287.229296)
			(xy 48.834294 -287.172654) (xy 48.811434 -287.167828) (xy 48.800004 -287.170876) (xy 48.78152 -287.175272)
			(xy 48.743818 -287.17998) (xy 48.72482 -287.180274) (xy 48.699564 -287.179783) (xy 48.649741 -287.171472)
			(xy 48.601965 -287.155073) (xy 48.55754 -287.131034) (xy 48.517677 -287.100011) (xy 48.483465 -287.062849)
			(xy 48.455837 -287.020563) (xy 48.435546 -286.974306) (xy 48.423145 -286.925339) (xy 48.418974 -286.875)
			(xy 48.423145 -286.824661) (xy 48.435546 -286.775694) (xy 48.455837 -286.729437) (xy 48.483465 -286.687151)
			(xy 48.517677 -286.649989) (xy 48.55754 -286.618966) (xy 48.601965 -286.594927) (xy 48.649741 -286.578528)
			(xy 48.699564 -286.570217) (xy 48.72482 -286.569658) (xy 48.743817 -286.569948) (xy 48.781519 -286.574665)
			(xy 48.800004 -286.579056) (xy 48.811434 -286.582104) (xy 48.834294 -286.577278) (xy 48.906938 -286.520636)
			(xy 48.915765 -286.513044) (xy 48.925946 -286.492135) (xy 48.926496 -286.480504) (xy 48.926496 -286.319214)
			(xy 48.925922 -286.307593) (xy 48.915733 -286.2867) (xy 48.906938 -286.279082) (xy 48.834294 -286.22244)
			(xy 48.811434 -286.217614) (xy 48.800004 -286.220662) (xy 48.78152 -286.225058) (xy 48.743818 -286.229767)
			(xy 48.72482 -286.23006) (xy 48.699565 -286.229569) (xy 48.649744 -286.221258) (xy 48.60197 -286.20486)
			(xy 48.557547 -286.180822) (xy 48.517687 -286.1498) (xy 48.483477 -286.11264) (xy 48.455849 -286.070356)
			(xy 48.435559 -286.024101) (xy 48.423159 -285.975137) (xy 48.418988 -285.9248) (xy 48.423159 -285.874463)
			(xy 48.435559 -285.825499) (xy 48.455849 -285.779244) (xy 48.483477 -285.73696) (xy 48.517687 -285.6998)
			(xy 48.557547 -285.668778) (xy 48.60197 -285.64474) (xy 48.649744 -285.628342) (xy 48.699565 -285.620031)
			(xy 48.72482 -285.619444) (xy 48.743817 -285.619734) (xy 48.781519 -285.624451) (xy 48.800004 -285.628842)
			(xy 48.811434 -285.63189) (xy 48.834294 -285.627064) (xy 48.906938 -285.570422) (xy 48.915763 -285.562829)
			(xy 48.925938 -285.54192) (xy 48.926496 -285.53029) (xy 48.926496 -285.369254) (xy 48.92593 -285.357629)
			(xy 48.915752 -285.336723) (xy 48.906938 -285.329122) (xy 48.834294 -285.27248) (xy 48.811434 -285.267654)
			(xy 48.800004 -285.270702) (xy 48.78152 -285.275098) (xy 48.743818 -285.279806) (xy 48.72482 -285.2801)
			(xy 48.699562 -285.279609) (xy 48.649734 -285.271297) (xy 48.601954 -285.254897) (xy 48.557525 -285.230856)
			(xy 48.51766 -285.19983) (xy 48.483445 -285.162665) (xy 48.455814 -285.120375) (xy 48.435521 -285.074114)
			(xy 48.42312 -285.025144) (xy 48.418948 -284.9748) (xy 48.42312 -284.924456) (xy 48.435521 -284.875486)
			(xy 48.455814 -284.829225) (xy 48.483445 -284.786935) (xy 48.51766 -284.74977) (xy 48.557525 -284.718744)
			(xy 48.601954 -284.694703) (xy 48.649734 -284.678303) (xy 48.699562 -284.669991) (xy 48.72482 -284.669484)
			(xy 48.743817 -284.669774) (xy 48.781518 -284.674491) (xy 48.800004 -284.678882) (xy 48.811434 -284.68193)
			(xy 48.834294 -284.677104) (xy 48.906938 -284.620462) (xy 48.915769 -284.612872) (xy 48.925961 -284.591962)
			(xy 48.926496 -284.58033) (xy 48.926496 -284.419294) (xy 48.925918 -284.407675) (xy 48.915724 -284.386789)
			(xy 48.906938 -284.379162) (xy 48.834294 -284.32252) (xy 48.811434 -284.317694) (xy 48.800004 -284.320742)
			(xy 48.78152 -284.325137) (xy 48.743818 -284.329844) (xy 48.72482 -284.33014) (xy 48.699559 -284.329649)
			(xy 48.649724 -284.321336) (xy 48.601938 -284.304934) (xy 48.557504 -284.280889) (xy 48.517633 -284.249859)
			(xy 48.483413 -284.212689) (xy 48.455779 -284.170394) (xy 48.435483 -284.124127) (xy 48.42308 -284.07515)
			(xy 48.418908 -284.0248) (xy 48.42308 -283.97445) (xy 48.435483 -283.925473) (xy 48.455779 -283.879206)
			(xy 48.483413 -283.836911) (xy 48.517633 -283.799741) (xy 48.557504 -283.768711) (xy 48.601938 -283.744666)
			(xy 48.649724 -283.728264) (xy 48.699559 -283.719951) (xy 48.72482 -283.719524) (xy 48.743818 -283.719814)
			(xy 48.781519 -283.72453) (xy 48.800004 -283.728922) (xy 48.811434 -283.73197) (xy 48.834294 -283.727144)
			(xy 48.906938 -283.670502) (xy 48.915759 -283.662908) (xy 48.925927 -283.641998) (xy 48.926496 -283.63037)
			(xy 48.926496 -283.469334) (xy 48.925926 -283.457711) (xy 48.915742 -283.436812) (xy 48.906938 -283.429202)
			(xy 48.834294 -283.37256) (xy 48.811434 -283.367734) (xy 48.800004 -283.370782) (xy 48.78152 -283.375178)
			(xy 48.743818 -283.379886) (xy 48.72482 -283.38018) (xy 48.699564 -283.379689) (xy 48.649739 -283.371378)
			(xy 48.601962 -283.354979) (xy 48.557536 -283.330939) (xy 48.517673 -283.299915) (xy 48.483461 -283.262753)
			(xy 48.455832 -283.220466) (xy 48.43554 -283.174207) (xy 48.423139 -283.12524) (xy 48.418968 -283.0749)
			(xy 48.423139 -283.02456) (xy 48.43554 -282.975593) (xy 48.455832 -282.929334) (xy 48.483461 -282.887047)
			(xy 48.517673 -282.849885) (xy 48.557536 -282.818861) (xy 48.601962 -282.794821) (xy 48.649739 -282.778422)
			(xy 48.699564 -282.770111) (xy 48.72482 -282.769564) (xy 48.743817 -282.769854) (xy 48.781519 -282.774571)
			(xy 48.800004 -282.778962) (xy 48.811434 -282.78201) (xy 48.834294 -282.777184) (xy 48.906938 -282.720542)
			(xy 48.915766 -282.712951) (xy 48.92595 -282.692041) (xy 48.926496 -282.68041) (xy 48.926496 -282.092146)
			(xy 48.926012 -282.082183) (xy 48.918427 -282.063756) (xy 48.911764 -282.056332) (xy 48.639984 -281.784552)
			(xy 48.632587 -281.777702) (xy 48.613989 -281.769965) (xy 48.603916 -281.769566) (xy 48.54829 -281.769566)
			(xy 48.524668 -281.783536) (xy 48.51781 -281.795982) (xy 48.505321 -281.817856) (xy 48.474311 -281.857543)
			(xy 48.437203 -281.891597) (xy 48.395005 -281.919093) (xy 48.348865 -281.939285) (xy 48.300034 -281.951624)
			(xy 48.24984 -281.955774) (xy 48.199646 -281.951624) (xy 48.150815 -281.939285) (xy 48.104675 -281.919093)
			(xy 48.062477 -281.891597) (xy 48.025369 -281.857543) (xy 47.994359 -281.817856) (xy 47.98187 -281.795982)
			(xy 47.975012 -281.783536) (xy 47.95139 -281.769566) (xy 47.59833 -281.769566) (xy 47.574708 -281.783536)
			(xy 47.56785 -281.795982) (xy 47.555361 -281.817856) (xy 47.524351 -281.857543) (xy 47.487243 -281.891597)
			(xy 47.445045 -281.919093) (xy 47.398905 -281.939285) (xy 47.350074 -281.951624) (xy 47.29988 -281.955774)
			(xy 47.249686 -281.951624) (xy 47.200855 -281.939285) (xy 47.154715 -281.919093) (xy 47.112517 -281.891597)
			(xy 47.075409 -281.857543) (xy 47.044399 -281.817856) (xy 47.03191 -281.795982) (xy 47.025052 -281.783536)
			(xy 47.00143 -281.769566) (xy 46.64837 -281.769566) (xy 46.624748 -281.783536) (xy 46.61789 -281.795982)
			(xy 46.605401 -281.817856) (xy 46.574391 -281.857543) (xy 46.537283 -281.891597) (xy 46.495085 -281.919093)
			(xy 46.448945 -281.939285) (xy 46.400114 -281.951624) (xy 46.34992 -281.955774) (xy 46.299726 -281.951624)
			(xy 46.250895 -281.939285) (xy 46.204755 -281.919093) (xy 46.162557 -281.891597) (xy 46.125449 -281.857543)
			(xy 46.094439 -281.817856) (xy 46.08195 -281.795982) (xy 46.075092 -281.783536) (xy 46.05147 -281.769566)
			(xy 45.69841 -281.769566) (xy 45.674788 -281.783536) (xy 45.66793 -281.795982) (xy 45.655441 -281.817856)
			(xy 45.624431 -281.857543) (xy 45.587323 -281.891597) (xy 45.545125 -281.919093) (xy 45.498985 -281.939285)
			(xy 45.450154 -281.951624) (xy 45.39996 -281.955774) (xy 45.349766 -281.951624) (xy 45.300935 -281.939285)
			(xy 45.254795 -281.919093) (xy 45.212597 -281.891597) (xy 45.175489 -281.857543) (xy 45.144479 -281.817856)
			(xy 45.13199 -281.795982) (xy 45.125132 -281.783536) (xy 45.10151 -281.769566) (xy 44.748196 -281.769566)
			(xy 44.724574 -281.783536) (xy 44.717716 -281.795982) (xy 44.706148 -281.816305) (xy 44.677791 -281.853487)
			(xy 44.64409 -281.885905) (xy 44.605837 -281.912799) (xy 44.563926 -281.933538) (xy 44.519341 -281.947638)
			(xy 44.473127 -281.954767) (xy 44.449746 -281.95524) (xy 44.435563 -281.955056) (xy 44.407323 -281.952387)
			(xy 44.393358 -281.949906) (xy 44.380912 -281.94762) (xy 44.35729 -281.954986) (xy 44.27982 -282.032456)
			(xy 44.272454 -282.056078) (xy 44.27474 -282.068524) (xy 44.277225 -282.082489) (xy 44.279896 -282.110729)
			(xy 44.280074 -282.124912) (xy 44.279552 -282.150167) (xy 44.271239 -282.199989) (xy 44.254838 -282.247763)
			(xy 44.230797 -282.292186) (xy 44.199773 -282.332046) (xy 44.162611 -282.366256) (xy 44.120325 -282.393882)
			(xy 44.074069 -282.414172) (xy 44.025104 -282.426572) (xy 43.974766 -282.430743) (xy 43.924428 -282.426572)
			(xy 43.875463 -282.414172) (xy 43.829207 -282.393882) (xy 43.786921 -282.366256) (xy 43.749759 -282.332046)
			(xy 43.718735 -282.292186) (xy 43.694694 -282.247763) (xy 43.678293 -282.199989) (xy 43.66998 -282.150167)
			(xy 43.669458 -282.124912) (xy 43.669964 -282.099187) (xy 43.678541 -282.048458) (xy 43.695503 -281.999886)
			(xy 43.720371 -281.954846) (xy 43.736006 -281.934412) (xy 43.74515 -281.922982) (xy 43.748452 -281.894026)
			(xy 43.702478 -281.798268) (xy 43.697979 -281.789865) (xy 43.684009 -281.776919) (xy 43.666281 -281.769956)
			(xy 43.656758 -281.769566) (xy 43.342814 -281.769566) (xy 43.33329 -281.769959) (xy 43.315558 -281.776913)
			(xy 43.301591 -281.789863) (xy 43.297094 -281.798268) (xy 43.25112 -281.894026) (xy 43.254422 -281.922982)
			(xy 43.263566 -281.934412) (xy 43.27918 -281.954861) (xy 43.304046 -281.999899) (xy 43.321017 -282.048466)
			(xy 43.329615 -282.099189) (xy 43.330114 -282.124912) (xy 43.329592 -282.150167) (xy 43.321279 -282.199989)
			(xy 43.304878 -282.247763) (xy 43.280837 -282.292186) (xy 43.249813 -282.332046) (xy 43.212651 -282.366256)
			(xy 43.170365 -282.393882) (xy 43.124109 -282.414172) (xy 43.075144 -282.426572) (xy 43.024806 -282.430743)
			(xy 42.974468 -282.426572) (xy 42.925503 -282.414172) (xy 42.879247 -282.393882) (xy 42.836961 -282.366256)
			(xy 42.799799 -282.332046) (xy 42.768775 -282.292186) (xy 42.744734 -282.247763) (xy 42.728333 -282.199989)
			(xy 42.72002 -282.150167) (xy 42.719498 -282.124912) (xy 42.720005 -282.099187) (xy 42.728582 -282.048459)
			(xy 42.745546 -281.999888) (xy 42.770417 -281.95485) (xy 42.786046 -281.934412) (xy 42.79519 -281.922982)
			(xy 42.798492 -281.894026) (xy 42.752518 -281.798268) (xy 42.748021 -281.789861) (xy 42.734053 -281.776904)
			(xy 42.716324 -281.769927) (xy 42.706798 -281.769566) (xy 42.392854 -281.769566) (xy 42.383326 -281.769953)
			(xy 42.365582 -281.776897) (xy 42.351603 -281.789846) (xy 42.347134 -281.798268) (xy 42.30116 -281.894026)
			(xy 42.304462 -281.922982) (xy 42.313606 -281.934412) (xy 42.329223 -281.95486) (xy 42.354094 -281.999897)
			(xy 42.371069 -282.048464) (xy 42.379668 -282.099188) (xy 42.380154 -282.124912) (xy 42.379632 -282.150167)
			(xy 42.371319 -282.199989) (xy 42.354918 -282.247763) (xy 42.330877 -282.292186) (xy 42.299853 -282.332046)
			(xy 42.262691 -282.366256) (xy 42.220405 -282.393882) (xy 42.174149 -282.414172) (xy 42.125184 -282.426572)
			(xy 42.074846 -282.430743) (xy 42.024508 -282.426572) (xy 41.975543 -282.414172) (xy 41.929287 -282.393882)
			(xy 41.887001 -282.366256) (xy 41.849839 -282.332046) (xy 41.818815 -282.292186) (xy 41.794774 -282.247763)
			(xy 41.778373 -282.199989) (xy 41.77006 -282.150167) (xy 41.769538 -282.124912) (xy 41.770044 -282.099187)
			(xy 41.77862 -282.048458) (xy 41.795582 -281.999885) (xy 41.820448 -281.954844) (xy 41.836086 -281.934412)
			(xy 41.84523 -281.922982) (xy 41.848532 -281.894026) (xy 41.802558 -281.798268) (xy 41.798058 -281.789867)
			(xy 41.784087 -281.776927) (xy 41.766359 -281.769971) (xy 41.756838 -281.769566) (xy 41.442894 -281.769566)
			(xy 41.433372 -281.769963) (xy 41.415645 -281.77692) (xy 41.401684 -281.789872) (xy 41.397174 -281.798268)
			(xy 41.3512 -281.894026) (xy 41.354502 -281.922982) (xy 41.363646 -281.934412) (xy 41.379261 -281.954861)
			(xy 41.404128 -281.999898) (xy 41.421101 -282.048465) (xy 41.4297 -282.099188) (xy 41.430194 -282.124912)
			(xy 41.429672 -282.150167) (xy 41.421359 -282.199989) (xy 41.404958 -282.247763) (xy 41.380917 -282.292186)
			(xy 41.349893 -282.332046) (xy 41.312731 -282.366256) (xy 41.270445 -282.393882) (xy 41.224189 -282.414172)
			(xy 41.175224 -282.426572) (xy 41.124886 -282.430743) (xy 41.074548 -282.426572) (xy 41.025583 -282.414172)
			(xy 40.979327 -282.393882) (xy 40.937041 -282.366256) (xy 40.899879 -282.332046) (xy 40.868855 -282.292186)
			(xy 40.844814 -282.247763) (xy 40.828413 -282.199989) (xy 40.8201 -282.150167) (xy 40.819578 -282.124912)
			(xy 40.820085 -282.099187) (xy 40.828661 -282.048459) (xy 40.845625 -281.999887) (xy 40.870494 -281.954848)
			(xy 40.886126 -281.934412) (xy 40.89527 -281.922982) (xy 40.898572 -281.894026) (xy 40.852598 -281.798268)
			(xy 40.8481 -281.789863) (xy 40.834131 -281.776911) (xy 40.816402 -281.769942) (xy 40.806878 -281.769566)
			(xy 40.492934 -281.769566) (xy 40.483408 -281.769956) (xy 40.46567 -281.776905) (xy 40.451697 -281.789855)
			(xy 40.447214 -281.798268) (xy 40.40124 -281.894026) (xy 40.404542 -281.922982) (xy 40.413686 -281.934412)
			(xy 40.429299 -281.954861) (xy 40.454163 -281.9999) (xy 40.471134 -282.048466) (xy 40.479731 -282.099189)
			(xy 40.480234 -282.124912) (xy 40.479712 -282.150167) (xy 40.471399 -282.199989) (xy 40.454998 -282.247763)
			(xy 40.430957 -282.292186) (xy 40.399933 -282.332046) (xy 40.362771 -282.366256) (xy 40.320485 -282.393882)
			(xy 40.274229 -282.414172) (xy 40.225264 -282.426572) (xy 40.174926 -282.430743) (xy 40.124588 -282.426572)
			(xy 40.075623 -282.414172) (xy 40.029367 -282.393882) (xy 39.987081 -282.366256) (xy 39.949919 -282.332046)
			(xy 39.918895 -282.292186) (xy 39.894854 -282.247763) (xy 39.878453 -282.199989) (xy 39.87014 -282.150167)
			(xy 39.869618 -282.124912) (xy 39.870125 -282.099187) (xy 39.878702 -282.048459) (xy 39.895668 -281.999889)
			(xy 39.920539 -281.954852) (xy 39.936166 -281.934412) (xy 39.94531 -281.922982) (xy 39.948612 -281.894026)
			(xy 39.902638 -281.798268) (xy 39.898137 -281.78987) (xy 39.884165 -281.776935) (xy 39.866438 -281.769986)
			(xy 39.856918 -281.769566) (xy 39.542974 -281.769566) (xy 39.533454 -281.769966) (xy 39.515733 -281.776928)
			(xy 39.501778 -281.78988) (xy 39.497254 -281.798268) (xy 39.45128 -281.894026) (xy 39.454582 -281.922982)
			(xy 39.463726 -281.934412) (xy 39.479342 -281.95486) (xy 39.504211 -281.999898) (xy 39.521185 -282.048464)
			(xy 39.529784 -282.099188) (xy 39.530274 -282.124912) (xy 39.529752 -282.150167) (xy 39.521439 -282.199989)
			(xy 39.505038 -282.247763) (xy 39.480997 -282.292186) (xy 39.449973 -282.332046) (xy 39.412811 -282.366256)
			(xy 39.370525 -282.393882) (xy 39.324269 -282.414172) (xy 39.275304 -282.426572) (xy 39.224966 -282.430743)
			(xy 39.174628 -282.426572) (xy 39.125663 -282.414172) (xy 39.079407 -282.393882) (xy 39.037121 -282.366256)
			(xy 38.999959 -282.332046) (xy 38.968935 -282.292186) (xy 38.944894 -282.247763) (xy 38.928493 -282.199989)
			(xy 38.92018 -282.150167) (xy 38.919658 -282.124912) (xy 38.920164 -282.099187) (xy 38.928741 -282.048458)
			(xy 38.945703 -281.999886) (xy 38.970571 -281.954846) (xy 38.986206 -281.934412) (xy 38.99535 -281.922982)
			(xy 38.998652 -281.894026) (xy 38.952678 -281.798268) (xy 38.948179 -281.789865) (xy 38.934209 -281.776919)
			(xy 38.916481 -281.769956) (xy 38.906958 -281.769566) (xy 38.593014 -281.769566) (xy 38.58349 -281.769959)
			(xy 38.565758 -281.776913) (xy 38.551791 -281.789863) (xy 38.547294 -281.798268) (xy 38.50132 -281.894026)
			(xy 38.504622 -281.922982) (xy 38.513766 -281.934412) (xy 38.52938 -281.954861) (xy 38.554246 -281.999899)
			(xy 38.571217 -282.048466) (xy 38.579815 -282.099189) (xy 38.580314 -282.124912) (xy 38.579792 -282.150167)
			(xy 38.571479 -282.199989) (xy 38.555078 -282.247763) (xy 38.531037 -282.292186) (xy 38.500013 -282.332046)
			(xy 38.462851 -282.366256) (xy 38.420565 -282.393882) (xy 38.374309 -282.414172) (xy 38.325344 -282.426572)
			(xy 38.275006 -282.430743) (xy 38.224668 -282.426572) (xy 38.175703 -282.414172) (xy 38.129447 -282.393882)
			(xy 38.087161 -282.366256) (xy 38.049999 -282.332046) (xy 38.018975 -282.292186) (xy 37.994934 -282.247763)
			(xy 37.978533 -282.199989) (xy 37.97022 -282.150167) (xy 37.969698 -282.124912) (xy 37.970205 -282.099187)
			(xy 37.978782 -282.048459) (xy 37.995746 -281.999888) (xy 38.020617 -281.95485) (xy 38.036246 -281.934412)
			(xy 38.04539 -281.922982) (xy 38.048692 -281.894026) (xy 38.002718 -281.798268) (xy 37.998221 -281.789861)
			(xy 37.984253 -281.776904) (xy 37.966524 -281.769927) (xy 37.956998 -281.769566) (xy 37.6428 -281.769566)
			(xy 37.633278 -281.769962) (xy 37.615549 -281.776918) (xy 37.601586 -281.789869) (xy 37.59708 -281.798268)
			(xy 37.551106 -281.894026) (xy 37.554408 -281.922982) (xy 37.563552 -281.934412) (xy 37.579167 -281.954861)
			(xy 37.604034 -281.999899) (xy 37.621006 -282.048465) (xy 37.629604 -282.099188) (xy 37.6301 -282.124912)
			(xy 37.629578 -282.150167) (xy 37.621265 -282.199989) (xy 37.604864 -282.247763) (xy 37.580823 -282.292186)
			(xy 37.549799 -282.332046) (xy 37.512637 -282.366256) (xy 37.470351 -282.393882) (xy 37.424095 -282.414172)
			(xy 37.37513 -282.426572) (xy 37.324792 -282.430743) (xy 37.274454 -282.426572) (xy 37.225489 -282.414172)
			(xy 37.179233 -282.393882) (xy 37.136947 -282.366256) (xy 37.099785 -282.332046) (xy 37.068761 -282.292186)
			(xy 37.04472 -282.247763) (xy 37.028319 -282.199989) (xy 37.020006 -282.150167) (xy 37.019484 -282.124912)
			(xy 37.019991 -282.099187) (xy 37.028568 -282.048459) (xy 37.045531 -281.999887) (xy 37.070401 -281.954849)
			(xy 37.086032 -281.934412) (xy 37.095176 -281.922982) (xy 37.098478 -281.894026) (xy 37.052504 -281.798268)
			(xy 37.048007 -281.789862) (xy 37.034038 -281.776909) (xy 37.016309 -281.769937) (xy 37.006784 -281.769566)
			(xy 36.69284 -281.769566) (xy 36.683314 -281.769955) (xy 36.665574 -281.776903) (xy 36.651599 -281.789852)
			(xy 36.64712 -281.798268) (xy 36.601146 -281.894026) (xy 36.604448 -281.922982) (xy 36.613592 -281.934412)
			(xy 36.629209 -281.95486) (xy 36.654081 -281.999897) (xy 36.671057 -282.048463) (xy 36.679657 -282.099188)
			(xy 36.68014 -282.124912) (xy 36.679618 -282.150167) (xy 36.671305 -282.199989) (xy 36.654904 -282.247763)
			(xy 36.630863 -282.292186) (xy 36.599839 -282.332046) (xy 36.562677 -282.366256) (xy 36.520391 -282.393882)
			(xy 36.474135 -282.414172) (xy 36.42517 -282.426572) (xy 36.374832 -282.430743) (xy 36.324494 -282.426572)
			(xy 36.275529 -282.414172) (xy 36.229273 -282.393882) (xy 36.186987 -282.366256) (xy 36.149825 -282.332046)
			(xy 36.118801 -282.292186) (xy 36.09476 -282.247763) (xy 36.078359 -282.199989) (xy 36.070046 -282.150167)
			(xy 36.069524 -282.124912) (xy 36.070031 -282.099187) (xy 36.078609 -282.04846) (xy 36.095574 -281.999889)
			(xy 36.120446 -281.954853) (xy 36.136072 -281.934412) (xy 36.145216 -281.922982) (xy 36.148518 -281.894026)
			(xy 36.102544 -281.798268) (xy 36.098044 -281.789869) (xy 36.084072 -281.776932) (xy 36.066345 -281.769981)
			(xy 36.056824 -281.769566) (xy 31.692596 -281.769566) (xy 31.682528 -281.769992) (xy 31.66393 -281.777714)
			(xy 31.656528 -281.784552) (xy 31.284418 -282.156662) (xy 31.27758 -282.164063) (xy 31.269865 -282.182661)
			(xy 31.269432 -282.19273) (xy 31.269432 -282.809188) (xy 31.269901 -282.81946) (xy 31.277951 -282.838359)
			(xy 31.292766 -282.85259) (xy 31.302198 -282.856686) (xy 31.405576 -282.89631) (xy 31.436056 -282.888944)
			(xy 31.446724 -282.877006) (xy 31.464891 -282.857386) (xy 31.50577 -282.822919) (xy 31.551063 -282.794499)
			(xy 31.599881 -282.772683) (xy 31.651267 -282.757899) (xy 31.704215 -282.750438) (xy 31.73095 -282.750006)
			(xy 31.758204 -282.750466) (xy 31.812159 -282.758217) (xy 31.86446 -282.773568) (xy 31.914045 -282.796207)
			(xy 31.959903 -282.825672) (xy 32.0011 -282.861365) (xy 32.036798 -282.902557) (xy 32.066269 -282.948411)
			(xy 32.088915 -282.997993) (xy 32.104273 -283.050293) (xy 32.107807 -283.074872) (xy 36.069028 -283.074872)
			(xy 36.072988 -283.025818) (xy 36.084765 -282.978034) (xy 36.104056 -282.932758) (xy 36.130359 -282.891162)
			(xy 36.162994 -282.854325) (xy 36.201115 -282.8232) (xy 36.243736 -282.798593) (xy 36.289752 -282.781141)
			(xy 36.337971 -282.771297) (xy 36.387146 -282.769316) (xy 36.436001 -282.775248) (xy 36.483272 -282.78894)
			(xy 36.527734 -282.810038) (xy 36.568237 -282.837994) (xy 36.60373 -282.872086) (xy 36.633295 -282.91143)
			(xy 36.656166 -282.955007) (xy 36.67175 -283.001688) (xy 36.679645 -283.050265) (xy 36.68014 -283.074872)
			(xy 37.018988 -283.074872) (xy 37.022948 -283.025818) (xy 37.034725 -282.978034) (xy 37.054016 -282.932758)
			(xy 37.080319 -282.891162) (xy 37.112954 -282.854325) (xy 37.151075 -282.8232) (xy 37.193696 -282.798593)
			(xy 37.239712 -282.781141) (xy 37.287931 -282.771297) (xy 37.337106 -282.769316) (xy 37.385961 -282.775248)
			(xy 37.433232 -282.78894) (xy 37.477694 -282.810038) (xy 37.518197 -282.837994) (xy 37.55369 -282.872086)
			(xy 37.583255 -282.91143) (xy 37.606126 -282.955007) (xy 37.62171 -283.001688) (xy 37.629605 -283.050265)
			(xy 37.6301 -283.074872) (xy 37.969202 -283.074872) (xy 37.973162 -283.025818) (xy 37.984939 -282.978034)
			(xy 38.00423 -282.932758) (xy 38.030533 -282.891162) (xy 38.063168 -282.854325) (xy 38.101289 -282.8232)
			(xy 38.14391 -282.798593) (xy 38.189926 -282.781141) (xy 38.238145 -282.771297) (xy 38.28732 -282.769316)
			(xy 38.336175 -282.775248) (xy 38.383446 -282.78894) (xy 38.427908 -282.810038) (xy 38.468411 -282.837994)
			(xy 38.503904 -282.872086) (xy 38.533469 -282.91143) (xy 38.55634 -282.955007) (xy 38.571924 -283.001688)
			(xy 38.579819 -283.050265) (xy 38.580314 -283.074872) (xy 38.919162 -283.074872) (xy 38.923122 -283.025818)
			(xy 38.934899 -282.978034) (xy 38.95419 -282.932758) (xy 38.980493 -282.891162) (xy 39.013128 -282.854325)
			(xy 39.051249 -282.8232) (xy 39.09387 -282.798593) (xy 39.139886 -282.781141) (xy 39.188105 -282.771297)
			(xy 39.23728 -282.769316) (xy 39.286135 -282.775248) (xy 39.333406 -282.78894) (xy 39.377868 -282.810038)
			(xy 39.418371 -282.837994) (xy 39.453864 -282.872086) (xy 39.483429 -282.91143) (xy 39.5063 -282.955007)
			(xy 39.521884 -283.001688) (xy 39.529779 -283.050265) (xy 39.530274 -283.074872) (xy 39.869122 -283.074872)
			(xy 39.873082 -283.025818) (xy 39.884859 -282.978034) (xy 39.90415 -282.932758) (xy 39.930453 -282.891162)
			(xy 39.963088 -282.854325) (xy 40.001209 -282.8232) (xy 40.04383 -282.798593) (xy 40.089846 -282.781141)
			(xy 40.138065 -282.771297) (xy 40.18724 -282.769316) (xy 40.236095 -282.775248) (xy 40.283366 -282.78894)
			(xy 40.327828 -282.810038) (xy 40.368331 -282.837994) (xy 40.403824 -282.872086) (xy 40.433389 -282.91143)
			(xy 40.45626 -282.955007) (xy 40.471844 -283.001688) (xy 40.479739 -283.050265) (xy 40.480234 -283.074872)
			(xy 40.819082 -283.074872) (xy 40.823042 -283.025818) (xy 40.834819 -282.978034) (xy 40.85411 -282.932758)
			(xy 40.880413 -282.891162) (xy 40.913048 -282.854325) (xy 40.951169 -282.8232) (xy 40.99379 -282.798593)
			(xy 41.039806 -282.781141) (xy 41.088025 -282.771297) (xy 41.1372 -282.769316) (xy 41.186055 -282.775248)
			(xy 41.233326 -282.78894) (xy 41.277788 -282.810038) (xy 41.318291 -282.837994) (xy 41.353784 -282.872086)
			(xy 41.383349 -282.91143) (xy 41.40622 -282.955007) (xy 41.421804 -283.001688) (xy 41.429699 -283.050265)
			(xy 41.430194 -283.074872) (xy 41.769042 -283.074872) (xy 41.773002 -283.025818) (xy 41.784779 -282.978034)
			(xy 41.80407 -282.932758) (xy 41.830373 -282.891162) (xy 41.863008 -282.854325) (xy 41.901129 -282.8232)
			(xy 41.94375 -282.798593) (xy 41.989766 -282.781141) (xy 42.037985 -282.771297) (xy 42.08716 -282.769316)
			(xy 42.136015 -282.775248) (xy 42.183286 -282.78894) (xy 42.227748 -282.810038) (xy 42.268251 -282.837994)
			(xy 42.303744 -282.872086) (xy 42.333309 -282.91143) (xy 42.35618 -282.955007) (xy 42.371764 -283.001688)
			(xy 42.379659 -283.050265) (xy 42.379988 -283.06664) (xy 44.619253 -283.06664) (xy 44.624617 -283.017284)
			(xy 44.637895 -282.969446) (xy 44.658738 -282.924387) (xy 44.686596 -282.883293) (xy 44.720735 -282.847248)
			(xy 44.760256 -282.8172) (xy 44.804118 -282.793942) (xy 44.851165 -282.778087) (xy 44.900157 -282.770052)
			(xy 44.92498 -282.769564) (xy 44.939163 -282.769744) (xy 44.967403 -282.772414) (xy 44.981368 -282.774898)
			(xy 44.993814 -282.777184) (xy 45.017436 -282.769818) (xy 45.094906 -282.692348) (xy 45.102272 -282.668726)
			(xy 45.099986 -282.65628) (xy 45.097511 -282.642314) (xy 45.094838 -282.614074) (xy 45.094652 -282.599892)
			(xy 45.095174 -282.574637) (xy 45.103487 -282.524815) (xy 45.119888 -282.477041) (xy 45.143929 -282.432618)
			(xy 45.174953 -282.392758) (xy 45.212115 -282.358548) (xy 45.254401 -282.330922) (xy 45.300657 -282.310632)
			(xy 45.349622 -282.298232) (xy 45.39996 -282.294061) (xy 45.450298 -282.298232) (xy 45.499263 -282.310632)
			(xy 45.545519 -282.330922) (xy 45.587805 -282.358548) (xy 45.624967 -282.392758) (xy 45.655991 -282.432618)
			(xy 45.680032 -282.477041) (xy 45.696433 -282.524815) (xy 45.704746 -282.574637) (xy 45.705268 -282.599892)
			(xy 45.705091 -282.614075) (xy 45.702419 -282.642315) (xy 45.699934 -282.65628) (xy 45.697648 -282.668726)
			(xy 45.705014 -282.692348) (xy 45.782484 -282.769818) (xy 45.806106 -282.777184) (xy 45.818552 -282.774898)
			(xy 45.832517 -282.772418) (xy 45.860757 -282.769749) (xy 45.87494 -282.769564) (xy 45.889123 -282.769736)
			(xy 45.917363 -282.772411) (xy 45.931328 -282.774898) (xy 45.943774 -282.777184) (xy 45.967396 -282.769818)
			(xy 46.044866 -282.692348) (xy 46.052232 -282.668726) (xy 46.049946 -282.65628) (xy 46.047471 -282.642314)
			(xy 46.044798 -282.614074) (xy 46.044612 -282.599892) (xy 46.045134 -282.574637) (xy 46.053447 -282.524815)
			(xy 46.069848 -282.477041) (xy 46.093889 -282.432618) (xy 46.124913 -282.392758) (xy 46.162075 -282.358548)
			(xy 46.204361 -282.330922) (xy 46.250617 -282.310632) (xy 46.299582 -282.298232) (xy 46.34992 -282.294061)
			(xy 46.400258 -282.298232) (xy 46.449223 -282.310632) (xy 46.495479 -282.330922) (xy 46.537765 -282.358548)
			(xy 46.574927 -282.392758) (xy 46.605951 -282.432618) (xy 46.629992 -282.477041) (xy 46.646393 -282.524815)
			(xy 46.654706 -282.574637) (xy 46.655228 -282.599892) (xy 46.65505 -282.614075) (xy 46.652379 -282.642315)
			(xy 46.649894 -282.65628) (xy 46.647608 -282.668726) (xy 46.654974 -282.692348) (xy 46.732444 -282.769818)
			(xy 46.756066 -282.777184) (xy 46.768512 -282.774898) (xy 46.782478 -282.772424) (xy 46.810718 -282.769751)
			(xy 46.8249 -282.769564) (xy 46.849721 -282.770078) (xy 46.89871 -282.778109) (xy 46.945754 -282.793961)
			(xy 46.989614 -282.817214) (xy 47.029133 -282.847257) (xy 47.063272 -282.883298) (xy 47.09113 -282.924387)
			(xy 47.111974 -282.969442) (xy 47.125253 -283.017276) (xy 47.130619 -283.066627) (xy 47.130172 -283.074872)
			(xy 47.469056 -283.074872) (xy 47.473016 -283.025818) (xy 47.484793 -282.978034) (xy 47.504084 -282.932758)
			(xy 47.530387 -282.891162) (xy 47.563022 -282.854325) (xy 47.601143 -282.8232) (xy 47.643764 -282.798593)
			(xy 47.68978 -282.781141) (xy 47.737999 -282.771297) (xy 47.787174 -282.769316) (xy 47.836029 -282.775248)
			(xy 47.8833 -282.78894) (xy 47.927762 -282.810038) (xy 47.968265 -282.837994) (xy 48.003758 -282.872086)
			(xy 48.033323 -282.91143) (xy 48.056194 -282.955007) (xy 48.071778 -283.001688) (xy 48.079673 -283.050265)
			(xy 48.080168 -283.074872) (xy 48.079673 -283.099479) (xy 48.071778 -283.148056) (xy 48.056194 -283.194737)
			(xy 48.033323 -283.238314) (xy 48.003758 -283.277658) (xy 47.968265 -283.31175) (xy 47.927762 -283.339706)
			(xy 47.8833 -283.360804) (xy 47.836029 -283.374496) (xy 47.787174 -283.380428) (xy 47.737999 -283.378447)
			(xy 47.68978 -283.368603) (xy 47.643764 -283.351151) (xy 47.601143 -283.326544) (xy 47.563022 -283.295419)
			(xy 47.530387 -283.258582) (xy 47.504084 -283.216986) (xy 47.484793 -283.17171) (xy 47.473016 -283.123926)
			(xy 47.469056 -283.074872) (xy 47.130172 -283.074872) (xy 47.12793 -283.116197) (xy 47.117257 -283.164679)
			(xy 47.09888 -283.210795) (xy 47.073285 -283.253331) (xy 47.041145 -283.291165) (xy 47.003308 -283.323301)
			(xy 46.96077 -283.348893) (xy 46.914652 -283.367265) (xy 46.866169 -283.377934) (xy 46.816599 -283.380618)
			(xy 46.767248 -283.375248) (xy 46.719416 -283.361964) (xy 46.674363 -283.341116) (xy 46.633276 -283.313255)
			(xy 46.597238 -283.279113) (xy 46.567199 -283.23959) (xy 46.54395 -283.195728) (xy 46.528103 -283.148683)
			(xy 46.520076 -283.099693) (xy 46.519592 -283.074872) (xy 46.519765 -283.060689) (xy 46.522439 -283.032449)
			(xy 46.524926 -283.018484) (xy 46.527212 -283.006038) (xy 46.519846 -282.982416) (xy 46.442376 -282.904946)
			(xy 46.418754 -282.89758) (xy 46.406308 -282.899866) (xy 46.392341 -282.902337) (xy 46.364102 -282.905013)
			(xy 46.34992 -282.9052) (xy 46.335737 -282.905021) (xy 46.307497 -282.90235) (xy 46.293532 -282.899866)
			(xy 46.281086 -282.89758) (xy 46.257464 -282.904946) (xy 46.179994 -282.982416) (xy 46.172628 -283.006038)
			(xy 46.174914 -283.018484) (xy 46.177398 -283.032449) (xy 46.180065 -283.060689) (xy 46.180248 -283.074872)
			(xy 46.179726 -283.100127) (xy 46.171413 -283.149949) (xy 46.155012 -283.197723) (xy 46.130971 -283.242146)
			(xy 46.099947 -283.282006) (xy 46.062785 -283.316216) (xy 46.020499 -283.343842) (xy 45.974243 -283.364132)
			(xy 45.925278 -283.376532) (xy 45.87494 -283.380703) (xy 45.824602 -283.376532) (xy 45.775637 -283.364132)
			(xy 45.729381 -283.343842) (xy 45.687095 -283.316216) (xy 45.649933 -283.282006) (xy 45.618909 -283.242146)
			(xy 45.594868 -283.197723) (xy 45.578467 -283.149949) (xy 45.570154 -283.100127) (xy 45.569632 -283.074872)
			(xy 45.569804 -283.060689) (xy 45.572479 -283.032449) (xy 45.574966 -283.018484) (xy 45.577252 -283.006038)
			(xy 45.569886 -282.982416) (xy 45.492416 -282.904946) (xy 45.468794 -282.89758) (xy 45.456348 -282.899866)
			(xy 45.442383 -282.902345) (xy 45.414143 -282.905015) (xy 45.39996 -282.9052) (xy 45.385777 -282.905029)
			(xy 45.357537 -282.902353) (xy 45.343572 -282.899866) (xy 45.331126 -282.89758) (xy 45.307504 -282.904946)
			(xy 45.230034 -282.982416) (xy 45.222668 -283.006038) (xy 45.224954 -283.018484) (xy 45.227438 -283.032449)
			(xy 45.230105 -283.060689) (xy 45.230288 -283.074872) (xy 45.229852 -283.099695) (xy 45.221825 -283.148689)
			(xy 45.205977 -283.195738) (xy 45.182726 -283.239603) (xy 45.152685 -283.279129) (xy 45.116644 -283.313274)
			(xy 45.075555 -283.341139) (xy 45.030499 -283.361988) (xy 44.982663 -283.375274) (xy 44.933308 -283.380646)
			(xy 44.883734 -283.377962) (xy 44.835247 -283.367294) (xy 44.789125 -283.348922) (xy 44.746583 -283.323329)
			(xy 44.708742 -283.291192) (xy 44.676599 -283.253356) (xy 44.651 -283.210818) (xy 44.63262 -283.164699)
			(xy 44.621944 -283.116214) (xy 44.619253 -283.06664) (xy 42.379988 -283.06664) (xy 42.380154 -283.074872)
			(xy 42.379659 -283.099479) (xy 42.371764 -283.148056) (xy 42.35618 -283.194737) (xy 42.333309 -283.238314)
			(xy 42.303744 -283.277658) (xy 42.268251 -283.31175) (xy 42.227748 -283.339706) (xy 42.183286 -283.360804)
			(xy 42.136015 -283.374496) (xy 42.08716 -283.380428) (xy 42.037985 -283.378447) (xy 41.989766 -283.368603)
			(xy 41.94375 -283.351151) (xy 41.901129 -283.326544) (xy 41.863008 -283.295419) (xy 41.830373 -283.258582)
			(xy 41.80407 -283.216986) (xy 41.784779 -283.17171) (xy 41.773002 -283.123926) (xy 41.769042 -283.074872)
			(xy 41.430194 -283.074872) (xy 41.429699 -283.099479) (xy 41.421804 -283.148056) (xy 41.40622 -283.194737)
			(xy 41.383349 -283.238314) (xy 41.353784 -283.277658) (xy 41.318291 -283.31175) (xy 41.277788 -283.339706)
			(xy 41.233326 -283.360804) (xy 41.186055 -283.374496) (xy 41.1372 -283.380428) (xy 41.088025 -283.378447)
			(xy 41.039806 -283.368603) (xy 40.99379 -283.351151) (xy 40.951169 -283.326544) (xy 40.913048 -283.295419)
			(xy 40.880413 -283.258582) (xy 40.85411 -283.216986) (xy 40.834819 -283.17171) (xy 40.823042 -283.123926)
			(xy 40.819082 -283.074872) (xy 40.480234 -283.074872) (xy 40.479739 -283.099479) (xy 40.471844 -283.148056)
			(xy 40.45626 -283.194737) (xy 40.433389 -283.238314) (xy 40.403824 -283.277658) (xy 40.368331 -283.31175)
			(xy 40.327828 -283.339706) (xy 40.283366 -283.360804) (xy 40.236095 -283.374496) (xy 40.18724 -283.380428)
			(xy 40.138065 -283.378447) (xy 40.089846 -283.368603) (xy 40.04383 -283.351151) (xy 40.001209 -283.326544)
			(xy 39.963088 -283.295419) (xy 39.930453 -283.258582) (xy 39.90415 -283.216986) (xy 39.884859 -283.17171)
			(xy 39.873082 -283.123926) (xy 39.869122 -283.074872) (xy 39.530274 -283.074872) (xy 39.529779 -283.099479)
			(xy 39.521884 -283.148056) (xy 39.5063 -283.194737) (xy 39.483429 -283.238314) (xy 39.453864 -283.277658)
			(xy 39.418371 -283.31175) (xy 39.377868 -283.339706) (xy 39.333406 -283.360804) (xy 39.286135 -283.374496)
			(xy 39.23728 -283.380428) (xy 39.188105 -283.378447) (xy 39.139886 -283.368603) (xy 39.09387 -283.351151)
			(xy 39.051249 -283.326544) (xy 39.013128 -283.295419) (xy 38.980493 -283.258582) (xy 38.95419 -283.216986)
			(xy 38.934899 -283.17171) (xy 38.923122 -283.123926) (xy 38.919162 -283.074872) (xy 38.580314 -283.074872)
			(xy 38.579819 -283.099479) (xy 38.571924 -283.148056) (xy 38.55634 -283.194737) (xy 38.533469 -283.238314)
			(xy 38.503904 -283.277658) (xy 38.468411 -283.31175) (xy 38.427908 -283.339706) (xy 38.383446 -283.360804)
			(xy 38.336175 -283.374496) (xy 38.28732 -283.380428) (xy 38.238145 -283.378447) (xy 38.189926 -283.368603)
			(xy 38.14391 -283.351151) (xy 38.101289 -283.326544) (xy 38.063168 -283.295419) (xy 38.030533 -283.258582)
			(xy 38.00423 -283.216986) (xy 37.984939 -283.17171) (xy 37.973162 -283.123926) (xy 37.969202 -283.074872)
			(xy 37.6301 -283.074872) (xy 37.629605 -283.099479) (xy 37.62171 -283.148056) (xy 37.606126 -283.194737)
			(xy 37.583255 -283.238314) (xy 37.55369 -283.277658) (xy 37.518197 -283.31175) (xy 37.477694 -283.339706)
			(xy 37.433232 -283.360804) (xy 37.385961 -283.374496) (xy 37.337106 -283.380428) (xy 37.287931 -283.378447)
			(xy 37.239712 -283.368603) (xy 37.193696 -283.351151) (xy 37.151075 -283.326544) (xy 37.112954 -283.295419)
			(xy 37.080319 -283.258582) (xy 37.054016 -283.216986) (xy 37.034725 -283.17171) (xy 37.022948 -283.123926)
			(xy 37.018988 -283.074872) (xy 36.68014 -283.074872) (xy 36.679645 -283.099479) (xy 36.67175 -283.148056)
			(xy 36.656166 -283.194737) (xy 36.633295 -283.238314) (xy 36.60373 -283.277658) (xy 36.568237 -283.31175)
			(xy 36.527734 -283.339706) (xy 36.483272 -283.360804) (xy 36.436001 -283.374496) (xy 36.387146 -283.380428)
			(xy 36.337971 -283.378447) (xy 36.289752 -283.368603) (xy 36.243736 -283.351151) (xy 36.201115 -283.326544)
			(xy 36.162994 -283.295419) (xy 36.130359 -283.258582) (xy 36.104056 -283.216986) (xy 36.084765 -283.17171)
			(xy 36.072988 -283.123926) (xy 36.069028 -283.074872) (xy 32.107807 -283.074872) (xy 32.112031 -283.104246)
			(xy 32.112031 -283.158754) (xy 32.104273 -283.212707) (xy 32.088915 -283.265007) (xy 32.066269 -283.314589)
			(xy 32.036798 -283.360443) (xy 32.0011 -283.401635) (xy 31.959903 -283.437328) (xy 31.914045 -283.466793)
			(xy 31.86446 -283.489432) (xy 31.812159 -283.504783) (xy 31.758204 -283.512534) (xy 31.73095 -283.513022)
			(xy 31.704217 -283.51257) (xy 31.651274 -283.5051) (xy 31.599893 -283.490313) (xy 31.551078 -283.468499)
			(xy 31.505786 -283.440085) (xy 31.464904 -283.405627) (xy 31.446724 -283.386022) (xy 31.436056 -283.374084)
			(xy 31.405576 -283.366718) (xy 31.302198 -283.406342) (xy 31.292761 -283.410426) (xy 31.277948 -283.424662)
			(xy 31.269906 -283.443567) (xy 31.269432 -283.45384) (xy 31.269432 -284.000956) (xy 31.269866 -284.011021)
			(xy 31.277598 -284.029608) (xy 31.284418 -284.037024) (xy 31.375096 -284.127702) (xy 31.382494 -284.134549)
			(xy 31.401092 -284.142285) (xy 31.411164 -284.142688) (xy 33.400238 -284.142688) (xy 33.410305 -284.142258)
			(xy 33.428898 -284.134532) (xy 33.436306 -284.127702) (xy 33.615122 -283.948886) (xy 33.622996 -283.928312)
			(xy 33.622234 -283.91739) (xy 33.621472 -283.893514) (xy 33.621957 -283.866262) (xy 33.629712 -283.812311)
			(xy 33.645065 -283.760014) (xy 33.667705 -283.710433) (xy 33.697171 -283.66458) (xy 33.732862 -283.623386)
			(xy 33.774053 -283.587691) (xy 33.819904 -283.558222) (xy 33.869482 -283.535577) (xy 33.921778 -283.520219)
			(xy 33.975728 -283.512459) (xy 34.00298 -283.512006) (xy 34.029262 -283.512444) (xy 34.081329 -283.519658)
			(xy 34.131913 -283.533952) (xy 34.180055 -283.555055) (xy 34.224844 -283.582568) (xy 34.265432 -283.61597)
			(xy 34.301049 -283.654628) (xy 34.331022 -283.697809) (xy 34.354783 -283.744697) (xy 34.371881 -283.794403)
			(xy 34.377376 -283.820108) (xy 34.380932 -283.838142) (xy 34.408872 -283.861002) (xy 36.090606 -283.861002)
			(xy 36.102427 -283.860449) (xy 36.123622 -283.849987) (xy 36.131246 -283.840936) (xy 36.147116 -283.820762)
			(xy 36.184437 -283.785527) (xy 36.227128 -283.757036) (xy 36.273986 -283.73609) (xy 36.323688 -283.723282)
			(xy 36.374832 -283.718972) (xy 36.425976 -283.723282) (xy 36.475678 -283.73609) (xy 36.522536 -283.757036)
			(xy 36.565227 -283.785527) (xy 36.602548 -283.820762) (xy 36.618418 -283.840936) (xy 36.62606 -283.849967)
			(xy 36.647242 -283.86044) (xy 36.659058 -283.861002) (xy 37.040566 -283.861002) (xy 37.052392 -283.860458)
			(xy 37.0736 -283.850005) (xy 37.081206 -283.840936) (xy 37.097076 -283.820762) (xy 37.134397 -283.785527)
			(xy 37.177088 -283.757036) (xy 37.223946 -283.73609) (xy 37.273648 -283.723282) (xy 37.324792 -283.718972)
			(xy 37.375936 -283.723282) (xy 37.425638 -283.73609) (xy 37.472496 -283.757036) (xy 37.515187 -283.785527)
			(xy 37.552508 -283.820762) (xy 37.568378 -283.840936) (xy 37.576023 -283.849957) (xy 37.597207 -283.860406)
			(xy 37.609018 -283.861002) (xy 37.99078 -283.861002) (xy 38.002604 -283.860455) (xy 38.023808 -283.849999)
			(xy 38.03142 -283.840936) (xy 38.04729 -283.820762) (xy 38.084611 -283.785527) (xy 38.127302 -283.757036)
			(xy 38.17416 -283.73609) (xy 38.223862 -283.723282) (xy 38.275006 -283.718972) (xy 38.32615 -283.723282)
			(xy 38.375852 -283.73609) (xy 38.42271 -283.757036) (xy 38.465401 -283.785527) (xy 38.502722 -283.820762)
			(xy 38.518592 -283.840936) (xy 38.526239 -283.849955) (xy 38.547422 -283.860397) (xy 38.559232 -283.861002)
			(xy 38.94074 -283.861002) (xy 38.952558 -283.860442) (xy 38.97374 -283.849971) (xy 38.98138 -283.840936)
			(xy 38.99725 -283.820762) (xy 39.034571 -283.785527) (xy 39.077262 -283.757036) (xy 39.12412 -283.73609)
			(xy 39.173822 -283.723282) (xy 39.224966 -283.718972) (xy 39.27611 -283.723282) (xy 39.325812 -283.73609)
			(xy 39.37267 -283.757036) (xy 39.415361 -283.785527) (xy 39.452682 -283.820762) (xy 39.468552 -283.840936)
			(xy 39.476196 -283.849961) (xy 39.497379 -283.86042) (xy 39.509192 -283.861002) (xy 39.8907 -283.861002)
			(xy 39.902522 -283.860451) (xy 39.923718 -283.84999) (xy 39.93134 -283.840936) (xy 39.94721 -283.820762)
			(xy 39.984531 -283.785527) (xy 40.027222 -283.757036) (xy 40.07408 -283.73609) (xy 40.123782 -283.723282)
			(xy 40.174926 -283.718972) (xy 40.22607 -283.723282) (xy 40.275772 -283.73609) (xy 40.32263 -283.757036)
			(xy 40.365321 -283.785527) (xy 40.402642 -283.820762) (xy 40.418512 -283.840936) (xy 40.426153 -283.849968)
			(xy 40.447336 -283.860443) (xy 40.459152 -283.861002) (xy 40.84066 -283.861002) (xy 40.852487 -283.860459)
			(xy 40.873697 -283.850008) (xy 40.8813 -283.840936) (xy 40.89717 -283.820762) (xy 40.934491 -283.785527)
			(xy 40.977182 -283.757036) (xy 41.02404 -283.73609) (xy 41.073742 -283.723282) (xy 41.124886 -283.718972)
			(xy 41.17603 -283.723282) (xy 41.225732 -283.73609) (xy 41.27259 -283.757036) (xy 41.315281 -283.785527)
			(xy 41.352602 -283.820762) (xy 41.368472 -283.840936) (xy 41.376117 -283.849958) (xy 41.3973 -283.860409)
			(xy 41.409112 -283.861002) (xy 44.640754 -283.861002) (xy 44.652581 -283.86046) (xy 44.673793 -283.850011)
			(xy 44.681394 -283.840936) (xy 44.697264 -283.820762) (xy 44.734585 -283.785527) (xy 44.777276 -283.757036)
			(xy 44.824134 -283.73609) (xy 44.873836 -283.723282) (xy 44.92498 -283.718972) (xy 44.976124 -283.723282)
			(xy 45.025826 -283.73609) (xy 45.072684 -283.757036) (xy 45.115375 -283.785527) (xy 45.152696 -283.820762)
			(xy 45.168566 -283.840936) (xy 45.176211 -283.849959) (xy 45.197394 -283.860412) (xy 45.209206 -283.861002)
			(xy 45.590714 -283.861002) (xy 45.602535 -283.860448) (xy 45.623726 -283.849983) (xy 45.631354 -283.840936)
			(xy 45.647224 -283.820762) (xy 45.684545 -283.785527) (xy 45.727236 -283.757036) (xy 45.774094 -283.73609)
			(xy 45.823796 -283.723282) (xy 45.87494 -283.718972) (xy 45.926084 -283.723282) (xy 45.975786 -283.73609)
			(xy 46.022644 -283.757036) (xy 46.065335 -283.785527) (xy 46.102656 -283.820762) (xy 46.118526 -283.840936)
			(xy 46.126168 -283.849966) (xy 46.147351 -283.860435) (xy 46.159166 -283.861002) (xy 46.540674 -283.861002)
			(xy 46.552499 -283.860456) (xy 46.573704 -283.850002) (xy 46.581314 -283.840936) (xy 46.595823 -283.822417)
			(xy 46.629576 -283.789647) (xy 46.66796 -283.762447) (xy 46.710065 -283.741462) (xy 46.754891 -283.727189)
			(xy 46.801378 -283.719967) (xy 46.8249 -283.719524) (xy 46.848892 -283.71997) (xy 46.896286 -283.727477)
			(xy 46.941921 -283.742306) (xy 46.984675 -283.764092) (xy 47.023494 -283.792298) (xy 47.057423 -283.82623)
			(xy 47.085625 -283.865052) (xy 47.107406 -283.907808) (xy 47.12223 -283.953445) (xy 47.129732 -284.00084)
			(xy 47.130208 -284.024832) (xy 47.469056 -284.024832) (xy 47.473016 -283.975778) (xy 47.484793 -283.927994)
			(xy 47.504084 -283.882718) (xy 47.530387 -283.841122) (xy 47.563022 -283.804285) (xy 47.601143 -283.77316)
			(xy 47.643764 -283.748553) (xy 47.68978 -283.731101) (xy 47.737999 -283.721257) (xy 47.787174 -283.719276)
			(xy 47.836029 -283.725208) (xy 47.8833 -283.7389) (xy 47.927762 -283.759998) (xy 47.968265 -283.787954)
			(xy 48.003758 -283.822046) (xy 48.033323 -283.86139) (xy 48.056194 -283.904967) (xy 48.071778 -283.951648)
			(xy 48.079673 -284.000225) (xy 48.080168 -284.024832) (xy 48.079673 -284.049439) (xy 48.071778 -284.098016)
			(xy 48.056194 -284.144697) (xy 48.033323 -284.188274) (xy 48.003758 -284.227618) (xy 47.968265 -284.26171)
			(xy 47.927762 -284.289666) (xy 47.8833 -284.310764) (xy 47.836029 -284.324456) (xy 47.787174 -284.330388)
			(xy 47.737999 -284.328407) (xy 47.68978 -284.318563) (xy 47.643764 -284.301111) (xy 47.601143 -284.276504)
			(xy 47.563022 -284.245379) (xy 47.530387 -284.208542) (xy 47.504084 -284.166946) (xy 47.484793 -284.12167)
			(xy 47.473016 -284.073886) (xy 47.469056 -284.024832) (xy 47.130208 -284.024832) (xy 47.130047 -284.038692)
			(xy 47.127506 -284.066295) (xy 47.125128 -284.07995) (xy 47.122842 -284.092396) (xy 47.130208 -284.116018)
			(xy 47.141892 -284.127702) (xy 47.148739 -284.1351) (xy 47.156474 -284.153698) (xy 47.156878 -284.16377)
			(xy 47.156878 -284.325314) (xy 47.157417 -284.335301) (xy 47.165132 -284.353731) (xy 47.171864 -284.361128)
			(xy 47.27575 -284.465268) (xy 47.282555 -284.472614) (xy 47.290271 -284.491078) (xy 47.290736 -284.501082)
			(xy 47.290736 -284.974792) (xy 47.469056 -284.974792) (xy 47.473016 -284.925738) (xy 47.484793 -284.877954)
			(xy 47.504084 -284.832678) (xy 47.530387 -284.791082) (xy 47.563022 -284.754245) (xy 47.601143 -284.72312)
			(xy 47.643764 -284.698513) (xy 47.68978 -284.681061) (xy 47.737999 -284.671217) (xy 47.787174 -284.669236)
			(xy 47.836029 -284.675168) (xy 47.8833 -284.68886) (xy 47.927762 -284.709958) (xy 47.968265 -284.737914)
			(xy 48.003758 -284.772006) (xy 48.033323 -284.81135) (xy 48.056194 -284.854927) (xy 48.071778 -284.901608)
			(xy 48.079673 -284.950185) (xy 48.080168 -284.974792) (xy 48.079673 -284.999399) (xy 48.071778 -285.047976)
			(xy 48.056194 -285.094657) (xy 48.033323 -285.138234) (xy 48.003758 -285.177578) (xy 47.968265 -285.21167)
			(xy 47.927762 -285.239626) (xy 47.8833 -285.260724) (xy 47.836029 -285.274416) (xy 47.787174 -285.280348)
			(xy 47.737999 -285.278367) (xy 47.68978 -285.268523) (xy 47.643764 -285.251071) (xy 47.601143 -285.226464)
			(xy 47.563022 -285.195339) (xy 47.530387 -285.158502) (xy 47.504084 -285.116906) (xy 47.484793 -285.07163)
			(xy 47.473016 -285.023846) (xy 47.469056 -284.974792) (xy 47.290736 -284.974792) (xy 47.290736 -285.924752)
			(xy 47.469056 -285.924752) (xy 47.473016 -285.875698) (xy 47.484793 -285.827914) (xy 47.504084 -285.782638)
			(xy 47.530387 -285.741042) (xy 47.563022 -285.704205) (xy 47.601143 -285.67308) (xy 47.643764 -285.648473)
			(xy 47.68978 -285.631021) (xy 47.737999 -285.621177) (xy 47.787174 -285.619196) (xy 47.836029 -285.625128)
			(xy 47.8833 -285.63882) (xy 47.927762 -285.659918) (xy 47.968265 -285.687874) (xy 48.003758 -285.721966)
			(xy 48.033323 -285.76131) (xy 48.056194 -285.804887) (xy 48.071778 -285.851568) (xy 48.079673 -285.900145)
			(xy 48.080168 -285.924752) (xy 48.079673 -285.949359) (xy 48.071778 -285.997936) (xy 48.056194 -286.044617)
			(xy 48.033323 -286.088194) (xy 48.003758 -286.127538) (xy 47.968265 -286.16163) (xy 47.927762 -286.189586)
			(xy 47.8833 -286.210684) (xy 47.836029 -286.224376) (xy 47.787174 -286.230308) (xy 47.737999 -286.228327)
			(xy 47.68978 -286.218483) (xy 47.643764 -286.201031) (xy 47.601143 -286.176424) (xy 47.563022 -286.145299)
			(xy 47.530387 -286.108462) (xy 47.504084 -286.066866) (xy 47.484793 -286.02159) (xy 47.473016 -285.973806)
			(xy 47.469056 -285.924752) (xy 47.290736 -285.924752) (xy 47.290736 -286.874966) (xy 47.469056 -286.874966)
			(xy 47.473016 -286.825912) (xy 47.484793 -286.778128) (xy 47.504084 -286.732852) (xy 47.530387 -286.691256)
			(xy 47.563022 -286.654419) (xy 47.601143 -286.623294) (xy 47.643764 -286.598687) (xy 47.68978 -286.581235)
			(xy 47.737999 -286.571391) (xy 47.787174 -286.56941) (xy 47.836029 -286.575342) (xy 47.8833 -286.589034)
			(xy 47.927762 -286.610132) (xy 47.968265 -286.638088) (xy 48.003758 -286.67218) (xy 48.033323 -286.711524)
			(xy 48.056194 -286.755101) (xy 48.071778 -286.801782) (xy 48.079673 -286.850359) (xy 48.080168 -286.874966)
			(xy 48.079673 -286.899573) (xy 48.071778 -286.94815) (xy 48.056194 -286.994831) (xy 48.033323 -287.038408)
			(xy 48.003758 -287.077752) (xy 47.968265 -287.111844) (xy 47.927762 -287.1398) (xy 47.8833 -287.160898)
			(xy 47.836029 -287.17459) (xy 47.787174 -287.180522) (xy 47.737999 -287.178541) (xy 47.68978 -287.168697)
			(xy 47.643764 -287.151245) (xy 47.601143 -287.126638) (xy 47.563022 -287.095513) (xy 47.530387 -287.058676)
			(xy 47.504084 -287.01708) (xy 47.484793 -286.971804) (xy 47.473016 -286.92402) (xy 47.469056 -286.874966)
			(xy 47.290736 -286.874966) (xy 47.290736 -287.824926) (xy 47.469056 -287.824926) (xy 47.473016 -287.775872)
			(xy 47.484793 -287.728088) (xy 47.504084 -287.682812) (xy 47.530387 -287.641216) (xy 47.563022 -287.604379)
			(xy 47.601143 -287.573254) (xy 47.643764 -287.548647) (xy 47.68978 -287.531195) (xy 47.737999 -287.521351)
			(xy 47.787174 -287.51937) (xy 47.836029 -287.525302) (xy 47.8833 -287.538994) (xy 47.927762 -287.560092)
			(xy 47.968265 -287.588048) (xy 48.003758 -287.62214) (xy 48.033323 -287.661484) (xy 48.056194 -287.705061)
			(xy 48.071778 -287.751742) (xy 48.079673 -287.800319) (xy 48.080168 -287.824926) (xy 48.079673 -287.849533)
			(xy 48.071778 -287.89811) (xy 48.056194 -287.944791) (xy 48.033323 -287.988368) (xy 48.003758 -288.027712)
			(xy 47.968265 -288.061804) (xy 47.927762 -288.08976) (xy 47.8833 -288.110858) (xy 47.836029 -288.12455)
			(xy 47.787174 -288.130482) (xy 47.737999 -288.128501) (xy 47.68978 -288.118657) (xy 47.643764 -288.101205)
			(xy 47.601143 -288.076598) (xy 47.563022 -288.045473) (xy 47.530387 -288.008636) (xy 47.504084 -287.96704)
			(xy 47.484793 -287.921764) (xy 47.473016 -287.87398) (xy 47.469056 -287.824926) (xy 47.290736 -287.824926)
			(xy 47.290736 -288.774886) (xy 47.469056 -288.774886) (xy 47.473016 -288.725832) (xy 47.484793 -288.678048)
			(xy 47.504084 -288.632772) (xy 47.530387 -288.591176) (xy 47.563022 -288.554339) (xy 47.601143 -288.523214)
			(xy 47.643764 -288.498607) (xy 47.68978 -288.481155) (xy 47.737999 -288.471311) (xy 47.787174 -288.46933)
			(xy 47.836029 -288.475262) (xy 47.8833 -288.488954) (xy 47.927762 -288.510052) (xy 47.968265 -288.538008)
			(xy 48.003758 -288.5721) (xy 48.033323 -288.611444) (xy 48.056194 -288.655021) (xy 48.071778 -288.701702)
			(xy 48.079673 -288.750279) (xy 48.080168 -288.774886) (xy 48.079673 -288.799493) (xy 48.071778 -288.84807)
			(xy 48.056194 -288.894751) (xy 48.033323 -288.938328) (xy 48.003758 -288.977672) (xy 47.968265 -289.011764)
			(xy 47.927762 -289.03972) (xy 47.8833 -289.060818) (xy 47.836029 -289.07451) (xy 47.787174 -289.080442)
			(xy 47.737999 -289.078461) (xy 47.68978 -289.068617) (xy 47.643764 -289.051165) (xy 47.601143 -289.026558)
			(xy 47.563022 -288.995433) (xy 47.530387 -288.958596) (xy 47.504084 -288.917) (xy 47.484793 -288.871724)
			(xy 47.473016 -288.82394) (xy 47.469056 -288.774886) (xy 47.290736 -288.774886) (xy 47.290736 -289.724846)
			(xy 47.469056 -289.724846) (xy 47.473016 -289.675792) (xy 47.484793 -289.628008) (xy 47.504084 -289.582732)
			(xy 47.530387 -289.541136) (xy 47.563022 -289.504299) (xy 47.601143 -289.473174) (xy 47.643764 -289.448567)
			(xy 47.68978 -289.431115) (xy 47.737999 -289.421271) (xy 47.787174 -289.41929) (xy 47.836029 -289.425222)
			(xy 47.8833 -289.438914) (xy 47.927762 -289.460012) (xy 47.968265 -289.487968) (xy 48.003758 -289.52206)
			(xy 48.033323 -289.561404) (xy 48.056194 -289.604981) (xy 48.071778 -289.651662) (xy 48.079673 -289.700239)
			(xy 48.080168 -289.724846) (xy 48.079673 -289.749453) (xy 48.071778 -289.79803) (xy 48.056194 -289.844711)
			(xy 48.033323 -289.888288) (xy 48.003758 -289.927632) (xy 47.968265 -289.961724) (xy 47.927762 -289.98968)
			(xy 47.8833 -290.010778) (xy 47.836029 -290.02447) (xy 47.787174 -290.030402) (xy 47.737999 -290.028421)
			(xy 47.68978 -290.018577) (xy 47.643764 -290.001125) (xy 47.601143 -289.976518) (xy 47.563022 -289.945393)
			(xy 47.530387 -289.908556) (xy 47.504084 -289.86696) (xy 47.484793 -289.821684) (xy 47.473016 -289.7739)
			(xy 47.469056 -289.724846) (xy 47.290736 -289.724846) (xy 47.290736 -290.674806) (xy 47.469056 -290.674806)
			(xy 47.473016 -290.625752) (xy 47.484793 -290.577968) (xy 47.504084 -290.532692) (xy 47.530387 -290.491096)
			(xy 47.563022 -290.454259) (xy 47.601143 -290.423134) (xy 47.643764 -290.398527) (xy 47.68978 -290.381075)
			(xy 47.737999 -290.371231) (xy 47.787174 -290.36925) (xy 47.836029 -290.375182) (xy 47.8833 -290.388874)
			(xy 47.927762 -290.409972) (xy 47.968265 -290.437928) (xy 48.003758 -290.47202) (xy 48.033323 -290.511364)
			(xy 48.056194 -290.554941) (xy 48.071778 -290.601622) (xy 48.079673 -290.650199) (xy 48.080168 -290.674806)
			(xy 48.079673 -290.699413) (xy 48.071778 -290.74799) (xy 48.056194 -290.794671) (xy 48.033323 -290.838248)
			(xy 48.003758 -290.877592) (xy 47.968265 -290.911684) (xy 47.927762 -290.93964) (xy 47.8833 -290.960738)
			(xy 47.836029 -290.97443) (xy 47.787174 -290.980362) (xy 47.737999 -290.978381) (xy 47.68978 -290.968537)
			(xy 47.643764 -290.951085) (xy 47.601143 -290.926478) (xy 47.563022 -290.895353) (xy 47.530387 -290.858516)
			(xy 47.504084 -290.81692) (xy 47.484793 -290.771644) (xy 47.473016 -290.72386) (xy 47.469056 -290.674806)
			(xy 47.290736 -290.674806) (xy 47.290736 -292.759384) (xy 47.291153 -292.769405) (xy 47.298822 -292.787921)
			(xy 47.312996 -292.802089) (xy 47.331515 -292.809751) (xy 47.341536 -292.810184)
		)
		(stroke
			(width 0)
			(type solid)
		)
		(fill yes)
		(layer "In13.Cu")
		(net "PCEPLL7_VDDA18_PEX0")
	)
	(gr_poly
		(pts
			(xy 27.78252 -257.048762) (xy 27.791967 -257.048276) (xy 27.80956 -257.041375) (xy 27.81681 -257.0353)
			(xy 27.874468 -256.982214) (xy 27.88285 -256.965196) (xy 27.883612 -256.955544) (xy 27.886347 -256.92865)
			(xy 27.898438 -256.875963) (xy 27.917843 -256.825509) (xy 27.944175 -256.778299) (xy 27.976906 -256.735278)
			(xy 28.015381 -256.697307) (xy 28.058829 -256.665146) (xy 28.106382 -256.639438) (xy 28.157087 -256.620699)
			(xy 28.209929 -256.609303) (xy 28.26385 -256.605479) (xy 28.317771 -256.609303) (xy 28.370613 -256.620699)
			(xy 28.421318 -256.639438) (xy 28.468871 -256.665146) (xy 28.512319 -256.697307) (xy 28.550794 -256.735278)
			(xy 28.583525 -256.778299) (xy 28.609857 -256.825509) (xy 28.629262 -256.875963) (xy 28.641353 -256.92865)
			(xy 28.644088 -256.955544) (xy 28.64485 -256.965196) (xy 28.653232 -256.982214) (xy 28.71089 -257.0353)
			(xy 28.718092 -257.041457) (xy 28.735713 -257.048388) (xy 28.74518 -257.048762) (xy 34.285174 -257.048762)
			(xy 34.311336 -257.029966) (xy 34.31667 -257.014472) (xy 34.326353 -256.987826) (xy 34.35247 -256.937509)
			(xy 34.38574 -256.891606) (xy 34.425432 -256.851128) (xy 34.447734 -256.833624) (xy 34.457132 -256.826258)
			(xy 34.467546 -256.805684) (xy 34.46907 -256.701798) (xy 34.459164 -256.680716) (xy 34.45002 -256.67335)
			(xy 34.428194 -256.65512) (xy 34.389663 -256.613299) (xy 34.357759 -256.566226) (xy 34.333187 -256.514943)
			(xy 34.316493 -256.460583) (xy 34.308043 -256.404349) (xy 34.307526 -256.375916) (xy 34.308012 -256.348665)
			(xy 34.315768 -256.294717) (xy 34.331123 -256.242422) (xy 34.353765 -256.192845) (xy 34.383231 -256.146995)
			(xy 34.418922 -256.105804) (xy 34.460113 -256.070113) (xy 34.505963 -256.040647) (xy 34.55554 -256.018005)
			(xy 34.607835 -256.00265) (xy 34.661783 -255.994894) (xy 34.716285 -255.994894) (xy 34.770233 -256.00265)
			(xy 34.822528 -256.018005) (xy 34.872105 -256.040647) (xy 34.917955 -256.070113) (xy 34.959146 -256.105804)
			(xy 34.994837 -256.146995) (xy 35.024303 -256.192845) (xy 35.046945 -256.242422) (xy 35.0623 -256.294717)
			(xy 35.070056 -256.348665) (xy 35.070542 -256.375916) (xy 35.069977 -256.405295) (xy 35.060926 -256.463352)
			(xy 35.043085 -256.519336) (xy 35.016876 -256.571926) (xy 34.982919 -256.619878) (xy 34.942015 -256.662061)
			(xy 34.918904 -256.680208) (xy 34.909506 -256.687574) (xy 34.899092 -256.708148) (xy 34.897568 -256.812034)
			(xy 34.907474 -256.833116) (xy 34.916618 -256.840482) (xy 34.937305 -256.85772) (xy 34.974097 -256.897038)
			(xy 35.004993 -256.94114) (xy 35.029381 -256.989149) (xy 35.038538 -257.014472) (xy 35.043872 -257.029966)
			(xy 35.070034 -257.048762) (xy 35.682174 -257.048762) (xy 35.708336 -257.029966) (xy 35.71367 -257.014472)
			(xy 35.723168 -256.988271) (xy 35.748683 -256.938726) (xy 35.781137 -256.89342) (xy 35.819837 -256.85332)
			(xy 35.863961 -256.819277) (xy 35.912568 -256.792018) (xy 35.964625 -256.772121) (xy 36.019023 -256.760011)
			(xy 36.074604 -256.755946) (xy 36.130185 -256.760011) (xy 36.184583 -256.772121) (xy 36.23664 -256.792018)
			(xy 36.285247 -256.819277) (xy 36.329371 -256.85332) (xy 36.368071 -256.89342) (xy 36.400525 -256.938726)
			(xy 36.42604 -256.988271) (xy 36.435538 -257.014472) (xy 36.440872 -257.029966) (xy 36.467034 -257.048762)
			(xy 36.568634 -257.048762) (xy 36.594796 -257.029966) (xy 36.60013 -257.014472) (xy 36.609628 -256.988271)
			(xy 36.635143 -256.938726) (xy 36.667597 -256.89342) (xy 36.706297 -256.85332) (xy 36.750421 -256.819277)
			(xy 36.799028 -256.792018) (xy 36.851085 -256.772121) (xy 36.905483 -256.760011) (xy 36.961064 -256.755946)
			(xy 37.016645 -256.760011) (xy 37.071043 -256.772121) (xy 37.1231 -256.792018) (xy 37.171707 -256.819277)
			(xy 37.215831 -256.85332) (xy 37.254531 -256.89342) (xy 37.286985 -256.938726) (xy 37.3125 -256.988271)
			(xy 37.321998 -257.014472) (xy 37.327332 -257.029966) (xy 37.353494 -257.048762) (xy 94.210632 -257.048762)
			(xy 94.220699 -257.048332) (xy 94.239291 -257.040605) (xy 94.2467 -257.033776) (xy 96.448118 -254.832358)
			(xy 96.455738 -254.81153) (xy 96.454722 -254.8001) (xy 96.452944 -254.764032) (xy 96.453706 -254.742696)
			(xy 96.454214 -254.73025) (xy 96.444054 -254.707898) (xy 96.358964 -254.641096) (xy 96.334834 -254.636778)
			(xy 96.322896 -254.640334) (xy 96.295977 -254.647951) (xy 96.240632 -254.656118) (xy 96.21266 -254.65659)
			(xy 96.185402 -254.656123) (xy 96.131441 -254.648357) (xy 96.079135 -254.632989) (xy 96.02955 -254.610331)
			(xy 95.983695 -254.580846) (xy 95.942504 -254.545133) (xy 95.906816 -254.503921) (xy 95.877358 -254.458048)
			(xy 95.854731 -254.408449) (xy 95.839394 -254.356134) (xy 95.83166 -254.302169) (xy 95.831687 -254.247652)
			(xy 95.839475 -254.193694) (xy 95.854864 -254.141394) (xy 95.877541 -254.091818) (xy 95.907044 -254.045974)
			(xy 95.942773 -254.004798) (xy 95.983999 -253.969126) (xy 96.029884 -253.939686) (xy 96.079492 -253.917078)
			(xy 96.131813 -253.901762) (xy 96.185781 -253.89405) (xy 96.240298 -253.894098) (xy 96.294253 -253.901907)
			(xy 96.346546 -253.917316) (xy 96.396114 -253.940013) (xy 96.441946 -253.969534) (xy 96.483108 -254.005279)
			(xy 96.518764 -254.04652) (xy 96.548185 -254.092416) (xy 96.570774 -254.142033) (xy 96.58607 -254.19436)
			(xy 96.593761 -254.248331) (xy 96.594168 -254.27559) (xy 96.594168 -254.28829) (xy 96.605344 -254.30988)
			(xy 96.693736 -254.372364) (xy 96.717866 -254.375666) (xy 96.729804 -254.371602) (xy 96.763686 -254.360318)
			(xy 96.834054 -254.348181) (xy 96.869758 -254.347472) (xy 96.905826 -254.348996) (xy 96.917256 -254.350012)
			(xy 96.938084 -254.342392) (xy 96.939354 -254.341122) (xy 96.957896 -254.333502) (xy 100.170488 -254.333502)
			(xy 100.180559 -254.333081) (xy 100.199167 -254.32537) (xy 100.206556 -254.318516) (xy 106.813858 -247.711214)
			(xy 106.820696 -247.703813) (xy 106.828405 -247.685214) (xy 106.828844 -247.675146) (xy 106.828844 -244.435884)
			(xy 106.828416 -244.425816) (xy 106.820692 -244.407221) (xy 106.813858 -244.399816) (xy 106.43489 -244.020848)
			(xy 106.427493 -244.013998) (xy 106.408895 -244.006259) (xy 106.398822 -244.005862) (xy 101.641148 -244.005862)
			(xy 101.633277 -244.006161) (xy 101.618281 -244.010954) (xy 101.611684 -244.01526) (xy 101.590028 -244.0302)
			(xy 101.54343 -244.054624) (xy 101.493917 -244.072409) (xy 101.442428 -244.083217) (xy 101.389942 -244.086843)
			(xy 101.337456 -244.083217) (xy 101.285967 -244.072409) (xy 101.236454 -244.054624) (xy 101.189856 -244.0302)
			(xy 101.1682 -244.01526) (xy 101.161615 -244.01093) (xy 101.146611 -244.00614) (xy 101.138736 -244.005862)
			(xy 99.457256 -244.005862) (xy 99.444636 -244.006458) (xy 99.422369 -244.018323) (xy 99.414838 -244.028468)
			(xy 99.399583 -244.050392) (xy 99.363921 -244.090155) (xy 99.323061 -244.124553) (xy 99.277802 -244.152916)
			(xy 99.229029 -244.174688) (xy 99.177695 -244.189444) (xy 99.124806 -244.196894) (xy 99.071394 -244.196894)
			(xy 99.018505 -244.189444) (xy 98.967171 -244.174688) (xy 98.918398 -244.152916) (xy 98.873139 -244.124553)
			(xy 98.832279 -244.090155) (xy 98.796617 -244.050392) (xy 98.781362 -244.028468) (xy 98.773796 -244.018367)
			(xy 98.751548 -244.00652) (xy 98.738944 -244.005862) (xy 98.27514 -244.005862) (xy 98.266531 -244.006202)
			(xy 98.250281 -244.011893) (xy 98.236812 -244.02262) (xy 98.23196 -244.029738) (xy 98.216916 -244.05285)
			(xy 98.181227 -244.094891) (xy 98.139857 -244.131355) (xy 98.093668 -244.161482) (xy 98.043622 -244.184644)
			(xy 97.990762 -244.200359) (xy 97.936191 -244.2083) (xy 97.881045 -244.2083) (xy 97.826474 -244.200359)
			(xy 97.773614 -244.184644) (xy 97.723568 -244.161482) (xy 97.677379 -244.131355) (xy 97.636009 -244.094891)
			(xy 97.60032 -244.05285) (xy 97.585276 -244.029738) (xy 97.58044 -244.022596) (xy 97.56699 -244.011815)
			(xy 97.550716 -244.006135) (xy 97.542096 -244.005862) (xy 96.671384 -244.005862) (xy 96.662838 -244.006191)
			(xy 96.646699 -244.011818) (xy 96.63331 -244.022441) (xy 96.628458 -244.029484) (xy 96.575626 -244.11305)
			(xy 96.573848 -244.138704) (xy 96.579436 -244.150642) (xy 96.590905 -244.176145) (xy 96.60708 -244.229672)
			(xy 96.615252 -244.284989) (xy 96.615758 -244.312948) (xy 96.615272 -244.340199) (xy 96.607516 -244.394147)
			(xy 96.592161 -244.446442) (xy 96.569519 -244.496019) (xy 96.540053 -244.541869) (xy 96.518543 -244.566694)
			(xy 100.51999 -244.566694) (xy 100.524061 -244.511072) (xy 100.536187 -244.456635) (xy 100.55611 -244.404544)
			(xy 100.583406 -244.355909) (xy 100.617492 -244.311766) (xy 100.657641 -244.273057) (xy 100.702999 -244.240606)
			(xy 100.752599 -244.215105) (xy 100.805383 -244.197098) (xy 100.860226 -244.186968) (xy 100.91596 -244.184931)
			(xy 100.971397 -244.191031) (xy 101.025354 -244.205137) (xy 101.076683 -244.226949) (xy 101.124289 -244.256003)
			(xy 101.167157 -244.291678) (xy 101.204374 -244.333215) (xy 101.235147 -244.379728) (xy 101.258819 -244.430225)
			(xy 101.274887 -244.483632) (xy 101.283007 -244.538808) (xy 101.283516 -244.566694) (xy 101.283007 -244.59458)
			(xy 101.274887 -244.649756) (xy 101.258819 -244.703163) (xy 101.235147 -244.75366) (xy 101.204374 -244.800173)
			(xy 101.167157 -244.84171) (xy 101.124289 -244.877385) (xy 101.076683 -244.906439) (xy 101.025354 -244.928251)
			(xy 100.971397 -244.942357) (xy 100.91596 -244.948457) (xy 100.860226 -244.94642) (xy 100.805383 -244.93629)
			(xy 100.752599 -244.918283) (xy 100.702999 -244.892782) (xy 100.657641 -244.860331) (xy 100.617492 -244.821622)
			(xy 100.583406 -244.777479) (xy 100.55611 -244.728844) (xy 100.536187 -244.676753) (xy 100.524061 -244.622316)
			(xy 100.51999 -244.566694) (xy 96.518543 -244.566694) (xy 96.504362 -244.58306) (xy 96.463171 -244.618751)
			(xy 96.417321 -244.648217) (xy 96.367744 -244.670859) (xy 96.315449 -244.686214) (xy 96.261501 -244.69397)
			(xy 96.206999 -244.69397) (xy 96.153051 -244.686214) (xy 96.100756 -244.670859) (xy 96.051179 -244.648217)
			(xy 96.005329 -244.618751) (xy 95.964138 -244.58306) (xy 95.928447 -244.541869) (xy 95.898981 -244.496019)
			(xy 95.876339 -244.446442) (xy 95.860984 -244.394147) (xy 95.853228 -244.340199) (xy 95.852742 -244.312948)
			(xy 95.853254 -244.284991) (xy 95.861448 -244.229679) (xy 95.877611 -244.176151) (xy 95.889064 -244.150642)
			(xy 95.894652 -244.138704) (xy 95.892874 -244.11305) (xy 95.840042 -244.029484) (xy 95.835199 -244.022429)
			(xy 95.821813 -244.011784) (xy 95.805667 -244.006144) (xy 95.797116 -244.005862) (xy 94.376494 -244.005862)
			(xy 94.364759 -244.006382) (xy 94.343689 -244.016703) (xy 94.336108 -244.025674) (xy 94.319359 -244.046584)
			(xy 94.280973 -244.083956) (xy 94.237736 -244.115591) (xy 94.190498 -244.140865) (xy 94.140189 -244.159281)
			(xy 94.087798 -244.170478) (xy 94.034356 -244.174235) (xy 93.980914 -244.170478) (xy 93.928523 -244.159281)
			(xy 93.878214 -244.140865) (xy 93.830976 -244.115591) (xy 93.787739 -244.083956) (xy 93.749353 -244.046584)
			(xy 93.732604 -244.025674) (xy 93.724971 -244.016768) (xy 93.703933 -244.006454) (xy 93.692218 -244.005862)
			(xy 24.77135 -244.005862) (xy 24.761285 -244.006296) (xy 24.7427 -244.01403) (xy 24.735282 -244.020848)
			(xy 23.947882 -244.808248) (xy 93.652338 -244.808248) (xy 93.656409 -244.752626) (xy 93.668535 -244.698189)
			(xy 93.688458 -244.646098) (xy 93.715754 -244.597463) (xy 93.74984 -244.55332) (xy 93.789989 -244.514611)
			(xy 93.835347 -244.48216) (xy 93.884947 -244.456659) (xy 93.937731 -244.438652) (xy 93.992574 -244.428522)
			(xy 94.048308 -244.426485) (xy 94.103745 -244.432585) (xy 94.157702 -244.446691) (xy 94.209031 -244.468503)
			(xy 94.256637 -244.497557) (xy 94.299505 -244.533232) (xy 94.336722 -244.574769) (xy 94.367495 -244.621282)
			(xy 94.391167 -244.671779) (xy 94.407235 -244.725186) (xy 94.415355 -244.780362) (xy 94.415864 -244.808248)
			(xy 94.415355 -244.836134) (xy 94.407235 -244.89131) (xy 94.391167 -244.944717) (xy 94.367495 -244.995214)
			(xy 94.336722 -245.041727) (xy 94.299505 -245.083264) (xy 94.256637 -245.118939) (xy 94.209031 -245.147993)
			(xy 94.157702 -245.169805) (xy 94.103745 -245.183911) (xy 94.048308 -245.190011) (xy 93.992574 -245.187974)
			(xy 93.937731 -245.177844) (xy 93.884947 -245.159837) (xy 93.835347 -245.134336) (xy 93.789989 -245.101885)
			(xy 93.74984 -245.063176) (xy 93.715754 -245.019033) (xy 93.688458 -244.970398) (xy 93.668535 -244.918307)
			(xy 93.656409 -244.86387) (xy 93.652338 -244.808248) (xy 23.947882 -244.808248) (xy 22.931882 -245.824248)
			(xy 93.652338 -245.824248) (xy 93.656409 -245.768626) (xy 93.668535 -245.714189) (xy 93.688458 -245.662098)
			(xy 93.715754 -245.613463) (xy 93.74984 -245.56932) (xy 93.789989 -245.530611) (xy 93.835347 -245.49816)
			(xy 93.884947 -245.472659) (xy 93.937731 -245.454652) (xy 93.992574 -245.444522) (xy 94.048308 -245.442485)
			(xy 94.103745 -245.448585) (xy 94.157702 -245.462691) (xy 94.209031 -245.484503) (xy 94.256637 -245.513557)
			(xy 94.299505 -245.549232) (xy 94.336722 -245.590769) (xy 94.367495 -245.637282) (xy 94.391167 -245.687779)
			(xy 94.407235 -245.741186) (xy 94.415355 -245.796362) (xy 94.415864 -245.824248) (xy 95.865694 -245.824248)
			(xy 95.869765 -245.768626) (xy 95.881891 -245.714189) (xy 95.901814 -245.662098) (xy 95.92911 -245.613463)
			(xy 95.963196 -245.56932) (xy 96.003345 -245.530611) (xy 96.048703 -245.49816) (xy 96.098303 -245.472659)
			(xy 96.151087 -245.454652) (xy 96.20593 -245.444522) (xy 96.261664 -245.442485) (xy 96.317101 -245.448585)
			(xy 96.371058 -245.462691) (xy 96.422387 -245.484503) (xy 96.469993 -245.513557) (xy 96.512861 -245.549232)
			(xy 96.550078 -245.590769) (xy 96.580851 -245.637282) (xy 96.604523 -245.687779) (xy 96.620591 -245.741186)
			(xy 96.628711 -245.796362) (xy 96.62922 -245.824248) (xy 96.628711 -245.852134) (xy 96.620591 -245.90731)
			(xy 96.609282 -245.944898) (xy 100.372416 -245.944898) (xy 100.376487 -245.889276) (xy 100.388613 -245.834839)
			(xy 100.408536 -245.782748) (xy 100.435832 -245.734113) (xy 100.469918 -245.68997) (xy 100.510067 -245.651261)
			(xy 100.555425 -245.61881) (xy 100.605025 -245.593309) (xy 100.657809 -245.575302) (xy 100.712652 -245.565172)
			(xy 100.768386 -245.563135) (xy 100.823823 -245.569235) (xy 100.87778 -245.583341) (xy 100.929109 -245.605153)
			(xy 100.976715 -245.634207) (xy 101.019583 -245.669882) (xy 101.0568 -245.711419) (xy 101.087573 -245.757932)
			(xy 101.111245 -245.808429) (xy 101.127313 -245.861836) (xy 101.135433 -245.917012) (xy 101.135942 -245.944898)
			(xy 101.135433 -245.972784) (xy 101.127313 -246.02796) (xy 101.111245 -246.081367) (xy 101.087573 -246.131864)
			(xy 101.0568 -246.178377) (xy 101.019583 -246.219914) (xy 100.976715 -246.255589) (xy 100.929109 -246.284643)
			(xy 100.87778 -246.306455) (xy 100.823823 -246.320561) (xy 100.768386 -246.326661) (xy 100.712652 -246.324624)
			(xy 100.657809 -246.314494) (xy 100.605025 -246.296487) (xy 100.555425 -246.270986) (xy 100.510067 -246.238535)
			(xy 100.469918 -246.199826) (xy 100.435832 -246.155683) (xy 100.408536 -246.107048) (xy 100.388613 -246.054957)
			(xy 100.376487 -246.00052) (xy 100.372416 -245.944898) (xy 96.609282 -245.944898) (xy 96.604523 -245.960717)
			(xy 96.580851 -246.011214) (xy 96.550078 -246.057727) (xy 96.512861 -246.099264) (xy 96.469993 -246.134939)
			(xy 96.422387 -246.163993) (xy 96.371058 -246.185805) (xy 96.317101 -246.199911) (xy 96.261664 -246.206011)
			(xy 96.20593 -246.203974) (xy 96.151087 -246.193844) (xy 96.098303 -246.175837) (xy 96.048703 -246.150336)
			(xy 96.003345 -246.117885) (xy 95.963196 -246.079176) (xy 95.92911 -246.035033) (xy 95.901814 -245.986398)
			(xy 95.881891 -245.934307) (xy 95.869765 -245.87987) (xy 95.865694 -245.824248) (xy 94.415864 -245.824248)
			(xy 94.415355 -245.852134) (xy 94.407235 -245.90731) (xy 94.391167 -245.960717) (xy 94.367495 -246.011214)
			(xy 94.336722 -246.057727) (xy 94.299505 -246.099264) (xy 94.256637 -246.134939) (xy 94.209031 -246.163993)
			(xy 94.157702 -246.185805) (xy 94.103745 -246.199911) (xy 94.048308 -246.206011) (xy 93.992574 -246.203974)
			(xy 93.937731 -246.193844) (xy 93.884947 -246.175837) (xy 93.835347 -246.150336) (xy 93.789989 -246.117885)
			(xy 93.74984 -246.079176) (xy 93.715754 -246.035033) (xy 93.688458 -245.986398) (xy 93.668535 -245.934307)
			(xy 93.656409 -245.87987) (xy 93.652338 -245.824248) (xy 22.931882 -245.824248) (xy 22.186646 -246.569484)
			(xy 22.179808 -246.576885) (xy 22.172097 -246.595484) (xy 22.17166 -246.605552) (xy 22.17166 -246.840248)
			(xy 93.652338 -246.840248) (xy 93.656409 -246.784626) (xy 93.668535 -246.730189) (xy 93.688458 -246.678098)
			(xy 93.715754 -246.629463) (xy 93.74984 -246.58532) (xy 93.789989 -246.546611) (xy 93.835347 -246.51416)
			(xy 93.884947 -246.488659) (xy 93.937731 -246.470652) (xy 93.992574 -246.460522) (xy 94.048308 -246.458485)
			(xy 94.103745 -246.464585) (xy 94.157702 -246.478691) (xy 94.209031 -246.500503) (xy 94.256637 -246.529557)
			(xy 94.299505 -246.565232) (xy 94.336722 -246.606769) (xy 94.367495 -246.653282) (xy 94.391167 -246.703779)
			(xy 94.407235 -246.757186) (xy 94.415355 -246.812362) (xy 94.415716 -246.83212) (xy 99.693474 -246.83212)
			(xy 99.697545 -246.776498) (xy 99.709671 -246.722061) (xy 99.729594 -246.66997) (xy 99.75689 -246.621335)
			(xy 99.790976 -246.577192) (xy 99.831125 -246.538483) (xy 99.876483 -246.506032) (xy 99.926083 -246.480531)
			(xy 99.978867 -246.462524) (xy 100.03371 -246.452394) (xy 100.089444 -246.450357) (xy 100.144881 -246.456457)
			(xy 100.198838 -246.470563) (xy 100.250167 -246.492375) (xy 100.297773 -246.521429) (xy 100.340641 -246.557104)
			(xy 100.377858 -246.598641) (xy 100.408631 -246.645154) (xy 100.432303 -246.695651) (xy 100.448371 -246.749058)
			(xy 100.456491 -246.804234) (xy 100.457 -246.83212) (xy 100.456491 -246.860006) (xy 100.448371 -246.915182)
			(xy 100.432303 -246.968589) (xy 100.408631 -247.019086) (xy 100.377858 -247.065599) (xy 100.340641 -247.107136)
			(xy 100.297773 -247.142811) (xy 100.250167 -247.171865) (xy 100.198838 -247.193677) (xy 100.144881 -247.207783)
			(xy 100.089444 -247.213883) (xy 100.03371 -247.211846) (xy 99.978867 -247.201716) (xy 99.926083 -247.183709)
			(xy 99.876483 -247.158208) (xy 99.831125 -247.125757) (xy 99.790976 -247.087048) (xy 99.75689 -247.042905)
			(xy 99.729594 -246.99427) (xy 99.709671 -246.942179) (xy 99.697545 -246.887742) (xy 99.693474 -246.83212)
			(xy 94.415716 -246.83212) (xy 94.415864 -246.840248) (xy 94.415355 -246.868134) (xy 94.407235 -246.92331)
			(xy 94.391167 -246.976717) (xy 94.367495 -247.027214) (xy 94.336722 -247.073727) (xy 94.299505 -247.115264)
			(xy 94.256637 -247.150939) (xy 94.209031 -247.179993) (xy 94.157702 -247.201805) (xy 94.103745 -247.215911)
			(xy 94.048308 -247.222011) (xy 93.992574 -247.219974) (xy 93.937731 -247.209844) (xy 93.884947 -247.191837)
			(xy 93.835347 -247.166336) (xy 93.789989 -247.133885) (xy 93.74984 -247.095176) (xy 93.715754 -247.051033)
			(xy 93.688458 -247.002398) (xy 93.668535 -246.950307) (xy 93.656409 -246.89587) (xy 93.652338 -246.840248)
			(xy 22.17166 -246.840248) (xy 22.17166 -251.158502) (xy 23.960326 -251.158502) (xy 23.964397 -251.10288)
			(xy 23.976523 -251.048443) (xy 23.996446 -250.996352) (xy 24.023742 -250.947717) (xy 24.057828 -250.903574)
			(xy 24.097977 -250.864865) (xy 24.143335 -250.832414) (xy 24.192935 -250.806913) (xy 24.245719 -250.788906)
			(xy 24.300562 -250.778776) (xy 24.356296 -250.776739) (xy 24.411733 -250.782839) (xy 24.46569 -250.796945)
			(xy 24.517019 -250.818757) (xy 24.564625 -250.847811) (xy 24.607493 -250.883486) (xy 24.64471 -250.925023)
			(xy 24.675483 -250.971536) (xy 24.699155 -251.022033) (xy 24.715223 -251.07544) (xy 24.723343 -251.130616)
			(xy 24.723792 -251.1552) (xy 25.068782 -251.1552) (xy 25.072853 -251.099578) (xy 25.084979 -251.045141)
			(xy 25.104902 -250.99305) (xy 25.132198 -250.944415) (xy 25.166284 -250.900272) (xy 25.206433 -250.861563)
			(xy 25.251791 -250.829112) (xy 25.301391 -250.803611) (xy 25.354175 -250.785604) (xy 25.409018 -250.775474)
			(xy 25.464752 -250.773437) (xy 25.520189 -250.779537) (xy 25.574146 -250.793643) (xy 25.625475 -250.815455)
			(xy 25.673081 -250.844509) (xy 25.715949 -250.880184) (xy 25.753166 -250.921721) (xy 25.783939 -250.968234)
			(xy 25.807611 -251.018731) (xy 25.823679 -251.072138) (xy 25.831799 -251.127314) (xy 25.832308 -251.1552)
			(xy 25.832248 -251.158502) (xy 25.992326 -251.158502) (xy 25.996397 -251.10288) (xy 26.008523 -251.048443)
			(xy 26.028446 -250.996352) (xy 26.055742 -250.947717) (xy 26.089828 -250.903574) (xy 26.129977 -250.864865)
			(xy 26.175335 -250.832414) (xy 26.224935 -250.806913) (xy 26.277719 -250.788906) (xy 26.332562 -250.778776)
			(xy 26.388296 -250.776739) (xy 26.443733 -250.782839) (xy 26.49769 -250.796945) (xy 26.549019 -250.818757)
			(xy 26.596625 -250.847811) (xy 26.639493 -250.883486) (xy 26.67671 -250.925023) (xy 26.707483 -250.971536)
			(xy 26.731155 -251.022033) (xy 26.747223 -251.07544) (xy 26.755343 -251.130616) (xy 26.755852 -251.158502)
			(xy 27.008326 -251.158502) (xy 27.012397 -251.10288) (xy 27.024523 -251.048443) (xy 27.044446 -250.996352)
			(xy 27.071742 -250.947717) (xy 27.105828 -250.903574) (xy 27.145977 -250.864865) (xy 27.191335 -250.832414)
			(xy 27.240935 -250.806913) (xy 27.293719 -250.788906) (xy 27.348562 -250.778776) (xy 27.404296 -250.776739)
			(xy 27.459733 -250.782839) (xy 27.51369 -250.796945) (xy 27.565019 -250.818757) (xy 27.612625 -250.847811)
			(xy 27.655493 -250.883486) (xy 27.69271 -250.925023) (xy 27.723483 -250.971536) (xy 27.747155 -251.022033)
			(xy 27.763223 -251.07544) (xy 27.771343 -251.130616) (xy 27.771852 -251.158502) (xy 28.024326 -251.158502)
			(xy 28.028397 -251.10288) (xy 28.040523 -251.048443) (xy 28.060446 -250.996352) (xy 28.087742 -250.947717)
			(xy 28.121828 -250.903574) (xy 28.161977 -250.864865) (xy 28.207335 -250.832414) (xy 28.256935 -250.806913)
			(xy 28.309719 -250.788906) (xy 28.364562 -250.778776) (xy 28.420296 -250.776739) (xy 28.475733 -250.782839)
			(xy 28.52969 -250.796945) (xy 28.581019 -250.818757) (xy 28.628625 -250.847811) (xy 28.671493 -250.883486)
			(xy 28.70871 -250.925023) (xy 28.739483 -250.971536) (xy 28.763155 -251.022033) (xy 28.779223 -251.07544)
			(xy 28.787343 -251.130616) (xy 28.787852 -251.158502) (xy 29.040326 -251.158502) (xy 29.044397 -251.10288)
			(xy 29.056523 -251.048443) (xy 29.076446 -250.996352) (xy 29.103742 -250.947717) (xy 29.137828 -250.903574)
			(xy 29.177977 -250.864865) (xy 29.223335 -250.832414) (xy 29.272935 -250.806913) (xy 29.325719 -250.788906)
			(xy 29.380562 -250.778776) (xy 29.436296 -250.776739) (xy 29.491733 -250.782839) (xy 29.54569 -250.796945)
			(xy 29.597019 -250.818757) (xy 29.644625 -250.847811) (xy 29.687493 -250.883486) (xy 29.72471 -250.925023)
			(xy 29.755483 -250.971536) (xy 29.779155 -251.022033) (xy 29.795223 -251.07544) (xy 29.803343 -251.130616)
			(xy 29.803852 -251.158502) (xy 30.056326 -251.158502) (xy 30.060397 -251.10288) (xy 30.072523 -251.048443)
			(xy 30.092446 -250.996352) (xy 30.119742 -250.947717) (xy 30.153828 -250.903574) (xy 30.193977 -250.864865)
			(xy 30.239335 -250.832414) (xy 30.288935 -250.806913) (xy 30.341719 -250.788906) (xy 30.396562 -250.778776)
			(xy 30.452296 -250.776739) (xy 30.507733 -250.782839) (xy 30.56169 -250.796945) (xy 30.613019 -250.818757)
			(xy 30.660625 -250.847811) (xy 30.703493 -250.883486) (xy 30.74071 -250.925023) (xy 30.771483 -250.971536)
			(xy 30.795155 -251.022033) (xy 30.811223 -251.07544) (xy 30.819343 -251.130616) (xy 30.819852 -251.158502)
			(xy 31.072326 -251.158502) (xy 31.076397 -251.10288) (xy 31.088523 -251.048443) (xy 31.108446 -250.996352)
			(xy 31.135742 -250.947717) (xy 31.169828 -250.903574) (xy 31.209977 -250.864865) (xy 31.255335 -250.832414)
			(xy 31.304935 -250.806913) (xy 31.357719 -250.788906) (xy 31.412562 -250.778776) (xy 31.468296 -250.776739)
			(xy 31.523733 -250.782839) (xy 31.57769 -250.796945) (xy 31.629019 -250.818757) (xy 31.676625 -250.847811)
			(xy 31.719493 -250.883486) (xy 31.75671 -250.925023) (xy 31.787483 -250.971536) (xy 31.811155 -251.022033)
			(xy 31.827223 -251.07544) (xy 31.835343 -251.130616) (xy 31.835852 -251.158502) (xy 32.088326 -251.158502)
			(xy 32.092397 -251.10288) (xy 32.104523 -251.048443) (xy 32.124446 -250.996352) (xy 32.151742 -250.947717)
			(xy 32.185828 -250.903574) (xy 32.225977 -250.864865) (xy 32.271335 -250.832414) (xy 32.320935 -250.806913)
			(xy 32.373719 -250.788906) (xy 32.428562 -250.778776) (xy 32.484296 -250.776739) (xy 32.539733 -250.782839)
			(xy 32.59369 -250.796945) (xy 32.645019 -250.818757) (xy 32.692625 -250.847811) (xy 32.735493 -250.883486)
			(xy 32.77271 -250.925023) (xy 32.803483 -250.971536) (xy 32.827155 -251.022033) (xy 32.843223 -251.07544)
			(xy 32.851343 -251.130616) (xy 32.851852 -251.158502) (xy 33.104326 -251.158502) (xy 33.108397 -251.10288)
			(xy 33.120523 -251.048443) (xy 33.140446 -250.996352) (xy 33.167742 -250.947717) (xy 33.201828 -250.903574)
			(xy 33.241977 -250.864865) (xy 33.287335 -250.832414) (xy 33.336935 -250.806913) (xy 33.389719 -250.788906)
			(xy 33.444562 -250.778776) (xy 33.500296 -250.776739) (xy 33.555733 -250.782839) (xy 33.60969 -250.796945)
			(xy 33.661019 -250.818757) (xy 33.708625 -250.847811) (xy 33.751493 -250.883486) (xy 33.78871 -250.925023)
			(xy 33.819483 -250.971536) (xy 33.843155 -251.022033) (xy 33.859223 -251.07544) (xy 33.867343 -251.130616)
			(xy 33.867852 -251.158502) (xy 34.120326 -251.158502) (xy 34.124397 -251.10288) (xy 34.136523 -251.048443)
			(xy 34.156446 -250.996352) (xy 34.183742 -250.947717) (xy 34.217828 -250.903574) (xy 34.257977 -250.864865)
			(xy 34.303335 -250.832414) (xy 34.352935 -250.806913) (xy 34.405719 -250.788906) (xy 34.460562 -250.778776)
			(xy 34.516296 -250.776739) (xy 34.571733 -250.782839) (xy 34.62569 -250.796945) (xy 34.677019 -250.818757)
			(xy 34.724625 -250.847811) (xy 34.767493 -250.883486) (xy 34.80471 -250.925023) (xy 34.835483 -250.971536)
			(xy 34.859155 -251.022033) (xy 34.875223 -251.07544) (xy 34.883343 -251.130616) (xy 34.883852 -251.158502)
			(xy 35.136326 -251.158502) (xy 35.140397 -251.10288) (xy 35.152523 -251.048443) (xy 35.172446 -250.996352)
			(xy 35.199742 -250.947717) (xy 35.233828 -250.903574) (xy 35.273977 -250.864865) (xy 35.319335 -250.832414)
			(xy 35.368935 -250.806913) (xy 35.421719 -250.788906) (xy 35.476562 -250.778776) (xy 35.532296 -250.776739)
			(xy 35.587733 -250.782839) (xy 35.64169 -250.796945) (xy 35.693019 -250.818757) (xy 35.740625 -250.847811)
			(xy 35.783493 -250.883486) (xy 35.82071 -250.925023) (xy 35.851483 -250.971536) (xy 35.875155 -251.022033)
			(xy 35.891223 -251.07544) (xy 35.899343 -251.130616) (xy 35.899852 -251.158502) (xy 36.152326 -251.158502)
			(xy 36.156397 -251.10288) (xy 36.168523 -251.048443) (xy 36.188446 -250.996352) (xy 36.215742 -250.947717)
			(xy 36.249828 -250.903574) (xy 36.289977 -250.864865) (xy 36.335335 -250.832414) (xy 36.384935 -250.806913)
			(xy 36.437719 -250.788906) (xy 36.492562 -250.778776) (xy 36.548296 -250.776739) (xy 36.603733 -250.782839)
			(xy 36.65769 -250.796945) (xy 36.709019 -250.818757) (xy 36.756625 -250.847811) (xy 36.799493 -250.883486)
			(xy 36.83671 -250.925023) (xy 36.867483 -250.971536) (xy 36.891155 -251.022033) (xy 36.907223 -251.07544)
			(xy 36.915343 -251.130616) (xy 36.915852 -251.158502) (xy 37.168326 -251.158502) (xy 37.172397 -251.10288)
			(xy 37.184523 -251.048443) (xy 37.204446 -250.996352) (xy 37.231742 -250.947717) (xy 37.265828 -250.903574)
			(xy 37.305977 -250.864865) (xy 37.351335 -250.832414) (xy 37.400935 -250.806913) (xy 37.453719 -250.788906)
			(xy 37.508562 -250.778776) (xy 37.564296 -250.776739) (xy 37.619733 -250.782839) (xy 37.67369 -250.796945)
			(xy 37.725019 -250.818757) (xy 37.772625 -250.847811) (xy 37.815493 -250.883486) (xy 37.85271 -250.925023)
			(xy 37.883483 -250.971536) (xy 37.907155 -251.022033) (xy 37.923223 -251.07544) (xy 37.931343 -251.130616)
			(xy 37.931852 -251.158502) (xy 38.184326 -251.158502) (xy 38.188397 -251.10288) (xy 38.200523 -251.048443)
			(xy 38.220446 -250.996352) (xy 38.247742 -250.947717) (xy 38.281828 -250.903574) (xy 38.321977 -250.864865)
			(xy 38.367335 -250.832414) (xy 38.416935 -250.806913) (xy 38.469719 -250.788906) (xy 38.524562 -250.778776)
			(xy 38.580296 -250.776739) (xy 38.635733 -250.782839) (xy 38.68969 -250.796945) (xy 38.741019 -250.818757)
			(xy 38.788625 -250.847811) (xy 38.831493 -250.883486) (xy 38.86871 -250.925023) (xy 38.899483 -250.971536)
			(xy 38.923155 -251.022033) (xy 38.939223 -251.07544) (xy 38.947343 -251.130616) (xy 38.947852 -251.158502)
			(xy 40.216326 -251.158502) (xy 40.220397 -251.10288) (xy 40.232523 -251.048443) (xy 40.252446 -250.996352)
			(xy 40.279742 -250.947717) (xy 40.313828 -250.903574) (xy 40.353977 -250.864865) (xy 40.399335 -250.832414)
			(xy 40.448935 -250.806913) (xy 40.501719 -250.788906) (xy 40.556562 -250.778776) (xy 40.612296 -250.776739)
			(xy 40.667733 -250.782839) (xy 40.72169 -250.796945) (xy 40.773019 -250.818757) (xy 40.820625 -250.847811)
			(xy 40.863493 -250.883486) (xy 40.90071 -250.925023) (xy 40.931483 -250.971536) (xy 40.955155 -251.022033)
			(xy 40.971223 -251.07544) (xy 40.979343 -251.130616) (xy 40.979852 -251.158502) (xy 40.979343 -251.186388)
			(xy 40.971223 -251.241564) (xy 40.955155 -251.294971) (xy 40.931483 -251.345468) (xy 40.90071 -251.391981)
			(xy 40.863493 -251.433518) (xy 40.820625 -251.469193) (xy 40.773019 -251.498247) (xy 40.72169 -251.520059)
			(xy 40.667733 -251.534165) (xy 40.612296 -251.540265) (xy 40.556562 -251.538228) (xy 40.501719 -251.528098)
			(xy 40.448935 -251.510091) (xy 40.399335 -251.48459) (xy 40.353977 -251.452139) (xy 40.313828 -251.41343)
			(xy 40.279742 -251.369287) (xy 40.252446 -251.320652) (xy 40.232523 -251.268561) (xy 40.220397 -251.214124)
			(xy 40.216326 -251.158502) (xy 38.947852 -251.158502) (xy 38.947343 -251.186388) (xy 38.939223 -251.241564)
			(xy 38.923155 -251.294971) (xy 38.899483 -251.345468) (xy 38.86871 -251.391981) (xy 38.831493 -251.433518)
			(xy 38.788625 -251.469193) (xy 38.741019 -251.498247) (xy 38.68969 -251.520059) (xy 38.635733 -251.534165)
			(xy 38.580296 -251.540265) (xy 38.524562 -251.538228) (xy 38.469719 -251.528098) (xy 38.416935 -251.510091)
			(xy 38.367335 -251.48459) (xy 38.321977 -251.452139) (xy 38.281828 -251.41343) (xy 38.247742 -251.369287)
			(xy 38.220446 -251.320652) (xy 38.200523 -251.268561) (xy 38.188397 -251.214124) (xy 38.184326 -251.158502)
			(xy 37.931852 -251.158502) (xy 37.931343 -251.186388) (xy 37.923223 -251.241564) (xy 37.907155 -251.294971)
			(xy 37.883483 -251.345468) (xy 37.85271 -251.391981) (xy 37.815493 -251.433518) (xy 37.772625 -251.469193)
			(xy 37.725019 -251.498247) (xy 37.67369 -251.520059) (xy 37.619733 -251.534165) (xy 37.564296 -251.540265)
			(xy 37.508562 -251.538228) (xy 37.453719 -251.528098) (xy 37.400935 -251.510091) (xy 37.351335 -251.48459)
			(xy 37.305977 -251.452139) (xy 37.265828 -251.41343) (xy 37.231742 -251.369287) (xy 37.204446 -251.320652)
			(xy 37.184523 -251.268561) (xy 37.172397 -251.214124) (xy 37.168326 -251.158502) (xy 36.915852 -251.158502)
			(xy 36.915343 -251.186388) (xy 36.907223 -251.241564) (xy 36.891155 -251.294971) (xy 36.867483 -251.345468)
			(xy 36.83671 -251.391981) (xy 36.799493 -251.433518) (xy 36.756625 -251.469193) (xy 36.709019 -251.498247)
			(xy 36.65769 -251.520059) (xy 36.603733 -251.534165) (xy 36.548296 -251.540265) (xy 36.492562 -251.538228)
			(xy 36.437719 -251.528098) (xy 36.384935 -251.510091) (xy 36.335335 -251.48459) (xy 36.289977 -251.452139)
			(xy 36.249828 -251.41343) (xy 36.215742 -251.369287) (xy 36.188446 -251.320652) (xy 36.168523 -251.268561)
			(xy 36.156397 -251.214124) (xy 36.152326 -251.158502) (xy 35.899852 -251.158502) (xy 35.899343 -251.186388)
			(xy 35.891223 -251.241564) (xy 35.875155 -251.294971) (xy 35.851483 -251.345468) (xy 35.82071 -251.391981)
			(xy 35.783493 -251.433518) (xy 35.740625 -251.469193) (xy 35.693019 -251.498247) (xy 35.64169 -251.520059)
			(xy 35.587733 -251.534165) (xy 35.532296 -251.540265) (xy 35.476562 -251.538228) (xy 35.421719 -251.528098)
			(xy 35.368935 -251.510091) (xy 35.319335 -251.48459) (xy 35.273977 -251.452139) (xy 35.233828 -251.41343)
			(xy 35.199742 -251.369287) (xy 35.172446 -251.320652) (xy 35.152523 -251.268561) (xy 35.140397 -251.214124)
			(xy 35.136326 -251.158502) (xy 34.883852 -251.158502) (xy 34.883343 -251.186388) (xy 34.875223 -251.241564)
			(xy 34.859155 -251.294971) (xy 34.835483 -251.345468) (xy 34.80471 -251.391981) (xy 34.767493 -251.433518)
			(xy 34.724625 -251.469193) (xy 34.677019 -251.498247) (xy 34.62569 -251.520059) (xy 34.571733 -251.534165)
			(xy 34.516296 -251.540265) (xy 34.460562 -251.538228) (xy 34.405719 -251.528098) (xy 34.352935 -251.510091)
			(xy 34.303335 -251.48459) (xy 34.257977 -251.452139) (xy 34.217828 -251.41343) (xy 34.183742 -251.369287)
			(xy 34.156446 -251.320652) (xy 34.136523 -251.268561) (xy 34.124397 -251.214124) (xy 34.120326 -251.158502)
			(xy 33.867852 -251.158502) (xy 33.867343 -251.186388) (xy 33.859223 -251.241564) (xy 33.843155 -251.294971)
			(xy 33.819483 -251.345468) (xy 33.78871 -251.391981) (xy 33.751493 -251.433518) (xy 33.708625 -251.469193)
			(xy 33.661019 -251.498247) (xy 33.60969 -251.520059) (xy 33.555733 -251.534165) (xy 33.500296 -251.540265)
			(xy 33.444562 -251.538228) (xy 33.389719 -251.528098) (xy 33.336935 -251.510091) (xy 33.287335 -251.48459)
			(xy 33.241977 -251.452139) (xy 33.201828 -251.41343) (xy 33.167742 -251.369287) (xy 33.140446 -251.320652)
			(xy 33.120523 -251.268561) (xy 33.108397 -251.214124) (xy 33.104326 -251.158502) (xy 32.851852 -251.158502)
			(xy 32.851343 -251.186388) (xy 32.843223 -251.241564) (xy 32.827155 -251.294971) (xy 32.803483 -251.345468)
			(xy 32.77271 -251.391981) (xy 32.735493 -251.433518) (xy 32.692625 -251.469193) (xy 32.645019 -251.498247)
			(xy 32.59369 -251.520059) (xy 32.539733 -251.534165) (xy 32.484296 -251.540265) (xy 32.428562 -251.538228)
			(xy 32.373719 -251.528098) (xy 32.320935 -251.510091) (xy 32.271335 -251.48459) (xy 32.225977 -251.452139)
			(xy 32.185828 -251.41343) (xy 32.151742 -251.369287) (xy 32.124446 -251.320652) (xy 32.104523 -251.268561)
			(xy 32.092397 -251.214124) (xy 32.088326 -251.158502) (xy 31.835852 -251.158502) (xy 31.835343 -251.186388)
			(xy 31.827223 -251.241564) (xy 31.811155 -251.294971) (xy 31.787483 -251.345468) (xy 31.75671 -251.391981)
			(xy 31.719493 -251.433518) (xy 31.676625 -251.469193) (xy 31.629019 -251.498247) (xy 31.57769 -251.520059)
			(xy 31.523733 -251.534165) (xy 31.468296 -251.540265) (xy 31.412562 -251.538228) (xy 31.357719 -251.528098)
			(xy 31.304935 -251.510091) (xy 31.255335 -251.48459) (xy 31.209977 -251.452139) (xy 31.169828 -251.41343)
			(xy 31.135742 -251.369287) (xy 31.108446 -251.320652) (xy 31.088523 -251.268561) (xy 31.076397 -251.214124)
			(xy 31.072326 -251.158502) (xy 30.819852 -251.158502) (xy 30.819343 -251.186388) (xy 30.811223 -251.241564)
			(xy 30.795155 -251.294971) (xy 30.771483 -251.345468) (xy 30.74071 -251.391981) (xy 30.703493 -251.433518)
			(xy 30.660625 -251.469193) (xy 30.613019 -251.498247) (xy 30.56169 -251.520059) (xy 30.507733 -251.534165)
			(xy 30.452296 -251.540265) (xy 30.396562 -251.538228) (xy 30.341719 -251.528098) (xy 30.288935 -251.510091)
			(xy 30.239335 -251.48459) (xy 30.193977 -251.452139) (xy 30.153828 -251.41343) (xy 30.119742 -251.369287)
			(xy 30.092446 -251.320652) (xy 30.072523 -251.268561) (xy 30.060397 -251.214124) (xy 30.056326 -251.158502)
			(xy 29.803852 -251.158502) (xy 29.803343 -251.186388) (xy 29.795223 -251.241564) (xy 29.779155 -251.294971)
			(xy 29.755483 -251.345468) (xy 29.72471 -251.391981) (xy 29.687493 -251.433518) (xy 29.644625 -251.469193)
			(xy 29.597019 -251.498247) (xy 29.54569 -251.520059) (xy 29.491733 -251.534165) (xy 29.436296 -251.540265)
			(xy 29.380562 -251.538228) (xy 29.325719 -251.528098) (xy 29.272935 -251.510091) (xy 29.223335 -251.48459)
			(xy 29.177977 -251.452139) (xy 29.137828 -251.41343) (xy 29.103742 -251.369287) (xy 29.076446 -251.320652)
			(xy 29.056523 -251.268561) (xy 29.044397 -251.214124) (xy 29.040326 -251.158502) (xy 28.787852 -251.158502)
			(xy 28.787343 -251.186388) (xy 28.779223 -251.241564) (xy 28.763155 -251.294971) (xy 28.739483 -251.345468)
			(xy 28.70871 -251.391981) (xy 28.671493 -251.433518) (xy 28.628625 -251.469193) (xy 28.581019 -251.498247)
			(xy 28.52969 -251.520059) (xy 28.475733 -251.534165) (xy 28.420296 -251.540265) (xy 28.364562 -251.538228)
			(xy 28.309719 -251.528098) (xy 28.256935 -251.510091) (xy 28.207335 -251.48459) (xy 28.161977 -251.452139)
			(xy 28.121828 -251.41343) (xy 28.087742 -251.369287) (xy 28.060446 -251.320652) (xy 28.040523 -251.268561)
			(xy 28.028397 -251.214124) (xy 28.024326 -251.158502) (xy 27.771852 -251.158502) (xy 27.771343 -251.186388)
			(xy 27.763223 -251.241564) (xy 27.747155 -251.294971) (xy 27.723483 -251.345468) (xy 27.69271 -251.391981)
			(xy 27.655493 -251.433518) (xy 27.612625 -251.469193) (xy 27.565019 -251.498247) (xy 27.51369 -251.520059)
			(xy 27.459733 -251.534165) (xy 27.404296 -251.540265) (xy 27.348562 -251.538228) (xy 27.293719 -251.528098)
			(xy 27.240935 -251.510091) (xy 27.191335 -251.48459) (xy 27.145977 -251.452139) (xy 27.105828 -251.41343)
			(xy 27.071742 -251.369287) (xy 27.044446 -251.320652) (xy 27.024523 -251.268561) (xy 27.012397 -251.214124)
			(xy 27.008326 -251.158502) (xy 26.755852 -251.158502) (xy 26.755343 -251.186388) (xy 26.747223 -251.241564)
			(xy 26.731155 -251.294971) (xy 26.707483 -251.345468) (xy 26.67671 -251.391981) (xy 26.639493 -251.433518)
			(xy 26.596625 -251.469193) (xy 26.549019 -251.498247) (xy 26.49769 -251.520059) (xy 26.443733 -251.534165)
			(xy 26.388296 -251.540265) (xy 26.332562 -251.538228) (xy 26.277719 -251.528098) (xy 26.224935 -251.510091)
			(xy 26.175335 -251.48459) (xy 26.129977 -251.452139) (xy 26.089828 -251.41343) (xy 26.055742 -251.369287)
			(xy 26.028446 -251.320652) (xy 26.008523 -251.268561) (xy 25.996397 -251.214124) (xy 25.992326 -251.158502)
			(xy 25.832248 -251.158502) (xy 25.831799 -251.183086) (xy 25.823679 -251.238262) (xy 25.807611 -251.291669)
			(xy 25.783939 -251.342166) (xy 25.753166 -251.388679) (xy 25.715949 -251.430216) (xy 25.673081 -251.465891)
			(xy 25.625475 -251.494945) (xy 25.574146 -251.516757) (xy 25.520189 -251.530863) (xy 25.464752 -251.536963)
			(xy 25.409018 -251.534926) (xy 25.354175 -251.524796) (xy 25.301391 -251.506789) (xy 25.251791 -251.481288)
			(xy 25.206433 -251.448837) (xy 25.166284 -251.410128) (xy 25.132198 -251.365985) (xy 25.104902 -251.31735)
			(xy 25.084979 -251.265259) (xy 25.072853 -251.210822) (xy 25.068782 -251.1552) (xy 24.723792 -251.1552)
			(xy 24.723852 -251.158502) (xy 24.723343 -251.186388) (xy 24.715223 -251.241564) (xy 24.699155 -251.294971)
			(xy 24.675483 -251.345468) (xy 24.64471 -251.391981) (xy 24.607493 -251.433518) (xy 24.564625 -251.469193)
			(xy 24.517019 -251.498247) (xy 24.46569 -251.520059) (xy 24.411733 -251.534165) (xy 24.356296 -251.540265)
			(xy 24.300562 -251.538228) (xy 24.245719 -251.528098) (xy 24.192935 -251.510091) (xy 24.143335 -251.48459)
			(xy 24.097977 -251.452139) (xy 24.057828 -251.41343) (xy 24.023742 -251.369287) (xy 23.996446 -251.320652)
			(xy 23.976523 -251.268561) (xy 23.964397 -251.214124) (xy 23.960326 -251.158502) (xy 22.17166 -251.158502)
			(xy 22.17166 -253.45644) (xy 23.960326 -253.45644) (xy 23.964397 -253.400818) (xy 23.976523 -253.346381)
			(xy 23.996446 -253.29429) (xy 24.023742 -253.245655) (xy 24.057828 -253.201512) (xy 24.097977 -253.162803)
			(xy 24.143335 -253.130352) (xy 24.192935 -253.104851) (xy 24.245719 -253.086844) (xy 24.300562 -253.076714)
			(xy 24.356296 -253.074677) (xy 24.411733 -253.080777) (xy 24.46569 -253.094883) (xy 24.517019 -253.116695)
			(xy 24.564625 -253.145749) (xy 24.607493 -253.181424) (xy 24.64471 -253.222961) (xy 24.675483 -253.269474)
			(xy 24.699155 -253.319971) (xy 24.715223 -253.373378) (xy 24.723343 -253.428554) (xy 24.723852 -253.45644)
			(xy 24.976326 -253.45644) (xy 24.980397 -253.400818) (xy 24.992523 -253.346381) (xy 25.012446 -253.29429)
			(xy 25.039742 -253.245655) (xy 25.073828 -253.201512) (xy 25.113977 -253.162803) (xy 25.159335 -253.130352)
			(xy 25.208935 -253.104851) (xy 25.261719 -253.086844) (xy 25.316562 -253.076714) (xy 25.372296 -253.074677)
			(xy 25.427733 -253.080777) (xy 25.48169 -253.094883) (xy 25.533019 -253.116695) (xy 25.580625 -253.145749)
			(xy 25.623493 -253.181424) (xy 25.66071 -253.222961) (xy 25.691483 -253.269474) (xy 25.715155 -253.319971)
			(xy 25.731223 -253.373378) (xy 25.739343 -253.428554) (xy 25.739852 -253.45644) (xy 25.992326 -253.45644)
			(xy 25.996397 -253.400818) (xy 26.008523 -253.346381) (xy 26.028446 -253.29429) (xy 26.055742 -253.245655)
			(xy 26.089828 -253.201512) (xy 26.129977 -253.162803) (xy 26.175335 -253.130352) (xy 26.224935 -253.104851)
			(xy 26.277719 -253.086844) (xy 26.332562 -253.076714) (xy 26.388296 -253.074677) (xy 26.443733 -253.080777)
			(xy 26.49769 -253.094883) (xy 26.549019 -253.116695) (xy 26.596625 -253.145749) (xy 26.639493 -253.181424)
			(xy 26.67671 -253.222961) (xy 26.707483 -253.269474) (xy 26.731155 -253.319971) (xy 26.747223 -253.373378)
			(xy 26.755343 -253.428554) (xy 26.755852 -253.45644) (xy 27.008326 -253.45644) (xy 27.012397 -253.400818)
			(xy 27.024523 -253.346381) (xy 27.044446 -253.29429) (xy 27.071742 -253.245655) (xy 27.105828 -253.201512)
			(xy 27.145977 -253.162803) (xy 27.191335 -253.130352) (xy 27.240935 -253.104851) (xy 27.293719 -253.086844)
			(xy 27.348562 -253.076714) (xy 27.404296 -253.074677) (xy 27.459733 -253.080777) (xy 27.51369 -253.094883)
			(xy 27.565019 -253.116695) (xy 27.612625 -253.145749) (xy 27.655493 -253.181424) (xy 27.69271 -253.222961)
			(xy 27.723483 -253.269474) (xy 27.747155 -253.319971) (xy 27.763223 -253.373378) (xy 27.771343 -253.428554)
			(xy 27.771852 -253.45644) (xy 28.024326 -253.45644) (xy 28.028397 -253.400818) (xy 28.040523 -253.346381)
			(xy 28.060446 -253.29429) (xy 28.087742 -253.245655) (xy 28.121828 -253.201512) (xy 28.161977 -253.162803)
			(xy 28.207335 -253.130352) (xy 28.256935 -253.104851) (xy 28.309719 -253.086844) (xy 28.364562 -253.076714)
			(xy 28.420296 -253.074677) (xy 28.475733 -253.080777) (xy 28.52969 -253.094883) (xy 28.581019 -253.116695)
			(xy 28.628625 -253.145749) (xy 28.671493 -253.181424) (xy 28.70871 -253.222961) (xy 28.739483 -253.269474)
			(xy 28.763155 -253.319971) (xy 28.779223 -253.373378) (xy 28.787343 -253.428554) (xy 28.787852 -253.45644)
			(xy 29.040326 -253.45644) (xy 29.044397 -253.400818) (xy 29.056523 -253.346381) (xy 29.076446 -253.29429)
			(xy 29.103742 -253.245655) (xy 29.137828 -253.201512) (xy 29.177977 -253.162803) (xy 29.223335 -253.130352)
			(xy 29.272935 -253.104851) (xy 29.325719 -253.086844) (xy 29.380562 -253.076714) (xy 29.436296 -253.074677)
			(xy 29.491733 -253.080777) (xy 29.54569 -253.094883) (xy 29.597019 -253.116695) (xy 29.644625 -253.145749)
			(xy 29.687493 -253.181424) (xy 29.72471 -253.222961) (xy 29.755483 -253.269474) (xy 29.779155 -253.319971)
			(xy 29.795223 -253.373378) (xy 29.803343 -253.428554) (xy 29.803852 -253.45644) (xy 30.056326 -253.45644)
			(xy 30.060397 -253.400818) (xy 30.072523 -253.346381) (xy 30.092446 -253.29429) (xy 30.119742 -253.245655)
			(xy 30.153828 -253.201512) (xy 30.193977 -253.162803) (xy 30.239335 -253.130352) (xy 30.288935 -253.104851)
			(xy 30.341719 -253.086844) (xy 30.396562 -253.076714) (xy 30.452296 -253.074677) (xy 30.507733 -253.080777)
			(xy 30.56169 -253.094883) (xy 30.613019 -253.116695) (xy 30.660625 -253.145749) (xy 30.703493 -253.181424)
			(xy 30.74071 -253.222961) (xy 30.771483 -253.269474) (xy 30.795155 -253.319971) (xy 30.811223 -253.373378)
			(xy 30.819343 -253.428554) (xy 30.819852 -253.45644) (xy 31.072326 -253.45644) (xy 31.076397 -253.400818)
			(xy 31.088523 -253.346381) (xy 31.108446 -253.29429) (xy 31.135742 -253.245655) (xy 31.169828 -253.201512)
			(xy 31.209977 -253.162803) (xy 31.255335 -253.130352) (xy 31.304935 -253.104851) (xy 31.357719 -253.086844)
			(xy 31.412562 -253.076714) (xy 31.468296 -253.074677) (xy 31.523733 -253.080777) (xy 31.57769 -253.094883)
			(xy 31.629019 -253.116695) (xy 31.676625 -253.145749) (xy 31.719493 -253.181424) (xy 31.75671 -253.222961)
			(xy 31.787483 -253.269474) (xy 31.811155 -253.319971) (xy 31.827223 -253.373378) (xy 31.835343 -253.428554)
			(xy 31.835852 -253.45644) (xy 32.088326 -253.45644) (xy 32.092397 -253.400818) (xy 32.104523 -253.346381)
			(xy 32.124446 -253.29429) (xy 32.151742 -253.245655) (xy 32.185828 -253.201512) (xy 32.225977 -253.162803)
			(xy 32.271335 -253.130352) (xy 32.320935 -253.104851) (xy 32.373719 -253.086844) (xy 32.428562 -253.076714)
			(xy 32.484296 -253.074677) (xy 32.539733 -253.080777) (xy 32.59369 -253.094883) (xy 32.645019 -253.116695)
			(xy 32.692625 -253.145749) (xy 32.735493 -253.181424) (xy 32.77271 -253.222961) (xy 32.803483 -253.269474)
			(xy 32.827155 -253.319971) (xy 32.843223 -253.373378) (xy 32.851343 -253.428554) (xy 32.851852 -253.45644)
			(xy 33.104326 -253.45644) (xy 33.108397 -253.400818) (xy 33.120523 -253.346381) (xy 33.140446 -253.29429)
			(xy 33.167742 -253.245655) (xy 33.201828 -253.201512) (xy 33.241977 -253.162803) (xy 33.287335 -253.130352)
			(xy 33.336935 -253.104851) (xy 33.389719 -253.086844) (xy 33.444562 -253.076714) (xy 33.500296 -253.074677)
			(xy 33.555733 -253.080777) (xy 33.60969 -253.094883) (xy 33.661019 -253.116695) (xy 33.708625 -253.145749)
			(xy 33.751493 -253.181424) (xy 33.78871 -253.222961) (xy 33.819483 -253.269474) (xy 33.843155 -253.319971)
			(xy 33.859223 -253.373378) (xy 33.867343 -253.428554) (xy 33.867852 -253.45644) (xy 34.120326 -253.45644)
			(xy 34.124397 -253.400818) (xy 34.136523 -253.346381) (xy 34.156446 -253.29429) (xy 34.183742 -253.245655)
			(xy 34.217828 -253.201512) (xy 34.257977 -253.162803) (xy 34.303335 -253.130352) (xy 34.352935 -253.104851)
			(xy 34.405719 -253.086844) (xy 34.460562 -253.076714) (xy 34.516296 -253.074677) (xy 34.571733 -253.080777)
			(xy 34.62569 -253.094883) (xy 34.677019 -253.116695) (xy 34.724625 -253.145749) (xy 34.767493 -253.181424)
			(xy 34.80471 -253.222961) (xy 34.835483 -253.269474) (xy 34.859155 -253.319971) (xy 34.875223 -253.373378)
			(xy 34.883343 -253.428554) (xy 34.883852 -253.45644) (xy 35.136326 -253.45644) (xy 35.140397 -253.400818)
			(xy 35.152523 -253.346381) (xy 35.172446 -253.29429) (xy 35.199742 -253.245655) (xy 35.233828 -253.201512)
			(xy 35.273977 -253.162803) (xy 35.319335 -253.130352) (xy 35.368935 -253.104851) (xy 35.421719 -253.086844)
			(xy 35.476562 -253.076714) (xy 35.532296 -253.074677) (xy 35.587733 -253.080777) (xy 35.64169 -253.094883)
			(xy 35.693019 -253.116695) (xy 35.740625 -253.145749) (xy 35.783493 -253.181424) (xy 35.82071 -253.222961)
			(xy 35.851483 -253.269474) (xy 35.875155 -253.319971) (xy 35.891223 -253.373378) (xy 35.899343 -253.428554)
			(xy 35.899852 -253.45644) (xy 36.152326 -253.45644) (xy 36.156397 -253.400818) (xy 36.168523 -253.346381)
			(xy 36.188446 -253.29429) (xy 36.215742 -253.245655) (xy 36.249828 -253.201512) (xy 36.289977 -253.162803)
			(xy 36.335335 -253.130352) (xy 36.384935 -253.104851) (xy 36.437719 -253.086844) (xy 36.492562 -253.076714)
			(xy 36.548296 -253.074677) (xy 36.603733 -253.080777) (xy 36.65769 -253.094883) (xy 36.709019 -253.116695)
			(xy 36.756625 -253.145749) (xy 36.799493 -253.181424) (xy 36.83671 -253.222961) (xy 36.867483 -253.269474)
			(xy 36.891155 -253.319971) (xy 36.907223 -253.373378) (xy 36.915343 -253.428554) (xy 36.915852 -253.45644)
			(xy 37.168326 -253.45644) (xy 37.172397 -253.400818) (xy 37.184523 -253.346381) (xy 37.204446 -253.29429)
			(xy 37.231742 -253.245655) (xy 37.265828 -253.201512) (xy 37.305977 -253.162803) (xy 37.351335 -253.130352)
			(xy 37.400935 -253.104851) (xy 37.453719 -253.086844) (xy 37.508562 -253.076714) (xy 37.564296 -253.074677)
			(xy 37.619733 -253.080777) (xy 37.67369 -253.094883) (xy 37.725019 -253.116695) (xy 37.772625 -253.145749)
			(xy 37.815493 -253.181424) (xy 37.85271 -253.222961) (xy 37.883483 -253.269474) (xy 37.907155 -253.319971)
			(xy 37.923223 -253.373378) (xy 37.931343 -253.428554) (xy 37.931852 -253.45644) (xy 38.184326 -253.45644)
			(xy 38.188397 -253.400818) (xy 38.200523 -253.346381) (xy 38.220446 -253.29429) (xy 38.247742 -253.245655)
			(xy 38.281828 -253.201512) (xy 38.321977 -253.162803) (xy 38.367335 -253.130352) (xy 38.416935 -253.104851)
			(xy 38.469719 -253.086844) (xy 38.524562 -253.076714) (xy 38.580296 -253.074677) (xy 38.635733 -253.080777)
			(xy 38.68969 -253.094883) (xy 38.741019 -253.116695) (xy 38.788625 -253.145749) (xy 38.831493 -253.181424)
			(xy 38.86871 -253.222961) (xy 38.899483 -253.269474) (xy 38.923155 -253.319971) (xy 38.939223 -253.373378)
			(xy 38.947343 -253.428554) (xy 38.947852 -253.45644) (xy 39.200326 -253.45644) (xy 39.204397 -253.400818)
			(xy 39.216523 -253.346381) (xy 39.236446 -253.29429) (xy 39.263742 -253.245655) (xy 39.297828 -253.201512)
			(xy 39.337977 -253.162803) (xy 39.383335 -253.130352) (xy 39.432935 -253.104851) (xy 39.485719 -253.086844)
			(xy 39.540562 -253.076714) (xy 39.596296 -253.074677) (xy 39.651733 -253.080777) (xy 39.70569 -253.094883)
			(xy 39.757019 -253.116695) (xy 39.804625 -253.145749) (xy 39.847493 -253.181424) (xy 39.88471 -253.222961)
			(xy 39.915483 -253.269474) (xy 39.939155 -253.319971) (xy 39.955223 -253.373378) (xy 39.963343 -253.428554)
			(xy 39.963852 -253.45644) (xy 40.216326 -253.45644) (xy 40.220397 -253.400818) (xy 40.232523 -253.346381)
			(xy 40.252446 -253.29429) (xy 40.279742 -253.245655) (xy 40.313828 -253.201512) (xy 40.353977 -253.162803)
			(xy 40.399335 -253.130352) (xy 40.448935 -253.104851) (xy 40.501719 -253.086844) (xy 40.556562 -253.076714)
			(xy 40.612296 -253.074677) (xy 40.667733 -253.080777) (xy 40.72169 -253.094883) (xy 40.773019 -253.116695)
			(xy 40.820625 -253.145749) (xy 40.863493 -253.181424) (xy 40.90071 -253.222961) (xy 40.931483 -253.269474)
			(xy 40.955155 -253.319971) (xy 40.971223 -253.373378) (xy 40.979343 -253.428554) (xy 40.979852 -253.45644)
			(xy 40.979343 -253.484326) (xy 40.971223 -253.539502) (xy 40.955155 -253.592909) (xy 40.931483 -253.643406)
			(xy 40.90071 -253.689919) (xy 40.863493 -253.731456) (xy 40.820625 -253.767131) (xy 40.773019 -253.796185)
			(xy 40.72169 -253.817997) (xy 40.667733 -253.832103) (xy 40.612296 -253.838203) (xy 40.556562 -253.836166)
			(xy 40.501719 -253.826036) (xy 40.448935 -253.808029) (xy 40.399335 -253.782528) (xy 40.353977 -253.750077)
			(xy 40.313828 -253.711368) (xy 40.279742 -253.667225) (xy 40.252446 -253.61859) (xy 40.232523 -253.566499)
			(xy 40.220397 -253.512062) (xy 40.216326 -253.45644) (xy 39.963852 -253.45644) (xy 39.963343 -253.484326)
			(xy 39.955223 -253.539502) (xy 39.939155 -253.592909) (xy 39.915483 -253.643406) (xy 39.88471 -253.689919)
			(xy 39.847493 -253.731456) (xy 39.804625 -253.767131) (xy 39.757019 -253.796185) (xy 39.70569 -253.817997)
			(xy 39.651733 -253.832103) (xy 39.596296 -253.838203) (xy 39.540562 -253.836166) (xy 39.485719 -253.826036)
			(xy 39.432935 -253.808029) (xy 39.383335 -253.782528) (xy 39.337977 -253.750077) (xy 39.297828 -253.711368)
			(xy 39.263742 -253.667225) (xy 39.236446 -253.61859) (xy 39.216523 -253.566499) (xy 39.204397 -253.512062)
			(xy 39.200326 -253.45644) (xy 38.947852 -253.45644) (xy 38.947343 -253.484326) (xy 38.939223 -253.539502)
			(xy 38.923155 -253.592909) (xy 38.899483 -253.643406) (xy 38.86871 -253.689919) (xy 38.831493 -253.731456)
			(xy 38.788625 -253.767131) (xy 38.741019 -253.796185) (xy 38.68969 -253.817997) (xy 38.635733 -253.832103)
			(xy 38.580296 -253.838203) (xy 38.524562 -253.836166) (xy 38.469719 -253.826036) (xy 38.416935 -253.808029)
			(xy 38.367335 -253.782528) (xy 38.321977 -253.750077) (xy 38.281828 -253.711368) (xy 38.247742 -253.667225)
			(xy 38.220446 -253.61859) (xy 38.200523 -253.566499) (xy 38.188397 -253.512062) (xy 38.184326 -253.45644)
			(xy 37.931852 -253.45644) (xy 37.931343 -253.484326) (xy 37.923223 -253.539502) (xy 37.907155 -253.592909)
			(xy 37.883483 -253.643406) (xy 37.85271 -253.689919) (xy 37.815493 -253.731456) (xy 37.772625 -253.767131)
			(xy 37.725019 -253.796185) (xy 37.67369 -253.817997) (xy 37.619733 -253.832103) (xy 37.564296 -253.838203)
			(xy 37.508562 -253.836166) (xy 37.453719 -253.826036) (xy 37.400935 -253.808029) (xy 37.351335 -253.782528)
			(xy 37.305977 -253.750077) (xy 37.265828 -253.711368) (xy 37.231742 -253.667225) (xy 37.204446 -253.61859)
			(xy 37.184523 -253.566499) (xy 37.172397 -253.512062) (xy 37.168326 -253.45644) (xy 36.915852 -253.45644)
			(xy 36.915343 -253.484326) (xy 36.907223 -253.539502) (xy 36.891155 -253.592909) (xy 36.867483 -253.643406)
			(xy 36.83671 -253.689919) (xy 36.799493 -253.731456) (xy 36.756625 -253.767131) (xy 36.709019 -253.796185)
			(xy 36.65769 -253.817997) (xy 36.603733 -253.832103) (xy 36.548296 -253.838203) (xy 36.492562 -253.836166)
			(xy 36.437719 -253.826036) (xy 36.384935 -253.808029) (xy 36.335335 -253.782528) (xy 36.289977 -253.750077)
			(xy 36.249828 -253.711368) (xy 36.215742 -253.667225) (xy 36.188446 -253.61859) (xy 36.168523 -253.566499)
			(xy 36.156397 -253.512062) (xy 36.152326 -253.45644) (xy 35.899852 -253.45644) (xy 35.899343 -253.484326)
			(xy 35.891223 -253.539502) (xy 35.875155 -253.592909) (xy 35.851483 -253.643406) (xy 35.82071 -253.689919)
			(xy 35.783493 -253.731456) (xy 35.740625 -253.767131) (xy 35.693019 -253.796185) (xy 35.64169 -253.817997)
			(xy 35.587733 -253.832103) (xy 35.532296 -253.838203) (xy 35.476562 -253.836166) (xy 35.421719 -253.826036)
			(xy 35.368935 -253.808029) (xy 35.319335 -253.782528) (xy 35.273977 -253.750077) (xy 35.233828 -253.711368)
			(xy 35.199742 -253.667225) (xy 35.172446 -253.61859) (xy 35.152523 -253.566499) (xy 35.140397 -253.512062)
			(xy 35.136326 -253.45644) (xy 34.883852 -253.45644) (xy 34.883343 -253.484326) (xy 34.875223 -253.539502)
			(xy 34.859155 -253.592909) (xy 34.835483 -253.643406) (xy 34.80471 -253.689919) (xy 34.767493 -253.731456)
			(xy 34.724625 -253.767131) (xy 34.677019 -253.796185) (xy 34.62569 -253.817997) (xy 34.571733 -253.832103)
			(xy 34.516296 -253.838203) (xy 34.460562 -253.836166) (xy 34.405719 -253.826036) (xy 34.352935 -253.808029)
			(xy 34.303335 -253.782528) (xy 34.257977 -253.750077) (xy 34.217828 -253.711368) (xy 34.183742 -253.667225)
			(xy 34.156446 -253.61859) (xy 34.136523 -253.566499) (xy 34.124397 -253.512062) (xy 34.120326 -253.45644)
			(xy 33.867852 -253.45644) (xy 33.867343 -253.484326) (xy 33.859223 -253.539502) (xy 33.843155 -253.592909)
			(xy 33.819483 -253.643406) (xy 33.78871 -253.689919) (xy 33.751493 -253.731456) (xy 33.708625 -253.767131)
			(xy 33.661019 -253.796185) (xy 33.60969 -253.817997) (xy 33.555733 -253.832103) (xy 33.500296 -253.838203)
			(xy 33.444562 -253.836166) (xy 33.389719 -253.826036) (xy 33.336935 -253.808029) (xy 33.287335 -253.782528)
			(xy 33.241977 -253.750077) (xy 33.201828 -253.711368) (xy 33.167742 -253.667225) (xy 33.140446 -253.61859)
			(xy 33.120523 -253.566499) (xy 33.108397 -253.512062) (xy 33.104326 -253.45644) (xy 32.851852 -253.45644)
			(xy 32.851343 -253.484326) (xy 32.843223 -253.539502) (xy 32.827155 -253.592909) (xy 32.803483 -253.643406)
			(xy 32.77271 -253.689919) (xy 32.735493 -253.731456) (xy 32.692625 -253.767131) (xy 32.645019 -253.796185)
			(xy 32.59369 -253.817997) (xy 32.539733 -253.832103) (xy 32.484296 -253.838203) (xy 32.428562 -253.836166)
			(xy 32.373719 -253.826036) (xy 32.320935 -253.808029) (xy 32.271335 -253.782528) (xy 32.225977 -253.750077)
			(xy 32.185828 -253.711368) (xy 32.151742 -253.667225) (xy 32.124446 -253.61859) (xy 32.104523 -253.566499)
			(xy 32.092397 -253.512062) (xy 32.088326 -253.45644) (xy 31.835852 -253.45644) (xy 31.835343 -253.484326)
			(xy 31.827223 -253.539502) (xy 31.811155 -253.592909) (xy 31.787483 -253.643406) (xy 31.75671 -253.689919)
			(xy 31.719493 -253.731456) (xy 31.676625 -253.767131) (xy 31.629019 -253.796185) (xy 31.57769 -253.817997)
			(xy 31.523733 -253.832103) (xy 31.468296 -253.838203) (xy 31.412562 -253.836166) (xy 31.357719 -253.826036)
			(xy 31.304935 -253.808029) (xy 31.255335 -253.782528) (xy 31.209977 -253.750077) (xy 31.169828 -253.711368)
			(xy 31.135742 -253.667225) (xy 31.108446 -253.61859) (xy 31.088523 -253.566499) (xy 31.076397 -253.512062)
			(xy 31.072326 -253.45644) (xy 30.819852 -253.45644) (xy 30.819343 -253.484326) (xy 30.811223 -253.539502)
			(xy 30.795155 -253.592909) (xy 30.771483 -253.643406) (xy 30.74071 -253.689919) (xy 30.703493 -253.731456)
			(xy 30.660625 -253.767131) (xy 30.613019 -253.796185) (xy 30.56169 -253.817997) (xy 30.507733 -253.832103)
			(xy 30.452296 -253.838203) (xy 30.396562 -253.836166) (xy 30.341719 -253.826036) (xy 30.288935 -253.808029)
			(xy 30.239335 -253.782528) (xy 30.193977 -253.750077) (xy 30.153828 -253.711368) (xy 30.119742 -253.667225)
			(xy 30.092446 -253.61859) (xy 30.072523 -253.566499) (xy 30.060397 -253.512062) (xy 30.056326 -253.45644)
			(xy 29.803852 -253.45644) (xy 29.803343 -253.484326) (xy 29.795223 -253.539502) (xy 29.779155 -253.592909)
			(xy 29.755483 -253.643406) (xy 29.72471 -253.689919) (xy 29.687493 -253.731456) (xy 29.644625 -253.767131)
			(xy 29.597019 -253.796185) (xy 29.54569 -253.817997) (xy 29.491733 -253.832103) (xy 29.436296 -253.838203)
			(xy 29.380562 -253.836166) (xy 29.325719 -253.826036) (xy 29.272935 -253.808029) (xy 29.223335 -253.782528)
			(xy 29.177977 -253.750077) (xy 29.137828 -253.711368) (xy 29.103742 -253.667225) (xy 29.076446 -253.61859)
			(xy 29.056523 -253.566499) (xy 29.044397 -253.512062) (xy 29.040326 -253.45644) (xy 28.787852 -253.45644)
			(xy 28.787343 -253.484326) (xy 28.779223 -253.539502) (xy 28.763155 -253.592909) (xy 28.739483 -253.643406)
			(xy 28.70871 -253.689919) (xy 28.671493 -253.731456) (xy 28.628625 -253.767131) (xy 28.581019 -253.796185)
			(xy 28.52969 -253.817997) (xy 28.475733 -253.832103) (xy 28.420296 -253.838203) (xy 28.364562 -253.836166)
			(xy 28.309719 -253.826036) (xy 28.256935 -253.808029) (xy 28.207335 -253.782528) (xy 28.161977 -253.750077)
			(xy 28.121828 -253.711368) (xy 28.087742 -253.667225) (xy 28.060446 -253.61859) (xy 28.040523 -253.566499)
			(xy 28.028397 -253.512062) (xy 28.024326 -253.45644) (xy 27.771852 -253.45644) (xy 27.771343 -253.484326)
			(xy 27.763223 -253.539502) (xy 27.747155 -253.592909) (xy 27.723483 -253.643406) (xy 27.69271 -253.689919)
			(xy 27.655493 -253.731456) (xy 27.612625 -253.767131) (xy 27.565019 -253.796185) (xy 27.51369 -253.817997)
			(xy 27.459733 -253.832103) (xy 27.404296 -253.838203) (xy 27.348562 -253.836166) (xy 27.293719 -253.826036)
			(xy 27.240935 -253.808029) (xy 27.191335 -253.782528) (xy 27.145977 -253.750077) (xy 27.105828 -253.711368)
			(xy 27.071742 -253.667225) (xy 27.044446 -253.61859) (xy 27.024523 -253.566499) (xy 27.012397 -253.512062)
			(xy 27.008326 -253.45644) (xy 26.755852 -253.45644) (xy 26.755343 -253.484326) (xy 26.747223 -253.539502)
			(xy 26.731155 -253.592909) (xy 26.707483 -253.643406) (xy 26.67671 -253.689919) (xy 26.639493 -253.731456)
			(xy 26.596625 -253.767131) (xy 26.549019 -253.796185) (xy 26.49769 -253.817997) (xy 26.443733 -253.832103)
			(xy 26.388296 -253.838203) (xy 26.332562 -253.836166) (xy 26.277719 -253.826036) (xy 26.224935 -253.808029)
			(xy 26.175335 -253.782528) (xy 26.129977 -253.750077) (xy 26.089828 -253.711368) (xy 26.055742 -253.667225)
			(xy 26.028446 -253.61859) (xy 26.008523 -253.566499) (xy 25.996397 -253.512062) (xy 25.992326 -253.45644)
			(xy 25.739852 -253.45644) (xy 25.739343 -253.484326) (xy 25.731223 -253.539502) (xy 25.715155 -253.592909)
			(xy 25.691483 -253.643406) (xy 25.66071 -253.689919) (xy 25.623493 -253.731456) (xy 25.580625 -253.767131)
			(xy 25.533019 -253.796185) (xy 25.48169 -253.817997) (xy 25.427733 -253.832103) (xy 25.372296 -253.838203)
			(xy 25.316562 -253.836166) (xy 25.261719 -253.826036) (xy 25.208935 -253.808029) (xy 25.159335 -253.782528)
			(xy 25.113977 -253.750077) (xy 25.073828 -253.711368) (xy 25.039742 -253.667225) (xy 25.012446 -253.61859)
			(xy 24.992523 -253.566499) (xy 24.980397 -253.512062) (xy 24.976326 -253.45644) (xy 24.723852 -253.45644)
			(xy 24.723343 -253.484326) (xy 24.715223 -253.539502) (xy 24.699155 -253.592909) (xy 24.675483 -253.643406)
			(xy 24.64471 -253.689919) (xy 24.607493 -253.731456) (xy 24.564625 -253.767131) (xy 24.517019 -253.796185)
			(xy 24.46569 -253.817997) (xy 24.411733 -253.832103) (xy 24.356296 -253.838203) (xy 24.300562 -253.836166)
			(xy 24.245719 -253.826036) (xy 24.192935 -253.808029) (xy 24.143335 -253.782528) (xy 24.097977 -253.750077)
			(xy 24.057828 -253.711368) (xy 24.023742 -253.667225) (xy 23.996446 -253.61859) (xy 23.976523 -253.566499)
			(xy 23.964397 -253.512062) (xy 23.960326 -253.45644) (xy 22.17166 -253.45644) (xy 22.17166 -255.341628)
			(xy 22.17209 -255.351695) (xy 22.179818 -255.370286) (xy 22.186646 -255.377696) (xy 22.343872 -255.534922)
			(xy 22.355048 -255.541526) (xy 22.361398 -255.543304) (xy 22.38816 -255.551307) (xy 22.439174 -255.574059)
			(xy 22.486324 -255.604007) (xy 22.528602 -255.640512) (xy 22.558338 -255.674954) (xy 22.765453 -255.674954)
			(xy 22.765453 -255.620446) (xy 22.773211 -255.566494) (xy 22.788567 -255.514195) (xy 22.811211 -255.464614)
			(xy 22.84068 -255.41876) (xy 22.876375 -255.377567) (xy 22.91757 -255.341873) (xy 22.963424 -255.312405)
			(xy 23.013006 -255.289763) (xy 23.065306 -255.274408) (xy 23.119258 -255.266653) (xy 23.146512 -255.26619)
			(xy 23.176121 -255.266801) (xy 23.23463 -255.275939) (xy 23.291025 -255.29401) (xy 23.343949 -255.320578)
			(xy 23.392131 -255.355006) (xy 23.434414 -255.396466) (xy 23.469782 -255.443963) (xy 23.484078 -255.469898)
			(xy 23.491605 -255.482931) (xy 23.512833 -255.504246) (xy 23.539345 -255.518463) (xy 23.568845 -255.524353)
			(xy 23.598783 -255.521405) (xy 23.626568 -255.509874) (xy 23.649797 -255.490759) (xy 23.658576 -255.478534)
			(xy 23.673758 -255.456285) (xy 23.709456 -255.415951) (xy 23.750471 -255.381036) (xy 23.795986 -255.352233)
			(xy 23.845098 -255.330115) (xy 23.896832 -255.31512) (xy 23.95016 -255.307547) (xy 23.977092 -255.307084)
			(xy 24.004345 -255.307563) (xy 24.058295 -255.315319) (xy 24.110593 -255.330674) (xy 24.160173 -255.353315)
			(xy 24.206026 -255.382782) (xy 24.247219 -255.418475) (xy 24.282913 -255.459667) (xy 24.312381 -255.50552)
			(xy 24.335024 -255.555099) (xy 24.35038 -255.607397) (xy 24.358137 -255.661347) (xy 24.358137 -255.715853)
			(xy 24.35038 -255.769803) (xy 24.335024 -255.822101) (xy 24.312381 -255.87168) (xy 24.282913 -255.917533)
			(xy 24.247219 -255.958725) (xy 24.206026 -255.994418) (xy 24.160173 -256.023885) (xy 24.110593 -256.046526)
			(xy 24.058295 -256.061881) (xy 24.004345 -256.069637) (xy 23.977092 -256.0701) (xy 23.947483 -256.06949)
			(xy 23.888973 -256.060353) (xy 23.832579 -256.042282) (xy 23.779655 -256.015714) (xy 23.731472 -255.981286)
			(xy 23.68919 -255.939825) (xy 23.653822 -255.892327) (xy 23.639526 -255.866392) (xy 23.631993 -255.853363)
			(xy 23.610765 -255.83205) (xy 23.584256 -255.817834) (xy 23.554757 -255.811945) (xy 23.524821 -255.814892)
			(xy 23.497037 -255.82642) (xy 23.473808 -255.845532) (xy 23.465028 -255.857756) (xy 23.44984 -255.88)
			(xy 23.414143 -255.920335) (xy 23.37313 -255.955251) (xy 23.327616 -255.984055) (xy 23.278504 -256.006174)
			(xy 23.226771 -256.021169) (xy 23.173443 -256.028743) (xy 23.146512 -256.029206) (xy 23.119258 -256.028747)
			(xy 23.065306 -256.020992) (xy 23.013006 -256.005637) (xy 22.963424 -255.982995) (xy 22.91757 -255.953527)
			(xy 22.876375 -255.917833) (xy 22.84068 -255.87664) (xy 22.811211 -255.830786) (xy 22.788567 -255.781205)
			(xy 22.773211 -255.728906) (xy 22.765453 -255.674954) (xy 22.558338 -255.674954) (xy 22.565105 -255.682792)
			(xy 22.59505 -255.729944) (xy 22.617799 -255.780959) (xy 22.625812 -255.807718) (xy 22.62759 -255.814068)
			(xy 22.634194 -255.825244) (xy 23.288571 -256.479621) (xy 25.279328 -256.479621) (xy 25.279328 -256.425119)
			(xy 25.287084 -256.371171) (xy 25.302439 -256.318876) (xy 25.325081 -256.269299) (xy 25.354547 -256.223449)
			(xy 25.390238 -256.182258) (xy 25.431429 -256.146567) (xy 25.477279 -256.117101) (xy 25.526856 -256.094459)
			(xy 25.579151 -256.079104) (xy 25.633099 -256.071348) (xy 25.66035 -256.070862) (xy 25.686666 -256.071314)
			(xy 25.7388 -256.078536) (xy 25.789447 -256.09285) (xy 25.837649 -256.113985) (xy 25.882491 -256.14154)
			(xy 25.923123 -256.174992) (xy 25.941274 -256.194052) (xy 25.94881 -256.201437) (xy 25.968079 -256.209972)
			(xy 25.978612 -256.210562) (xy 26.053288 -256.210562) (xy 26.06384 -256.210051) (xy 26.083136 -256.201504)
			(xy 26.090626 -256.194052) (xy 26.108758 -256.17497) (xy 26.149378 -256.14149) (xy 26.194219 -256.113919)
			(xy 26.242427 -256.09278) (xy 26.293085 -256.078477) (xy 26.34523 -256.071281) (xy 26.37155 -256.070862)
			(xy 26.398801 -256.071348) (xy 26.452749 -256.079104) (xy 26.505044 -256.094459) (xy 26.513997 -256.098548)
			(xy 27.881832 -256.098548) (xy 27.885903 -256.042926) (xy 27.898029 -255.988489) (xy 27.917952 -255.936398)
			(xy 27.945248 -255.887763) (xy 27.979334 -255.84362) (xy 28.019483 -255.804911) (xy 28.064841 -255.77246)
			(xy 28.114441 -255.746959) (xy 28.167225 -255.728952) (xy 28.222068 -255.718822) (xy 28.277802 -255.716785)
			(xy 28.333239 -255.722885) (xy 28.387196 -255.736991) (xy 28.438525 -255.758803) (xy 28.486131 -255.787857)
			(xy 28.528999 -255.823532) (xy 28.566216 -255.865069) (xy 28.596989 -255.911582) (xy 28.620661 -255.962079)
			(xy 28.636729 -256.015486) (xy 28.644849 -256.070662) (xy 28.645358 -256.098548) (xy 28.644849 -256.126434)
			(xy 28.636729 -256.18161) (xy 28.620661 -256.235017) (xy 28.596989 -256.285514) (xy 28.566216 -256.332027)
			(xy 28.528999 -256.373564) (xy 28.526173 -256.375916) (xy 28.769562 -256.375916) (xy 28.773633 -256.320294)
			(xy 28.785759 -256.265857) (xy 28.805682 -256.213766) (xy 28.832978 -256.165131) (xy 28.867064 -256.120988)
			(xy 28.907213 -256.082279) (xy 28.952571 -256.049828) (xy 29.002171 -256.024327) (xy 29.054955 -256.00632)
			(xy 29.109798 -255.99619) (xy 29.165532 -255.994153) (xy 29.220969 -256.000253) (xy 29.274926 -256.014359)
			(xy 29.326255 -256.036171) (xy 29.373861 -256.065225) (xy 29.416729 -256.1009) (xy 29.453946 -256.142437)
			(xy 29.484719 -256.18895) (xy 29.508391 -256.239447) (xy 29.524459 -256.292854) (xy 29.532579 -256.34803)
			(xy 29.533088 -256.375916) (xy 30.245048 -256.375916) (xy 30.249119 -256.320294) (xy 30.261245 -256.265857)
			(xy 30.281168 -256.213766) (xy 30.308464 -256.165131) (xy 30.34255 -256.120988) (xy 30.382699 -256.082279)
			(xy 30.428057 -256.049828) (xy 30.477657 -256.024327) (xy 30.530441 -256.00632) (xy 30.585284 -255.99619)
			(xy 30.641018 -255.994153) (xy 30.696455 -256.000253) (xy 30.750412 -256.014359) (xy 30.801741 -256.036171)
			(xy 30.849347 -256.065225) (xy 30.892215 -256.1009) (xy 30.929432 -256.142437) (xy 30.960205 -256.18895)
			(xy 30.983877 -256.239447) (xy 30.999945 -256.292854) (xy 31.008065 -256.34803) (xy 31.008574 -256.375916)
			(xy 31.134048 -256.375916) (xy 31.138119 -256.320294) (xy 31.150245 -256.265857) (xy 31.170168 -256.213766)
			(xy 31.197464 -256.165131) (xy 31.23155 -256.120988) (xy 31.271699 -256.082279) (xy 31.317057 -256.049828)
			(xy 31.366657 -256.024327) (xy 31.419441 -256.00632) (xy 31.474284 -255.99619) (xy 31.530018 -255.994153)
			(xy 31.585455 -256.000253) (xy 31.639412 -256.014359) (xy 31.690741 -256.036171) (xy 31.738347 -256.065225)
			(xy 31.781215 -256.1009) (xy 31.818432 -256.142437) (xy 31.849205 -256.18895) (xy 31.872877 -256.239447)
			(xy 31.888945 -256.292854) (xy 31.897065 -256.34803) (xy 31.897574 -256.375916) (xy 31.897065 -256.403802)
			(xy 31.888945 -256.458978) (xy 31.872877 -256.512385) (xy 31.849205 -256.562882) (xy 31.818432 -256.609395)
			(xy 31.781215 -256.650932) (xy 31.738347 -256.686607) (xy 31.690741 -256.715661) (xy 31.639412 -256.737473)
			(xy 31.585455 -256.751579) (xy 31.530018 -256.757679) (xy 31.474284 -256.755642) (xy 31.419441 -256.745512)
			(xy 31.366657 -256.727505) (xy 31.317057 -256.702004) (xy 31.271699 -256.669553) (xy 31.23155 -256.630844)
			(xy 31.197464 -256.586701) (xy 31.170168 -256.538066) (xy 31.150245 -256.485975) (xy 31.138119 -256.431538)
			(xy 31.134048 -256.375916) (xy 31.008574 -256.375916) (xy 31.008065 -256.403802) (xy 30.999945 -256.458978)
			(xy 30.983877 -256.512385) (xy 30.960205 -256.562882) (xy 30.929432 -256.609395) (xy 30.892215 -256.650932)
			(xy 30.849347 -256.686607) (xy 30.801741 -256.715661) (xy 30.750412 -256.737473) (xy 30.696455 -256.751579)
			(xy 30.641018 -256.757679) (xy 30.585284 -256.755642) (xy 30.530441 -256.745512) (xy 30.477657 -256.727505)
			(xy 30.428057 -256.702004) (xy 30.382699 -256.669553) (xy 30.34255 -256.630844) (xy 30.308464 -256.586701)
			(xy 30.281168 -256.538066) (xy 30.261245 -256.485975) (xy 30.249119 -256.431538) (xy 30.245048 -256.375916)
			(xy 29.533088 -256.375916) (xy 29.532579 -256.403802) (xy 29.524459 -256.458978) (xy 29.508391 -256.512385)
			(xy 29.484719 -256.562882) (xy 29.453946 -256.609395) (xy 29.416729 -256.650932) (xy 29.373861 -256.686607)
			(xy 29.326255 -256.715661) (xy 29.274926 -256.737473) (xy 29.220969 -256.751579) (xy 29.165532 -256.757679)
			(xy 29.109798 -256.755642) (xy 29.054955 -256.745512) (xy 29.002171 -256.727505) (xy 28.952571 -256.702004)
			(xy 28.907213 -256.669553) (xy 28.867064 -256.630844) (xy 28.832978 -256.586701) (xy 28.805682 -256.538066)
			(xy 28.785759 -256.485975) (xy 28.773633 -256.431538) (xy 28.769562 -256.375916) (xy 28.526173 -256.375916)
			(xy 28.486131 -256.409239) (xy 28.438525 -256.438293) (xy 28.387196 -256.460105) (xy 28.333239 -256.474211)
			(xy 28.277802 -256.480311) (xy 28.222068 -256.478274) (xy 28.167225 -256.468144) (xy 28.114441 -256.450137)
			(xy 28.064841 -256.424636) (xy 28.019483 -256.392185) (xy 27.979334 -256.353476) (xy 27.945248 -256.309333)
			(xy 27.917952 -256.260698) (xy 27.898029 -256.208607) (xy 27.885903 -256.15417) (xy 27.881832 -256.098548)
			(xy 26.513997 -256.098548) (xy 26.554621 -256.117101) (xy 26.600471 -256.146567) (xy 26.641662 -256.182258)
			(xy 26.677353 -256.223449) (xy 26.706819 -256.269299) (xy 26.729461 -256.318876) (xy 26.744816 -256.371171)
			(xy 26.752572 -256.425119) (xy 26.752572 -256.479621) (xy 26.744816 -256.533569) (xy 26.729461 -256.585864)
			(xy 26.706819 -256.635441) (xy 26.677353 -256.681291) (xy 26.641662 -256.722482) (xy 26.600471 -256.758173)
			(xy 26.554621 -256.787639) (xy 26.505044 -256.810281) (xy 26.452749 -256.825636) (xy 26.398801 -256.833392)
			(xy 26.37155 -256.833878) (xy 26.345233 -256.833445) (xy 26.293098 -256.826222) (xy 26.242449 -256.811905)
			(xy 26.194247 -256.790767) (xy 26.149406 -256.763208) (xy 26.108775 -256.72975) (xy 26.090626 -256.710688)
			(xy 26.083098 -256.703294) (xy 26.063823 -256.694766) (xy 26.053288 -256.694178) (xy 25.978612 -256.694178)
			(xy 25.968062 -256.694706) (xy 25.948767 -256.703243) (xy 25.941274 -256.710688) (xy 25.92315 -256.729778)
			(xy 25.882527 -256.763255) (xy 25.837685 -256.790825) (xy 25.789475 -256.811962) (xy 25.738816 -256.826264)
			(xy 25.68667 -256.833459) (xy 25.66035 -256.833878) (xy 25.633099 -256.833392) (xy 25.579151 -256.825636)
			(xy 25.526856 -256.810281) (xy 25.477279 -256.787639) (xy 25.431429 -256.758173) (xy 25.390238 -256.722482)
			(xy 25.354547 -256.681291) (xy 25.325081 -256.635441) (xy 25.302439 -256.585864) (xy 25.287084 -256.533569)
			(xy 25.279328 -256.479621) (xy 23.288571 -256.479621) (xy 23.842726 -257.033776) (xy 23.850125 -257.040621)
			(xy 23.868723 -257.04835) (xy 23.878794 -257.048762)
		)
		(stroke
			(width 0)
			(type solid)
		)
		(fill yes)
		(layer "In13.Cu")
		(net "P1V8_PEX")
	)
	(gr_poly
		(pts
			(xy 275.858224 -288.67735) (xy 275.863812 -288.66211) (xy 275.872887 -288.638501) (xy 275.897171 -288.594137)
			(xy 275.927927 -288.553987) (xy 275.964438 -288.518989) (xy 276.005851 -288.489957) (xy 276.051203 -288.467569)
			(xy 276.099434 -288.452348) (xy 276.14942 -288.444647) (xy 276.199996 -288.444647) (xy 276.249982 -288.452348)
			(xy 276.298213 -288.467569) (xy 276.343565 -288.489957) (xy 276.384978 -288.518989) (xy 276.421489 -288.553987)
			(xy 276.452245 -288.594137) (xy 276.476529 -288.638501) (xy 276.485604 -288.66211) (xy 276.491192 -288.67735)
			(xy 276.517354 -288.695638) (xy 276.782276 -288.695638) (xy 276.808438 -288.67735) (xy 276.814026 -288.66211)
			(xy 276.823101 -288.638501) (xy 276.847385 -288.594137) (xy 276.878141 -288.553987) (xy 276.914652 -288.518989)
			(xy 276.956065 -288.489957) (xy 277.001417 -288.467569) (xy 277.049648 -288.452348) (xy 277.099634 -288.444647)
			(xy 277.15021 -288.444647) (xy 277.200196 -288.452348) (xy 277.248427 -288.467569) (xy 277.293779 -288.489957)
			(xy 277.335192 -288.518989) (xy 277.371703 -288.553987) (xy 277.402459 -288.594137) (xy 277.426743 -288.638501)
			(xy 277.435818 -288.66211) (xy 277.441406 -288.67735) (xy 277.467568 -288.695638) (xy 277.732236 -288.695638)
			(xy 277.758398 -288.67735) (xy 277.763986 -288.66211) (xy 277.773061 -288.638502) (xy 277.797346 -288.594137)
			(xy 277.828103 -288.553988) (xy 277.864613 -288.518989) (xy 277.906026 -288.489956) (xy 277.951377 -288.467568)
			(xy 277.999608 -288.452344) (xy 278.049594 -288.444641) (xy 278.074882 -288.444178) (xy 278.101344 -288.444697)
			(xy 278.153595 -288.45312) (xy 278.203837 -288.469755) (xy 278.250791 -288.494176) (xy 278.293257 -288.525762)
			(xy 278.330153 -288.563706) (xy 278.360537 -288.607039) (xy 278.37257 -288.630614) (xy 278.37892 -288.644076)
			(xy 278.403304 -288.659316) (xy 278.72436 -288.659316) (xy 278.748236 -288.644838) (xy 278.75484 -288.632138)
			(xy 278.76631 -288.611434) (xy 278.794647 -288.573528) (xy 278.82849 -288.540442) (xy 278.867028 -288.51297)
			(xy 278.909341 -288.491767) (xy 278.954417 -288.47734) (xy 279.001178 -288.470035) (xy 279.024842 -288.469578)
			(xy 279.043712 -288.469892) (xy 279.081158 -288.474606) (xy 279.099518 -288.478976) (xy 279.112726 -288.482278)
			(xy 279.13838 -288.475166) (xy 279.301194 -288.312352) (xy 279.308034 -288.304951) (xy 279.315752 -288.286353)
			(xy 279.31618 -288.276284) (xy 279.31618 -283.43479) (xy 279.31583 -283.426058) (xy 279.309954 -283.409614)
			(xy 279.298863 -283.396126) (xy 279.291542 -283.391356) (xy 279.20569 -283.33954) (xy 279.17902 -283.338778)
			(xy 279.167336 -283.344874) (xy 279.145246 -283.355989) (xy 279.098367 -283.371716) (xy 279.049566 -283.379687)
			(xy 279.024842 -283.38018) (xy 278.999584 -283.379691) (xy 278.949757 -283.371382) (xy 278.901977 -283.354985)
			(xy 278.857548 -283.330947) (xy 278.817682 -283.299923) (xy 278.783466 -283.26276) (xy 278.755835 -283.220472)
			(xy 278.735542 -283.174212) (xy 278.72314 -283.125243) (xy 278.718968 -283.0749) (xy 278.72314 -283.024557)
			(xy 278.735542 -282.975588) (xy 278.755835 -282.929328) (xy 278.783466 -282.88704) (xy 278.817682 -282.849877)
			(xy 278.857548 -282.818853) (xy 278.901977 -282.794815) (xy 278.949757 -282.778418) (xy 278.999584 -282.770109)
			(xy 279.024842 -282.769564) (xy 279.049568 -282.770038) (xy 279.098373 -282.778003) (xy 279.145255 -282.793734)
			(xy 279.167336 -282.80487) (xy 279.17902 -282.810966) (xy 279.20569 -282.810204) (xy 279.291542 -282.758388)
			(xy 279.29882 -282.753574) (xy 279.309867 -282.74008) (xy 279.315773 -282.723671) (xy 279.31618 -282.714954)
			(xy 279.31618 -281.950922) (xy 279.315607 -281.9393) (xy 279.305419 -281.918407) (xy 279.296622 -281.91079)
			(xy 279.277133 -281.895025) (xy 279.242686 -281.858609) (xy 279.214131 -281.817412) (xy 279.192121 -281.772376)
			(xy 279.17716 -281.724534) (xy 279.169591 -281.674983) (xy 279.169588 -281.624856) (xy 279.177151 -281.575304)
			(xy 279.192106 -281.527461) (xy 279.214111 -281.482422) (xy 279.242662 -281.441222) (xy 279.277104 -281.404802)
			(xy 279.296622 -281.389074) (xy 279.305458 -281.381486) (xy 279.315658 -281.360576) (xy 279.31618 -281.348942)
			(xy 279.31618 -280.996136) (xy 279.315624 -280.984608) (xy 279.305562 -280.963861) (xy 279.296876 -280.956258)
			(xy 279.277881 -280.940651) (xy 279.244346 -280.904705) (xy 279.216572 -280.864143) (xy 279.195185 -280.819878)
			(xy 279.180668 -280.772911) (xy 279.173349 -280.724298) (xy 279.172924 -280.699718) (xy 279.17335 -280.675138)
			(xy 279.180677 -280.626529) (xy 279.195198 -280.579564) (xy 279.216585 -280.535302) (xy 279.244358 -280.494741)
			(xy 279.277889 -280.458794) (xy 279.296876 -280.443178) (xy 279.305576 -280.435594) (xy 279.315599 -280.41483)
			(xy 279.31618 -280.4033) (xy 279.31618 -280.045922) (xy 279.315641 -280.034385) (xy 279.305601 -280.01361)
			(xy 279.296876 -280.006044) (xy 279.277882 -279.990437) (xy 279.244348 -279.954491) (xy 279.216576 -279.913928)
			(xy 279.195191 -279.869663) (xy 279.180676 -279.822696) (xy 279.173358 -279.774084) (xy 279.172924 -279.749504)
			(xy 279.173351 -279.724925) (xy 279.18068 -279.676317) (xy 279.195202 -279.629353) (xy 279.216591 -279.585093)
			(xy 279.244364 -279.544533) (xy 279.277896 -279.508588) (xy 279.296876 -279.492964) (xy 279.305591 -279.485386)
			(xy 279.315648 -279.464622) (xy 279.31618 -279.453086) (xy 279.31618 -279.100788) (xy 279.3156 -279.08917)
			(xy 279.305403 -279.068288) (xy 279.296622 -279.060656) (xy 279.277135 -279.044891) (xy 279.242694 -279.008476)
			(xy 279.214144 -278.96728) (xy 279.192138 -278.922247) (xy 279.177181 -278.874408) (xy 279.169617 -278.82486)
			(xy 279.169617 -278.774738) (xy 279.177182 -278.72519) (xy 279.192139 -278.677351) (xy 279.214145 -278.632318)
			(xy 279.242696 -278.591122) (xy 279.277137 -278.554708) (xy 279.296622 -278.53894) (xy 279.305452 -278.53135)
			(xy 279.315638 -278.51044) (xy 279.31618 -278.498808) (xy 279.31618 -278.150828) (xy 279.315608 -278.139206)
			(xy 279.305421 -278.118311) (xy 279.296622 -278.110696) (xy 279.277132 -278.094931) (xy 279.242685 -278.058515)
			(xy 279.214129 -278.017317) (xy 279.192118 -277.972281) (xy 279.177156 -277.924439) (xy 279.169587 -277.874887)
			(xy 279.169583 -277.82476) (xy 279.177146 -277.775206) (xy 279.1921 -277.727362) (xy 279.214105 -277.682323)
			(xy 279.242656 -277.641121) (xy 279.277098 -277.604701) (xy 279.296622 -277.58898) (xy 279.305459 -277.581392)
			(xy 279.315661 -277.560483) (xy 279.31618 -277.548848) (xy 279.31618 -277.200868) (xy 279.315617 -277.189242)
			(xy 279.305439 -277.168333) (xy 279.296622 -277.160736) (xy 279.277137 -277.144971) (xy 279.242699 -277.108556)
			(xy 279.214151 -277.067361) (xy 279.192148 -277.022329) (xy 279.177194 -276.974492) (xy 279.169631 -276.924946)
			(xy 279.169633 -276.874827) (xy 279.1772 -276.825281) (xy 279.192158 -276.777445) (xy 279.214165 -276.732415)
			(xy 279.242716 -276.691223) (xy 279.277157 -276.654811) (xy 279.296622 -276.63902) (xy 279.305449 -276.631428)
			(xy 279.315627 -276.610518) (xy 279.31618 -276.598888) (xy 279.31618 -276.246336) (xy 279.315624 -276.234808)
			(xy 279.305562 -276.214061) (xy 279.296876 -276.206458) (xy 279.277881 -276.190851) (xy 279.244346 -276.154905)
			(xy 279.216572 -276.114343) (xy 279.195185 -276.070078) (xy 279.180668 -276.023111) (xy 279.173349 -275.974498)
			(xy 279.172924 -275.949918) (xy 279.17335 -275.925338) (xy 279.180677 -275.876729) (xy 279.195198 -275.829764)
			(xy 279.216585 -275.785502) (xy 279.244358 -275.744941) (xy 279.277889 -275.708994) (xy 279.296876 -275.693378)
			(xy 279.305576 -275.685794) (xy 279.315599 -275.66503) (xy 279.31618 -275.6535) (xy 279.31618 -275.296376)
			(xy 279.315632 -275.284844) (xy 279.30558 -275.264084) (xy 279.296876 -275.256498) (xy 279.277879 -275.240892)
			(xy 279.244339 -275.204947) (xy 279.21656 -275.164385) (xy 279.195168 -275.120121) (xy 279.180646 -275.073153)
			(xy 279.17332 -275.024539) (xy 279.172924 -274.999958) (xy 279.173347 -274.975377) (xy 279.180669 -274.926764)
			(xy 279.195185 -274.879796) (xy 279.21657 -274.835529) (xy 279.24434 -274.794963) (xy 279.27787 -274.759012)
			(xy 279.296876 -274.743418) (xy 279.305583 -274.735837) (xy 279.315622 -274.715073) (xy 279.31618 -274.70354)
			(xy 279.31618 -274.350734) (xy 279.31561 -274.339111) (xy 279.305424 -274.318214) (xy 279.296622 -274.310602)
			(xy 279.277132 -274.294837) (xy 279.242684 -274.258421) (xy 279.214127 -274.217223) (xy 279.192115 -274.172186)
			(xy 279.177152 -274.124344) (xy 279.169583 -274.074791) (xy 279.169578 -274.024663) (xy 279.17714 -273.975109)
			(xy 279.192095 -273.927264) (xy 279.214099 -273.882224) (xy 279.24265 -273.841021) (xy 279.277092 -273.8046)
			(xy 279.296622 -273.788886) (xy 279.30546 -273.781299) (xy 279.315665 -273.760389) (xy 279.31618 -273.748754)
			(xy 279.31618 -273.4945) (xy 279.315756 -273.48443) (xy 279.30804 -273.465828) (xy 279.301194 -273.458432)
			(xy 279.022556 -273.179794) (xy 279.01632 -273.174027) (xy 279.001043 -273.166624) (xy 278.984187 -273.164608)
			(xy 278.97582 -273.166078) (xy 278.879554 -273.186652) (xy 278.86025 -273.203416) (xy 278.855678 -273.215608)
			(xy 278.846515 -273.238579) (xy 278.82227 -273.281681) (xy 278.791808 -273.320639) (xy 278.755826 -273.354563)
			(xy 278.715143 -273.38268) (xy 278.670689 -273.404348) (xy 278.623479 -273.419072) (xy 278.574589 -273.426516)
			(xy 278.549862 -273.426936) (xy 278.52416 -273.426455) (xy 278.473391 -273.418405) (xy 278.424507 -273.402509)
			(xy 278.378713 -273.37916) (xy 278.337137 -273.348932) (xy 278.300803 -273.31257) (xy 278.270607 -273.27097)
			(xy 278.247293 -273.225158) (xy 278.231436 -273.176262) (xy 278.223425 -273.125486) (xy 278.222964 -273.099784)
			(xy 278.22341 -273.075069) (xy 278.230837 -273.026201) (xy 278.245533 -272.979006) (xy 278.267163 -272.934561)
			(xy 278.295237 -272.893877) (xy 278.329113 -272.857882) (xy 278.36802 -272.827394) (xy 278.411072 -272.803109)
			(xy 278.434038 -272.793968) (xy 278.44623 -272.789396) (xy 278.462994 -272.770092) (xy 278.483568 -272.673826)
			(xy 278.485089 -272.66546) (xy 278.483097 -272.648583) (xy 278.475655 -272.633305) (xy 278.469852 -272.62709)
			(xy 278.247348 -272.404586) (xy 278.239951 -272.397739) (xy 278.221352 -272.39001) (xy 278.21128 -272.3896)
			(xy 276.896322 -272.3896) (xy 276.887372 -272.389997) (xy 276.870595 -272.396249) (xy 276.863556 -272.401792)
			(xy 276.845531 -272.416551) (xy 276.806121 -272.441393) (xy 276.763616 -272.460461) (xy 276.718856 -272.473379)
			(xy 276.672727 -272.47989) (xy 276.649434 -272.480278) (xy 276.626141 -272.479896) (xy 276.580011 -272.473388)
			(xy 276.535252 -272.460468) (xy 276.49275 -272.441393) (xy 276.453348 -272.416539) (xy 276.435312 -272.401792)
			(xy 276.428281 -272.396238) (xy 276.411498 -272.389995) (xy 276.402546 -272.3896) (xy 274.65909 -272.3896)
			(xy 274.646928 -272.390293) (xy 274.625302 -272.401428) (xy 274.617688 -272.410936) (xy 274.56257 -272.48866)
			(xy 274.559014 -272.51279) (xy 274.563078 -272.524474) (xy 274.571013 -272.548794) (xy 274.579563 -272.599227)
			(xy 274.580096 -272.624804) (xy 274.579574 -272.650059) (xy 274.571261 -272.699881) (xy 274.55486 -272.747655)
			(xy 274.530819 -272.792078) (xy 274.499795 -272.831938) (xy 274.462633 -272.866148) (xy 274.420347 -272.893774)
			(xy 274.374091 -272.914064) (xy 274.325126 -272.926464) (xy 274.274788 -272.930635) (xy 274.22445 -272.926464)
			(xy 274.175485 -272.914064) (xy 274.129229 -272.893774) (xy 274.086943 -272.866148) (xy 274.049781 -272.831938)
			(xy 274.018757 -272.792078) (xy 273.994716 -272.747655) (xy 273.978315 -272.699881) (xy 273.970002 -272.650059)
			(xy 273.96948 -272.624804) (xy 273.970019 -272.599228) (xy 273.978568 -272.548795) (xy 273.986498 -272.524474)
			(xy 273.990562 -272.51279) (xy 273.987006 -272.48866) (xy 273.931888 -272.410936) (xy 273.924277 -272.401416)
			(xy 273.902654 -272.390249) (xy 273.890486 -272.3896) (xy 272.75917 -272.3896) (xy 272.74701 -272.390297)
			(xy 272.725391 -272.401437) (xy 272.717768 -272.410936) (xy 272.66265 -272.48866) (xy 272.659094 -272.51279)
			(xy 272.663158 -272.524474) (xy 272.671091 -272.548794) (xy 272.679639 -272.599228) (xy 272.680176 -272.624804)
			(xy 272.679654 -272.650059) (xy 272.671341 -272.699881) (xy 272.65494 -272.747655) (xy 272.630899 -272.792078)
			(xy 272.599875 -272.831938) (xy 272.562713 -272.866148) (xy 272.520427 -272.893774) (xy 272.474171 -272.914064)
			(xy 272.425206 -272.926464) (xy 272.374868 -272.930635) (xy 272.32453 -272.926464) (xy 272.275565 -272.914064)
			(xy 272.229309 -272.893774) (xy 272.187023 -272.866148) (xy 272.149861 -272.831938) (xy 272.118837 -272.792078)
			(xy 272.094796 -272.747655) (xy 272.078395 -272.699881) (xy 272.070082 -272.650059) (xy 272.06956 -272.624804)
			(xy 272.070099 -272.599228) (xy 272.078647 -272.548795) (xy 272.086578 -272.524474) (xy 272.090642 -272.51279)
			(xy 272.087086 -272.48866) (xy 272.031968 -272.410936) (xy 272.024356 -272.40142) (xy 272.002733 -272.390261)
			(xy 271.990566 -272.3896) (xy 271.488408 -272.3896) (xy 271.478337 -272.389178) (xy 271.459731 -272.381466)
			(xy 271.45234 -272.374614) (xy 265.080242 -266.002516) (xy 265.072841 -265.995677) (xy 265.054243 -265.987961)
			(xy 265.044174 -265.98753) (xy 252.577854 -265.98753) (xy 252.567855 -265.988026) (xy 252.549384 -265.995695)
			(xy 252.535252 -266.009848) (xy 252.527611 -266.02833) (xy 252.527054 -266.03833) (xy 252.527054 -270.89989)
			(xy 259.082549 -270.89989) (xy 259.086538 -270.75135) (xy 259.098495 -270.603237) (xy 259.118385 -270.45598)
			(xy 259.14615 -270.310004) (xy 259.181711 -270.165727) (xy 259.224965 -270.023568) (xy 259.275787 -269.883935)
			(xy 259.334031 -269.747232) (xy 259.399529 -269.613852) (xy 259.472092 -269.48418) (xy 259.55151 -269.35859)
			(xy 259.637555 -269.237443) (xy 259.729979 -269.12109) (xy 259.828515 -269.009866) (xy 259.932879 -268.904091)
			(xy 260.042771 -268.804071) (xy 260.157872 -268.710093) (xy 260.277852 -268.622429) (xy 260.402365 -268.541332)
			(xy 260.531051 -268.467035) (xy 260.66354 -268.399753) (xy 260.799449 -268.339679) (xy 260.938387 -268.286987)
			(xy 261.079953 -268.241828) (xy 261.223739 -268.204333) (xy 261.36933 -268.174611) (xy 261.516306 -268.152746)
			(xy 261.664245 -268.138802) (xy 261.812718 -268.132818) (xy 261.961299 -268.134813) (xy 262.109558 -268.144781)
			(xy 262.257069 -268.162692) (xy 262.403405 -268.188495) (xy 262.548146 -268.222115) (xy 262.690873 -268.263457)
			(xy 262.831176 -268.3124) (xy 262.968649 -268.368803) (xy 263.102896 -268.432504) (xy 263.233531 -268.50332)
			(xy 263.360176 -268.581045) (xy 263.482466 -268.665456) (xy 263.600049 -268.756309) (xy 263.712586 -268.853343)
			(xy 263.819753 -268.956278) (xy 263.92124 -269.064817) (xy 264.016754 -269.178646) (xy 264.106021 -269.297439)
			(xy 264.188782 -269.420851) (xy 264.2648 -269.548529) (xy 264.333855 -269.680102) (xy 264.395748 -269.815193)
			(xy 264.450301 -269.95341) (xy 264.497356 -270.094357) (xy 264.536778 -270.237627) (xy 264.568452 -270.382806)
			(xy 264.592288 -270.529475) (xy 264.608217 -270.677213) (xy 264.616193 -270.825593) (xy 264.616692 -270.89989)
			(xy 264.616193 -270.974187) (xy 264.608217 -271.122567) (xy 264.592288 -271.270305) (xy 264.568452 -271.416974)
			(xy 264.536778 -271.562153) (xy 264.497356 -271.705423) (xy 264.450301 -271.84637) (xy 264.395748 -271.984587)
			(xy 264.333855 -272.119678) (xy 264.2648 -272.251251) (xy 264.188782 -272.378929) (xy 264.106021 -272.502341)
			(xy 264.016754 -272.621134) (xy 264.013675 -272.624804) (xy 270.169144 -272.624804) (xy 270.173104 -272.57575)
			(xy 270.184881 -272.527966) (xy 270.204172 -272.48269) (xy 270.230475 -272.441094) (xy 270.26311 -272.404257)
			(xy 270.301231 -272.373132) (xy 270.343852 -272.348525) (xy 270.389868 -272.331073) (xy 270.438087 -272.321229)
			(xy 270.487262 -272.319248) (xy 270.536117 -272.32518) (xy 270.583388 -272.338872) (xy 270.62785 -272.35997)
			(xy 270.668353 -272.387926) (xy 270.703846 -272.422018) (xy 270.733411 -272.461362) (xy 270.756282 -272.504939)
			(xy 270.771866 -272.55162) (xy 270.779761 -272.600197) (xy 270.780256 -272.624804) (xy 270.779761 -272.649411)
			(xy 270.771866 -272.697988) (xy 270.756282 -272.744669) (xy 270.733411 -272.788246) (xy 270.703846 -272.82759)
			(xy 270.668353 -272.861682) (xy 270.62785 -272.889638) (xy 270.583388 -272.910736) (xy 270.536117 -272.924428)
			(xy 270.487262 -272.93036) (xy 270.438087 -272.928379) (xy 270.389868 -272.918535) (xy 270.343852 -272.901083)
			(xy 270.301231 -272.876476) (xy 270.26311 -272.845351) (xy 270.230475 -272.808514) (xy 270.204172 -272.766918)
			(xy 270.184881 -272.721642) (xy 270.173104 -272.673858) (xy 270.169144 -272.624804) (xy 264.013675 -272.624804)
			(xy 263.92124 -272.734963) (xy 263.819753 -272.843502) (xy 263.712586 -272.946437) (xy 263.600049 -273.043471)
			(xy 263.493896 -273.125492) (xy 276.32304 -273.125492) (xy 276.32304 -273.074076) (xy 276.331083 -273.023294)
			(xy 276.346971 -272.974395) (xy 276.370314 -272.928583) (xy 276.400535 -272.886987) (xy 276.436891 -272.850631)
			(xy 276.478487 -272.82041) (xy 276.524299 -272.797067) (xy 276.573198 -272.781179) (xy 276.62398 -272.773136)
			(xy 276.675396 -272.773136) (xy 276.726178 -272.781179) (xy 276.775077 -272.797067) (xy 276.820889 -272.82041)
			(xy 276.862485 -272.850631) (xy 276.898841 -272.886987) (xy 276.929062 -272.928583) (xy 276.952405 -272.974395)
			(xy 276.968293 -273.023294) (xy 276.976336 -273.074076) (xy 276.97684 -273.099784) (xy 276.976336 -273.125492)
			(xy 276.968293 -273.176274) (xy 276.952405 -273.225173) (xy 276.929062 -273.270985) (xy 276.898841 -273.312581)
			(xy 276.862485 -273.348937) (xy 276.820889 -273.379158) (xy 276.775077 -273.402501) (xy 276.726178 -273.418389)
			(xy 276.675396 -273.426432) (xy 276.62398 -273.426432) (xy 276.573198 -273.418389) (xy 276.524299 -273.402501)
			(xy 276.478487 -273.379158) (xy 276.436891 -273.348937) (xy 276.400535 -273.312581) (xy 276.370314 -273.270985)
			(xy 276.346971 -273.225173) (xy 276.331083 -273.176274) (xy 276.32304 -273.125492) (xy 263.493896 -273.125492)
			(xy 263.482466 -273.134324) (xy 263.360176 -273.218735) (xy 263.233531 -273.29646) (xy 263.102896 -273.367276)
			(xy 262.968649 -273.430977) (xy 262.831176 -273.48738) (xy 262.690873 -273.536323) (xy 262.558161 -273.574764)
			(xy 272.069064 -273.574764) (xy 272.073024 -273.52571) (xy 272.084801 -273.477926) (xy 272.104092 -273.43265)
			(xy 272.130395 -273.391054) (xy 272.16303 -273.354217) (xy 272.201151 -273.323092) (xy 272.243772 -273.298485)
			(xy 272.289788 -273.281033) (xy 272.338007 -273.271189) (xy 272.387182 -273.269208) (xy 272.436037 -273.27514)
			(xy 272.483308 -273.288832) (xy 272.52777 -273.30993) (xy 272.568273 -273.337886) (xy 272.603766 -273.371978)
			(xy 272.633331 -273.411322) (xy 272.656202 -273.454899) (xy 272.671786 -273.50158) (xy 272.679681 -273.550157)
			(xy 272.680176 -273.574764) (xy 273.968984 -273.574764) (xy 273.972944 -273.52571) (xy 273.984721 -273.477926)
			(xy 274.004012 -273.43265) (xy 274.030315 -273.391054) (xy 274.06295 -273.354217) (xy 274.101071 -273.323092)
			(xy 274.143692 -273.298485) (xy 274.189708 -273.281033) (xy 274.237927 -273.271189) (xy 274.287102 -273.269208)
			(xy 274.335957 -273.27514) (xy 274.383228 -273.288832) (xy 274.42769 -273.30993) (xy 274.468193 -273.337886)
			(xy 274.503686 -273.371978) (xy 274.533251 -273.411322) (xy 274.556122 -273.454899) (xy 274.571706 -273.50158)
			(xy 274.579601 -273.550157) (xy 274.580096 -273.574764) (xy 274.579601 -273.599371) (xy 274.571706 -273.647948)
			(xy 274.556122 -273.694629) (xy 274.533251 -273.738206) (xy 274.503686 -273.77755) (xy 274.468193 -273.811642)
			(xy 274.42769 -273.839598) (xy 274.383228 -273.860696) (xy 274.335957 -273.874388) (xy 274.287102 -273.88032)
			(xy 274.237927 -273.878339) (xy 274.189708 -273.868495) (xy 274.143692 -273.851043) (xy 274.101071 -273.826436)
			(xy 274.06295 -273.795311) (xy 274.030315 -273.758474) (xy 274.004012 -273.716878) (xy 273.984721 -273.671602)
			(xy 273.972944 -273.623818) (xy 273.968984 -273.574764) (xy 272.680176 -273.574764) (xy 272.679681 -273.599371)
			(xy 272.671786 -273.647948) (xy 272.656202 -273.694629) (xy 272.633331 -273.738206) (xy 272.603766 -273.77755)
			(xy 272.568273 -273.811642) (xy 272.52777 -273.839598) (xy 272.483308 -273.860696) (xy 272.436037 -273.874388)
			(xy 272.387182 -273.88032) (xy 272.338007 -273.878339) (xy 272.289788 -273.868495) (xy 272.243772 -273.851043)
			(xy 272.201151 -273.826436) (xy 272.16303 -273.795311) (xy 272.130395 -273.758474) (xy 272.104092 -273.716878)
			(xy 272.084801 -273.671602) (xy 272.073024 -273.623818) (xy 272.069064 -273.574764) (xy 262.558161 -273.574764)
			(xy 262.548146 -273.577665) (xy 262.403405 -273.611285) (xy 262.257069 -273.637088) (xy 262.109558 -273.654999)
			(xy 261.961299 -273.664967) (xy 261.812718 -273.666962) (xy 261.664245 -273.660978) (xy 261.516306 -273.647034)
			(xy 261.36933 -273.625169) (xy 261.223739 -273.595447) (xy 261.079953 -273.557952) (xy 260.938387 -273.512793)
			(xy 260.799449 -273.460101) (xy 260.66354 -273.400027) (xy 260.531051 -273.332745) (xy 260.402365 -273.258448)
			(xy 260.277852 -273.177351) (xy 260.157872 -273.089687) (xy 260.042771 -272.995709) (xy 259.932879 -272.895689)
			(xy 259.828515 -272.789914) (xy 259.729979 -272.67869) (xy 259.637555 -272.562337) (xy 259.55151 -272.44119)
			(xy 259.472092 -272.3156) (xy 259.399529 -272.185928) (xy 259.334031 -272.052548) (xy 259.275787 -271.915845)
			(xy 259.224965 -271.776212) (xy 259.181711 -271.634053) (xy 259.14615 -271.489776) (xy 259.118385 -271.3438)
			(xy 259.098495 -271.196543) (xy 259.086538 -271.04843) (xy 259.082549 -270.89989) (xy 252.527054 -270.89989)
			(xy 252.527054 -274.075452) (xy 276.32304 -274.075452) (xy 276.32304 -274.024036) (xy 276.331083 -273.973254)
			(xy 276.346971 -273.924355) (xy 276.370314 -273.878543) (xy 276.400535 -273.836947) (xy 276.436891 -273.800591)
			(xy 276.478487 -273.77037) (xy 276.524299 -273.747027) (xy 276.573198 -273.731139) (xy 276.62398 -273.723096)
			(xy 276.675396 -273.723096) (xy 276.726178 -273.731139) (xy 276.775077 -273.747027) (xy 276.820889 -273.77037)
			(xy 276.862485 -273.800591) (xy 276.898841 -273.836947) (xy 276.929062 -273.878543) (xy 276.952405 -273.924355)
			(xy 276.968293 -273.973254) (xy 276.976336 -274.024036) (xy 276.97684 -274.049744) (xy 276.976336 -274.075452)
			(xy 278.223214 -274.075452) (xy 278.223214 -274.024036) (xy 278.231257 -273.973254) (xy 278.247145 -273.924355)
			(xy 278.270488 -273.878543) (xy 278.300709 -273.836947) (xy 278.337065 -273.800591) (xy 278.378661 -273.77037)
			(xy 278.424473 -273.747027) (xy 278.473372 -273.731139) (xy 278.524154 -273.723096) (xy 278.57557 -273.723096)
			(xy 278.626352 -273.731139) (xy 278.675251 -273.747027) (xy 278.721063 -273.77037) (xy 278.762659 -273.800591)
			(xy 278.799015 -273.836947) (xy 278.829236 -273.878543) (xy 278.852579 -273.924355) (xy 278.868467 -273.973254)
			(xy 278.87651 -274.024036) (xy 278.877014 -274.049744) (xy 278.87651 -274.075452) (xy 278.868467 -274.126234)
			(xy 278.852579 -274.175133) (xy 278.829236 -274.220945) (xy 278.799015 -274.262541) (xy 278.762659 -274.298897)
			(xy 278.721063 -274.329118) (xy 278.675251 -274.352461) (xy 278.626352 -274.368349) (xy 278.57557 -274.376392)
			(xy 278.524154 -274.376392) (xy 278.473372 -274.368349) (xy 278.424473 -274.352461) (xy 278.378661 -274.329118)
			(xy 278.337065 -274.298897) (xy 278.300709 -274.262541) (xy 278.270488 -274.220945) (xy 278.247145 -274.175133)
			(xy 278.231257 -274.126234) (xy 278.223214 -274.075452) (xy 276.976336 -274.075452) (xy 276.968293 -274.126234)
			(xy 276.952405 -274.175133) (xy 276.929062 -274.220945) (xy 276.898841 -274.262541) (xy 276.862485 -274.298897)
			(xy 276.820889 -274.329118) (xy 276.775077 -274.352461) (xy 276.726178 -274.368349) (xy 276.675396 -274.376392)
			(xy 276.62398 -274.376392) (xy 276.573198 -274.368349) (xy 276.524299 -274.352461) (xy 276.478487 -274.329118)
			(xy 276.436891 -274.298897) (xy 276.400535 -274.262541) (xy 276.370314 -274.220945) (xy 276.346971 -274.175133)
			(xy 276.331083 -274.126234) (xy 276.32304 -274.075452) (xy 252.527054 -274.075452) (xy 252.527054 -274.4216)
			(xy 252.527479 -274.431669) (xy 252.535199 -274.450268) (xy 252.54204 -274.457668) (xy 252.60935 -274.524978)
			(xy 271.119104 -274.524978) (xy 271.123064 -274.475924) (xy 271.134841 -274.42814) (xy 271.154132 -274.382864)
			(xy 271.180435 -274.341268) (xy 271.21307 -274.304431) (xy 271.251191 -274.273306) (xy 271.293812 -274.248699)
			(xy 271.339828 -274.231247) (xy 271.388047 -274.221403) (xy 271.437222 -274.219422) (xy 271.486077 -274.225354)
			(xy 271.533348 -274.239046) (xy 271.57781 -274.260144) (xy 271.618313 -274.2881) (xy 271.653806 -274.322192)
			(xy 271.683371 -274.361536) (xy 271.706242 -274.405113) (xy 271.721826 -274.451794) (xy 271.729721 -274.500371)
			(xy 271.730216 -274.524978) (xy 273.019024 -274.524978) (xy 273.022984 -274.475924) (xy 273.034761 -274.42814)
			(xy 273.054052 -274.382864) (xy 273.080355 -274.341268) (xy 273.11299 -274.304431) (xy 273.151111 -274.273306)
			(xy 273.193732 -274.248699) (xy 273.239748 -274.231247) (xy 273.287967 -274.221403) (xy 273.337142 -274.219422)
			(xy 273.385997 -274.225354) (xy 273.433268 -274.239046) (xy 273.47773 -274.260144) (xy 273.518233 -274.2881)
			(xy 273.553726 -274.322192) (xy 273.583291 -274.361536) (xy 273.606162 -274.405113) (xy 273.621746 -274.451794)
			(xy 273.629641 -274.500371) (xy 273.630136 -274.524978) (xy 274.918944 -274.524978) (xy 274.922904 -274.475924)
			(xy 274.934681 -274.42814) (xy 274.953972 -274.382864) (xy 274.980275 -274.341268) (xy 275.01291 -274.304431)
			(xy 275.051031 -274.273306) (xy 275.093652 -274.248699) (xy 275.139668 -274.231247) (xy 275.187887 -274.221403)
			(xy 275.237062 -274.219422) (xy 275.285917 -274.225354) (xy 275.333188 -274.239046) (xy 275.37765 -274.260144)
			(xy 275.418153 -274.2881) (xy 275.453646 -274.322192) (xy 275.483211 -274.361536) (xy 275.506082 -274.405113)
			(xy 275.521666 -274.451794) (xy 275.529561 -274.500371) (xy 275.530056 -274.524978) (xy 275.529561 -274.549585)
			(xy 275.521666 -274.598162) (xy 275.506082 -274.644843) (xy 275.483211 -274.68842) (xy 275.453646 -274.727764)
			(xy 275.418153 -274.761856) (xy 275.37765 -274.789812) (xy 275.333188 -274.81091) (xy 275.285917 -274.824602)
			(xy 275.237062 -274.830534) (xy 275.187887 -274.828553) (xy 275.139668 -274.818709) (xy 275.093652 -274.801257)
			(xy 275.051031 -274.77665) (xy 275.01291 -274.745525) (xy 274.980275 -274.708688) (xy 274.953972 -274.667092)
			(xy 274.934681 -274.621816) (xy 274.922904 -274.574032) (xy 274.918944 -274.524978) (xy 273.630136 -274.524978)
			(xy 273.629641 -274.549585) (xy 273.621746 -274.598162) (xy 273.606162 -274.644843) (xy 273.583291 -274.68842)
			(xy 273.553726 -274.727764) (xy 273.518233 -274.761856) (xy 273.47773 -274.789812) (xy 273.433268 -274.81091)
			(xy 273.385997 -274.824602) (xy 273.337142 -274.830534) (xy 273.287967 -274.828553) (xy 273.239748 -274.818709)
			(xy 273.193732 -274.801257) (xy 273.151111 -274.77665) (xy 273.11299 -274.745525) (xy 273.080355 -274.708688)
			(xy 273.054052 -274.667092) (xy 273.034761 -274.621816) (xy 273.022984 -274.574032) (xy 273.019024 -274.524978)
			(xy 271.730216 -274.524978) (xy 271.729721 -274.549585) (xy 271.721826 -274.598162) (xy 271.706242 -274.644843)
			(xy 271.683371 -274.68842) (xy 271.653806 -274.727764) (xy 271.618313 -274.761856) (xy 271.57781 -274.789812)
			(xy 271.533348 -274.81091) (xy 271.486077 -274.824602) (xy 271.437222 -274.830534) (xy 271.388047 -274.828553)
			(xy 271.339828 -274.818709) (xy 271.293812 -274.801257) (xy 271.251191 -274.77665) (xy 271.21307 -274.745525)
			(xy 271.180435 -274.708688) (xy 271.154132 -274.667092) (xy 271.134841 -274.621816) (xy 271.123064 -274.574032)
			(xy 271.119104 -274.524978) (xy 252.60935 -274.524978) (xy 253.110038 -275.025666) (xy 277.273254 -275.025666)
			(xy 277.273254 -274.97425) (xy 277.281297 -274.923468) (xy 277.297185 -274.874569) (xy 277.320528 -274.828757)
			(xy 277.350749 -274.787161) (xy 277.387105 -274.750805) (xy 277.428701 -274.720584) (xy 277.474513 -274.697241)
			(xy 277.523412 -274.681353) (xy 277.574194 -274.67331) (xy 277.62561 -274.67331) (xy 277.676392 -274.681353)
			(xy 277.725291 -274.697241) (xy 277.771103 -274.720584) (xy 277.812699 -274.750805) (xy 277.849055 -274.787161)
			(xy 277.879276 -274.828757) (xy 277.902619 -274.874569) (xy 277.918507 -274.923468) (xy 277.92655 -274.97425)
			(xy 277.927054 -274.999958) (xy 277.92655 -275.025666) (xy 277.918507 -275.076448) (xy 277.902619 -275.125347)
			(xy 277.879276 -275.171159) (xy 277.849055 -275.212755) (xy 277.812699 -275.249111) (xy 277.771103 -275.279332)
			(xy 277.725291 -275.302675) (xy 277.676392 -275.318563) (xy 277.62561 -275.326606) (xy 277.574194 -275.326606)
			(xy 277.523412 -275.318563) (xy 277.474513 -275.302675) (xy 277.428701 -275.279332) (xy 277.387105 -275.249111)
			(xy 277.350749 -275.212755) (xy 277.320528 -275.171159) (xy 277.297185 -275.125347) (xy 277.281297 -275.076448)
			(xy 277.273254 -275.025666) (xy 253.110038 -275.025666) (xy 253.55931 -275.474938) (xy 271.119104 -275.474938)
			(xy 271.123064 -275.425884) (xy 271.134841 -275.3781) (xy 271.154132 -275.332824) (xy 271.180435 -275.291228)
			(xy 271.21307 -275.254391) (xy 271.251191 -275.223266) (xy 271.293812 -275.198659) (xy 271.339828 -275.181207)
			(xy 271.388047 -275.171363) (xy 271.437222 -275.169382) (xy 271.486077 -275.175314) (xy 271.533348 -275.189006)
			(xy 271.57781 -275.210104) (xy 271.618313 -275.23806) (xy 271.653806 -275.272152) (xy 271.683371 -275.311496)
			(xy 271.706242 -275.355073) (xy 271.721826 -275.401754) (xy 271.729721 -275.450331) (xy 271.730216 -275.474938)
			(xy 273.019024 -275.474938) (xy 273.022984 -275.425884) (xy 273.034761 -275.3781) (xy 273.054052 -275.332824)
			(xy 273.080355 -275.291228) (xy 273.11299 -275.254391) (xy 273.151111 -275.223266) (xy 273.193732 -275.198659)
			(xy 273.239748 -275.181207) (xy 273.287967 -275.171363) (xy 273.337142 -275.169382) (xy 273.385997 -275.175314)
			(xy 273.433268 -275.189006) (xy 273.47773 -275.210104) (xy 273.518233 -275.23806) (xy 273.553726 -275.272152)
			(xy 273.583291 -275.311496) (xy 273.606162 -275.355073) (xy 273.621746 -275.401754) (xy 273.629641 -275.450331)
			(xy 273.630136 -275.474938) (xy 274.918944 -275.474938) (xy 274.922904 -275.425884) (xy 274.934681 -275.3781)
			(xy 274.953972 -275.332824) (xy 274.980275 -275.291228) (xy 275.01291 -275.254391) (xy 275.051031 -275.223266)
			(xy 275.093652 -275.198659) (xy 275.139668 -275.181207) (xy 275.187887 -275.171363) (xy 275.237062 -275.169382)
			(xy 275.285917 -275.175314) (xy 275.333188 -275.189006) (xy 275.37765 -275.210104) (xy 275.418153 -275.23806)
			(xy 275.453646 -275.272152) (xy 275.483211 -275.311496) (xy 275.506082 -275.355073) (xy 275.521666 -275.401754)
			(xy 275.529561 -275.450331) (xy 275.530056 -275.474938) (xy 275.529561 -275.499545) (xy 275.521666 -275.548122)
			(xy 275.506082 -275.594803) (xy 275.483211 -275.63838) (xy 275.453646 -275.677724) (xy 275.418153 -275.711816)
			(xy 275.37765 -275.739772) (xy 275.333188 -275.76087) (xy 275.285917 -275.774562) (xy 275.237062 -275.780494)
			(xy 275.187887 -275.778513) (xy 275.139668 -275.768669) (xy 275.093652 -275.751217) (xy 275.051031 -275.72661)
			(xy 275.01291 -275.695485) (xy 274.980275 -275.658648) (xy 274.953972 -275.617052) (xy 274.934681 -275.571776)
			(xy 274.922904 -275.523992) (xy 274.918944 -275.474938) (xy 273.630136 -275.474938) (xy 273.629641 -275.499545)
			(xy 273.621746 -275.548122) (xy 273.606162 -275.594803) (xy 273.583291 -275.63838) (xy 273.553726 -275.677724)
			(xy 273.518233 -275.711816) (xy 273.47773 -275.739772) (xy 273.433268 -275.76087) (xy 273.385997 -275.774562)
			(xy 273.337142 -275.780494) (xy 273.287967 -275.778513) (xy 273.239748 -275.768669) (xy 273.193732 -275.751217)
			(xy 273.151111 -275.72661) (xy 273.11299 -275.695485) (xy 273.080355 -275.658648) (xy 273.054052 -275.617052)
			(xy 273.034761 -275.571776) (xy 273.022984 -275.523992) (xy 273.019024 -275.474938) (xy 271.730216 -275.474938)
			(xy 271.729721 -275.499545) (xy 271.721826 -275.548122) (xy 271.706242 -275.594803) (xy 271.683371 -275.63838)
			(xy 271.653806 -275.677724) (xy 271.618313 -275.711816) (xy 271.57781 -275.739772) (xy 271.533348 -275.76087)
			(xy 271.486077 -275.774562) (xy 271.437222 -275.780494) (xy 271.388047 -275.778513) (xy 271.339828 -275.768669)
			(xy 271.293812 -275.751217) (xy 271.251191 -275.72661) (xy 271.21307 -275.695485) (xy 271.180435 -275.658648)
			(xy 271.154132 -275.617052) (xy 271.134841 -275.571776) (xy 271.123064 -275.523992) (xy 271.119104 -275.474938)
			(xy 253.55931 -275.474938) (xy 254.059998 -275.975626) (xy 277.273254 -275.975626) (xy 277.273254 -275.92421)
			(xy 277.281297 -275.873428) (xy 277.297185 -275.824529) (xy 277.320528 -275.778717) (xy 277.350749 -275.737121)
			(xy 277.387105 -275.700765) (xy 277.428701 -275.670544) (xy 277.474513 -275.647201) (xy 277.523412 -275.631313)
			(xy 277.574194 -275.62327) (xy 277.62561 -275.62327) (xy 277.676392 -275.631313) (xy 277.725291 -275.647201)
			(xy 277.771103 -275.670544) (xy 277.812699 -275.700765) (xy 277.849055 -275.737121) (xy 277.879276 -275.778717)
			(xy 277.902619 -275.824529) (xy 277.918507 -275.873428) (xy 277.92655 -275.92421) (xy 277.927054 -275.949918)
			(xy 277.92655 -275.975626) (xy 277.918507 -276.026408) (xy 277.902619 -276.075307) (xy 277.879276 -276.121119)
			(xy 277.849055 -276.162715) (xy 277.812699 -276.199071) (xy 277.771103 -276.229292) (xy 277.725291 -276.252635)
			(xy 277.676392 -276.268523) (xy 277.62561 -276.276566) (xy 277.574194 -276.276566) (xy 277.523412 -276.268523)
			(xy 277.474513 -276.252635) (xy 277.428701 -276.229292) (xy 277.387105 -276.199071) (xy 277.350749 -276.162715)
			(xy 277.320528 -276.121119) (xy 277.297185 -276.075307) (xy 277.281297 -276.026408) (xy 277.273254 -275.975626)
			(xy 254.059998 -275.975626) (xy 254.50927 -276.424898) (xy 268.26897 -276.424898) (xy 268.27293 -276.375844)
			(xy 268.284707 -276.32806) (xy 268.303998 -276.282784) (xy 268.330301 -276.241188) (xy 268.362936 -276.204351)
			(xy 268.401057 -276.173226) (xy 268.443678 -276.148619) (xy 268.489694 -276.131167) (xy 268.537913 -276.121323)
			(xy 268.587088 -276.119342) (xy 268.635943 -276.125274) (xy 268.683214 -276.138966) (xy 268.727676 -276.160064)
			(xy 268.768179 -276.18802) (xy 268.803672 -276.222112) (xy 268.833237 -276.261456) (xy 268.856108 -276.305033)
			(xy 268.871692 -276.351714) (xy 268.879587 -276.400291) (xy 268.880082 -276.424898) (xy 269.21893 -276.424898)
			(xy 269.22289 -276.375844) (xy 269.234667 -276.32806) (xy 269.253958 -276.282784) (xy 269.280261 -276.241188)
			(xy 269.312896 -276.204351) (xy 269.351017 -276.173226) (xy 269.393638 -276.148619) (xy 269.439654 -276.131167)
			(xy 269.487873 -276.121323) (xy 269.537048 -276.119342) (xy 269.585903 -276.125274) (xy 269.633174 -276.138966)
			(xy 269.677636 -276.160064) (xy 269.718139 -276.18802) (xy 269.753632 -276.222112) (xy 269.783197 -276.261456)
			(xy 269.806068 -276.305033) (xy 269.821652 -276.351714) (xy 269.829547 -276.400291) (xy 269.830042 -276.424898)
			(xy 269.829547 -276.449505) (xy 269.821652 -276.498082) (xy 269.806068 -276.544763) (xy 269.783197 -276.58834)
			(xy 269.753632 -276.627684) (xy 269.718139 -276.661776) (xy 269.677636 -276.689732) (xy 269.633174 -276.71083)
			(xy 269.585903 -276.724522) (xy 269.537048 -276.730454) (xy 269.487873 -276.728473) (xy 269.439654 -276.718629)
			(xy 269.393638 -276.701177) (xy 269.351017 -276.67657) (xy 269.312896 -276.645445) (xy 269.280261 -276.608608)
			(xy 269.253958 -276.567012) (xy 269.234667 -276.521736) (xy 269.22289 -276.473952) (xy 269.21893 -276.424898)
			(xy 268.880082 -276.424898) (xy 268.879587 -276.449505) (xy 268.871692 -276.498082) (xy 268.856108 -276.544763)
			(xy 268.833237 -276.58834) (xy 268.803672 -276.627684) (xy 268.768179 -276.661776) (xy 268.727676 -276.689732)
			(xy 268.683214 -276.71083) (xy 268.635943 -276.724522) (xy 268.587088 -276.730454) (xy 268.537913 -276.728473)
			(xy 268.489694 -276.718629) (xy 268.443678 -276.701177) (xy 268.401057 -276.67657) (xy 268.362936 -276.645445)
			(xy 268.330301 -276.608608) (xy 268.303998 -276.567012) (xy 268.284707 -276.521736) (xy 268.27293 -276.473952)
			(xy 268.26897 -276.424898) (xy 254.50927 -276.424898) (xy 255.45923 -277.374858) (xy 270.169144 -277.374858)
			(xy 270.173104 -277.325804) (xy 270.184881 -277.27802) (xy 270.204172 -277.232744) (xy 270.230475 -277.191148)
			(xy 270.26311 -277.154311) (xy 270.301231 -277.123186) (xy 270.343852 -277.098579) (xy 270.389868 -277.081127)
			(xy 270.438087 -277.071283) (xy 270.487262 -277.069302) (xy 270.536117 -277.075234) (xy 270.583388 -277.088926)
			(xy 270.62785 -277.110024) (xy 270.668353 -277.13798) (xy 270.703846 -277.172072) (xy 270.733411 -277.211416)
			(xy 270.756282 -277.254993) (xy 270.771866 -277.301674) (xy 270.779761 -277.350251) (xy 270.780256 -277.374858)
			(xy 272.069064 -277.374858) (xy 272.073024 -277.325804) (xy 272.084801 -277.27802) (xy 272.104092 -277.232744)
			(xy 272.130395 -277.191148) (xy 272.16303 -277.154311) (xy 272.201151 -277.123186) (xy 272.243772 -277.098579)
			(xy 272.289788 -277.081127) (xy 272.338007 -277.071283) (xy 272.387182 -277.069302) (xy 272.436037 -277.075234)
			(xy 272.483308 -277.088926) (xy 272.52777 -277.110024) (xy 272.568273 -277.13798) (xy 272.603766 -277.172072)
			(xy 272.633331 -277.211416) (xy 272.656202 -277.254993) (xy 272.671786 -277.301674) (xy 272.679681 -277.350251)
			(xy 272.680176 -277.374858) (xy 273.968984 -277.374858) (xy 273.972944 -277.325804) (xy 273.984721 -277.27802)
			(xy 274.004012 -277.232744) (xy 274.030315 -277.191148) (xy 274.06295 -277.154311) (xy 274.101071 -277.123186)
			(xy 274.143692 -277.098579) (xy 274.189708 -277.081127) (xy 274.237927 -277.071283) (xy 274.287102 -277.069302)
			(xy 274.335957 -277.075234) (xy 274.383228 -277.088926) (xy 274.42769 -277.110024) (xy 274.468193 -277.13798)
			(xy 274.503686 -277.172072) (xy 274.533251 -277.211416) (xy 274.556122 -277.254993) (xy 274.571706 -277.301674)
			(xy 274.579601 -277.350251) (xy 274.580096 -277.374858) (xy 274.579601 -277.399465) (xy 274.571706 -277.448042)
			(xy 274.556122 -277.494723) (xy 274.533251 -277.5383) (xy 274.503686 -277.577644) (xy 274.468193 -277.611736)
			(xy 274.42769 -277.639692) (xy 274.383228 -277.66079) (xy 274.335957 -277.674482) (xy 274.287102 -277.680414)
			(xy 274.237927 -277.678433) (xy 274.189708 -277.668589) (xy 274.143692 -277.651137) (xy 274.101071 -277.62653)
			(xy 274.06295 -277.595405) (xy 274.030315 -277.558568) (xy 274.004012 -277.516972) (xy 273.984721 -277.471696)
			(xy 273.972944 -277.423912) (xy 273.968984 -277.374858) (xy 272.680176 -277.374858) (xy 272.679681 -277.399465)
			(xy 272.671786 -277.448042) (xy 272.656202 -277.494723) (xy 272.633331 -277.5383) (xy 272.603766 -277.577644)
			(xy 272.568273 -277.611736) (xy 272.52777 -277.639692) (xy 272.483308 -277.66079) (xy 272.436037 -277.674482)
			(xy 272.387182 -277.680414) (xy 272.338007 -277.678433) (xy 272.289788 -277.668589) (xy 272.243772 -277.651137)
			(xy 272.201151 -277.62653) (xy 272.16303 -277.595405) (xy 272.130395 -277.558568) (xy 272.104092 -277.516972)
			(xy 272.084801 -277.471696) (xy 272.073024 -277.423912) (xy 272.069064 -277.374858) (xy 270.780256 -277.374858)
			(xy 270.779761 -277.399465) (xy 270.771866 -277.448042) (xy 270.756282 -277.494723) (xy 270.733411 -277.5383)
			(xy 270.703846 -277.577644) (xy 270.668353 -277.611736) (xy 270.62785 -277.639692) (xy 270.583388 -277.66079)
			(xy 270.536117 -277.674482) (xy 270.487262 -277.680414) (xy 270.438087 -277.678433) (xy 270.389868 -277.668589)
			(xy 270.343852 -277.651137) (xy 270.301231 -277.62653) (xy 270.26311 -277.595405) (xy 270.230475 -277.558568)
			(xy 270.204172 -277.516972) (xy 270.184881 -277.471696) (xy 270.173104 -277.423912) (xy 270.169144 -277.374858)
			(xy 255.45923 -277.374858) (xy 255.959918 -277.875546) (xy 276.32304 -277.875546) (xy 276.32304 -277.82413)
			(xy 276.331083 -277.773348) (xy 276.346971 -277.724449) (xy 276.370314 -277.678637) (xy 276.400535 -277.637041)
			(xy 276.436891 -277.600685) (xy 276.478487 -277.570464) (xy 276.524299 -277.547121) (xy 276.573198 -277.531233)
			(xy 276.62398 -277.52319) (xy 276.675396 -277.52319) (xy 276.726178 -277.531233) (xy 276.775077 -277.547121)
			(xy 276.820889 -277.570464) (xy 276.862485 -277.600685) (xy 276.898841 -277.637041) (xy 276.929062 -277.678637)
			(xy 276.952405 -277.724449) (xy 276.968293 -277.773348) (xy 276.976336 -277.82413) (xy 276.97684 -277.849838)
			(xy 276.976336 -277.875546) (xy 278.223214 -277.875546) (xy 278.223214 -277.82413) (xy 278.231257 -277.773348)
			(xy 278.247145 -277.724449) (xy 278.270488 -277.678637) (xy 278.300709 -277.637041) (xy 278.337065 -277.600685)
			(xy 278.378661 -277.570464) (xy 278.424473 -277.547121) (xy 278.473372 -277.531233) (xy 278.524154 -277.52319)
			(xy 278.57557 -277.52319) (xy 278.626352 -277.531233) (xy 278.675251 -277.547121) (xy 278.721063 -277.570464)
			(xy 278.762659 -277.600685) (xy 278.799015 -277.637041) (xy 278.829236 -277.678637) (xy 278.852579 -277.724449)
			(xy 278.868467 -277.773348) (xy 278.87651 -277.82413) (xy 278.877014 -277.849838) (xy 278.87651 -277.875546)
			(xy 278.868467 -277.926328) (xy 278.852579 -277.975227) (xy 278.829236 -278.021039) (xy 278.799015 -278.062635)
			(xy 278.762659 -278.098991) (xy 278.721063 -278.129212) (xy 278.675251 -278.152555) (xy 278.626352 -278.168443)
			(xy 278.57557 -278.176486) (xy 278.524154 -278.176486) (xy 278.473372 -278.168443) (xy 278.424473 -278.152555)
			(xy 278.378661 -278.129212) (xy 278.337065 -278.098991) (xy 278.300709 -278.062635) (xy 278.270488 -278.021039)
			(xy 278.247145 -277.975227) (xy 278.231257 -277.926328) (xy 278.223214 -277.875546) (xy 276.976336 -277.875546)
			(xy 276.968293 -277.926328) (xy 276.952405 -277.975227) (xy 276.929062 -278.021039) (xy 276.898841 -278.062635)
			(xy 276.862485 -278.098991) (xy 276.820889 -278.129212) (xy 276.775077 -278.152555) (xy 276.726178 -278.168443)
			(xy 276.675396 -278.176486) (xy 276.62398 -278.176486) (xy 276.573198 -278.168443) (xy 276.524299 -278.152555)
			(xy 276.478487 -278.129212) (xy 276.436891 -278.098991) (xy 276.400535 -278.062635) (xy 276.370314 -278.021039)
			(xy 276.346971 -277.975227) (xy 276.331083 -277.926328) (xy 276.32304 -277.875546) (xy 255.959918 -277.875546)
			(xy 256.40919 -278.324818) (xy 270.169144 -278.324818) (xy 270.173104 -278.275764) (xy 270.184881 -278.22798)
			(xy 270.204172 -278.182704) (xy 270.230475 -278.141108) (xy 270.26311 -278.104271) (xy 270.301231 -278.073146)
			(xy 270.343852 -278.048539) (xy 270.389868 -278.031087) (xy 270.438087 -278.021243) (xy 270.487262 -278.019262)
			(xy 270.536117 -278.025194) (xy 270.583388 -278.038886) (xy 270.62785 -278.059984) (xy 270.668353 -278.08794)
			(xy 270.703846 -278.122032) (xy 270.733411 -278.161376) (xy 270.756282 -278.204953) (xy 270.771866 -278.251634)
			(xy 270.779761 -278.300211) (xy 270.780256 -278.324818) (xy 272.069064 -278.324818) (xy 272.073024 -278.275764)
			(xy 272.084801 -278.22798) (xy 272.104092 -278.182704) (xy 272.130395 -278.141108) (xy 272.16303 -278.104271)
			(xy 272.201151 -278.073146) (xy 272.243772 -278.048539) (xy 272.289788 -278.031087) (xy 272.338007 -278.021243)
			(xy 272.387182 -278.019262) (xy 272.436037 -278.025194) (xy 272.483308 -278.038886) (xy 272.52777 -278.059984)
			(xy 272.568273 -278.08794) (xy 272.603766 -278.122032) (xy 272.633331 -278.161376) (xy 272.656202 -278.204953)
			(xy 272.671786 -278.251634) (xy 272.679681 -278.300211) (xy 272.680176 -278.324818) (xy 273.968984 -278.324818)
			(xy 273.972944 -278.275764) (xy 273.984721 -278.22798) (xy 274.004012 -278.182704) (xy 274.030315 -278.141108)
			(xy 274.06295 -278.104271) (xy 274.101071 -278.073146) (xy 274.143692 -278.048539) (xy 274.189708 -278.031087)
			(xy 274.237927 -278.021243) (xy 274.287102 -278.019262) (xy 274.335957 -278.025194) (xy 274.383228 -278.038886)
			(xy 274.42769 -278.059984) (xy 274.468193 -278.08794) (xy 274.503686 -278.122032) (xy 274.533251 -278.161376)
			(xy 274.556122 -278.204953) (xy 274.571706 -278.251634) (xy 274.579601 -278.300211) (xy 274.580096 -278.324818)
			(xy 274.579601 -278.349425) (xy 274.571706 -278.398002) (xy 274.556122 -278.444683) (xy 274.533251 -278.48826)
			(xy 274.503686 -278.527604) (xy 274.468193 -278.561696) (xy 274.42769 -278.589652) (xy 274.383228 -278.61075)
			(xy 274.335957 -278.624442) (xy 274.287102 -278.630374) (xy 274.237927 -278.628393) (xy 274.189708 -278.618549)
			(xy 274.143692 -278.601097) (xy 274.101071 -278.57649) (xy 274.06295 -278.545365) (xy 274.030315 -278.508528)
			(xy 274.004012 -278.466932) (xy 273.984721 -278.421656) (xy 273.972944 -278.373872) (xy 273.968984 -278.324818)
			(xy 272.680176 -278.324818) (xy 272.679681 -278.349425) (xy 272.671786 -278.398002) (xy 272.656202 -278.444683)
			(xy 272.633331 -278.48826) (xy 272.603766 -278.527604) (xy 272.568273 -278.561696) (xy 272.52777 -278.589652)
			(xy 272.483308 -278.61075) (xy 272.436037 -278.624442) (xy 272.387182 -278.630374) (xy 272.338007 -278.628393)
			(xy 272.289788 -278.618549) (xy 272.243772 -278.601097) (xy 272.201151 -278.57649) (xy 272.16303 -278.545365)
			(xy 272.130395 -278.508528) (xy 272.104092 -278.466932) (xy 272.084801 -278.421656) (xy 272.073024 -278.373872)
			(xy 272.069064 -278.324818) (xy 270.780256 -278.324818) (xy 270.779761 -278.349425) (xy 270.771866 -278.398002)
			(xy 270.756282 -278.444683) (xy 270.733411 -278.48826) (xy 270.703846 -278.527604) (xy 270.668353 -278.561696)
			(xy 270.62785 -278.589652) (xy 270.583388 -278.61075) (xy 270.536117 -278.624442) (xy 270.487262 -278.630374)
			(xy 270.438087 -278.628393) (xy 270.389868 -278.618549) (xy 270.343852 -278.601097) (xy 270.301231 -278.57649)
			(xy 270.26311 -278.545365) (xy 270.230475 -278.508528) (xy 270.204172 -278.466932) (xy 270.184881 -278.421656)
			(xy 270.173104 -278.373872) (xy 270.169144 -278.324818) (xy 256.40919 -278.324818) (xy 259.60832 -281.523948)
			(xy 259.644896 -281.52725) (xy 259.660136 -281.516582) (xy 259.684287 -281.50035) (xy 259.736477 -281.47462)
			(xy 259.791972 -281.457126) (xy 259.849482 -281.448274) (xy 259.878576 -281.447748) (xy 259.90583 -281.448232)
			(xy 259.959782 -281.455986) (xy 260.012082 -281.471338) (xy 260.061665 -281.493977) (xy 260.107522 -281.523442)
			(xy 260.148719 -281.559133) (xy 260.184417 -281.600324) (xy 260.21389 -281.646175) (xy 260.236538 -281.695754)
			(xy 260.2519 -281.748051) (xy 260.259663 -281.802003) (xy 260.260084 -281.829256) (xy 260.259512 -281.858346)
			(xy 260.25064 -281.915846) (xy 260.233156 -281.971337) (xy 260.207463 -282.023537) (xy 260.19125 -282.047696)
			(xy 260.180582 -282.062936) (xy 260.183884 -282.099512) (xy 260.839204 -282.754832) (xy 260.850634 -282.761436)
			(xy 260.856984 -282.763214) (xy 260.877506 -282.769009) (xy 260.917223 -282.784539) (xy 260.936232 -282.794202)
			(xy 260.94817 -282.800552) (xy 260.97484 -282.79979) (xy 261.060946 -282.747974) (xy 261.068259 -282.743192)
			(xy 261.079353 -282.729709) (xy 261.085236 -282.71327) (xy 261.085584 -282.70454) (xy 261.085584 -280.279094)
			(xy 261.086087 -280.247472) (xy 261.094311 -280.184765) (xy 261.110644 -280.123667) (xy 261.134807 -280.065221)
			(xy 261.166386 -280.010426) (xy 261.204843 -279.960218) (xy 261.226808 -279.937464) (xy 262.42137 -278.742902)
			(xy 262.444088 -278.720883) (xy 262.494281 -278.682368) (xy 262.549073 -278.650737) (xy 262.607526 -278.62653)
			(xy 262.668639 -278.610163) (xy 262.731366 -278.601915) (xy 262.763 -278.601424) (xy 264.032746 -278.601424)
			(xy 264.064371 -278.601922) (xy 264.127078 -278.610186) (xy 264.188169 -278.626566) (xy 264.2466 -278.650781)
			(xy 264.301368 -278.682418) (xy 264.351537 -278.720935) (xy 264.396249 -278.765672) (xy 264.434736 -278.815863)
			(xy 264.440299 -278.825506) (xy 276.32304 -278.825506) (xy 276.32304 -278.77409) (xy 276.331083 -278.723308)
			(xy 276.346971 -278.674409) (xy 276.370314 -278.628597) (xy 276.400535 -278.587001) (xy 276.436891 -278.550645)
			(xy 276.478487 -278.520424) (xy 276.524299 -278.497081) (xy 276.573198 -278.481193) (xy 276.62398 -278.47315)
			(xy 276.675396 -278.47315) (xy 276.726178 -278.481193) (xy 276.775077 -278.497081) (xy 276.820889 -278.520424)
			(xy 276.862485 -278.550645) (xy 276.898841 -278.587001) (xy 276.929062 -278.628597) (xy 276.952405 -278.674409)
			(xy 276.968293 -278.723308) (xy 276.976336 -278.77409) (xy 276.97684 -278.799798) (xy 276.976336 -278.825506)
			(xy 278.223214 -278.825506) (xy 278.223214 -278.77409) (xy 278.231257 -278.723308) (xy 278.247145 -278.674409)
			(xy 278.270488 -278.628597) (xy 278.300709 -278.587001) (xy 278.337065 -278.550645) (xy 278.378661 -278.520424)
			(xy 278.424473 -278.497081) (xy 278.473372 -278.481193) (xy 278.524154 -278.47315) (xy 278.57557 -278.47315)
			(xy 278.626352 -278.481193) (xy 278.675251 -278.497081) (xy 278.721063 -278.520424) (xy 278.762659 -278.550645)
			(xy 278.799015 -278.587001) (xy 278.829236 -278.628597) (xy 278.852579 -278.674409) (xy 278.868467 -278.723308)
			(xy 278.87651 -278.77409) (xy 278.877014 -278.799798) (xy 278.87651 -278.825506) (xy 278.868467 -278.876288)
			(xy 278.852579 -278.925187) (xy 278.829236 -278.970999) (xy 278.799015 -279.012595) (xy 278.762659 -279.048951)
			(xy 278.721063 -279.079172) (xy 278.675251 -279.102515) (xy 278.626352 -279.118403) (xy 278.57557 -279.126446)
			(xy 278.524154 -279.126446) (xy 278.473372 -279.118403) (xy 278.424473 -279.102515) (xy 278.378661 -279.079172)
			(xy 278.337065 -279.048951) (xy 278.300709 -279.012595) (xy 278.270488 -278.970999) (xy 278.247145 -278.925187)
			(xy 278.231257 -278.876288) (xy 278.223214 -278.825506) (xy 276.976336 -278.825506) (xy 276.968293 -278.876288)
			(xy 276.952405 -278.925187) (xy 276.929062 -278.970999) (xy 276.898841 -279.012595) (xy 276.862485 -279.048951)
			(xy 276.820889 -279.079172) (xy 276.775077 -279.102515) (xy 276.726178 -279.118403) (xy 276.675396 -279.126446)
			(xy 276.62398 -279.126446) (xy 276.573198 -279.118403) (xy 276.524299 -279.102515) (xy 276.478487 -279.079172)
			(xy 276.436891 -279.048951) (xy 276.400535 -279.012595) (xy 276.370314 -278.970999) (xy 276.346971 -278.925187)
			(xy 276.331083 -278.876288) (xy 276.32304 -278.825506) (xy 264.440299 -278.825506) (xy 264.466342 -278.87065)
			(xy 264.490524 -278.929094) (xy 264.506869 -278.990195) (xy 264.515096 -279.052907) (xy 264.5156 -279.084532)
			(xy 264.515152 -279.114408) (xy 264.507779 -279.173703) (xy 264.49315 -279.231637) (xy 264.476368 -279.274778)
			(xy 268.26897 -279.274778) (xy 268.27293 -279.225724) (xy 268.284707 -279.17794) (xy 268.303998 -279.132664)
			(xy 268.330301 -279.091068) (xy 268.362936 -279.054231) (xy 268.401057 -279.023106) (xy 268.443678 -278.998499)
			(xy 268.489694 -278.981047) (xy 268.537913 -278.971203) (xy 268.587088 -278.969222) (xy 268.635943 -278.975154)
			(xy 268.683214 -278.988846) (xy 268.727676 -279.009944) (xy 268.768179 -279.0379) (xy 268.803672 -279.071992)
			(xy 268.833237 -279.111336) (xy 268.856108 -279.154913) (xy 268.871692 -279.201594) (xy 268.879587 -279.250171)
			(xy 268.880082 -279.274778) (xy 269.21893 -279.274778) (xy 269.22289 -279.225724) (xy 269.234667 -279.17794)
			(xy 269.253958 -279.132664) (xy 269.280261 -279.091068) (xy 269.312896 -279.054231) (xy 269.351017 -279.023106)
			(xy 269.393638 -278.998499) (xy 269.439654 -278.981047) (xy 269.487873 -278.971203) (xy 269.537048 -278.969222)
			(xy 269.585903 -278.975154) (xy 269.633174 -278.988846) (xy 269.677636 -279.009944) (xy 269.718139 -279.0379)
			(xy 269.753632 -279.071992) (xy 269.783197 -279.111336) (xy 269.806068 -279.154913) (xy 269.821652 -279.201594)
			(xy 269.829547 -279.250171) (xy 269.830042 -279.274778) (xy 271.119104 -279.274778) (xy 271.123064 -279.225724)
			(xy 271.134841 -279.17794) (xy 271.154132 -279.132664) (xy 271.180435 -279.091068) (xy 271.21307 -279.054231)
			(xy 271.251191 -279.023106) (xy 271.293812 -278.998499) (xy 271.339828 -278.981047) (xy 271.388047 -278.971203)
			(xy 271.437222 -278.969222) (xy 271.486077 -278.975154) (xy 271.533348 -278.988846) (xy 271.57781 -279.009944)
			(xy 271.618313 -279.0379) (xy 271.653806 -279.071992) (xy 271.683371 -279.111336) (xy 271.706242 -279.154913)
			(xy 271.721826 -279.201594) (xy 271.729721 -279.250171) (xy 271.730216 -279.274778) (xy 273.019024 -279.274778)
			(xy 273.022984 -279.225724) (xy 273.034761 -279.17794) (xy 273.054052 -279.132664) (xy 273.080355 -279.091068)
			(xy 273.11299 -279.054231) (xy 273.151111 -279.023106) (xy 273.193732 -278.998499) (xy 273.239748 -278.981047)
			(xy 273.287967 -278.971203) (xy 273.337142 -278.969222) (xy 273.385997 -278.975154) (xy 273.433268 -278.988846)
			(xy 273.47773 -279.009944) (xy 273.518233 -279.0379) (xy 273.553726 -279.071992) (xy 273.583291 -279.111336)
			(xy 273.606162 -279.154913) (xy 273.621746 -279.201594) (xy 273.629641 -279.250171) (xy 273.630136 -279.274778)
			(xy 273.629641 -279.299385) (xy 273.621746 -279.347962) (xy 273.606162 -279.394643) (xy 273.583291 -279.43822)
			(xy 273.553726 -279.477564) (xy 273.518233 -279.511656) (xy 273.47773 -279.539612) (xy 273.433268 -279.56071)
			(xy 273.385997 -279.574402) (xy 273.337142 -279.580334) (xy 273.287967 -279.578353) (xy 273.239748 -279.568509)
			(xy 273.193732 -279.551057) (xy 273.151111 -279.52645) (xy 273.11299 -279.495325) (xy 273.080355 -279.458488)
			(xy 273.054052 -279.416892) (xy 273.034761 -279.371616) (xy 273.022984 -279.323832) (xy 273.019024 -279.274778)
			(xy 271.730216 -279.274778) (xy 271.729721 -279.299385) (xy 271.721826 -279.347962) (xy 271.706242 -279.394643)
			(xy 271.683371 -279.43822) (xy 271.653806 -279.477564) (xy 271.618313 -279.511656) (xy 271.57781 -279.539612)
			(xy 271.533348 -279.56071) (xy 271.486077 -279.574402) (xy 271.437222 -279.580334) (xy 271.388047 -279.578353)
			(xy 271.339828 -279.568509) (xy 271.293812 -279.551057) (xy 271.251191 -279.52645) (xy 271.21307 -279.495325)
			(xy 271.180435 -279.458488) (xy 271.154132 -279.416892) (xy 271.134841 -279.371616) (xy 271.123064 -279.323832)
			(xy 271.119104 -279.274778) (xy 269.830042 -279.274778) (xy 269.829547 -279.299385) (xy 269.821652 -279.347962)
			(xy 269.806068 -279.394643) (xy 269.783197 -279.43822) (xy 269.753632 -279.477564) (xy 269.718139 -279.511656)
			(xy 269.677636 -279.539612) (xy 269.633174 -279.56071) (xy 269.585903 -279.574402) (xy 269.537048 -279.580334)
			(xy 269.487873 -279.578353) (xy 269.439654 -279.568509) (xy 269.393638 -279.551057) (xy 269.351017 -279.52645)
			(xy 269.312896 -279.495325) (xy 269.280261 -279.458488) (xy 269.253958 -279.416892) (xy 269.234667 -279.371616)
			(xy 269.22289 -279.323832) (xy 269.21893 -279.274778) (xy 268.880082 -279.274778) (xy 268.879587 -279.299385)
			(xy 268.871692 -279.347962) (xy 268.856108 -279.394643) (xy 268.833237 -279.43822) (xy 268.803672 -279.477564)
			(xy 268.768179 -279.511656) (xy 268.727676 -279.539612) (xy 268.683214 -279.56071) (xy 268.635943 -279.574402)
			(xy 268.587088 -279.580334) (xy 268.537913 -279.578353) (xy 268.489694 -279.568509) (xy 268.443678 -279.551057)
			(xy 268.401057 -279.52645) (xy 268.362936 -279.495325) (xy 268.330301 -279.458488) (xy 268.303998 -279.416892)
			(xy 268.284707 -279.371616) (xy 268.27293 -279.323832) (xy 268.26897 -279.274778) (xy 264.476368 -279.274778)
			(xy 264.471487 -279.287324) (xy 264.443123 -279.339914) (xy 264.408489 -279.388605) (xy 264.368114 -279.432653)
			(xy 264.322616 -279.471385) (xy 264.272688 -279.50421) (xy 264.246106 -279.517856) (xy 264.235184 -279.52319)
			(xy 264.22096 -279.541986) (xy 264.200894 -279.644856) (xy 264.207244 -279.667716) (xy 264.215118 -279.67686)
			(xy 264.233319 -279.697944) (xy 264.264047 -279.744399) (xy 264.278493 -279.775212) (xy 277.273254 -279.775212)
			(xy 277.273254 -279.723796) (xy 277.281297 -279.673014) (xy 277.297185 -279.624115) (xy 277.320528 -279.578303)
			(xy 277.350749 -279.536707) (xy 277.387105 -279.500351) (xy 277.428701 -279.47013) (xy 277.474513 -279.446787)
			(xy 277.523412 -279.430899) (xy 277.574194 -279.422856) (xy 277.62561 -279.422856) (xy 277.676392 -279.430899)
			(xy 277.725291 -279.446787) (xy 277.771103 -279.47013) (xy 277.812699 -279.500351) (xy 277.849055 -279.536707)
			(xy 277.879276 -279.578303) (xy 277.902619 -279.624115) (xy 277.918507 -279.673014) (xy 277.92655 -279.723796)
			(xy 277.927054 -279.749504) (xy 277.92655 -279.775212) (xy 277.918507 -279.825994) (xy 277.902619 -279.874893)
			(xy 277.879276 -279.920705) (xy 277.849055 -279.962301) (xy 277.812699 -279.998657) (xy 277.771103 -280.028878)
			(xy 277.725291 -280.052221) (xy 277.676392 -280.068109) (xy 277.62561 -280.076152) (xy 277.574194 -280.076152)
			(xy 277.523412 -280.068109) (xy 277.474513 -280.052221) (xy 277.428701 -280.028878) (xy 277.387105 -279.998657)
			(xy 277.350749 -279.962301) (xy 277.320528 -279.920705) (xy 277.297185 -279.874893) (xy 277.281297 -279.825994)
			(xy 277.273254 -279.775212) (xy 264.278493 -279.775212) (xy 264.28769 -279.79483) (xy 264.303747 -279.848163)
			(xy 264.311875 -279.903265) (xy 264.3124 -279.931114) (xy 264.311836 -279.960493) (xy 264.302786 -280.018552)
			(xy 264.284947 -280.074539) (xy 264.258741 -280.127131) (xy 264.224787 -280.175088) (xy 264.183887 -280.217276)
			(xy 264.174369 -280.224738) (xy 271.119104 -280.224738) (xy 271.123064 -280.175684) (xy 271.134841 -280.1279)
			(xy 271.154132 -280.082624) (xy 271.180435 -280.041028) (xy 271.21307 -280.004191) (xy 271.251191 -279.973066)
			(xy 271.293812 -279.948459) (xy 271.339828 -279.931007) (xy 271.388047 -279.921163) (xy 271.437222 -279.919182)
			(xy 271.486077 -279.925114) (xy 271.533348 -279.938806) (xy 271.57781 -279.959904) (xy 271.618313 -279.98786)
			(xy 271.653806 -280.021952) (xy 271.683371 -280.061296) (xy 271.706242 -280.104873) (xy 271.721826 -280.151554)
			(xy 271.729721 -280.200131) (xy 271.730216 -280.224738) (xy 273.019024 -280.224738) (xy 273.022984 -280.175684)
			(xy 273.034761 -280.1279) (xy 273.054052 -280.082624) (xy 273.080355 -280.041028) (xy 273.11299 -280.004191)
			(xy 273.151111 -279.973066) (xy 273.193732 -279.948459) (xy 273.239748 -279.931007) (xy 273.287967 -279.921163)
			(xy 273.337142 -279.919182) (xy 273.385997 -279.925114) (xy 273.433268 -279.938806) (xy 273.47773 -279.959904)
			(xy 273.518233 -279.98786) (xy 273.553726 -280.021952) (xy 273.583291 -280.061296) (xy 273.606162 -280.104873)
			(xy 273.621746 -280.151554) (xy 273.629641 -280.200131) (xy 273.630136 -280.224738) (xy 274.918944 -280.224738)
			(xy 274.922904 -280.175684) (xy 274.934681 -280.1279) (xy 274.953972 -280.082624) (xy 274.980275 -280.041028)
			(xy 275.01291 -280.004191) (xy 275.051031 -279.973066) (xy 275.093652 -279.948459) (xy 275.139668 -279.931007)
			(xy 275.187887 -279.921163) (xy 275.237062 -279.919182) (xy 275.285917 -279.925114) (xy 275.333188 -279.938806)
			(xy 275.37765 -279.959904) (xy 275.418153 -279.98786) (xy 275.453646 -280.021952) (xy 275.483211 -280.061296)
			(xy 275.506082 -280.104873) (xy 275.521666 -280.151554) (xy 275.529561 -280.200131) (xy 275.530056 -280.224738)
			(xy 275.529561 -280.249345) (xy 275.521666 -280.297922) (xy 275.506082 -280.344603) (xy 275.483211 -280.38818)
			(xy 275.453646 -280.427524) (xy 275.418153 -280.461616) (xy 275.37765 -280.489572) (xy 275.333188 -280.51067)
			(xy 275.285917 -280.524362) (xy 275.237062 -280.530294) (xy 275.187887 -280.528313) (xy 275.139668 -280.518469)
			(xy 275.093652 -280.501017) (xy 275.051031 -280.47641) (xy 275.01291 -280.445285) (xy 274.980275 -280.408448)
			(xy 274.953972 -280.366852) (xy 274.934681 -280.321576) (xy 274.922904 -280.273792) (xy 274.918944 -280.224738)
			(xy 273.630136 -280.224738) (xy 273.629641 -280.249345) (xy 273.621746 -280.297922) (xy 273.606162 -280.344603)
			(xy 273.583291 -280.38818) (xy 273.553726 -280.427524) (xy 273.518233 -280.461616) (xy 273.47773 -280.489572)
			(xy 273.433268 -280.51067) (xy 273.385997 -280.524362) (xy 273.337142 -280.530294) (xy 273.287967 -280.528313)
			(xy 273.239748 -280.518469) (xy 273.193732 -280.501017) (xy 273.151111 -280.47641) (xy 273.11299 -280.445285)
			(xy 273.080355 -280.408448) (xy 273.054052 -280.366852) (xy 273.034761 -280.321576) (xy 273.022984 -280.273792)
			(xy 273.019024 -280.224738) (xy 271.730216 -280.224738) (xy 271.729721 -280.249345) (xy 271.721826 -280.297922)
			(xy 271.706242 -280.344603) (xy 271.683371 -280.38818) (xy 271.653806 -280.427524) (xy 271.618313 -280.461616)
			(xy 271.57781 -280.489572) (xy 271.533348 -280.51067) (xy 271.486077 -280.524362) (xy 271.437222 -280.530294)
			(xy 271.388047 -280.528313) (xy 271.339828 -280.518469) (xy 271.293812 -280.501017) (xy 271.251191 -280.47641)
			(xy 271.21307 -280.445285) (xy 271.180435 -280.408448) (xy 271.154132 -280.366852) (xy 271.134841 -280.321576)
			(xy 271.123064 -280.273792) (xy 271.119104 -280.224738) (xy 264.174369 -280.224738) (xy 264.160762 -280.235406)
			(xy 264.151364 -280.242772) (xy 264.14095 -280.263346) (xy 264.139426 -280.367232) (xy 264.149332 -280.388314)
			(xy 264.158476 -280.39568) (xy 264.1803 -280.413911) (xy 264.218829 -280.455733) (xy 264.25073 -280.502806)
			(xy 264.275297 -280.554089) (xy 264.291988 -280.608448) (xy 264.300433 -280.664682) (xy 264.30097 -280.693114)
			(xy 264.934444 -280.693114) (xy 264.938515 -280.637492) (xy 264.950641 -280.583055) (xy 264.970564 -280.530964)
			(xy 264.99786 -280.482329) (xy 265.031946 -280.438186) (xy 265.072095 -280.399477) (xy 265.117453 -280.367026)
			(xy 265.167053 -280.341525) (xy 265.219837 -280.323518) (xy 265.27468 -280.313388) (xy 265.330414 -280.311351)
			(xy 265.385851 -280.317451) (xy 265.439808 -280.331557) (xy 265.491137 -280.353369) (xy 265.538743 -280.382423)
			(xy 265.581611 -280.418098) (xy 265.618828 -280.459635) (xy 265.649601 -280.506148) (xy 265.673273 -280.556645)
			(xy 265.689341 -280.610052) (xy 265.697461 -280.665228) (xy 265.69797 -280.693114) (xy 265.697461 -280.721)
			(xy 265.69681 -280.725426) (xy 277.273254 -280.725426) (xy 277.273254 -280.67401) (xy 277.281297 -280.623228)
			(xy 277.297185 -280.574329) (xy 277.320528 -280.528517) (xy 277.350749 -280.486921) (xy 277.387105 -280.450565)
			(xy 277.428701 -280.420344) (xy 277.474513 -280.397001) (xy 277.523412 -280.381113) (xy 277.574194 -280.37307)
			(xy 277.62561 -280.37307) (xy 277.676392 -280.381113) (xy 277.725291 -280.397001) (xy 277.771103 -280.420344)
			(xy 277.812699 -280.450565) (xy 277.849055 -280.486921) (xy 277.879276 -280.528517) (xy 277.902619 -280.574329)
			(xy 277.918507 -280.623228) (xy 277.92655 -280.67401) (xy 277.927054 -280.699718) (xy 277.92655 -280.725426)
			(xy 277.918507 -280.776208) (xy 277.902619 -280.825107) (xy 277.879276 -280.870919) (xy 277.849055 -280.912515)
			(xy 277.812699 -280.948871) (xy 277.771103 -280.979092) (xy 277.725291 -281.002435) (xy 277.676392 -281.018323)
			(xy 277.62561 -281.026366) (xy 277.574194 -281.026366) (xy 277.523412 -281.018323) (xy 277.474513 -281.002435)
			(xy 277.428701 -280.979092) (xy 277.387105 -280.948871) (xy 277.350749 -280.912515) (xy 277.320528 -280.870919)
			(xy 277.297185 -280.825107) (xy 277.281297 -280.776208) (xy 277.273254 -280.725426) (xy 265.69681 -280.725426)
			(xy 265.689341 -280.776176) (xy 265.673273 -280.829583) (xy 265.649601 -280.88008) (xy 265.618828 -280.926593)
			(xy 265.581611 -280.96813) (xy 265.538743 -281.003805) (xy 265.491137 -281.032859) (xy 265.439808 -281.054671)
			(xy 265.385851 -281.068777) (xy 265.330414 -281.074877) (xy 265.27468 -281.07284) (xy 265.219837 -281.06271)
			(xy 265.167053 -281.044703) (xy 265.117453 -281.019202) (xy 265.072095 -280.986751) (xy 265.031946 -280.948042)
			(xy 264.99786 -280.903899) (xy 264.970564 -280.855264) (xy 264.950641 -280.803173) (xy 264.938515 -280.748736)
			(xy 264.934444 -280.693114) (xy 264.30097 -280.693114) (xy 264.300484 -280.720365) (xy 264.292728 -280.774313)
			(xy 264.277373 -280.826608) (xy 264.254731 -280.876185) (xy 264.225265 -280.922035) (xy 264.189574 -280.963226)
			(xy 264.148383 -280.998917) (xy 264.102533 -281.028383) (xy 264.052956 -281.051025) (xy 264.000661 -281.06638)
			(xy 263.946713 -281.074136) (xy 263.892211 -281.074136) (xy 263.838263 -281.06638) (xy 263.785968 -281.051025)
			(xy 263.736391 -281.028383) (xy 263.690541 -280.998917) (xy 263.64935 -280.963226) (xy 263.613659 -280.922035)
			(xy 263.584193 -280.876185) (xy 263.561551 -280.826608) (xy 263.546196 -280.774313) (xy 263.53844 -280.720365)
			(xy 263.537954 -280.693114) (xy 263.538517 -280.663734) (xy 263.547564 -280.605675) (xy 263.565401 -280.549687)
			(xy 263.591607 -280.497094) (xy 263.625563 -280.449137) (xy 263.666466 -280.406951) (xy 263.689592 -280.388822)
			(xy 263.69899 -280.381456) (xy 263.709404 -280.360882) (xy 263.710928 -280.256996) (xy 263.701022 -280.235914)
			(xy 263.691878 -280.228548) (xy 263.670054 -280.210317) (xy 263.631527 -280.168494) (xy 263.599627 -280.12142)
			(xy 263.575059 -280.070138) (xy 263.558366 -280.015779) (xy 263.549918 -279.959546) (xy 263.549384 -279.931114)
			(xy 263.549857 -279.903754) (xy 263.557669 -279.849593) (xy 263.573121 -279.797099) (xy 263.595898 -279.747344)
			(xy 263.610344 -279.724104) (xy 263.617964 -279.71242) (xy 263.61898 -279.684734) (xy 263.569704 -279.594056)
			(xy 263.564983 -279.586258) (xy 263.551184 -279.574366) (xy 263.534108 -279.568023) (xy 263.525 -279.56764)
			(xy 262.98398 -279.56764) (xy 262.974015 -279.568119) (xy 262.955582 -279.575699) (xy 262.948166 -279.582372)
			(xy 262.066278 -280.46426) (xy 262.059469 -280.471605) (xy 262.051746 -280.490068) (xy 262.051292 -280.500074)
			(xy 262.051292 -281.174952) (xy 268.26897 -281.174952) (xy 268.27293 -281.125898) (xy 268.284707 -281.078114)
			(xy 268.303998 -281.032838) (xy 268.330301 -280.991242) (xy 268.362936 -280.954405) (xy 268.401057 -280.92328)
			(xy 268.443678 -280.898673) (xy 268.489694 -280.881221) (xy 268.537913 -280.871377) (xy 268.587088 -280.869396)
			(xy 268.635943 -280.875328) (xy 268.683214 -280.88902) (xy 268.727676 -280.910118) (xy 268.768179 -280.938074)
			(xy 268.803672 -280.972166) (xy 268.833237 -281.01151) (xy 268.856108 -281.055087) (xy 268.871692 -281.101768)
			(xy 268.879587 -281.150345) (xy 268.880082 -281.174952) (xy 269.21893 -281.174952) (xy 269.22289 -281.125898)
			(xy 269.234667 -281.078114) (xy 269.253958 -281.032838) (xy 269.280261 -280.991242) (xy 269.312896 -280.954405)
			(xy 269.351017 -280.92328) (xy 269.393638 -280.898673) (xy 269.439654 -280.881221) (xy 269.487873 -280.871377)
			(xy 269.537048 -280.869396) (xy 269.585903 -280.875328) (xy 269.633174 -280.88902) (xy 269.677636 -280.910118)
			(xy 269.718139 -280.938074) (xy 269.753632 -280.972166) (xy 269.783197 -281.01151) (xy 269.806068 -281.055087)
			(xy 269.821652 -281.101768) (xy 269.829547 -281.150345) (xy 269.830042 -281.174952) (xy 269.829547 -281.199559)
			(xy 269.821652 -281.248136) (xy 269.806068 -281.294817) (xy 269.783197 -281.338394) (xy 269.753632 -281.377738)
			(xy 269.718139 -281.41183) (xy 269.677636 -281.439786) (xy 269.633174 -281.460884) (xy 269.585903 -281.474576)
			(xy 269.537048 -281.480508) (xy 269.487873 -281.478527) (xy 269.439654 -281.468683) (xy 269.393638 -281.451231)
			(xy 269.351017 -281.426624) (xy 269.312896 -281.395499) (xy 269.280261 -281.358662) (xy 269.253958 -281.317066)
			(xy 269.234667 -281.27179) (xy 269.22289 -281.224006) (xy 269.21893 -281.174952) (xy 268.880082 -281.174952)
			(xy 268.879587 -281.199559) (xy 268.871692 -281.248136) (xy 268.856108 -281.294817) (xy 268.833237 -281.338394)
			(xy 268.803672 -281.377738) (xy 268.768179 -281.41183) (xy 268.727676 -281.439786) (xy 268.683214 -281.460884)
			(xy 268.635943 -281.474576) (xy 268.587088 -281.480508) (xy 268.537913 -281.478527) (xy 268.489694 -281.468683)
			(xy 268.443678 -281.451231) (xy 268.401057 -281.426624) (xy 268.362936 -281.395499) (xy 268.330301 -281.358662)
			(xy 268.303998 -281.317066) (xy 268.284707 -281.27179) (xy 268.27293 -281.224006) (xy 268.26897 -281.174952)
			(xy 262.051292 -281.174952) (xy 262.051292 -282.124912) (xy 270.169144 -282.124912) (xy 270.173104 -282.075858)
			(xy 270.184881 -282.028074) (xy 270.204172 -281.982798) (xy 270.230475 -281.941202) (xy 270.26311 -281.904365)
			(xy 270.301231 -281.87324) (xy 270.343852 -281.848633) (xy 270.389868 -281.831181) (xy 270.438087 -281.821337)
			(xy 270.487262 -281.819356) (xy 270.536117 -281.825288) (xy 270.583388 -281.83898) (xy 270.62785 -281.860078)
			(xy 270.668353 -281.888034) (xy 270.703846 -281.922126) (xy 270.733411 -281.96147) (xy 270.756282 -282.005047)
			(xy 270.771866 -282.051728) (xy 270.779761 -282.100305) (xy 270.780256 -282.124912) (xy 271.119104 -282.124912)
			(xy 271.123064 -282.075858) (xy 271.134841 -282.028074) (xy 271.154132 -281.982798) (xy 271.180435 -281.941202)
			(xy 271.21307 -281.904365) (xy 271.251191 -281.87324) (xy 271.293812 -281.848633) (xy 271.339828 -281.831181)
			(xy 271.388047 -281.821337) (xy 271.437222 -281.819356) (xy 271.486077 -281.825288) (xy 271.533348 -281.83898)
			(xy 271.57781 -281.860078) (xy 271.618313 -281.888034) (xy 271.653806 -281.922126) (xy 271.683371 -281.96147)
			(xy 271.706242 -282.005047) (xy 271.721826 -282.051728) (xy 271.729721 -282.100305) (xy 271.730216 -282.124912)
			(xy 273.019024 -282.124912) (xy 273.022984 -282.075858) (xy 273.034761 -282.028074) (xy 273.054052 -281.982798)
			(xy 273.080355 -281.941202) (xy 273.11299 -281.904365) (xy 273.151111 -281.87324) (xy 273.193732 -281.848633)
			(xy 273.239748 -281.831181) (xy 273.287967 -281.821337) (xy 273.337142 -281.819356) (xy 273.385997 -281.825288)
			(xy 273.433268 -281.83898) (xy 273.47773 -281.860078) (xy 273.518233 -281.888034) (xy 273.553726 -281.922126)
			(xy 273.583291 -281.96147) (xy 273.606162 -282.005047) (xy 273.621746 -282.051728) (xy 273.629641 -282.100305)
			(xy 273.630136 -282.124912) (xy 273.968984 -282.124912) (xy 273.972944 -282.075858) (xy 273.984721 -282.028074)
			(xy 274.004012 -281.982798) (xy 274.030315 -281.941202) (xy 274.06295 -281.904365) (xy 274.101071 -281.87324)
			(xy 274.143692 -281.848633) (xy 274.189708 -281.831181) (xy 274.237927 -281.821337) (xy 274.287102 -281.819356)
			(xy 274.335957 -281.825288) (xy 274.383228 -281.83898) (xy 274.42769 -281.860078) (xy 274.468193 -281.888034)
			(xy 274.503686 -281.922126) (xy 274.533251 -281.96147) (xy 274.556122 -282.005047) (xy 274.571706 -282.051728)
			(xy 274.579601 -282.100305) (xy 274.580096 -282.124912) (xy 274.579601 -282.149519) (xy 274.571706 -282.198096)
			(xy 274.556122 -282.244777) (xy 274.533251 -282.288354) (xy 274.503686 -282.327698) (xy 274.468193 -282.36179)
			(xy 274.42769 -282.389746) (xy 274.383228 -282.410844) (xy 274.335957 -282.424536) (xy 274.287102 -282.430468)
			(xy 274.237927 -282.428487) (xy 274.189708 -282.418643) (xy 274.143692 -282.401191) (xy 274.101071 -282.376584)
			(xy 274.06295 -282.345459) (xy 274.030315 -282.308622) (xy 274.004012 -282.267026) (xy 273.984721 -282.22175)
			(xy 273.972944 -282.173966) (xy 273.968984 -282.124912) (xy 273.630136 -282.124912) (xy 273.629641 -282.149519)
			(xy 273.621746 -282.198096) (xy 273.606162 -282.244777) (xy 273.583291 -282.288354) (xy 273.553726 -282.327698)
			(xy 273.518233 -282.36179) (xy 273.47773 -282.389746) (xy 273.433268 -282.410844) (xy 273.385997 -282.424536)
			(xy 273.337142 -282.430468) (xy 273.287967 -282.428487) (xy 273.239748 -282.418643) (xy 273.193732 -282.401191)
			(xy 273.151111 -282.376584) (xy 273.11299 -282.345459) (xy 273.080355 -282.308622) (xy 273.054052 -282.267026)
			(xy 273.034761 -282.22175) (xy 273.022984 -282.173966) (xy 273.019024 -282.124912) (xy 271.730216 -282.124912)
			(xy 271.729721 -282.149519) (xy 271.721826 -282.198096) (xy 271.706242 -282.244777) (xy 271.683371 -282.288354)
			(xy 271.653806 -282.327698) (xy 271.618313 -282.36179) (xy 271.57781 -282.389746) (xy 271.533348 -282.410844)
			(xy 271.486077 -282.424536) (xy 271.437222 -282.430468) (xy 271.388047 -282.428487) (xy 271.339828 -282.418643)
			(xy 271.293812 -282.401191) (xy 271.251191 -282.376584) (xy 271.21307 -282.345459) (xy 271.180435 -282.308622)
			(xy 271.154132 -282.267026) (xy 271.134841 -282.22175) (xy 271.123064 -282.173966) (xy 271.119104 -282.124912)
			(xy 270.780256 -282.124912) (xy 270.779761 -282.149519) (xy 270.771866 -282.198096) (xy 270.756282 -282.244777)
			(xy 270.733411 -282.288354) (xy 270.703846 -282.327698) (xy 270.668353 -282.36179) (xy 270.62785 -282.389746)
			(xy 270.583388 -282.410844) (xy 270.536117 -282.424536) (xy 270.487262 -282.430468) (xy 270.438087 -282.428487)
			(xy 270.389868 -282.418643) (xy 270.343852 -282.401191) (xy 270.301231 -282.376584) (xy 270.26311 -282.345459)
			(xy 270.230475 -282.308622) (xy 270.204172 -282.267026) (xy 270.184881 -282.22175) (xy 270.173104 -282.173966)
			(xy 270.169144 -282.124912) (xy 262.051292 -282.124912) (xy 262.051292 -282.880054) (xy 262.051704 -282.890082)
			(xy 262.059365 -282.908616) (xy 262.073539 -282.922805) (xy 262.092064 -282.930486) (xy 262.102092 -282.930854)
			(xy 263.579356 -282.930854) (xy 263.591451 -282.930116) (xy 263.612934 -282.91898) (xy 263.620504 -282.909518)
			(xy 263.637155 -282.887136) (xy 263.675887 -282.84699) (xy 263.720049 -282.812909) (xy 263.768701 -282.785618)
			(xy 263.820807 -282.765698) (xy 263.875257 -282.753574) (xy 263.930892 -282.749504) (xy 263.986527 -282.753574)
			(xy 264.040977 -282.765698) (xy 264.093083 -282.785618) (xy 264.141735 -282.812909) (xy 264.185897 -282.84699)
			(xy 264.224629 -282.887136) (xy 264.24128 -282.909518) (xy 264.248851 -282.918976) (xy 264.270335 -282.930099)
			(xy 264.282428 -282.930854) (xy 268.276578 -282.930854) (xy 268.28931 -282.930151) (xy 268.311698 -282.918015)
			(xy 268.31925 -282.90774) (xy 268.333504 -282.886899) (xy 268.367714 -282.849769) (xy 268.407567 -282.818772)
			(xy 268.451975 -282.794754) (xy 268.49973 -282.778369) (xy 268.54953 -282.770063) (xy 268.600018 -282.770063)
			(xy 268.649818 -282.778369) (xy 268.697573 -282.794754) (xy 268.741981 -282.818772) (xy 268.781834 -282.849769)
			(xy 268.816044 -282.886899) (xy 268.830298 -282.90774) (xy 268.835156 -282.914679) (xy 268.84849 -282.925111)
			(xy 268.864504 -282.930601) (xy 268.87297 -282.930854) (xy 269.226538 -282.930854) (xy 269.239275 -282.930159)
			(xy 269.261678 -282.918033) (xy 269.26921 -282.90774) (xy 269.283464 -282.886899) (xy 269.317674 -282.849769)
			(xy 269.357527 -282.818772) (xy 269.401935 -282.794754) (xy 269.44969 -282.778369) (xy 269.49949 -282.770063)
			(xy 269.549978 -282.770063) (xy 269.599778 -282.778369) (xy 269.647533 -282.794754) (xy 269.691941 -282.818772)
			(xy 269.731794 -282.849769) (xy 269.766004 -282.886899) (xy 269.780258 -282.90774) (xy 269.785119 -282.914673)
			(xy 269.798455 -282.925089) (xy 269.814468 -282.93056) (xy 269.82293 -282.930854) (xy 269.939008 -282.930854)
			(xy 269.949076 -282.93128) (xy 269.967674 -282.939003) (xy 269.975076 -282.94584) (xy 270.104108 -283.074872)
			(xy 274.918944 -283.074872) (xy 274.922904 -283.025818) (xy 274.934681 -282.978034) (xy 274.953972 -282.932758)
			(xy 274.980275 -282.891162) (xy 275.01291 -282.854325) (xy 275.051031 -282.8232) (xy 275.093652 -282.798593)
			(xy 275.139668 -282.781141) (xy 275.187887 -282.771297) (xy 275.237062 -282.769316) (xy 275.285917 -282.775248)
			(xy 275.333188 -282.78894) (xy 275.37765 -282.810038) (xy 275.418153 -282.837994) (xy 275.453646 -282.872086)
			(xy 275.483211 -282.91143) (xy 275.506082 -282.955007) (xy 275.521666 -283.001688) (xy 275.529561 -283.050265)
			(xy 275.530056 -283.074872) (xy 275.868904 -283.074872) (xy 275.872864 -283.025818) (xy 275.884641 -282.978034)
			(xy 275.903932 -282.932758) (xy 275.930235 -282.891162) (xy 275.96287 -282.854325) (xy 276.000991 -282.8232)
			(xy 276.043612 -282.798593) (xy 276.089628 -282.781141) (xy 276.137847 -282.771297) (xy 276.187022 -282.769316)
			(xy 276.235877 -282.775248) (xy 276.283148 -282.78894) (xy 276.32761 -282.810038) (xy 276.368113 -282.837994)
			(xy 276.403606 -282.872086) (xy 276.433171 -282.91143) (xy 276.456042 -282.955007) (xy 276.471626 -283.001688)
			(xy 276.479521 -283.050265) (xy 276.480016 -283.074872) (xy 276.479521 -283.099479) (xy 276.471626 -283.148056)
			(xy 276.456042 -283.194737) (xy 276.433171 -283.238314) (xy 276.403606 -283.277658) (xy 276.368113 -283.31175)
			(xy 276.32761 -283.339706) (xy 276.283148 -283.360804) (xy 276.235877 -283.374496) (xy 276.187022 -283.380428)
			(xy 276.137847 -283.378447) (xy 276.089628 -283.368603) (xy 276.043612 -283.351151) (xy 276.000991 -283.326544)
			(xy 275.96287 -283.295419) (xy 275.930235 -283.258582) (xy 275.903932 -283.216986) (xy 275.884641 -283.17171)
			(xy 275.872864 -283.123926) (xy 275.868904 -283.074872) (xy 275.530056 -283.074872) (xy 275.529561 -283.099479)
			(xy 275.521666 -283.148056) (xy 275.506082 -283.194737) (xy 275.483211 -283.238314) (xy 275.453646 -283.277658)
			(xy 275.418153 -283.31175) (xy 275.37765 -283.339706) (xy 275.333188 -283.360804) (xy 275.285917 -283.374496)
			(xy 275.237062 -283.380428) (xy 275.187887 -283.378447) (xy 275.139668 -283.368603) (xy 275.093652 -283.351151)
			(xy 275.051031 -283.326544) (xy 275.01291 -283.295419) (xy 274.980275 -283.258582) (xy 274.953972 -283.216986)
			(xy 274.934681 -283.17171) (xy 274.922904 -283.123926) (xy 274.918944 -283.074872) (xy 270.104108 -283.074872)
			(xy 270.975074 -283.945838) (xy 270.984486 -283.954354) (xy 271.00875 -283.961687) (xy 271.021302 -283.959808)
			(xy 271.11706 -283.939996) (xy 271.136618 -283.92374) (xy 271.141444 -283.911802) (xy 271.151538 -283.887837)
			(xy 271.178661 -283.843474) (xy 271.212913 -283.804352) (xy 271.2533 -283.771602) (xy 271.298655 -283.746173)
			(xy 271.347664 -283.7288) (xy 271.398909 -283.719987) (xy 271.424908 -283.719524) (xy 271.4489 -283.719971)
			(xy 271.496292 -283.727479) (xy 271.541927 -283.742308) (xy 271.58468 -283.764095) (xy 271.623498 -283.792301)
			(xy 271.657425 -283.826233) (xy 271.685626 -283.865054) (xy 271.707407 -283.90781) (xy 271.722231 -283.953446)
			(xy 271.729732 -284.00084) (xy 271.730216 -284.024832) (xy 273.019024 -284.024832) (xy 273.022984 -283.975778)
			(xy 273.034761 -283.927994) (xy 273.054052 -283.882718) (xy 273.080355 -283.841122) (xy 273.11299 -283.804285)
			(xy 273.151111 -283.77316) (xy 273.193732 -283.748553) (xy 273.239748 -283.731101) (xy 273.287967 -283.721257)
			(xy 273.337142 -283.719276) (xy 273.385997 -283.725208) (xy 273.433268 -283.7389) (xy 273.47773 -283.759998)
			(xy 273.518233 -283.787954) (xy 273.553726 -283.822046) (xy 273.583291 -283.86139) (xy 273.606162 -283.904967)
			(xy 273.621746 -283.951648) (xy 273.629641 -284.000225) (xy 273.630136 -284.024832) (xy 273.968984 -284.024832)
			(xy 273.972944 -283.975778) (xy 273.984721 -283.927994) (xy 274.004012 -283.882718) (xy 274.030315 -283.841122)
			(xy 274.06295 -283.804285) (xy 274.101071 -283.77316) (xy 274.143692 -283.748553) (xy 274.189708 -283.731101)
			(xy 274.237927 -283.721257) (xy 274.287102 -283.719276) (xy 274.335957 -283.725208) (xy 274.383228 -283.7389)
			(xy 274.42769 -283.759998) (xy 274.468193 -283.787954) (xy 274.503686 -283.822046) (xy 274.533251 -283.86139)
			(xy 274.556122 -283.904967) (xy 274.571706 -283.951648) (xy 274.579601 -284.000225) (xy 274.580096 -284.024832)
			(xy 274.579601 -284.049439) (xy 274.571706 -284.098016) (xy 274.556122 -284.144697) (xy 274.533251 -284.188274)
			(xy 274.503686 -284.227618) (xy 274.468193 -284.26171) (xy 274.42769 -284.289666) (xy 274.383228 -284.310764)
			(xy 274.335957 -284.324456) (xy 274.287102 -284.330388) (xy 274.237927 -284.328407) (xy 274.189708 -284.318563)
			(xy 274.143692 -284.301111) (xy 274.101071 -284.276504) (xy 274.06295 -284.245379) (xy 274.030315 -284.208542)
			(xy 274.004012 -284.166946) (xy 273.984721 -284.12167) (xy 273.972944 -284.073886) (xy 273.968984 -284.024832)
			(xy 273.630136 -284.024832) (xy 273.629641 -284.049439) (xy 273.621746 -284.098016) (xy 273.606162 -284.144697)
			(xy 273.583291 -284.188274) (xy 273.553726 -284.227618) (xy 273.518233 -284.26171) (xy 273.47773 -284.289666)
			(xy 273.433268 -284.310764) (xy 273.385997 -284.324456) (xy 273.337142 -284.330388) (xy 273.287967 -284.328407)
			(xy 273.239748 -284.318563) (xy 273.193732 -284.301111) (xy 273.151111 -284.276504) (xy 273.11299 -284.245379)
			(xy 273.080355 -284.208542) (xy 273.054052 -284.166946) (xy 273.034761 -284.12167) (xy 273.022984 -284.073886)
			(xy 273.019024 -284.024832) (xy 271.730216 -284.024832) (xy 271.729689 -284.050826) (xy 271.720874 -284.102062)
			(xy 271.703505 -284.151063) (xy 271.678084 -284.196412) (xy 271.645346 -284.236798) (xy 271.606238 -284.271053)
			(xy 271.561891 -284.298186) (xy 271.537938 -284.308296) (xy 271.526 -284.313122) (xy 271.509744 -284.33268)
			(xy 271.489932 -284.428438) (xy 271.488065 -284.44099) (xy 271.495393 -284.465251) (xy 271.503902 -284.474666)
			(xy 272.004028 -284.974792) (xy 273.019024 -284.974792) (xy 273.022984 -284.925738) (xy 273.034761 -284.877954)
			(xy 273.054052 -284.832678) (xy 273.080355 -284.791082) (xy 273.11299 -284.754245) (xy 273.151111 -284.72312)
			(xy 273.193732 -284.698513) (xy 273.239748 -284.681061) (xy 273.287967 -284.671217) (xy 273.337142 -284.669236)
			(xy 273.385997 -284.675168) (xy 273.433268 -284.68886) (xy 273.47773 -284.709958) (xy 273.518233 -284.737914)
			(xy 273.553726 -284.772006) (xy 273.583291 -284.81135) (xy 273.606162 -284.854927) (xy 273.621746 -284.901608)
			(xy 273.629641 -284.950185) (xy 273.630136 -284.974792) (xy 273.629641 -284.999399) (xy 273.621746 -285.047976)
			(xy 273.606162 -285.094657) (xy 273.583291 -285.138234) (xy 273.553726 -285.177578) (xy 273.518233 -285.21167)
			(xy 273.47773 -285.239626) (xy 273.433268 -285.260724) (xy 273.385997 -285.274416) (xy 273.337142 -285.280348)
			(xy 273.287967 -285.278367) (xy 273.239748 -285.268523) (xy 273.193732 -285.251071) (xy 273.151111 -285.226464)
			(xy 273.11299 -285.195339) (xy 273.080355 -285.158502) (xy 273.054052 -285.116906) (xy 273.034761 -285.07163)
			(xy 273.022984 -285.023846) (xy 273.019024 -284.974792) (xy 272.004028 -284.974792) (xy 275.709888 -288.680652)
			(xy 275.717284 -288.687505) (xy 275.735882 -288.695252) (xy 275.745956 -288.695638) (xy 275.832062 -288.695638)
		)
		(stroke
			(width 0)
			(type solid)
		)
		(fill yes)
		(layer "In13.Cu")
		(net "GND")
	)
	(gr_poly
		(pts
			(xy 203.887324 -375.835164) (xy 203.893842 -375.834934) (xy 203.906446 -375.831598) (xy 203.912216 -375.82856)
			(xy 203.922376 -375.82094) (xy 204.145134 -375.598182) (xy 204.149452 -375.593864) (xy 204.269848 -375.473468)
			(xy 204.276615 -375.466039) (xy 204.28419 -375.447443) (xy 204.28458 -375.4374) (xy 204.28458 -374.914922)
			(xy 204.284137 -374.904892) (xy 204.276554 -374.886325) (xy 204.269848 -374.878854) (xy 204.188568 -374.797828)
			(xy 204.181789 -374.790403) (xy 204.17419 -374.771807) (xy 204.173836 -374.76176) (xy 204.173836 -372.693692)
			(xy 204.173158 -372.681052) (xy 204.161153 -372.658804) (xy 204.150976 -372.651274) (xy 204.069442 -372.597426)
			(xy 204.044042 -372.595394) (xy 204.038962 -372.597426) (xy 204.014225 -372.608087) (xy 203.962501 -372.623126)
			(xy 203.909176 -372.630738) (xy 203.882244 -372.631208) (xy 203.881736 -372.631208) (xy 203.85446 -372.630747)
			(xy 203.800463 -372.622988) (xy 203.748119 -372.607623) (xy 203.698496 -372.584965) (xy 203.652602 -372.555474)
			(xy 203.611373 -372.519753) (xy 203.575647 -372.478527) (xy 203.546153 -372.432636) (xy 203.52349 -372.383014)
			(xy 203.50812 -372.330672) (xy 203.500356 -372.276676) (xy 203.500356 -372.222124) (xy 203.50812 -372.168128)
			(xy 203.52349 -372.115786) (xy 203.546153 -372.066164) (xy 203.575647 -372.020273) (xy 203.611373 -371.979047)
			(xy 203.652602 -371.943326) (xy 203.698496 -371.913835) (xy 203.748119 -371.891177) (xy 203.800463 -371.875812)
			(xy 203.85446 -371.868053) (xy 203.881736 -371.867684) (xy 203.882244 -371.867684) (xy 203.909124 -371.868145)
			(xy 203.962352 -371.87569) (xy 204.013996 -371.890626) (xy 204.038708 -371.901212) (xy 204.03947 -371.90172)
			(xy 204.044042 -371.903498) (xy 204.069442 -371.901466) (xy 204.150976 -371.847618) (xy 204.161157 -371.840098)
			(xy 204.17314 -371.817839) (xy 204.173836 -371.8052) (xy 204.173836 -371.286278) (xy 204.173407 -371.276211)
			(xy 204.16568 -371.257618) (xy 204.15885 -371.25021) (xy 204.045566 -371.136926) (xy 204.038724 -371.129527)
			(xy 204.031006 -371.110928) (xy 204.03058 -371.100858) (xy 204.03058 -368.539776) (xy 204.030152 -368.529708)
			(xy 204.022429 -368.511112) (xy 204.015594 -368.503708) (xy 203.979272 -368.467894) (xy 203.976478 -368.467894)
			(xy 203.949209 -368.467406) (xy 203.895226 -368.459642) (xy 203.842897 -368.444275) (xy 203.793288 -368.421618)
			(xy 203.747407 -368.392132) (xy 203.70619 -368.356417) (xy 203.670474 -368.315201) (xy 203.640987 -368.269321)
			(xy 203.618328 -368.219712) (xy 203.60296 -368.167384) (xy 203.595195 -368.113401) (xy 203.594716 -368.086132)
			(xy 203.595224 -368.065812) (xy 203.595224 -368.065304) (xy 203.595172 -368.05474) (xy 203.587556 -368.035061)
			(xy 203.580492 -368.027204) (xy 203.527406 -367.974118) (xy 203.52044 -367.967802) (xy 203.503241 -367.960243)
			(xy 203.493878 -367.959386) (xy 203.488798 -367.959386) (xy 203.468478 -367.959894) (xy 203.448158 -367.959386)
			(xy 203.44765 -367.959386) (xy 203.437082 -367.959429) (xy 203.417391 -367.967034) (xy 203.40955 -367.974118)
			(xy 203.356464 -368.027204) (xy 203.34941 -368.035064) (xy 203.341807 -368.054743) (xy 203.341732 -368.065304)
			(xy 203.341732 -368.065812) (xy 203.34224 -368.086132) (xy 203.341751 -368.113399) (xy 203.333986 -368.167377)
			(xy 203.318618 -368.219701) (xy 203.29596 -368.269305) (xy 203.266474 -368.31518) (xy 203.230759 -368.356392)
			(xy 203.189543 -368.392102) (xy 203.143665 -368.421583) (xy 203.094058 -368.444234) (xy 203.041732 -368.459596)
			(xy 202.987753 -368.467355) (xy 202.933219 -368.467353) (xy 202.87924 -368.45959) (xy 202.826916 -368.444224)
			(xy 202.777311 -368.421569) (xy 202.731434 -368.392085) (xy 202.690221 -368.356372) (xy 202.654509 -368.315158)
			(xy 202.625026 -368.269281) (xy 202.602372 -368.219675) (xy 202.587008 -368.16735) (xy 202.579247 -368.113371)
			(xy 202.579246 -368.058837) (xy 202.587006 -368.004858) (xy 202.602369 -367.952533) (xy 202.625022 -367.902926)
			(xy 202.654504 -367.857049) (xy 202.690215 -367.815834) (xy 202.731428 -367.78012) (xy 202.777304 -367.750635)
			(xy 202.826908 -367.727978) (xy 202.879233 -367.712612) (xy 202.933211 -367.704848) (xy 202.960478 -367.70437)
			(xy 202.980798 -367.704878) (xy 202.981306 -367.704878) (xy 202.99187 -367.704825) (xy 203.011552 -367.697212)
			(xy 203.019406 -367.690146) (xy 203.072492 -367.63706) (xy 203.079545 -367.6292) (xy 203.087142 -367.609521)
			(xy 203.087224 -367.59896) (xy 203.087224 -367.598452) (xy 203.086716 -367.578132) (xy 203.087202 -367.550863)
			(xy 203.094964 -367.496879) (xy 203.110329 -367.444549) (xy 203.132986 -367.394939) (xy 203.162472 -367.349058)
			(xy 203.198187 -367.307841) (xy 203.239404 -367.272126) (xy 203.285285 -367.24264) (xy 203.334895 -367.219983)
			(xy 203.387225 -367.204618) (xy 203.441209 -367.196856) (xy 203.495747 -367.196856) (xy 203.549731 -367.204618)
			(xy 203.602061 -367.219983) (xy 203.651671 -367.24264) (xy 203.697552 -367.272126) (xy 203.738769 -367.307841)
			(xy 203.774484 -367.349058) (xy 203.80397 -367.394939) (xy 203.826627 -367.444549) (xy 203.841992 -367.496879)
			(xy 203.849754 -367.550863) (xy 203.85024 -367.578132) (xy 203.849732 -367.598452) (xy 203.849732 -367.59896)
			(xy 203.849776 -367.609528) (xy 203.857378 -367.629221) (xy 203.864464 -367.63706) (xy 203.91755 -367.690146)
			(xy 203.924517 -367.696461) (xy 203.941714 -367.704026) (xy 203.951078 -367.704878) (xy 203.956158 -367.704878)
			(xy 203.976478 -367.70437) (xy 203.979272 -367.70437) (xy 204.015594 -367.668556) (xy 204.022434 -367.661155)
			(xy 204.030154 -367.642557) (xy 204.03058 -367.632488) (xy 204.03058 -367.118138) (xy 204.031019 -367.108106)
			(xy 204.038593 -367.089531) (xy 204.045312 -367.08207) (xy 204.145388 -366.982248) (xy 204.152175 -366.974827)
			(xy 204.159788 -366.95623) (xy 204.16012 -366.94618) (xy 204.16012 -364.10392) (xy 204.082904 -364.026704)
			(xy 202.844654 -364.026704) (xy 202.817386 -364.026214) (xy 202.763405 -364.018448) (xy 202.711078 -364.003079)
			(xy 202.661471 -363.980421) (xy 202.615593 -363.950934) (xy 202.574378 -363.915219) (xy 202.538663 -363.874004)
			(xy 202.509177 -363.828125) (xy 202.48652 -363.778518) (xy 202.471151 -363.726191) (xy 202.463385 -363.67221)
			(xy 202.462892 -363.644942) (xy 202.463374 -363.617785) (xy 202.47108 -363.564019) (xy 202.486327 -363.511889)
			(xy 202.508808 -363.462445) (xy 202.538069 -363.416686) (xy 202.573519 -363.375536) (xy 202.614444 -363.339825)
			(xy 202.660016 -363.310274) (xy 202.709316 -363.287479) (xy 202.73518 -363.279182) (xy 202.743816 -363.276388)
			(xy 203.182728 -362.83773) (xy 203.188362 -362.831684) (xy 203.19574 -362.816908) (xy 203.197206 -362.808774)
			(xy 203.19869 -362.79499) (xy 203.195057 -362.767517) (xy 203.184163 -362.742035) (xy 203.166811 -362.720428)
			(xy 203.155804 -362.712) (xy 203.13506 -362.696553) (xy 203.097529 -362.660967) (xy 203.065141 -362.620644)
			(xy 203.038489 -362.57632) (xy 203.018059 -362.528807) (xy 203.004224 -362.478972) (xy 202.997239 -362.427726)
			(xy 202.9968 -362.401866) (xy 202.997289 -362.374597) (xy 203.005054 -362.320615) (xy 203.020422 -362.268288)
			(xy 203.04308 -362.218679) (xy 203.072566 -362.1728) (xy 203.10828 -362.131583) (xy 203.149497 -362.095868)
			(xy 203.195376 -362.066382) (xy 203.244984 -362.043723) (xy 203.297311 -362.028355) (xy 203.351293 -362.020589)
			(xy 203.378562 -362.020104) (xy 203.404423 -362.020531) (xy 203.455674 -362.027507) (xy 203.505513 -362.041336)
			(xy 203.55303 -362.061766) (xy 203.597355 -362.088421) (xy 203.637677 -362.120816) (xy 203.673258 -362.158356)
			(xy 203.688696 -362.179108) (xy 203.697147 -362.190097) (xy 203.71875 -362.207449) (xy 203.744223 -362.218354)
			(xy 203.77169 -362.222008) (xy 203.78547 -362.22051) (xy 203.793603 -362.219041) (xy 203.80838 -362.211664)
			(xy 203.814426 -362.206032) (xy 204.863192 -361.157012) (xy 204.877103 -361.143546) (xy 204.907535 -361.119609)
			(xy 204.923898 -361.10926) (xy 204.933042 -361.101894) (xy 204.949806 -361.08513) (xy 204.95715 -361.078317)
			(xy 204.975613 -361.070582) (xy 204.98562 -361.070144) (xy 205.015592 -361.070144) (xy 205.021434 -361.068874)
			(xy 205.040211 -361.064726) (xy 205.078407 -361.060267) (xy 205.097634 -361.059984) (xy 211.253324 -361.059984)
			(xy 211.272553 -361.060249) (xy 211.31075 -361.064707) (xy 211.329524 -361.068874) (xy 211.335366 -361.070144)
			(xy 211.365338 -361.070144) (xy 211.375321 -361.07069) (xy 211.393739 -361.078418) (xy 211.401152 -361.08513)
			(xy 211.417916 -361.101894) (xy 211.42706 -361.10926) (xy 211.44342 -361.119613) (xy 211.473849 -361.143553)
			(xy 211.487766 -361.157012) (xy 212.339174 -362.00842) (xy 212.35264 -362.022331) (xy 212.376575 -362.052764)
			(xy 212.386926 -362.069126) (xy 212.390228 -362.074206) (xy 212.411056 -362.095034) (xy 212.417866 -362.102379)
			(xy 212.425593 -362.120842) (xy 212.426042 -362.130848) (xy 212.426042 -362.16082) (xy 212.427312 -362.166662)
			(xy 212.431557 -362.185491) (xy 212.436143 -362.223817) (xy 212.436456 -362.243116) (xy 212.436456 -364.545118)
			(xy 212.436115 -364.564415) (xy 212.431531 -364.602738) (xy 212.427312 -364.621572) (xy 212.426042 -364.627414)
			(xy 212.426042 -364.657386) (xy 212.425506 -364.667373) (xy 212.417789 -364.685804) (xy 212.411056 -364.6932)
			(xy 212.390228 -364.714028) (xy 212.386926 -364.719108) (xy 212.376575 -364.735469) (xy 212.352637 -364.765901)
			(xy 212.339174 -364.779814) (xy 211.798662 -365.320326) (xy 214.325706 -365.320326) (xy 214.329777 -365.264704)
			(xy 214.341903 -365.210267) (xy 214.361826 -365.158176) (xy 214.389122 -365.109541) (xy 214.423208 -365.065398)
			(xy 214.463357 -365.026689) (xy 214.508715 -364.994238) (xy 214.558315 -364.968737) (xy 214.611099 -364.95073)
			(xy 214.665942 -364.9406) (xy 214.721676 -364.938563) (xy 214.777113 -364.944663) (xy 214.83107 -364.958769)
			(xy 214.882399 -364.980581) (xy 214.930005 -365.009635) (xy 214.972873 -365.04531) (xy 215.01009 -365.086847)
			(xy 215.040863 -365.13336) (xy 215.064535 -365.183857) (xy 215.080603 -365.237264) (xy 215.088723 -365.29244)
			(xy 215.089232 -365.320326) (xy 215.088723 -365.348212) (xy 215.080603 -365.403388) (xy 215.064535 -365.456795)
			(xy 215.040863 -365.507292) (xy 215.01009 -365.553805) (xy 214.972873 -365.595342) (xy 214.930005 -365.631017)
			(xy 214.882399 -365.660071) (xy 214.83107 -365.681883) (xy 214.777113 -365.695989) (xy 214.721676 -365.702089)
			(xy 214.665942 -365.700052) (xy 214.611099 -365.689922) (xy 214.558315 -365.671915) (xy 214.508715 -365.646414)
			(xy 214.463357 -365.613963) (xy 214.423208 -365.575254) (xy 214.389122 -365.531111) (xy 214.361826 -365.482476)
			(xy 214.341903 -365.430385) (xy 214.329777 -365.375948) (xy 214.325706 -365.320326) (xy 211.798662 -365.320326)
			(xy 211.143342 -365.975646) (xy 212.140798 -365.975646) (xy 212.144869 -365.920024) (xy 212.156995 -365.865587)
			(xy 212.176918 -365.813496) (xy 212.204214 -365.764861) (xy 212.2383 -365.720718) (xy 212.278449 -365.682009)
			(xy 212.323807 -365.649558) (xy 212.373407 -365.624057) (xy 212.426191 -365.60605) (xy 212.481034 -365.59592)
			(xy 212.536768 -365.593883) (xy 212.592205 -365.599983) (xy 212.646162 -365.614089) (xy 212.697491 -365.635901)
			(xy 212.745097 -365.664955) (xy 212.787965 -365.70063) (xy 212.825182 -365.742167) (xy 212.855955 -365.78868)
			(xy 212.879627 -365.839177) (xy 212.895695 -365.892584) (xy 212.903815 -365.94776) (xy 212.904324 -365.975646)
			(xy 212.903815 -366.003532) (xy 212.895695 -366.058708) (xy 212.879627 -366.112115) (xy 212.855955 -366.162612)
			(xy 212.825182 -366.209125) (xy 212.787965 -366.250662) (xy 212.745097 -366.286337) (xy 212.697491 -366.315391)
			(xy 212.646162 -366.337203) (xy 212.592205 -366.351309) (xy 212.536768 -366.357409) (xy 212.481034 -366.355372)
			(xy 212.426191 -366.345242) (xy 212.373407 -366.327235) (xy 212.323807 -366.301734) (xy 212.278449 -366.269283)
			(xy 212.2383 -366.230574) (xy 212.204214 -366.186431) (xy 212.176918 -366.137796) (xy 212.156995 -366.085705)
			(xy 212.144869 -366.031268) (xy 212.140798 -365.975646) (xy 211.143342 -365.975646) (xy 210.922362 -366.196626)
			(xy 210.915513 -366.204023) (xy 210.907778 -366.222622) (xy 210.907376 -366.232694) (xy 210.907376 -366.991646)
			(xy 212.150958 -366.991646) (xy 212.155029 -366.936024) (xy 212.167155 -366.881587) (xy 212.187078 -366.829496)
			(xy 212.214374 -366.780861) (xy 212.24846 -366.736718) (xy 212.288609 -366.698009) (xy 212.333967 -366.665558)
			(xy 212.383567 -366.640057) (xy 212.436351 -366.62205) (xy 212.491194 -366.61192) (xy 212.546928 -366.609883)
			(xy 212.602365 -366.615983) (xy 212.656322 -366.630089) (xy 212.707651 -366.651901) (xy 212.755257 -366.680955)
			(xy 212.798125 -366.71663) (xy 212.835342 -366.758167) (xy 212.866115 -366.80468) (xy 212.889787 -366.855177)
			(xy 212.905855 -366.908584) (xy 212.913975 -366.96376) (xy 212.914484 -366.991646) (xy 212.913975 -367.019532)
			(xy 212.905855 -367.074708) (xy 212.889787 -367.128115) (xy 212.866115 -367.178612) (xy 212.835342 -367.225125)
			(xy 212.798125 -367.266662) (xy 212.755257 -367.302337) (xy 212.707651 -367.331391) (xy 212.656322 -367.353203)
			(xy 212.602365 -367.367309) (xy 212.546928 -367.373409) (xy 212.491194 -367.371372) (xy 212.436351 -367.361242)
			(xy 212.383567 -367.343235) (xy 212.333967 -367.317734) (xy 212.288609 -367.285283) (xy 212.24846 -367.246574)
			(xy 212.214374 -367.202431) (xy 212.187078 -367.153796) (xy 212.167155 -367.101705) (xy 212.155029 -367.047268)
			(xy 212.150958 -366.991646) (xy 210.907376 -366.991646) (xy 210.907376 -368.007646) (xy 212.140798 -368.007646)
			(xy 212.144869 -367.952024) (xy 212.156995 -367.897587) (xy 212.176918 -367.845496) (xy 212.204214 -367.796861)
			(xy 212.2383 -367.752718) (xy 212.278449 -367.714009) (xy 212.323807 -367.681558) (xy 212.373407 -367.656057)
			(xy 212.426191 -367.63805) (xy 212.481034 -367.62792) (xy 212.536768 -367.625883) (xy 212.592205 -367.631983)
			(xy 212.646162 -367.646089) (xy 212.697491 -367.667901) (xy 212.717293 -367.679986) (xy 215.656158 -367.679986)
			(xy 215.660229 -367.624364) (xy 215.672355 -367.569927) (xy 215.692278 -367.517836) (xy 215.719574 -367.469201)
			(xy 215.75366 -367.425058) (xy 215.793809 -367.386349) (xy 215.839167 -367.353898) (xy 215.888767 -367.328397)
			(xy 215.941551 -367.31039) (xy 215.996394 -367.30026) (xy 216.052128 -367.298223) (xy 216.107565 -367.304323)
			(xy 216.161522 -367.318429) (xy 216.212851 -367.340241) (xy 216.260457 -367.369295) (xy 216.303325 -367.40497)
			(xy 216.340542 -367.446507) (xy 216.371315 -367.49302) (xy 216.394987 -367.543517) (xy 216.411055 -367.596924)
			(xy 216.419175 -367.6521) (xy 216.419684 -367.679986) (xy 216.419175 -367.707872) (xy 216.411055 -367.763048)
			(xy 216.394987 -367.816455) (xy 216.371315 -367.866952) (xy 216.340542 -367.913465) (xy 216.303325 -367.955002)
			(xy 216.260457 -367.990677) (xy 216.212851 -368.019731) (xy 216.161522 -368.041543) (xy 216.107565 -368.055649)
			(xy 216.052128 -368.061749) (xy 215.996394 -368.059712) (xy 215.941551 -368.049582) (xy 215.888767 -368.031575)
			(xy 215.839167 -368.006074) (xy 215.793809 -367.973623) (xy 215.75366 -367.934914) (xy 215.719574 -367.890771)
			(xy 215.692278 -367.842136) (xy 215.672355 -367.790045) (xy 215.660229 -367.735608) (xy 215.656158 -367.679986)
			(xy 212.717293 -367.679986) (xy 212.745097 -367.696955) (xy 212.787965 -367.73263) (xy 212.825182 -367.774167)
			(xy 212.855955 -367.82068) (xy 212.879627 -367.871177) (xy 212.895695 -367.924584) (xy 212.903815 -367.97976)
			(xy 212.904324 -368.007646) (xy 212.903815 -368.035532) (xy 212.895695 -368.090708) (xy 212.879627 -368.144115)
			(xy 212.855955 -368.194612) (xy 212.825182 -368.241125) (xy 212.787965 -368.282662) (xy 212.745097 -368.318337)
			(xy 212.697491 -368.347391) (xy 212.646162 -368.369203) (xy 212.592205 -368.383309) (xy 212.536768 -368.389409)
			(xy 212.481034 -368.387372) (xy 212.426191 -368.377242) (xy 212.373407 -368.359235) (xy 212.323807 -368.333734)
			(xy 212.278449 -368.301283) (xy 212.2383 -368.262574) (xy 212.204214 -368.218431) (xy 212.176918 -368.169796)
			(xy 212.156995 -368.117705) (xy 212.144869 -368.063268) (xy 212.140798 -368.007646) (xy 210.907376 -368.007646)
			(xy 210.907376 -368.670586) (xy 214.513158 -368.670586) (xy 214.517229 -368.614964) (xy 214.529355 -368.560527)
			(xy 214.549278 -368.508436) (xy 214.576574 -368.459801) (xy 214.61066 -368.415658) (xy 214.650809 -368.376949)
			(xy 214.696167 -368.344498) (xy 214.745767 -368.318997) (xy 214.798551 -368.30099) (xy 214.853394 -368.29086)
			(xy 214.909128 -368.288823) (xy 214.964565 -368.294923) (xy 215.018522 -368.309029) (xy 215.069851 -368.330841)
			(xy 215.117457 -368.359895) (xy 215.160325 -368.39557) (xy 215.197542 -368.437107) (xy 215.228315 -368.48362)
			(xy 215.251987 -368.534117) (xy 215.268055 -368.587524) (xy 215.276175 -368.6427) (xy 215.276684 -368.670586)
			(xy 215.276175 -368.698472) (xy 215.268055 -368.753648) (xy 215.251987 -368.807055) (xy 215.228315 -368.857552)
			(xy 215.197542 -368.904065) (xy 215.160325 -368.945602) (xy 215.117457 -368.981277) (xy 215.069851 -369.010331)
			(xy 215.018522 -369.032143) (xy 214.964565 -369.046249) (xy 214.909128 -369.052349) (xy 214.853394 -369.050312)
			(xy 214.798551 -369.040182) (xy 214.745767 -369.022175) (xy 214.696167 -368.996674) (xy 214.650809 -368.964223)
			(xy 214.61066 -368.925514) (xy 214.576574 -368.881371) (xy 214.549278 -368.832736) (xy 214.529355 -368.780645)
			(xy 214.517229 -368.726208) (xy 214.513158 -368.670586) (xy 210.907376 -368.670586) (xy 210.907376 -370.810282)
			(xy 210.90769 -370.818565) (xy 210.912995 -370.834256) (xy 210.91779 -370.841016) (xy 210.927057 -370.852418)
			(xy 210.950737 -370.869793) (xy 210.978382 -370.879712) (xy 211.007706 -370.881355) (xy 211.036286 -370.874587)
			(xy 211.061759 -370.859966) (xy 211.072222 -370.849652) (xy 211.090315 -370.831182) (xy 211.13062 -370.798797)
			(xy 211.174928 -370.772151) (xy 211.222429 -370.751732) (xy 211.272252 -370.737914) (xy 211.323484 -370.73095)
			(xy 211.349336 -370.730526) (xy 211.380381 -370.731152) (xy 211.441649 -370.741233) (xy 211.471256 -370.750592)
			(xy 211.471764 -370.750592) (xy 211.475828 -370.752116) (xy 211.477606 -370.752878) (xy 211.481162 -370.753894)
			(xy 211.484972 -370.754656) (xy 211.490814 -370.755672) (xy 211.498085 -370.756724) (xy 211.512675 -370.755049)
			(xy 211.519516 -370.75237) (xy 211.572602 -370.729764) (xy 211.581492 -370.725954) (xy 211.6074 -370.700554)
			(xy 211.61121 -370.692426) (xy 211.624139 -370.666252) (xy 211.656748 -370.617834) (xy 211.69635 -370.574946)
			(xy 211.742023 -370.538591) (xy 211.792699 -370.509616) (xy 211.819744 -370.498624) (xy 211.829904 -370.494814)
			(xy 211.837524 -370.48694) (xy 211.841187 -370.483067) (xy 211.846947 -370.474099) (xy 211.848954 -370.46916)
			(xy 211.875116 -370.399564) (xy 211.877402 -370.391182) (xy 211.878407 -370.384749) (xy 211.8775 -370.371764)
			(xy 211.875624 -370.365528) (xy 211.87283 -370.357146) (xy 211.871052 -370.35359) (xy 211.870798 -370.353336)
			(xy 211.857508 -370.326234) (xy 211.838712 -370.268876) (xy 211.829196 -370.209272) (xy 211.828634 -370.179092)
			(xy 211.828634 -370.178838) (xy 211.82912 -370.151569) (xy 211.836882 -370.097585) (xy 211.852247 -370.045255)
			(xy 211.874904 -369.995645) (xy 211.90439 -369.949764) (xy 211.940105 -369.908547) (xy 211.981322 -369.872832)
			(xy 212.027203 -369.843346) (xy 212.076813 -369.820689) (xy 212.129143 -369.805324) (xy 212.183127 -369.797562)
			(xy 212.237665 -369.797562) (xy 212.291649 -369.805324) (xy 212.343979 -369.820689) (xy 212.393589 -369.843346)
			(xy 212.43947 -369.872832) (xy 212.480687 -369.908547) (xy 212.516402 -369.949764) (xy 212.545888 -369.995645)
			(xy 212.568545 -370.045255) (xy 212.58391 -370.097585) (xy 212.591672 -370.151569) (xy 212.592158 -370.178838)
			(xy 212.591643 -370.207569) (xy 212.583041 -370.264382) (xy 212.566021 -370.319264) (xy 212.540968 -370.370976)
			(xy 212.508448 -370.418349) (xy 212.469195 -370.460313) (xy 212.424097 -370.49592) (xy 212.374171 -370.524367)
			(xy 212.347556 -370.5352) (xy 212.347048 -370.535454) (xy 212.337268 -370.539805) (xy 212.322286 -370.555068)
			(xy 212.318092 -370.564918) (xy 212.292184 -370.634514) (xy 212.28943 -370.642711) (xy 212.289033 -370.659986)
			(xy 212.291422 -370.668296) (xy 212.294216 -370.676678) (xy 212.295994 -370.680234) (xy 212.296248 -370.680488)
			(xy 212.309535 -370.70759) (xy 212.328325 -370.764949) (xy 212.337836 -370.824553) (xy 212.338412 -370.854732)
			(xy 212.338412 -370.854986) (xy 212.337927 -370.882257) (xy 212.330167 -370.936245) (xy 212.314803 -370.988579)
			(xy 212.292148 -371.038194) (xy 212.262664 -371.084081) (xy 212.226949 -371.125304) (xy 212.185732 -371.161025)
			(xy 212.139851 -371.190518) (xy 212.090239 -371.213181) (xy 212.037908 -371.228553) (xy 211.983921 -371.236322)
			(xy 211.95665 -371.236748) (xy 211.925605 -371.236121) (xy 211.864338 -371.226037) (xy 211.83473 -371.216682)
			(xy 211.834222 -371.216682) (xy 211.830158 -371.215158) (xy 211.82838 -371.214396) (xy 211.824824 -371.21338)
			(xy 211.821014 -371.212618) (xy 211.815172 -371.211602) (xy 211.807901 -371.210552) (xy 211.793313 -371.21223)
			(xy 211.78647 -371.214904) (xy 211.733384 -371.23751) (xy 211.724494 -371.24132) (xy 211.698586 -371.26672)
			(xy 211.694776 -371.274848) (xy 211.682838 -371.297962) (xy 211.712556 -371.348508) (xy 211.717354 -371.355887)
			(xy 211.730906 -371.367096) (xy 211.747451 -371.373063) (xy 211.756244 -371.3734) (xy 212.768688 -371.3734)
			(xy 212.778759 -371.372979) (xy 212.797367 -371.365268) (xy 212.804756 -371.358414) (xy 212.926422 -371.236748)
			(xy 212.929216 -371.228112) (xy 212.937459 -371.202227) (xy 212.960249 -371.152915) (xy 212.9898 -371.107333)
			(xy 213.025515 -371.066401) (xy 213.066673 -371.030946) (xy 213.112441 -371.001685) (xy 213.161896 -370.979208)
			(xy 213.214038 -370.96397) (xy 213.267814 -370.956279) (xy 213.294976 -370.955824) (xy 213.29523 -370.955824)
			(xy 213.326076 -370.956411) (xy 213.386966 -370.966324) (xy 213.445468 -370.985904) (xy 213.47303 -370.999766)
			(xy 213.478562 -371.002458) (xy 213.490503 -371.005403) (xy 213.496652 -371.005608) (xy 213.698328 -371.005608)
			(xy 213.708396 -371.00518) (xy 213.726994 -370.99746) (xy 213.734396 -370.990622) (xy 216.597738 -368.12728)
			(xy 216.604588 -368.119883) (xy 216.612325 -368.101285) (xy 216.612724 -368.091212) (xy 216.612724 -361.517692)
			(xy 216.613064 -361.498395) (xy 216.617647 -361.460071) (xy 216.621868 -361.441238) (xy 216.623138 -361.435396)
			(xy 216.623138 -361.405424) (xy 216.623672 -361.395435) (xy 216.631384 -361.377001) (xy 216.638124 -361.36961)
			(xy 216.658952 -361.348782) (xy 216.662254 -361.343702) (xy 216.672604 -361.32734) (xy 216.69654 -361.296907)
			(xy 216.710006 -361.282996) (xy 217.151204 -360.841798) (xy 217.165116 -360.828333) (xy 217.195549 -360.804398)
			(xy 217.21191 -360.794046) (xy 217.221054 -360.78668) (xy 217.237818 -360.769916) (xy 217.245164 -360.763107)
			(xy 217.263626 -360.755378) (xy 217.273632 -360.75493) (xy 217.303604 -360.75493) (xy 217.309446 -360.75366)
			(xy 217.328275 -360.749414) (xy 217.366601 -360.744825) (xy 217.3859 -360.744516) (xy 222.525844 -360.744516)
			(xy 222.545141 -360.744858) (xy 222.583464 -360.749445) (xy 222.602298 -360.75366) (xy 222.60814 -360.75493)
			(xy 222.638112 -360.75493) (xy 222.648098 -360.75547) (xy 222.666524 -360.76319) (xy 222.673926 -360.769916)
			(xy 222.69069 -360.78668) (xy 222.699834 -360.794046) (xy 222.716195 -360.804398) (xy 222.746626 -360.828335)
			(xy 222.76054 -360.841798) (xy 223.170242 -361.2515) (xy 223.183709 -361.26541) (xy 223.207648 -361.295841)
			(xy 223.217994 -361.312206) (xy 223.221296 -361.317286) (xy 223.242124 -361.338114) (xy 223.24894 -361.345456)
			(xy 223.25668 -361.36392) (xy 223.25711 -361.373928) (xy 223.25711 -361.4039) (xy 223.25838 -361.409742)
			(xy 223.262626 -361.428571) (xy 223.267215 -361.466897) (xy 223.267524 -361.486196) (xy 223.267524 -365.978186)
			(xy 226.247958 -365.978186) (xy 226.252029 -365.922564) (xy 226.264155 -365.868127) (xy 226.284078 -365.816036)
			(xy 226.311374 -365.767401) (xy 226.34546 -365.723258) (xy 226.385609 -365.684549) (xy 226.430967 -365.652098)
			(xy 226.480567 -365.626597) (xy 226.533351 -365.60859) (xy 226.588194 -365.59846) (xy 226.643928 -365.596423)
			(xy 226.699365 -365.602523) (xy 226.753322 -365.616629) (xy 226.804651 -365.638441) (xy 226.852257 -365.667495)
			(xy 226.895125 -365.70317) (xy 226.932342 -365.744707) (xy 226.963115 -365.79122) (xy 226.986787 -365.841717)
			(xy 227.002855 -365.895124) (xy 227.010975 -365.9503) (xy 227.011484 -365.978186) (xy 227.010975 -366.006072)
			(xy 227.002855 -366.061248) (xy 226.986787 -366.114655) (xy 226.963115 -366.165152) (xy 226.932342 -366.211665)
			(xy 226.895125 -366.253202) (xy 226.852257 -366.288877) (xy 226.804651 -366.317931) (xy 226.753322 -366.339743)
			(xy 226.699365 -366.353849) (xy 226.643928 -366.359949) (xy 226.588194 -366.357912) (xy 226.533351 -366.347782)
			(xy 226.480567 -366.329775) (xy 226.430967 -366.304274) (xy 226.385609 -366.271823) (xy 226.34546 -366.233114)
			(xy 226.311374 -366.188971) (xy 226.284078 -366.140336) (xy 226.264155 -366.088245) (xy 226.252029 -366.033808)
			(xy 226.247958 -365.978186) (xy 223.267524 -365.978186) (xy 223.267524 -366.547146) (xy 223.267182 -366.566443)
			(xy 223.262595 -366.604766) (xy 223.25838 -366.6236) (xy 223.25711 -366.629442) (xy 223.25711 -366.659414)
			(xy 223.25657 -366.669401) (xy 223.248854 -366.68783) (xy 223.242124 -366.695228) (xy 223.221296 -366.716056)
			(xy 223.217994 -366.721136) (xy 223.207641 -366.737496) (xy 223.1837 -366.767924) (xy 223.170242 -366.781842)
			(xy 222.957898 -366.994186) (xy 225.485958 -366.994186) (xy 225.490029 -366.938564) (xy 225.502155 -366.884127)
			(xy 225.522078 -366.832036) (xy 225.549374 -366.783401) (xy 225.58346 -366.739258) (xy 225.623609 -366.700549)
			(xy 225.668967 -366.668098) (xy 225.718567 -366.642597) (xy 225.771351 -366.62459) (xy 225.826194 -366.61446)
			(xy 225.881928 -366.612423) (xy 225.937365 -366.618523) (xy 225.991322 -366.632629) (xy 226.042651 -366.654441)
			(xy 226.090257 -366.683495) (xy 226.133125 -366.71917) (xy 226.170342 -366.760707) (xy 226.201115 -366.80722)
			(xy 226.224787 -366.857717) (xy 226.240855 -366.911124) (xy 226.248975 -366.9663) (xy 226.249484 -366.994186)
			(xy 226.248975 -367.022072) (xy 226.240855 -367.077248) (xy 226.224787 -367.130655) (xy 226.201115 -367.181152)
			(xy 226.170342 -367.227665) (xy 226.133125 -367.269202) (xy 226.090257 -367.304877) (xy 226.042651 -367.333931)
			(xy 225.991322 -367.355743) (xy 225.937365 -367.369849) (xy 225.881928 -367.375949) (xy 225.826194 -367.373912)
			(xy 225.771351 -367.363782) (xy 225.718567 -367.345775) (xy 225.668967 -367.320274) (xy 225.623609 -367.287823)
			(xy 225.58346 -367.249114) (xy 225.549374 -367.204971) (xy 225.522078 -367.156336) (xy 225.502155 -367.104245)
			(xy 225.490029 -367.049808) (xy 225.485958 -366.994186) (xy 222.957898 -366.994186) (xy 222.280226 -367.671858)
			(xy 222.279718 -367.678716) (xy 222.279718 -368.207544) (xy 226.247958 -368.207544) (xy 226.252029 -368.151922)
			(xy 226.264155 -368.097485) (xy 226.284078 -368.045394) (xy 226.311374 -367.996759) (xy 226.34546 -367.952616)
			(xy 226.385609 -367.913907) (xy 226.430967 -367.881456) (xy 226.480567 -367.855955) (xy 226.533351 -367.837948)
			(xy 226.588194 -367.827818) (xy 226.643928 -367.825781) (xy 226.699365 -367.831881) (xy 226.753322 -367.845987)
			(xy 226.804651 -367.867799) (xy 226.852257 -367.896853) (xy 226.895125 -367.932528) (xy 226.932342 -367.974065)
			(xy 226.963115 -368.020578) (xy 226.986787 -368.071075) (xy 227.002855 -368.124482) (xy 227.010975 -368.179658)
			(xy 227.011484 -368.207544) (xy 227.010975 -368.23543) (xy 227.002855 -368.290606) (xy 226.986787 -368.344013)
			(xy 226.963115 -368.39451) (xy 226.932342 -368.441023) (xy 226.895125 -368.48256) (xy 226.852257 -368.518235)
			(xy 226.804651 -368.547289) (xy 226.753322 -368.569101) (xy 226.699365 -368.583207) (xy 226.643928 -368.589307)
			(xy 226.588194 -368.58727) (xy 226.533351 -368.57714) (xy 226.480567 -368.559133) (xy 226.430967 -368.533632)
			(xy 226.385609 -368.501181) (xy 226.34546 -368.462472) (xy 226.311374 -368.418329) (xy 226.284078 -368.369694)
			(xy 226.264155 -368.317603) (xy 226.252029 -368.263166) (xy 226.247958 -368.207544) (xy 222.279718 -368.207544)
			(xy 222.279718 -368.727736) (xy 222.2802 -368.742085) (xy 222.288168 -368.769655) (xy 222.303494 -368.793918)
			(xy 222.324967 -368.812958) (xy 222.35089 -368.825271) (xy 222.379215 -368.829883) (xy 222.39351 -368.828574)
			(xy 222.404832 -368.827275) (xy 222.42758 -368.825875) (xy 222.438976 -368.82578) (xy 222.439738 -368.82578)
			(xy 222.471917 -368.826424) (xy 222.535374 -368.837148) (xy 222.565976 -368.847116) (xy 222.57258 -368.849148)
			(xy 222.587271 -368.851574) (xy 222.616902 -368.848782) (xy 222.644472 -368.837573) (xy 222.667645 -368.818896)
			(xy 222.684455 -368.794336) (xy 222.693477 -368.765975) (xy 222.694246 -368.751104) (xy 222.693992 -368.74577)
			(xy 222.693992 -368.744754) (xy 222.693738 -368.74323) (xy 222.693738 -368.742722) (xy 222.692214 -368.708178)
			(xy 222.692214 -368.70767) (xy 222.692703 -368.680399) (xy 222.700469 -368.626413) (xy 222.715839 -368.574081)
			(xy 222.738501 -368.52447) (xy 222.767992 -368.478589) (xy 222.803712 -368.437371) (xy 222.844935 -368.401657)
			(xy 222.890821 -368.372173) (xy 222.940436 -368.349519) (xy 222.99277 -368.334157) (xy 223.046757 -368.326398)
			(xy 223.101299 -368.326402) (xy 223.155285 -368.334169) (xy 223.207617 -368.349539) (xy 223.257228 -368.3722)
			(xy 223.30311 -368.401691) (xy 223.344327 -368.437411) (xy 223.380042 -368.478634) (xy 223.409526 -368.524519)
			(xy 223.43218 -368.574134) (xy 223.447543 -368.626468) (xy 223.455301 -368.680455) (xy 223.455298 -368.734997)
			(xy 223.447532 -368.788983) (xy 223.432162 -368.841315) (xy 223.409501 -368.890926) (xy 223.380011 -368.936808)
			(xy 223.369691 -368.948716) (xy 225.509326 -368.948716) (xy 225.513397 -368.893094) (xy 225.525523 -368.838657)
			(xy 225.545446 -368.786566) (xy 225.572742 -368.737931) (xy 225.606828 -368.693788) (xy 225.646977 -368.655079)
			(xy 225.692335 -368.622628) (xy 225.741935 -368.597127) (xy 225.794719 -368.57912) (xy 225.849562 -368.56899)
			(xy 225.905296 -368.566953) (xy 225.960733 -368.573053) (xy 226.01469 -368.587159) (xy 226.066019 -368.608971)
			(xy 226.113625 -368.638025) (xy 226.156493 -368.6737) (xy 226.19371 -368.715237) (xy 226.224483 -368.76175)
			(xy 226.248155 -368.812247) (xy 226.264223 -368.865654) (xy 226.272343 -368.92083) (xy 226.272852 -368.948716)
			(xy 226.272343 -368.976602) (xy 226.264223 -369.031778) (xy 226.248155 -369.085185) (xy 226.224483 -369.135682)
			(xy 226.19371 -369.182195) (xy 226.156493 -369.223732) (xy 226.113625 -369.259407) (xy 226.066019 -369.288461)
			(xy 226.01469 -369.310273) (xy 225.960733 -369.324379) (xy 225.905296 -369.330479) (xy 225.849562 -369.328442)
			(xy 225.794719 -369.318312) (xy 225.741935 -369.300305) (xy 225.692335 -369.274804) (xy 225.646977 -369.242353)
			(xy 225.606828 -369.203644) (xy 225.572742 -369.159501) (xy 225.545446 -369.110866) (xy 225.525523 -369.058775)
			(xy 225.513397 -369.004338) (xy 225.509326 -368.948716) (xy 223.369691 -368.948716) (xy 223.34429 -368.978026)
			(xy 223.303068 -369.013741) (xy 223.257183 -369.043225) (xy 223.207568 -369.06588) (xy 223.155234 -369.081243)
			(xy 223.101247 -369.089001) (xy 223.073976 -369.089432) (xy 223.073214 -369.089432) (xy 223.041036 -369.088784)
			(xy 222.977582 -369.078053) (xy 222.946976 -369.068096) (xy 222.940372 -369.066064) (xy 222.925677 -369.06363)
			(xy 222.896035 -369.06641) (xy 222.868452 -369.077615) (xy 222.845267 -369.096293) (xy 222.828449 -369.12086)
			(xy 222.819424 -369.149231) (xy 222.818706 -369.164108) (xy 222.81896 -369.169442) (xy 222.81896 -369.170458)
			(xy 222.819214 -369.171982) (xy 222.819214 -369.17249) (xy 222.820738 -369.207034) (xy 222.820738 -369.207542)
			(xy 222.820249 -369.234809) (xy 222.812482 -369.288787) (xy 222.797113 -369.34111) (xy 222.774454 -369.390713)
			(xy 222.744966 -369.436587) (xy 222.709251 -369.477798) (xy 222.668034 -369.513506) (xy 222.622155 -369.542986)
			(xy 222.572548 -369.565636) (xy 222.520222 -369.580996) (xy 222.466243 -369.588753) (xy 222.438976 -369.589304)
			(xy 222.427581 -369.589193) (xy 222.404833 -369.587792) (xy 222.39351 -369.58651) (xy 222.379211 -369.585273)
			(xy 222.350894 -369.589882) (xy 222.324976 -369.602183) (xy 222.303501 -369.621206) (xy 222.288163 -369.64545)
			(xy 222.280171 -369.673004) (xy 222.279718 -369.687348) (xy 222.279718 -370.042186) (xy 223.453958 -370.042186)
			(xy 223.458029 -369.986564) (xy 223.470155 -369.932127) (xy 223.490078 -369.880036) (xy 223.517374 -369.831401)
			(xy 223.55146 -369.787258) (xy 223.591609 -369.748549) (xy 223.636967 -369.716098) (xy 223.686567 -369.690597)
			(xy 223.739351 -369.67259) (xy 223.794194 -369.66246) (xy 223.849928 -369.660423) (xy 223.905365 -369.666523)
			(xy 223.959322 -369.680629) (xy 224.010651 -369.702441) (xy 224.058257 -369.731495) (xy 224.101125 -369.76717)
			(xy 224.138342 -369.808707) (xy 224.169115 -369.85522) (xy 224.192787 -369.905717) (xy 224.208855 -369.959124)
			(xy 224.216975 -370.0143) (xy 224.217484 -370.042186) (xy 224.216975 -370.070072) (xy 224.208855 -370.125248)
			(xy 224.192787 -370.178655) (xy 224.169115 -370.229152) (xy 224.138342 -370.275665) (xy 224.101125 -370.317202)
			(xy 224.058257 -370.352877) (xy 224.010651 -370.381931) (xy 223.959322 -370.403743) (xy 223.905365 -370.417849)
			(xy 223.849928 -370.423949) (xy 223.794194 -370.421912) (xy 223.739351 -370.411782) (xy 223.686567 -370.393775)
			(xy 223.636967 -370.368274) (xy 223.591609 -370.335823) (xy 223.55146 -370.297114) (xy 223.517374 -370.252971)
			(xy 223.490078 -370.204336) (xy 223.470155 -370.152245) (xy 223.458029 -370.097808) (xy 223.453958 -370.042186)
			(xy 222.279718 -370.042186) (xy 222.279718 -373.089932) (xy 222.280226 -373.097044) (xy 223.936814 -374.753632)
			(xy 223.94545 -374.756426) (xy 223.974891 -374.765881) (xy 224.030479 -374.79296) (xy 224.080975 -374.828647)
			(xy 224.103438 -374.849898) (xy 224.122677 -374.869443) (xy 224.155924 -374.913058) (xy 224.182594 -374.960979)
			(xy 224.202138 -375.01222) (xy 224.208594 -375.038874) (xy 224.208594 -375.039128) (xy 224.211651 -375.050216)
			(xy 224.225948 -375.068206) (xy 224.246635 -375.07821) (xy 224.258124 -375.078752) (xy 225.254312 -375.078752)
			(xy 225.26438 -375.078325) (xy 225.282977 -375.070602) (xy 225.29038 -375.063766) (xy 226.334574 -374.019572)
			(xy 226.339775 -374.013824) (xy 226.346759 -373.999993) (xy 226.34829 -373.992394) (xy 226.349052 -373.984012)
			(xy 226.349052 -373.48287) (xy 226.348516 -373.467876) (xy 226.339805 -373.43918) (xy 226.323143 -373.414247)
			(xy 226.299962 -373.395222) (xy 226.272258 -373.383742) (xy 226.242415 -373.380796) (xy 226.213 -373.386636)
			(xy 226.186546 -373.40076) (xy 226.17557 -373.410988) (xy 226.174808 -373.41175) (xy 226.124008 -373.41175)
			(xy 226.118166 -373.41302) (xy 226.105802 -373.415822) (xy 226.080755 -373.419761) (xy 226.068128 -373.420894)
			(xy 226.062883 -373.42141) (xy 226.052767 -373.424361) (xy 226.048062 -373.426736) (xy 226.020227 -373.44092)
			(xy 225.961087 -373.461042) (xy 225.899464 -373.47129) (xy 225.86823 -373.471948) (xy 225.867976 -373.471948)
			(xy 225.840709 -373.47146) (xy 225.78673 -373.463696) (xy 225.734405 -373.448329) (xy 225.6848 -373.425672)
			(xy 225.638923 -373.396187) (xy 225.59771 -373.360473) (xy 225.561999 -373.319257) (xy 225.532516 -373.273379)
			(xy 225.509863 -373.223772) (xy 225.494499 -373.171447) (xy 225.486738 -373.117467) (xy 225.486738 -373.062933)
			(xy 225.494499 -373.008953) (xy 225.509863 -372.956628) (xy 225.532516 -372.907021) (xy 225.561999 -372.861143)
			(xy 225.59771 -372.819927) (xy 225.638923 -372.784213) (xy 225.6848 -372.754728) (xy 225.734405 -372.732071)
			(xy 225.78673 -372.716704) (xy 225.840709 -372.70894) (xy 225.867976 -372.708424) (xy 225.881357 -372.708558)
			(xy 225.908051 -372.710466) (xy 225.921316 -372.712234) (xy 225.921824 -372.712234) (xy 225.938334 -372.71452)
			(xy 225.94824 -372.714266) (xy 226.851464 -371.811296) (xy 226.857103 -371.805252) (xy 226.864494 -371.790478)
			(xy 226.865942 -371.78234) (xy 226.86742 -371.76883) (xy 226.863998 -371.741878) (xy 226.853592 -371.716782)
			(xy 226.836936 -371.695318) (xy 226.826318 -371.686836) (xy 226.803052 -371.668684) (xy 226.76187 -371.626421)
			(xy 226.727679 -371.578328) (xy 226.701292 -371.525547) (xy 226.683337 -371.469336) (xy 226.674241 -371.411032)
			(xy 226.673664 -371.381528) (xy 226.674126 -371.354256) (xy 226.681885 -371.300268) (xy 226.697249 -371.247933)
			(xy 226.719905 -371.198318) (xy 226.749392 -371.152433) (xy 226.78511 -371.111212) (xy 226.826331 -371.075494)
			(xy 226.872217 -371.046006) (xy 226.921831 -371.023349) (xy 226.974166 -371.007985) (xy 227.028154 -371.000226)
			(xy 227.055426 -370.999766) (xy 227.084934 -371.000311) (xy 227.143249 -371.009388) (xy 227.19947 -371.027335)
			(xy 227.252258 -371.053725) (xy 227.300352 -371.087929) (xy 227.342605 -371.129131) (xy 227.360734 -371.15242)
			(xy 227.369227 -371.163031) (xy 227.390683 -371.1797) (xy 227.415777 -371.190115) (xy 227.44273 -371.19354)
			(xy 227.456238 -371.192044) (xy 227.464366 -371.190567) (xy 227.479132 -371.18318) (xy 227.485194 -371.177566)
			(xy 227.649786 -371.012974) (xy 227.65663 -371.005575) (xy 227.664357 -370.986977) (xy 227.664772 -370.976906)
			(xy 227.664772 -370.625116) (xy 227.664487 -370.61686) (xy 227.659293 -370.60119) (xy 227.654612 -370.594382)
			(xy 227.64627 -370.583959) (xy 227.625242 -370.567524) (xy 227.60067 -370.557108) (xy 227.574236 -370.553425)
			(xy 227.547753 -370.556726) (xy 227.535232 -370.561362) (xy 227.512389 -370.570182) (xy 227.465023 -370.582604)
			(xy 227.41646 -370.588884) (xy 227.391976 -370.589302) (xy 227.364705 -370.588814) (xy 227.310718 -370.581049)
			(xy 227.258386 -370.56568) (xy 227.208774 -370.54302) (xy 227.162891 -370.51353) (xy 227.121672 -370.477811)
			(xy 227.085956 -370.43659) (xy 227.056469 -370.390705) (xy 227.033812 -370.341091) (xy 227.018446 -370.288758)
			(xy 227.010684 -370.234771) (xy 227.010684 -370.180229) (xy 227.018446 -370.126242) (xy 227.033812 -370.073909)
			(xy 227.056469 -370.024295) (xy 227.085956 -369.97841) (xy 227.121672 -369.937189) (xy 227.162891 -369.90147)
			(xy 227.208774 -369.87198) (xy 227.258386 -369.84932) (xy 227.310718 -369.833951) (xy 227.364705 -369.826186)
			(xy 227.391976 -369.825778) (xy 227.416463 -369.826149) (xy 227.465035 -369.832413) (xy 227.512403 -369.844854)
			(xy 227.535232 -369.853718) (xy 227.547757 -369.858297) (xy 227.574217 -369.861532) (xy 227.600615 -369.857823)
			(xy 227.625159 -369.847422) (xy 227.646185 -369.831036) (xy 227.654612 -369.820698) (xy 227.659315 -369.813902)
			(xy 227.664506 -369.798223) (xy 227.664772 -369.789964) (xy 227.664772 -361.769914) (xy 227.665035 -361.750685)
			(xy 227.669489 -361.712486) (xy 227.673662 -361.693714) (xy 227.674932 -361.687872) (xy 227.674932 -361.6579)
			(xy 227.67547 -361.647913) (xy 227.683187 -361.629484) (xy 227.689918 -361.622086) (xy 227.710746 -361.601258)
			(xy 227.714048 -361.596178) (xy 227.724399 -361.579817) (xy 227.748336 -361.549385) (xy 227.7618 -361.535472)
			(xy 228.171756 -361.125516) (xy 228.185666 -361.112049) (xy 228.216096 -361.088109) (xy 228.232462 -361.077764)
			(xy 228.241606 -361.070398) (xy 228.25837 -361.053634) (xy 228.265717 -361.046831) (xy 228.28418 -361.039118)
			(xy 228.294184 -361.038648) (xy 228.324156 -361.038648) (xy 228.329998 -361.037378) (xy 228.348775 -361.033233)
			(xy 228.386971 -361.028782) (xy 228.406198 -361.028488) (xy 233.089196 -361.028488) (xy 233.108425 -361.028751)
			(xy 233.146623 -361.033207) (xy 233.165396 -361.037378) (xy 233.171238 -361.038648) (xy 233.20121 -361.038648)
			(xy 233.211196 -361.039189) (xy 233.22962 -361.04691) (xy 233.237024 -361.053634) (xy 233.253788 -361.070398)
			(xy 233.262932 -361.077764) (xy 233.279293 -361.088116) (xy 233.309723 -361.112054) (xy 233.323638 -361.125516)
			(xy 234.829096 -362.630974) (xy 234.847128 -362.649745) (xy 234.877707 -362.691862) (xy 234.901334 -362.738238)
			(xy 234.917427 -362.787735) (xy 234.925593 -362.839139) (xy 234.926124 -362.865162) (xy 234.926124 -368.69243)
			(xy 234.925598 -368.718454) (xy 234.917433 -368.769859) (xy 234.901341 -368.819357) (xy 234.877715 -368.865735)
			(xy 234.847135 -368.907853) (xy 234.829096 -368.926618) (xy 234.47629 -369.279424) (xy 234.469437 -369.286819)
			(xy 234.461698 -369.305419) (xy 234.461304 -369.315492) (xy 234.461304 -374.996964) (xy 234.461744 -375.006995)
			(xy 234.469322 -375.025567) (xy 234.476036 -375.033032) (xy 234.53725 -375.094246) (xy 234.544649 -375.10109)
			(xy 234.563247 -375.108815) (xy 234.573318 -375.109232) (xy 234.86491 -375.109232) (xy 234.876848 -375.106184)
			(xy 234.882436 -375.103136) (xy 234.910007 -375.089294) (xy 234.968506 -375.069712) (xy 235.029391 -375.059786)
			(xy 235.060236 -375.059194) (xy 235.06049 -375.059194) (xy 235.087693 -375.059674) (xy 235.141548 -375.067389)
			(xy 235.193764 -375.082665) (xy 235.243286 -375.105194) (xy 235.289111 -375.134518) (xy 235.330314 -375.170046)
			(xy 235.348526 -375.190258) (xy 235.679742 -375.190258) (xy 235.821728 -375.048272) (xy 235.821728 -368.224562)
			(xy 235.822159 -368.214495) (xy 235.829886 -368.195904) (xy 235.836714 -368.188494) (xy 236.545628 -367.479326)
			(xy 236.545628 -367.47069) (xy 236.62386 -367.401094) (xy 236.628319 -367.395303) (xy 236.634109 -367.381891)
			(xy 236.63529 -367.374678) (xy 236.635544 -367.368582) (xy 236.635544 -366.539526) (xy 236.635106 -366.529463)
			(xy 236.627366 -366.510883) (xy 236.620558 -366.503458) (xy 236.358938 -366.241838) (xy 236.352097 -366.234438)
			(xy 236.344379 -366.215839) (xy 236.343952 -366.20577) (xy 236.343952 -361.125516) (xy 236.344392 -361.115454)
			(xy 236.352134 -361.096876) (xy 236.358938 -361.089448) (xy 236.620558 -360.827828) (xy 236.627398 -360.820428)
			(xy 236.635113 -360.801829) (xy 236.635544 -360.79176) (xy 236.635544 -358.773984) (xy 236.635195 -358.765294)
			(xy 236.629345 -358.748929) (xy 236.624114 -358.74198) (xy 236.620812 -358.73817) (xy 236.618018 -358.735376)
			(xy 236.61751 -358.735122) (xy 236.405928 -358.523286) (xy 235.989876 -358.107234) (xy 235.988352 -358.105964)
			(xy 235.987844 -358.105456) (xy 235.986828 -358.10444) (xy 235.978954 -358.096312) (xy 235.978192 -358.09555)
			(xy 235.97108 -358.088184) (xy 235.961428 -358.084374) (xy 235.956861 -358.082618) (xy 235.947269 -358.080697)
			(xy 235.942378 -358.080564) (xy 202.191366 -358.080564) (xy 202.177278 -358.081022) (xy 202.150177 -358.088728)
			(xy 202.126211 -358.103544) (xy 202.107204 -358.124343) (xy 202.094602 -358.149543) (xy 202.089363 -358.177227)
			(xy 202.091885 -358.20529) (xy 202.101977 -358.231596) (xy 202.110086 -358.243124) (xy 202.127995 -358.268058)
			(xy 202.156459 -358.322447) (xy 202.175854 -358.380689) (xy 202.18568 -358.441285) (xy 202.186286 -358.471978)
			(xy 202.1858 -358.499247) (xy 202.178038 -358.553231) (xy 202.162673 -358.605561) (xy 202.140016 -358.655171)
			(xy 202.11053 -358.701052) (xy 202.074815 -358.742269) (xy 202.033598 -358.777984) (xy 201.987717 -358.80747)
			(xy 201.938107 -358.830127) (xy 201.885777 -358.845492) (xy 201.831793 -358.853254) (xy 201.777255 -358.853254)
			(xy 201.723271 -358.845492) (xy 201.670941 -358.830127) (xy 201.621331 -358.80747) (xy 201.57545 -358.777984)
			(xy 201.534233 -358.742269) (xy 201.498518 -358.701052) (xy 201.469032 -358.655171) (xy 201.446375 -358.605561)
			(xy 201.43101 -358.553231) (xy 201.423248 -358.499247) (xy 201.422762 -358.471978) (xy 201.423377 -358.441286)
			(xy 201.433203 -358.380692) (xy 201.4526 -358.322452) (xy 201.481066 -358.268067) (xy 201.498962 -358.243124)
			(xy 201.507047 -358.231584) (xy 201.517141 -358.205289) (xy 201.519665 -358.177236) (xy 201.514428 -358.149561)
			(xy 201.501827 -358.124371) (xy 201.482822 -358.103583) (xy 201.45886 -358.08878) (xy 201.431765 -358.081088)
			(xy 201.417682 -358.080564) (xy 199.49541 -358.080564) (xy 199.483005 -358.080952) (xy 199.458944 -358.08701)
			(xy 199.437055 -358.098695) (xy 199.427592 -358.106726) (xy 199.427084 -358.107234) (xy 199.422259 -358.111809)
			(xy 199.413718 -358.121998) (xy 199.410066 -358.127554) (xy 199.409558 -358.12857) (xy 199.40905 -358.129078)
			(xy 199.407018 -358.13238) (xy 199.399602 -358.146743) (xy 199.393345 -358.17844) (xy 199.397313 -358.210503)
			(xy 199.403716 -358.225344) (xy 199.415181 -358.250849) (xy 199.431354 -358.304376) (xy 199.43954 -358.359691)
			(xy 199.440038 -358.38765) (xy 199.440038 -358.388158) (xy 199.439552 -358.415427) (xy 199.43179 -358.469411)
			(xy 199.416425 -358.521741) (xy 199.393768 -358.571351) (xy 199.364282 -358.617232) (xy 199.328567 -358.658449)
			(xy 199.28735 -358.694164) (xy 199.241469 -358.72365) (xy 199.191859 -358.746307) (xy 199.139529 -358.761672)
			(xy 199.085545 -358.769434) (xy 199.031007 -358.769434) (xy 198.977023 -358.761672) (xy 198.924693 -358.746307)
			(xy 198.875083 -358.72365) (xy 198.829202 -358.694164) (xy 198.787985 -358.658449) (xy 198.75227 -358.617232)
			(xy 198.722784 -358.571351) (xy 198.700127 -358.521741) (xy 198.684762 -358.469411) (xy 198.677 -358.415427)
			(xy 198.676514 -358.388158) (xy 198.676514 -358.38765) (xy 198.67702 -358.359692) (xy 198.685206 -358.304377)
			(xy 198.701367 -358.250846) (xy 198.712836 -358.225344) (xy 198.719164 -358.210483) (xy 198.7231 -358.178441)
			(xy 198.716891 -358.14676) (xy 198.709534 -358.13238) (xy 198.707502 -358.129078) (xy 198.706994 -358.12857)
			(xy 198.706486 -358.127554) (xy 198.702835 -358.121997) (xy 198.694299 -358.111803) (xy 198.689468 -358.107234)
			(xy 198.68896 -358.106726) (xy 198.679512 -358.098673) (xy 198.657619 -358.086983) (xy 198.63355 -358.080929)
			(xy 198.621142 -358.080564) (xy 197.19163 -358.080564) (xy 197.182937 -358.080906) (xy 197.166563 -358.086745)
			(xy 197.159626 -358.091994) (xy 197.155816 -358.095296) (xy 196.684138 -358.566974) (xy 196.682868 -358.568498)
			(xy 196.68236 -358.569006) (xy 196.681344 -358.570022) (xy 196.673216 -358.577896) (xy 196.672454 -358.578658)
			(xy 196.665088 -358.58577) (xy 196.661278 -358.595422) (xy 196.659527 -358.59999) (xy 196.657614 -358.609582)
			(xy 196.657468 -358.614472) (xy 196.657468 -358.863392) (xy 197.77913 -358.863392) (xy 197.783201 -358.80777)
			(xy 197.795327 -358.753333) (xy 197.81525 -358.701242) (xy 197.842546 -358.652607) (xy 197.876632 -358.608464)
			(xy 197.916781 -358.569755) (xy 197.962139 -358.537304) (xy 198.011739 -358.511803) (xy 198.064523 -358.493796)
			(xy 198.119366 -358.483666) (xy 198.1751 -358.481629) (xy 198.230537 -358.487729) (xy 198.284494 -358.501835)
			(xy 198.335823 -358.523647) (xy 198.383429 -358.552701) (xy 198.426297 -358.588376) (xy 198.463514 -358.629913)
			(xy 198.494287 -358.676426) (xy 198.517959 -358.726923) (xy 198.534027 -358.78033) (xy 198.542147 -358.835506)
			(xy 198.542656 -358.863392) (xy 198.542147 -358.891278) (xy 198.534027 -358.946454) (xy 198.517959 -358.999861)
			(xy 198.494287 -359.050358) (xy 198.463514 -359.096871) (xy 198.426297 -359.138408) (xy 198.383429 -359.174083)
			(xy 198.335823 -359.203137) (xy 198.284494 -359.224949) (xy 198.230537 -359.239055) (xy 198.1751 -359.245155)
			(xy 198.119366 -359.243118) (xy 198.064523 -359.232988) (xy 198.011739 -359.214981) (xy 197.962139 -359.18948)
			(xy 197.916781 -359.157029) (xy 197.876632 -359.11832) (xy 197.842546 -359.074177) (xy 197.81525 -359.025542)
			(xy 197.795327 -358.973451) (xy 197.783201 -358.919014) (xy 197.77913 -358.863392) (xy 196.657468 -358.863392)
			(xy 196.657468 -359.311154) (xy 201.002385 -359.311154) (xy 201.010141 -359.257208) (xy 201.025495 -359.204915)
			(xy 201.048134 -359.15534) (xy 201.077598 -359.109491) (xy 201.113287 -359.068301) (xy 201.154475 -359.03261)
			(xy 201.200322 -359.003143) (xy 201.249897 -358.980502) (xy 201.302189 -358.965145) (xy 201.356134 -358.957387)
			(xy 201.410634 -358.957385) (xy 201.46458 -358.965138) (xy 201.516873 -358.98049) (xy 201.56645 -359.003128)
			(xy 201.6123 -359.032591) (xy 201.65349 -359.068278) (xy 201.689183 -359.109465) (xy 201.718651 -359.155312)
			(xy 201.741294 -359.204885) (xy 201.756652 -359.257177) (xy 201.764412 -359.311122) (xy 201.7649 -359.338372)
			(xy 201.7649 -359.33888) (xy 201.764514 -359.36276) (xy 201.758532 -359.410144) (xy 201.752962 -359.433368)
			(xy 201.750059 -359.446706) (xy 201.750476 -359.473984) (xy 201.758111 -359.500175) (xy 201.772418 -359.523403)
			(xy 201.792371 -359.542007) (xy 201.816543 -359.554654) (xy 201.843204 -359.560439) (xy 201.870444 -359.558948)
			(xy 201.883518 -359.555034) (xy 201.912952 -359.545795) (xy 201.973832 -359.535837) (xy 202.004676 -359.535222)
			(xy 202.005184 -359.535222) (xy 202.032436 -359.535661) (xy 202.086386 -359.543415) (xy 202.138683 -359.558768)
			(xy 202.188263 -359.581408) (xy 202.234117 -359.610873) (xy 202.27531 -359.646564) (xy 202.311005 -359.687754)
			(xy 202.340474 -359.733605) (xy 202.363119 -359.783182) (xy 202.378477 -359.835478) (xy 202.386237 -359.889427)
			(xy 202.38624 -359.943932) (xy 202.378486 -359.997882) (xy 202.363133 -360.050179) (xy 202.340494 -360.099759)
			(xy 202.31103 -360.145613) (xy 202.275339 -360.186807) (xy 202.23415 -360.222502) (xy 202.1883 -360.251972)
			(xy 202.138722 -360.274617) (xy 202.086427 -360.289976) (xy 202.032477 -360.297736) (xy 201.977973 -360.29774)
			(xy 201.924023 -360.289987) (xy 201.871725 -360.274635) (xy 201.822145 -360.251996) (xy 201.776291 -360.222532)
			(xy 201.735097 -360.186843) (xy 201.699401 -360.145653) (xy 201.66993 -360.099804) (xy 201.647285 -360.050226)
			(xy 201.631925 -359.997931) (xy 201.624164 -359.943982) (xy 201.623676 -359.91673) (xy 201.623676 -359.916222)
			(xy 201.62406 -359.892342) (xy 201.630043 -359.844958) (xy 201.635614 -359.821734) (xy 201.638546 -359.8084)
			(xy 201.63813 -359.781117) (xy 201.630493 -359.754921) (xy 201.616183 -359.731689) (xy 201.596224 -359.713083)
			(xy 201.572046 -359.700436) (xy 201.545379 -359.694654) (xy 201.518134 -359.696151) (xy 201.505058 -359.700068)
			(xy 201.475626 -359.709313) (xy 201.414744 -359.719267) (xy 201.3839 -359.71988) (xy 201.383392 -359.71988)
			(xy 201.356142 -359.719414) (xy 201.302196 -359.711657) (xy 201.249904 -359.696301) (xy 201.200329 -359.67366)
			(xy 201.154481 -359.644195) (xy 201.113293 -359.608505) (xy 201.077603 -359.567316) (xy 201.048138 -359.521467)
			(xy 201.025497 -359.471892) (xy 201.010143 -359.4196) (xy 201.002386 -359.365654) (xy 201.002385 -359.311154)
			(xy 196.657468 -359.311154) (xy 196.657468 -359.714292) (xy 197.403972 -359.714292) (xy 197.408043 -359.65867)
			(xy 197.420169 -359.604233) (xy 197.440092 -359.552142) (xy 197.467388 -359.503507) (xy 197.501474 -359.459364)
			(xy 197.541623 -359.420655) (xy 197.586981 -359.388204) (xy 197.636581 -359.362703) (xy 197.689365 -359.344696)
			(xy 197.744208 -359.334566) (xy 197.799942 -359.332529) (xy 197.855379 -359.338629) (xy 197.909336 -359.352735)
			(xy 197.960665 -359.374547) (xy 198.008271 -359.403601) (xy 198.051139 -359.439276) (xy 198.088356 -359.480813)
			(xy 198.119129 -359.527326) (xy 198.142801 -359.577823) (xy 198.158869 -359.63123) (xy 198.166989 -359.686406)
			(xy 198.167498 -359.714292) (xy 198.166989 -359.742178) (xy 198.158869 -359.797354) (xy 198.142801 -359.850761)
			(xy 198.119129 -359.901258) (xy 198.088356 -359.947771) (xy 198.051139 -359.989308) (xy 198.008271 -360.024983)
			(xy 197.960665 -360.054037) (xy 197.909336 -360.075849) (xy 197.855379 -360.089955) (xy 197.799942 -360.096055)
			(xy 197.744208 -360.094018) (xy 197.689365 -360.083888) (xy 197.636581 -360.065881) (xy 197.586981 -360.04038)
			(xy 197.541623 -360.007929) (xy 197.501474 -359.96922) (xy 197.467388 -359.925077) (xy 197.440092 -359.876442)
			(xy 197.420169 -359.824351) (xy 197.408043 -359.769914) (xy 197.403972 -359.714292) (xy 196.657468 -359.714292)
			(xy 196.657468 -361.199176) (xy 199.934574 -361.199176) (xy 199.938645 -361.143554) (xy 199.950771 -361.089117)
			(xy 199.970694 -361.037026) (xy 199.99799 -360.988391) (xy 200.032076 -360.944248) (xy 200.072225 -360.905539)
			(xy 200.117583 -360.873088) (xy 200.167183 -360.847587) (xy 200.219967 -360.82958) (xy 200.27481 -360.81945)
			(xy 200.330544 -360.817413) (xy 200.385981 -360.823513) (xy 200.439938 -360.837619) (xy 200.491267 -360.859431)
			(xy 200.538873 -360.888485) (xy 200.581741 -360.92416) (xy 200.618958 -360.965697) (xy 200.649731 -361.01221)
			(xy 200.673403 -361.062707) (xy 200.689471 -361.116114) (xy 200.697591 -361.17129) (xy 200.6981 -361.199176)
			(xy 200.697591 -361.227062) (xy 200.689471 -361.282238) (xy 200.673403 -361.335645) (xy 200.649731 -361.386142)
			(xy 200.618958 -361.432655) (xy 200.581741 -361.474192) (xy 200.538873 -361.509867) (xy 200.491267 -361.538921)
			(xy 200.439938 -361.560733) (xy 200.385981 -361.574839) (xy 200.330544 -361.580939) (xy 200.27481 -361.578902)
			(xy 200.219967 -361.568772) (xy 200.167183 -361.550765) (xy 200.117583 -361.525264) (xy 200.072225 -361.492813)
			(xy 200.032076 -361.454104) (xy 199.99799 -361.409961) (xy 199.970694 -361.361326) (xy 199.950771 -361.309235)
			(xy 199.938645 -361.254798) (xy 199.934574 -361.199176) (xy 196.657468 -361.199176) (xy 196.657468 -361.889656)
			(xy 198.620025 -361.889656) (xy 198.620025 -361.835144) (xy 198.627783 -361.781186) (xy 198.643142 -361.728882)
			(xy 198.665788 -361.679296) (xy 198.695261 -361.633438) (xy 198.73096 -361.592242) (xy 198.772159 -361.556545)
			(xy 198.818019 -361.527076) (xy 198.867607 -361.504433) (xy 198.919912 -361.489078) (xy 198.97387 -361.481323)
			(xy 199.001126 -361.480862) (xy 199.028882 -361.481405) (xy 199.08381 -361.489427) (xy 199.136996 -361.505329)
			(xy 199.187314 -361.528772) (xy 199.233701 -361.559263) (xy 199.275179 -361.596156) (xy 199.310869 -361.638673)
			(xy 199.340019 -361.685915) (xy 199.362011 -361.736884) (xy 199.36968 -361.763564) (xy 199.37222 -361.773216)
			(xy 199.384412 -361.789218) (xy 199.465438 -361.835192) (xy 199.48525 -361.837732) (xy 199.494902 -361.834938)
			(xy 199.495156 -361.834938) (xy 199.520415 -361.828278) (xy 199.572162 -361.821141) (xy 199.59828 -361.820714)
			(xy 199.625535 -361.821132) (xy 199.679492 -361.828887) (xy 199.731795 -361.844242) (xy 199.781381 -361.866885)
			(xy 199.827239 -361.896354) (xy 199.868436 -361.932049) (xy 199.904134 -361.973245) (xy 199.933606 -362.019102)
			(xy 199.956251 -362.068686) (xy 199.971609 -362.120989) (xy 199.979367 -362.174945) (xy 199.979367 -362.229455)
			(xy 199.971609 -362.283411) (xy 199.956251 -362.335714) (xy 199.933606 -362.385298) (xy 199.904134 -362.431155)
			(xy 199.868436 -362.472351) (xy 199.827239 -362.508046) (xy 199.781381 -362.537515) (xy 199.731795 -362.560158)
			(xy 199.679492 -362.575513) (xy 199.625535 -362.583268) (xy 199.59828 -362.58373) (xy 199.570521 -362.583277)
			(xy 199.515589 -362.575241) (xy 199.462401 -362.559327) (xy 199.412082 -362.535871) (xy 199.365695 -362.505369)
			(xy 199.324219 -362.468465) (xy 199.28853 -362.425939) (xy 199.259383 -362.378688) (xy 199.237393 -362.327711)
			(xy 199.229726 -362.301028) (xy 199.227186 -362.291376) (xy 199.214994 -362.275374) (xy 199.133968 -362.2294)
			(xy 199.114156 -362.22686) (xy 199.104504 -362.229654) (xy 199.10425 -362.229654) (xy 199.078991 -362.236313)
			(xy 199.027244 -362.243451) (xy 199.001126 -362.243878) (xy 198.97387 -362.243477) (xy 198.919912 -362.235722)
			(xy 198.867607 -362.220367) (xy 198.818019 -362.197724) (xy 198.772159 -362.168255) (xy 198.73096 -362.132558)
			(xy 198.695261 -362.091362) (xy 198.665788 -362.045504) (xy 198.643142 -361.995918) (xy 198.627783 -361.943614)
			(xy 198.620025 -361.889656) (xy 196.657468 -361.889656) (xy 196.657468 -362.589572) (xy 200.18832 -362.589572)
			(xy 200.192391 -362.53395) (xy 200.204517 -362.479513) (xy 200.22444 -362.427422) (xy 200.251736 -362.378787)
			(xy 200.285822 -362.334644) (xy 200.325971 -362.295935) (xy 200.371329 -362.263484) (xy 200.420929 -362.237983)
			(xy 200.473713 -362.219976) (xy 200.528556 -362.209846) (xy 200.58429 -362.207809) (xy 200.639727 -362.213909)
			(xy 200.693684 -362.228015) (xy 200.745013 -362.249827) (xy 200.792619 -362.278881) (xy 200.835487 -362.314556)
			(xy 200.872704 -362.356093) (xy 200.903477 -362.402606) (xy 200.927149 -362.453103) (xy 200.943217 -362.50651)
			(xy 200.951337 -362.561686) (xy 200.951846 -362.589572) (xy 200.951337 -362.617458) (xy 200.943217 -362.672634)
			(xy 200.927149 -362.726041) (xy 200.903477 -362.776538) (xy 200.872704 -362.823051) (xy 200.835487 -362.864588)
			(xy 200.792619 -362.900263) (xy 200.745013 -362.929317) (xy 200.693684 -362.951129) (xy 200.639727 -362.965235)
			(xy 200.58429 -362.971335) (xy 200.528556 -362.969298) (xy 200.473713 -362.959168) (xy 200.420929 -362.941161)
			(xy 200.371329 -362.91566) (xy 200.325971 -362.883209) (xy 200.285822 -362.8445) (xy 200.251736 -362.800357)
			(xy 200.22444 -362.751722) (xy 200.204517 -362.699631) (xy 200.192391 -362.645194) (xy 200.18832 -362.589572)
			(xy 196.657468 -362.589572) (xy 196.657468 -363.00791) (xy 201.156568 -363.00791) (xy 201.160639 -362.952288)
			(xy 201.172765 -362.897851) (xy 201.192688 -362.84576) (xy 201.219984 -362.797125) (xy 201.25407 -362.752982)
			(xy 201.294219 -362.714273) (xy 201.339577 -362.681822) (xy 201.389177 -362.656321) (xy 201.441961 -362.638314)
			(xy 201.496804 -362.628184) (xy 201.552538 -362.626147) (xy 201.607975 -362.632247) (xy 201.661932 -362.646353)
			(xy 201.713261 -362.668165) (xy 201.760867 -362.697219) (xy 201.803735 -362.732894) (xy 201.840952 -362.774431)
			(xy 201.871725 -362.820944) (xy 201.895397 -362.871441) (xy 201.911465 -362.924848) (xy 201.919585 -362.980024)
			(xy 201.920094 -363.00791) (xy 201.919585 -363.035796) (xy 201.911465 -363.090972) (xy 201.895397 -363.144379)
			(xy 201.871725 -363.194876) (xy 201.840952 -363.241389) (xy 201.803735 -363.282926) (xy 201.760867 -363.318601)
			(xy 201.713261 -363.347655) (xy 201.661932 -363.369467) (xy 201.607975 -363.383573) (xy 201.552538 -363.389673)
			(xy 201.496804 -363.387636) (xy 201.441961 -363.377506) (xy 201.389177 -363.359499) (xy 201.339577 -363.333998)
			(xy 201.294219 -363.301547) (xy 201.25407 -363.262838) (xy 201.219984 -363.218695) (xy 201.192688 -363.17006)
			(xy 201.172765 -363.117969) (xy 201.160639 -363.063532) (xy 201.156568 -363.00791) (xy 196.657468 -363.00791)
			(xy 196.657468 -363.458506) (xy 196.657349 -363.463461) (xy 196.655431 -363.473182) (xy 196.653658 -363.47781)
			(xy 196.646546 -363.494574) (xy 196.644744 -363.49926) (xy 196.642819 -363.509112) (xy 196.642736 -363.514132)
			(xy 196.642736 -364.1852) (xy 199.46188 -364.1852) (xy 199.465951 -364.129578) (xy 199.478077 -364.075141)
			(xy 199.498 -364.02305) (xy 199.525296 -363.974415) (xy 199.559382 -363.930272) (xy 199.599531 -363.891563)
			(xy 199.644889 -363.859112) (xy 199.694489 -363.833611) (xy 199.747273 -363.815604) (xy 199.802116 -363.805474)
			(xy 199.85785 -363.803437) (xy 199.913287 -363.809537) (xy 199.967244 -363.823643) (xy 200.018573 -363.845455)
			(xy 200.066179 -363.874509) (xy 200.109047 -363.910184) (xy 200.146264 -363.951721) (xy 200.177037 -363.998234)
			(xy 200.200709 -364.048731) (xy 200.216777 -364.102138) (xy 200.224897 -364.157314) (xy 200.225406 -364.1852)
			(xy 200.224897 -364.213086) (xy 200.216777 -364.268262) (xy 200.200709 -364.321669) (xy 200.177037 -364.372166)
			(xy 200.146264 -364.418679) (xy 200.109047 -364.460216) (xy 200.066179 -364.495891) (xy 200.018573 -364.524945)
			(xy 199.967244 -364.546757) (xy 199.913287 -364.560863) (xy 199.85785 -364.566963) (xy 199.802116 -364.564926)
			(xy 199.747273 -364.554796) (xy 199.694489 -364.536789) (xy 199.644889 -364.511288) (xy 199.599531 -364.478837)
			(xy 199.559382 -364.440128) (xy 199.525296 -364.395985) (xy 199.498 -364.34735) (xy 199.478077 -364.295259)
			(xy 199.465951 -364.240822) (xy 199.46188 -364.1852) (xy 196.642736 -364.1852) (xy 196.642736 -366.33658)
			(xy 197.004938 -366.33658) (xy 197.009009 -366.280958) (xy 197.021135 -366.226521) (xy 197.041058 -366.17443)
			(xy 197.068354 -366.125795) (xy 197.10244 -366.081652) (xy 197.142589 -366.042943) (xy 197.187947 -366.010492)
			(xy 197.237547 -365.984991) (xy 197.290331 -365.966984) (xy 197.345174 -365.956854) (xy 197.400908 -365.954817)
			(xy 197.456345 -365.960917) (xy 197.510302 -365.975023) (xy 197.561631 -365.996835) (xy 197.609237 -366.025889)
			(xy 197.652105 -366.061564) (xy 197.689322 -366.103101) (xy 197.720095 -366.149614) (xy 197.743767 -366.200111)
			(xy 197.759835 -366.253518) (xy 197.767955 -366.308694) (xy 197.768464 -366.33658) (xy 197.767955 -366.364466)
			(xy 197.759835 -366.419642) (xy 197.743767 -366.473049) (xy 197.737955 -366.485447) (xy 199.693324 -366.485447)
			(xy 199.693324 -366.430953) (xy 199.701079 -366.377014) (xy 199.716431 -366.324728) (xy 199.739068 -366.275158)
			(xy 199.768528 -366.229314) (xy 199.804213 -366.18813) (xy 199.845395 -366.152443) (xy 199.891237 -366.122979)
			(xy 199.940805 -366.100339) (xy 199.993091 -366.084984) (xy 200.047029 -366.077226) (xy 200.074276 -366.076738)
			(xy 200.099405 -366.077117) (xy 200.149228 -366.083724) (xy 200.197752 -366.096816) (xy 200.244138 -366.116164)
			(xy 200.287582 -366.141433) (xy 200.307702 -366.156494) (xy 200.307956 -366.156748) (xy 200.315425 -366.161974)
			(xy 200.332852 -366.167276) (xy 200.351036 -366.166182) (xy 200.359518 -366.162844) (xy 200.441052 -366.126776)
			(xy 200.449254 -366.1228) (xy 200.462325 -366.110114) (xy 200.470129 -366.093655) (xy 200.471278 -366.084612)
			(xy 200.471278 -366.084358) (xy 200.474123 -366.05607) (xy 200.487093 -366.000718) (xy 200.508134 -365.947904)
			(xy 200.53678 -365.898798) (xy 200.572398 -365.854487) (xy 200.614197 -365.815953) (xy 200.661252 -365.784049)
			(xy 200.712521 -365.759482) (xy 200.766869 -365.742796) (xy 200.82309 -365.734361) (xy 200.851516 -365.733838)
			(xy 200.880176 -365.734359) (xy 200.93685 -365.742944) (xy 200.991605 -365.759903) (xy 201.04321 -365.784856)
			(xy 201.090505 -365.817241) (xy 201.132428 -365.856332) (xy 201.168038 -365.901249) (xy 201.182732 -365.925862)
			(xy 201.189082 -365.937292) (xy 201.211942 -365.951008) (xy 201.311764 -365.954056) (xy 201.320401 -365.954016)
			(xy 201.336867 -365.94884) (xy 201.350655 -365.938456) (xy 201.355706 -365.93145) (xy 201.355706 -365.930942)
			(xy 201.370938 -365.908696) (xy 201.406641 -365.868298) (xy 201.447672 -365.833325) (xy 201.493215 -365.804473)
			(xy 201.542365 -365.782315) (xy 201.594143 -365.767292) (xy 201.647519 -365.759704) (xy 201.674476 -365.759238)
			(xy 201.701733 -365.759607) (xy 201.755693 -365.767362) (xy 201.808 -365.782718) (xy 201.85759 -365.805362)
			(xy 201.903451 -365.834833) (xy 201.944652 -365.870531) (xy 201.980352 -365.911729) (xy 202.006902 -365.95304)
			(xy 202.97216 -365.95304) (xy 202.976231 -365.897418) (xy 202.988357 -365.842981) (xy 203.00828 -365.79089)
			(xy 203.035576 -365.742255) (xy 203.069662 -365.698112) (xy 203.109811 -365.659403) (xy 203.155169 -365.626952)
			(xy 203.204769 -365.601451) (xy 203.257553 -365.583444) (xy 203.312396 -365.573314) (xy 203.36813 -365.571277)
			(xy 203.423567 -365.577377) (xy 203.477524 -365.591483) (xy 203.528853 -365.613295) (xy 203.576459 -365.642349)
			(xy 203.619327 -365.678024) (xy 203.656544 -365.719561) (xy 203.687317 -365.766074) (xy 203.710989 -365.816571)
			(xy 203.727057 -365.869978) (xy 203.735177 -365.925154) (xy 203.735686 -365.95304) (xy 203.735177 -365.980926)
			(xy 203.727057 -366.036102) (xy 203.710989 -366.089509) (xy 203.687317 -366.140006) (xy 203.656544 -366.186519)
			(xy 203.619327 -366.228056) (xy 203.576459 -366.263731) (xy 203.528853 -366.292785) (xy 203.477524 -366.314597)
			(xy 203.423567 -366.328703) (xy 203.36813 -366.334803) (xy 203.312396 -366.332766) (xy 203.257553 -366.322636)
			(xy 203.204769 -366.304629) (xy 203.155169 -366.279128) (xy 203.109811 -366.246677) (xy 203.069662 -366.207968)
			(xy 203.035576 -366.163825) (xy 203.00828 -366.11519) (xy 202.988357 -366.063099) (xy 202.976231 -366.008662)
			(xy 202.97216 -365.95304) (xy 202.006902 -365.95304) (xy 202.009826 -365.957589) (xy 202.032473 -366.007177)
			(xy 202.047832 -366.059483) (xy 202.055591 -366.113443) (xy 202.055591 -366.167957) (xy 202.047832 -366.221917)
			(xy 202.032473 -366.274223) (xy 202.009826 -366.323811) (xy 201.980352 -366.369671) (xy 201.944652 -366.410869)
			(xy 201.903451 -366.446567) (xy 201.85759 -366.476038) (xy 201.808 -366.498682) (xy 201.755693 -366.514038)
			(xy 201.701733 -366.521793) (xy 201.674476 -366.522254) (xy 201.645815 -366.521743) (xy 201.58914 -366.513157)
			(xy 201.534386 -366.496196) (xy 201.482781 -366.471242) (xy 201.435486 -366.438855) (xy 201.393562 -366.399763)
			(xy 201.357953 -366.354843) (xy 201.34326 -366.33023) (xy 201.33691 -366.3188) (xy 201.31405 -366.305084)
			(xy 201.214228 -366.302036) (xy 201.205591 -366.302074) (xy 201.189125 -366.307252) (xy 201.175337 -366.317636)
			(xy 201.170286 -366.324642) (xy 201.170286 -366.32515) (xy 201.155056 -366.347398) (xy 201.119354 -366.387796)
			(xy 201.078322 -366.422769) (xy 201.032779 -366.451621) (xy 200.983629 -366.473779) (xy 200.93185 -366.488801)
			(xy 200.878473 -366.496389) (xy 200.851516 -366.496854) (xy 200.826386 -366.496481) (xy 200.776563 -366.489872)
			(xy 200.728039 -366.47678) (xy 200.681654 -366.457431) (xy 200.63821 -366.432159) (xy 200.61809 -366.417098)
			(xy 200.617836 -366.416844) (xy 200.610371 -366.411612) (xy 200.592941 -366.406313) (xy 200.574757 -366.407409)
			(xy 200.566274 -366.410748) (xy 200.48474 -366.446816) (xy 200.47654 -366.450794) (xy 200.463469 -366.46348)
			(xy 200.455664 -366.479938) (xy 200.454514 -366.48898) (xy 200.454514 -366.489234) (xy 200.45167 -366.517522)
			(xy 200.438701 -366.572875) (xy 200.41766 -366.625689) (xy 200.389014 -366.674796) (xy 200.353397 -366.719108)
			(xy 200.311597 -366.757642) (xy 200.264542 -366.789546) (xy 200.213272 -366.814112) (xy 200.158924 -366.830797)
			(xy 200.102702 -366.839232) (xy 200.074276 -366.839754) (xy 200.047029 -366.839174) (xy 199.993091 -366.831416)
			(xy 199.940805 -366.816061) (xy 199.891237 -366.793421) (xy 199.845395 -366.763957) (xy 199.804213 -366.72827)
			(xy 199.768528 -366.687086) (xy 199.739068 -366.641242) (xy 199.716431 -366.591672) (xy 199.701079 -366.539386)
			(xy 199.693324 -366.485447) (xy 197.737955 -366.485447) (xy 197.720095 -366.523546) (xy 197.689322 -366.570059)
			(xy 197.652105 -366.611596) (xy 197.609237 -366.647271) (xy 197.561631 -366.676325) (xy 197.510302 -366.698137)
			(xy 197.456345 -366.712243) (xy 197.400908 -366.718343) (xy 197.345174 -366.716306) (xy 197.290331 -366.706176)
			(xy 197.237547 -366.688169) (xy 197.187947 -366.662668) (xy 197.142589 -366.630217) (xy 197.10244 -366.591508)
			(xy 197.068354 -366.547365) (xy 197.041058 -366.49873) (xy 197.021135 -366.446639) (xy 197.009009 -366.392202)
			(xy 197.004938 -366.33658) (xy 196.642736 -366.33658) (xy 196.642736 -367.344198) (xy 197.042022 -367.344198)
			(xy 197.046093 -367.288576) (xy 197.058219 -367.234139) (xy 197.078142 -367.182048) (xy 197.105438 -367.133413)
			(xy 197.139524 -367.08927) (xy 197.179673 -367.050561) (xy 197.225031 -367.01811) (xy 197.274631 -366.992609)
			(xy 197.327415 -366.974602) (xy 197.382258 -366.964472) (xy 197.437992 -366.962435) (xy 197.493429 -366.968535)
			(xy 197.547386 -366.982641) (xy 197.598715 -367.004453) (xy 197.646321 -367.033507) (xy 197.689189 -367.069182)
			(xy 197.726406 -367.110719) (xy 197.757179 -367.157232) (xy 197.780851 -367.207729) (xy 197.796919 -367.261136)
			(xy 197.805039 -367.316312) (xy 197.805548 -367.344198) (xy 197.805039 -367.372084) (xy 197.796919 -367.42726)
			(xy 197.780851 -367.480667) (xy 197.757179 -367.531164) (xy 197.726406 -367.577677) (xy 197.689189 -367.619214)
			(xy 197.646321 -367.654889) (xy 197.598715 -367.683943) (xy 197.547386 -367.705755) (xy 197.493429 -367.719861)
			(xy 197.437992 -367.725961) (xy 197.382258 -367.723924) (xy 197.327415 -367.713794) (xy 197.274631 -367.695787)
			(xy 197.225031 -367.670286) (xy 197.179673 -367.637835) (xy 197.139524 -367.599126) (xy 197.105438 -367.554983)
			(xy 197.078142 -367.506348) (xy 197.058219 -367.454257) (xy 197.046093 -367.39982) (xy 197.042022 -367.344198)
			(xy 196.642736 -367.344198) (xy 196.642736 -367.76533) (xy 200.369676 -367.76533) (xy 200.373747 -367.709708)
			(xy 200.385873 -367.655271) (xy 200.405796 -367.60318) (xy 200.433092 -367.554545) (xy 200.467178 -367.510402)
			(xy 200.507327 -367.471693) (xy 200.552685 -367.439242) (xy 200.602285 -367.413741) (xy 200.655069 -367.395734)
			(xy 200.709912 -367.385604) (xy 200.765646 -367.383567) (xy 200.821083 -367.389667) (xy 200.87504 -367.403773)
			(xy 200.926369 -367.425585) (xy 200.973975 -367.454639) (xy 201.016843 -367.490314) (xy 201.05406 -367.531851)
			(xy 201.084833 -367.578364) (xy 201.108505 -367.628861) (xy 201.124573 -367.682268) (xy 201.132693 -367.737444)
			(xy 201.133202 -367.76533) (xy 201.132693 -367.793216) (xy 201.124573 -367.848392) (xy 201.108505 -367.901799)
			(xy 201.084833 -367.952296) (xy 201.05406 -367.998809) (xy 201.016843 -368.040346) (xy 200.973975 -368.076021)
			(xy 200.926369 -368.105075) (xy 200.87504 -368.126887) (xy 200.821083 -368.140993) (xy 200.765646 -368.147093)
			(xy 200.709912 -368.145056) (xy 200.655069 -368.134926) (xy 200.602285 -368.116919) (xy 200.552685 -368.091418)
			(xy 200.507327 -368.058967) (xy 200.467178 -368.020258) (xy 200.433092 -367.976115) (xy 200.405796 -367.92748)
			(xy 200.385873 -367.875389) (xy 200.373747 -367.820952) (xy 200.369676 -367.76533) (xy 196.642736 -367.76533)
			(xy 196.642736 -368.349022) (xy 197.160132 -368.349022) (xy 197.164203 -368.2934) (xy 197.176329 -368.238963)
			(xy 197.196252 -368.186872) (xy 197.223548 -368.138237) (xy 197.257634 -368.094094) (xy 197.297783 -368.055385)
			(xy 197.343141 -368.022934) (xy 197.392741 -367.997433) (xy 197.445525 -367.979426) (xy 197.500368 -367.969296)
			(xy 197.556102 -367.967259) (xy 197.611539 -367.973359) (xy 197.665496 -367.987465) (xy 197.716825 -368.009277)
			(xy 197.764431 -368.038331) (xy 197.807299 -368.074006) (xy 197.844516 -368.115543) (xy 197.875289 -368.162056)
			(xy 197.898961 -368.212553) (xy 197.915029 -368.26596) (xy 197.923149 -368.321136) (xy 197.923658 -368.349022)
			(xy 197.923149 -368.376908) (xy 197.915029 -368.432084) (xy 197.898961 -368.485491) (xy 197.875289 -368.535988)
			(xy 197.844516 -368.582501) (xy 197.807299 -368.624038) (xy 197.764431 -368.659713) (xy 197.716825 -368.688767)
			(xy 197.665496 -368.710579) (xy 197.611539 -368.724685) (xy 197.556102 -368.730785) (xy 197.500368 -368.728748)
			(xy 197.445525 -368.718618) (xy 197.392741 -368.700611) (xy 197.343141 -368.67511) (xy 197.297783 -368.642659)
			(xy 197.257634 -368.60395) (xy 197.223548 -368.559807) (xy 197.196252 -368.511172) (xy 197.176329 -368.459081)
			(xy 197.164203 -368.404644) (xy 197.160132 -368.349022) (xy 196.642736 -368.349022) (xy 196.642736 -369.011962)
			(xy 199.412096 -369.011962) (xy 199.416167 -368.95634) (xy 199.428293 -368.901903) (xy 199.448216 -368.849812)
			(xy 199.475512 -368.801177) (xy 199.509598 -368.757034) (xy 199.549747 -368.718325) (xy 199.595105 -368.685874)
			(xy 199.644705 -368.660373) (xy 199.697489 -368.642366) (xy 199.752332 -368.632236) (xy 199.808066 -368.630199)
			(xy 199.863503 -368.636299) (xy 199.91746 -368.650405) (xy 199.968789 -368.672217) (xy 200.016395 -368.701271)
			(xy 200.059263 -368.736946) (xy 200.09648 -368.778483) (xy 200.127253 -368.824996) (xy 200.150925 -368.875493)
			(xy 200.166993 -368.9289) (xy 200.175113 -368.984076) (xy 200.175622 -369.011962) (xy 200.175113 -369.039848)
			(xy 200.166993 -369.095024) (xy 200.150925 -369.148431) (xy 200.127253 -369.198928) (xy 200.09648 -369.245441)
			(xy 200.059263 -369.286978) (xy 200.016395 -369.322653) (xy 199.968789 -369.351707) (xy 199.91746 -369.373519)
			(xy 199.863503 -369.387625) (xy 199.808066 -369.393725) (xy 199.752332 -369.391688) (xy 199.697489 -369.381558)
			(xy 199.644705 -369.363551) (xy 199.595105 -369.33805) (xy 199.549747 -369.305599) (xy 199.509598 -369.26689)
			(xy 199.475512 -369.222747) (xy 199.448216 -369.174112) (xy 199.428293 -369.122021) (xy 199.416167 -369.067584)
			(xy 199.412096 -369.011962) (xy 196.642736 -369.011962) (xy 196.642736 -369.74653) (xy 200.529188 -369.74653)
			(xy 200.533259 -369.690908) (xy 200.545385 -369.636471) (xy 200.565308 -369.58438) (xy 200.592604 -369.535745)
			(xy 200.62669 -369.491602) (xy 200.666839 -369.452893) (xy 200.712197 -369.420442) (xy 200.761797 -369.394941)
			(xy 200.814581 -369.376934) (xy 200.869424 -369.366804) (xy 200.925158 -369.364767) (xy 200.980595 -369.370867)
			(xy 201.034552 -369.384973) (xy 201.085881 -369.406785) (xy 201.133487 -369.435839) (xy 201.176355 -369.471514)
			(xy 201.213572 -369.513051) (xy 201.244345 -369.559564) (xy 201.268017 -369.610061) (xy 201.284085 -369.663468)
			(xy 201.292205 -369.718644) (xy 201.292714 -369.74653) (xy 201.292205 -369.774416) (xy 201.284085 -369.829592)
			(xy 201.268017 -369.882999) (xy 201.244345 -369.933496) (xy 201.213572 -369.980009) (xy 201.176355 -370.021546)
			(xy 201.133487 -370.057221) (xy 201.085881 -370.086275) (xy 201.034552 -370.108087) (xy 200.980595 -370.122193)
			(xy 200.925158 -370.128293) (xy 200.869424 -370.126256) (xy 200.814581 -370.116126) (xy 200.761797 -370.098119)
			(xy 200.712197 -370.072618) (xy 200.666839 -370.040167) (xy 200.62669 -370.001458) (xy 200.592604 -369.957315)
			(xy 200.565308 -369.90868) (xy 200.545385 -369.856589) (xy 200.533259 -369.802152) (xy 200.529188 -369.74653)
			(xy 196.642736 -369.74653) (xy 196.642736 -370.450872) (xy 196.643498 -370.459254) (xy 196.645006 -370.466862)
			(xy 196.651984 -370.480705) (xy 196.657214 -370.486432) (xy 196.990716 -370.819934) (xy 197.038234 -370.867432)
			(xy 198.657462 -370.867432) (xy 198.661533 -370.81181) (xy 198.673659 -370.757373) (xy 198.693582 -370.705282)
			(xy 198.720878 -370.656647) (xy 198.754964 -370.612504) (xy 198.795113 -370.573795) (xy 198.840471 -370.541344)
			(xy 198.890071 -370.515843) (xy 198.942855 -370.497836) (xy 198.997698 -370.487706) (xy 199.053432 -370.485669)
			(xy 199.108869 -370.491769) (xy 199.162826 -370.505875) (xy 199.214155 -370.527687) (xy 199.261761 -370.556741)
			(xy 199.304629 -370.592416) (xy 199.341846 -370.633953) (xy 199.372619 -370.680466) (xy 199.396291 -370.730963)
			(xy 199.412359 -370.78437) (xy 199.420479 -370.839546) (xy 199.420988 -370.867432) (xy 199.420479 -370.895318)
			(xy 199.412359 -370.950494) (xy 199.404871 -370.975382) (xy 199.525634 -370.975382) (xy 199.529705 -370.91976)
			(xy 199.541831 -370.865323) (xy 199.561754 -370.813232) (xy 199.58905 -370.764597) (xy 199.623136 -370.720454)
			(xy 199.663285 -370.681745) (xy 199.708643 -370.649294) (xy 199.758243 -370.623793) (xy 199.811027 -370.605786)
			(xy 199.86587 -370.595656) (xy 199.921604 -370.593619) (xy 199.977041 -370.599719) (xy 200.030998 -370.613825)
			(xy 200.082327 -370.635637) (xy 200.129933 -370.664691) (xy 200.172801 -370.700366) (xy 200.210018 -370.741903)
			(xy 200.240791 -370.788416) (xy 200.264463 -370.838913) (xy 200.280531 -370.89232) (xy 200.288651 -370.947496)
			(xy 200.28916 -370.975382) (xy 200.288651 -371.003268) (xy 200.280531 -371.058444) (xy 200.264463 -371.111851)
			(xy 200.240791 -371.162348) (xy 200.210018 -371.208861) (xy 200.172801 -371.250398) (xy 200.129933 -371.286073)
			(xy 200.082327 -371.315127) (xy 200.030998 -371.336939) (xy 199.977041 -371.351045) (xy 199.921604 -371.357145)
			(xy 199.86587 -371.355108) (xy 199.811027 -371.344978) (xy 199.758243 -371.326971) (xy 199.708643 -371.30147)
			(xy 199.663285 -371.269019) (xy 199.623136 -371.23031) (xy 199.58905 -371.186167) (xy 199.561754 -371.137532)
			(xy 199.541831 -371.085441) (xy 199.529705 -371.031004) (xy 199.525634 -370.975382) (xy 199.404871 -370.975382)
			(xy 199.396291 -371.003901) (xy 199.372619 -371.054398) (xy 199.341846 -371.100911) (xy 199.304629 -371.142448)
			(xy 199.261761 -371.178123) (xy 199.214155 -371.207177) (xy 199.162826 -371.228989) (xy 199.108869 -371.243095)
			(xy 199.053432 -371.249195) (xy 198.997698 -371.247158) (xy 198.942855 -371.237028) (xy 198.890071 -371.219021)
			(xy 198.840471 -371.19352) (xy 198.795113 -371.161069) (xy 198.754964 -371.12236) (xy 198.720878 -371.078217)
			(xy 198.693582 -371.029582) (xy 198.673659 -370.977491) (xy 198.661533 -370.923054) (xy 198.657462 -370.867432)
			(xy 197.038234 -370.867432) (xy 197.579996 -371.40896) (xy 197.588632 -371.40896) (xy 197.658228 -371.487192)
			(xy 197.661022 -371.489478) (xy 197.667372 -371.493034) (xy 197.670166 -371.494558) (xy 197.675064 -371.496586)
			(xy 197.685439 -371.498757) (xy 197.69074 -371.498876) (xy 197.695058 -371.498876) (xy 197.914781 -371.718586)
			(xy 200.353166 -371.718586) (xy 200.357237 -371.662964) (xy 200.369363 -371.608527) (xy 200.389286 -371.556436)
			(xy 200.416582 -371.507801) (xy 200.450668 -371.463658) (xy 200.490817 -371.424949) (xy 200.536175 -371.392498)
			(xy 200.585775 -371.366997) (xy 200.638559 -371.34899) (xy 200.693402 -371.33886) (xy 200.749136 -371.336823)
			(xy 200.804573 -371.342923) (xy 200.85853 -371.357029) (xy 200.909859 -371.378841) (xy 200.957465 -371.407895)
			(xy 201.000333 -371.44357) (xy 201.03755 -371.485107) (xy 201.068323 -371.53162) (xy 201.091995 -371.582117)
			(xy 201.108063 -371.635524) (xy 201.116183 -371.6907) (xy 201.116692 -371.718586) (xy 201.116183 -371.746472)
			(xy 201.108063 -371.801648) (xy 201.091995 -371.855055) (xy 201.070358 -371.901212) (xy 201.295252 -371.901212)
			(xy 201.299323 -371.84559) (xy 201.311449 -371.791153) (xy 201.331372 -371.739062) (xy 201.358668 -371.690427)
			(xy 201.392754 -371.646284) (xy 201.432903 -371.607575) (xy 201.478261 -371.575124) (xy 201.527861 -371.549623)
			(xy 201.580645 -371.531616) (xy 201.635488 -371.521486) (xy 201.691222 -371.519449) (xy 201.746659 -371.525549)
			(xy 201.800616 -371.539655) (xy 201.851945 -371.561467) (xy 201.899551 -371.590521) (xy 201.942419 -371.626196)
			(xy 201.979636 -371.667733) (xy 202.010409 -371.714246) (xy 202.034081 -371.764743) (xy 202.050149 -371.81815)
			(xy 202.058269 -371.873326) (xy 202.058778 -371.901212) (xy 202.058269 -371.929098) (xy 202.050149 -371.984274)
			(xy 202.034081 -372.037681) (xy 202.010409 -372.088178) (xy 201.979636 -372.134691) (xy 201.942419 -372.176228)
			(xy 201.899551 -372.211903) (xy 201.851945 -372.240957) (xy 201.800616 -372.262769) (xy 201.746659 -372.276875)
			(xy 201.691222 -372.282975) (xy 201.635488 -372.280938) (xy 201.580645 -372.270808) (xy 201.527861 -372.252801)
			(xy 201.478261 -372.2273) (xy 201.432903 -372.194849) (xy 201.392754 -372.15614) (xy 201.358668 -372.111997)
			(xy 201.331372 -372.063362) (xy 201.311449 -372.011271) (xy 201.299323 -371.956834) (xy 201.295252 -371.901212)
			(xy 201.070358 -371.901212) (xy 201.068323 -371.905552) (xy 201.03755 -371.952065) (xy 201.000333 -371.993602)
			(xy 200.957465 -372.029277) (xy 200.909859 -372.058331) (xy 200.85853 -372.080143) (xy 200.804573 -372.094249)
			(xy 200.749136 -372.100349) (xy 200.693402 -372.098312) (xy 200.638559 -372.088182) (xy 200.585775 -372.070175)
			(xy 200.536175 -372.044674) (xy 200.490817 -372.012223) (xy 200.450668 -371.973514) (xy 200.416582 -371.929371)
			(xy 200.389286 -371.880736) (xy 200.369363 -371.828645) (xy 200.357237 -371.774208) (xy 200.353166 -371.718586)
			(xy 197.914781 -371.718586) (xy 199.113517 -372.917252) (xy 201.224589 -372.917252) (xy 201.224589 -372.862748)
			(xy 201.232347 -372.808798) (xy 201.247704 -372.756501) (xy 201.270347 -372.706923) (xy 201.299816 -372.661072)
			(xy 201.335511 -372.619882) (xy 201.376705 -372.584191) (xy 201.42256 -372.554727) (xy 201.472141 -372.532089)
			(xy 201.524439 -372.516738) (xy 201.57839 -372.508986) (xy 201.605642 -372.508526) (xy 201.633733 -372.509045)
			(xy 201.68931 -372.517265) (xy 201.743079 -372.53355) (xy 201.793878 -372.557549) (xy 201.840605 -372.58874)
			(xy 201.88225 -372.62645) (xy 201.917912 -372.669862) (xy 201.932794 -372.693692) (xy 201.94016 -372.705884)
			(xy 201.964798 -372.718838) (xy 202.082908 -372.712488) (xy 202.106276 -372.696486) (xy 202.112118 -372.683532)
			(xy 202.123893 -372.658969) (xy 202.153381 -372.61317) (xy 202.189081 -372.572029) (xy 202.230268 -372.536382)
			(xy 202.276106 -372.506954) (xy 202.325662 -372.484343) (xy 202.377929 -372.469007) (xy 202.431847 -372.46126)
			(xy 202.459082 -372.460774) (xy 202.486332 -372.461295) (xy 202.540277 -372.469049) (xy 202.59257 -372.4844)
			(xy 202.642146 -372.507038) (xy 202.687996 -372.536501) (xy 202.729186 -372.572189) (xy 202.764878 -372.613375)
			(xy 202.794345 -372.659222) (xy 202.816987 -372.708796) (xy 202.832344 -372.761087) (xy 202.840102 -372.815032)
			(xy 202.84059 -372.842282) (xy 202.840062 -372.870014) (xy 202.832039 -372.924894) (xy 202.816158 -372.978036)
			(xy 202.792755 -373.02832) (xy 202.762321 -373.074688) (xy 202.725498 -373.116164) (xy 202.68306 -373.151875)
			(xy 202.659742 -373.166894) (xy 202.64755 -373.17426) (xy 202.63485 -373.199406) (xy 202.642978 -373.317516)
			(xy 202.65898 -373.340376) (xy 202.672188 -373.346218) (xy 202.697276 -373.357729) (xy 202.744091 -373.38697)
			(xy 202.786202 -373.422656) (xy 202.822729 -373.464039) (xy 202.852908 -373.510256) (xy 202.87611 -373.56034)
			(xy 202.891849 -373.613247) (xy 202.899796 -373.667869) (xy 202.90028 -373.695468) (xy 202.899794 -373.722719)
			(xy 202.892038 -373.776667) (xy 202.876683 -373.828962) (xy 202.854041 -373.878539) (xy 202.824575 -373.924389)
			(xy 202.788884 -373.96558) (xy 202.747693 -374.001271) (xy 202.701843 -374.030737) (xy 202.652266 -374.053379)
			(xy 202.599971 -374.068734) (xy 202.546023 -374.07649) (xy 202.491521 -374.07649) (xy 202.437573 -374.068734)
			(xy 202.385278 -374.053379) (xy 202.335701 -374.030737) (xy 202.289851 -374.001271) (xy 202.24866 -373.96558)
			(xy 202.212969 -373.924389) (xy 202.183503 -373.878539) (xy 202.160861 -373.828962) (xy 202.145506 -373.776667)
			(xy 202.13775 -373.722719) (xy 202.137264 -373.695468) (xy 202.137727 -373.667734) (xy 202.145759 -373.612849)
			(xy 202.161649 -373.559705) (xy 202.185063 -373.50942) (xy 202.215507 -373.463052) (xy 202.252341 -373.421579)
			(xy 202.294789 -373.385872) (xy 202.318112 -373.370856) (xy 202.330304 -373.36349) (xy 202.343004 -373.338344)
			(xy 202.334876 -373.220234) (xy 202.318874 -373.197374) (xy 202.305666 -373.191532) (xy 202.278935 -373.17925)
			(xy 202.229327 -373.147637) (xy 202.185173 -373.108768) (xy 202.147524 -373.063569) (xy 202.13193 -373.038624)
			(xy 202.124564 -373.026432) (xy 202.099926 -373.013478) (xy 201.981816 -373.019828) (xy 201.958448 -373.03583)
			(xy 201.952606 -373.048784) (xy 201.94082 -373.073341) (xy 201.911332 -373.119139) (xy 201.875633 -373.160279)
			(xy 201.834448 -373.195926) (xy 201.788612 -373.225354) (xy 201.739058 -373.247967) (xy 201.686792 -373.263304)
			(xy 201.632877 -373.271055) (xy 201.605642 -373.271542) (xy 201.57839 -373.271014) (xy 201.524439 -373.263262)
			(xy 201.472141 -373.247911) (xy 201.42256 -373.225273) (xy 201.376705 -373.195809) (xy 201.335511 -373.160118)
			(xy 201.299816 -373.118928) (xy 201.270347 -373.073077) (xy 201.247704 -373.023499) (xy 201.232347 -372.971202)
			(xy 201.224589 -372.917252) (xy 199.113517 -372.917252) (xy 201.022399 -374.826022) (xy 202.643738 -374.826022)
			(xy 202.647809 -374.7704) (xy 202.659935 -374.715963) (xy 202.679858 -374.663872) (xy 202.707154 -374.615237)
			(xy 202.74124 -374.571094) (xy 202.781389 -374.532385) (xy 202.826747 -374.499934) (xy 202.876347 -374.474433)
			(xy 202.929131 -374.456426) (xy 202.983974 -374.446296) (xy 203.039708 -374.444259) (xy 203.095145 -374.450359)
			(xy 203.149102 -374.464465) (xy 203.200431 -374.486277) (xy 203.248037 -374.515331) (xy 203.290905 -374.551006)
			(xy 203.328122 -374.592543) (xy 203.358895 -374.639056) (xy 203.382567 -374.689553) (xy 203.398635 -374.74296)
			(xy 203.406755 -374.798136) (xy 203.407264 -374.826022) (xy 203.406755 -374.853908) (xy 203.398635 -374.909084)
			(xy 203.382567 -374.962491) (xy 203.358895 -375.012988) (xy 203.328122 -375.059501) (xy 203.290905 -375.101038)
			(xy 203.248037 -375.136713) (xy 203.200431 -375.165767) (xy 203.149102 -375.187579) (xy 203.095145 -375.201685)
			(xy 203.039708 -375.207785) (xy 202.983974 -375.205748) (xy 202.929131 -375.195618) (xy 202.876347 -375.177611)
			(xy 202.826747 -375.15211) (xy 202.781389 -375.119659) (xy 202.74124 -375.08095) (xy 202.707154 -375.036807)
			(xy 202.679858 -374.988172) (xy 202.659935 -374.936081) (xy 202.647809 -374.881644) (xy 202.643738 -374.826022)
			(xy 201.022399 -374.826022) (xy 202.019916 -375.82348) (xy 202.030584 -375.830338) (xy 202.034927 -375.832289)
			(xy 202.044132 -375.834712) (xy 202.048872 -375.835164)
		)
		(stroke
			(width 0)
			(type solid)
		)
		(fill yes)
		(layer "In13.Cu")
		(net "AGND_HSC")
	)
	(gr_poly
		(pts
			(xy 112.734598 -417.167314) (xy 112.744669 -417.166892) (xy 112.763275 -417.159179) (xy 112.770666 -417.152328)
			(xy 114.80038 -415.122614) (xy 114.807215 -415.115212) (xy 114.814921 -415.096613) (xy 114.815366 -415.086546)
			(xy 114.815366 -395.03604) (xy 114.815047 -395.027489) (xy 114.809434 -395.011334) (xy 114.798818 -394.997925)
			(xy 114.791744 -394.993114) (xy 114.787934 -394.990828) (xy 114.776504 -394.986002) (xy 114.766344 -394.981938)
			(xy 114.737896 -394.97) (xy 114.73688 -394.969492) (xy 114.387884 -394.82522) (xy 114.387376 -394.824458)
			(xy 114.386868 -394.824204) (xy 114.32921 -394.684758) (xy 114.324933 -394.675722) (xy 114.310818 -394.661593)
			(xy 114.301778 -394.657326) (xy 113.716562 -394.414756) (xy 113.716308 -394.414756) (xy 113.715292 -394.414248)
			(xy 113.59515 -394.363956) (xy 113.593118 -394.363194) (xy 113.588725 -394.361719) (xy 113.58054 -394.357376)
			(xy 113.576862 -394.354558) (xy 113.481104 -394.276326) (xy 113.480596 -394.276072) (xy 113.470182 -394.26769)
			(xy 113.460784 -394.26007) (xy 113.452722 -394.25423) (xy 113.433642 -394.24862) (xy 113.4237 -394.249148)
			(xy 113.274094 -394.264642) (xy 113.273332 -394.264134) (xy 113.27257 -394.264134) (xy 112.97793 -394.023596)
			(xy 112.977422 -394.023088) (xy 112.954562 -394.0048) (xy 112.954054 -394.004292) (xy 112.929924 -393.984734)
			(xy 112.92967 -393.984734) (xy 112.728756 -393.82065) (xy 112.613948 -393.726924) (xy 112.613694 -393.726924)
			(xy 112.607852 -393.722098) (xy 112.607598 -393.72159) (xy 112.296448 -393.467844) (xy 112.296448 -393.46759)
			(xy 112.092486 -393.30122) (xy 112.092232 -393.300966) (xy 112.082834 -393.293346) (xy 112.08258 -393.293092)
			(xy 112.056164 -393.271756) (xy 112.055656 -393.271756) (xy 111.82223 -393.081002) (xy 111.739934 -393.013946)
			(xy 111.7346 -393.009628) (xy 111.734346 -393.009374) (xy 111.422434 -392.754866) (xy 111.422434 -392.754612)
			(xy 111.210598 -392.581638) (xy 111.209328 -392.580876) (xy 111.208312 -392.580114) (xy 111.18215 -392.558778)
			(xy 111.181642 -392.558778) (xy 111.029496 -392.434318) (xy 110.89132 -392.32205) (xy 110.89132 -392.321542)
			(xy 110.865412 -392.30046) (xy 110.86465 -392.299952) (xy 110.651036 -392.125454) (xy 110.65002 -392.125454)
			(xy 110.334552 -391.867644) (xy 110.33379 -391.867136) (xy 110.005876 -391.599674) (xy 110.005368 -391.599166)
			(xy 109.978952 -391.57783) (xy 109.978444 -391.577322) (xy 109.689392 -391.341864) (xy 109.681891 -391.335121)
			(xy 109.672449 -391.317315) (xy 109.671104 -391.30732) (xy 109.65815 -391.17778) (xy 109.656731 -391.167816)
			(xy 109.647178 -391.150121) (xy 109.639608 -391.14349) (xy 109.153706 -390.747504) (xy 109.136942 -390.733534)
			(xy 109.136434 -390.733026) (xy 109.04601 -390.659366) (xy 109.043112 -390.65692) (xy 109.038015 -390.651304)
			(xy 109.03585 -390.64819) (xy 108.971842 -390.553194) (xy 108.971334 -390.552432) (xy 108.969302 -390.54913)
			(xy 108.968286 -390.54786) (xy 108.94949 -390.520174) (xy 108.949236 -390.519412) (xy 108.626148 -390.038844)
			(xy 107.294172 -388.05739) (xy 107.294172 -388.056374) (xy 107.285028 -388.043166) (xy 107.284012 -388.041388)
			(xy 107.25658 -387.999478) (xy 107.255818 -387.999732) (xy 107.216448 -387.941312) (xy 107.214439 -387.938162)
			(xy 107.211255 -387.931403) (xy 107.210098 -387.92785) (xy 107.17657 -387.817868) (xy 107.176316 -387.817106)
			(xy 107.174284 -387.809994) (xy 107.17403 -387.808978) (xy 107.169204 -387.7945) (xy 106.498136 -385.598924)
			(xy 106.493137 -385.584622) (xy 106.476109 -385.559582) (xy 106.452489 -385.540636) (xy 106.424351 -385.529448)
			(xy 106.394169 -385.527001) (xy 106.364596 -385.533512) (xy 106.338233 -385.548407) (xy 106.327448 -385.559046)
			(xy 106.322876 -385.56438) (xy 106.321606 -385.565904) (xy 106.320844 -385.566666) (xy 106.302259 -385.59033)
			(xy 106.259882 -385.633047) (xy 106.212268 -385.669837) (xy 106.16024 -385.700064) (xy 106.104697 -385.723205)
			(xy 106.046598 -385.738861) (xy 105.986948 -385.746762) (xy 105.956862 -385.74726) (xy 105.093262 -385.74726)
			(xy 105.063279 -385.746768) (xy 105.003828 -385.738936) (xy 104.945907 -385.723412) (xy 104.890508 -385.700461)
			(xy 104.838578 -385.670475) (xy 104.791006 -385.633969) (xy 104.748606 -385.591565) (xy 104.712104 -385.54399)
			(xy 104.682122 -385.492058) (xy 104.659176 -385.436657) (xy 104.643657 -385.378735) (xy 104.63583 -385.319283)
			(xy 104.63583 -385.259317) (xy 104.643657 -385.199865) (xy 104.659176 -385.141943) (xy 104.682122 -385.086542)
			(xy 104.712104 -385.03461) (xy 104.748606 -384.987035) (xy 104.791006 -384.944631) (xy 104.838578 -384.908125)
			(xy 104.890508 -384.878139) (xy 104.945907 -384.855188) (xy 105.003828 -384.839664) (xy 105.063279 -384.831832)
			(xy 105.093262 -384.831336) (xy 105.956862 -384.831336) (xy 105.991129 -384.831958) (xy 106.058892 -384.842206)
			(xy 106.124369 -384.862447) (xy 106.15549 -384.876802) (xy 106.156252 -384.877056) (xy 106.163618 -384.880358)
			(xy 106.176397 -384.884434) (xy 106.203136 -384.886458) (xy 106.229478 -384.881445) (xy 106.253604 -384.869742)
			(xy 106.273847 -384.852157) (xy 106.288809 -384.829904) (xy 106.297456 -384.804522) (xy 106.29919 -384.777763)
			(xy 106.296968 -384.764534) (xy 106.269028 -384.626358) (xy 106.261916 -384.61315) (xy 106.256582 -384.607816)
			(xy 106.253788 -384.605022) (xy 106.253788 -384.559048) (xy 106.252772 -384.548888) (xy 106.206544 -384.319018)
			(xy 106.206544 -384.316986) (xy 106.205274 -384.311652) (xy 106.20121 -384.291586) (xy 106.20121 -384.290824)
			(xy 106.187494 -384.224022) (xy 106.186478 -384.213354) (xy 106.186732 -384.186176) (xy 106.186224 -384.182366)
			(xy 105.818178 -381.45847) (xy 105.818178 -381.457962) (xy 105.81767 -381.454406) (xy 105.814368 -381.42799)
			(xy 105.814368 -381.426974) (xy 105.807764 -381.368554) (xy 105.805451 -381.353345) (xy 105.792964 -381.325244)
			(xy 105.772697 -381.302118) (xy 105.746477 -381.286052) (xy 105.71667 -381.278497) (xy 105.685963 -381.280132)
			(xy 105.671366 -381.284988) (xy 105.663746 -381.288036) (xy 105.662222 -381.288798) (xy 105.630855 -381.303418)
			(xy 105.564815 -381.324097) (xy 105.496416 -381.334611) (xy 105.461816 -381.33528) (xy 105.461562 -381.33528)
			(xy 105.431589 -381.334788) (xy 105.372157 -381.326962) (xy 105.314254 -381.311449) (xy 105.25887 -381.288514)
			(xy 105.206952 -381.258549) (xy 105.159387 -381.222066) (xy 105.116989 -381.179689) (xy 105.080482 -381.132143)
			(xy 105.05049 -381.08024) (xy 105.027526 -381.024867) (xy 105.011984 -380.966972) (xy 105.004127 -380.907544)
			(xy 105.0036 -380.877572) (xy 105.0036 -380.013972) (xy 105.004092 -379.984006) (xy 105.011918 -379.924586)
			(xy 105.027433 -379.866697) (xy 105.050371 -379.811327) (xy 105.08034 -379.759426) (xy 105.116826 -379.71188)
			(xy 105.159207 -379.669502) (xy 105.206756 -379.633019) (xy 105.25866 -379.603055) (xy 105.314031 -379.580121)
			(xy 105.371922 -379.564611) (xy 105.431342 -379.556789) (xy 105.461308 -379.556264) (xy 105.46207 -379.556264)
			(xy 105.483406 -379.556772) (xy 105.494328 -379.556772) (xy 105.50788 -379.555296) (xy 105.533526 -379.546088)
			(xy 105.555814 -379.53041) (xy 105.573146 -379.509383) (xy 105.584283 -379.484513) (xy 105.588426 -379.457581)
			(xy 105.587292 -379.443996) (xy 105.15473 -375.666762) (xy 105.128314 -375.641616) (xy 105.109772 -375.640346)
			(xy 105.078513 -375.637797) (xy 105.017068 -375.625225) (xy 104.957913 -375.604386) (xy 104.902155 -375.57567)
			(xy 104.850837 -375.539615) (xy 104.804918 -375.496895) (xy 104.765258 -375.448309) (xy 104.732598 -375.394766)
			(xy 104.707549 -375.337267) (xy 104.690581 -375.276888) (xy 104.68201 -375.214759) (xy 104.681528 -375.1834)
			(xy 104.681973 -375.154732) (xy 104.689132 -375.097843) (xy 104.703338 -375.042294) (xy 104.724368 -374.988953)
			(xy 104.751893 -374.938655) (xy 104.785484 -374.892188) (xy 104.824613 -374.850278) (xy 104.846374 -374.83161)
			(xy 104.846882 -374.831356) (xy 104.852724 -374.826276) (xy 104.859582 -374.818148) (xy 104.862376 -374.812306)
			(xy 104.87152 -374.79351) (xy 104.87386 -374.788287) (xy 104.876419 -374.777133) (xy 104.8766 -374.771412)
			(xy 104.8766 -372.026434) (xy 104.87616 -372.012423) (xy 104.868546 -371.985456) (xy 104.853882 -371.961578)
			(xy 104.833275 -371.94259) (xy 104.808279 -371.929924) (xy 104.780781 -371.924536) (xy 104.752854 -371.926833)
			(xy 104.726605 -371.936641) (xy 104.704014 -371.95322) (xy 104.69499 -371.96395) (xy 104.676773 -371.986394)
			(xy 104.634721 -372.026056) (xy 104.587177 -372.058932) (xy 104.535223 -372.084273) (xy 104.480045 -372.1015)
			(xy 104.422902 -372.11022) (xy 104.394 -372.110762) (xy 104.366731 -372.110276) (xy 104.312747 -372.102514)
			(xy 104.260417 -372.087149) (xy 104.210807 -372.064492) (xy 104.164926 -372.035006) (xy 104.123709 -371.999291)
			(xy 104.087994 -371.958074) (xy 104.058508 -371.912193) (xy 104.035851 -371.862583) (xy 104.020486 -371.810253)
			(xy 104.012724 -371.756269) (xy 104.012238 -371.729) (xy 104.01277 -371.700097) (xy 104.021482 -371.642952)
			(xy 104.038708 -371.587773) (xy 104.064055 -371.535821) (xy 104.096941 -371.488283) (xy 104.136618 -371.446244)
			(xy 104.15905 -371.42801) (xy 104.170859 -371.418115) (xy 104.188383 -371.392792) (xy 104.197562 -371.363397)
			(xy 104.197562 -371.332603) (xy 104.188383 -371.303208) (xy 104.170859 -371.277885) (xy 104.15905 -371.26799)
			(xy 104.138319 -371.251197) (xy 104.101265 -371.212814) (xy 104.069912 -371.169648) (xy 104.04487 -371.12254)
			(xy 104.026626 -371.072406) (xy 104.015537 -371.020221) (xy 104.011816 -370.967) (xy 104.015537 -370.913779)
			(xy 104.026626 -370.861594) (xy 104.04487 -370.81146) (xy 104.069912 -370.764352) (xy 104.101265 -370.721186)
			(xy 104.138319 -370.682803) (xy 104.15905 -370.66601) (xy 104.170859 -370.656115) (xy 104.188383 -370.630792)
			(xy 104.197562 -370.601397) (xy 104.197562 -370.570603) (xy 104.188383 -370.541208) (xy 104.170859 -370.515885)
			(xy 104.15905 -370.50599) (xy 104.138319 -370.489197) (xy 104.101265 -370.450814) (xy 104.069912 -370.407648)
			(xy 104.04487 -370.36054) (xy 104.026626 -370.310406) (xy 104.015537 -370.258221) (xy 104.011816 -370.205)
			(xy 104.015537 -370.151779) (xy 104.026626 -370.099594) (xy 104.04487 -370.04946) (xy 104.069912 -370.002352)
			(xy 104.101265 -369.959186) (xy 104.138319 -369.920803) (xy 104.15905 -369.90401) (xy 104.170859 -369.894115)
			(xy 104.188383 -369.868792) (xy 104.197562 -369.839397) (xy 104.197562 -369.808603) (xy 104.188383 -369.779208)
			(xy 104.170859 -369.753885) (xy 104.15905 -369.74399) (xy 104.136606 -369.725773) (xy 104.096944 -369.683721)
			(xy 104.064068 -369.636177) (xy 104.038727 -369.584223) (xy 104.0215 -369.529045) (xy 104.01278 -369.471902)
			(xy 104.012238 -369.443) (xy 104.012724 -369.415731) (xy 104.020486 -369.361747) (xy 104.035851 -369.309417)
			(xy 104.058508 -369.259807) (xy 104.087994 -369.213926) (xy 104.123709 -369.172709) (xy 104.164926 -369.136994)
			(xy 104.210807 -369.107508) (xy 104.260417 -369.084851) (xy 104.312747 -369.069486) (xy 104.366731 -369.061724)
			(xy 104.394 -369.061238) (xy 104.422903 -369.06177) (xy 104.480048 -369.070482) (xy 104.535227 -369.087708)
			(xy 104.587179 -369.113055) (xy 104.634717 -369.145941) (xy 104.676756 -369.185618) (xy 104.69499 -369.20805)
			(xy 104.703965 -369.218811) (xy 104.726566 -369.235358) (xy 104.752813 -369.24514) (xy 104.780731 -369.247419)
			(xy 104.808217 -369.242025) (xy 104.833203 -369.229362) (xy 104.853806 -369.210385) (xy 104.868475 -369.186522)
			(xy 104.876106 -369.159571) (xy 104.8766 -369.145566) (xy 104.8766 -368.851434) (xy 104.87616 -368.837423)
			(xy 104.868546 -368.810456) (xy 104.853882 -368.786578) (xy 104.833275 -368.76759) (xy 104.808279 -368.754924)
			(xy 104.780781 -368.749536) (xy 104.752854 -368.751833) (xy 104.726605 -368.761641) (xy 104.704014 -368.77822)
			(xy 104.69499 -368.78895) (xy 104.676773 -368.811394) (xy 104.634721 -368.851056) (xy 104.587177 -368.883932)
			(xy 104.535223 -368.909273) (xy 104.480045 -368.9265) (xy 104.422902 -368.93522) (xy 104.394 -368.935762)
			(xy 104.366715 -368.935298) (xy 104.312701 -368.92753) (xy 104.260342 -368.912152) (xy 104.210706 -368.889477)
			(xy 104.164803 -368.859968) (xy 104.123568 -368.824224) (xy 104.087841 -368.782975) (xy 104.05835 -368.737061)
			(xy 104.035695 -368.687416) (xy 104.020338 -368.635051) (xy 104.016048 -368.608102) (xy 104.013366 -368.593238)
			(xy 104.000539 -368.565911) (xy 103.980286 -368.543526) (xy 103.954373 -368.528039) (xy 103.925066 -368.520802)
			(xy 103.894923 -368.522447) (xy 103.866577 -368.532831) (xy 103.85425 -368.541554) (xy 103.829259 -368.55966)
			(xy 103.774657 -368.588409) (xy 103.71614 -368.608) (xy 103.655234 -368.617923) (xy 103.62438 -368.618516)
			(xy 103.597115 -368.618028) (xy 103.54314 -368.610265) (xy 103.490819 -368.5949) (xy 103.441217 -368.572245)
			(xy 103.395345 -368.542763) (xy 103.354134 -368.507052) (xy 103.318425 -368.465839) (xy 103.288945 -368.419965)
			(xy 103.266293 -368.370362) (xy 103.25093 -368.318041) (xy 103.24317 -368.264065) (xy 103.24317 -368.209535)
			(xy 103.25093 -368.155559) (xy 103.266293 -368.103238) (xy 103.288945 -368.053635) (xy 103.318425 -368.007761)
			(xy 103.354134 -367.966548) (xy 103.395345 -367.930837) (xy 103.441217 -367.901355) (xy 103.490819 -367.8787)
			(xy 103.54314 -367.863335) (xy 103.597115 -367.855572) (xy 103.62438 -367.854992) (xy 103.65166 -367.855462)
			(xy 103.705664 -367.86324) (xy 103.75801 -367.878626) (xy 103.807634 -367.901306) (xy 103.853523 -367.930819)
			(xy 103.894744 -367.966564) (xy 103.930458 -368.007813) (xy 103.959935 -368.053725) (xy 103.982578 -368.103366)
			(xy 103.997923 -368.155725) (xy 104.002332 -368.182652) (xy 104.00502 -368.197512) (xy 104.017854 -368.224829)
			(xy 104.038109 -368.247205) (xy 104.064017 -368.262687) (xy 104.093318 -368.269925) (xy 104.123456 -368.268286)
			(xy 104.1518 -368.257914) (xy 104.16413 -368.2492) (xy 104.189121 -368.231095) (xy 104.243724 -368.202346)
			(xy 104.30224 -368.182755) (xy 104.363146 -368.172829) (xy 104.394 -368.172238) (xy 104.422903 -368.17277)
			(xy 104.480048 -368.181482) (xy 104.535227 -368.198708) (xy 104.587179 -368.224055) (xy 104.634717 -368.256941)
			(xy 104.676756 -368.296618) (xy 104.69499 -368.31905) (xy 104.703965 -368.329811) (xy 104.726566 -368.346358)
			(xy 104.752813 -368.35614) (xy 104.780731 -368.358419) (xy 104.808217 -368.353025) (xy 104.833203 -368.340362)
			(xy 104.853806 -368.321385) (xy 104.868475 -368.297522) (xy 104.876106 -368.270571) (xy 104.8766 -368.256566)
			(xy 104.8766 -368.133122) (xy 104.86898 -368.114326) (xy 104.861614 -368.107214) (xy 104.22763 -367.47323)
			(xy 104.221898 -367.46695) (xy 104.214499 -367.451653) (xy 104.213152 -367.443258) (xy 103.417116 -360.490516)
			(xy 103.415128 -360.478807) (xy 103.402136 -360.458962) (xy 103.392224 -360.452416) (xy 103.311198 -360.405426)
			(xy 103.287322 -360.403902) (xy 103.276146 -360.408728) (xy 103.247543 -360.420455) (xy 103.18797 -360.436973)
			(xy 103.126716 -360.445315) (xy 103.095806 -360.445812) (xy 102.232206 -360.445812) (xy 102.202217 -360.445343)
			(xy 102.142751 -360.437515) (xy 102.084817 -360.421992) (xy 102.029404 -360.39904) (xy 101.977461 -360.369051)
			(xy 101.929876 -360.332539) (xy 101.887465 -360.290128) (xy 101.850952 -360.242544) (xy 101.820963 -360.190602)
			(xy 101.79801 -360.135189) (xy 101.782486 -360.077254) (xy 101.774657 -360.017789) (xy 101.774657 -359.957811)
			(xy 101.782486 -359.898346) (xy 101.79801 -359.840411) (xy 101.820963 -359.784998) (xy 101.850952 -359.733056)
			(xy 101.887465 -359.685472) (xy 101.929876 -359.643061) (xy 101.977461 -359.606549) (xy 102.029404 -359.57656)
			(xy 102.084817 -359.553608) (xy 102.142751 -359.538085) (xy 102.202217 -359.530257) (xy 102.232206 -359.529888)
			(xy 103.09606 -359.529888) (xy 103.11617 -359.53013) (xy 103.156232 -359.533694) (xy 103.17607 -359.537)
			(xy 103.176578 -359.537) (xy 103.188516 -359.539032) (xy 103.21163 -359.532174) (xy 103.220012 -359.524046)
			(xy 103.22052 -359.523538) (xy 103.279194 -359.46842) (xy 103.287447 -359.459797) (xy 103.295646 -359.437411)
			(xy 103.294942 -359.425494) (xy 102.995984 -356.813612) (xy 102.99192 -356.769162) (xy 102.763066 -353.457764)
			(xy 102.761034 -353.411282) (xy 102.76078 -353.395788) (xy 102.743254 -353.370388) (xy 102.70871 -353.356926)
			(xy 102.69855 -353.354132) (xy 102.691809 -353.353261) (xy 102.678294 -353.354675) (xy 102.67188 -353.356926)
			(xy 102.671372 -353.35718) (xy 102.662736 -353.360736) (xy 102.655116 -353.364546) (xy 102.643686 -353.371404)
			(xy 102.640638 -353.374198) (xy 102.619752 -353.391747) (xy 102.573904 -353.421309) (xy 102.524306 -353.444023)
			(xy 102.471973 -353.459425) (xy 102.417978 -353.467198) (xy 102.390702 -353.46767) (xy 102.390194 -353.46767)
			(xy 102.363964 -353.467234) (xy 102.312 -353.460045) (xy 102.261511 -353.445803) (xy 102.21345 -353.424777)
			(xy 102.168724 -353.397364) (xy 102.128175 -353.364081) (xy 102.09257 -353.325556) (xy 102.062579 -353.282515)
			(xy 102.038769 -353.235771) (xy 102.029768 -353.21113) (xy 102.024434 -353.195636) (xy 101.998018 -353.17684)
			(xy 100.914708 -353.17684) (xy 100.910233 -353.176911) (xy 100.901417 -353.178443) (xy 100.897182 -353.179888)
			(xy 100.891848 -353.18192) (xy 100.863146 -353.198684) (xy 100.854256 -353.20732) (xy 100.850954 -353.212908)
			(xy 100.835975 -353.236384) (xy 100.800287 -353.279131) (xy 100.758765 -353.316238) (xy 100.712291 -353.346915)
			(xy 100.661852 -353.370512) (xy 100.608518 -353.386527) (xy 100.553423 -353.394621) (xy 100.497737 -353.394621)
			(xy 100.442642 -353.386527) (xy 100.389308 -353.370512) (xy 100.338869 -353.346915) (xy 100.292395 -353.316238)
			(xy 100.250873 -353.279131) (xy 100.215185 -353.236384) (xy 100.200206 -353.212908) (xy 100.196904 -353.20732)
			(xy 100.188014 -353.198684) (xy 100.163376 -353.184206) (xy 100.154994 -353.180396) (xy 100.145596 -353.17684)
			(xy 100.097844 -353.17684) (xy 100.08754 -353.177315) (xy 100.068599 -353.185435) (xy 100.054402 -353.200374)
			(xy 100.050346 -353.20986) (xy 100.039932 -353.2378) (xy 100.039932 -353.238054) (xy 100.033328 -353.25558)
			(xy 100.033074 -353.255834) (xy 100.029264 -353.266248) (xy 100.020628 -353.28881) (xy 100.00144 -353.333152)
			(xy 99.99091 -353.354894) (xy 99.977717 -353.38129) (xy 99.948614 -353.432631) (xy 99.932744 -353.45751)
			(xy 99.251749 -354.50526) (xy 99.97643 -354.50526) (xy 99.980501 -354.449638) (xy 99.992627 -354.395201)
			(xy 100.01255 -354.34311) (xy 100.039846 -354.294475) (xy 100.073932 -354.250332) (xy 100.114081 -354.211623)
			(xy 100.159439 -354.179172) (xy 100.209039 -354.153671) (xy 100.261823 -354.135664) (xy 100.316666 -354.125534)
			(xy 100.3724 -354.123497) (xy 100.427837 -354.129597) (xy 100.481794 -354.143703) (xy 100.533123 -354.165515)
			(xy 100.580729 -354.194569) (xy 100.623597 -354.230244) (xy 100.660814 -354.271781) (xy 100.691587 -354.318294)
			(xy 100.715259 -354.368791) (xy 100.731327 -354.422198) (xy 100.739447 -354.477374) (xy 100.739956 -354.50526)
			(xy 100.739447 -354.533146) (xy 100.731327 -354.588322) (xy 100.715259 -354.641729) (xy 100.691587 -354.692226)
			(xy 100.660814 -354.738739) (xy 100.623597 -354.780276) (xy 100.580729 -354.815951) (xy 100.533123 -354.845005)
			(xy 100.481794 -354.866817) (xy 100.427837 -354.880923) (xy 100.3724 -354.887023) (xy 100.316666 -354.884986)
			(xy 100.261823 -354.874856) (xy 100.209039 -354.856849) (xy 100.159439 -354.831348) (xy 100.114081 -354.798897)
			(xy 100.073932 -354.760188) (xy 100.039846 -354.716045) (xy 100.01255 -354.66741) (xy 99.992627 -354.615319)
			(xy 99.980501 -354.560882) (xy 99.97643 -354.50526) (xy 99.251749 -354.50526) (xy 98.576698 -355.543866)
			(xy 100.796342 -355.543866) (xy 100.800413 -355.488244) (xy 100.812539 -355.433807) (xy 100.832462 -355.381716)
			(xy 100.859758 -355.333081) (xy 100.893844 -355.288938) (xy 100.933993 -355.250229) (xy 100.979351 -355.217778)
			(xy 101.028951 -355.192277) (xy 101.081735 -355.17427) (xy 101.136578 -355.16414) (xy 101.192312 -355.162103)
			(xy 101.247749 -355.168203) (xy 101.301706 -355.182309) (xy 101.353035 -355.204121) (xy 101.400641 -355.233175)
			(xy 101.443509 -355.26885) (xy 101.480726 -355.310387) (xy 101.511499 -355.3569) (xy 101.535171 -355.407397)
			(xy 101.551239 -355.460804) (xy 101.559359 -355.51598) (xy 101.559868 -355.543866) (xy 101.559359 -355.571752)
			(xy 101.551239 -355.626928) (xy 101.535171 -355.680335) (xy 101.511499 -355.730832) (xy 101.480726 -355.777345)
			(xy 101.443509 -355.818882) (xy 101.400641 -355.854557) (xy 101.353035 -355.883611) (xy 101.301706 -355.905423)
			(xy 101.247749 -355.919529) (xy 101.192312 -355.925629) (xy 101.136578 -355.923592) (xy 101.081735 -355.913462)
			(xy 101.028951 -355.895455) (xy 100.979351 -355.869954) (xy 100.933993 -355.837503) (xy 100.893844 -355.798794)
			(xy 100.859758 -355.754651) (xy 100.832462 -355.706016) (xy 100.812539 -355.653925) (xy 100.800413 -355.599488)
			(xy 100.796342 -355.543866) (xy 98.576698 -355.543866) (xy 94.644098 -361.5944) (xy 99.489292 -361.5944)
			(xy 99.493275 -361.541253) (xy 99.505134 -361.489292) (xy 99.524605 -361.43968) (xy 99.551252 -361.393523)
			(xy 99.58448 -361.351854) (xy 99.623548 -361.315602) (xy 99.667582 -361.285577) (xy 99.7156 -361.26245)
			(xy 99.766527 -361.246738) (xy 99.819228 -361.238791) (xy 99.845876 -361.238292) (xy 99.872284 -361.238789)
			(xy 99.924522 -361.246586) (xy 99.975035 -361.262015) (xy 100.022714 -361.284735) (xy 100.066515 -361.314249)
			(xy 100.105476 -361.349909) (xy 100.122482 -361.370118) (xy 100.130063 -361.378668) (xy 100.150689 -361.388452)
			(xy 100.162106 -361.388914) (xy 100.240846 -361.388914) (xy 100.252228 -361.388292) (xy 100.272798 -361.378547)
			(xy 100.28047 -361.370118) (xy 100.297489 -361.349919) (xy 100.336446 -361.314256) (xy 100.380244 -361.284738)
			(xy 100.427921 -361.262012) (xy 100.478432 -361.246578) (xy 100.530668 -361.238773) (xy 100.557076 -361.238292)
			(xy 100.583728 -361.238764) (xy 100.636438 -361.246705) (xy 100.687375 -361.262414) (xy 100.735402 -361.28554)
			(xy 100.779446 -361.315565) (xy 100.818522 -361.35182) (xy 100.851758 -361.393494) (xy 100.878411 -361.439657)
			(xy 100.897886 -361.489276) (xy 100.909748 -361.541244) (xy 100.913732 -361.5944) (xy 100.909748 -361.647556)
			(xy 100.897886 -361.699524) (xy 100.878411 -361.749143) (xy 100.851758 -361.795306) (xy 100.818522 -361.83698)
			(xy 100.779446 -361.873235) (xy 100.735402 -361.90326) (xy 100.687375 -361.926386) (xy 100.636438 -361.942095)
			(xy 100.583728 -361.950036) (xy 100.557076 -361.950508) (xy 100.530667 -361.950046) (xy 100.478427 -361.942241)
			(xy 100.427914 -361.926806) (xy 100.380234 -361.904079) (xy 100.336434 -361.874559) (xy 100.297475 -361.838894)
			(xy 100.28047 -361.818682) (xy 100.272909 -361.81011) (xy 100.252268 -361.800338) (xy 100.240846 -361.799886)
			(xy 100.162106 -361.799886) (xy 100.150721 -361.80048) (xy 100.130151 -361.810245) (xy 100.122482 -361.818682)
			(xy 100.105489 -361.838904) (xy 100.066527 -361.874566) (xy 100.022724 -361.904081) (xy 99.975041 -361.926803)
			(xy 99.924526 -361.942232) (xy 99.872286 -361.95003) (xy 99.845876 -361.950508) (xy 99.819228 -361.950009)
			(xy 99.766527 -361.942062) (xy 99.7156 -361.92635) (xy 99.667582 -361.903223) (xy 99.623548 -361.873198)
			(xy 99.58448 -361.836946) (xy 99.551252 -361.795277) (xy 99.524605 -361.74912) (xy 99.505134 -361.699508)
			(xy 99.493275 -361.647547) (xy 99.489292 -361.5944) (xy 94.644098 -361.5944) (xy 92.248482 -365.280194)
			(xy 92.248228 -365.280702) (xy 92.241624 -365.291116) (xy 92.241116 -365.291878) (xy 91.357704 -366.650778)
			(xy 90.687558 -367.680826) (xy 99.682623 -367.680826) (xy 99.682626 -367.626333) (xy 99.690383 -367.572394)
			(xy 99.705738 -367.520109) (xy 99.728377 -367.47054) (xy 99.75784 -367.424698) (xy 99.793527 -367.383516)
			(xy 99.834711 -367.347831) (xy 99.880554 -367.31837) (xy 99.930124 -367.295733) (xy 99.98241 -367.28038)
			(xy 100.036349 -367.272624) (xy 100.090842 -367.272624) (xy 100.144781 -367.280378) (xy 100.197068 -367.295729)
			(xy 100.246637 -367.318365) (xy 100.292481 -367.347825) (xy 100.333666 -367.383509) (xy 100.369354 -367.424691)
			(xy 100.398818 -367.470532) (xy 100.421459 -367.5201) (xy 100.436815 -367.572385) (xy 100.444574 -367.626323)
			(xy 100.445062 -367.65357) (xy 100.444303 -367.687997) (xy 100.431907 -367.755726) (xy 100.420424 -367.78819)
			(xy 100.415625 -367.80207) (xy 100.413449 -367.83135) (xy 100.419694 -367.860038) (xy 100.433846 -367.885763)
			(xy 100.454732 -367.906397) (xy 100.480627 -367.920234) (xy 100.509389 -367.926131) (xy 100.524056 -367.92535)
			(xy 100.555552 -367.92408) (xy 100.582809 -367.924504) (xy 100.63677 -367.932255) (xy 100.689078 -367.947608)
			(xy 100.738668 -367.970248) (xy 100.784532 -367.999716) (xy 100.825735 -368.035411) (xy 100.861438 -368.076607)
			(xy 100.890915 -368.122465) (xy 100.913566 -368.172051) (xy 100.928929 -368.224356) (xy 100.936691 -368.278315)
			(xy 100.936695 -368.332829) (xy 100.92894 -368.386789) (xy 100.913585 -368.439097) (xy 100.890942 -368.488686)
			(xy 100.861472 -368.534548) (xy 100.825775 -368.575749) (xy 100.784577 -368.61145) (xy 100.738718 -368.640925)
			(xy 100.68913 -368.663573) (xy 100.636825 -368.678933) (xy 100.582865 -368.686692) (xy 100.528351 -368.686694)
			(xy 100.474391 -368.678936) (xy 100.422085 -368.663578) (xy 100.372496 -368.640933) (xy 100.326636 -368.61146)
			(xy 100.285437 -368.57576) (xy 100.249738 -368.534561) (xy 100.220266 -368.4887) (xy 100.19762 -368.439112)
			(xy 100.182263 -368.386805) (xy 100.174506 -368.332845) (xy 100.174044 -368.305588) (xy 100.174792 -368.271161)
			(xy 100.187196 -368.203431) (xy 100.198682 -368.170968) (xy 100.203407 -368.157064) (xy 100.205595 -368.127796)
			(xy 100.199362 -368.099115) (xy 100.185224 -368.073394) (xy 100.164349 -368.052762) (xy 100.138465 -368.038925)
			(xy 100.109713 -368.033028) (xy 100.09505 -368.033808) (xy 100.063554 -368.035078) (xy 100.036307 -368.034573)
			(xy 99.982369 -368.026811) (xy 99.930085 -368.011453) (xy 99.880518 -367.98881) (xy 99.834678 -367.959345)
			(xy 99.793498 -367.923655) (xy 99.757815 -367.882469) (xy 99.728358 -367.836623) (xy 99.705724 -367.787053)
			(xy 99.690375 -367.734766) (xy 99.682623 -367.680826) (xy 90.687558 -367.680826) (xy 90.624152 -367.778284)
			(xy 90.623644 -367.7793) (xy 90.620088 -367.785142) (xy 90.616651 -367.791196) (xy 90.612906 -367.804599)
			(xy 90.612722 -367.811558) (xy 90.612722 -368.990118) (xy 91.223854 -368.990118) (xy 91.227845 -368.927951)
			(xy 91.239754 -368.866804) (xy 91.259383 -368.807683) (xy 91.286412 -368.751557) (xy 91.320396 -368.699348)
			(xy 91.360778 -368.651913) (xy 91.406894 -368.610032) (xy 91.457986 -368.574392) (xy 91.513217 -368.545578)
			(xy 91.571679 -368.524064) (xy 91.632413 -368.510202) (xy 91.69442 -368.50422) (xy 91.756683 -368.506216)
			(xy 91.81818 -368.516159) (xy 91.877901 -368.533883) (xy 91.934864 -368.5591) (xy 91.988135 -368.591393)
			(xy 92.03684 -368.630233) (xy 92.080177 -368.674983) (xy 92.117437 -368.724907) (xy 92.148006 -368.779186)
			(xy 92.171384 -368.836929) (xy 92.187185 -368.897187) (xy 92.19206 -368.935) (xy 102.360982 -368.935)
			(xy 102.365053 -368.879378) (xy 102.377179 -368.824941) (xy 102.397102 -368.77285) (xy 102.424398 -368.724215)
			(xy 102.458484 -368.680072) (xy 102.498633 -368.641363) (xy 102.543991 -368.608912) (xy 102.593591 -368.583411)
			(xy 102.646375 -368.565404) (xy 102.701218 -368.555274) (xy 102.756952 -368.553237) (xy 102.812389 -368.559337)
			(xy 102.866346 -368.573443) (xy 102.917675 -368.595255) (xy 102.965281 -368.624309) (xy 103.008149 -368.659984)
			(xy 103.045366 -368.701521) (xy 103.076139 -368.748034) (xy 103.099811 -368.798531) (xy 103.115879 -368.851938)
			(xy 103.123999 -368.907114) (xy 103.124508 -368.935) (xy 103.123999 -368.962886) (xy 103.115879 -369.018062)
			(xy 103.099811 -369.071469) (xy 103.076139 -369.121966) (xy 103.045366 -369.168479) (xy 103.008149 -369.210016)
			(xy 102.965281 -369.245691) (xy 102.917675 -369.274745) (xy 102.866346 -369.296557) (xy 102.812389 -369.310663)
			(xy 102.756952 -369.316763) (xy 102.701218 -369.314726) (xy 102.646375 -369.304596) (xy 102.593591 -369.286589)
			(xy 102.543991 -369.261088) (xy 102.498633 -369.228637) (xy 102.458484 -369.189928) (xy 102.424398 -369.145785)
			(xy 102.397102 -369.09715) (xy 102.377179 -369.045059) (xy 102.365053 -368.990622) (xy 102.360982 -368.935)
			(xy 92.19206 -368.935) (xy 92.195151 -368.95897) (xy 92.19565 -368.990118) (xy 92.195151 -369.021266)
			(xy 92.187185 -369.083049) (xy 92.171384 -369.143307) (xy 92.148006 -369.20105) (xy 92.117437 -369.255329)
			(xy 92.080177 -369.305253) (xy 92.03684 -369.350003) (xy 91.988135 -369.388843) (xy 91.934864 -369.421136)
			(xy 91.877901 -369.446353) (xy 91.81818 -369.464077) (xy 91.756683 -369.47402) (xy 91.69442 -369.476016)
			(xy 91.632413 -369.470034) (xy 91.571679 -369.456172) (xy 91.513217 -369.434658) (xy 91.457986 -369.405844)
			(xy 91.406894 -369.370204) (xy 91.360778 -369.328323) (xy 91.320396 -369.280888) (xy 91.286412 -369.228679)
			(xy 91.259383 -369.172553) (xy 91.239754 -369.113432) (xy 91.227845 -369.052285) (xy 91.223854 -368.990118)
			(xy 90.612722 -368.990118) (xy 90.612722 -371.590062) (xy 91.223854 -371.590062) (xy 91.227845 -371.527895)
			(xy 91.239754 -371.466748) (xy 91.259383 -371.407627) (xy 91.286412 -371.351501) (xy 91.320396 -371.299292)
			(xy 91.360778 -371.251857) (xy 91.406894 -371.209976) (xy 91.457986 -371.174336) (xy 91.513217 -371.145522)
			(xy 91.571679 -371.124008) (xy 91.632413 -371.110146) (xy 91.69442 -371.104164) (xy 91.756683 -371.10616)
			(xy 91.81818 -371.116103) (xy 91.877901 -371.133827) (xy 91.934864 -371.159044) (xy 91.988135 -371.191337)
			(xy 92.03684 -371.230177) (xy 92.080177 -371.274927) (xy 92.117437 -371.324851) (xy 92.148006 -371.37913)
			(xy 92.171384 -371.436873) (xy 92.187185 -371.497131) (xy 92.195151 -371.558914) (xy 92.19565 -371.590062)
			(xy 92.195151 -371.62121) (xy 92.187185 -371.682993) (xy 92.171384 -371.743251) (xy 92.148006 -371.800994)
			(xy 92.117437 -371.855273) (xy 92.080177 -371.905197) (xy 92.03684 -371.949947) (xy 91.988135 -371.988787)
			(xy 91.934864 -372.02108) (xy 91.877901 -372.046297) (xy 91.81818 -372.064021) (xy 91.756683 -372.073964)
			(xy 91.69442 -372.07596) (xy 91.632413 -372.069978) (xy 91.571679 -372.056116) (xy 91.513217 -372.034602)
			(xy 91.457986 -372.005788) (xy 91.406894 -371.970148) (xy 91.360778 -371.928267) (xy 91.320396 -371.880832)
			(xy 91.286412 -371.828623) (xy 91.259383 -371.772497) (xy 91.239754 -371.713376) (xy 91.227845 -371.652229)
			(xy 91.223854 -371.590062) (xy 90.612722 -371.590062) (xy 90.612722 -372.890034) (xy 91.223854 -372.890034)
			(xy 91.227845 -372.827867) (xy 91.239754 -372.76672) (xy 91.259383 -372.707599) (xy 91.286412 -372.651473)
			(xy 91.320396 -372.599264) (xy 91.360778 -372.551829) (xy 91.406894 -372.509948) (xy 91.457986 -372.474308)
			(xy 91.513217 -372.445494) (xy 91.571679 -372.42398) (xy 91.632413 -372.410118) (xy 91.69442 -372.404136)
			(xy 91.756683 -372.406132) (xy 91.81818 -372.416075) (xy 91.877901 -372.433799) (xy 91.934864 -372.459016)
			(xy 91.988135 -372.491309) (xy 92.03684 -372.530149) (xy 92.080177 -372.574899) (xy 92.117437 -372.624823)
			(xy 92.148006 -372.679102) (xy 92.171384 -372.736845) (xy 92.187185 -372.797103) (xy 92.195151 -372.858886)
			(xy 92.19565 -372.890034) (xy 92.195151 -372.921182) (xy 92.187185 -372.982965) (xy 92.171384 -373.043223)
			(xy 92.148006 -373.100966) (xy 92.117437 -373.155245) (xy 92.080177 -373.205169) (xy 92.03684 -373.249919)
			(xy 91.988135 -373.288759) (xy 91.934864 -373.321052) (xy 91.877901 -373.346269) (xy 91.81818 -373.363993)
			(xy 91.756683 -373.373936) (xy 91.69442 -373.375932) (xy 91.632413 -373.36995) (xy 91.571679 -373.356088)
			(xy 91.513217 -373.334574) (xy 91.457986 -373.30576) (xy 91.406894 -373.27012) (xy 91.360778 -373.228239)
			(xy 91.320396 -373.180804) (xy 91.286412 -373.128595) (xy 91.259383 -373.072469) (xy 91.239754 -373.013348)
			(xy 91.227845 -372.952201) (xy 91.223854 -372.890034) (xy 90.612722 -372.890034) (xy 90.612722 -375.490232)
			(xy 91.223854 -375.490232) (xy 91.227845 -375.428065) (xy 91.239754 -375.366918) (xy 91.259383 -375.307797)
			(xy 91.286412 -375.251671) (xy 91.320396 -375.199462) (xy 91.360778 -375.152027) (xy 91.406894 -375.110146)
			(xy 91.457986 -375.074506) (xy 91.513217 -375.045692) (xy 91.571679 -375.024178) (xy 91.632413 -375.010316)
			(xy 91.69442 -375.004334) (xy 91.756683 -375.00633) (xy 91.81818 -375.016273) (xy 91.877901 -375.033997)
			(xy 91.934864 -375.059214) (xy 91.988135 -375.091507) (xy 92.03684 -375.130347) (xy 92.080177 -375.175097)
			(xy 92.117437 -375.225021) (xy 92.148006 -375.2793) (xy 92.171384 -375.337043) (xy 92.187185 -375.397301)
			(xy 92.195151 -375.459084) (xy 92.19565 -375.490232) (xy 92.195151 -375.52138) (xy 92.187185 -375.583163)
			(xy 92.171384 -375.643421) (xy 92.148006 -375.701164) (xy 92.117437 -375.755443) (xy 92.080177 -375.805367)
			(xy 92.03684 -375.850117) (xy 91.988135 -375.888957) (xy 91.934864 -375.92125) (xy 91.877901 -375.946467)
			(xy 91.81818 -375.964191) (xy 91.756683 -375.974134) (xy 91.69442 -375.97613) (xy 91.632413 -375.970148)
			(xy 91.571679 -375.956286) (xy 91.513217 -375.934772) (xy 91.457986 -375.905958) (xy 91.406894 -375.870318)
			(xy 91.360778 -375.828437) (xy 91.320396 -375.781002) (xy 91.286412 -375.728793) (xy 91.259383 -375.672667)
			(xy 91.239754 -375.613546) (xy 91.227845 -375.552399) (xy 91.223854 -375.490232) (xy 90.612722 -375.490232)
			(xy 90.612722 -376.790204) (xy 91.223854 -376.790204) (xy 91.227845 -376.728037) (xy 91.239754 -376.66689)
			(xy 91.259383 -376.607769) (xy 91.286412 -376.551643) (xy 91.320396 -376.499434) (xy 91.360778 -376.451999)
			(xy 91.406894 -376.410118) (xy 91.457986 -376.374478) (xy 91.513217 -376.345664) (xy 91.571679 -376.32415)
			(xy 91.632413 -376.310288) (xy 91.69442 -376.304306) (xy 91.756683 -376.306302) (xy 91.81818 -376.316245)
			(xy 91.877901 -376.333969) (xy 91.934864 -376.359186) (xy 91.988135 -376.391479) (xy 92.03684 -376.430319)
			(xy 92.080177 -376.475069) (xy 92.087322 -376.484642) (xy 99.998528 -376.484642) (xy 100.002599 -376.42902)
			(xy 100.014725 -376.374583) (xy 100.034648 -376.322492) (xy 100.061944 -376.273857) (xy 100.09603 -376.229714)
			(xy 100.136179 -376.191005) (xy 100.181537 -376.158554) (xy 100.231137 -376.133053) (xy 100.283921 -376.115046)
			(xy 100.338764 -376.104916) (xy 100.394498 -376.102879) (xy 100.449935 -376.108979) (xy 100.503892 -376.123085)
			(xy 100.555221 -376.144897) (xy 100.602827 -376.173951) (xy 100.645695 -376.209626) (xy 100.682912 -376.251163)
			(xy 100.713685 -376.297676) (xy 100.737357 -376.348173) (xy 100.753425 -376.40158) (xy 100.761545 -376.456756)
			(xy 100.762054 -376.484642) (xy 100.761545 -376.512528) (xy 100.753425 -376.567704) (xy 100.737357 -376.621111)
			(xy 100.713685 -376.671608) (xy 100.682912 -376.718121) (xy 100.645695 -376.759658) (xy 100.602827 -376.795333)
			(xy 100.555221 -376.824387) (xy 100.503892 -376.846199) (xy 100.449935 -376.860305) (xy 100.394498 -376.866405)
			(xy 100.338764 -376.864368) (xy 100.283921 -376.854238) (xy 100.231137 -376.836231) (xy 100.181537 -376.81073)
			(xy 100.136179 -376.778279) (xy 100.09603 -376.73957) (xy 100.061944 -376.695427) (xy 100.034648 -376.646792)
			(xy 100.014725 -376.594701) (xy 100.002599 -376.540264) (xy 99.998528 -376.484642) (xy 92.087322 -376.484642)
			(xy 92.117437 -376.524993) (xy 92.148006 -376.579272) (xy 92.171384 -376.637015) (xy 92.187185 -376.697273)
			(xy 92.195151 -376.759056) (xy 92.19565 -376.790204) (xy 92.195151 -376.821352) (xy 92.187185 -376.883135)
			(xy 92.171384 -376.943393) (xy 92.148006 -377.001136) (xy 92.117437 -377.055415) (xy 92.080177 -377.105339)
			(xy 92.03684 -377.150089) (xy 91.988135 -377.188929) (xy 91.934864 -377.221222) (xy 91.877901 -377.246439)
			(xy 91.81818 -377.264163) (xy 91.756683 -377.274106) (xy 91.69442 -377.276102) (xy 91.632413 -377.27012)
			(xy 91.571679 -377.256258) (xy 91.513217 -377.234744) (xy 91.457986 -377.20593) (xy 91.406894 -377.17029)
			(xy 91.360778 -377.128409) (xy 91.320396 -377.080974) (xy 91.286412 -377.028765) (xy 91.259383 -376.972639)
			(xy 91.239754 -376.913518) (xy 91.227845 -376.852371) (xy 91.223854 -376.790204) (xy 90.612722 -376.790204)
			(xy 90.612722 -377.387612) (xy 100.044502 -377.387612) (xy 100.048573 -377.33199) (xy 100.060699 -377.277553)
			(xy 100.080622 -377.225462) (xy 100.107918 -377.176827) (xy 100.142004 -377.132684) (xy 100.182153 -377.093975)
			(xy 100.227511 -377.061524) (xy 100.277111 -377.036023) (xy 100.329895 -377.018016) (xy 100.384738 -377.007886)
			(xy 100.440472 -377.005849) (xy 100.495909 -377.011949) (xy 100.549866 -377.026055) (xy 100.601195 -377.047867)
			(xy 100.648801 -377.076921) (xy 100.691669 -377.112596) (xy 100.728886 -377.154133) (xy 100.759659 -377.200646)
			(xy 100.783331 -377.251143) (xy 100.799399 -377.30455) (xy 100.807519 -377.359726) (xy 100.808028 -377.387612)
			(xy 100.807519 -377.415498) (xy 100.799399 -377.470674) (xy 100.783331 -377.524081) (xy 100.759659 -377.574578)
			(xy 100.728886 -377.621091) (xy 100.691669 -377.662628) (xy 100.648801 -377.698303) (xy 100.601195 -377.727357)
			(xy 100.549866 -377.749169) (xy 100.495909 -377.763275) (xy 100.440472 -377.769375) (xy 100.384738 -377.767338)
			(xy 100.329895 -377.757208) (xy 100.277111 -377.739201) (xy 100.227511 -377.7137) (xy 100.182153 -377.681249)
			(xy 100.142004 -377.64254) (xy 100.107918 -377.598397) (xy 100.080622 -377.549762) (xy 100.060699 -377.497671)
			(xy 100.048573 -377.443234) (xy 100.044502 -377.387612) (xy 90.612722 -377.387612) (xy 90.612722 -379.390148)
			(xy 91.223854 -379.390148) (xy 91.227845 -379.327981) (xy 91.239754 -379.266834) (xy 91.259383 -379.207713)
			(xy 91.286412 -379.151587) (xy 91.320396 -379.099378) (xy 91.360778 -379.051943) (xy 91.406894 -379.010062)
			(xy 91.457986 -378.974422) (xy 91.513217 -378.945608) (xy 91.571679 -378.924094) (xy 91.632413 -378.910232)
			(xy 91.69442 -378.90425) (xy 91.756683 -378.906246) (xy 91.81818 -378.916189) (xy 91.877901 -378.933913)
			(xy 91.934864 -378.95913) (xy 91.988135 -378.991423) (xy 92.03684 -379.030263) (xy 92.080177 -379.075013)
			(xy 92.117437 -379.124937) (xy 92.148006 -379.179216) (xy 92.171384 -379.236959) (xy 92.187185 -379.297217)
			(xy 92.195151 -379.359) (xy 92.19565 -379.390148) (xy 92.195151 -379.421296) (xy 92.187185 -379.483079)
			(xy 92.171384 -379.543337) (xy 92.148006 -379.60108) (xy 92.117437 -379.655359) (xy 92.080177 -379.705283)
			(xy 92.03684 -379.750033) (xy 91.988135 -379.788873) (xy 91.934864 -379.821166) (xy 91.877901 -379.846383)
			(xy 91.81818 -379.864107) (xy 91.756683 -379.87405) (xy 91.69442 -379.876046) (xy 91.632413 -379.870064)
			(xy 91.571679 -379.856202) (xy 91.513217 -379.834688) (xy 91.457986 -379.805874) (xy 91.406894 -379.770234)
			(xy 91.360778 -379.728353) (xy 91.320396 -379.680918) (xy 91.286412 -379.628709) (xy 91.259383 -379.572583)
			(xy 91.239754 -379.513462) (xy 91.227845 -379.452315) (xy 91.223854 -379.390148) (xy 90.612722 -379.390148)
			(xy 90.612722 -380.69012) (xy 91.223854 -380.69012) (xy 91.227845 -380.627953) (xy 91.239754 -380.566806)
			(xy 91.259383 -380.507685) (xy 91.286412 -380.451559) (xy 91.320396 -380.39935) (xy 91.360778 -380.351915)
			(xy 91.406894 -380.310034) (xy 91.457986 -380.274394) (xy 91.513217 -380.24558) (xy 91.571679 -380.224066)
			(xy 91.632413 -380.210204) (xy 91.69442 -380.204222) (xy 91.756683 -380.206218) (xy 91.81818 -380.216161)
			(xy 91.877901 -380.233885) (xy 91.934864 -380.259102) (xy 91.988135 -380.291395) (xy 92.03684 -380.330235)
			(xy 92.080177 -380.374985) (xy 92.117437 -380.424909) (xy 92.148006 -380.479188) (xy 92.171384 -380.536931)
			(xy 92.187185 -380.597189) (xy 92.195151 -380.658972) (xy 92.19565 -380.69012) (xy 92.195151 -380.721268)
			(xy 92.187185 -380.783051) (xy 92.171384 -380.843309) (xy 92.148006 -380.901052) (xy 92.117437 -380.955331)
			(xy 92.080177 -381.005255) (xy 92.03684 -381.050005) (xy 91.988135 -381.088845) (xy 91.934864 -381.121138)
			(xy 91.877901 -381.146355) (xy 91.81818 -381.164079) (xy 91.756683 -381.174022) (xy 91.69442 -381.176018)
			(xy 91.632413 -381.170036) (xy 91.571679 -381.156174) (xy 91.513217 -381.13466) (xy 91.457986 -381.105846)
			(xy 91.406894 -381.070206) (xy 91.360778 -381.028325) (xy 91.320396 -380.98089) (xy 91.286412 -380.928681)
			(xy 91.259383 -380.872555) (xy 91.239754 -380.813434) (xy 91.227845 -380.752287) (xy 91.223854 -380.69012)
			(xy 90.612722 -380.69012) (xy 90.612722 -381.286851) (xy 100.042966 -381.286851) (xy 100.042966 -381.232349)
			(xy 100.050722 -381.178401) (xy 100.066077 -381.126106) (xy 100.088717 -381.076529) (xy 100.118182 -381.030678)
			(xy 100.153873 -380.989487) (xy 100.195062 -380.953794) (xy 100.240911 -380.924327) (xy 100.290488 -380.901684)
			(xy 100.342782 -380.886326) (xy 100.396729 -380.878567) (xy 100.42398 -380.87808) (xy 100.453271 -380.878598)
			(xy 100.511167 -380.887545) (xy 100.567016 -380.905232) (xy 100.619507 -380.931244) (xy 100.667407 -380.96497)
			(xy 100.709593 -381.005618) (xy 100.745074 -381.052234) (xy 100.759514 -381.077724) (xy 100.766512 -381.089738)
			(xy 100.78586 -381.109691) (xy 100.809873 -381.123686) (xy 100.83677 -381.130687) (xy 100.864559 -381.130175)
			(xy 100.89118 -381.122187) (xy 100.91466 -381.107316) (xy 100.93326 -381.086664) (xy 100.939854 -381.074422)
			(xy 100.952016 -381.050864) (xy 100.981867 -381.007049) (xy 101.017499 -380.967792) (xy 101.058226 -380.93385)
			(xy 101.103263 -380.905877) (xy 101.15174 -380.884412) (xy 101.202723 -380.86987) (xy 101.25523 -380.862531)
			(xy 101.281738 -380.862078) (xy 101.308986 -380.862595) (xy 101.362928 -380.870355) (xy 101.415216 -380.885713)
			(xy 101.464787 -380.908356) (xy 101.510631 -380.937822) (xy 101.551815 -380.973512) (xy 101.587501 -381.0147)
			(xy 101.616963 -381.060547) (xy 101.6396 -381.110119) (xy 101.654953 -381.162409) (xy 101.662708 -381.216352)
			(xy 101.662708 -381.270848) (xy 101.654953 -381.324791) (xy 101.6396 -381.377081) (xy 101.616963 -381.426653)
			(xy 101.587501 -381.4725) (xy 101.551815 -381.513688) (xy 101.510631 -381.549378) (xy 101.464787 -381.578844)
			(xy 101.415216 -381.601487) (xy 101.362928 -381.616845) (xy 101.308986 -381.624605) (xy 101.281738 -381.625094)
			(xy 101.252446 -381.624576) (xy 101.194551 -381.61563) (xy 101.138701 -381.597945) (xy 101.086209 -381.571933)
			(xy 101.038308 -381.538207) (xy 100.996123 -381.497558) (xy 100.960643 -381.450941) (xy 100.946204 -381.42545)
			(xy 100.939178 -381.413456) (xy 100.919833 -381.393509) (xy 100.895826 -381.379518) (xy 100.868935 -381.372518)
			(xy 100.841153 -381.373028) (xy 100.814538 -381.38101) (xy 100.79106 -381.395872) (xy 100.77246 -381.416515)
			(xy 100.765864 -381.428752) (xy 100.753677 -381.452297) (xy 100.723831 -381.496112) (xy 100.688202 -381.53537)
			(xy 100.647479 -381.569314) (xy 100.602446 -381.597289) (xy 100.553972 -381.618756) (xy 100.502991 -381.6333)
			(xy 100.450487 -381.640642) (xy 100.42398 -381.641096) (xy 100.396729 -381.640633) (xy 100.342782 -381.632874)
			(xy 100.290488 -381.617516) (xy 100.240911 -381.594873) (xy 100.195062 -381.565406) (xy 100.153873 -381.529713)
			(xy 100.118182 -381.488522) (xy 100.088717 -381.442671) (xy 100.066077 -381.393094) (xy 100.050722 -381.340799)
			(xy 100.042966 -381.286851) (xy 90.612722 -381.286851) (xy 90.612722 -383.322792) (xy 91.22486 -383.322792)
			(xy 91.224864 -383.257346) (xy 91.233662 -383.192494) (xy 91.251095 -383.129413) (xy 91.276847 -383.069246)
			(xy 91.293188 -383.04089) (xy 91.296505 -383.034867) (xy 91.30011 -383.021602) (xy 91.3003 -383.014728)
			(xy 91.3003 -382.728724) (xy 91.300741 -382.718571) (xy 91.308529 -382.699819) (xy 91.32292 -382.685495)
			(xy 91.341708 -382.677795) (xy 91.351862 -382.677416) (xy 92.068142 -382.677416) (xy 92.078268 -382.677891)
			(xy 92.096986 -382.685629) (xy 92.11134 -382.699918) (xy 92.119162 -382.7186) (xy 92.119704 -382.728724)
			(xy 92.119704 -383.014728) (xy 92.119885 -383.021602) (xy 92.1235 -383.034865) (xy 92.126816 -383.04089)
			(xy 92.143124 -383.069263) (xy 92.168873 -383.129425) (xy 92.186305 -383.192502) (xy 92.195102 -383.257349)
			(xy 92.195107 -383.32279) (xy 92.186317 -383.387638) (xy 92.168894 -383.450717) (xy 92.143152 -383.510882)
			(xy 92.126816 -383.539238) (xy 92.123489 -383.545257) (xy 92.119891 -383.558525) (xy 92.119704 -383.5654)
			(xy 92.119704 -384.3147) (xy 92.119895 -384.321573) (xy 92.123504 -384.334836) (xy 92.126816 -384.340862)
			(xy 92.143185 -384.369201) (xy 92.168929 -384.429371) (xy 92.186353 -384.492455) (xy 92.195143 -384.557308)
			(xy 92.195139 -384.622754) (xy 92.186341 -384.687606) (xy 92.168908 -384.750687) (xy 92.143157 -384.810854)
			(xy 92.126816 -384.83921) (xy 92.123499 -384.845233) (xy 92.119894 -384.858498) (xy 92.119704 -384.865372)
			(xy 92.119704 -385.151376) (xy 92.119259 -385.161528) (xy 92.111472 -385.180279) (xy 92.097082 -385.194603)
			(xy 92.078296 -385.202305) (xy 92.068142 -385.202684) (xy 91.351862 -385.202684) (xy 91.341736 -385.202205)
			(xy 91.323018 -385.194469) (xy 91.308664 -385.180181) (xy 91.300842 -385.1615) (xy 91.3003 -385.151376)
			(xy 91.3003 -384.865372) (xy 91.300119 -384.858498) (xy 91.296503 -384.845235) (xy 91.293188 -384.83921)
			(xy 91.27688 -384.810838) (xy 91.25113 -384.750675) (xy 91.233699 -384.687598) (xy 91.224901 -384.622751)
			(xy 91.224897 -384.55731) (xy 91.233686 -384.492462) (xy 91.25111 -384.429383) (xy 91.276852 -384.369218)
			(xy 91.293188 -384.340862) (xy 91.296515 -384.334844) (xy 91.300113 -384.321575) (xy 91.3003 -384.3147)
			(xy 91.3003 -383.5654) (xy 91.300108 -383.558527) (xy 91.2965 -383.545264) (xy 91.293188 -383.539238)
			(xy 91.276819 -383.510899) (xy 91.251075 -383.450729) (xy 91.23365 -383.387645) (xy 91.22486 -383.322792)
			(xy 90.612722 -383.322792) (xy 90.612722 -385.583938) (xy 100.447856 -385.583938) (xy 100.447856 -384.720338)
			(xy 100.448346 -384.690354) (xy 100.456174 -384.630898) (xy 100.471695 -384.572973) (xy 100.494644 -384.517569)
			(xy 100.524628 -384.465635) (xy 100.561134 -384.418059) (xy 100.603539 -384.375654) (xy 100.651115 -384.339148)
			(xy 100.703049 -384.309164) (xy 100.758453 -384.286215) (xy 100.816378 -384.270694) (xy 100.875834 -384.262866)
			(xy 100.935802 -384.262866) (xy 100.995258 -384.270694) (xy 101.053183 -384.286215) (xy 101.108587 -384.309164)
			(xy 101.160521 -384.339148) (xy 101.208097 -384.375654) (xy 101.250502 -384.418059) (xy 101.287008 -384.465635)
			(xy 101.316992 -384.517569) (xy 101.339941 -384.572973) (xy 101.355462 -384.630898) (xy 101.36329 -384.690354)
			(xy 101.36378 -384.720338) (xy 101.36378 -385.583938) (xy 101.36329 -385.613922) (xy 101.355462 -385.673378)
			(xy 101.339941 -385.731303) (xy 101.316992 -385.786707) (xy 101.287008 -385.838641) (xy 101.250502 -385.886217)
			(xy 101.208097 -385.928622) (xy 101.160521 -385.965128) (xy 101.108587 -385.995112) (xy 101.053183 -386.018061)
			(xy 100.995258 -386.033582) (xy 100.935802 -386.04141) (xy 100.875834 -386.04141) (xy 100.816378 -386.033582)
			(xy 100.758453 -386.018061) (xy 100.703049 -385.995112) (xy 100.651115 -385.965128) (xy 100.603539 -385.928622)
			(xy 100.561134 -385.886217) (xy 100.524628 -385.838641) (xy 100.494644 -385.786707) (xy 100.471695 -385.731303)
			(xy 100.456174 -385.673378) (xy 100.448346 -385.613922) (xy 100.447856 -385.583938) (xy 90.612722 -385.583938)
			(xy 90.612722 -388.911846) (xy 103.494838 -388.911846) (xy 103.498909 -388.856224) (xy 103.511035 -388.801787)
			(xy 103.530958 -388.749696) (xy 103.558254 -388.701061) (xy 103.59234 -388.656918) (xy 103.632489 -388.618209)
			(xy 103.677847 -388.585758) (xy 103.727447 -388.560257) (xy 103.780231 -388.54225) (xy 103.835074 -388.53212)
			(xy 103.890808 -388.530083) (xy 103.946245 -388.536183) (xy 104.000202 -388.550289) (xy 104.051531 -388.572101)
			(xy 104.099137 -388.601155) (xy 104.142005 -388.63683) (xy 104.179222 -388.678367) (xy 104.209995 -388.72488)
			(xy 104.233667 -388.775377) (xy 104.249735 -388.828784) (xy 104.257855 -388.88396) (xy 104.258364 -388.911846)
			(xy 104.257855 -388.939732) (xy 104.249735 -388.994908) (xy 104.233667 -389.048315) (xy 104.209995 -389.098812)
			(xy 104.179222 -389.145325) (xy 104.142005 -389.186862) (xy 104.099137 -389.222537) (xy 104.051531 -389.251591)
			(xy 104.000202 -389.273403) (xy 103.946245 -389.287509) (xy 103.890808 -389.293609) (xy 103.835074 -389.291572)
			(xy 103.780231 -389.281442) (xy 103.727447 -389.263435) (xy 103.677847 -389.237934) (xy 103.632489 -389.205483)
			(xy 103.59234 -389.166774) (xy 103.558254 -389.122631) (xy 103.530958 -389.073996) (xy 103.511035 -389.021905)
			(xy 103.498909 -388.967468) (xy 103.494838 -388.911846) (xy 90.612722 -388.911846) (xy 90.612722 -390.3726)
			(xy 98.601782 -390.3726) (xy 98.605853 -390.316978) (xy 98.617979 -390.262541) (xy 98.637902 -390.21045)
			(xy 98.665198 -390.161815) (xy 98.699284 -390.117672) (xy 98.739433 -390.078963) (xy 98.784791 -390.046512)
			(xy 98.834391 -390.021011) (xy 98.887175 -390.003004) (xy 98.942018 -389.992874) (xy 98.997752 -389.990837)
			(xy 99.053189 -389.996937) (xy 99.107146 -390.011043) (xy 99.158475 -390.032855) (xy 99.206081 -390.061909)
			(xy 99.248949 -390.097584) (xy 99.286166 -390.139121) (xy 99.316939 -390.185634) (xy 99.340611 -390.236131)
			(xy 99.356679 -390.289538) (xy 99.364799 -390.344714) (xy 99.365308 -390.3726) (xy 99.364799 -390.400486)
			(xy 99.356679 -390.455662) (xy 99.340611 -390.509069) (xy 99.316939 -390.559566) (xy 99.291747 -390.597644)
			(xy 99.793806 -390.597644) (xy 99.794296 -390.570275) (xy 99.802108 -390.516097) (xy 99.817591 -390.463594)
			(xy 99.840428 -390.413846) (xy 99.870147 -390.367878) (xy 99.887786 -390.346946) (xy 99.893882 -390.339834)
			(xy 99.900232 -390.322816) (xy 99.900232 -390.237472) (xy 99.893882 -390.220454) (xy 99.887786 -390.213342)
			(xy 99.870151 -390.192407) (xy 99.840439 -390.146435) (xy 99.817602 -390.096688) (xy 99.80211 -390.044188)
			(xy 99.794281 -389.990013) (xy 99.793806 -389.962644) (xy 99.794292 -389.935393) (xy 99.802048 -389.881445)
			(xy 99.817403 -389.82915) (xy 99.840045 -389.779573) (xy 99.869511 -389.733723) (xy 99.905202 -389.692532)
			(xy 99.946393 -389.656841) (xy 99.992243 -389.627375) (xy 100.04182 -389.604733) (xy 100.094115 -389.589378)
			(xy 100.148063 -389.581622) (xy 100.202565 -389.581622) (xy 100.256513 -389.589378) (xy 100.308808 -389.604733)
			(xy 100.358385 -389.627375) (xy 100.404235 -389.656841) (xy 100.445426 -389.692532) (xy 100.475893 -389.727694)
			(xy 106.942888 -389.727694) (xy 106.946959 -389.672072) (xy 106.959085 -389.617635) (xy 106.979008 -389.565544)
			(xy 107.006304 -389.516909) (xy 107.04039 -389.472766) (xy 107.080539 -389.434057) (xy 107.125897 -389.401606)
			(xy 107.175497 -389.376105) (xy 107.228281 -389.358098) (xy 107.283124 -389.347968) (xy 107.338858 -389.345931)
			(xy 107.394295 -389.352031) (xy 107.448252 -389.366137) (xy 107.499581 -389.387949) (xy 107.547187 -389.417003)
			(xy 107.590055 -389.452678) (xy 107.627272 -389.494215) (xy 107.658045 -389.540728) (xy 107.681717 -389.591225)
			(xy 107.697785 -389.644632) (xy 107.705905 -389.699808) (xy 107.706414 -389.727694) (xy 107.705905 -389.75558)
			(xy 107.697785 -389.810756) (xy 107.681717 -389.864163) (xy 107.658045 -389.91466) (xy 107.627272 -389.961173)
			(xy 107.590055 -390.00271) (xy 107.547187 -390.038385) (xy 107.499581 -390.067439) (xy 107.448252 -390.089251)
			(xy 107.394295 -390.103357) (xy 107.338858 -390.109457) (xy 107.283124 -390.10742) (xy 107.228281 -390.09729)
			(xy 107.175497 -390.079283) (xy 107.125897 -390.053782) (xy 107.080539 -390.021331) (xy 107.04039 -389.982622)
			(xy 107.006304 -389.938479) (xy 106.979008 -389.889844) (xy 106.959085 -389.837753) (xy 106.946959 -389.783316)
			(xy 106.942888 -389.727694) (xy 100.475893 -389.727694) (xy 100.481117 -389.733723) (xy 100.510583 -389.779573)
			(xy 100.533225 -389.82915) (xy 100.54858 -389.881445) (xy 100.556336 -389.935393) (xy 100.556822 -389.962644)
			(xy 100.556342 -389.990014) (xy 100.548531 -390.044193) (xy 100.533046 -390.096697) (xy 100.510207 -390.146444)
			(xy 100.480483 -390.192411) (xy 100.462842 -390.213342) (xy 100.456746 -390.220454) (xy 100.450396 -390.237472)
			(xy 100.450396 -390.322816) (xy 100.456746 -390.339834) (xy 100.462842 -390.346946) (xy 100.480476 -390.367882)
			(xy 100.510187 -390.413854) (xy 100.533024 -390.463601) (xy 100.548516 -390.5161) (xy 100.556347 -390.570275)
			(xy 100.556822 -390.597644) (xy 100.556336 -390.624895) (xy 100.54858 -390.678843) (xy 100.533225 -390.731138)
			(xy 100.510583 -390.780715) (xy 100.481117 -390.826565) (xy 100.445426 -390.867756) (xy 100.404235 -390.903447)
			(xy 100.358385 -390.932913) (xy 100.308808 -390.955555) (xy 100.256513 -390.97091) (xy 100.202565 -390.978666)
			(xy 100.148063 -390.978666) (xy 100.094115 -390.97091) (xy 100.04182 -390.955555) (xy 99.992243 -390.932913)
			(xy 99.946393 -390.903447) (xy 99.905202 -390.867756) (xy 99.869511 -390.826565) (xy 99.840045 -390.780715)
			(xy 99.817403 -390.731138) (xy 99.802048 -390.678843) (xy 99.794292 -390.624895) (xy 99.793806 -390.597644)
			(xy 99.291747 -390.597644) (xy 99.286166 -390.606079) (xy 99.248949 -390.647616) (xy 99.206081 -390.683291)
			(xy 99.158475 -390.712345) (xy 99.107146 -390.734157) (xy 99.053189 -390.748263) (xy 98.997752 -390.754363)
			(xy 98.942018 -390.752326) (xy 98.887175 -390.742196) (xy 98.834391 -390.724189) (xy 98.784791 -390.698688)
			(xy 98.739433 -390.666237) (xy 98.699284 -390.627528) (xy 98.665198 -390.583385) (xy 98.637902 -390.53475)
			(xy 98.617979 -390.482659) (xy 98.605853 -390.428222) (xy 98.601782 -390.3726) (xy 90.612722 -390.3726)
			(xy 90.612722 -391.294366) (xy 99.119942 -391.294366) (xy 99.124013 -391.238744) (xy 99.136139 -391.184307)
			(xy 99.156062 -391.132216) (xy 99.183358 -391.083581) (xy 99.217444 -391.039438) (xy 99.257593 -391.000729)
			(xy 99.302951 -390.968278) (xy 99.352551 -390.942777) (xy 99.405335 -390.92477) (xy 99.460178 -390.91464)
			(xy 99.515912 -390.912603) (xy 99.571349 -390.918703) (xy 99.625306 -390.932809) (xy 99.676635 -390.954621)
			(xy 99.724241 -390.983675) (xy 99.767109 -391.01935) (xy 99.804326 -391.060887) (xy 99.835099 -391.1074)
			(xy 99.857137 -391.154412) (xy 106.201208 -391.154412) (xy 106.205279 -391.09879) (xy 106.217405 -391.044353)
			(xy 106.237328 -390.992262) (xy 106.264624 -390.943627) (xy 106.29871 -390.899484) (xy 106.338859 -390.860775)
			(xy 106.384217 -390.828324) (xy 106.433817 -390.802823) (xy 106.486601 -390.784816) (xy 106.541444 -390.774686)
			(xy 106.597178 -390.772649) (xy 106.652615 -390.778749) (xy 106.706572 -390.792855) (xy 106.757901 -390.814667)
			(xy 106.805507 -390.843721) (xy 106.848375 -390.879396) (xy 106.885592 -390.920933) (xy 106.916365 -390.967446)
			(xy 106.940037 -391.017943) (xy 106.956105 -391.07135) (xy 106.964225 -391.126526) (xy 106.964734 -391.154412)
			(xy 106.964225 -391.182298) (xy 106.956105 -391.237474) (xy 106.940037 -391.290881) (xy 106.916365 -391.341378)
			(xy 106.885592 -391.387891) (xy 106.848375 -391.429428) (xy 106.805507 -391.465103) (xy 106.757901 -391.494157)
			(xy 106.706572 -391.515969) (xy 106.652615 -391.530075) (xy 106.597178 -391.536175) (xy 106.541444 -391.534138)
			(xy 106.486601 -391.524008) (xy 106.433817 -391.506001) (xy 106.384217 -391.4805) (xy 106.338859 -391.448049)
			(xy 106.29871 -391.40934) (xy 106.264624 -391.365197) (xy 106.237328 -391.316562) (xy 106.217405 -391.264471)
			(xy 106.205279 -391.210034) (xy 106.201208 -391.154412) (xy 99.857137 -391.154412) (xy 99.858771 -391.157897)
			(xy 99.874839 -391.211304) (xy 99.882959 -391.26648) (xy 99.883468 -391.294366) (xy 99.882959 -391.322252)
			(xy 99.874839 -391.377428) (xy 99.858771 -391.430835) (xy 99.835099 -391.481332) (xy 99.804326 -391.527845)
			(xy 99.767109 -391.569382) (xy 99.724241 -391.605057) (xy 99.676635 -391.634111) (xy 99.628565 -391.654538)
			(xy 108.000036 -391.654538) (xy 108.004107 -391.598916) (xy 108.016233 -391.544479) (xy 108.036156 -391.492388)
			(xy 108.063452 -391.443753) (xy 108.097538 -391.39961) (xy 108.137687 -391.360901) (xy 108.183045 -391.32845)
			(xy 108.232645 -391.302949) (xy 108.285429 -391.284942) (xy 108.340272 -391.274812) (xy 108.396006 -391.272775)
			(xy 108.451443 -391.278875) (xy 108.5054 -391.292981) (xy 108.556729 -391.314793) (xy 108.604335 -391.343847)
			(xy 108.647203 -391.379522) (xy 108.68442 -391.421059) (xy 108.715193 -391.467572) (xy 108.738865 -391.518069)
			(xy 108.754933 -391.571476) (xy 108.763053 -391.626652) (xy 108.763562 -391.654538) (xy 108.763053 -391.682424)
			(xy 108.754933 -391.7376) (xy 108.738865 -391.791007) (xy 108.715193 -391.841504) (xy 108.68442 -391.888017)
			(xy 108.647203 -391.929554) (xy 108.604335 -391.965229) (xy 108.556729 -391.994283) (xy 108.5054 -392.016095)
			(xy 108.451443 -392.030201) (xy 108.396006 -392.036301) (xy 108.340272 -392.034264) (xy 108.285429 -392.024134)
			(xy 108.232645 -392.006127) (xy 108.183045 -391.980626) (xy 108.137687 -391.948175) (xy 108.097538 -391.909466)
			(xy 108.063452 -391.865323) (xy 108.036156 -391.816688) (xy 108.016233 -391.764597) (xy 108.004107 -391.71016)
			(xy 108.000036 -391.654538) (xy 99.628565 -391.654538) (xy 99.625306 -391.655923) (xy 99.571349 -391.670029)
			(xy 99.515912 -391.676129) (xy 99.460178 -391.674092) (xy 99.405335 -391.663962) (xy 99.352551 -391.645955)
			(xy 99.302951 -391.620454) (xy 99.257593 -391.588003) (xy 99.217444 -391.549294) (xy 99.183358 -391.505151)
			(xy 99.156062 -391.456516) (xy 99.136139 -391.404425) (xy 99.124013 -391.349988) (xy 99.119942 -391.294366)
			(xy 90.612722 -391.294366) (xy 90.612722 -392.3792) (xy 96.620582 -392.3792) (xy 96.624653 -392.323578)
			(xy 96.636779 -392.269141) (xy 96.656702 -392.21705) (xy 96.683998 -392.168415) (xy 96.718084 -392.124272)
			(xy 96.758233 -392.085563) (xy 96.803591 -392.053112) (xy 96.853191 -392.027611) (xy 96.905975 -392.009604)
			(xy 96.960818 -391.999474) (xy 97.016552 -391.997437) (xy 97.071989 -392.003537) (xy 97.125946 -392.017643)
			(xy 97.177275 -392.039455) (xy 97.224881 -392.068509) (xy 97.267749 -392.104184) (xy 97.304966 -392.145721)
			(xy 97.335739 -392.192234) (xy 97.359411 -392.242731) (xy 97.375479 -392.296138) (xy 97.383599 -392.351314)
			(xy 97.384108 -392.3792) (xy 97.383599 -392.407086) (xy 97.375479 -392.462262) (xy 97.359411 -392.515669)
			(xy 97.335739 -392.566166) (xy 97.320125 -392.589766) (xy 99.119942 -392.589766) (xy 99.124013 -392.534144)
			(xy 99.136139 -392.479707) (xy 99.156062 -392.427616) (xy 99.183358 -392.378981) (xy 99.217444 -392.334838)
			(xy 99.257593 -392.296129) (xy 99.302951 -392.263678) (xy 99.352551 -392.238177) (xy 99.405335 -392.22017)
			(xy 99.460178 -392.21004) (xy 99.515912 -392.208003) (xy 99.571349 -392.214103) (xy 99.625306 -392.228209)
			(xy 99.676635 -392.250021) (xy 99.724241 -392.279075) (xy 99.767109 -392.31475) (xy 99.785029 -392.33475)
			(xy 106.667298 -392.33475) (xy 106.671369 -392.279128) (xy 106.683495 -392.224691) (xy 106.703418 -392.1726)
			(xy 106.730714 -392.123965) (xy 106.7648 -392.079822) (xy 106.804949 -392.041113) (xy 106.850307 -392.008662)
			(xy 106.899907 -391.983161) (xy 106.952691 -391.965154) (xy 107.007534 -391.955024) (xy 107.063268 -391.952987)
			(xy 107.118705 -391.959087) (xy 107.172662 -391.973193) (xy 107.223991 -391.995005) (xy 107.271597 -392.024059)
			(xy 107.314465 -392.059734) (xy 107.351682 -392.101271) (xy 107.382455 -392.147784) (xy 107.406127 -392.198281)
			(xy 107.422195 -392.251688) (xy 107.430315 -392.306864) (xy 107.430824 -392.33475) (xy 107.430315 -392.362636)
			(xy 107.422195 -392.417812) (xy 107.406127 -392.471219) (xy 107.382455 -392.521716) (xy 107.351682 -392.568229)
			(xy 107.314465 -392.609766) (xy 107.271597 -392.645441) (xy 107.223991 -392.674495) (xy 107.172662 -392.696307)
			(xy 107.118705 -392.710413) (xy 107.063268 -392.716513) (xy 107.007534 -392.714476) (xy 106.952691 -392.704346)
			(xy 106.899907 -392.686339) (xy 106.850307 -392.660838) (xy 106.804949 -392.628387) (xy 106.7648 -392.589678)
			(xy 106.730714 -392.545535) (xy 106.703418 -392.4969) (xy 106.683495 -392.444809) (xy 106.671369 -392.390372)
			(xy 106.667298 -392.33475) (xy 99.785029 -392.33475) (xy 99.804326 -392.356287) (xy 99.835099 -392.4028)
			(xy 99.858771 -392.453297) (xy 99.874839 -392.506704) (xy 99.882959 -392.56188) (xy 99.883468 -392.589766)
			(xy 99.882959 -392.617652) (xy 99.874839 -392.672828) (xy 99.858771 -392.726235) (xy 99.835099 -392.776732)
			(xy 99.804326 -392.823245) (xy 99.767109 -392.864782) (xy 99.724241 -392.900457) (xy 99.676635 -392.929511)
			(xy 99.625306 -392.951323) (xy 99.571349 -392.965429) (xy 99.515912 -392.971529) (xy 99.460178 -392.969492)
			(xy 99.405335 -392.959362) (xy 99.352551 -392.941355) (xy 99.302951 -392.915854) (xy 99.257593 -392.883403)
			(xy 99.217444 -392.844694) (xy 99.183358 -392.800551) (xy 99.156062 -392.751916) (xy 99.136139 -392.699825)
			(xy 99.124013 -392.645388) (xy 99.119942 -392.589766) (xy 97.320125 -392.589766) (xy 97.304966 -392.612679)
			(xy 97.267749 -392.654216) (xy 97.224881 -392.689891) (xy 97.177275 -392.718945) (xy 97.125946 -392.740757)
			(xy 97.071989 -392.754863) (xy 97.016552 -392.760963) (xy 96.960818 -392.758926) (xy 96.905975 -392.748796)
			(xy 96.853191 -392.730789) (xy 96.803591 -392.705288) (xy 96.758233 -392.672837) (xy 96.718084 -392.634128)
			(xy 96.683998 -392.589985) (xy 96.656702 -392.54135) (xy 96.636779 -392.489259) (xy 96.624653 -392.434822)
			(xy 96.620582 -392.3792) (xy 90.612722 -392.3792) (xy 90.612722 -393.885166) (xy 99.119942 -393.885166)
			(xy 99.124013 -393.829544) (xy 99.136139 -393.775107) (xy 99.156062 -393.723016) (xy 99.183358 -393.674381)
			(xy 99.217444 -393.630238) (xy 99.257593 -393.591529) (xy 99.302951 -393.559078) (xy 99.352551 -393.533577)
			(xy 99.405335 -393.51557) (xy 99.460178 -393.50544) (xy 99.515912 -393.503403) (xy 99.571349 -393.509503)
			(xy 99.625306 -393.523609) (xy 99.676635 -393.545421) (xy 99.724241 -393.574475) (xy 99.767109 -393.61015)
			(xy 99.804326 -393.651687) (xy 99.835099 -393.6982) (xy 99.858771 -393.748697) (xy 99.874839 -393.802104)
			(xy 99.882959 -393.85728) (xy 99.883468 -393.885166) (xy 99.882959 -393.913052) (xy 99.874839 -393.968228)
			(xy 99.858771 -394.021635) (xy 99.835099 -394.072132) (xy 99.804326 -394.118645) (xy 99.767109 -394.160182)
			(xy 99.724241 -394.195857) (xy 99.676635 -394.224911) (xy 99.625306 -394.246723) (xy 99.571349 -394.260829)
			(xy 99.515912 -394.266929) (xy 99.460178 -394.264892) (xy 99.405335 -394.254762) (xy 99.352551 -394.236755)
			(xy 99.302951 -394.211254) (xy 99.257593 -394.178803) (xy 99.217444 -394.140094) (xy 99.183358 -394.095951)
			(xy 99.156062 -394.047316) (xy 99.136139 -393.995225) (xy 99.124013 -393.940788) (xy 99.119942 -393.885166)
			(xy 90.612722 -393.885166) (xy 90.612722 -394.32738) (xy 105.828336 -394.32738) (xy 105.832407 -394.271758)
			(xy 105.844533 -394.217321) (xy 105.864456 -394.16523) (xy 105.891752 -394.116595) (xy 105.925838 -394.072452)
			(xy 105.965987 -394.033743) (xy 106.011345 -394.001292) (xy 106.060945 -393.975791) (xy 106.113729 -393.957784)
			(xy 106.168572 -393.947654) (xy 106.224306 -393.945617) (xy 106.279743 -393.951717) (xy 106.3337 -393.965823)
			(xy 106.385029 -393.987635) (xy 106.432635 -394.016689) (xy 106.475503 -394.052364) (xy 106.51272 -394.093901)
			(xy 106.543493 -394.140414) (xy 106.567165 -394.190911) (xy 106.583233 -394.244318) (xy 106.591353 -394.299494)
			(xy 106.591862 -394.32738) (xy 106.591353 -394.355266) (xy 106.583233 -394.410442) (xy 106.567165 -394.463849)
			(xy 106.543493 -394.514346) (xy 106.51272 -394.560859) (xy 106.475503 -394.602396) (xy 106.432635 -394.638071)
			(xy 106.385029 -394.667125) (xy 106.3337 -394.688937) (xy 106.279743 -394.703043) (xy 106.224306 -394.709143)
			(xy 106.168572 -394.707106) (xy 106.113729 -394.696976) (xy 106.060945 -394.678969) (xy 106.011345 -394.653468)
			(xy 105.965987 -394.621017) (xy 105.925838 -394.582308) (xy 105.891752 -394.538165) (xy 105.864456 -394.48953)
			(xy 105.844533 -394.437439) (xy 105.832407 -394.383002) (xy 105.828336 -394.32738) (xy 90.612722 -394.32738)
			(xy 90.612722 -395.180566) (xy 99.119942 -395.180566) (xy 99.124013 -395.124944) (xy 99.136139 -395.070507)
			(xy 99.156062 -395.018416) (xy 99.183358 -394.969781) (xy 99.217444 -394.925638) (xy 99.257593 -394.886929)
			(xy 99.302951 -394.854478) (xy 99.352551 -394.828977) (xy 99.405335 -394.81097) (xy 99.460178 -394.80084)
			(xy 99.515912 -394.798803) (xy 99.571349 -394.804903) (xy 99.625306 -394.819009) (xy 99.676635 -394.840821)
			(xy 99.724241 -394.869875) (xy 99.767109 -394.90555) (xy 99.804326 -394.947087) (xy 99.835099 -394.9936)
			(xy 99.858771 -395.044097) (xy 99.874839 -395.097504) (xy 99.882959 -395.15268) (xy 99.883468 -395.180566)
			(xy 99.883347 -395.18717) (xy 101.058724 -395.18717) (xy 101.062795 -395.131548) (xy 101.074921 -395.077111)
			(xy 101.094844 -395.02502) (xy 101.12214 -394.976385) (xy 101.156226 -394.932242) (xy 101.196375 -394.893533)
			(xy 101.241733 -394.861082) (xy 101.291333 -394.835581) (xy 101.344117 -394.817574) (xy 101.39896 -394.807444)
			(xy 101.454694 -394.805407) (xy 101.510131 -394.811507) (xy 101.564088 -394.825613) (xy 101.615417 -394.847425)
			(xy 101.663023 -394.876479) (xy 101.705891 -394.912154) (xy 101.743108 -394.953691) (xy 101.773881 -395.000204)
			(xy 101.797553 -395.050701) (xy 101.813621 -395.104108) (xy 101.821741 -395.159284) (xy 101.82225 -395.18717)
			(xy 101.821741 -395.215056) (xy 101.813621 -395.270232) (xy 101.797553 -395.323639) (xy 101.773881 -395.374136)
			(xy 101.743108 -395.420649) (xy 101.705891 -395.462186) (xy 101.663023 -395.497861) (xy 101.615417 -395.526915)
			(xy 101.564088 -395.548727) (xy 101.510131 -395.562833) (xy 101.454694 -395.568933) (xy 101.39896 -395.566896)
			(xy 101.344117 -395.556766) (xy 101.291333 -395.538759) (xy 101.241733 -395.513258) (xy 101.196375 -395.480807)
			(xy 101.156226 -395.442098) (xy 101.12214 -395.397955) (xy 101.094844 -395.34932) (xy 101.074921 -395.297229)
			(xy 101.062795 -395.242792) (xy 101.058724 -395.18717) (xy 99.883347 -395.18717) (xy 99.882959 -395.208452)
			(xy 99.874839 -395.263628) (xy 99.858771 -395.317035) (xy 99.835099 -395.367532) (xy 99.804326 -395.414045)
			(xy 99.767109 -395.455582) (xy 99.724241 -395.491257) (xy 99.676635 -395.520311) (xy 99.625306 -395.542123)
			(xy 99.571349 -395.556229) (xy 99.515912 -395.562329) (xy 99.460178 -395.560292) (xy 99.405335 -395.550162)
			(xy 99.352551 -395.532155) (xy 99.302951 -395.506654) (xy 99.257593 -395.474203) (xy 99.217444 -395.435494)
			(xy 99.183358 -395.391351) (xy 99.156062 -395.342716) (xy 99.136139 -395.290625) (xy 99.124013 -395.236188)
			(xy 99.119942 -395.180566) (xy 90.612722 -395.180566) (xy 90.612722 -396.1638) (xy 96.6503 -396.1638)
			(xy 96.654371 -396.108178) (xy 96.666497 -396.053741) (xy 96.68642 -396.00165) (xy 96.713716 -395.953015)
			(xy 96.747802 -395.908872) (xy 96.787951 -395.870163) (xy 96.833309 -395.837712) (xy 96.882909 -395.812211)
			(xy 96.935693 -395.794204) (xy 96.990536 -395.784074) (xy 97.04627 -395.782037) (xy 97.101707 -395.788137)
			(xy 97.155664 -395.802243) (xy 97.206993 -395.824055) (xy 97.254599 -395.853109) (xy 97.297467 -395.888784)
			(xy 97.334684 -395.930321) (xy 97.365457 -395.976834) (xy 97.389129 -396.027331) (xy 97.405197 -396.080738)
			(xy 97.413317 -396.135914) (xy 97.413826 -396.1638) (xy 97.413317 -396.191686) (xy 97.405197 -396.246862)
			(xy 97.389129 -396.300269) (xy 97.365457 -396.350766) (xy 97.334684 -396.397279) (xy 97.297467 -396.438816)
			(xy 97.254599 -396.474491) (xy 97.212644 -396.500096) (xy 100.023166 -396.500096) (xy 100.027237 -396.444474)
			(xy 100.039363 -396.390037) (xy 100.059286 -396.337946) (xy 100.086582 -396.289311) (xy 100.120668 -396.245168)
			(xy 100.160817 -396.206459) (xy 100.206175 -396.174008) (xy 100.255775 -396.148507) (xy 100.308559 -396.1305)
			(xy 100.363402 -396.12037) (xy 100.419136 -396.118333) (xy 100.474573 -396.124433) (xy 100.52853 -396.138539)
			(xy 100.579859 -396.160351) (xy 100.627465 -396.189405) (xy 100.670333 -396.22508) (xy 100.70755 -396.266617)
			(xy 100.738323 -396.31313) (xy 100.761995 -396.363627) (xy 100.778063 -396.417034) (xy 100.786183 -396.47221)
			(xy 100.786692 -396.500096) (xy 101.318566 -396.500096) (xy 101.322637 -396.444474) (xy 101.334763 -396.390037)
			(xy 101.354686 -396.337946) (xy 101.381982 -396.289311) (xy 101.416068 -396.245168) (xy 101.456217 -396.206459)
			(xy 101.501575 -396.174008) (xy 101.551175 -396.148507) (xy 101.603959 -396.1305) (xy 101.658802 -396.12037)
			(xy 101.714536 -396.118333) (xy 101.769973 -396.124433) (xy 101.82393 -396.138539) (xy 101.875259 -396.160351)
			(xy 101.922865 -396.189405) (xy 101.965733 -396.22508) (xy 102.00295 -396.266617) (xy 102.033723 -396.31313)
			(xy 102.057395 -396.363627) (xy 102.073463 -396.417034) (xy 102.081583 -396.47221) (xy 102.082092 -396.500096)
			(xy 102.613966 -396.500096) (xy 102.618037 -396.444474) (xy 102.630163 -396.390037) (xy 102.650086 -396.337946)
			(xy 102.677382 -396.289311) (xy 102.711468 -396.245168) (xy 102.751617 -396.206459) (xy 102.796975 -396.174008)
			(xy 102.846575 -396.148507) (xy 102.899359 -396.1305) (xy 102.954202 -396.12037) (xy 103.009936 -396.118333)
			(xy 103.065373 -396.124433) (xy 103.11933 -396.138539) (xy 103.170659 -396.160351) (xy 103.218265 -396.189405)
			(xy 103.261133 -396.22508) (xy 103.29835 -396.266617) (xy 103.329123 -396.31313) (xy 103.352795 -396.363627)
			(xy 103.368863 -396.417034) (xy 103.376983 -396.47221) (xy 103.377492 -396.500096) (xy 103.909366 -396.500096)
			(xy 103.913437 -396.444474) (xy 103.925563 -396.390037) (xy 103.945486 -396.337946) (xy 103.972782 -396.289311)
			(xy 104.006868 -396.245168) (xy 104.047017 -396.206459) (xy 104.092375 -396.174008) (xy 104.141975 -396.148507)
			(xy 104.194759 -396.1305) (xy 104.249602 -396.12037) (xy 104.305336 -396.118333) (xy 104.360773 -396.124433)
			(xy 104.41473 -396.138539) (xy 104.466059 -396.160351) (xy 104.513665 -396.189405) (xy 104.556533 -396.22508)
			(xy 104.59375 -396.266617) (xy 104.624523 -396.31313) (xy 104.648195 -396.363627) (xy 104.664263 -396.417034)
			(xy 104.672383 -396.47221) (xy 104.672892 -396.500096) (xy 104.672383 -396.527982) (xy 104.664263 -396.583158)
			(xy 104.648195 -396.636565) (xy 104.624523 -396.687062) (xy 104.59375 -396.733575) (xy 104.556533 -396.775112)
			(xy 104.513665 -396.810787) (xy 104.466059 -396.839841) (xy 104.41473 -396.861653) (xy 104.360773 -396.875759)
			(xy 104.305336 -396.881859) (xy 104.249602 -396.879822) (xy 104.194759 -396.869692) (xy 104.141975 -396.851685)
			(xy 104.092375 -396.826184) (xy 104.047017 -396.793733) (xy 104.006868 -396.755024) (xy 103.972782 -396.710881)
			(xy 103.945486 -396.662246) (xy 103.925563 -396.610155) (xy 103.913437 -396.555718) (xy 103.909366 -396.500096)
			(xy 103.377492 -396.500096) (xy 103.376983 -396.527982) (xy 103.368863 -396.583158) (xy 103.352795 -396.636565)
			(xy 103.329123 -396.687062) (xy 103.29835 -396.733575) (xy 103.261133 -396.775112) (xy 103.218265 -396.810787)
			(xy 103.170659 -396.839841) (xy 103.11933 -396.861653) (xy 103.065373 -396.875759) (xy 103.009936 -396.881859)
			(xy 102.954202 -396.879822) (xy 102.899359 -396.869692) (xy 102.846575 -396.851685) (xy 102.796975 -396.826184)
			(xy 102.751617 -396.793733) (xy 102.711468 -396.755024) (xy 102.677382 -396.710881) (xy 102.650086 -396.662246)
			(xy 102.630163 -396.610155) (xy 102.618037 -396.555718) (xy 102.613966 -396.500096) (xy 102.082092 -396.500096)
			(xy 102.081583 -396.527982) (xy 102.073463 -396.583158) (xy 102.057395 -396.636565) (xy 102.033723 -396.687062)
			(xy 102.00295 -396.733575) (xy 101.965733 -396.775112) (xy 101.922865 -396.810787) (xy 101.875259 -396.839841)
			(xy 101.82393 -396.861653) (xy 101.769973 -396.875759) (xy 101.714536 -396.881859) (xy 101.658802 -396.879822)
			(xy 101.603959 -396.869692) (xy 101.551175 -396.851685) (xy 101.501575 -396.826184) (xy 101.456217 -396.793733)
			(xy 101.416068 -396.755024) (xy 101.381982 -396.710881) (xy 101.354686 -396.662246) (xy 101.334763 -396.610155)
			(xy 101.322637 -396.555718) (xy 101.318566 -396.500096) (xy 100.786692 -396.500096) (xy 100.786183 -396.527982)
			(xy 100.778063 -396.583158) (xy 100.761995 -396.636565) (xy 100.738323 -396.687062) (xy 100.70755 -396.733575)
			(xy 100.670333 -396.775112) (xy 100.627465 -396.810787) (xy 100.579859 -396.839841) (xy 100.52853 -396.861653)
			(xy 100.474573 -396.875759) (xy 100.419136 -396.881859) (xy 100.363402 -396.879822) (xy 100.308559 -396.869692)
			(xy 100.255775 -396.851685) (xy 100.206175 -396.826184) (xy 100.160817 -396.793733) (xy 100.120668 -396.755024)
			(xy 100.086582 -396.710881) (xy 100.059286 -396.662246) (xy 100.039363 -396.610155) (xy 100.027237 -396.555718)
			(xy 100.023166 -396.500096) (xy 97.212644 -396.500096) (xy 97.206993 -396.503545) (xy 97.155664 -396.525357)
			(xy 97.101707 -396.539463) (xy 97.04627 -396.545563) (xy 96.990536 -396.543526) (xy 96.935693 -396.533396)
			(xy 96.882909 -396.515389) (xy 96.833309 -396.489888) (xy 96.787951 -396.457437) (xy 96.747802 -396.418728)
			(xy 96.713716 -396.374585) (xy 96.68642 -396.32595) (xy 96.666497 -396.273859) (xy 96.654371 -396.219422)
			(xy 96.6503 -396.1638) (xy 90.612722 -396.1638) (xy 90.612722 -397.557287) (xy 91.224885 -397.557287)
			(xy 91.233678 -397.492438) (xy 91.251105 -397.429358) (xy 91.27685 -397.369192) (xy 91.293188 -397.340836)
			(xy 91.296489 -397.334805) (xy 91.300104 -397.321546) (xy 91.3003 -397.314674) (xy 91.3003 -397.028924)
			(xy 91.300741 -397.018771) (xy 91.308529 -397.000019) (xy 91.32292 -396.985695) (xy 91.341708 -396.977995)
			(xy 91.351862 -396.977616) (xy 92.068142 -396.977616) (xy 92.078268 -396.978091) (xy 92.096986 -396.985829)
			(xy 92.11134 -397.000118) (xy 92.119162 -397.0188) (xy 92.119704 -397.028924) (xy 92.119704 -397.314674)
			(xy 92.119906 -397.321547) (xy 92.123507 -397.334809) (xy 92.126816 -397.340836) (xy 92.143163 -397.369187)
			(xy 92.168909 -397.429354) (xy 92.186336 -397.492436) (xy 92.195129 -397.557286) (xy 92.195127 -397.622731)
			(xy 92.186332 -397.687581) (xy 92.168903 -397.750662) (xy 92.143155 -397.810828) (xy 92.126816 -397.839184)
			(xy 92.123508 -397.845212) (xy 92.119898 -397.858473) (xy 92.119704 -397.865346) (xy 92.119704 -398.6149)
			(xy 92.119895 -398.621773) (xy 92.123504 -398.635036) (xy 92.126816 -398.641062) (xy 92.142514 -398.66824)
			(xy 100.573076 -398.66824) (xy 100.577147 -398.612618) (xy 100.589273 -398.558181) (xy 100.609196 -398.50609)
			(xy 100.636492 -398.457455) (xy 100.670578 -398.413312) (xy 100.710727 -398.374603) (xy 100.756085 -398.342152)
			(xy 100.805685 -398.316651) (xy 100.858469 -398.298644) (xy 100.913312 -398.288514) (xy 100.969046 -398.286477)
			(xy 101.024483 -398.292577) (xy 101.07844 -398.306683) (xy 101.129769 -398.328495) (xy 101.177375 -398.357549)
			(xy 101.220243 -398.393224) (xy 101.25746 -398.434761) (xy 101.288233 -398.481274) (xy 101.311905 -398.531771)
			(xy 101.327973 -398.585178) (xy 101.336093 -398.640354) (xy 101.336602 -398.66824) (xy 101.589076 -398.66824)
			(xy 101.593147 -398.612618) (xy 101.605273 -398.558181) (xy 101.625196 -398.50609) (xy 101.652492 -398.457455)
			(xy 101.686578 -398.413312) (xy 101.726727 -398.374603) (xy 101.772085 -398.342152) (xy 101.821685 -398.316651)
			(xy 101.874469 -398.298644) (xy 101.929312 -398.288514) (xy 101.985046 -398.286477) (xy 102.040483 -398.292577)
			(xy 102.09444 -398.306683) (xy 102.145769 -398.328495) (xy 102.193375 -398.357549) (xy 102.236243 -398.393224)
			(xy 102.27346 -398.434761) (xy 102.304233 -398.481274) (xy 102.327905 -398.531771) (xy 102.343973 -398.585178)
			(xy 102.352093 -398.640354) (xy 102.352602 -398.66824) (xy 102.352491 -398.674336) (xy 105.653076 -398.674336)
			(xy 105.657147 -398.618714) (xy 105.669273 -398.564277) (xy 105.689196 -398.512186) (xy 105.716492 -398.463551)
			(xy 105.750578 -398.419408) (xy 105.790727 -398.380699) (xy 105.836085 -398.348248) (xy 105.885685 -398.322747)
			(xy 105.938469 -398.30474) (xy 105.993312 -398.29461) (xy 106.049046 -398.292573) (xy 106.104483 -398.298673)
			(xy 106.15844 -398.312779) (xy 106.209769 -398.334591) (xy 106.257375 -398.363645) (xy 106.300243 -398.39932)
			(xy 106.33746 -398.440857) (xy 106.368233 -398.48737) (xy 106.391905 -398.537867) (xy 106.407973 -398.591274)
			(xy 106.416093 -398.64645) (xy 106.416602 -398.674336) (xy 106.416093 -398.702222) (xy 106.407973 -398.757398)
			(xy 106.391905 -398.810805) (xy 106.368233 -398.861302) (xy 106.33746 -398.907815) (xy 106.300243 -398.949352)
			(xy 106.257375 -398.985027) (xy 106.209769 -399.014081) (xy 106.15844 -399.035893) (xy 106.104483 -399.049999)
			(xy 106.049046 -399.056099) (xy 105.993312 -399.054062) (xy 105.938469 -399.043932) (xy 105.885685 -399.025925)
			(xy 105.836085 -399.000424) (xy 105.790727 -398.967973) (xy 105.750578 -398.929264) (xy 105.716492 -398.885121)
			(xy 105.689196 -398.836486) (xy 105.669273 -398.784395) (xy 105.657147 -398.729958) (xy 105.653076 -398.674336)
			(xy 102.352491 -398.674336) (xy 102.352093 -398.696126) (xy 102.343973 -398.751302) (xy 102.327905 -398.804709)
			(xy 102.304233 -398.855206) (xy 102.27346 -398.901719) (xy 102.236243 -398.943256) (xy 102.193375 -398.978931)
			(xy 102.145769 -399.007985) (xy 102.09444 -399.029797) (xy 102.040483 -399.043903) (xy 101.985046 -399.050003)
			(xy 101.929312 -399.047966) (xy 101.874469 -399.037836) (xy 101.821685 -399.019829) (xy 101.772085 -398.994328)
			(xy 101.726727 -398.961877) (xy 101.686578 -398.923168) (xy 101.652492 -398.879025) (xy 101.625196 -398.83039)
			(xy 101.605273 -398.778299) (xy 101.593147 -398.723862) (xy 101.589076 -398.66824) (xy 101.336602 -398.66824)
			(xy 101.336093 -398.696126) (xy 101.327973 -398.751302) (xy 101.311905 -398.804709) (xy 101.288233 -398.855206)
			(xy 101.25746 -398.901719) (xy 101.220243 -398.943256) (xy 101.177375 -398.978931) (xy 101.129769 -399.007985)
			(xy 101.07844 -399.029797) (xy 101.024483 -399.043903) (xy 100.969046 -399.050003) (xy 100.913312 -399.047966)
			(xy 100.858469 -399.037836) (xy 100.805685 -399.019829) (xy 100.756085 -398.994328) (xy 100.710727 -398.961877)
			(xy 100.670578 -398.923168) (xy 100.636492 -398.879025) (xy 100.609196 -398.83039) (xy 100.589273 -398.778299)
			(xy 100.577147 -398.723862) (xy 100.573076 -398.66824) (xy 92.142514 -398.66824) (xy 92.143185 -398.669401)
			(xy 92.168929 -398.729571) (xy 92.186353 -398.792655) (xy 92.195143 -398.857508) (xy 92.195139 -398.922954)
			(xy 92.186341 -398.987806) (xy 92.168908 -399.050887) (xy 92.143157 -399.111054) (xy 92.126816 -399.13941)
			(xy 92.123499 -399.145433) (xy 92.119894 -399.158698) (xy 92.119704 -399.165572) (xy 92.119704 -399.451576)
			(xy 92.119259 -399.461728) (xy 92.111472 -399.480479) (xy 92.097082 -399.494803) (xy 92.078296 -399.502505)
			(xy 92.068142 -399.502884) (xy 91.351862 -399.502884) (xy 91.341736 -399.502405) (xy 91.323018 -399.494669)
			(xy 91.308664 -399.480381) (xy 91.300842 -399.4617) (xy 91.3003 -399.451576) (xy 91.3003 -399.165572)
			(xy 91.300119 -399.158698) (xy 91.296503 -399.145435) (xy 91.293188 -399.13941) (xy 91.27688 -399.111038)
			(xy 91.25113 -399.050875) (xy 91.233699 -398.987798) (xy 91.224901 -398.922951) (xy 91.224897 -398.85751)
			(xy 91.233686 -398.792662) (xy 91.25111 -398.729583) (xy 91.276852 -398.669418) (xy 91.293188 -398.641062)
			(xy 91.296515 -398.635044) (xy 91.300113 -398.621775) (xy 91.3003 -398.6149) (xy 91.3003 -397.865346)
			(xy 91.30009 -397.858474) (xy 91.296494 -397.845211) (xy 91.293188 -397.839184) (xy 91.276858 -397.810824)
			(xy 91.25111 -397.750658) (xy 91.233681 -397.687579) (xy 91.224886 -397.62273) (xy 91.224885 -397.557287)
			(xy 90.612722 -397.557287) (xy 90.612722 -401.49018) (xy 91.223854 -401.49018) (xy 91.227845 -401.428013)
			(xy 91.239754 -401.366866) (xy 91.259383 -401.307745) (xy 91.286412 -401.251619) (xy 91.320396 -401.19941)
			(xy 91.360778 -401.151975) (xy 91.406894 -401.110094) (xy 91.457986 -401.074454) (xy 91.513217 -401.04564)
			(xy 91.571679 -401.024126) (xy 91.632413 -401.010264) (xy 91.69442 -401.004282) (xy 91.756683 -401.006278)
			(xy 91.81818 -401.016221) (xy 91.877901 -401.033945) (xy 91.934864 -401.059162) (xy 91.988135 -401.091455)
			(xy 92.03684 -401.130295) (xy 92.080177 -401.175045) (xy 92.117437 -401.224969) (xy 92.148006 -401.279248)
			(xy 92.171384 -401.336991) (xy 92.187185 -401.397249) (xy 92.195151 -401.459032) (xy 92.19565 -401.49018)
			(xy 92.195151 -401.521328) (xy 92.187185 -401.583111) (xy 92.171384 -401.643369) (xy 92.148006 -401.701112)
			(xy 92.117437 -401.755391) (xy 92.080177 -401.805315) (xy 92.03684 -401.850065) (xy 91.988135 -401.888905)
			(xy 91.934864 -401.921198) (xy 91.877901 -401.946415) (xy 91.81818 -401.964139) (xy 91.756683 -401.974082)
			(xy 91.69442 -401.976078) (xy 91.632413 -401.970096) (xy 91.571679 -401.956234) (xy 91.513217 -401.93472)
			(xy 91.457986 -401.905906) (xy 91.406894 -401.870266) (xy 91.360778 -401.828385) (xy 91.320396 -401.78095)
			(xy 91.286412 -401.728741) (xy 91.259383 -401.672615) (xy 91.239754 -401.613494) (xy 91.227845 -401.552347)
			(xy 91.223854 -401.49018) (xy 90.612722 -401.49018) (xy 90.612722 -402.790152) (xy 91.223854 -402.790152)
			(xy 91.227845 -402.727985) (xy 91.239754 -402.666838) (xy 91.259383 -402.607717) (xy 91.286412 -402.551591)
			(xy 91.320396 -402.499382) (xy 91.360778 -402.451947) (xy 91.406894 -402.410066) (xy 91.457986 -402.374426)
			(xy 91.513217 -402.345612) (xy 91.571679 -402.324098) (xy 91.632413 -402.310236) (xy 91.69442 -402.304254)
			(xy 91.756683 -402.30625) (xy 91.81818 -402.316193) (xy 91.877901 -402.333917) (xy 91.934864 -402.359134)
			(xy 91.988135 -402.391427) (xy 92.03684 -402.430267) (xy 92.080177 -402.475017) (xy 92.117437 -402.524941)
			(xy 92.148006 -402.57922) (xy 92.171384 -402.636963) (xy 92.187185 -402.697221) (xy 92.195151 -402.759004)
			(xy 92.19565 -402.790152) (xy 92.195151 -402.8213) (xy 92.187185 -402.883083) (xy 92.171384 -402.943341)
			(xy 92.148006 -403.001084) (xy 92.117437 -403.055363) (xy 92.080177 -403.105287) (xy 92.03684 -403.150037)
			(xy 91.988135 -403.188877) (xy 91.934864 -403.22117) (xy 91.877901 -403.246387) (xy 91.81818 -403.264111)
			(xy 91.756683 -403.274054) (xy 91.69442 -403.27605) (xy 91.632413 -403.270068) (xy 91.571679 -403.256206)
			(xy 91.513217 -403.234692) (xy 91.457986 -403.205878) (xy 91.406894 -403.170238) (xy 91.360778 -403.128357)
			(xy 91.320396 -403.080922) (xy 91.286412 -403.028713) (xy 91.259383 -402.972587) (xy 91.239754 -402.913466)
			(xy 91.227845 -402.852319) (xy 91.223854 -402.790152) (xy 90.612722 -402.790152) (xy 90.612722 -406.722795)
			(xy 91.224862 -406.722795) (xy 91.224866 -406.65735) (xy 91.233664 -406.592498) (xy 91.251096 -406.529417)
			(xy 91.276847 -406.46925) (xy 91.293188 -406.440894) (xy 91.296504 -406.43487) (xy 91.300109 -406.421606)
			(xy 91.3003 -406.414732) (xy 91.3003 -405.665432) (xy 91.300096 -405.65856) (xy 91.296496 -405.645297)
			(xy 91.293188 -405.63927) (xy 91.276846 -405.610916) (xy 91.2511 -405.55075) (xy 91.233672 -405.487669)
			(xy 91.224878 -405.422818) (xy 91.224879 -405.357375) (xy 91.233673 -405.292524) (xy 91.251102 -405.229444)
			(xy 91.276849 -405.169278) (xy 91.293188 -405.140922) (xy 91.296494 -405.134893) (xy 91.300105 -405.121633)
			(xy 91.3003 -405.11476) (xy 91.3003 -404.828756) (xy 91.300686 -404.818599) (xy 91.308496 -404.799846)
			(xy 91.322903 -404.785524) (xy 91.341703 -404.777826) (xy 91.351862 -404.777448) (xy 92.068142 -404.777448)
			(xy 92.078272 -404.777892) (xy 92.096996 -404.785635) (xy 92.111351 -404.799934) (xy 92.119167 -404.818628)
			(xy 92.119704 -404.828756) (xy 92.119704 -405.11476) (xy 92.119911 -405.121632) (xy 92.123509 -405.134895)
			(xy 92.126816 -405.140922) (xy 92.143151 -405.16928) (xy 92.168898 -405.229445) (xy 92.186326 -405.292525)
			(xy 92.195121 -405.357375) (xy 92.195121 -405.422818) (xy 92.186328 -405.487668) (xy 92.1689 -405.550748)
			(xy 92.143155 -405.610914) (xy 92.126816 -405.63927) (xy 92.123513 -405.6453) (xy 92.1199 -405.65856)
			(xy 92.119704 -405.665432) (xy 92.119704 -406.414732) (xy 92.119883 -406.421606) (xy 92.1235 -406.434869)
			(xy 92.126816 -406.440894) (xy 92.143128 -406.469265) (xy 92.168876 -406.529427) (xy 92.186308 -406.592505)
			(xy 92.195105 -406.657352) (xy 92.195108 -406.722793) (xy 92.186319 -406.787642) (xy 92.168895 -406.850721)
			(xy 92.143153 -406.910886) (xy 92.126816 -406.939242) (xy 92.123487 -406.94526) (xy 92.11989 -406.958529)
			(xy 92.119704 -406.965404) (xy 92.119704 -407.251408) (xy 92.119285 -407.261562) (xy 92.111487 -407.280314)
			(xy 92.09709 -407.294637) (xy 92.078298 -407.302337) (xy 92.068142 -407.302716) (xy 91.351862 -407.302716)
			(xy 91.341727 -407.302303) (xy 91.322997 -407.294555) (xy 91.308641 -407.280246) (xy 91.30083 -407.261541)
			(xy 91.3003 -407.251408) (xy 91.3003 -406.965404) (xy 91.300107 -406.958531) (xy 91.2965 -406.945268)
			(xy 91.293188 -406.939242) (xy 91.276822 -406.910901) (xy 91.251078 -406.850732) (xy 91.233653 -406.787648)
			(xy 91.224862 -406.722795) (xy 90.612722 -406.722795) (xy 90.612722 -410.622709) (xy 91.224871 -410.622709)
			(xy 91.224873 -410.557264) (xy 91.233669 -410.492413) (xy 91.251099 -410.429332) (xy 91.276848 -410.369166)
			(xy 91.293188 -410.34081) (xy 91.296498 -410.334783) (xy 91.300107 -410.321521) (xy 91.3003 -410.314648)
			(xy 91.3003 -409.565348) (xy 91.30009 -409.558476) (xy 91.296494 -409.545213) (xy 91.293188 -409.539186)
			(xy 91.276859 -409.510825) (xy 91.251112 -409.45066) (xy 91.233682 -409.387581) (xy 91.224887 -409.322732)
			(xy 91.224886 -409.257289) (xy 91.233678 -409.19244) (xy 91.251105 -409.12936) (xy 91.27685 -409.069194)
			(xy 91.293188 -409.040838) (xy 91.296488 -409.034806) (xy 91.300103 -409.021548) (xy 91.3003 -409.014676)
			(xy 91.3003 -408.728672) (xy 91.300699 -408.718516) (xy 91.308503 -408.699763) (xy 91.322907 -408.685441)
			(xy 91.341704 -408.677742) (xy 91.351862 -408.677364) (xy 92.068142 -408.677364) (xy 92.078274 -408.677793)
			(xy 92.097001 -408.685539) (xy 92.111357 -408.699843) (xy 92.11917 -408.718542) (xy 92.119704 -408.728672)
			(xy 92.119704 -409.014676) (xy 92.119905 -409.021549) (xy 92.123507 -409.034811) (xy 92.126816 -409.040838)
			(xy 92.143165 -409.069188) (xy 92.16891 -409.129356) (xy 92.186337 -409.192437) (xy 92.19513 -409.257288)
			(xy 92.195128 -409.322732) (xy 92.186333 -409.387583) (xy 92.168903 -409.450664) (xy 92.143156 -409.51083)
			(xy 92.126816 -409.539186) (xy 92.123507 -409.545214) (xy 92.119898 -409.558475) (xy 92.119704 -409.565348)
			(xy 92.119704 -410.314648) (xy 92.119915 -410.32152) (xy 92.12351 -410.334783) (xy 92.126816 -410.34081)
			(xy 92.143141 -410.369173) (xy 92.168889 -410.429338) (xy 92.186318 -410.492416) (xy 92.195114 -410.557265)
			(xy 92.195116 -410.622707) (xy 92.186324 -410.687557) (xy 92.168898 -410.750636) (xy 92.143154 -410.810802)
			(xy 92.126816 -410.839158) (xy 92.123517 -410.845191) (xy 92.119901 -410.858448) (xy 92.119704 -410.86532)
			(xy 92.119704 -411.151324) (xy 92.119298 -411.161479) (xy 92.111495 -411.180231) (xy 92.097094 -411.194554)
			(xy 92.078299 -411.202253) (xy 92.068142 -411.202632) (xy 91.351862 -411.202632) (xy 91.341729 -411.202204)
			(xy 91.323002 -411.194458) (xy 91.308646 -411.180154) (xy 91.300833 -411.161455) (xy 91.3003 -411.151324)
			(xy 91.3003 -410.86532) (xy 91.3001 -410.858447) (xy 91.296497 -410.845185) (xy 91.293188 -410.839158)
			(xy 91.276836 -410.81081) (xy 91.25109 -410.750642) (xy 91.233664 -410.68756) (xy 91.224871 -410.622709)
			(xy 90.612722 -410.622709) (xy 90.612722 -413.319468) (xy 90.613158 -413.329532) (xy 90.620892 -413.348117)
			(xy 90.627708 -413.355536) (xy 94.4245 -417.152328) (xy 94.431895 -417.159182) (xy 94.450494 -417.166928)
			(xy 94.460568 -417.167314)
		)
		(stroke
			(width 0)
			(type solid)
		)
		(fill yes)
		(layer "In13.Cu")
		(net "GND")
	)
	(gr_poly
		(pts
			(xy 412.02229 -173.095412) (xy 412.032279 -173.094876) (xy 412.050714 -173.087167) (xy 412.058104 -173.080426)
			(xy 412.29915 -172.83938) (xy 412.305963 -172.832036) (xy 412.313696 -172.813573) (xy 412.314136 -172.803566)
			(xy 412.314136 -147.845526) (xy 412.313698 -147.835463) (xy 412.305957 -147.816884) (xy 412.29915 -147.809458)
			(xy 405.732996 -141.243304) (xy 405.725884 -141.236192) (xy 405.707342 -141.228318) (xy 405.615394 -141.228064)
			(xy 405.597106 -141.23543) (xy 405.589994 -141.242542) (xy 405.56847 -141.262848) (xy 405.520317 -141.297233)
			(xy 405.467432 -141.323772) (xy 405.411085 -141.341829) (xy 405.352625 -141.35097) (xy 405.32304 -141.351508)
			(xy 405.295785 -141.351047) (xy 405.24183 -141.343295) (xy 405.189527 -141.327942) (xy 405.139942 -141.305302)
			(xy 405.094084 -141.275835) (xy 405.052887 -141.240142) (xy 405.017189 -141.198948) (xy 404.987717 -141.153093)
			(xy 404.965072 -141.10351) (xy 404.949713 -141.051209) (xy 404.941955 -140.997255) (xy 404.941532 -140.97)
			(xy 404.942089 -140.940416) (xy 404.951225 -140.881957) (xy 404.969277 -140.82561) (xy 404.995813 -140.772725)
			(xy 405.030197 -140.724573) (xy 405.050498 -140.703046) (xy 405.05761 -140.695934) (xy 405.064976 -140.677646)
			(xy 405.064722 -140.595858) (xy 405.064178 -140.585873) (xy 405.056456 -140.56745) (xy 405.049736 -140.560044)
			(xy 404.137622 -139.64793) (xy 404.13051 -139.640564) (xy 404.111714 -139.632944) (xy 402.360638 -139.632944)
			(xy 402.353526 -139.633452) (xy 401.808442 -140.178536) (xy 401.789651 -140.196625) (xy 401.747441 -140.227261)
			(xy 401.700957 -140.250913) (xy 401.651344 -140.266999) (xy 401.599824 -140.275123) (xy 401.573746 -140.275564)
			(xy 401.072096 -140.275564) (xy 401.061563 -140.276091) (xy 401.042274 -140.284559) (xy 401.028013 -140.300064)
			(xy 401.02409 -140.309854) (xy 400.99107 -140.405866) (xy 401.000214 -140.436854) (xy 401.012914 -140.447014)
			(xy 401.035179 -140.465208) (xy 401.074509 -140.507151) (xy 401.107102 -140.554518) (xy 401.132222 -140.606239)
			(xy 401.1493 -140.661142) (xy 401.157949 -140.717985) (xy 401.158456 -140.746734) (xy 401.157968 -140.773985)
			(xy 401.150208 -140.827932) (xy 401.13485 -140.880225) (xy 401.112208 -140.929801) (xy 401.082741 -140.975651)
			(xy 401.047051 -141.016841) (xy 401.005862 -141.052533) (xy 400.960013 -141.082001) (xy 400.910438 -141.104645)
			(xy 400.858145 -141.120005) (xy 400.804199 -141.127767) (xy 400.776948 -141.128242) (xy 400.748566 -141.127725)
			(xy 400.692427 -141.119319) (xy 400.638154 -141.102688) (xy 400.586945 -141.078196) (xy 400.539931 -141.046386)
			(xy 400.49815 -141.00796) (xy 400.462525 -140.963767) (xy 400.447764 -140.93952) (xy 400.440652 -140.927582)
			(xy 400.416776 -140.91412) (xy 400.300444 -140.91666) (xy 400.277076 -140.931138) (xy 400.270472 -140.94333)
			(xy 400.256163 -140.969217) (xy 400.220788 -141.016619) (xy 400.178521 -141.057993) (xy 400.130375 -141.092348)
			(xy 400.077503 -141.118859) (xy 400.021172 -141.136893) (xy 399.962733 -141.146015) (xy 399.93316 -141.14653)
			(xy 399.905909 -141.146041) (xy 399.851963 -141.13828) (xy 399.79967 -141.12292) (xy 399.750095 -141.100276)
			(xy 399.704246 -141.070807) (xy 399.663059 -141.035113) (xy 399.627369 -140.993921) (xy 399.597905 -140.94807)
			(xy 399.575266 -140.898493) (xy 399.559912 -140.846198) (xy 399.552156 -140.792251) (xy 399.552156 -140.737749)
			(xy 399.559912 -140.683802) (xy 399.575266 -140.631507) (xy 399.597905 -140.58193) (xy 399.627369 -140.536079)
			(xy 399.663059 -140.494887) (xy 399.704246 -140.459193) (xy 399.750095 -140.429724) (xy 399.79967 -140.40708)
			(xy 399.851963 -140.39172) (xy 399.905909 -140.383959) (xy 399.93316 -140.383514) (xy 399.961541 -140.384033)
			(xy 400.017678 -140.39244) (xy 400.071948 -140.409074) (xy 400.123153 -140.433568) (xy 400.170163 -140.465381)
			(xy 400.211938 -140.50381) (xy 400.247557 -140.548006) (xy 400.262344 -140.572236) (xy 400.269456 -140.584174)
			(xy 400.293332 -140.597636) (xy 400.409664 -140.595096) (xy 400.433032 -140.580618) (xy 400.439636 -140.568426)
			(xy 400.454289 -140.54195) (xy 400.49066 -140.49359) (xy 400.512026 -140.47216) (xy 400.540982 -140.447014)
			(xy 400.553682 -140.436854) (xy 400.562826 -140.405866) (xy 400.529806 -140.309854) (xy 400.525886 -140.300062)
			(xy 400.51162 -140.284556) (xy 400.492334 -140.276071) (xy 400.4818 -140.275564) (xy 397.860774 -140.275564)
			(xy 397.834696 -140.2751) (xy 397.783177 -140.266982) (xy 397.733562 -140.250903) (xy 397.687075 -140.22726)
			(xy 397.644859 -140.196633) (xy 397.626078 -140.178536) (xy 397.095472 -139.64793) (xy 397.088073 -139.641085)
			(xy 397.069475 -139.633356) (xy 397.059404 -139.632944) (xy 395.970252 -139.632944) (xy 395.960289 -139.633428)
			(xy 395.941864 -139.641016) (xy 395.934438 -139.647676) (xy 395.876272 -139.705334) (xy 395.868652 -139.723368)
			(xy 395.868652 -139.733782) (xy 395.868033 -139.760713) (xy 395.860144 -139.814) (xy 395.844831 -139.865645)
			(xy 395.822398 -139.914619) (xy 395.793294 -139.959948) (xy 395.758098 -140.000727) (xy 395.738096 -140.01877)
			(xy 395.730476 -140.025374) (xy 395.725904 -140.034518) (xy 395.723632 -140.039305) (xy 395.720934 -140.049552)
			(xy 395.72057 -140.054838) (xy 395.717522 -140.128498) (xy 395.717412 -140.133547) (xy 395.718941 -140.14353)
			(xy 395.72057 -140.14831) (xy 395.724126 -140.157962) (xy 395.745237 -140.17961) (xy 395.781033 -140.228338)
			(xy 395.8087 -140.2821) (xy 395.827543 -140.339552) (xy 395.837094 -140.399256) (xy 395.837664 -140.429488)
			(xy 395.837178 -140.456739) (xy 395.829422 -140.510687) (xy 395.814067 -140.562982) (xy 395.791425 -140.612559)
			(xy 395.761959 -140.658409) (xy 395.726268 -140.6996) (xy 395.685077 -140.735291) (xy 395.639227 -140.764757)
			(xy 395.58965 -140.787399) (xy 395.537355 -140.802754) (xy 395.483407 -140.81051) (xy 395.428905 -140.81051)
			(xy 395.374957 -140.802754) (xy 395.322662 -140.787399) (xy 395.273085 -140.764757) (xy 395.227235 -140.735291)
			(xy 395.186044 -140.6996) (xy 395.150353 -140.658409) (xy 395.120887 -140.612559) (xy 395.098245 -140.562982)
			(xy 395.08289 -140.510687) (xy 395.075134 -140.456739) (xy 395.074648 -140.429488) (xy 395.075107 -140.402345)
			(xy 395.082769 -140.348603) (xy 395.097978 -140.296491) (xy 395.120427 -140.247065) (xy 395.149662 -140.201324)
			(xy 395.18509 -140.160193) (xy 395.205204 -140.14196) (xy 395.212824 -140.135356) (xy 395.217396 -140.126212)
			(xy 395.219661 -140.121423) (xy 395.222344 -140.111176) (xy 395.22273 -140.105892) (xy 395.225778 -140.032232)
			(xy 395.225881 -140.027184) (xy 395.22434 -140.017206) (xy 395.22273 -140.01242) (xy 395.219174 -140.002768)
			(xy 395.198251 -139.981293) (xy 395.16269 -139.933026) (xy 395.135112 -139.879792) (xy 395.116196 -139.822902)
			(xy 395.106407 -139.763754) (xy 395.105636 -139.733782) (xy 395.105636 -139.723368) (xy 395.098016 -139.705334)
			(xy 395.03985 -139.647676) (xy 395.032442 -139.640987) (xy 395.014006 -139.63339) (xy 395.004036 -139.632944)
			(xy 387.528562 -139.632944) (xy 387.518496 -139.633375) (xy 387.499906 -139.641104) (xy 387.492494 -139.64793)
			(xy 386.110988 -141.029436) (xy 387.891272 -141.029436) (xy 387.895343 -140.973814) (xy 387.907469 -140.919377)
			(xy 387.927392 -140.867286) (xy 387.954688 -140.818651) (xy 387.988774 -140.774508) (xy 388.028923 -140.735799)
			(xy 388.074281 -140.703348) (xy 388.123881 -140.677847) (xy 388.176665 -140.65984) (xy 388.231508 -140.64971)
			(xy 388.287242 -140.647673) (xy 388.342679 -140.653773) (xy 388.396636 -140.667879) (xy 388.447965 -140.689691)
			(xy 388.495571 -140.718745) (xy 388.538439 -140.75442) (xy 388.575656 -140.795957) (xy 388.606429 -140.84247)
			(xy 388.630101 -140.892967) (xy 388.646169 -140.946374) (xy 388.654289 -141.00155) (xy 388.654798 -141.029436)
			(xy 388.654289 -141.057322) (xy 388.646169 -141.112498) (xy 388.630101 -141.165905) (xy 388.606429 -141.216402)
			(xy 388.575656 -141.262915) (xy 388.538439 -141.304452) (xy 388.495571 -141.340127) (xy 388.447965 -141.369181)
			(xy 388.396636 -141.390993) (xy 388.342679 -141.405099) (xy 388.287242 -141.411199) (xy 388.231508 -141.409162)
			(xy 388.176665 -141.399032) (xy 388.123881 -141.381025) (xy 388.074281 -141.355524) (xy 388.028923 -141.323073)
			(xy 387.988774 -141.284364) (xy 387.954688 -141.240221) (xy 387.927392 -141.191586) (xy 387.907469 -141.139495)
			(xy 387.895343 -141.085058) (xy 387.891272 -141.029436) (xy 386.110988 -141.029436) (xy 384.662934 -142.47749)
			(xy 384.655568 -142.484602) (xy 384.647948 -142.503398) (xy 384.647948 -142.748762) (xy 387.818882 -142.748762)
			(xy 387.822953 -142.69314) (xy 387.835079 -142.638703) (xy 387.855002 -142.586612) (xy 387.882298 -142.537977)
			(xy 387.916384 -142.493834) (xy 387.956533 -142.455125) (xy 388.001891 -142.422674) (xy 388.051491 -142.397173)
			(xy 388.104275 -142.379166) (xy 388.159118 -142.369036) (xy 388.214852 -142.366999) (xy 388.270289 -142.373099)
			(xy 388.324246 -142.387205) (xy 388.375575 -142.409017) (xy 388.423181 -142.438071) (xy 388.466049 -142.473746)
			(xy 388.503266 -142.515283) (xy 388.534039 -142.561796) (xy 388.557711 -142.612293) (xy 388.573779 -142.6657)
			(xy 388.581899 -142.720876) (xy 388.582408 -142.748762) (xy 388.581899 -142.776648) (xy 388.573779 -142.831824)
			(xy 388.565145 -142.860522) (xy 394.933678 -142.860522) (xy 394.934203 -142.83184) (xy 394.942811 -142.775124)
			(xy 394.959807 -142.720334) (xy 394.984808 -142.668703) (xy 395.017251 -142.621393) (xy 395.056407 -142.579469)
			(xy 395.101393 -142.543874) (xy 395.151199 -142.51541) (xy 395.204702 -142.494716) (xy 395.260698 -142.48226)
			(xy 395.289278 -142.479776) (xy 395.303769 -142.478234) (xy 395.33107 -142.468086) (xy 395.354397 -142.450646)
			(xy 395.371854 -142.42733) (xy 395.382019 -142.400036) (xy 395.383512 -142.385542) (xy 395.385993 -142.356958)
			(xy 395.398422 -142.300947) (xy 395.419097 -142.247428) (xy 395.447552 -142.197608) (xy 395.483146 -142.15261)
			(xy 395.525075 -142.113449) (xy 395.572395 -142.081006) (xy 395.624039 -142.056014) (xy 395.678843 -142.039036)
			(xy 395.735571 -142.030454) (xy 395.764258 -142.029942) (xy 395.791512 -142.030395) (xy 395.845466 -142.038147)
			(xy 395.897767 -142.0535) (xy 395.94735 -142.076142) (xy 395.993206 -142.10561) (xy 396.034401 -142.141305)
			(xy 396.070095 -142.1825) (xy 396.099562 -142.228357) (xy 396.122202 -142.27794) (xy 396.137555 -142.330242)
			(xy 396.145306 -142.384196) (xy 396.145766 -142.41145) (xy 396.145266 -142.440132) (xy 396.136649 -142.496847)
			(xy 396.119646 -142.551635) (xy 396.095891 -142.60068) (xy 399.905728 -142.60068) (xy 399.906192 -142.573275)
			(xy 399.914043 -142.519031) (xy 399.92958 -142.466469) (xy 399.952483 -142.416674) (xy 399.982281 -142.370671)
			(xy 399.999962 -142.349728) (xy 400.006058 -142.342616) (xy 400.012408 -142.325598) (xy 400.012408 -142.24)
			(xy 400.006058 -142.222982) (xy 399.999962 -142.21587) (xy 399.98229 -142.19492) (xy 399.952493 -142.148919)
			(xy 399.929591 -142.099125) (xy 399.914055 -142.046565) (xy 399.906204 -141.992322) (xy 399.905728 -141.964918)
			(xy 399.906214 -141.937667) (xy 399.91397 -141.883719) (xy 399.929325 -141.831424) (xy 399.951967 -141.781847)
			(xy 399.981433 -141.735997) (xy 400.017124 -141.694806) (xy 400.058315 -141.659115) (xy 400.104165 -141.629649)
			(xy 400.153742 -141.607007) (xy 400.206037 -141.591652) (xy 400.259985 -141.583896) (xy 400.314487 -141.583896)
			(xy 400.368435 -141.591652) (xy 400.42073 -141.607007) (xy 400.470307 -141.629649) (xy 400.516157 -141.659115)
			(xy 400.557348 -141.694806) (xy 400.593039 -141.735997) (xy 400.622505 -141.781847) (xy 400.645147 -141.831424)
			(xy 400.660502 -141.883719) (xy 400.668258 -141.937667) (xy 400.668744 -141.964918) (xy 400.668286 -141.992323)
			(xy 400.660434 -142.046568) (xy 400.644896 -142.09913) (xy 400.621992 -142.148925) (xy 400.592192 -142.194927)
			(xy 400.57451 -142.21587) (xy 400.568414 -142.222982) (xy 400.562064 -142.24) (xy 400.562064 -142.325598)
			(xy 400.568414 -142.342616) (xy 400.57451 -142.349728) (xy 400.589072 -142.367) (xy 401.882862 -142.367)
			(xy 401.886933 -142.311378) (xy 401.899059 -142.256941) (xy 401.918982 -142.20485) (xy 401.946278 -142.156215)
			(xy 401.980364 -142.112072) (xy 402.020513 -142.073363) (xy 402.065871 -142.040912) (xy 402.115471 -142.015411)
			(xy 402.168255 -141.997404) (xy 402.223098 -141.987274) (xy 402.278832 -141.985237) (xy 402.334269 -141.991337)
			(xy 402.388226 -142.005443) (xy 402.439555 -142.027255) (xy 402.487161 -142.056309) (xy 402.530029 -142.091984)
			(xy 402.567246 -142.133521) (xy 402.598019 -142.180034) (xy 402.621691 -142.230531) (xy 402.637759 -142.283938)
			(xy 402.645879 -142.339114) (xy 402.646388 -142.367) (xy 402.645879 -142.394886) (xy 402.637759 -142.450062)
			(xy 402.621691 -142.503469) (xy 402.598019 -142.553966) (xy 402.567246 -142.600479) (xy 402.530029 -142.642016)
			(xy 402.487161 -142.677691) (xy 402.439555 -142.706745) (xy 402.388226 -142.728557) (xy 402.334269 -142.742663)
			(xy 402.278832 -142.748763) (xy 402.223098 -142.746726) (xy 402.168255 -142.736596) (xy 402.115471 -142.718589)
			(xy 402.065871 -142.693088) (xy 402.020513 -142.660637) (xy 401.980364 -142.621928) (xy 401.946278 -142.577785)
			(xy 401.918982 -142.52915) (xy 401.899059 -142.477059) (xy 401.886933 -142.422622) (xy 401.882862 -142.367)
			(xy 400.589072 -142.367) (xy 400.592177 -142.370683) (xy 400.621975 -142.416682) (xy 400.644879 -142.466475)
			(xy 400.660417 -142.519034) (xy 400.668268 -142.573276) (xy 400.668744 -142.60068) (xy 400.668258 -142.627931)
			(xy 400.660502 -142.681879) (xy 400.645147 -142.734174) (xy 400.622505 -142.783751) (xy 400.593039 -142.829601)
			(xy 400.557348 -142.870792) (xy 400.516157 -142.906483) (xy 400.470307 -142.935949) (xy 400.42073 -142.958591)
			(xy 400.368435 -142.973946) (xy 400.314487 -142.981702) (xy 400.259985 -142.981702) (xy 400.206037 -142.973946)
			(xy 400.153742 -142.958591) (xy 400.104165 -142.935949) (xy 400.058315 -142.906483) (xy 400.017124 -142.870792)
			(xy 399.981433 -142.829601) (xy 399.951967 -142.783751) (xy 399.929325 -142.734174) (xy 399.91397 -142.681879)
			(xy 399.906214 -142.627931) (xy 399.905728 -142.60068) (xy 396.095891 -142.60068) (xy 396.09464 -142.603263)
			(xy 396.062193 -142.650571) (xy 396.023036 -142.692494) (xy 395.978049 -142.728088) (xy 395.928244 -142.756553)
			(xy 395.874741 -142.777249) (xy 395.818745 -142.789709) (xy 395.790166 -142.792196) (xy 395.775659 -142.79363)
			(xy 395.748348 -142.8038) (xy 395.725018 -142.821266) (xy 395.707567 -142.844608) (xy 395.697415 -142.871926)
			(xy 395.695932 -142.88643) (xy 395.693482 -142.915018) (xy 395.681054 -142.971033) (xy 395.660379 -143.024556)
			(xy 395.631922 -143.074379) (xy 395.596325 -143.11938) (xy 395.554392 -143.158542) (xy 395.507066 -143.190984)
			(xy 395.455417 -143.215973) (xy 395.400608 -143.232947) (xy 395.343875 -143.241522) (xy 395.315186 -143.24203)
			(xy 395.287935 -143.241535) (xy 395.233989 -143.233777) (xy 395.181696 -143.218422) (xy 395.13212 -143.19578)
			(xy 395.086271 -143.166315) (xy 395.045081 -143.130624) (xy 395.00939 -143.089436) (xy 394.979923 -143.043587)
			(xy 394.957281 -142.994012) (xy 394.941924 -142.941719) (xy 394.934165 -142.887773) (xy 394.933678 -142.860522)
			(xy 388.565145 -142.860522) (xy 388.557711 -142.885231) (xy 388.534039 -142.935728) (xy 388.503266 -142.982241)
			(xy 388.466049 -143.023778) (xy 388.423181 -143.059453) (xy 388.375575 -143.088507) (xy 388.324246 -143.110319)
			(xy 388.270289 -143.124425) (xy 388.214852 -143.130525) (xy 388.159118 -143.128488) (xy 388.104275 -143.118358)
			(xy 388.051491 -143.100351) (xy 388.001891 -143.07485) (xy 387.956533 -143.042399) (xy 387.916384 -143.00369)
			(xy 387.882298 -142.959547) (xy 387.855002 -142.910912) (xy 387.835079 -142.858821) (xy 387.822953 -142.804384)
			(xy 387.818882 -142.748762) (xy 384.647948 -142.748762) (xy 384.647948 -145.329148) (xy 391.465308 -145.329148)
			(xy 391.465774 -145.302766) (xy 391.473059 -145.250508) (xy 391.487469 -145.19975) (xy 391.50873 -145.151459)
			(xy 391.536436 -145.106555) (xy 391.57006 -145.065893) (xy 391.608963 -145.030247) (xy 391.652402 -145.000297)
			(xy 391.699551 -144.976611) (xy 391.724388 -144.967706) (xy 391.733532 -144.964658) (xy 391.747756 -144.952974)
			(xy 391.790428 -144.876266) (xy 391.792968 -144.857978) (xy 391.790682 -144.84858) (xy 391.786023 -144.827167)
			(xy 391.781055 -144.783625) (xy 391.780776 -144.761712) (xy 391.781289 -144.734462) (xy 391.789044 -144.680516)
			(xy 391.804397 -144.628223) (xy 391.827035 -144.578647) (xy 391.856499 -144.532797) (xy 391.892187 -144.491607)
			(xy 391.933375 -144.455915) (xy 391.979222 -144.426449) (xy 392.028796 -144.403806) (xy 392.081089 -144.38845)
			(xy 392.135034 -144.380691) (xy 392.162284 -144.380204) (xy 392.174255 -144.38032) (xy 392.198148 -144.381842)
			(xy 392.210036 -144.383252) (xy 392.219688 -144.384522) (xy 392.237468 -144.37995) (xy 392.309096 -144.330166)
			(xy 392.31951 -144.314926) (xy 392.321796 -144.305528) (xy 392.328784 -144.277975) (xy 392.349819 -144.225168)
			(xy 392.378459 -144.176068) (xy 392.414069 -144.131763) (xy 392.455861 -144.093235) (xy 392.502909 -144.061337)
			(xy 392.55417 -144.036775) (xy 392.60851 -144.020094) (xy 392.664723 -144.011663) (xy 392.693144 -144.011142)
			(xy 392.717815 -144.011556) (xy 392.766741 -144.017956) (xy 392.814436 -144.030605) (xy 392.837416 -144.03959)
			(xy 392.848592 -144.043908) (xy 392.872214 -144.042384) (xy 392.962638 -143.98879) (xy 392.975338 -143.968978)
			(xy 392.976862 -143.956786) (xy 392.980529 -143.929214) (xy 392.994763 -143.875448) (xy 393.016658 -143.824319)
			(xy 393.045747 -143.776914) (xy 393.081414 -143.734237) (xy 393.122903 -143.697195) (xy 393.169333 -143.666572)
			(xy 393.219718 -143.643019) (xy 393.272991 -143.627035) (xy 393.328021 -143.61896) (xy 393.35583 -143.618458)
			(xy 393.38308 -143.61895) (xy 393.437026 -143.62671) (xy 393.489319 -143.642067) (xy 393.538894 -143.664709)
			(xy 393.584742 -143.694175) (xy 393.625931 -143.729866) (xy 393.661622 -143.771054) (xy 393.691089 -143.816903)
			(xy 393.713732 -143.866478) (xy 393.72909 -143.91877) (xy 393.73685 -143.972716) (xy 393.737338 -143.999966)
			(xy 393.736862 -144.026547) (xy 393.72948 -144.079193) (xy 393.714855 -144.130303) (xy 393.693271 -144.178885)
			(xy 393.665146 -144.223998) (xy 393.631026 -144.264764) (xy 393.611608 -144.282922) (xy 393.604496 -144.289272)
			(xy 393.596368 -144.305528) (xy 393.586462 -144.391126) (xy 393.591034 -144.408652) (xy 393.596368 -144.416272)
			(xy 393.612484 -144.440397) (xy 393.638018 -144.492491) (xy 393.655375 -144.547849) (xy 393.664154 -144.605196)
			(xy 393.664694 -144.634204) (xy 393.664248 -144.661458) (xy 393.65649 -144.71541) (xy 393.641133 -144.767709)
			(xy 393.618489 -144.81729) (xy 393.58902 -144.863144) (xy 393.553324 -144.904337) (xy 393.512129 -144.94003)
			(xy 393.466274 -144.969498) (xy 393.416692 -144.99214) (xy 393.364392 -145.007494) (xy 393.31044 -145.01525)
			(xy 393.283186 -145.015712) (xy 393.273262 -145.015658) (xy 393.25344 -145.014641) (xy 393.243562 -145.01368)
			(xy 393.23391 -145.012664) (xy 393.215622 -145.017744) (xy 393.14501 -145.070068) (xy 393.135104 -145.086324)
			(xy 393.133326 -145.095722) (xy 393.127934 -145.12156) (xy 393.111003 -145.171551) (xy 393.087342 -145.218731)
			(xy 393.057405 -145.2622) (xy 393.021762 -145.301128) (xy 392.981094 -145.334771) (xy 392.936177 -145.362489)
			(xy 392.887869 -145.38375) (xy 392.837091 -145.398151) (xy 392.784812 -145.405415) (xy 392.758422 -145.405856)
			(xy 392.729473 -145.405315) (xy 392.672242 -145.396543) (xy 392.616992 -145.379227) (xy 392.564992 -145.353765)
			(xy 392.517435 -145.32074) (xy 392.475411 -145.280911) (xy 392.439885 -145.235192) (xy 392.411672 -145.184631)
			(xy 392.401044 -145.157698) (xy 392.397046 -145.148307) (xy 392.383026 -145.133498) (xy 392.373866 -145.128996)
			(xy 392.344656 -145.116042) (xy 392.335124 -145.112305) (xy 392.314666 -145.112061) (xy 392.305032 -145.115534)
			(xy 392.284712 -145.123154) (xy 392.275568 -145.126202) (xy 392.261344 -145.137886) (xy 392.218672 -145.214594)
			(xy 392.216132 -145.232882) (xy 392.218418 -145.24228) (xy 392.223087 -145.263691) (xy 392.228049 -145.307235)
			(xy 392.228324 -145.329148) (xy 392.227838 -145.356399) (xy 392.220082 -145.410347) (xy 392.204727 -145.462642)
			(xy 392.182085 -145.512219) (xy 392.152619 -145.558069) (xy 392.116928 -145.59926) (xy 392.075737 -145.634951)
			(xy 392.029887 -145.664417) (xy 391.98031 -145.687059) (xy 391.928015 -145.702414) (xy 391.874067 -145.71017)
			(xy 391.819565 -145.71017) (xy 391.765617 -145.702414) (xy 391.713322 -145.687059) (xy 391.663745 -145.664417)
			(xy 391.617895 -145.634951) (xy 391.576704 -145.59926) (xy 391.541013 -145.558069) (xy 391.511547 -145.512219)
			(xy 391.488905 -145.462642) (xy 391.47355 -145.410347) (xy 391.465794 -145.356399) (xy 391.465308 -145.329148)
			(xy 384.647948 -145.329148) (xy 384.647948 -145.821908) (xy 395.071092 -145.821908) (xy 395.071684 -145.793229)
			(xy 395.080292 -145.73652) (xy 395.097285 -145.681736) (xy 395.12228 -145.630111) (xy 395.154717 -145.582804)
			(xy 395.193864 -145.540882) (xy 395.238841 -145.505286) (xy 395.288636 -145.476818) (xy 395.342129 -145.456118)
			(xy 395.398116 -145.443652) (xy 395.426692 -145.441162) (xy 395.441186 -145.439643) (xy 395.46849 -145.429491)
			(xy 395.491817 -145.412045) (xy 395.509272 -145.388724) (xy 395.519435 -145.361424) (xy 395.520926 -145.346928)
			(xy 395.523381 -145.318341) (xy 395.535813 -145.262329) (xy 395.556491 -145.208809) (xy 395.584949 -145.158988)
			(xy 395.620545 -145.11399) (xy 395.662478 -145.074829) (xy 395.709801 -145.042387) (xy 395.761447 -145.017396)
			(xy 395.816254 -145.000419) (xy 395.872984 -144.991839) (xy 395.901672 -144.991328) (xy 395.928926 -144.991781)
			(xy 395.982879 -144.999536) (xy 396.035179 -145.01489) (xy 396.084762 -145.037532) (xy 396.130617 -145.067)
			(xy 396.171811 -145.102695) (xy 396.207505 -145.14389) (xy 396.236972 -145.189745) (xy 396.259613 -145.239328)
			(xy 396.274966 -145.291629) (xy 396.282719 -145.345582) (xy 396.28318 -145.372836) (xy 396.282655 -145.401517)
			(xy 396.27404 -145.45823) (xy 396.257039 -145.513017) (xy 396.232036 -145.564644) (xy 396.199592 -145.611952)
			(xy 396.160438 -145.653874) (xy 396.115453 -145.689469) (xy 396.065651 -145.717935) (xy 396.012152 -145.738632)
			(xy 395.956158 -145.751094) (xy 395.92758 -145.753582) (xy 395.913076 -145.755039) (xy 395.885767 -145.765204)
			(xy 395.862438 -145.782665) (xy 395.844986 -145.806001) (xy 395.834831 -145.833314) (xy 395.833346 -145.847816)
			(xy 395.83087 -145.876401) (xy 395.818445 -145.932415) (xy 395.797773 -145.985937) (xy 395.769319 -146.035759)
			(xy 395.733725 -146.080759) (xy 395.691794 -146.119922) (xy 395.644472 -146.152365) (xy 395.638704 -146.155156)
			(xy 399.668492 -146.155156) (xy 399.668993 -146.127787) (xy 399.676803 -146.07361) (xy 399.692284 -146.021107)
			(xy 399.715118 -145.971359) (xy 399.744834 -145.925391) (xy 399.762472 -145.904458) (xy 399.768568 -145.897346)
			(xy 399.774918 -145.880328) (xy 399.774918 -145.794984) (xy 399.768568 -145.777966) (xy 399.762472 -145.770854)
			(xy 399.744786 -145.749957) (xy 399.71506 -145.703984) (xy 399.692214 -145.654232) (xy 399.67672 -145.601724)
			(xy 399.668894 -145.54754) (xy 399.668899 -145.492794) (xy 399.676734 -145.438611) (xy 399.692238 -145.386106)
			(xy 399.715092 -145.336358) (xy 399.744826 -145.29039) (xy 399.762472 -145.269458) (xy 399.768568 -145.262346)
			(xy 399.774918 -145.245328) (xy 399.774918 -145.159984) (xy 399.768568 -145.142966) (xy 399.762472 -145.135854)
			(xy 399.744786 -145.114957) (xy 399.71506 -145.068984) (xy 399.692214 -145.019232) (xy 399.67672 -144.966724)
			(xy 399.668894 -144.91254) (xy 399.668899 -144.857794) (xy 399.676734 -144.803611) (xy 399.692238 -144.751106)
			(xy 399.715092 -144.701358) (xy 399.744826 -144.65539) (xy 399.762472 -144.634458) (xy 399.768568 -144.627346)
			(xy 399.774918 -144.610328) (xy 399.774918 -144.524984) (xy 399.768568 -144.507966) (xy 399.762472 -144.500854)
			(xy 399.744786 -144.479957) (xy 399.71506 -144.433984) (xy 399.692214 -144.384232) (xy 399.67672 -144.331724)
			(xy 399.668894 -144.27754) (xy 399.668899 -144.222794) (xy 399.676734 -144.168611) (xy 399.692238 -144.116106)
			(xy 399.715092 -144.066358) (xy 399.744826 -144.02039) (xy 399.762472 -143.999458) (xy 399.768568 -143.992346)
			(xy 399.774918 -143.975328) (xy 399.774918 -143.889984) (xy 399.768568 -143.872966) (xy 399.762472 -143.865854)
			(xy 399.74484 -143.844916) (xy 399.715128 -143.798944) (xy 399.692291 -143.749198) (xy 399.676799 -143.696699)
			(xy 399.668968 -143.642525) (xy 399.668492 -143.615156) (xy 399.668978 -143.587905) (xy 399.676734 -143.533957)
			(xy 399.692089 -143.481662) (xy 399.714731 -143.432085) (xy 399.744197 -143.386235) (xy 399.779888 -143.345044)
			(xy 399.821079 -143.309353) (xy 399.866929 -143.279887) (xy 399.916506 -143.257245) (xy 399.968801 -143.24189)
			(xy 400.022749 -143.234134) (xy 400.077251 -143.234134) (xy 400.131199 -143.24189) (xy 400.183494 -143.257245)
			(xy 400.233071 -143.279887) (xy 400.278921 -143.309353) (xy 400.320112 -143.345044) (xy 400.355803 -143.386235)
			(xy 400.385269 -143.432085) (xy 400.407911 -143.481662) (xy 400.423266 -143.533957) (xy 400.431022 -143.587905)
			(xy 400.431508 -143.615156) (xy 400.431014 -143.642525) (xy 400.423203 -143.696703) (xy 400.40772 -143.749206)
			(xy 400.384885 -143.798953) (xy 400.355166 -143.844921) (xy 400.337528 -143.865854) (xy 400.331432 -143.872966)
			(xy 400.325082 -143.889984) (xy 400.325082 -143.975328) (xy 400.331432 -143.992346) (xy 400.337528 -143.999458)
			(xy 400.355127 -144.020425) (xy 400.384857 -144.066386) (xy 400.407708 -144.116126) (xy 400.42321 -144.168623)
			(xy 400.431043 -144.222798) (xy 400.431047 -144.272) (xy 404.687022 -144.272) (xy 404.691093 -144.216378)
			(xy 404.703219 -144.161941) (xy 404.723142 -144.10985) (xy 404.750438 -144.061215) (xy 404.784524 -144.017072)
			(xy 404.824673 -143.978363) (xy 404.870031 -143.945912) (xy 404.919631 -143.920411) (xy 404.972415 -143.902404)
			(xy 405.027258 -143.892274) (xy 405.082992 -143.890237) (xy 405.138429 -143.896337) (xy 405.192386 -143.910443)
			(xy 405.243715 -143.932255) (xy 405.291321 -143.961309) (xy 405.334189 -143.996984) (xy 405.371406 -144.038521)
			(xy 405.402179 -144.085034) (xy 405.425851 -144.135531) (xy 405.441919 -144.188938) (xy 405.450039 -144.244114)
			(xy 405.450548 -144.272) (xy 405.450039 -144.299886) (xy 405.441919 -144.355062) (xy 405.425851 -144.408469)
			(xy 405.402179 -144.458966) (xy 405.371406 -144.505479) (xy 405.334189 -144.547016) (xy 405.291321 -144.582691)
			(xy 405.243715 -144.611745) (xy 405.192386 -144.633557) (xy 405.138429 -144.647663) (xy 405.082992 -144.653763)
			(xy 405.027258 -144.651726) (xy 404.972415 -144.641596) (xy 404.919631 -144.623589) (xy 404.870031 -144.598088)
			(xy 404.824673 -144.565637) (xy 404.784524 -144.526928) (xy 404.750438 -144.482785) (xy 404.723142 -144.43415)
			(xy 404.703219 -144.382059) (xy 404.691093 -144.327622) (xy 404.687022 -144.272) (xy 400.431047 -144.272)
			(xy 400.431048 -144.277536) (xy 400.423224 -144.331712) (xy 400.407731 -144.384212) (xy 400.384889 -144.433956)
			(xy 400.355167 -144.479922) (xy 400.337528 -144.500854) (xy 400.331432 -144.507966) (xy 400.325082 -144.524984)
			(xy 400.325082 -144.610328) (xy 400.331432 -144.627346) (xy 400.337528 -144.634458) (xy 400.355127 -144.655425)
			(xy 400.384857 -144.701386) (xy 400.407708 -144.751126) (xy 400.42321 -144.803623) (xy 400.431043 -144.857798)
			(xy 400.431048 -144.912536) (xy 400.423224 -144.966712) (xy 400.407731 -145.019212) (xy 400.384889 -145.068956)
			(xy 400.355167 -145.114922) (xy 400.337528 -145.135854) (xy 400.331432 -145.142966) (xy 400.325082 -145.159984)
			(xy 400.325082 -145.245328) (xy 400.331432 -145.262346) (xy 400.337528 -145.269458) (xy 400.355127 -145.290425)
			(xy 400.384857 -145.336386) (xy 400.407708 -145.386126) (xy 400.42321 -145.438623) (xy 400.431043 -145.492798)
			(xy 400.431048 -145.547536) (xy 400.423224 -145.601712) (xy 400.407731 -145.654212) (xy 400.384889 -145.703956)
			(xy 400.355167 -145.749922) (xy 400.337528 -145.770854) (xy 400.331432 -145.777966) (xy 400.325082 -145.794984)
			(xy 400.325082 -145.880328) (xy 400.331432 -145.897346) (xy 400.337528 -145.904458) (xy 400.355165 -145.925391)
			(xy 400.384876 -145.971364) (xy 400.407712 -146.021112) (xy 400.423204 -146.073612) (xy 400.431033 -146.127787)
			(xy 400.431508 -146.155156) (xy 400.431022 -146.182407) (xy 400.423266 -146.236355) (xy 400.407911 -146.28865)
			(xy 400.385269 -146.338227) (xy 400.355803 -146.384077) (xy 400.320112 -146.425268) (xy 400.278921 -146.460959)
			(xy 400.233071 -146.490425) (xy 400.183494 -146.513067) (xy 400.131199 -146.528422) (xy 400.077251 -146.536178)
			(xy 400.022749 -146.536178) (xy 399.968801 -146.528422) (xy 399.916506 -146.513067) (xy 399.866929 -146.490425)
			(xy 399.821079 -146.460959) (xy 399.779888 -146.425268) (xy 399.744197 -146.384077) (xy 399.714731 -146.338227)
			(xy 399.692089 -146.28865) (xy 399.676734 -146.236355) (xy 399.668978 -146.182407) (xy 399.668492 -146.155156)
			(xy 395.638704 -146.155156) (xy 395.592825 -146.177355) (xy 395.538018 -146.19433) (xy 395.481288 -146.202907)
			(xy 395.4526 -146.203416) (xy 395.425349 -146.202922) (xy 395.371402 -146.195166) (xy 395.319108 -146.179811)
			(xy 395.269531 -146.157171) (xy 395.223681 -146.127705) (xy 395.182491 -146.092014) (xy 395.1468 -146.050825)
			(xy 395.117333 -146.004976) (xy 395.094692 -145.9554) (xy 395.079336 -145.903106) (xy 395.071578 -145.849159)
			(xy 395.071092 -145.821908) (xy 384.647948 -145.821908) (xy 384.647948 -146.739864) (xy 397.210024 -146.739864)
			(xy 397.214095 -146.684242) (xy 397.226221 -146.629805) (xy 397.246144 -146.577714) (xy 397.27344 -146.529079)
			(xy 397.307526 -146.484936) (xy 397.347675 -146.446227) (xy 397.393033 -146.413776) (xy 397.442633 -146.388275)
			(xy 397.495417 -146.370268) (xy 397.55026 -146.360138) (xy 397.605994 -146.358101) (xy 397.661431 -146.364201)
			(xy 397.715388 -146.378307) (xy 397.766717 -146.400119) (xy 397.814323 -146.429173) (xy 397.857191 -146.464848)
			(xy 397.894408 -146.506385) (xy 397.925181 -146.552898) (xy 397.948853 -146.603395) (xy 397.964921 -146.656802)
			(xy 397.973041 -146.711978) (xy 397.97355 -146.739864) (xy 397.973041 -146.76775) (xy 397.968884 -146.795998)
			(xy 398.843752 -146.795998) (xy 398.847823 -146.740376) (xy 398.859949 -146.685939) (xy 398.879872 -146.633848)
			(xy 398.907168 -146.585213) (xy 398.941254 -146.54107) (xy 398.981403 -146.502361) (xy 399.026761 -146.46991)
			(xy 399.076361 -146.444409) (xy 399.129145 -146.426402) (xy 399.183988 -146.416272) (xy 399.239722 -146.414235)
			(xy 399.295159 -146.420335) (xy 399.349116 -146.434441) (xy 399.400445 -146.456253) (xy 399.448051 -146.485307)
			(xy 399.490919 -146.520982) (xy 399.528136 -146.562519) (xy 399.558909 -146.609032) (xy 399.582581 -146.659529)
			(xy 399.598649 -146.712936) (xy 399.606769 -146.768112) (xy 399.607278 -146.795998) (xy 399.606769 -146.823884)
			(xy 399.598649 -146.87906) (xy 399.582581 -146.932467) (xy 399.558909 -146.982964) (xy 399.528136 -147.029477)
			(xy 399.490919 -147.071014) (xy 399.448051 -147.106689) (xy 399.400445 -147.135743) (xy 399.349116 -147.157555)
			(xy 399.295159 -147.171661) (xy 399.239722 -147.177761) (xy 399.183988 -147.175724) (xy 399.129145 -147.165594)
			(xy 399.076361 -147.147587) (xy 399.026761 -147.122086) (xy 398.981403 -147.089635) (xy 398.941254 -147.050926)
			(xy 398.907168 -147.006783) (xy 398.879872 -146.958148) (xy 398.859949 -146.906057) (xy 398.847823 -146.85162)
			(xy 398.843752 -146.795998) (xy 397.968884 -146.795998) (xy 397.964921 -146.822926) (xy 397.948853 -146.876333)
			(xy 397.925181 -146.92683) (xy 397.894408 -146.973343) (xy 397.857191 -147.01488) (xy 397.814323 -147.050555)
			(xy 397.766717 -147.079609) (xy 397.715388 -147.101421) (xy 397.661431 -147.115527) (xy 397.605994 -147.121627)
			(xy 397.55026 -147.11959) (xy 397.495417 -147.10946) (xy 397.442633 -147.091453) (xy 397.393033 -147.065952)
			(xy 397.347675 -147.033501) (xy 397.307526 -146.994792) (xy 397.27344 -146.950649) (xy 397.246144 -146.902014)
			(xy 397.226221 -146.849923) (xy 397.214095 -146.795486) (xy 397.210024 -146.739864) (xy 384.647948 -146.739864)
			(xy 384.647948 -148.368528) (xy 391.5128 -148.368528) (xy 391.5128 -148.281628) (xy 391.520818 -148.195099)
			(xy 391.536786 -148.109679) (xy 391.560567 -148.026097) (xy 391.591959 -147.945065) (xy 391.630693 -147.867276)
			(xy 391.67644 -147.793392) (xy 391.728809 -147.724045) (xy 391.787353 -147.659825) (xy 391.851573 -147.601281)
			(xy 391.92092 -147.548912) (xy 391.994804 -147.503165) (xy 392.072593 -147.464431) (xy 392.153625 -147.433039)
			(xy 392.237207 -147.409258) (xy 392.322627 -147.39329) (xy 392.409156 -147.385272) (xy 392.496056 -147.385272)
			(xy 392.582585 -147.39329) (xy 392.668005 -147.409258) (xy 392.751587 -147.433039) (xy 392.832619 -147.464431)
			(xy 392.910408 -147.503165) (xy 392.984292 -147.548912) (xy 393.053639 -147.601281) (xy 393.117859 -147.659825)
			(xy 393.176403 -147.724045) (xy 393.228772 -147.793392) (xy 393.274519 -147.867276) (xy 393.313253 -147.945065)
			(xy 393.344645 -148.026097) (xy 393.368426 -148.109679) (xy 393.384394 -148.195099) (xy 393.392412 -148.281628)
			(xy 393.392914 -148.325078) (xy 393.392412 -148.368528) (xy 393.392411 -148.368539) (xy 394.775926 -148.368539)
			(xy 394.775926 -148.281661) (xy 394.783942 -148.195154) (xy 394.799905 -148.109756) (xy 394.82368 -148.026194)
			(xy 394.855064 -147.945183) (xy 394.893788 -147.867413) (xy 394.939523 -147.793548) (xy 394.991879 -147.724218)
			(xy 395.050407 -147.660014) (xy 395.11461 -147.601485) (xy 395.18394 -147.549129) (xy 395.257805 -147.503393)
			(xy 395.335574 -147.464668) (xy 395.416585 -147.433283) (xy 395.500146 -147.409508) (xy 395.585544 -147.393543)
			(xy 395.672051 -147.385526) (xy 395.71549 -147.385024) (xy 397.56969 -147.385024) (xy 397.613128 -147.385554)
			(xy 397.699634 -147.393569) (xy 397.785031 -147.409532) (xy 397.868591 -147.433306) (xy 397.949601 -147.464689)
			(xy 398.027369 -147.503412) (xy 398.101233 -147.549146) (xy 398.170562 -147.6015) (xy 398.234765 -147.660028)
			(xy 398.293293 -147.72423) (xy 398.345648 -147.793558) (xy 398.391383 -147.867422) (xy 398.430107 -147.94519)
			(xy 398.461491 -148.0262) (xy 398.485266 -148.109759) (xy 398.501229 -148.195156) (xy 398.509245 -148.281662)
			(xy 398.509245 -148.368528) (xy 398.88261 -148.368528) (xy 398.88261 -148.281628) (xy 398.890628 -148.195099)
			(xy 398.906596 -148.109679) (xy 398.930377 -148.026097) (xy 398.961769 -147.945065) (xy 399.000503 -147.867276)
			(xy 399.04625 -147.793392) (xy 399.098619 -147.724045) (xy 399.157163 -147.659825) (xy 399.221383 -147.601281)
			(xy 399.29073 -147.548912) (xy 399.364614 -147.503165) (xy 399.442403 -147.464431) (xy 399.523435 -147.433039)
			(xy 399.607017 -147.409258) (xy 399.692437 -147.39329) (xy 399.778966 -147.385272) (xy 399.865866 -147.385272)
			(xy 399.952395 -147.39329) (xy 400.037815 -147.409258) (xy 400.121397 -147.433039) (xy 400.202429 -147.464431)
			(xy 400.280218 -147.503165) (xy 400.354102 -147.548912) (xy 400.423449 -147.601281) (xy 400.487669 -147.659825)
			(xy 400.546213 -147.724045) (xy 400.598582 -147.793392) (xy 400.644329 -147.867276) (xy 400.683063 -147.945065)
			(xy 400.714455 -148.026097) (xy 400.738236 -148.109679) (xy 400.754204 -148.195099) (xy 400.762222 -148.281628)
			(xy 400.762724 -148.325078) (xy 400.762222 -148.368528) (xy 400.754204 -148.455057) (xy 400.738236 -148.540477)
			(xy 400.714455 -148.624059) (xy 400.683063 -148.705091) (xy 400.644329 -148.78288) (xy 400.598582 -148.856764)
			(xy 400.546213 -148.926111) (xy 400.487669 -148.990331) (xy 400.423449 -149.048875) (xy 400.354102 -149.101244)
			(xy 400.280218 -149.146991) (xy 400.202429 -149.185725) (xy 400.121397 -149.217117) (xy 400.037815 -149.240898)
			(xy 399.952395 -149.256866) (xy 399.865866 -149.264884) (xy 399.778966 -149.264884) (xy 399.692437 -149.256866)
			(xy 399.607017 -149.240898) (xy 399.523435 -149.217117) (xy 399.442403 -149.185725) (xy 399.364614 -149.146991)
			(xy 399.29073 -149.101244) (xy 399.221383 -149.048875) (xy 399.157163 -148.990331) (xy 399.098619 -148.926111)
			(xy 399.04625 -148.856764) (xy 399.000503 -148.78288) (xy 398.961769 -148.705091) (xy 398.930377 -148.624059)
			(xy 398.906596 -148.540477) (xy 398.890628 -148.455057) (xy 398.88261 -148.368528) (xy 398.509245 -148.368528)
			(xy 398.509245 -148.368538) (xy 398.501229 -148.455044) (xy 398.485266 -148.540441) (xy 398.461491 -148.624)
			(xy 398.430107 -148.70501) (xy 398.391383 -148.782778) (xy 398.345648 -148.856642) (xy 398.293293 -148.92597)
			(xy 398.234765 -148.990172) (xy 398.170562 -149.0487) (xy 398.101233 -149.101054) (xy 398.027369 -149.146788)
			(xy 397.949601 -149.185511) (xy 397.868591 -149.216894) (xy 397.785031 -149.240668) (xy 397.699634 -149.256631)
			(xy 397.613128 -149.264646) (xy 397.56969 -149.265132) (xy 395.71549 -149.265132) (xy 395.672051 -149.264674)
			(xy 395.585544 -149.256657) (xy 395.500146 -149.240692) (xy 395.416585 -149.216917) (xy 395.335574 -149.185532)
			(xy 395.257805 -149.146807) (xy 395.18394 -149.101071) (xy 395.11461 -149.048715) (xy 395.050407 -148.990186)
			(xy 394.991879 -148.925982) (xy 394.939523 -148.856652) (xy 394.893788 -148.782787) (xy 394.855064 -148.705017)
			(xy 394.82368 -148.624006) (xy 394.799905 -148.540444) (xy 394.783942 -148.455046) (xy 394.775926 -148.368539)
			(xy 393.392411 -148.368539) (xy 393.384394 -148.455057) (xy 393.368426 -148.540477) (xy 393.344645 -148.624059)
			(xy 393.313253 -148.705091) (xy 393.274519 -148.78288) (xy 393.228772 -148.856764) (xy 393.176403 -148.926111)
			(xy 393.117859 -148.990331) (xy 393.053639 -149.048875) (xy 392.984292 -149.101244) (xy 392.910408 -149.146991)
			(xy 392.832619 -149.185725) (xy 392.751587 -149.217117) (xy 392.668005 -149.240898) (xy 392.582585 -149.256866)
			(xy 392.496056 -149.264884) (xy 392.409156 -149.264884) (xy 392.322627 -149.256866) (xy 392.237207 -149.240898)
			(xy 392.153625 -149.217117) (xy 392.072593 -149.185725) (xy 391.994804 -149.146991) (xy 391.92092 -149.101244)
			(xy 391.851573 -149.048875) (xy 391.787353 -148.990331) (xy 391.728809 -148.926111) (xy 391.67644 -148.856764)
			(xy 391.630693 -148.78288) (xy 391.591959 -148.705091) (xy 391.560567 -148.624059) (xy 391.536786 -148.540477)
			(xy 391.520818 -148.455057) (xy 391.5128 -148.368528) (xy 384.647948 -148.368528) (xy 384.647948 -151.045672)
			(xy 384.903218 -151.045672) (xy 384.903683 -151.01937) (xy 384.910926 -150.967268) (xy 384.925258 -150.916654)
			(xy 384.946407 -150.868489) (xy 384.973972 -150.823686) (xy 385.00743 -150.783094) (xy 385.046146 -150.747482)
			(xy 385.089388 -150.717527) (xy 385.136334 -150.693796) (xy 385.186096 -150.676738) (xy 385.211828 -150.671276)
			(xy 385.222242 -150.669244) (xy 385.239006 -150.65756) (xy 385.29006 -150.578058) (xy 385.293616 -150.557738)
			(xy 385.291076 -150.547578) (xy 385.2861 -150.525497) (xy 385.280747 -150.480549) (xy 385.280408 -150.457916)
			(xy 385.280833 -150.430925) (xy 385.288441 -150.377482) (xy 385.303509 -150.325646) (xy 385.325734 -150.276452)
			(xy 385.354673 -150.230883) (xy 385.389748 -150.189849) (xy 385.409694 -150.171658) (xy 385.417822 -150.164546)
			(xy 385.426712 -150.145496) (xy 385.428744 -150.048976) (xy 385.42087 -150.029672) (xy 385.412996 -150.022306)
			(xy 385.3948 -150.004279) (xy 385.362963 -149.964151) (xy 385.336781 -149.920125) (xy 385.316724 -149.872992)
			(xy 385.303153 -149.8236) (xy 385.29631 -149.772836) (xy 385.295902 -149.747224) (xy 385.296388 -149.719973)
			(xy 385.304144 -149.666025) (xy 385.319499 -149.61373) (xy 385.342141 -149.564153) (xy 385.371607 -149.518303)
			(xy 385.407298 -149.477112) (xy 385.448489 -149.441421) (xy 385.494339 -149.411955) (xy 385.543916 -149.389313)
			(xy 385.596211 -149.373958) (xy 385.650159 -149.366202) (xy 385.704661 -149.366202) (xy 385.758609 -149.373958)
			(xy 385.810904 -149.389313) (xy 385.860481 -149.411955) (xy 385.906331 -149.441421) (xy 385.947522 -149.477112)
			(xy 385.983213 -149.518303) (xy 386.012679 -149.564153) (xy 386.035321 -149.61373) (xy 386.050676 -149.666025)
			(xy 386.058432 -149.719973) (xy 386.058918 -149.747224) (xy 386.058444 -149.774213) (xy 386.050844 -149.827653)
			(xy 386.035786 -149.879488) (xy 386.01357 -149.928683) (xy 385.98464 -149.974253) (xy 385.949573 -150.01529)
			(xy 385.929632 -150.033482) (xy 385.921504 -150.040594) (xy 385.912614 -150.059644) (xy 385.910582 -150.156164)
			(xy 385.918456 -150.175468) (xy 385.92633 -150.182834) (xy 385.944483 -150.200903) (xy 385.976326 -150.24102)
			(xy 386.002516 -150.285037) (xy 386.022581 -150.332162) (xy 386.036161 -150.381548) (xy 386.043011 -150.432307)
			(xy 386.043424 -150.457916) (xy 386.042915 -150.484216) (xy 386.035674 -150.536315) (xy 386.021345 -150.586926)
			(xy 386.0002 -150.635089) (xy 385.97264 -150.679891) (xy 385.939188 -150.720483) (xy 385.900477 -150.756094)
			(xy 385.857241 -150.786051) (xy 385.8103 -150.809786) (xy 385.760544 -150.826847) (xy 385.734814 -150.832312)
			(xy 385.7244 -150.834344) (xy 385.707636 -150.846028) (xy 385.656582 -150.92553) (xy 385.653026 -150.94585)
			(xy 385.655566 -150.95601) (xy 385.656582 -150.960328) (xy 385.658868 -150.970234) (xy 385.670552 -150.986744)
			(xy 385.749038 -151.035766) (xy 385.76885 -151.039068) (xy 385.778756 -151.036528) (xy 385.800168 -151.031863)
			(xy 385.843711 -151.026899) (xy 385.865624 -151.026622) (xy 385.892876 -151.027049) (xy 385.946826 -151.034809)
			(xy 385.999122 -151.050168) (xy 386.0487 -151.072812) (xy 386.094551 -151.102281) (xy 386.135741 -151.137976)
			(xy 386.152599 -151.157432) (xy 392.904978 -151.157432) (xy 392.909049 -151.10181) (xy 392.921175 -151.047373)
			(xy 392.941098 -150.995282) (xy 392.968394 -150.946647) (xy 393.00248 -150.902504) (xy 393.042629 -150.863795)
			(xy 393.087987 -150.831344) (xy 393.137587 -150.805843) (xy 393.190371 -150.787836) (xy 393.245214 -150.777706)
			(xy 393.300948 -150.775669) (xy 393.356385 -150.781769) (xy 393.410342 -150.795875) (xy 393.461671 -150.817687)
			(xy 393.509277 -150.846741) (xy 393.552145 -150.882416) (xy 393.589362 -150.923953) (xy 393.620135 -150.970466)
			(xy 393.623479 -150.9776) (xy 396.463772 -150.9776) (xy 396.467843 -150.921978) (xy 396.479969 -150.867541)
			(xy 396.499892 -150.81545) (xy 396.527188 -150.766815) (xy 396.561274 -150.722672) (xy 396.601423 -150.683963)
			(xy 396.646781 -150.651512) (xy 396.696381 -150.626011) (xy 396.749165 -150.608004) (xy 396.804008 -150.597874)
			(xy 396.859742 -150.595837) (xy 396.915179 -150.601937) (xy 396.969136 -150.616043) (xy 397.020465 -150.637855)
			(xy 397.068071 -150.666909) (xy 397.110939 -150.702584) (xy 397.148156 -150.744121) (xy 397.178929 -150.790634)
			(xy 397.202601 -150.841131) (xy 397.218669 -150.894538) (xy 397.226789 -150.949714) (xy 397.227298 -150.9776)
			(xy 397.226789 -151.005486) (xy 397.218669 -151.060662) (xy 397.202601 -151.114069) (xy 397.181083 -151.159972)
			(xy 399.551142 -151.159972) (xy 399.555213 -151.10435) (xy 399.567339 -151.049913) (xy 399.587262 -150.997822)
			(xy 399.614558 -150.949187) (xy 399.648644 -150.905044) (xy 399.688793 -150.866335) (xy 399.734151 -150.833884)
			(xy 399.783751 -150.808383) (xy 399.836535 -150.790376) (xy 399.891378 -150.780246) (xy 399.947112 -150.778209)
			(xy 400.002549 -150.784309) (xy 400.056506 -150.798415) (xy 400.107835 -150.820227) (xy 400.155441 -150.849281)
			(xy 400.198309 -150.884956) (xy 400.235526 -150.926493) (xy 400.266299 -150.973006) (xy 400.289971 -151.023503)
			(xy 400.306039 -151.07691) (xy 400.314159 -151.132086) (xy 400.314668 -151.159972) (xy 400.314159 -151.187858)
			(xy 400.306039 -151.243034) (xy 400.301837 -151.257) (xy 400.877022 -151.257) (xy 400.881093 -151.201378)
			(xy 400.893219 -151.146941) (xy 400.913142 -151.09485) (xy 400.940438 -151.046215) (xy 400.974524 -151.002072)
			(xy 401.014673 -150.963363) (xy 401.060031 -150.930912) (xy 401.109631 -150.905411) (xy 401.162415 -150.887404)
			(xy 401.217258 -150.877274) (xy 401.272992 -150.875237) (xy 401.328429 -150.881337) (xy 401.382386 -150.895443)
			(xy 401.433715 -150.917255) (xy 401.481321 -150.946309) (xy 401.524189 -150.981984) (xy 401.561406 -151.023521)
			(xy 401.592179 -151.070034) (xy 401.615851 -151.120531) (xy 401.631919 -151.173938) (xy 401.640039 -151.229114)
			(xy 401.640548 -151.257) (xy 401.640039 -151.284886) (xy 401.631919 -151.340062) (xy 401.615851 -151.393469)
			(xy 401.592179 -151.443966) (xy 401.561406 -151.490479) (xy 401.524189 -151.532016) (xy 401.481321 -151.567691)
			(xy 401.433715 -151.596745) (xy 401.382386 -151.618557) (xy 401.328429 -151.632663) (xy 401.272992 -151.638763)
			(xy 401.217258 -151.636726) (xy 401.162415 -151.626596) (xy 401.109631 -151.608589) (xy 401.060031 -151.583088)
			(xy 401.014673 -151.550637) (xy 400.974524 -151.511928) (xy 400.940438 -151.467785) (xy 400.913142 -151.41915)
			(xy 400.893219 -151.367059) (xy 400.881093 -151.312622) (xy 400.877022 -151.257) (xy 400.301837 -151.257)
			(xy 400.289971 -151.296441) (xy 400.266299 -151.346938) (xy 400.235526 -151.393451) (xy 400.198309 -151.434988)
			(xy 400.155441 -151.470663) (xy 400.107835 -151.499717) (xy 400.056506 -151.521529) (xy 400.002549 -151.535635)
			(xy 399.947112 -151.541735) (xy 399.891378 -151.539698) (xy 399.836535 -151.529568) (xy 399.783751 -151.511561)
			(xy 399.734151 -151.48606) (xy 399.688793 -151.453609) (xy 399.648644 -151.4149) (xy 399.614558 -151.370757)
			(xy 399.587262 -151.322122) (xy 399.567339 -151.270031) (xy 399.555213 -151.215594) (xy 399.551142 -151.159972)
			(xy 397.181083 -151.159972) (xy 397.178929 -151.164566) (xy 397.148156 -151.211079) (xy 397.110939 -151.252616)
			(xy 397.068071 -151.288291) (xy 397.020465 -151.317345) (xy 396.969136 -151.339157) (xy 396.915179 -151.353263)
			(xy 396.859742 -151.359363) (xy 396.804008 -151.357326) (xy 396.749165 -151.347196) (xy 396.696381 -151.329189)
			(xy 396.646781 -151.303688) (xy 396.601423 -151.271237) (xy 396.561274 -151.232528) (xy 396.527188 -151.188385)
			(xy 396.499892 -151.13975) (xy 396.479969 -151.087659) (xy 396.467843 -151.033222) (xy 396.463772 -150.9776)
			(xy 393.623479 -150.9776) (xy 393.643807 -151.020963) (xy 393.659875 -151.07437) (xy 393.667995 -151.129546)
			(xy 393.668504 -151.157432) (xy 393.667995 -151.185318) (xy 393.659875 -151.240494) (xy 393.643807 -151.293901)
			(xy 393.620135 -151.344398) (xy 393.589362 -151.390911) (xy 393.552145 -151.432448) (xy 393.509277 -151.468123)
			(xy 393.461671 -151.497177) (xy 393.410342 -151.518989) (xy 393.356385 -151.533095) (xy 393.300948 -151.539195)
			(xy 393.245214 -151.537158) (xy 393.190371 -151.527028) (xy 393.137587 -151.509021) (xy 393.087987 -151.48352)
			(xy 393.042629 -151.451069) (xy 393.00248 -151.41236) (xy 392.968394 -151.368217) (xy 392.941098 -151.319582)
			(xy 392.921175 -151.267491) (xy 392.909049 -151.213054) (xy 392.904978 -151.157432) (xy 386.152599 -151.157432)
			(xy 386.171433 -151.179169) (xy 386.200899 -151.225021) (xy 386.223541 -151.274601) (xy 386.238896 -151.326898)
			(xy 386.246652 -151.380848) (xy 386.246652 -151.435352) (xy 386.238896 -151.489302) (xy 386.223541 -151.541599)
			(xy 386.200899 -151.591179) (xy 386.171433 -151.637031) (xy 386.135741 -151.678224) (xy 386.094551 -151.713919)
			(xy 386.0487 -151.743388) (xy 385.999122 -151.766032) (xy 385.946826 -151.781391) (xy 385.892876 -151.789151)
			(xy 385.865624 -151.789638) (xy 385.847281 -151.789405) (xy 385.810768 -151.785842) (xy 385.792726 -151.782526)
			(xy 385.78282 -151.780748) (xy 385.763516 -151.784558) (xy 385.687062 -151.835612) (xy 385.675886 -151.851868)
			(xy 385.673854 -151.862028) (xy 385.670806 -151.875998) (xy 385.71551 -151.916384) (xy 385.722068 -151.92189)
			(xy 385.737852 -151.928509) (xy 385.754935 -151.929561) (xy 385.763262 -151.92756) (xy 385.788169 -151.921136)
			(xy 385.839143 -151.914249) (xy 385.864862 -151.913844) (xy 385.892119 -151.914314) (xy 385.946079 -151.922067)
			(xy 385.998386 -151.937421) (xy 386.047975 -151.960063) (xy 386.093837 -151.989532) (xy 386.098532 -151.9936)
			(xy 396.463772 -151.9936) (xy 396.467843 -151.937978) (xy 396.479969 -151.883541) (xy 396.499892 -151.83145)
			(xy 396.527188 -151.782815) (xy 396.561274 -151.738672) (xy 396.601423 -151.699963) (xy 396.646781 -151.667512)
			(xy 396.696381 -151.642011) (xy 396.749165 -151.624004) (xy 396.804008 -151.613874) (xy 396.859742 -151.611837)
			(xy 396.915179 -151.617937) (xy 396.969136 -151.632043) (xy 397.020465 -151.653855) (xy 397.068071 -151.682909)
			(xy 397.110939 -151.718584) (xy 397.148156 -151.760121) (xy 397.178929 -151.806634) (xy 397.202601 -151.857131)
			(xy 397.218669 -151.910538) (xy 397.226789 -151.965714) (xy 397.227298 -151.9936) (xy 397.226789 -152.021486)
			(xy 397.218669 -152.076662) (xy 397.202601 -152.130069) (xy 397.178929 -152.180566) (xy 397.16604 -152.200048)
			(xy 400.856707 -152.200048) (xy 400.856707 -152.142752) (xy 400.864861 -152.086038) (xy 400.881004 -152.031063)
			(xy 400.904805 -151.978944) (xy 400.935782 -151.930743) (xy 400.973303 -151.887441) (xy 401.016605 -151.84992)
			(xy 401.064806 -151.818943) (xy 401.116925 -151.795142) (xy 401.1719 -151.778999) (xy 401.228614 -151.770845)
			(xy 401.28591 -151.770845) (xy 401.342624 -151.778999) (xy 401.397599 -151.795142) (xy 401.449718 -151.818943)
			(xy 401.497919 -151.84992) (xy 401.541221 -151.887441) (xy 401.578742 -151.930743) (xy 401.609719 -151.978944)
			(xy 401.63352 -152.031063) (xy 401.649663 -152.086038) (xy 401.657817 -152.142752) (xy 401.658328 -152.1714)
			(xy 401.657817 -152.200048) (xy 401.649663 -152.256762) (xy 401.63352 -152.311737) (xy 401.609719 -152.363856)
			(xy 401.578742 -152.412057) (xy 401.541221 -152.455359) (xy 401.497919 -152.49288) (xy 401.449718 -152.523857)
			(xy 401.397599 -152.547658) (xy 401.342624 -152.563801) (xy 401.28591 -152.571955) (xy 401.228614 -152.571955)
			(xy 401.1719 -152.563801) (xy 401.116925 -152.547658) (xy 401.064806 -152.523857) (xy 401.016605 -152.49288)
			(xy 400.973303 -152.455359) (xy 400.935782 -152.412057) (xy 400.904805 -152.363856) (xy 400.881004 -152.311737)
			(xy 400.864861 -152.256762) (xy 400.856707 -152.200048) (xy 397.16604 -152.200048) (xy 397.148156 -152.227079)
			(xy 397.110939 -152.268616) (xy 397.068071 -152.304291) (xy 397.020465 -152.333345) (xy 396.969136 -152.355157)
			(xy 396.915179 -152.369263) (xy 396.859742 -152.375363) (xy 396.804008 -152.373326) (xy 396.749165 -152.363196)
			(xy 396.696381 -152.345189) (xy 396.646781 -152.319688) (xy 396.601423 -152.287237) (xy 396.561274 -152.248528)
			(xy 396.527188 -152.204385) (xy 396.499892 -152.15575) (xy 396.479969 -152.103659) (xy 396.467843 -152.049222)
			(xy 396.463772 -151.9936) (xy 386.098532 -151.9936) (xy 386.135038 -152.025228) (xy 386.170739 -152.066425)
			(xy 386.200214 -152.112284) (xy 386.222862 -152.16187) (xy 386.238222 -152.214175) (xy 386.245982 -152.268134)
			(xy 386.245984 -152.322648) (xy 386.238226 -152.376607) (xy 386.222869 -152.428912) (xy 386.200223 -152.4785)
			(xy 386.170751 -152.52436) (xy 386.135051 -152.565558) (xy 386.093852 -152.601257) (xy 386.047991 -152.630728)
			(xy 385.998403 -152.653372) (xy 385.946097 -152.668729) (xy 385.892138 -152.676484) (xy 385.837624 -152.676482)
			(xy 385.783665 -152.66872) (xy 385.731361 -152.653359) (xy 385.681775 -152.630709) (xy 385.635917 -152.601233)
			(xy 385.594721 -152.565531) (xy 385.559026 -152.524329) (xy 385.529558 -152.478466) (xy 385.506918 -152.428876)
			(xy 385.491565 -152.376569) (xy 385.483814 -152.322609) (xy 385.483354 -152.295352) (xy 385.48437 -152.268428)
			(xy 385.485132 -152.256744) (xy 385.476496 -152.235154) (xy 385.399534 -152.165558) (xy 385.377182 -152.159208)
			(xy 385.365498 -152.16124) (xy 385.349307 -152.163869) (xy 385.316622 -152.166668) (xy 385.30022 -152.166828)
			(xy 385.27297 -152.166303) (xy 385.219025 -152.15855) (xy 385.166732 -152.143198) (xy 385.117156 -152.120561)
			(xy 385.071307 -152.091099) (xy 385.030117 -152.055411) (xy 384.994425 -152.014225) (xy 384.964958 -151.968379)
			(xy 384.942316 -151.918805) (xy 384.926959 -151.866514) (xy 384.9192 -151.81257) (xy 384.918712 -151.78532)
			(xy 384.91921 -151.758241) (xy 384.926861 -151.704626) (xy 384.942012 -151.652631) (xy 384.96436 -151.603299)
			(xy 384.993455 -151.55762) (xy 385.028714 -151.516512) (xy 385.04876 -151.4983) (xy 385.057396 -151.490934)
			(xy 385.066286 -151.470614) (xy 385.064254 -151.369776) (xy 385.054348 -151.349964) (xy 385.045458 -151.342852)
			(xy 385.023696 -151.324595) (xy 384.985223 -151.282807) (xy 384.95337 -151.235778) (xy 384.92884 -151.184546)
			(xy 384.912176 -151.130245) (xy 384.903745 -151.074072) (xy 384.903218 -151.045672) (xy 384.647948 -151.045672)
			(xy 384.647948 -152.958038) (xy 392.787122 -152.958038) (xy 392.791193 -152.902416) (xy 392.803319 -152.847979)
			(xy 392.823242 -152.795888) (xy 392.850538 -152.747253) (xy 392.884624 -152.70311) (xy 392.924773 -152.664401)
			(xy 392.970131 -152.63195) (xy 393.019731 -152.606449) (xy 393.072515 -152.588442) (xy 393.127358 -152.578312)
			(xy 393.183092 -152.576275) (xy 393.238529 -152.582375) (xy 393.292486 -152.596481) (xy 393.343815 -152.618293)
			(xy 393.391421 -152.647347) (xy 393.434289 -152.683022) (xy 393.471506 -152.724559) (xy 393.502279 -152.771072)
			(xy 393.525951 -152.821569) (xy 393.542019 -152.874976) (xy 393.550139 -152.930152) (xy 393.550648 -152.958038)
			(xy 393.550139 -152.985924) (xy 393.546655 -153.0096) (xy 396.463772 -153.0096) (xy 396.467843 -152.953978)
			(xy 396.479969 -152.899541) (xy 396.499892 -152.84745) (xy 396.527188 -152.798815) (xy 396.561274 -152.754672)
			(xy 396.601423 -152.715963) (xy 396.646781 -152.683512) (xy 396.696381 -152.658011) (xy 396.749165 -152.640004)
			(xy 396.804008 -152.629874) (xy 396.859742 -152.627837) (xy 396.915179 -152.633937) (xy 396.969136 -152.648043)
			(xy 397.020465 -152.669855) (xy 397.068071 -152.698909) (xy 397.110939 -152.734584) (xy 397.148156 -152.776121)
			(xy 397.178929 -152.822634) (xy 397.202601 -152.873131) (xy 397.218669 -152.926538) (xy 397.223604 -152.96007)
			(xy 399.551142 -152.96007) (xy 399.555213 -152.904448) (xy 399.567339 -152.850011) (xy 399.587262 -152.79792)
			(xy 399.614558 -152.749285) (xy 399.648644 -152.705142) (xy 399.688793 -152.666433) (xy 399.734151 -152.633982)
			(xy 399.783751 -152.608481) (xy 399.836535 -152.590474) (xy 399.891378 -152.580344) (xy 399.947112 -152.578307)
			(xy 400.002549 -152.584407) (xy 400.056506 -152.598513) (xy 400.107835 -152.620325) (xy 400.155441 -152.649379)
			(xy 400.198309 -152.685054) (xy 400.235526 -152.726591) (xy 400.266299 -152.773104) (xy 400.289971 -152.823601)
			(xy 400.306039 -152.877008) (xy 400.314159 -152.932184) (xy 400.314668 -152.96007) (xy 400.314159 -152.987956)
			(xy 400.306039 -153.043132) (xy 400.289971 -153.096539) (xy 400.266299 -153.147036) (xy 400.235526 -153.193549)
			(xy 400.198309 -153.235086) (xy 400.155441 -153.270761) (xy 400.107835 -153.299815) (xy 400.056506 -153.321627)
			(xy 400.002549 -153.335733) (xy 399.947112 -153.341833) (xy 399.891378 -153.339796) (xy 399.836535 -153.329666)
			(xy 399.783751 -153.311659) (xy 399.734151 -153.286158) (xy 399.688793 -153.253707) (xy 399.648644 -153.214998)
			(xy 399.614558 -153.170855) (xy 399.587262 -153.12222) (xy 399.567339 -153.070129) (xy 399.555213 -153.015692)
			(xy 399.551142 -152.96007) (xy 397.223604 -152.96007) (xy 397.226789 -152.981714) (xy 397.227298 -153.0096)
			(xy 397.226789 -153.037486) (xy 397.218669 -153.092662) (xy 397.202601 -153.146069) (xy 397.178929 -153.196566)
			(xy 397.148156 -153.243079) (xy 397.110939 -153.284616) (xy 397.068071 -153.320291) (xy 397.020465 -153.349345)
			(xy 396.969136 -153.371157) (xy 396.915179 -153.385263) (xy 396.859742 -153.391363) (xy 396.804008 -153.389326)
			(xy 396.749165 -153.379196) (xy 396.696381 -153.361189) (xy 396.646781 -153.335688) (xy 396.601423 -153.303237)
			(xy 396.561274 -153.264528) (xy 396.527188 -153.220385) (xy 396.499892 -153.17175) (xy 396.479969 -153.119659)
			(xy 396.467843 -153.065222) (xy 396.463772 -153.0096) (xy 393.546655 -153.0096) (xy 393.542019 -153.0411)
			(xy 393.525951 -153.094507) (xy 393.502279 -153.145004) (xy 393.471506 -153.191517) (xy 393.434289 -153.233054)
			(xy 393.391421 -153.268729) (xy 393.343815 -153.297783) (xy 393.292486 -153.319595) (xy 393.238529 -153.333701)
			(xy 393.183092 -153.339801) (xy 393.127358 -153.337764) (xy 393.072515 -153.327634) (xy 393.019731 -153.309627)
			(xy 392.970131 -153.284126) (xy 392.924773 -153.251675) (xy 392.884624 -153.212966) (xy 392.850538 -153.168823)
			(xy 392.823242 -153.120188) (xy 392.803319 -153.068097) (xy 392.791193 -153.01366) (xy 392.787122 -152.958038)
			(xy 384.647948 -152.958038) (xy 384.647948 -154.327352) (xy 385.482844 -154.327352) (xy 385.486915 -154.27173)
			(xy 385.499041 -154.217293) (xy 385.518964 -154.165202) (xy 385.54626 -154.116567) (xy 385.580346 -154.072424)
			(xy 385.620495 -154.033715) (xy 385.665853 -154.001264) (xy 385.715453 -153.975763) (xy 385.768237 -153.957756)
			(xy 385.82308 -153.947626) (xy 385.878814 -153.945589) (xy 385.934251 -153.951689) (xy 385.988208 -153.965795)
			(xy 386.039537 -153.987607) (xy 386.087143 -154.016661) (xy 386.097884 -154.0256) (xy 396.463772 -154.0256)
			(xy 396.467843 -153.969978) (xy 396.479969 -153.915541) (xy 396.499892 -153.86345) (xy 396.527188 -153.814815)
			(xy 396.561274 -153.770672) (xy 396.601423 -153.731963) (xy 396.646781 -153.699512) (xy 396.696381 -153.674011)
			(xy 396.749165 -153.656004) (xy 396.804008 -153.645874) (xy 396.859742 -153.643837) (xy 396.915179 -153.649937)
			(xy 396.969136 -153.664043) (xy 397.020465 -153.685855) (xy 397.068071 -153.714909) (xy 397.110939 -153.750584)
			(xy 397.148156 -153.792121) (xy 397.178929 -153.838634) (xy 397.202601 -153.889131) (xy 397.218669 -153.942538)
			(xy 397.226789 -153.997714) (xy 397.227298 -154.0256) (xy 397.226789 -154.053486) (xy 397.218669 -154.108662)
			(xy 397.202601 -154.162069) (xy 397.190793 -154.187257) (xy 399.607921 -154.187257) (xy 399.607921 -154.132743)
			(xy 399.61568 -154.078784) (xy 399.631039 -154.026478) (xy 399.653687 -153.976891) (xy 399.683161 -153.931031)
			(xy 399.718862 -153.889834) (xy 399.760063 -153.854137) (xy 399.805926 -153.824667) (xy 399.855515 -153.802025)
			(xy 399.907823 -153.786671) (xy 399.961783 -153.778918) (xy 399.98904 -153.778458) (xy 400.015571 -153.778901)
			(xy 400.068122 -153.786247) (xy 400.119147 -153.800806) (xy 400.167662 -153.822296) (xy 400.21273 -153.850303)
			(xy 400.253482 -153.884286) (xy 400.28913 -153.923589) (xy 400.318987 -153.967454) (xy 400.342476 -154.015034)
			(xy 400.351244 -154.040078) (xy 400.355562 -154.053286) (xy 400.376644 -154.071574) (xy 400.492214 -154.092148)
			(xy 400.518376 -154.082496) (xy 400.527266 -154.07132) (xy 400.544564 -154.050248) (xy 400.583967 -154.01257)
			(xy 400.628118 -153.980586) (xy 400.6762 -153.954887) (xy 400.727324 -153.93595) (xy 400.753834 -153.929588)
			(xy 400.76628 -153.926794) (xy 400.78533 -153.910538) (xy 400.825716 -153.809192) (xy 400.822922 -153.784046)
			(xy 400.81581 -153.773632) (xy 400.800383 -153.749841) (xy 400.775961 -153.698671) (xy 400.759388 -153.644448)
			(xy 400.751031 -153.588368) (xy 400.750532 -153.560018) (xy 400.751018 -153.532767) (xy 400.758774 -153.478819)
			(xy 400.774129 -153.426524) (xy 400.796771 -153.376947) (xy 400.826237 -153.331097) (xy 400.861928 -153.289906)
			(xy 400.903119 -153.254215) (xy 400.948969 -153.224749) (xy 400.998546 -153.202107) (xy 401.050841 -153.186752)
			(xy 401.104789 -153.178996) (xy 401.159291 -153.178996) (xy 401.213239 -153.186752) (xy 401.265534 -153.202107)
			(xy 401.315111 -153.224749) (xy 401.360961 -153.254215) (xy 401.402152 -153.289906) (xy 401.437843 -153.331097)
			(xy 401.467309 -153.376947) (xy 401.489951 -153.426524) (xy 401.505306 -153.478819) (xy 401.513062 -153.532767)
			(xy 401.513548 -153.560018) (xy 401.512998 -153.588111) (xy 401.504781 -153.643691) (xy 401.488499 -153.697465)
			(xy 401.464504 -153.748268) (xy 401.433315 -153.795001) (xy 401.395607 -153.836653) (xy 401.352197 -153.872321)
			(xy 401.304023 -153.901235) (xy 401.252128 -153.922768) (xy 401.225004 -153.930096) (xy 401.212558 -153.933144)
			(xy 401.194016 -153.949908) (xy 401.15617 -154.052524) (xy 401.159726 -154.077416) (xy 401.167092 -154.087576)
			(xy 401.184739 -154.113254) (xy 401.212683 -154.16894) (xy 401.231663 -154.228283) (xy 401.241222 -154.289849)
			(xy 401.241768 -154.321002) (xy 401.241162 -154.355004) (xy 401.229795 -154.422049) (xy 401.219162 -154.454352)
			(xy 401.214336 -154.467814) (xy 401.21967 -154.494738) (xy 401.298156 -154.582114) (xy 401.324572 -154.590242)
			(xy 401.338288 -154.58694) (xy 401.359942 -154.582155) (xy 401.403997 -154.577059) (xy 401.426172 -154.57678)
			(xy 401.453425 -154.577265) (xy 401.507378 -154.585019) (xy 401.559677 -154.600372) (xy 401.609259 -154.623012)
			(xy 401.655114 -154.652479) (xy 401.696309 -154.688171) (xy 401.732005 -154.729363) (xy 401.761474 -154.775216)
			(xy 401.784118 -154.824797) (xy 401.799475 -154.877095) (xy 401.807233 -154.931047) (xy 401.807233 -154.985553)
			(xy 401.799475 -155.039505) (xy 401.784118 -155.091803) (xy 401.761474 -155.141384) (xy 401.732005 -155.187237)
			(xy 401.696309 -155.228429) (xy 401.655114 -155.264121) (xy 401.609259 -155.293588) (xy 401.559677 -155.316228)
			(xy 401.507378 -155.331581) (xy 401.453425 -155.339335) (xy 401.426172 -155.339796) (xy 401.410678 -155.339542)
			(xy 401.3962 -155.33878) (xy 401.371562 -155.352496) (xy 401.312634 -155.455874) (xy 401.313396 -155.484068)
			(xy 401.321016 -155.49626) (xy 401.336227 -155.520703) (xy 401.360308 -155.572994) (xy 401.376674 -155.628188)
			(xy 401.38499 -155.685154) (xy 401.385532 -155.713938) (xy 401.385014 -155.742582) (xy 401.376856 -155.799287)
			(xy 401.360711 -155.854254) (xy 401.336909 -155.906364) (xy 401.305932 -155.954557) (xy 401.268413 -155.99785)
			(xy 401.225115 -156.035364) (xy 401.176919 -156.066334) (xy 401.124806 -156.09013) (xy 401.069837 -156.106267)
			(xy 401.01313 -156.114418) (xy 400.955842 -156.114416) (xy 400.899136 -156.106261) (xy 400.844168 -156.09012)
			(xy 400.792057 -156.06632) (xy 400.743863 -156.035347) (xy 400.700567 -155.99783) (xy 400.663051 -155.954534)
			(xy 400.632078 -155.90634) (xy 400.608279 -155.854228) (xy 400.592138 -155.79926) (xy 400.583984 -155.742554)
			(xy 400.583982 -155.685266) (xy 400.592134 -155.62856) (xy 400.608272 -155.573591) (xy 400.632068 -155.521478)
			(xy 400.663039 -155.473282) (xy 400.700553 -155.429984) (xy 400.743847 -155.392465) (xy 400.792039 -155.361489)
			(xy 400.844149 -155.337687) (xy 400.899116 -155.321543) (xy 400.955822 -155.313385) (xy 400.984466 -155.312872)
			(xy 401.009104 -155.313634) (xy 401.023328 -155.31465) (xy 401.048474 -155.301442) (xy 401.109434 -155.199334)
			(xy 401.10918 -155.17114) (xy 401.10156 -155.158948) (xy 401.088053 -155.136238) (xy 401.066758 -155.087881)
			(xy 401.052346 -155.037046) (xy 401.045092 -154.984708) (xy 401.044664 -154.958288) (xy 401.045227 -154.927983)
			(xy 401.054803 -154.868133) (xy 401.063714 -154.839162) (xy 401.068286 -154.8257) (xy 401.06219 -154.798776)
			(xy 400.981926 -154.713178) (xy 400.95551 -154.705558) (xy 400.941794 -154.709114) (xy 400.917023 -154.715156)
			(xy 400.86645 -154.721654) (xy 400.840956 -154.722068) (xy 400.812595 -154.721564) (xy 400.756441 -154.713554)
			(xy 400.701975 -154.697713) (xy 400.650284 -154.674359) (xy 400.602397 -154.643956) (xy 400.559271 -154.607111)
			(xy 400.521765 -154.564558) (xy 400.490627 -154.517146) (xy 400.466478 -154.465821) (xy 400.45767 -154.438858)
			(xy 400.453606 -154.425396) (xy 400.432778 -154.4066) (xy 400.317716 -154.38374) (xy 400.291554 -154.392884)
			(xy 400.28241 -154.403806) (xy 400.264224 -154.424979) (xy 400.222678 -154.462251) (xy 400.176143 -154.49307)
			(xy 400.125613 -154.516777) (xy 400.072167 -154.532865) (xy 400.016947 -154.540992) (xy 399.98904 -154.541474)
			(xy 399.961783 -154.541082) (xy 399.907823 -154.533329) (xy 399.855515 -154.517975) (xy 399.805926 -154.495333)
			(xy 399.760063 -154.465863) (xy 399.718862 -154.430166) (xy 399.683161 -154.388969) (xy 399.653687 -154.343109)
			(xy 399.631039 -154.293522) (xy 399.61568 -154.241216) (xy 399.607921 -154.187257) (xy 397.190793 -154.187257)
			(xy 397.178929 -154.212566) (xy 397.148156 -154.259079) (xy 397.110939 -154.300616) (xy 397.068071 -154.336291)
			(xy 397.020465 -154.365345) (xy 396.969136 -154.387157) (xy 396.915179 -154.401263) (xy 396.859742 -154.407363)
			(xy 396.804008 -154.405326) (xy 396.749165 -154.395196) (xy 396.696381 -154.377189) (xy 396.646781 -154.351688)
			(xy 396.601423 -154.319237) (xy 396.561274 -154.280528) (xy 396.527188 -154.236385) (xy 396.499892 -154.18775)
			(xy 396.479969 -154.135659) (xy 396.467843 -154.081222) (xy 396.463772 -154.0256) (xy 386.097884 -154.0256)
			(xy 386.130011 -154.052336) (xy 386.167228 -154.093873) (xy 386.198001 -154.140386) (xy 386.221673 -154.190883)
			(xy 386.237741 -154.24429) (xy 386.245861 -154.299466) (xy 386.24637 -154.327352) (xy 386.245861 -154.355238)
			(xy 386.237741 -154.410414) (xy 386.221673 -154.463821) (xy 386.198001 -154.514318) (xy 386.167228 -154.560831)
			(xy 386.130011 -154.602368) (xy 386.087143 -154.638043) (xy 386.039537 -154.667097) (xy 385.988208 -154.688909)
			(xy 385.934251 -154.703015) (xy 385.878814 -154.709115) (xy 385.82308 -154.707078) (xy 385.768237 -154.696948)
			(xy 385.715453 -154.678941) (xy 385.665853 -154.65344) (xy 385.620495 -154.620989) (xy 385.580346 -154.58228)
			(xy 385.54626 -154.538137) (xy 385.518964 -154.489502) (xy 385.499041 -154.437411) (xy 385.486915 -154.382974)
			(xy 385.482844 -154.327352) (xy 384.647948 -154.327352) (xy 384.647948 -155.598368) (xy 399.668236 -155.598368)
			(xy 399.672307 -155.542746) (xy 399.684433 -155.488309) (xy 399.704356 -155.436218) (xy 399.731652 -155.387583)
			(xy 399.765738 -155.34344) (xy 399.805887 -155.304731) (xy 399.851245 -155.27228) (xy 399.900845 -155.246779)
			(xy 399.953629 -155.228772) (xy 400.008472 -155.218642) (xy 400.064206 -155.216605) (xy 400.119643 -155.222705)
			(xy 400.1736 -155.236811) (xy 400.224929 -155.258623) (xy 400.272535 -155.287677) (xy 400.315403 -155.323352)
			(xy 400.35262 -155.364889) (xy 400.383393 -155.411402) (xy 400.407065 -155.461899) (xy 400.423133 -155.515306)
			(xy 400.431253 -155.570482) (xy 400.431762 -155.598368) (xy 400.431253 -155.626254) (xy 400.423133 -155.68143)
			(xy 400.407065 -155.734837) (xy 400.383393 -155.785334) (xy 400.35262 -155.831847) (xy 400.315403 -155.873384)
			(xy 400.272535 -155.909059) (xy 400.224929 -155.938113) (xy 400.1736 -155.959925) (xy 400.119643 -155.974031)
			(xy 400.064206 -155.980131) (xy 400.008472 -155.978094) (xy 399.953629 -155.967964) (xy 399.900845 -155.949957)
			(xy 399.851245 -155.924456) (xy 399.805887 -155.892005) (xy 399.765738 -155.853296) (xy 399.731652 -155.809153)
			(xy 399.704356 -155.760518) (xy 399.684433 -155.708427) (xy 399.672307 -155.65399) (xy 399.668236 -155.598368)
			(xy 384.647948 -155.598368) (xy 384.647948 -156.3624) (xy 385.490972 -156.3624) (xy 385.495043 -156.306778)
			(xy 385.507169 -156.252341) (xy 385.527092 -156.20025) (xy 385.554388 -156.151615) (xy 385.588474 -156.107472)
			(xy 385.628623 -156.068763) (xy 385.673981 -156.036312) (xy 385.723581 -156.010811) (xy 385.776365 -155.992804)
			(xy 385.831208 -155.982674) (xy 385.886942 -155.980637) (xy 385.942379 -155.986737) (xy 385.996336 -156.000843)
			(xy 386.047665 -156.022655) (xy 386.095271 -156.051709) (xy 386.10235 -156.0576) (xy 396.463772 -156.0576)
			(xy 396.467843 -156.001978) (xy 396.479969 -155.947541) (xy 396.499892 -155.89545) (xy 396.527188 -155.846815)
			(xy 396.561274 -155.802672) (xy 396.601423 -155.763963) (xy 396.646781 -155.731512) (xy 396.696381 -155.706011)
			(xy 396.749165 -155.688004) (xy 396.804008 -155.677874) (xy 396.859742 -155.675837) (xy 396.915179 -155.681937)
			(xy 396.969136 -155.696043) (xy 397.020465 -155.717855) (xy 397.068071 -155.746909) (xy 397.110939 -155.782584)
			(xy 397.148156 -155.824121) (xy 397.178929 -155.870634) (xy 397.202601 -155.921131) (xy 397.218669 -155.974538)
			(xy 397.226789 -156.029714) (xy 397.227298 -156.0576) (xy 397.226789 -156.085486) (xy 397.218669 -156.140662)
			(xy 397.202601 -156.194069) (xy 397.178929 -156.244566) (xy 397.148156 -156.291079) (xy 397.110939 -156.332616)
			(xy 397.068071 -156.368291) (xy 397.020465 -156.397345) (xy 396.969136 -156.419157) (xy 396.915179 -156.433263)
			(xy 396.859742 -156.439363) (xy 396.804008 -156.437326) (xy 396.749165 -156.427196) (xy 396.696381 -156.409189)
			(xy 396.646781 -156.383688) (xy 396.601423 -156.351237) (xy 396.561274 -156.312528) (xy 396.527188 -156.268385)
			(xy 396.499892 -156.21975) (xy 396.479969 -156.167659) (xy 396.467843 -156.113222) (xy 396.463772 -156.0576)
			(xy 386.10235 -156.0576) (xy 386.138139 -156.087384) (xy 386.175356 -156.128921) (xy 386.206129 -156.175434)
			(xy 386.229801 -156.225931) (xy 386.245869 -156.279338) (xy 386.253989 -156.334514) (xy 386.254498 -156.3624)
			(xy 386.253989 -156.390286) (xy 386.245869 -156.445462) (xy 386.229801 -156.498869) (xy 386.208402 -156.544518)
			(xy 401.027898 -156.544518) (xy 401.031969 -156.488896) (xy 401.044095 -156.434459) (xy 401.064018 -156.382368)
			(xy 401.091314 -156.333733) (xy 401.1254 -156.28959) (xy 401.165549 -156.250881) (xy 401.210907 -156.21843)
			(xy 401.260507 -156.192929) (xy 401.313291 -156.174922) (xy 401.368134 -156.164792) (xy 401.423868 -156.162755)
			(xy 401.479305 -156.168855) (xy 401.533262 -156.182961) (xy 401.584591 -156.204773) (xy 401.632197 -156.233827)
			(xy 401.675065 -156.269502) (xy 401.712282 -156.311039) (xy 401.743055 -156.357552) (xy 401.766727 -156.408049)
			(xy 401.782795 -156.461456) (xy 401.790915 -156.516632) (xy 401.791424 -156.544518) (xy 401.790915 -156.572404)
			(xy 401.782795 -156.62758) (xy 401.766727 -156.680987) (xy 401.743055 -156.731484) (xy 401.712282 -156.777997)
			(xy 401.675065 -156.819534) (xy 401.632197 -156.855209) (xy 401.584591 -156.884263) (xy 401.533262 -156.906075)
			(xy 401.479305 -156.920181) (xy 401.423868 -156.926281) (xy 401.368134 -156.924244) (xy 401.313291 -156.914114)
			(xy 401.260507 -156.896107) (xy 401.210907 -156.870606) (xy 401.165549 -156.838155) (xy 401.1254 -156.799446)
			(xy 401.091314 -156.755303) (xy 401.064018 -156.706668) (xy 401.044095 -156.654577) (xy 401.031969 -156.60014)
			(xy 401.027898 -156.544518) (xy 386.208402 -156.544518) (xy 386.206129 -156.549366) (xy 386.175356 -156.595879)
			(xy 386.138139 -156.637416) (xy 386.095271 -156.673091) (xy 386.047665 -156.702145) (xy 385.996336 -156.723957)
			(xy 385.942379 -156.738063) (xy 385.886942 -156.744163) (xy 385.831208 -156.742126) (xy 385.776365 -156.731996)
			(xy 385.723581 -156.713989) (xy 385.673981 -156.688488) (xy 385.628623 -156.656037) (xy 385.588474 -156.617328)
			(xy 385.554388 -156.573185) (xy 385.527092 -156.52455) (xy 385.507169 -156.472459) (xy 385.495043 -156.418022)
			(xy 385.490972 -156.3624) (xy 384.647948 -156.3624) (xy 384.647948 -157.0736) (xy 399.596862 -157.0736)
			(xy 399.600933 -157.017978) (xy 399.613059 -156.963541) (xy 399.632982 -156.91145) (xy 399.660278 -156.862815)
			(xy 399.694364 -156.818672) (xy 399.734513 -156.779963) (xy 399.779871 -156.747512) (xy 399.829471 -156.722011)
			(xy 399.882255 -156.704004) (xy 399.937098 -156.693874) (xy 399.992832 -156.691837) (xy 400.048269 -156.697937)
			(xy 400.102226 -156.712043) (xy 400.153555 -156.733855) (xy 400.201161 -156.762909) (xy 400.244029 -156.798584)
			(xy 400.281246 -156.840121) (xy 400.312019 -156.886634) (xy 400.335691 -156.937131) (xy 400.351759 -156.990538)
			(xy 400.359796 -157.045152) (xy 409.710634 -157.045152) (xy 409.714705 -156.98953) (xy 409.726831 -156.935093)
			(xy 409.746754 -156.883002) (xy 409.77405 -156.834367) (xy 409.808136 -156.790224) (xy 409.848285 -156.751515)
			(xy 409.893643 -156.719064) (xy 409.943243 -156.693563) (xy 409.996027 -156.675556) (xy 410.05087 -156.665426)
			(xy 410.106604 -156.663389) (xy 410.162041 -156.669489) (xy 410.215998 -156.683595) (xy 410.267327 -156.705407)
			(xy 410.314933 -156.734461) (xy 410.357801 -156.770136) (xy 410.395018 -156.811673) (xy 410.425791 -156.858186)
			(xy 410.449463 -156.908683) (xy 410.465531 -156.96209) (xy 410.473651 -157.017266) (xy 410.47416 -157.045152)
			(xy 410.726634 -157.045152) (xy 410.730705 -156.98953) (xy 410.742831 -156.935093) (xy 410.762754 -156.883002)
			(xy 410.79005 -156.834367) (xy 410.824136 -156.790224) (xy 410.864285 -156.751515) (xy 410.909643 -156.719064)
			(xy 410.959243 -156.693563) (xy 411.012027 -156.675556) (xy 411.06687 -156.665426) (xy 411.122604 -156.663389)
			(xy 411.178041 -156.669489) (xy 411.231998 -156.683595) (xy 411.283327 -156.705407) (xy 411.330933 -156.734461)
			(xy 411.373801 -156.770136) (xy 411.411018 -156.811673) (xy 411.441791 -156.858186) (xy 411.465463 -156.908683)
			(xy 411.481531 -156.96209) (xy 411.489651 -157.017266) (xy 411.49016 -157.045152) (xy 411.489651 -157.073038)
			(xy 411.481531 -157.128214) (xy 411.465463 -157.181621) (xy 411.441791 -157.232118) (xy 411.411018 -157.278631)
			(xy 411.373801 -157.320168) (xy 411.330933 -157.355843) (xy 411.283327 -157.384897) (xy 411.231998 -157.406709)
			(xy 411.178041 -157.420815) (xy 411.122604 -157.426915) (xy 411.06687 -157.424878) (xy 411.012027 -157.414748)
			(xy 410.959243 -157.396741) (xy 410.909643 -157.37124) (xy 410.864285 -157.338789) (xy 410.824136 -157.30008)
			(xy 410.79005 -157.255937) (xy 410.762754 -157.207302) (xy 410.742831 -157.155211) (xy 410.730705 -157.100774)
			(xy 410.726634 -157.045152) (xy 410.47416 -157.045152) (xy 410.473651 -157.073038) (xy 410.465531 -157.128214)
			(xy 410.449463 -157.181621) (xy 410.425791 -157.232118) (xy 410.395018 -157.278631) (xy 410.357801 -157.320168)
			(xy 410.314933 -157.355843) (xy 410.267327 -157.384897) (xy 410.215998 -157.406709) (xy 410.162041 -157.420815)
			(xy 410.106604 -157.426915) (xy 410.05087 -157.424878) (xy 409.996027 -157.414748) (xy 409.943243 -157.396741)
			(xy 409.893643 -157.37124) (xy 409.848285 -157.338789) (xy 409.808136 -157.30008) (xy 409.77405 -157.255937)
			(xy 409.746754 -157.207302) (xy 409.726831 -157.155211) (xy 409.714705 -157.100774) (xy 409.710634 -157.045152)
			(xy 400.359796 -157.045152) (xy 400.359879 -157.045714) (xy 400.360388 -157.0736) (xy 400.359879 -157.101486)
			(xy 400.351759 -157.156662) (xy 400.335691 -157.210069) (xy 400.312019 -157.260566) (xy 400.281246 -157.307079)
			(xy 400.244029 -157.348616) (xy 400.201161 -157.384291) (xy 400.153555 -157.413345) (xy 400.102226 -157.435157)
			(xy 400.048269 -157.449263) (xy 399.992832 -157.455363) (xy 399.937098 -157.453326) (xy 399.882255 -157.443196)
			(xy 399.829471 -157.425189) (xy 399.779871 -157.399688) (xy 399.734513 -157.367237) (xy 399.694364 -157.328528)
			(xy 399.660278 -157.284385) (xy 399.632982 -157.23575) (xy 399.613059 -157.183659) (xy 399.600933 -157.129222)
			(xy 399.596862 -157.0736) (xy 384.647948 -157.0736) (xy 384.647948 -158.275274) (xy 384.648417 -158.285148)
			(xy 384.655869 -158.303437) (xy 384.662426 -158.310834) (xy 384.66268 -158.311088) (xy 385.328414 -158.976822)
			(xy 385.328922 -158.97733) (xy 385.336301 -158.98392) (xy 385.3546 -158.991385) (xy 385.364482 -158.991808)
			(xy 388.645908 -158.991808) (xy 388.655977 -158.992233) (xy 388.674579 -158.99995) (xy 388.681976 -159.006794)
			(xy 390.490964 -160.815782) (xy 390.498365 -160.82262) (xy 390.516964 -160.830334) (xy 390.527032 -160.830768)
			(xy 393.857734 -160.830768) (xy 393.866463 -160.830414) (xy 393.8829 -160.824532) (xy 393.896379 -160.813438)
			(xy 393.901168 -160.80613) (xy 393.953238 -160.720278) (xy 393.954 -160.693862) (xy 393.94765 -160.681924)
			(xy 393.926545 -160.640723) (xy 393.890716 -160.555358) (xy 393.862415 -160.467211) (xy 393.841854 -160.376944)
			(xy 393.829187 -160.285235) (xy 393.82451 -160.192775) (xy 393.827858 -160.100256) (xy 393.839205 -160.008375)
			(xy 393.858467 -159.917822) (xy 393.885499 -159.829277) (xy 393.920097 -159.743406) (xy 393.962001 -159.660854)
			(xy 394.010898 -159.582241) (xy 394.066419 -159.508158) (xy 394.128146 -159.439161) (xy 394.195618 -159.375769)
			(xy 394.268325 -159.318459) (xy 394.345723 -159.26766) (xy 394.427229 -159.223755) (xy 394.512231 -159.187074)
			(xy 394.60009 -159.157891) (xy 394.690147 -159.136427) (xy 394.781724 -159.122843) (xy 394.874133 -159.11724)
			(xy 394.96668 -159.119662) (xy 395.05867 -159.130089) (xy 395.149412 -159.148443) (xy 395.238223 -159.174587)
			(xy 395.324436 -159.208323) (xy 395.407403 -159.249399) (xy 395.486502 -159.297506) (xy 395.561138 -159.352282)
			(xy 395.630749 -159.413316) (xy 395.694813 -159.480149) (xy 395.752849 -159.552279) (xy 395.80442 -159.629165)
			(xy 395.849138 -159.710227) (xy 395.886669 -159.794857) (xy 395.91673 -159.88242) (xy 395.939094 -159.972257)
			(xy 395.946007 -160.015845) (xy 399.451879 -160.015845) (xy 399.451879 -159.958555) (xy 399.460032 -159.901847)
			(xy 399.476173 -159.846877) (xy 399.499971 -159.794764) (xy 399.530945 -159.746568) (xy 399.568461 -159.70327)
			(xy 399.611758 -159.665752) (xy 399.659953 -159.634777) (xy 399.712066 -159.610977) (xy 399.767036 -159.594835)
			(xy 399.823743 -159.58668) (xy 399.852388 -159.586168) (xy 399.862375 -159.586239) (xy 399.882324 -159.587255)
			(xy 399.892266 -159.5882) (xy 399.904458 -159.58947) (xy 399.926048 -159.581342) (xy 399.99793 -159.505142)
			(xy 400.004788 -159.483044) (xy 400.002756 -159.471106) (xy 400.000483 -159.456033) (xy 399.998069 -159.425643)
			(xy 399.99793 -159.4104) (xy 399.998378 -159.383149) (xy 400.006134 -159.329203) (xy 400.021488 -159.276909)
			(xy 400.044129 -159.227333) (xy 400.073594 -159.181483) (xy 400.109284 -159.140293) (xy 400.150473 -159.104601)
			(xy 400.196321 -159.075135) (xy 400.245897 -159.052493) (xy 400.29819 -159.037137) (xy 400.352137 -159.029379)
			(xy 400.406638 -159.029377) (xy 400.460585 -159.037131) (xy 400.512879 -159.052484) (xy 400.562456 -159.075123)
			(xy 400.608307 -159.104586) (xy 400.649498 -159.140275) (xy 400.685191 -159.181462) (xy 400.714659 -159.22731)
			(xy 400.737303 -159.276885) (xy 400.752661 -159.329178) (xy 400.76042 -159.383124) (xy 400.760424 -159.437625)
			(xy 400.752671 -159.491573) (xy 400.73732 -159.543867) (xy 400.714684 -159.593445) (xy 400.685221 -159.639297)
			(xy 400.649534 -159.680489) (xy 400.608348 -159.716183) (xy 400.562501 -159.745653) (xy 400.512927 -159.768298)
			(xy 400.460634 -159.783658) (xy 400.406689 -159.79142) (xy 400.379438 -159.791908) (xy 400.353022 -159.790892)
			(xy 400.34083 -159.79013) (xy 400.319494 -159.79902) (xy 400.249898 -159.877252) (xy 400.243802 -159.899604)
			(xy 400.246088 -159.911542) (xy 400.249442 -159.930284) (xy 400.253001 -159.968195) (xy 400.2532 -159.987234)
			(xy 400.252184 -160.018984) (xy 400.250914 -160.032954) (xy 400.263106 -160.057592) (xy 400.360642 -160.122108)
			(xy 400.388074 -160.123378) (xy 400.40052 -160.117028) (xy 400.42799 -160.103296) (xy 400.48624 -160.083846)
			(xy 400.546853 -160.073974) (xy 400.577558 -160.07334) (xy 400.604812 -160.073733) (xy 400.658767 -160.081484)
			(xy 400.711069 -160.096835) (xy 400.760654 -160.119473) (xy 400.806512 -160.148938) (xy 400.847711 -160.184628)
			(xy 400.883411 -160.225819) (xy 400.912885 -160.271671) (xy 400.935535 -160.321251) (xy 400.950897 -160.373549)
			(xy 400.958661 -160.427502) (xy 400.958667 -160.48201) (xy 400.950916 -160.535965) (xy 400.935565 -160.588267)
			(xy 400.912928 -160.637852) (xy 400.883464 -160.683711) (xy 400.847773 -160.724909) (xy 400.806583 -160.76061)
			(xy 400.760731 -160.790085) (xy 400.711151 -160.812734) (xy 400.658853 -160.828097) (xy 400.6049 -160.835861)
			(xy 400.550392 -160.835867) (xy 400.496437 -160.828117) (xy 400.444135 -160.812766) (xy 400.39455 -160.790129)
			(xy 400.348691 -160.760665) (xy 400.307492 -160.724975) (xy 400.271792 -160.683784) (xy 400.242316 -160.637933)
			(xy 400.219667 -160.588353) (xy 400.204303 -160.536055) (xy 400.196539 -160.482102) (xy 400.19605 -160.454848)
			(xy 400.196558 -160.433004) (xy 400.197574 -160.419034) (xy 400.184874 -160.39465) (xy 400.085814 -160.332166)
			(xy 400.058382 -160.331404) (xy 400.04619 -160.338262) (xy 400.023865 -160.350161) (xy 399.976856 -160.368861)
			(xy 399.92787 -160.381507) (xy 399.877684 -160.387899) (xy 399.852388 -160.3883) (xy 399.823743 -160.38772)
			(xy 399.767036 -160.379565) (xy 399.712066 -160.363423) (xy 399.659953 -160.339623) (xy 399.611758 -160.308648)
			(xy 399.568461 -160.27113) (xy 399.530945 -160.227832) (xy 399.499971 -160.179636) (xy 399.476173 -160.127523)
			(xy 399.460032 -160.072553) (xy 399.451879 -160.015845) (xy 395.946007 -160.015845) (xy 395.953595 -160.063694)
			(xy 395.960122 -160.156042) (xy 395.958628 -160.248609) (xy 395.949122 -160.340699) (xy 395.931677 -160.43162)
			(xy 395.906424 -160.520688) (xy 395.873552 -160.607235) (xy 395.85392 -160.649158) (xy 395.848078 -160.661096)
			(xy 395.849348 -160.68675) (xy 395.90218 -160.771078) (xy 395.907057 -160.778156) (xy 395.92053 -160.788812)
			(xy 395.93677 -160.794411) (xy 395.94536 -160.7947) (xy 397.56969 -160.7947) (xy 397.612039 -160.795204)
			(xy 397.69639 -160.802889) (xy 397.779709 -160.818118) (xy 397.820642 -160.82899) (xy 397.827246 -160.830768)
			(xy 398.039336 -160.830768) (xy 398.049404 -160.831197) (xy 398.068002 -160.838917) (xy 398.075404 -160.845754)
			(xy 398.987518 -161.757868) (xy 409.659834 -161.757868) (xy 409.663905 -161.702246) (xy 409.676031 -161.647809)
			(xy 409.695954 -161.595718) (xy 409.72325 -161.547083) (xy 409.757336 -161.50294) (xy 409.797485 -161.464231)
			(xy 409.842843 -161.43178) (xy 409.892443 -161.406279) (xy 409.945227 -161.388272) (xy 410.00007 -161.378142)
			(xy 410.055804 -161.376105) (xy 410.111241 -161.382205) (xy 410.165198 -161.396311) (xy 410.216527 -161.418123)
			(xy 410.264133 -161.447177) (xy 410.307001 -161.482852) (xy 410.344218 -161.524389) (xy 410.374991 -161.570902)
			(xy 410.398663 -161.621399) (xy 410.414731 -161.674806) (xy 410.422851 -161.729982) (xy 410.42336 -161.757868)
			(xy 410.422851 -161.785754) (xy 410.414731 -161.84093) (xy 410.398663 -161.894337) (xy 410.374991 -161.944834)
			(xy 410.344218 -161.991347) (xy 410.307001 -162.032884) (xy 410.264133 -162.068559) (xy 410.239242 -162.08375)
			(xy 411.159958 -162.08375) (xy 411.164029 -162.028128) (xy 411.176155 -161.973691) (xy 411.196078 -161.9216)
			(xy 411.223374 -161.872965) (xy 411.25746 -161.828822) (xy 411.297609 -161.790113) (xy 411.342967 -161.757662)
			(xy 411.392567 -161.732161) (xy 411.445351 -161.714154) (xy 411.500194 -161.704024) (xy 411.555928 -161.701987)
			(xy 411.611365 -161.708087) (xy 411.665322 -161.722193) (xy 411.716651 -161.744005) (xy 411.764257 -161.773059)
			(xy 411.807125 -161.808734) (xy 411.844342 -161.850271) (xy 411.875115 -161.896784) (xy 411.898787 -161.947281)
			(xy 411.914855 -162.000688) (xy 411.922975 -162.055864) (xy 411.923484 -162.08375) (xy 411.922975 -162.111636)
			(xy 411.914855 -162.166812) (xy 411.898787 -162.220219) (xy 411.875115 -162.270716) (xy 411.844342 -162.317229)
			(xy 411.807125 -162.358766) (xy 411.764257 -162.394441) (xy 411.716651 -162.423495) (xy 411.665322 -162.445307)
			(xy 411.611365 -162.459413) (xy 411.555928 -162.465513) (xy 411.500194 -162.463476) (xy 411.445351 -162.453346)
			(xy 411.392567 -162.435339) (xy 411.342967 -162.409838) (xy 411.297609 -162.377387) (xy 411.25746 -162.338678)
			(xy 411.223374 -162.294535) (xy 411.196078 -162.2459) (xy 411.176155 -162.193809) (xy 411.164029 -162.139372)
			(xy 411.159958 -162.08375) (xy 410.239242 -162.08375) (xy 410.216527 -162.097613) (xy 410.165198 -162.119425)
			(xy 410.111241 -162.133531) (xy 410.055804 -162.139631) (xy 410.00007 -162.137594) (xy 409.945227 -162.127464)
			(xy 409.892443 -162.109457) (xy 409.842843 -162.083956) (xy 409.797485 -162.051505) (xy 409.757336 -162.012796)
			(xy 409.72325 -161.968653) (xy 409.695954 -161.920018) (xy 409.676031 -161.867927) (xy 409.663905 -161.81349)
			(xy 409.659834 -161.757868) (xy 398.987518 -161.757868) (xy 400.268948 -163.039298) (xy 400.276296 -163.046101)
			(xy 400.294758 -163.053817) (xy 400.304762 -163.054284) (xy 400.805396 -163.054284) (xy 400.83147 -163.054779)
			(xy 400.88298 -163.062905) (xy 400.932586 -163.078989) (xy 400.979064 -163.102634) (xy 401.021271 -163.133259)
			(xy 401.040092 -163.151312) (xy 404.594314 -166.705534) (xy 410.42793 -166.705534) (xy 410.432001 -166.649912)
			(xy 410.444127 -166.595475) (xy 410.46405 -166.543384) (xy 410.491346 -166.494749) (xy 410.525432 -166.450606)
			(xy 410.565581 -166.411897) (xy 410.610939 -166.379446) (xy 410.660539 -166.353945) (xy 410.713323 -166.335938)
			(xy 410.768166 -166.325808) (xy 410.8239 -166.323771) (xy 410.879337 -166.329871) (xy 410.933294 -166.343977)
			(xy 410.984623 -166.365789) (xy 411.032229 -166.394843) (xy 411.075097 -166.430518) (xy 411.112314 -166.472055)
			(xy 411.143087 -166.518568) (xy 411.166759 -166.569065) (xy 411.182827 -166.622472) (xy 411.190947 -166.677648)
			(xy 411.191456 -166.705534) (xy 411.44393 -166.705534) (xy 411.448001 -166.649912) (xy 411.460127 -166.595475)
			(xy 411.48005 -166.543384) (xy 411.507346 -166.494749) (xy 411.541432 -166.450606) (xy 411.581581 -166.411897)
			(xy 411.626939 -166.379446) (xy 411.676539 -166.353945) (xy 411.729323 -166.335938) (xy 411.784166 -166.325808)
			(xy 411.8399 -166.323771) (xy 411.895337 -166.329871) (xy 411.949294 -166.343977) (xy 412.000623 -166.365789)
			(xy 412.048229 -166.394843) (xy 412.091097 -166.430518) (xy 412.128314 -166.472055) (xy 412.159087 -166.518568)
			(xy 412.182759 -166.569065) (xy 412.198827 -166.622472) (xy 412.206947 -166.677648) (xy 412.207456 -166.705534)
			(xy 412.206947 -166.73342) (xy 412.198827 -166.788596) (xy 412.182759 -166.842003) (xy 412.159087 -166.8925)
			(xy 412.128314 -166.939013) (xy 412.091097 -166.98055) (xy 412.048229 -167.016225) (xy 412.000623 -167.045279)
			(xy 411.949294 -167.067091) (xy 411.895337 -167.081197) (xy 411.8399 -167.087297) (xy 411.784166 -167.08526)
			(xy 411.729323 -167.07513) (xy 411.676539 -167.057123) (xy 411.626939 -167.031622) (xy 411.581581 -166.999171)
			(xy 411.541432 -166.960462) (xy 411.507346 -166.916319) (xy 411.48005 -166.867684) (xy 411.460127 -166.815593)
			(xy 411.448001 -166.761156) (xy 411.44393 -166.705534) (xy 411.191456 -166.705534) (xy 411.190947 -166.73342)
			(xy 411.182827 -166.788596) (xy 411.166759 -166.842003) (xy 411.143087 -166.8925) (xy 411.112314 -166.939013)
			(xy 411.075097 -166.98055) (xy 411.032229 -167.016225) (xy 410.984623 -167.045279) (xy 410.933294 -167.067091)
			(xy 410.879337 -167.081197) (xy 410.8239 -167.087297) (xy 410.768166 -167.08526) (xy 410.713323 -167.07513)
			(xy 410.660539 -167.057123) (xy 410.610939 -167.031622) (xy 410.565581 -166.999171) (xy 410.525432 -166.960462)
			(xy 410.491346 -166.916319) (xy 410.46405 -166.867684) (xy 410.444127 -166.815593) (xy 410.432001 -166.761156)
			(xy 410.42793 -166.705534) (xy 404.594314 -166.705534) (xy 405.82469 -167.93591) (xy 405.842805 -167.954689)
			(xy 405.873495 -167.996885) (xy 405.8972 -168.043366) (xy 405.913336 -168.092985) (xy 405.921504 -168.144518)
			(xy 405.921972 -168.170606) (xy 405.921972 -168.67124) (xy 405.922453 -168.681205) (xy 405.930031 -168.699639)
			(xy 405.936704 -168.707054) (xy 406.031446 -168.801796) (xy 406.038299 -168.809192) (xy 406.046043 -168.82779)
			(xy 406.046432 -168.837864) (xy 406.046432 -168.94556) (xy 410.550104 -168.94556) (xy 410.554175 -168.889938)
			(xy 410.566301 -168.835501) (xy 410.586224 -168.78341) (xy 410.61352 -168.734775) (xy 410.647606 -168.690632)
			(xy 410.687755 -168.651923) (xy 410.733113 -168.619472) (xy 410.782713 -168.593971) (xy 410.835497 -168.575964)
			(xy 410.89034 -168.565834) (xy 410.946074 -168.563797) (xy 411.001511 -168.569897) (xy 411.055468 -168.584003)
			(xy 411.106797 -168.605815) (xy 411.154403 -168.634869) (xy 411.197271 -168.670544) (xy 411.234488 -168.712081)
			(xy 411.265261 -168.758594) (xy 411.288933 -168.809091) (xy 411.305001 -168.862498) (xy 411.313121 -168.917674)
			(xy 411.31363 -168.94556) (xy 411.313121 -168.973446) (xy 411.305001 -169.028622) (xy 411.288933 -169.082029)
			(xy 411.265261 -169.132526) (xy 411.234488 -169.179039) (xy 411.197271 -169.220576) (xy 411.154403 -169.256251)
			(xy 411.106797 -169.285305) (xy 411.055468 -169.307117) (xy 411.001511 -169.321223) (xy 410.946074 -169.327323)
			(xy 410.89034 -169.325286) (xy 410.835497 -169.315156) (xy 410.782713 -169.297149) (xy 410.733113 -169.271648)
			(xy 410.687755 -169.239197) (xy 410.647606 -169.200488) (xy 410.61352 -169.156345) (xy 410.586224 -169.10771)
			(xy 410.566301 -169.055619) (xy 410.554175 -169.001182) (xy 410.550104 -168.94556) (xy 406.046432 -168.94556)
			(xy 406.046432 -171.039536) (xy 406.046862 -171.049603) (xy 406.05459 -171.068195) (xy 406.061418 -171.075604)
			(xy 407.315162 -172.329348) (xy 409.347922 -172.329348) (xy 409.351993 -172.273726) (xy 409.364119 -172.219289)
			(xy 409.384042 -172.167198) (xy 409.411338 -172.118563) (xy 409.445424 -172.07442) (xy 409.485573 -172.035711)
			(xy 409.530931 -172.00326) (xy 409.580531 -171.977759) (xy 409.633315 -171.959752) (xy 409.688158 -171.949622)
			(xy 409.743892 -171.947585) (xy 409.799329 -171.953685) (xy 409.853286 -171.967791) (xy 409.904615 -171.989603)
			(xy 409.952221 -172.018657) (xy 409.995089 -172.054332) (xy 410.032306 -172.095869) (xy 410.063079 -172.142382)
			(xy 410.086751 -172.192879) (xy 410.102819 -172.246286) (xy 410.110939 -172.301462) (xy 410.111448 -172.329348)
			(xy 410.110939 -172.357234) (xy 410.102819 -172.41241) (xy 410.086751 -172.465817) (xy 410.063079 -172.516314)
			(xy 410.032306 -172.562827) (xy 409.995089 -172.604364) (xy 409.952221 -172.640039) (xy 409.904615 -172.669093)
			(xy 409.853286 -172.690905) (xy 409.799329 -172.705011) (xy 409.743892 -172.711111) (xy 409.688158 -172.709074)
			(xy 409.633315 -172.698944) (xy 409.580531 -172.680937) (xy 409.530931 -172.655436) (xy 409.485573 -172.622985)
			(xy 409.445424 -172.584276) (xy 409.411338 -172.540133) (xy 409.384042 -172.491498) (xy 409.364119 -172.439407)
			(xy 409.351993 -172.38497) (xy 409.347922 -172.329348) (xy 407.315162 -172.329348) (xy 408.06624 -173.080426)
			(xy 408.073637 -173.087274) (xy 408.092236 -173.095006) (xy 408.102308 -173.095412)
		)
		(stroke
			(width 0)
			(type solid)
		)
		(fill yes)
		(layer "In13.Cu")
		(net "P3V3_NIC6")
	)
	(gr_poly
		(pts
			(xy 460.425292 -238.204756) (xy 460.435164 -238.204284) (xy 460.453449 -238.196828) (xy 460.460852 -238.190278)
			(xy 460.461106 -238.190024) (xy 463.254344 -235.396786) (xy 463.261194 -235.38939) (xy 463.268933 -235.370791)
			(xy 463.26933 -235.360718) (xy 463.26933 -142.12316) (xy 463.2689 -142.113092) (xy 463.261179 -142.094496)
			(xy 463.254344 -142.087092) (xy 463.012028 -141.844776) (xy 463.004629 -141.837933) (xy 462.98603 -141.830213)
			(xy 462.97596 -141.82979) (xy 443.332616 -141.82979) (xy 443.322456 -141.830806) (xy 443.31255 -141.832838)
			(xy 443.303406 -141.835632) (xy 443.273323 -141.847164) (xy 443.210137 -141.859709) (xy 443.17793 -141.860524)
			(xy 412.934658 -141.860524) (xy 412.924592 -141.860955) (xy 412.906001 -141.868683) (xy 412.89859 -141.87551)
			(xy 412.590234 -142.183866) (xy 412.583394 -142.191266) (xy 412.575679 -142.209865) (xy 412.575248 -142.219934)
			(xy 412.575248 -142.829788) (xy 412.56966 -142.835122) (xy 412.56966 -143.48714) (xy 414.899348 -143.48714)
			(xy 414.899348 -142.62354) (xy 414.899838 -142.593556) (xy 414.907666 -142.5341) (xy 414.923187 -142.476175)
			(xy 414.946136 -142.420771) (xy 414.97612 -142.368837) (xy 415.012626 -142.321261) (xy 415.055031 -142.278856)
			(xy 415.102607 -142.24235) (xy 415.154541 -142.212366) (xy 415.209945 -142.189417) (xy 415.26787 -142.173896)
			(xy 415.327326 -142.166068) (xy 415.387294 -142.166068) (xy 415.44675 -142.173896) (xy 415.504675 -142.189417)
			(xy 415.560079 -142.212366) (xy 415.612013 -142.24235) (xy 415.659589 -142.278856) (xy 415.701994 -142.321261)
			(xy 415.7385 -142.368837) (xy 415.768484 -142.420771) (xy 415.791433 -142.476175) (xy 415.806954 -142.5341)
			(xy 415.814782 -142.593556) (xy 415.815272 -142.62354) (xy 415.815272 -143.479266) (xy 429.3743 -143.479266)
			(xy 429.3743 -142.615666) (xy 429.37479 -142.585682) (xy 429.382618 -142.526226) (xy 429.398139 -142.468301)
			(xy 429.421088 -142.412897) (xy 429.451072 -142.360963) (xy 429.487578 -142.313387) (xy 429.529983 -142.270982)
			(xy 429.577559 -142.234476) (xy 429.629493 -142.204492) (xy 429.684897 -142.181543) (xy 429.742822 -142.166022)
			(xy 429.802278 -142.158194) (xy 429.862246 -142.158194) (xy 429.921702 -142.166022) (xy 429.979627 -142.181543)
			(xy 430.035031 -142.204492) (xy 430.086965 -142.234476) (xy 430.134541 -142.270982) (xy 430.176946 -142.313387)
			(xy 430.213452 -142.360963) (xy 430.243436 -142.412897) (xy 430.266385 -142.468301) (xy 430.281906 -142.526226)
			(xy 430.289734 -142.585682) (xy 430.290224 -142.615666) (xy 430.290224 -143.479266) (xy 430.289734 -143.50925)
			(xy 430.281906 -143.568706) (xy 430.266385 -143.626631) (xy 430.243436 -143.682035) (xy 430.213452 -143.733969)
			(xy 430.176946 -143.781545) (xy 430.134541 -143.82395) (xy 430.086965 -143.860456) (xy 430.035031 -143.89044)
			(xy 429.979627 -143.913389) (xy 429.921702 -143.92891) (xy 429.862246 -143.936738) (xy 429.802278 -143.936738)
			(xy 429.742822 -143.92891) (xy 429.684897 -143.913389) (xy 429.629493 -143.89044) (xy 429.577559 -143.860456)
			(xy 429.529983 -143.82395) (xy 429.487578 -143.781545) (xy 429.451072 -143.733969) (xy 429.421088 -143.682035)
			(xy 429.398139 -143.626631) (xy 429.382618 -143.568706) (xy 429.37479 -143.50925) (xy 429.3743 -143.479266)
			(xy 415.815272 -143.479266) (xy 415.815272 -143.48714) (xy 415.814782 -143.517124) (xy 415.806954 -143.57658)
			(xy 415.791433 -143.634505) (xy 415.768484 -143.689909) (xy 415.7385 -143.741843) (xy 415.701994 -143.789419)
			(xy 415.659589 -143.831824) (xy 415.612013 -143.86833) (xy 415.560079 -143.898314) (xy 415.504675 -143.921263)
			(xy 415.44675 -143.936784) (xy 415.387294 -143.944612) (xy 415.327326 -143.944612) (xy 415.26787 -143.936784)
			(xy 415.209945 -143.921263) (xy 415.154541 -143.898314) (xy 415.102607 -143.86833) (xy 415.055031 -143.831824)
			(xy 415.012626 -143.789419) (xy 414.97612 -143.741843) (xy 414.946136 -143.689909) (xy 414.923187 -143.634505)
			(xy 414.907666 -143.57658) (xy 414.899838 -143.517124) (xy 414.899348 -143.48714) (xy 412.56966 -143.48714)
			(xy 412.56966 -145.287238) (xy 413.045148 -145.287238) (xy 413.045148 -144.423638) (xy 413.045638 -144.393654)
			(xy 413.053466 -144.334198) (xy 413.068987 -144.276273) (xy 413.091936 -144.220869) (xy 413.12192 -144.168935)
			(xy 413.158426 -144.121359) (xy 413.200831 -144.078954) (xy 413.248407 -144.042448) (xy 413.300341 -144.012464)
			(xy 413.355745 -143.989515) (xy 413.41367 -143.973994) (xy 413.473126 -143.966166) (xy 413.533094 -143.966166)
			(xy 413.59255 -143.973994) (xy 413.650475 -143.989515) (xy 413.705879 -144.012464) (xy 413.757813 -144.042448)
			(xy 413.805389 -144.078954) (xy 413.847794 -144.121359) (xy 413.8843 -144.168935) (xy 413.914284 -144.220869)
			(xy 413.937233 -144.276273) (xy 413.952754 -144.334198) (xy 413.960582 -144.393654) (xy 413.961072 -144.423638)
			(xy 413.961072 -145.285714) (xy 432.016408 -145.285714) (xy 432.016408 -144.422114) (xy 432.016898 -144.39213)
			(xy 432.024726 -144.332674) (xy 432.040247 -144.274749) (xy 432.063196 -144.219345) (xy 432.09318 -144.167411)
			(xy 432.129686 -144.119835) (xy 432.172091 -144.07743) (xy 432.219667 -144.040924) (xy 432.271601 -144.01094)
			(xy 432.327005 -143.987991) (xy 432.38493 -143.97247) (xy 432.444386 -143.964642) (xy 432.504354 -143.964642)
			(xy 432.56381 -143.97247) (xy 432.621735 -143.987991) (xy 432.677139 -144.01094) (xy 432.729073 -144.040924)
			(xy 432.776649 -144.07743) (xy 432.819054 -144.119835) (xy 432.85556 -144.167411) (xy 432.885544 -144.219345)
			(xy 432.908493 -144.274749) (xy 432.924014 -144.332674) (xy 432.931842 -144.39213) (xy 432.932332 -144.422114)
			(xy 432.932332 -145.285714) (xy 432.931842 -145.315698) (xy 432.924014 -145.375154) (xy 432.908493 -145.433079)
			(xy 432.885544 -145.488483) (xy 432.85556 -145.540417) (xy 432.819054 -145.587993) (xy 432.776649 -145.630398)
			(xy 432.729073 -145.666904) (xy 432.677139 -145.696888) (xy 432.621735 -145.719837) (xy 432.56381 -145.735358)
			(xy 432.504354 -145.743186) (xy 432.444386 -145.743186) (xy 432.38493 -145.735358) (xy 432.327005 -145.719837)
			(xy 432.271601 -145.696888) (xy 432.219667 -145.666904) (xy 432.172091 -145.630398) (xy 432.129686 -145.587993)
			(xy 432.09318 -145.540417) (xy 432.063196 -145.488483) (xy 432.040247 -145.433079) (xy 432.024726 -145.375154)
			(xy 432.016898 -145.315698) (xy 432.016408 -145.285714) (xy 413.961072 -145.285714) (xy 413.961072 -145.287238)
			(xy 413.960582 -145.317222) (xy 413.952754 -145.376678) (xy 413.937233 -145.434603) (xy 413.914284 -145.490007)
			(xy 413.8843 -145.541941) (xy 413.847794 -145.589517) (xy 413.805389 -145.631922) (xy 413.757813 -145.668428)
			(xy 413.705879 -145.698412) (xy 413.650475 -145.721361) (xy 413.59255 -145.736882) (xy 413.533094 -145.74471)
			(xy 413.473126 -145.74471) (xy 413.41367 -145.736882) (xy 413.355745 -145.721361) (xy 413.300341 -145.698412)
			(xy 413.248407 -145.668428) (xy 413.200831 -145.631922) (xy 413.158426 -145.589517) (xy 413.12192 -145.541941)
			(xy 413.091936 -145.490007) (xy 413.068987 -145.434603) (xy 413.053466 -145.376678) (xy 413.045638 -145.317222)
			(xy 413.045148 -145.287238) (xy 412.56966 -145.287238) (xy 412.56966 -147.087336) (xy 414.899348 -147.087336)
			(xy 414.899348 -146.223736) (xy 414.899838 -146.193752) (xy 414.907666 -146.134296) (xy 414.923187 -146.076371)
			(xy 414.946136 -146.020967) (xy 414.97612 -145.969033) (xy 415.012626 -145.921457) (xy 415.055031 -145.879052)
			(xy 415.102607 -145.842546) (xy 415.154541 -145.812562) (xy 415.209945 -145.789613) (xy 415.26787 -145.774092)
			(xy 415.327326 -145.766264) (xy 415.387294 -145.766264) (xy 415.44675 -145.774092) (xy 415.504675 -145.789613)
			(xy 415.560079 -145.812562) (xy 415.612013 -145.842546) (xy 415.659589 -145.879052) (xy 415.701994 -145.921457)
			(xy 415.7385 -145.969033) (xy 415.768484 -146.020967) (xy 415.791433 -146.076371) (xy 415.806954 -146.134296)
			(xy 415.814782 -146.193752) (xy 415.815272 -146.223736) (xy 415.815272 -147.079208) (xy 429.3743 -147.079208)
			(xy 429.3743 -146.215608) (xy 429.37479 -146.185624) (xy 429.382618 -146.126168) (xy 429.398139 -146.068243)
			(xy 429.421088 -146.012839) (xy 429.451072 -145.960905) (xy 429.487578 -145.913329) (xy 429.529983 -145.870924)
			(xy 429.577559 -145.834418) (xy 429.629493 -145.804434) (xy 429.684897 -145.781485) (xy 429.742822 -145.765964)
			(xy 429.802278 -145.758136) (xy 429.862246 -145.758136) (xy 429.921702 -145.765964) (xy 429.979627 -145.781485)
			(xy 430.035031 -145.804434) (xy 430.086965 -145.834418) (xy 430.134541 -145.870924) (xy 430.176946 -145.913329)
			(xy 430.213452 -145.960905) (xy 430.243436 -146.012839) (xy 430.266385 -146.068243) (xy 430.281906 -146.126168)
			(xy 430.289734 -146.185624) (xy 430.290224 -146.215608) (xy 430.290224 -147.079208) (xy 430.289734 -147.109192)
			(xy 430.281906 -147.168648) (xy 430.266385 -147.226573) (xy 430.243436 -147.281977) (xy 430.213452 -147.333911)
			(xy 430.176946 -147.381487) (xy 430.134541 -147.423892) (xy 430.086965 -147.460398) (xy 430.035031 -147.490382)
			(xy 429.979627 -147.513331) (xy 429.921702 -147.528852) (xy 429.862246 -147.53668) (xy 429.802278 -147.53668)
			(xy 429.742822 -147.528852) (xy 429.684897 -147.513331) (xy 429.629493 -147.490382) (xy 429.577559 -147.460398)
			(xy 429.529983 -147.423892) (xy 429.487578 -147.381487) (xy 429.451072 -147.333911) (xy 429.421088 -147.281977)
			(xy 429.398139 -147.226573) (xy 429.382618 -147.168648) (xy 429.37479 -147.109192) (xy 429.3743 -147.079208)
			(xy 415.815272 -147.079208) (xy 415.815272 -147.087336) (xy 415.814782 -147.11732) (xy 415.806954 -147.176776)
			(xy 415.791433 -147.234701) (xy 415.768484 -147.290105) (xy 415.7385 -147.342039) (xy 415.701994 -147.389615)
			(xy 415.659589 -147.43202) (xy 415.612013 -147.468526) (xy 415.560079 -147.49851) (xy 415.504675 -147.521459)
			(xy 415.44675 -147.53698) (xy 415.387294 -147.544808) (xy 415.327326 -147.544808) (xy 415.26787 -147.53698)
			(xy 415.209945 -147.521459) (xy 415.154541 -147.49851) (xy 415.102607 -147.468526) (xy 415.055031 -147.43202)
			(xy 415.012626 -147.389615) (xy 414.97612 -147.342039) (xy 414.946136 -147.290105) (xy 414.923187 -147.234701)
			(xy 414.907666 -147.176776) (xy 414.899838 -147.11732) (xy 414.899348 -147.087336) (xy 412.56966 -147.087336)
			(xy 412.56966 -148.887434) (xy 413.045148 -148.887434) (xy 413.045148 -148.023834) (xy 413.045638 -147.99385)
			(xy 413.053466 -147.934394) (xy 413.068987 -147.876469) (xy 413.091936 -147.821065) (xy 413.12192 -147.769131)
			(xy 413.158426 -147.721555) (xy 413.200831 -147.67915) (xy 413.248407 -147.642644) (xy 413.300341 -147.61266)
			(xy 413.355745 -147.589711) (xy 413.41367 -147.57419) (xy 413.473126 -147.566362) (xy 413.533094 -147.566362)
			(xy 413.59255 -147.57419) (xy 413.650475 -147.589711) (xy 413.705879 -147.61266) (xy 413.757813 -147.642644)
			(xy 413.805389 -147.67915) (xy 413.847794 -147.721555) (xy 413.8843 -147.769131) (xy 413.914284 -147.821065)
			(xy 413.937233 -147.876469) (xy 413.952754 -147.934394) (xy 413.960582 -147.99385) (xy 413.961072 -148.023834)
			(xy 413.961072 -148.88591) (xy 432.016408 -148.88591) (xy 432.016408 -148.02231) (xy 432.016898 -147.992326)
			(xy 432.024726 -147.93287) (xy 432.040247 -147.874945) (xy 432.063196 -147.819541) (xy 432.09318 -147.767607)
			(xy 432.129686 -147.720031) (xy 432.172091 -147.677626) (xy 432.219667 -147.64112) (xy 432.271601 -147.611136)
			(xy 432.327005 -147.588187) (xy 432.38493 -147.572666) (xy 432.444386 -147.564838) (xy 432.504354 -147.564838)
			(xy 432.56381 -147.572666) (xy 432.621735 -147.588187) (xy 432.677139 -147.611136) (xy 432.729073 -147.64112)
			(xy 432.776649 -147.677626) (xy 432.819054 -147.720031) (xy 432.85556 -147.767607) (xy 432.885544 -147.819541)
			(xy 432.908493 -147.874945) (xy 432.924014 -147.93287) (xy 432.931842 -147.992326) (xy 432.932332 -148.02231)
			(xy 432.932332 -148.88591) (xy 432.931842 -148.915894) (xy 432.924014 -148.97535) (xy 432.908493 -149.033275)
			(xy 432.885544 -149.088679) (xy 432.85556 -149.140613) (xy 432.819054 -149.188189) (xy 432.776649 -149.230594)
			(xy 432.729073 -149.2671) (xy 432.677139 -149.297084) (xy 432.621735 -149.320033) (xy 432.56381 -149.335554)
			(xy 432.504354 -149.343382) (xy 432.444386 -149.343382) (xy 432.38493 -149.335554) (xy 432.327005 -149.320033)
			(xy 432.271601 -149.297084) (xy 432.219667 -149.2671) (xy 432.172091 -149.230594) (xy 432.129686 -149.188189)
			(xy 432.09318 -149.140613) (xy 432.063196 -149.088679) (xy 432.040247 -149.033275) (xy 432.024726 -148.97535)
			(xy 432.016898 -148.915894) (xy 432.016408 -148.88591) (xy 413.961072 -148.88591) (xy 413.961072 -148.887434)
			(xy 413.960582 -148.917418) (xy 413.952754 -148.976874) (xy 413.937233 -149.034799) (xy 413.914284 -149.090203)
			(xy 413.8843 -149.142137) (xy 413.847794 -149.189713) (xy 413.805389 -149.232118) (xy 413.757813 -149.268624)
			(xy 413.705879 -149.298608) (xy 413.650475 -149.321557) (xy 413.59255 -149.337078) (xy 413.533094 -149.344906)
			(xy 413.473126 -149.344906) (xy 413.41367 -149.337078) (xy 413.355745 -149.321557) (xy 413.300341 -149.298608)
			(xy 413.248407 -149.268624) (xy 413.200831 -149.232118) (xy 413.158426 -149.189713) (xy 413.12192 -149.142137)
			(xy 413.091936 -149.090203) (xy 413.068987 -149.034799) (xy 413.053466 -148.976874) (xy 413.045638 -148.917418)
			(xy 413.045148 -148.887434) (xy 412.56966 -148.887434) (xy 412.56966 -150.687278) (xy 414.899348 -150.687278)
			(xy 414.899348 -149.823678) (xy 414.899838 -149.793694) (xy 414.907666 -149.734238) (xy 414.923187 -149.676313)
			(xy 414.946136 -149.620909) (xy 414.97612 -149.568975) (xy 415.012626 -149.521399) (xy 415.055031 -149.478994)
			(xy 415.102607 -149.442488) (xy 415.154541 -149.412504) (xy 415.209945 -149.389555) (xy 415.26787 -149.374034)
			(xy 415.327326 -149.366206) (xy 415.387294 -149.366206) (xy 415.44675 -149.374034) (xy 415.504675 -149.389555)
			(xy 415.560079 -149.412504) (xy 415.612013 -149.442488) (xy 415.659589 -149.478994) (xy 415.701994 -149.521399)
			(xy 415.7385 -149.568975) (xy 415.768484 -149.620909) (xy 415.791433 -149.676313) (xy 415.806954 -149.734238)
			(xy 415.814782 -149.793694) (xy 415.815272 -149.823678) (xy 415.815272 -150.67915) (xy 429.3743 -150.67915)
			(xy 429.3743 -149.81555) (xy 429.37479 -149.785566) (xy 429.382618 -149.72611) (xy 429.398139 -149.668185)
			(xy 429.421088 -149.612781) (xy 429.451072 -149.560847) (xy 429.487578 -149.513271) (xy 429.529983 -149.470866)
			(xy 429.577559 -149.43436) (xy 429.629493 -149.404376) (xy 429.684897 -149.381427) (xy 429.742822 -149.365906)
			(xy 429.802278 -149.358078) (xy 429.862246 -149.358078) (xy 429.921702 -149.365906) (xy 429.979627 -149.381427)
			(xy 430.035031 -149.404376) (xy 430.086965 -149.43436) (xy 430.134541 -149.470866) (xy 430.176946 -149.513271)
			(xy 430.213452 -149.560847) (xy 430.243436 -149.612781) (xy 430.266385 -149.668185) (xy 430.281906 -149.72611)
			(xy 430.289734 -149.785566) (xy 430.290224 -149.81555) (xy 430.290224 -150.67915) (xy 430.289734 -150.709134)
			(xy 430.281906 -150.76859) (xy 430.266385 -150.826515) (xy 430.243436 -150.881919) (xy 430.213452 -150.933853)
			(xy 430.176946 -150.981429) (xy 430.134541 -151.023834) (xy 430.086965 -151.06034) (xy 430.035031 -151.090324)
			(xy 429.979627 -151.113273) (xy 429.921702 -151.128794) (xy 429.862246 -151.136622) (xy 429.802278 -151.136622)
			(xy 429.742822 -151.128794) (xy 429.684897 -151.113273) (xy 429.629493 -151.090324) (xy 429.577559 -151.06034)
			(xy 429.529983 -151.023834) (xy 429.487578 -150.981429) (xy 429.451072 -150.933853) (xy 429.421088 -150.881919)
			(xy 429.398139 -150.826515) (xy 429.382618 -150.76859) (xy 429.37479 -150.709134) (xy 429.3743 -150.67915)
			(xy 415.815272 -150.67915) (xy 415.815272 -150.687278) (xy 415.814782 -150.717262) (xy 415.806954 -150.776718)
			(xy 415.791433 -150.834643) (xy 415.768484 -150.890047) (xy 415.7385 -150.941981) (xy 415.701994 -150.989557)
			(xy 415.659589 -151.031962) (xy 415.612013 -151.068468) (xy 415.560079 -151.098452) (xy 415.504675 -151.121401)
			(xy 415.44675 -151.136922) (xy 415.387294 -151.14475) (xy 415.327326 -151.14475) (xy 415.26787 -151.136922)
			(xy 415.209945 -151.121401) (xy 415.154541 -151.098452) (xy 415.102607 -151.068468) (xy 415.055031 -151.031962)
			(xy 415.012626 -150.989557) (xy 414.97612 -150.941981) (xy 414.946136 -150.890047) (xy 414.923187 -150.834643)
			(xy 414.907666 -150.776718) (xy 414.899838 -150.717262) (xy 414.899348 -150.687278) (xy 412.56966 -150.687278)
			(xy 412.56966 -152.487376) (xy 413.045148 -152.487376) (xy 413.045148 -151.623776) (xy 413.045638 -151.593792)
			(xy 413.053466 -151.534336) (xy 413.068987 -151.476411) (xy 413.091936 -151.421007) (xy 413.12192 -151.369073)
			(xy 413.158426 -151.321497) (xy 413.200831 -151.279092) (xy 413.248407 -151.242586) (xy 413.300341 -151.212602)
			(xy 413.355745 -151.189653) (xy 413.41367 -151.174132) (xy 413.473126 -151.166304) (xy 413.533094 -151.166304)
			(xy 413.59255 -151.174132) (xy 413.650475 -151.189653) (xy 413.705879 -151.212602) (xy 413.757813 -151.242586)
			(xy 413.805389 -151.279092) (xy 413.847794 -151.321497) (xy 413.8843 -151.369073) (xy 413.914284 -151.421007)
			(xy 413.937233 -151.476411) (xy 413.952754 -151.534336) (xy 413.960582 -151.593792) (xy 413.961072 -151.623776)
			(xy 413.961072 -152.485852) (xy 432.016408 -152.485852) (xy 432.016408 -151.622252) (xy 432.016898 -151.592268)
			(xy 432.024726 -151.532812) (xy 432.040247 -151.474887) (xy 432.063196 -151.419483) (xy 432.09318 -151.367549)
			(xy 432.129686 -151.319973) (xy 432.172091 -151.277568) (xy 432.219667 -151.241062) (xy 432.271601 -151.211078)
			(xy 432.327005 -151.188129) (xy 432.38493 -151.172608) (xy 432.444386 -151.16478) (xy 432.504354 -151.16478)
			(xy 432.56381 -151.172608) (xy 432.621735 -151.188129) (xy 432.677139 -151.211078) (xy 432.729073 -151.241062)
			(xy 432.776649 -151.277568) (xy 432.819054 -151.319973) (xy 432.85556 -151.367549) (xy 432.885544 -151.419483)
			(xy 432.908493 -151.474887) (xy 432.924014 -151.532812) (xy 432.931842 -151.592268) (xy 432.932332 -151.622252)
			(xy 432.932332 -152.485852) (xy 432.931842 -152.515836) (xy 432.924014 -152.575292) (xy 432.908493 -152.633217)
			(xy 432.885544 -152.688621) (xy 432.85556 -152.740555) (xy 432.819054 -152.788131) (xy 432.776649 -152.830536)
			(xy 432.729073 -152.867042) (xy 432.677139 -152.897026) (xy 432.621735 -152.919975) (xy 432.56381 -152.935496)
			(xy 432.504354 -152.943324) (xy 432.444386 -152.943324) (xy 432.38493 -152.935496) (xy 432.327005 -152.919975)
			(xy 432.271601 -152.897026) (xy 432.219667 -152.867042) (xy 432.172091 -152.830536) (xy 432.129686 -152.788131)
			(xy 432.09318 -152.740555) (xy 432.063196 -152.688621) (xy 432.040247 -152.633217) (xy 432.024726 -152.575292)
			(xy 432.016898 -152.515836) (xy 432.016408 -152.485852) (xy 413.961072 -152.485852) (xy 413.961072 -152.487376)
			(xy 413.960582 -152.51736) (xy 413.952754 -152.576816) (xy 413.937233 -152.634741) (xy 413.914284 -152.690145)
			(xy 413.8843 -152.742079) (xy 413.847794 -152.789655) (xy 413.805389 -152.83206) (xy 413.757813 -152.868566)
			(xy 413.705879 -152.89855) (xy 413.650475 -152.921499) (xy 413.59255 -152.93702) (xy 413.533094 -152.944848)
			(xy 413.473126 -152.944848) (xy 413.41367 -152.93702) (xy 413.355745 -152.921499) (xy 413.300341 -152.89855)
			(xy 413.248407 -152.868566) (xy 413.200831 -152.83206) (xy 413.158426 -152.789655) (xy 413.12192 -152.742079)
			(xy 413.091936 -152.690145) (xy 413.068987 -152.634741) (xy 413.053466 -152.576816) (xy 413.045638 -152.51736)
			(xy 413.045148 -152.487376) (xy 412.56966 -152.487376) (xy 412.56966 -154.28722) (xy 414.899348 -154.28722)
			(xy 414.899348 -153.42362) (xy 414.899838 -153.393636) (xy 414.907666 -153.33418) (xy 414.923187 -153.276255)
			(xy 414.946136 -153.220851) (xy 414.97612 -153.168917) (xy 415.012626 -153.121341) (xy 415.055031 -153.078936)
			(xy 415.102607 -153.04243) (xy 415.154541 -153.012446) (xy 415.209945 -152.989497) (xy 415.26787 -152.973976)
			(xy 415.327326 -152.966148) (xy 415.387294 -152.966148) (xy 415.44675 -152.973976) (xy 415.504675 -152.989497)
			(xy 415.560079 -153.012446) (xy 415.612013 -153.04243) (xy 415.659589 -153.078936) (xy 415.701994 -153.121341)
			(xy 415.7385 -153.168917) (xy 415.768484 -153.220851) (xy 415.791433 -153.276255) (xy 415.806954 -153.33418)
			(xy 415.814782 -153.393636) (xy 415.815272 -153.42362) (xy 415.815272 -154.279346) (xy 429.3743 -154.279346)
			(xy 429.3743 -153.415746) (xy 429.37479 -153.385762) (xy 429.382618 -153.326306) (xy 429.398139 -153.268381)
			(xy 429.421088 -153.212977) (xy 429.451072 -153.161043) (xy 429.487578 -153.113467) (xy 429.529983 -153.071062)
			(xy 429.577559 -153.034556) (xy 429.629493 -153.004572) (xy 429.684897 -152.981623) (xy 429.742822 -152.966102)
			(xy 429.802278 -152.958274) (xy 429.862246 -152.958274) (xy 429.921702 -152.966102) (xy 429.979627 -152.981623)
			(xy 430.035031 -153.004572) (xy 430.086965 -153.034556) (xy 430.134541 -153.071062) (xy 430.176946 -153.113467)
			(xy 430.213452 -153.161043) (xy 430.243436 -153.212977) (xy 430.266385 -153.268381) (xy 430.281906 -153.326306)
			(xy 430.289734 -153.385762) (xy 430.290224 -153.415746) (xy 430.290224 -154.279346) (xy 430.289734 -154.30933)
			(xy 430.281906 -154.368786) (xy 430.266385 -154.426711) (xy 430.243436 -154.482115) (xy 430.213452 -154.534049)
			(xy 430.176946 -154.581625) (xy 430.134541 -154.62403) (xy 430.086965 -154.660536) (xy 430.035031 -154.69052)
			(xy 429.979627 -154.713469) (xy 429.921702 -154.72899) (xy 429.862246 -154.736818) (xy 429.802278 -154.736818)
			(xy 429.742822 -154.72899) (xy 429.684897 -154.713469) (xy 429.629493 -154.69052) (xy 429.577559 -154.660536)
			(xy 429.529983 -154.62403) (xy 429.487578 -154.581625) (xy 429.451072 -154.534049) (xy 429.421088 -154.482115)
			(xy 429.398139 -154.426711) (xy 429.382618 -154.368786) (xy 429.37479 -154.30933) (xy 429.3743 -154.279346)
			(xy 415.815272 -154.279346) (xy 415.815272 -154.28722) (xy 415.814782 -154.317204) (xy 415.806954 -154.37666)
			(xy 415.791433 -154.434585) (xy 415.768484 -154.489989) (xy 415.7385 -154.541923) (xy 415.701994 -154.589499)
			(xy 415.659589 -154.631904) (xy 415.612013 -154.66841) (xy 415.560079 -154.698394) (xy 415.504675 -154.721343)
			(xy 415.44675 -154.736864) (xy 415.387294 -154.744692) (xy 415.327326 -154.744692) (xy 415.26787 -154.736864)
			(xy 415.209945 -154.721343) (xy 415.154541 -154.698394) (xy 415.102607 -154.66841) (xy 415.055031 -154.631904)
			(xy 415.012626 -154.589499) (xy 414.97612 -154.541923) (xy 414.946136 -154.489989) (xy 414.923187 -154.434585)
			(xy 414.907666 -154.37666) (xy 414.899838 -154.317204) (xy 414.899348 -154.28722) (xy 412.56966 -154.28722)
			(xy 412.56966 -156.087318) (xy 413.045148 -156.087318) (xy 413.045148 -155.223718) (xy 413.045638 -155.193734)
			(xy 413.053466 -155.134278) (xy 413.068987 -155.076353) (xy 413.091936 -155.020949) (xy 413.12192 -154.969015)
			(xy 413.158426 -154.921439) (xy 413.200831 -154.879034) (xy 413.248407 -154.842528) (xy 413.300341 -154.812544)
			(xy 413.355745 -154.789595) (xy 413.41367 -154.774074) (xy 413.473126 -154.766246) (xy 413.533094 -154.766246)
			(xy 413.59255 -154.774074) (xy 413.650475 -154.789595) (xy 413.705879 -154.812544) (xy 413.757813 -154.842528)
			(xy 413.805389 -154.879034) (xy 413.847794 -154.921439) (xy 413.8843 -154.969015) (xy 413.914284 -155.020949)
			(xy 413.937233 -155.076353) (xy 413.952754 -155.134278) (xy 413.960582 -155.193734) (xy 413.961072 -155.223718)
			(xy 413.961072 -156.085794) (xy 432.016408 -156.085794) (xy 432.016408 -155.222194) (xy 432.016898 -155.19221)
			(xy 432.024726 -155.132754) (xy 432.040247 -155.074829) (xy 432.063196 -155.019425) (xy 432.09318 -154.967491)
			(xy 432.129686 -154.919915) (xy 432.172091 -154.87751) (xy 432.219667 -154.841004) (xy 432.271601 -154.81102)
			(xy 432.327005 -154.788071) (xy 432.38493 -154.77255) (xy 432.444386 -154.764722) (xy 432.504354 -154.764722)
			(xy 432.56381 -154.77255) (xy 432.621735 -154.788071) (xy 432.677139 -154.81102) (xy 432.729073 -154.841004)
			(xy 432.776649 -154.87751) (xy 432.819054 -154.919915) (xy 432.85556 -154.967491) (xy 432.885544 -155.019425)
			(xy 432.908493 -155.074829) (xy 432.924014 -155.132754) (xy 432.931842 -155.19221) (xy 432.932332 -155.222194)
			(xy 432.932332 -156.085794) (xy 432.931842 -156.115778) (xy 432.924014 -156.175234) (xy 432.908493 -156.233159)
			(xy 432.885544 -156.288563) (xy 432.85556 -156.340497) (xy 432.819054 -156.388073) (xy 432.776649 -156.430478)
			(xy 432.729073 -156.466984) (xy 432.677139 -156.496968) (xy 432.621735 -156.519917) (xy 432.56381 -156.535438)
			(xy 432.504354 -156.543266) (xy 432.444386 -156.543266) (xy 432.38493 -156.535438) (xy 432.327005 -156.519917)
			(xy 432.271601 -156.496968) (xy 432.219667 -156.466984) (xy 432.172091 -156.430478) (xy 432.129686 -156.388073)
			(xy 432.09318 -156.340497) (xy 432.063196 -156.288563) (xy 432.040247 -156.233159) (xy 432.024726 -156.175234)
			(xy 432.016898 -156.115778) (xy 432.016408 -156.085794) (xy 413.961072 -156.085794) (xy 413.961072 -156.087318)
			(xy 413.960582 -156.117302) (xy 413.952754 -156.176758) (xy 413.937233 -156.234683) (xy 413.914284 -156.290087)
			(xy 413.8843 -156.342021) (xy 413.847794 -156.389597) (xy 413.805389 -156.432002) (xy 413.757813 -156.468508)
			(xy 413.705879 -156.498492) (xy 413.650475 -156.521441) (xy 413.59255 -156.536962) (xy 413.533094 -156.54479)
			(xy 413.473126 -156.54479) (xy 413.41367 -156.536962) (xy 413.355745 -156.521441) (xy 413.300341 -156.498492)
			(xy 413.248407 -156.468508) (xy 413.200831 -156.432002) (xy 413.158426 -156.389597) (xy 413.12192 -156.342021)
			(xy 413.091936 -156.290087) (xy 413.068987 -156.234683) (xy 413.053466 -156.176758) (xy 413.045638 -156.117302)
			(xy 413.045148 -156.087318) (xy 412.56966 -156.087318) (xy 412.56966 -158.219648) (xy 429.482248 -158.219648)
			(xy 429.486319 -158.164026) (xy 429.498445 -158.109589) (xy 429.518368 -158.057498) (xy 429.545664 -158.008863)
			(xy 429.57975 -157.96472) (xy 429.619899 -157.926011) (xy 429.665257 -157.89356) (xy 429.714857 -157.868059)
			(xy 429.767641 -157.850052) (xy 429.822484 -157.839922) (xy 429.878218 -157.837885) (xy 429.933655 -157.843985)
			(xy 429.987612 -157.858091) (xy 430.038941 -157.879903) (xy 430.086547 -157.908957) (xy 430.129415 -157.944632)
			(xy 430.166632 -157.986169) (xy 430.197405 -158.032682) (xy 430.221077 -158.083179) (xy 430.237145 -158.136586)
			(xy 430.245265 -158.191762) (xy 430.245774 -158.219648) (xy 430.245265 -158.247534) (xy 430.237145 -158.30271)
			(xy 430.221077 -158.356117) (xy 430.197405 -158.406614) (xy 430.166632 -158.453127) (xy 430.129415 -158.494664)
			(xy 430.086547 -158.530339) (xy 430.038941 -158.559393) (xy 429.987612 -158.581205) (xy 429.933655 -158.595311)
			(xy 429.878218 -158.601411) (xy 429.822484 -158.599374) (xy 429.767641 -158.589244) (xy 429.714857 -158.571237)
			(xy 429.665257 -158.545736) (xy 429.619899 -158.513285) (xy 429.57975 -158.474576) (xy 429.545664 -158.430433)
			(xy 429.518368 -158.381798) (xy 429.498445 -158.329707) (xy 429.486319 -158.27527) (xy 429.482248 -158.219648)
			(xy 412.56966 -158.219648) (xy 412.56966 -160.1851) (xy 418.188915 -160.1851) (xy 418.192871 -160.093241)
			(xy 418.204708 -160.002062) (xy 418.22434 -159.912238) (xy 418.251621 -159.824435) (xy 418.286349 -159.739302)
			(xy 418.328267 -159.657469) (xy 418.377065 -159.579542) (xy 418.43238 -159.506099) (xy 418.493805 -159.437683)
			(xy 418.560884 -159.374801) (xy 418.633119 -159.317918) (xy 418.709978 -159.267455) (xy 418.79089 -159.223786)
			(xy 418.875256 -159.187234) (xy 418.962452 -159.15807) (xy 419.051833 -159.13651) (xy 419.142736 -159.122714)
			(xy 419.234489 -159.116782) (xy 419.326411 -159.118761) (xy 419.417824 -159.128634) (xy 419.508049 -159.146329)
			(xy 419.59642 -159.171714) (xy 419.68228 -159.204602) (xy 419.746243 -159.235648) (xy 429.639982 -159.235648)
			(xy 429.644053 -159.180026) (xy 429.656179 -159.125589) (xy 429.676102 -159.073498) (xy 429.703398 -159.024863)
			(xy 429.737484 -158.98072) (xy 429.777633 -158.942011) (xy 429.822991 -158.90956) (xy 429.872591 -158.884059)
			(xy 429.925375 -158.866052) (xy 429.980218 -158.855922) (xy 430.035952 -158.853885) (xy 430.091389 -158.859985)
			(xy 430.145346 -158.874091) (xy 430.196675 -158.895903) (xy 430.244281 -158.924957) (xy 430.287149 -158.960632)
			(xy 430.324366 -159.002169) (xy 430.355139 -159.048682) (xy 430.378811 -159.099179) (xy 430.394879 -159.152586)
			(xy 430.402999 -159.207762) (xy 430.403508 -159.235648) (xy 430.402999 -159.263534) (xy 430.394879 -159.31871)
			(xy 430.378811 -159.372117) (xy 430.355139 -159.422614) (xy 430.324366 -159.469127) (xy 430.287149 -159.510664)
			(xy 430.244281 -159.546339) (xy 430.196675 -159.575393) (xy 430.145346 -159.597205) (xy 430.091389 -159.611311)
			(xy 430.035952 -159.617411) (xy 429.980218 -159.615374) (xy 429.925375 -159.605244) (xy 429.872591 -159.587237)
			(xy 429.822991 -159.561736) (xy 429.777633 -159.529285) (xy 429.737484 -159.490576) (xy 429.703398 -159.446433)
			(xy 429.676102 -159.397798) (xy 429.656179 -159.345707) (xy 429.644053 -159.29127) (xy 429.639982 -159.235648)
			(xy 419.746243 -159.235648) (xy 419.764996 -159.24475) (xy 419.843954 -159.291859) (xy 419.918571 -159.345582)
			(xy 419.988292 -159.40552) (xy 420.052603 -159.47123) (xy 420.111028 -159.542226) (xy 420.163133 -159.61798)
			(xy 420.208532 -159.697934) (xy 420.246891 -159.781494) (xy 420.277924 -159.868043) (xy 420.301402 -159.956939)
			(xy 420.317152 -160.047524) (xy 420.325056 -160.139128) (xy 420.32555 -160.1851) (xy 420.325056 -160.231072)
			(xy 420.317152 -160.322676) (xy 420.301402 -160.413261) (xy 420.277924 -160.502157) (xy 420.246891 -160.588706)
			(xy 420.208532 -160.672266) (xy 420.163133 -160.75222) (xy 420.111028 -160.827974) (xy 420.052603 -160.89897)
			(xy 419.988292 -160.96468) (xy 419.918571 -161.024618) (xy 419.843954 -161.078341) (xy 419.764996 -161.12545)
			(xy 419.68228 -161.165598) (xy 419.59642 -161.198486) (xy 419.508049 -161.223871) (xy 419.417824 -161.241566)
			(xy 419.326411 -161.251439) (xy 419.234489 -161.253418) (xy 419.142736 -161.247486) (xy 419.051833 -161.23369)
			(xy 418.962452 -161.21213) (xy 418.875256 -161.182966) (xy 418.79089 -161.146414) (xy 418.709978 -161.102745)
			(xy 418.633119 -161.052282) (xy 418.560884 -160.995399) (xy 418.493805 -160.932517) (xy 418.43238 -160.864101)
			(xy 418.377065 -160.790658) (xy 418.328267 -160.712731) (xy 418.286349 -160.630898) (xy 418.251621 -160.545765)
			(xy 418.22434 -160.457962) (xy 418.204708 -160.368138) (xy 418.192871 -160.276959) (xy 418.188915 -160.1851)
			(xy 412.56966 -160.1851) (xy 412.56966 -161.872422) (xy 412.570089 -161.882489) (xy 412.577815 -161.901082)
			(xy 412.584646 -161.90849) (xy 413.616394 -162.940238) (xy 413.616511 -162.945334) (xy 413.618568 -162.955316)
			(xy 413.620458 -162.96005) (xy 413.63011 -162.980624) (xy 413.636206 -162.99053) (xy 413.639508 -162.994594)
			(xy 413.643318 -162.997896) (xy 413.667108 -163.018634) (xy 413.709887 -163.065034) (xy 413.746592 -163.116374)
			(xy 413.776657 -163.171864) (xy 413.799621 -163.23065) (xy 413.815128 -163.291826) (xy 413.822942 -163.354452)
			(xy 413.823404 -163.386008) (xy 413.823404 -172.522388) (xy 413.823557 -172.527623) (xy 413.825727 -172.537866)
			(xy 413.827722 -172.542708) (xy 413.831024 -172.550582) (xy 413.83585 -172.555408) (xy 413.83585 -173.09084)
			(xy 413.835418 -173.100906) (xy 413.827688 -173.119495) (xy 413.820864 -173.126908) (xy 410.908754 -176.039018)
			(xy 410.902068 -176.046417) (xy 410.894463 -176.06483) (xy 410.89446 -176.084752) (xy 410.897832 -176.094136)
			(xy 410.903674 -176.108614) (xy 410.929328 -176.125632) (xy 411.63621 -176.125632) (xy 411.669088 -176.126109)
			(xy 411.734428 -176.133499) (xy 411.798531 -176.148151) (xy 411.860593 -176.169882) (xy 411.919834 -176.198419)
			(xy 411.975512 -176.233403) (xy 412.026927 -176.274396) (xy 412.050484 -176.297336) (xy 415.145474 -179.392326)
			(xy 415.168372 -179.41589) (xy 415.209326 -179.467274) (xy 415.244274 -179.522917) (xy 415.272778 -179.58212)
			(xy 415.294479 -179.64414) (xy 415.309106 -179.708199) (xy 415.316474 -179.773492) (xy 415.316924 -179.806346)
			(xy 415.316924 -182.539132) (xy 415.316468 -182.571987) (xy 415.309118 -182.637285) (xy 415.294504 -182.70135)
			(xy 415.27281 -182.763376) (xy 415.244307 -182.822582) (xy 415.209355 -182.878226) (xy 415.168392 -182.929606)
			(xy 415.145474 -182.953152) (xy 413.865568 -184.233058) (xy 413.857821 -184.241487) (xy 413.850178 -184.263044)
			(xy 413.85265 -184.285781) (xy 413.858202 -184.295796) (xy 413.86252 -184.302654) (xy 413.88665 -184.326784)
			(xy 413.893762 -184.330594) (xy 413.900366 -184.33415) (xy 413.925858 -184.348561) (xy 413.97248 -184.383989)
			(xy 414.013135 -184.426132) (xy 414.046866 -184.473997) (xy 414.072879 -184.526459) (xy 414.090562 -184.582281)
			(xy 414.099499 -184.640152) (xy 414.10001 -184.66943) (xy 414.099551 -184.69604) (xy 414.092157 -184.748743)
			(xy 414.077501 -184.799905) (xy 414.055869 -184.848529) (xy 414.027683 -184.893672) (xy 413.99349 -184.934453)
			(xy 413.985428 -184.941718) (xy 414.979864 -184.941718) (xy 414.983935 -184.886096) (xy 414.996061 -184.831659)
			(xy 415.015984 -184.779568) (xy 415.04328 -184.730933) (xy 415.077366 -184.68679) (xy 415.117515 -184.648081)
			(xy 415.162873 -184.61563) (xy 415.212473 -184.590129) (xy 415.265257 -184.572122) (xy 415.3201 -184.561992)
			(xy 415.375834 -184.559955) (xy 415.431271 -184.566055) (xy 415.485228 -184.580161) (xy 415.536557 -184.601973)
			(xy 415.584163 -184.631027) (xy 415.627031 -184.666702) (xy 415.664248 -184.708239) (xy 415.695021 -184.754752)
			(xy 415.718693 -184.805249) (xy 415.734761 -184.858656) (xy 415.742881 -184.913832) (xy 415.74339 -184.941718)
			(xy 415.742881 -184.969604) (xy 415.734761 -185.02478) (xy 415.718693 -185.078187) (xy 415.695021 -185.128684)
			(xy 415.664248 -185.175197) (xy 415.627031 -185.216734) (xy 415.584163 -185.252409) (xy 415.536557 -185.281463)
			(xy 415.485228 -185.303275) (xy 415.431271 -185.317381) (xy 415.375834 -185.323481) (xy 415.3201 -185.321444)
			(xy 415.265257 -185.311314) (xy 415.212473 -185.293307) (xy 415.162873 -185.267806) (xy 415.117515 -185.235355)
			(xy 415.077366 -185.196646) (xy 415.04328 -185.152503) (xy 415.015984 -185.103868) (xy 414.996061 -185.051777)
			(xy 414.983935 -184.99734) (xy 414.979864 -184.941718) (xy 413.985428 -184.941718) (xy 413.953955 -184.970081)
			(xy 413.909848 -184.999861) (xy 413.862027 -185.023215) (xy 413.836866 -185.031888) (xy 413.83331 -185.032904)
			(xy 413.832294 -185.033412) (xy 413.827468 -185.034936) (xy 413.817578 -185.038819) (xy 413.801916 -185.053138)
			(xy 413.793414 -185.072582) (xy 413.792924 -185.083196) (xy 413.792924 -189.44209) (xy 413.793128 -189.448178)
			(xy 413.796073 -189.459995) (xy 413.798766 -189.465458) (xy 413.809434 -189.486286) (xy 413.812288 -189.49125)
			(xy 413.819864 -189.499834) (xy 413.82442 -189.503304) (xy 413.824674 -189.503304) (xy 413.848401 -189.521431)
			(xy 413.890452 -189.563819) (xy 413.925391 -189.612236) (xy 413.952367 -189.665502) (xy 413.970723 -189.722318)
			(xy 413.980009 -189.781298) (xy 413.98063 -189.811152) (xy 413.98017 -189.838408) (xy 413.972419 -189.892365)
			(xy 413.957067 -189.94467) (xy 413.934428 -189.994258) (xy 413.904962 -190.040118) (xy 413.869268 -190.081319)
			(xy 413.828075 -190.11702) (xy 413.782219 -190.146494) (xy 413.732636 -190.169143) (xy 413.680334 -190.184504)
			(xy 413.626378 -190.192265) (xy 413.599122 -190.19266) (xy 413.598868 -190.19266) (xy 413.570869 -190.192161)
			(xy 413.515472 -190.183974) (xy 413.461861 -190.167795) (xy 413.436308 -190.156338) (xy 413.42183 -190.14948)
			(xy 413.390334 -190.154814) (xy 412.462218 -191.082676) (xy 412.455382 -191.090078) (xy 412.447672 -191.108676)
			(xy 412.447232 -191.118744) (xy 412.447232 -192.815718) (xy 412.447659 -192.825786) (xy 412.455382 -192.844383)
			(xy 412.462218 -192.851786) (xy 412.476696 -192.866264) (xy 412.480064 -192.869463) (xy 412.487731 -192.874705)
			(xy 412.491936 -192.876678) (xy 412.515812 -192.887346) (xy 412.524702 -192.888108) (xy 412.551762 -192.890631)
			(xy 412.604826 -192.902366) (xy 412.655689 -192.921512) (xy 412.70332 -192.947681) (xy 412.746756 -192.980344)
			(xy 412.785118 -193.018839) (xy 412.817631 -193.062387) (xy 412.843636 -193.110108) (xy 412.862606 -193.161036)
			(xy 412.874159 -193.21414) (xy 412.87806 -193.268346) (xy 412.874231 -193.322558) (xy 412.862749 -193.375677)
			(xy 412.843846 -193.42663) (xy 412.817904 -193.474386) (xy 412.78545 -193.517977) (xy 412.747138 -193.556523)
			(xy 412.703745 -193.589243) (xy 412.656149 -193.615475) (xy 412.605312 -193.634689) (xy 412.552264 -193.646495)
			(xy 412.52521 -193.649092) (xy 412.51632 -193.649854) (xy 412.49219 -193.660522) (xy 412.487819 -193.662649)
			(xy 412.479897 -193.668279) (xy 412.476442 -193.671698) (xy 412.46171 -193.686938) (xy 412.455164 -193.694266)
			(xy 412.447716 -193.71243) (xy 412.447232 -193.722244) (xy 412.447232 -193.725038) (xy 412.806388 -194.084702)
			(xy 412.806896 -194.08521) (xy 412.812992 -194.091052) (xy 412.820341 -194.097541) (xy 412.838504 -194.104874)
			(xy 412.848298 -194.105276) (xy 420.929308 -194.105276) (xy 420.962164 -194.105731) (xy 421.027463 -194.113078)
			(xy 421.091529 -194.12769) (xy 421.153557 -194.149383) (xy 421.212765 -194.177884) (xy 421.268411 -194.212835)
			(xy 421.319793 -194.253796) (xy 421.343328 -194.276726) (xy 421.751252 -194.68465) (xy 421.774199 -194.708204)
			(xy 421.815222 -194.759602) (xy 421.850228 -194.815273) (xy 421.878777 -194.874515) (xy 421.900508 -194.936583)
			(xy 421.915148 -195.000695) (xy 421.922513 -195.066043) (xy 421.922956 -195.098924) (xy 421.922956 -196.047106)
			(xy 421.922479 -196.079984) (xy 421.91509 -196.145324) (xy 421.900437 -196.209427) (xy 421.878706 -196.271489)
			(xy 421.850169 -196.330731) (xy 421.815185 -196.386408) (xy 421.774192 -196.437823) (xy 421.751252 -196.46138)
			(xy 421.302942 -196.90969) (xy 421.279377 -196.932586) (xy 421.227992 -196.973536) (xy 421.172349 -197.00848)
			(xy 421.113145 -197.03698) (xy 421.051125 -197.058678) (xy 420.987067 -197.0733) (xy 420.921775 -197.080665)
			(xy 420.888922 -197.08114) (xy 420.888668 -197.08114) (xy 420.853271 -197.080604) (xy 420.782995 -197.072067)
			(xy 420.714259 -197.055123) (xy 420.648068 -197.030017) (xy 420.585384 -196.997116) (xy 420.527124 -196.956899)
			(xy 420.474135 -196.909954) (xy 420.427191 -196.856964) (xy 420.386976 -196.798702) (xy 420.354077 -196.736018)
			(xy 420.328973 -196.669825) (xy 420.31203 -196.601089) (xy 420.303495 -196.530813) (xy 420.302944 -196.495416)
			(xy 420.302944 -196.495162) (xy 420.303401 -196.462307) (xy 420.31075 -196.397009) (xy 420.325364 -196.332944)
			(xy 420.347059 -196.270918) (xy 420.37556 -196.211711) (xy 420.410512 -196.156066) (xy 420.451473 -196.104685)
			(xy 420.474394 -196.081142) (xy 420.641018 -195.914518) (xy 420.647703 -195.907117) (xy 420.655309 -195.888702)
			(xy 420.655325 -195.868779) (xy 420.65194 -195.8594) (xy 420.646098 -195.844922) (xy 420.620444 -195.827904)
			(xy 412.087568 -195.827904) (xy 412.05469 -195.827426) (xy 411.989351 -195.820034) (xy 411.925249 -195.80538)
			(xy 411.863188 -195.783649) (xy 411.803947 -195.755112) (xy 411.748269 -195.720128) (xy 411.696855 -195.679136)
			(xy 411.673294 -195.6562) (xy 410.972254 -194.95516) (xy 410.949356 -194.931596) (xy 410.908401 -194.880213)
			(xy 410.873453 -194.82457) (xy 410.844949 -194.765367) (xy 410.823248 -194.703346) (xy 410.808622 -194.639287)
			(xy 410.801255 -194.573994) (xy 410.800804 -194.54114) (xy 410.800804 -194.350132) (xy 410.800368 -194.340067)
			(xy 410.792637 -194.32148) (xy 410.785818 -194.314064) (xy 410.068268 -193.596514) (xy 410.059803 -193.588977)
			(xy 410.038443 -193.581482) (xy 410.02712 -193.582036) (xy 409.950412 -193.590164) (xy 409.941876 -193.591415)
			(xy 409.926309 -193.598829) (xy 409.919932 -193.604642) (xy 409.912058 -193.612516) (xy 409.909264 -193.61658)
			(xy 409.893966 -193.638315) (xy 409.858316 -193.677733) (xy 409.817539 -193.711822) (xy 409.772426 -193.739922)
			(xy 409.72385 -193.761489) (xy 409.67275 -193.776105) (xy 409.620116 -193.783487) (xy 409.593542 -193.783966)
			(xy 409.591256 -193.783966) (xy 409.584445 -193.784177) (xy 409.571305 -193.78777) (xy 409.565348 -193.791078)
			(xy 409.565094 -193.791078) (xy 409.558341 -193.795531) (xy 409.547863 -193.807841) (xy 409.54452 -193.815208)
			(xy 409.507944 -193.901822) (xy 409.50769 -193.90233) (xy 409.504409 -193.911745) (xy 409.504529 -193.931662)
			(xy 409.512182 -193.95005) (xy 409.518866 -193.957448) (xy 409.587954 -194.026536) (xy 409.606069 -194.045315)
			(xy 409.636759 -194.087511) (xy 409.660463 -194.133992) (xy 409.676597 -194.183611) (xy 409.684762 -194.235144)
			(xy 409.685236 -194.261232) (xy 409.685236 -196.755258) (xy 413.72104 -196.755258) (xy 413.725111 -196.699636)
			(xy 413.737237 -196.645199) (xy 413.75716 -196.593108) (xy 413.784456 -196.544473) (xy 413.818542 -196.50033)
			(xy 413.858691 -196.461621) (xy 413.904049 -196.42917) (xy 413.953649 -196.403669) (xy 414.006433 -196.385662)
			(xy 414.061276 -196.375532) (xy 414.11701 -196.373495) (xy 414.172447 -196.379595) (xy 414.226404 -196.393701)
			(xy 414.277733 -196.415513) (xy 414.325339 -196.444567) (xy 414.368207 -196.480242) (xy 414.405424 -196.521779)
			(xy 414.436197 -196.568292) (xy 414.459869 -196.618789) (xy 414.475937 -196.672196) (xy 414.484057 -196.727372)
			(xy 414.484566 -196.755258) (xy 414.484057 -196.783144) (xy 414.475937 -196.83832) (xy 414.459869 -196.891727)
			(xy 414.436197 -196.942224) (xy 414.405424 -196.988737) (xy 414.368207 -197.030274) (xy 414.325339 -197.065949)
			(xy 414.277733 -197.095003) (xy 414.226404 -197.116815) (xy 414.172447 -197.130921) (xy 414.11701 -197.137021)
			(xy 414.061276 -197.134984) (xy 414.006433 -197.124854) (xy 413.953649 -197.106847) (xy 413.904049 -197.081346)
			(xy 413.858691 -197.048895) (xy 413.818542 -197.010186) (xy 413.784456 -196.966043) (xy 413.75716 -196.917408)
			(xy 413.737237 -196.865317) (xy 413.725111 -196.81088) (xy 413.72104 -196.755258) (xy 409.685236 -196.755258)
			(xy 409.685236 -197.996048) (xy 409.68676 -198.008494) (xy 409.691078 -198.025766) (xy 409.693618 -198.0311)
			(xy 409.693872 -198.031608) (xy 409.706712 -198.058349) (xy 409.724894 -198.11481) (xy 409.734145 -198.173401)
			(xy 409.734766 -198.203058) (xy 409.73428 -198.230309) (xy 409.726524 -198.284257) (xy 409.711169 -198.336552)
			(xy 409.688527 -198.386129) (xy 409.659061 -198.431979) (xy 409.62337 -198.47317) (xy 409.582179 -198.508861)
			(xy 409.536329 -198.538327) (xy 409.486752 -198.560969) (xy 409.434457 -198.576324) (xy 409.380509 -198.58408)
			(xy 409.326007 -198.58408) (xy 409.272059 -198.576324) (xy 409.219764 -198.560969) (xy 409.170187 -198.538327)
			(xy 409.124337 -198.508861) (xy 409.083146 -198.47317) (xy 409.047455 -198.431979) (xy 409.017989 -198.386129)
			(xy 408.995347 -198.336552) (xy 408.979992 -198.284257) (xy 408.972236 -198.230309) (xy 408.97175 -198.203058)
			(xy 408.972317 -198.173258) (xy 408.981586 -198.114385) (xy 408.999921 -198.057677) (xy 409.012898 -198.030846)
			(xy 409.015438 -198.025512) (xy 409.019756 -198.00824) (xy 409.02128 -197.995794) (xy 409.02128 -197.60057)
			(xy 409.020765 -197.589123) (xy 409.01086 -197.568483) (xy 409.00223 -197.560946) (xy 408.941016 -197.51167)
			(xy 408.932468 -197.505498) (xy 408.91214 -197.499985) (xy 408.901646 -197.501002) (xy 408.897328 -197.50151)
			(xy 408.895804 -197.501764) (xy 408.89301 -197.502272) (xy 408.873313 -197.506275) (xy 408.833351 -197.510602)
			(xy 408.813254 -197.510908) (xy 408.813 -197.510908) (xy 408.785749 -197.510422) (xy 408.731801 -197.502666)
			(xy 408.679506 -197.487311) (xy 408.629929 -197.464669) (xy 408.584079 -197.435203) (xy 408.542888 -197.399512)
			(xy 408.507197 -197.358321) (xy 408.477731 -197.312471) (xy 408.455089 -197.262894) (xy 408.439734 -197.210599)
			(xy 408.431978 -197.156651) (xy 408.431978 -197.102149) (xy 408.439734 -197.048201) (xy 408.455089 -196.995906)
			(xy 408.477731 -196.946329) (xy 408.507197 -196.900479) (xy 408.542888 -196.859288) (xy 408.584079 -196.823597)
			(xy 408.629929 -196.794131) (xy 408.679506 -196.771489) (xy 408.731801 -196.756134) (xy 408.785749 -196.748378)
			(xy 408.813 -196.747892) (xy 408.813254 -196.747892) (xy 408.832377 -196.748198) (xy 408.870421 -196.75214)
			(xy 408.8892 -196.755766) (xy 408.889454 -196.755766) (xy 408.89682 -196.75729) (xy 408.902154 -196.757798)
			(xy 408.908873 -196.758195) (xy 408.922129 -196.755877) (xy 408.928316 -196.753226) (xy 408.934412 -196.750432)
			(xy 408.944826 -196.744082) (xy 409.00223 -196.697854) (xy 409.010755 -196.690227) (xy 409.020672 -196.66965)
			(xy 409.02128 -196.65823) (xy 409.02128 -194.419728) (xy 409.020843 -194.409664) (xy 409.013108 -194.39108)
			(xy 409.006294 -194.38366) (xy 408.631898 -194.009264) (xy 408.613785 -193.990484) (xy 408.583099 -193.948287)
			(xy 408.559399 -193.901806) (xy 408.543268 -193.852187) (xy 408.535104 -193.800655) (xy 408.534616 -193.774568)
			(xy 408.534616 -192.084198) (xy 408.534193 -192.074128) (xy 408.52648 -192.055522) (xy 408.51963 -192.04813)
			(xy 401.472146 -185.000392) (xy 401.464744 -184.993555) (xy 401.446146 -184.985841) (xy 401.436078 -184.985406)
			(xy 383.57683 -184.985406) (xy 383.566766 -184.985842) (xy 383.54818 -184.993575) (xy 383.540762 -185.000392)
			(xy 382.948434 -185.59272) (xy 382.941587 -185.600118) (xy 382.933854 -185.618716) (xy 382.933448 -185.628788)
			(xy 382.933448 -188.408564) (xy 382.933884 -188.418628) (xy 382.94162 -188.437211) (xy 382.948434 -188.444632)
			(xy 383.141474 -188.637672) (xy 383.16437 -188.661237) (xy 383.20532 -188.712622) (xy 383.240264 -188.768265)
			(xy 383.268763 -188.827468) (xy 383.29046 -188.889489) (xy 383.305081 -188.953547) (xy 383.312445 -189.018839)
			(xy 383.312924 -189.051692) (xy 383.312924 -199.981058) (xy 413.61944 -199.981058) (xy 413.623511 -199.925436)
			(xy 413.635637 -199.870999) (xy 413.65556 -199.818908) (xy 413.682856 -199.770273) (xy 413.716942 -199.72613)
			(xy 413.757091 -199.687421) (xy 413.802449 -199.65497) (xy 413.852049 -199.629469) (xy 413.904833 -199.611462)
			(xy 413.959676 -199.601332) (xy 414.01541 -199.599295) (xy 414.070847 -199.605395) (xy 414.124804 -199.619501)
			(xy 414.176133 -199.641313) (xy 414.223739 -199.670367) (xy 414.266607 -199.706042) (xy 414.303824 -199.747579)
			(xy 414.334597 -199.794092) (xy 414.358269 -199.844589) (xy 414.374337 -199.897996) (xy 414.382457 -199.953172)
			(xy 414.382966 -199.981058) (xy 414.382457 -200.008944) (xy 414.374337 -200.06412) (xy 414.358269 -200.117527)
			(xy 414.334597 -200.168024) (xy 414.303824 -200.214537) (xy 414.266607 -200.256074) (xy 414.223739 -200.291749)
			(xy 414.176133 -200.320803) (xy 414.124804 -200.342615) (xy 414.070847 -200.356721) (xy 414.01541 -200.362821)
			(xy 413.959676 -200.360784) (xy 413.904833 -200.350654) (xy 413.852049 -200.332647) (xy 413.802449 -200.307146)
			(xy 413.757091 -200.274695) (xy 413.716942 -200.235986) (xy 413.682856 -200.191843) (xy 413.65556 -200.143208)
			(xy 413.635637 -200.091117) (xy 413.623511 -200.03668) (xy 413.61944 -199.981058) (xy 383.312924 -199.981058)
			(xy 383.312924 -201.962258) (xy 409.033724 -201.962258) (xy 409.037795 -201.906636) (xy 409.049921 -201.852199)
			(xy 409.069844 -201.800108) (xy 409.09714 -201.751473) (xy 409.131226 -201.70733) (xy 409.171375 -201.668621)
			(xy 409.216733 -201.63617) (xy 409.266333 -201.610669) (xy 409.319117 -201.592662) (xy 409.37396 -201.582532)
			(xy 409.429694 -201.580495) (xy 409.485131 -201.586595) (xy 409.539088 -201.600701) (xy 409.590417 -201.622513)
			(xy 409.638023 -201.651567) (xy 409.680891 -201.687242) (xy 409.718108 -201.728779) (xy 409.748881 -201.775292)
			(xy 409.772553 -201.825789) (xy 409.788621 -201.879196) (xy 409.796741 -201.934372) (xy 409.79725 -201.962258)
			(xy 409.796741 -201.990144) (xy 409.788621 -202.04532) (xy 409.772553 -202.098727) (xy 409.748881 -202.149224)
			(xy 409.718108 -202.195737) (xy 409.680891 -202.237274) (xy 409.638023 -202.272949) (xy 409.590417 -202.302003)
			(xy 409.539088 -202.323815) (xy 409.485131 -202.337921) (xy 409.429694 -202.344021) (xy 409.37396 -202.341984)
			(xy 409.319117 -202.331854) (xy 409.266333 -202.313847) (xy 409.216733 -202.288346) (xy 409.171375 -202.255895)
			(xy 409.131226 -202.217186) (xy 409.09714 -202.173043) (xy 409.069844 -202.124408) (xy 409.049921 -202.072317)
			(xy 409.037795 -202.01788) (xy 409.033724 -201.962258) (xy 383.312924 -201.962258) (xy 383.312924 -203.562458)
			(xy 413.13684 -203.562458) (xy 413.140911 -203.506836) (xy 413.153037 -203.452399) (xy 413.17296 -203.400308)
			(xy 413.200256 -203.351673) (xy 413.234342 -203.30753) (xy 413.274491 -203.268821) (xy 413.319849 -203.23637)
			(xy 413.369449 -203.210869) (xy 413.422233 -203.192862) (xy 413.477076 -203.182732) (xy 413.53281 -203.180695)
			(xy 413.588247 -203.186795) (xy 413.642204 -203.200901) (xy 413.693533 -203.222713) (xy 413.741139 -203.251767)
			(xy 413.784007 -203.287442) (xy 413.821224 -203.328979) (xy 413.851997 -203.375492) (xy 413.875669 -203.425989)
			(xy 413.891737 -203.479396) (xy 413.899857 -203.534572) (xy 413.900366 -203.562458) (xy 413.899857 -203.590344)
			(xy 413.891737 -203.64552) (xy 413.875669 -203.698927) (xy 413.851997 -203.749424) (xy 413.821224 -203.795937)
			(xy 413.784007 -203.837474) (xy 413.741139 -203.873149) (xy 413.693533 -203.902203) (xy 413.642204 -203.924015)
			(xy 413.588247 -203.938121) (xy 413.53281 -203.944221) (xy 413.477076 -203.942184) (xy 413.422233 -203.932054)
			(xy 413.369449 -203.914047) (xy 413.319849 -203.888546) (xy 413.274491 -203.856095) (xy 413.234342 -203.817386)
			(xy 413.200256 -203.773243) (xy 413.17296 -203.724608) (xy 413.153037 -203.672517) (xy 413.140911 -203.61808)
			(xy 413.13684 -203.562458) (xy 383.312924 -203.562458) (xy 383.312924 -204.158596) (xy 407.590242 -204.158596)
			(xy 407.594313 -204.102974) (xy 407.606439 -204.048537) (xy 407.626362 -203.996446) (xy 407.653658 -203.947811)
			(xy 407.687744 -203.903668) (xy 407.727893 -203.864959) (xy 407.773251 -203.832508) (xy 407.822851 -203.807007)
			(xy 407.875635 -203.789) (xy 407.930478 -203.77887) (xy 407.986212 -203.776833) (xy 408.041649 -203.782933)
			(xy 408.095606 -203.797039) (xy 408.146935 -203.818851) (xy 408.194541 -203.847905) (xy 408.237409 -203.88358)
			(xy 408.274626 -203.925117) (xy 408.305399 -203.97163) (xy 408.329071 -204.022127) (xy 408.345139 -204.075534)
			(xy 408.353259 -204.13071) (xy 408.353768 -204.158596) (xy 408.353259 -204.186482) (xy 408.345139 -204.241658)
			(xy 408.329071 -204.295065) (xy 408.305399 -204.345562) (xy 408.274626 -204.392075) (xy 408.237409 -204.433612)
			(xy 408.194541 -204.469287) (xy 408.146935 -204.498341) (xy 408.095606 -204.520153) (xy 408.041649 -204.534259)
			(xy 407.986212 -204.540359) (xy 407.930478 -204.538322) (xy 407.875635 -204.528192) (xy 407.822851 -204.510185)
			(xy 407.773251 -204.484684) (xy 407.727893 -204.452233) (xy 407.687744 -204.413524) (xy 407.653658 -204.369381)
			(xy 407.626362 -204.320746) (xy 407.606439 -204.268655) (xy 407.594313 -204.214218) (xy 407.590242 -204.158596)
			(xy 383.312924 -204.158596) (xy 383.312924 -208.06791) (xy 407.722068 -208.06791) (xy 407.726139 -208.012288)
			(xy 407.738265 -207.957851) (xy 407.758188 -207.90576) (xy 407.785484 -207.857125) (xy 407.81957 -207.812982)
			(xy 407.859719 -207.774273) (xy 407.905077 -207.741822) (xy 407.954677 -207.716321) (xy 408.007461 -207.698314)
			(xy 408.062304 -207.688184) (xy 408.118038 -207.686147) (xy 408.173475 -207.692247) (xy 408.227432 -207.706353)
			(xy 408.278761 -207.728165) (xy 408.326367 -207.757219) (xy 408.369235 -207.792894) (xy 408.406452 -207.834431)
			(xy 408.437225 -207.880944) (xy 408.460897 -207.931441) (xy 408.47368 -207.97393) (xy 454.542396 -207.97393)
			(xy 454.546467 -207.918308) (xy 454.558593 -207.863871) (xy 454.578516 -207.81178) (xy 454.605812 -207.763145)
			(xy 454.639898 -207.719002) (xy 454.680047 -207.680293) (xy 454.725405 -207.647842) (xy 454.775005 -207.622341)
			(xy 454.827789 -207.604334) (xy 454.882632 -207.594204) (xy 454.938366 -207.592167) (xy 454.993803 -207.598267)
			(xy 455.04776 -207.612373) (xy 455.099089 -207.634185) (xy 455.146695 -207.663239) (xy 455.189563 -207.698914)
			(xy 455.22678 -207.740451) (xy 455.257553 -207.786964) (xy 455.281225 -207.837461) (xy 455.297293 -207.890868)
			(xy 455.305413 -207.946044) (xy 455.305922 -207.97393) (xy 455.305413 -208.001816) (xy 455.297293 -208.056992)
			(xy 455.281225 -208.110399) (xy 455.257553 -208.160896) (xy 455.22678 -208.207409) (xy 455.189563 -208.248946)
			(xy 455.146695 -208.284621) (xy 455.099089 -208.313675) (xy 455.04776 -208.335487) (xy 454.993803 -208.349593)
			(xy 454.938366 -208.355693) (xy 454.882632 -208.353656) (xy 454.827789 -208.343526) (xy 454.775005 -208.325519)
			(xy 454.725405 -208.300018) (xy 454.680047 -208.267567) (xy 454.639898 -208.228858) (xy 454.605812 -208.184715)
			(xy 454.578516 -208.13608) (xy 454.558593 -208.083989) (xy 454.546467 -208.029552) (xy 454.542396 -207.97393)
			(xy 408.47368 -207.97393) (xy 408.476965 -207.984848) (xy 408.485085 -208.040024) (xy 408.485594 -208.06791)
			(xy 408.485085 -208.095796) (xy 408.476965 -208.150972) (xy 408.460897 -208.204379) (xy 408.437225 -208.254876)
			(xy 408.406452 -208.301389) (xy 408.369235 -208.342926) (xy 408.326367 -208.378601) (xy 408.278761 -208.407655)
			(xy 408.227432 -208.429467) (xy 408.173475 -208.443573) (xy 408.118038 -208.449673) (xy 408.062304 -208.447636)
			(xy 408.007461 -208.437506) (xy 407.954677 -208.419499) (xy 407.905077 -208.393998) (xy 407.859719 -208.361547)
			(xy 407.81957 -208.322838) (xy 407.785484 -208.278695) (xy 407.758188 -208.23006) (xy 407.738265 -208.177969)
			(xy 407.726139 -208.123532) (xy 407.722068 -208.06791) (xy 383.312924 -208.06791) (xy 383.312924 -209.380836)
			(xy 445.288416 -209.380836) (xy 445.288416 -208.517236) (xy 445.288906 -208.487268) (xy 445.296729 -208.427846)
			(xy 445.312242 -208.369953) (xy 445.335178 -208.31458) (xy 445.365145 -208.262674) (xy 445.401632 -208.215124)
			(xy 445.444012 -208.172744) (xy 445.491562 -208.136257) (xy 445.543468 -208.10629) (xy 445.598841 -208.083354)
			(xy 445.656734 -208.067841) (xy 445.716156 -208.060018) (xy 445.776092 -208.060018) (xy 445.835514 -208.067841)
			(xy 445.893407 -208.083354) (xy 445.94878 -208.10629) (xy 446.000686 -208.136257) (xy 446.048236 -208.172744)
			(xy 446.090616 -208.215124) (xy 446.127103 -208.262674) (xy 446.15707 -208.31458) (xy 446.180006 -208.369953)
			(xy 446.195519 -208.427846) (xy 446.203342 -208.487268) (xy 446.203832 -208.517236) (xy 446.203832 -209.380836)
			(xy 446.203342 -209.410804) (xy 446.195519 -209.470226) (xy 446.180006 -209.528119) (xy 446.15707 -209.583492)
			(xy 446.127103 -209.635398) (xy 446.090616 -209.682948) (xy 446.048236 -209.725328) (xy 446.000686 -209.761815)
			(xy 445.94878 -209.791782) (xy 445.893407 -209.814718) (xy 445.835514 -209.830231) (xy 445.776092 -209.838054)
			(xy 445.716156 -209.838054) (xy 445.656734 -209.830231) (xy 445.598841 -209.814718) (xy 445.543468 -209.791782)
			(xy 445.491562 -209.761815) (xy 445.444012 -209.725328) (xy 445.401632 -209.682948) (xy 445.365145 -209.635398)
			(xy 445.335178 -209.583492) (xy 445.312242 -209.528119) (xy 445.296729 -209.470226) (xy 445.288906 -209.410804)
			(xy 445.288416 -209.380836) (xy 383.312924 -209.380836) (xy 383.312924 -209.94878) (xy 451.586598 -209.94878)
			(xy 451.590669 -209.893158) (xy 451.602795 -209.838721) (xy 451.622718 -209.78663) (xy 451.650014 -209.737995)
			(xy 451.6841 -209.693852) (xy 451.724249 -209.655143) (xy 451.769607 -209.622692) (xy 451.819207 -209.597191)
			(xy 451.871991 -209.579184) (xy 451.926834 -209.569054) (xy 451.982568 -209.567017) (xy 452.038005 -209.573117)
			(xy 452.091962 -209.587223) (xy 452.143291 -209.609035) (xy 452.190897 -209.638089) (xy 452.233765 -209.673764)
			(xy 452.270982 -209.715301) (xy 452.301755 -209.761814) (xy 452.325427 -209.812311) (xy 452.341495 -209.865718)
			(xy 452.349615 -209.920894) (xy 452.350124 -209.94878) (xy 452.349615 -209.976666) (xy 452.341495 -210.031842)
			(xy 452.325427 -210.085249) (xy 452.301755 -210.135746) (xy 452.270982 -210.182259) (xy 452.233765 -210.223796)
			(xy 452.190897 -210.259471) (xy 452.143291 -210.288525) (xy 452.091962 -210.310337) (xy 452.038005 -210.324443)
			(xy 451.982568 -210.330543) (xy 451.926834 -210.328506) (xy 451.871991 -210.318376) (xy 451.819207 -210.300369)
			(xy 451.769607 -210.274868) (xy 451.724249 -210.242417) (xy 451.6841 -210.203708) (xy 451.650014 -210.159565)
			(xy 451.622718 -210.11093) (xy 451.602795 -210.058839) (xy 451.590669 -210.004402) (xy 451.586598 -209.94878)
			(xy 383.312924 -209.94878) (xy 383.312924 -210.341718) (xy 409.3497 -210.341718) (xy 409.353771 -210.286096)
			(xy 409.365897 -210.231659) (xy 409.38582 -210.179568) (xy 409.413116 -210.130933) (xy 409.447202 -210.08679)
			(xy 409.487351 -210.048081) (xy 409.532709 -210.01563) (xy 409.582309 -209.990129) (xy 409.635093 -209.972122)
			(xy 409.689936 -209.961992) (xy 409.74567 -209.959955) (xy 409.801107 -209.966055) (xy 409.855064 -209.980161)
			(xy 409.906393 -210.001973) (xy 409.953999 -210.031027) (xy 409.996867 -210.066702) (xy 410.034084 -210.108239)
			(xy 410.064857 -210.154752) (xy 410.088529 -210.205249) (xy 410.104597 -210.258656) (xy 410.112717 -210.313832)
			(xy 410.113226 -210.341718) (xy 410.112717 -210.369604) (xy 410.104597 -210.42478) (xy 410.088529 -210.478187)
			(xy 410.064857 -210.528684) (xy 410.034084 -210.575197) (xy 409.996867 -210.616734) (xy 409.953999 -210.652409)
			(xy 409.906393 -210.681463) (xy 409.855064 -210.703275) (xy 409.801107 -210.717381) (xy 409.74567 -210.723481)
			(xy 409.689936 -210.721444) (xy 409.635093 -210.711314) (xy 409.582309 -210.693307) (xy 409.532709 -210.667806)
			(xy 409.487351 -210.635355) (xy 409.447202 -210.596646) (xy 409.413116 -210.552503) (xy 409.38582 -210.503868)
			(xy 409.365897 -210.451777) (xy 409.353771 -210.39734) (xy 409.3497 -210.341718) (xy 383.312924 -210.341718)
			(xy 383.312924 -211.301076) (xy 383.313302 -211.310187) (xy 383.319647 -211.327268) (xy 383.331523 -211.34109)
			(xy 383.33934 -211.34578) (xy 383.41554 -211.387182) (xy 383.420366 -211.389468) (xy 383.428413 -211.392472)
			(xy 383.445547 -211.393523) (xy 383.453894 -211.3915) (xy 383.469388 -211.386928) (xy 383.475484 -211.383372)
			(xy 383.475992 -211.383118) (xy 383.498451 -211.369965) (xy 383.546176 -211.3492) (xy 383.596281 -211.335118)
			(xy 383.647835 -211.327981) (xy 383.673858 -211.327492) (xy 383.701113 -211.327952) (xy 383.755068 -211.335705)
			(xy 383.807371 -211.351057) (xy 383.856957 -211.373697) (xy 383.902815 -211.403164) (xy 383.944013 -211.438858)
			(xy 383.979711 -211.480051) (xy 384.009183 -211.525907) (xy 384.031828 -211.575489) (xy 384.047186 -211.627791)
			(xy 384.054945 -211.681745) (xy 384.054945 -211.736255) (xy 384.047186 -211.790209) (xy 384.031828 -211.842511)
			(xy 384.009183 -211.892093) (xy 383.979711 -211.937949) (xy 383.944013 -211.979142) (xy 383.902815 -212.014836)
			(xy 383.856957 -212.044303) (xy 383.807371 -212.066943) (xy 383.755068 -212.082295) (xy 383.701113 -212.090048)
			(xy 383.673858 -212.090508) (xy 383.646832 -212.090016) (xy 383.593325 -212.082351) (xy 383.541432 -212.067221)
			(xy 383.492189 -212.044929) (xy 383.469134 -212.030818) (xy 383.457196 -212.023452) (xy 383.429764 -212.022436)
			(xy 383.33934 -212.07222) (xy 383.33158 -212.076917) (xy 383.31973 -212.090634) (xy 383.31337 -212.107608)
			(xy 383.312924 -212.11667) (xy 383.312924 -214.319612) (xy 383.312469 -214.352468) (xy 383.305121 -214.417767)
			(xy 383.290509 -214.481833) (xy 383.268816 -214.54386) (xy 383.240315 -214.603068) (xy 383.205363 -214.658713)
			(xy 383.164402 -214.710095) (xy 383.141474 -214.733632) (xy 379.471936 -218.40317) (xy 380.707644 -218.40317)
			(xy 380.711715 -218.347548) (xy 380.723841 -218.293111) (xy 380.743764 -218.24102) (xy 380.77106 -218.192385)
			(xy 380.805146 -218.148242) (xy 380.845295 -218.109533) (xy 380.890653 -218.077082) (xy 380.940253 -218.051581)
			(xy 380.993037 -218.033574) (xy 381.04788 -218.023444) (xy 381.103614 -218.021407) (xy 381.159051 -218.027507)
			(xy 381.213008 -218.041613) (xy 381.264337 -218.063425) (xy 381.311943 -218.092479) (xy 381.354811 -218.128154)
			(xy 381.392028 -218.169691) (xy 381.422801 -218.216204) (xy 381.446473 -218.266701) (xy 381.462541 -218.320108)
			(xy 381.469382 -218.366594) (xy 381.872234 -218.366594) (xy 381.876305 -218.310972) (xy 381.888431 -218.256535)
			(xy 381.908354 -218.204444) (xy 381.93565 -218.155809) (xy 381.969736 -218.111666) (xy 382.009885 -218.072957)
			(xy 382.055243 -218.040506) (xy 382.104843 -218.015005) (xy 382.157627 -217.996998) (xy 382.21247 -217.986868)
			(xy 382.268204 -217.984831) (xy 382.323641 -217.990931) (xy 382.377598 -218.005037) (xy 382.428927 -218.026849)
			(xy 382.476533 -218.055903) (xy 382.519401 -218.091578) (xy 382.556618 -218.133115) (xy 382.587391 -218.179628)
			(xy 382.611063 -218.230125) (xy 382.627131 -218.283532) (xy 382.635251 -218.338708) (xy 382.63576 -218.366594)
			(xy 382.635251 -218.39448) (xy 382.627131 -218.449656) (xy 382.611063 -218.503063) (xy 382.587391 -218.55356)
			(xy 382.556618 -218.600073) (xy 382.519401 -218.64161) (xy 382.476533 -218.677285) (xy 382.428927 -218.706339)
			(xy 382.377598 -218.728151) (xy 382.323641 -218.742257) (xy 382.268204 -218.748357) (xy 382.21247 -218.74632)
			(xy 382.157627 -218.73619) (xy 382.104843 -218.718183) (xy 382.055243 -218.692682) (xy 382.009885 -218.660231)
			(xy 381.969736 -218.621522) (xy 381.93565 -218.577379) (xy 381.908354 -218.528744) (xy 381.888431 -218.476653)
			(xy 381.876305 -218.422216) (xy 381.872234 -218.366594) (xy 381.469382 -218.366594) (xy 381.470661 -218.375284)
			(xy 381.47117 -218.40317) (xy 381.470661 -218.431056) (xy 381.462541 -218.486232) (xy 381.446473 -218.539639)
			(xy 381.422801 -218.590136) (xy 381.392028 -218.636649) (xy 381.354811 -218.678186) (xy 381.311943 -218.713861)
			(xy 381.264337 -218.742915) (xy 381.213008 -218.764727) (xy 381.159051 -218.778833) (xy 381.103614 -218.784933)
			(xy 381.04788 -218.782896) (xy 380.993037 -218.772766) (xy 380.940253 -218.754759) (xy 380.890653 -218.729258)
			(xy 380.845295 -218.696807) (xy 380.805146 -218.658098) (xy 380.77106 -218.613955) (xy 380.743764 -218.56532)
			(xy 380.723841 -218.513229) (xy 380.711715 -218.458792) (xy 380.707644 -218.40317) (xy 379.471936 -218.40317)
			(xy 378.028454 -219.846652) (xy 378.02161 -219.854051) (xy 378.013886 -219.87265) (xy 378.013468 -219.88272)
			(xy 378.013468 -220.324172) (xy 383.84683 -220.324172) (xy 383.850901 -220.26855) (xy 383.863027 -220.214113)
			(xy 383.88295 -220.162022) (xy 383.910246 -220.113387) (xy 383.944332 -220.069244) (xy 383.984481 -220.030535)
			(xy 384.029839 -219.998084) (xy 384.079439 -219.972583) (xy 384.132223 -219.954576) (xy 384.187066 -219.944446)
			(xy 384.2428 -219.942409) (xy 384.298237 -219.948509) (xy 384.352194 -219.962615) (xy 384.403523 -219.984427)
			(xy 384.451129 -220.013481) (xy 384.493997 -220.049156) (xy 384.531214 -220.090693) (xy 384.561987 -220.137206)
			(xy 384.585659 -220.187703) (xy 384.601727 -220.24111) (xy 384.609847 -220.296286) (xy 384.610356 -220.324172)
			(xy 384.609847 -220.352058) (xy 384.601727 -220.407234) (xy 384.585659 -220.460641) (xy 384.561987 -220.511138)
			(xy 384.531214 -220.557651) (xy 384.493997 -220.599188) (xy 384.451129 -220.634863) (xy 384.403523 -220.663917)
			(xy 384.352194 -220.685729) (xy 384.298237 -220.699835) (xy 384.2428 -220.705935) (xy 384.187066 -220.703898)
			(xy 384.132223 -220.693768) (xy 384.079439 -220.675761) (xy 384.029839 -220.65026) (xy 383.984481 -220.617809)
			(xy 383.944332 -220.5791) (xy 383.910246 -220.534957) (xy 383.88295 -220.486322) (xy 383.863027 -220.434231)
			(xy 383.850901 -220.379794) (xy 383.84683 -220.324172) (xy 378.013468 -220.324172) (xy 378.013468 -221.293182)
			(xy 378.036836 -221.321376) (xy 378.049497 -221.323662) (xy 417.33419 -221.323662) (xy 417.338261 -221.26804)
			(xy 417.350387 -221.213603) (xy 417.37031 -221.161512) (xy 417.397606 -221.112877) (xy 417.431692 -221.068734)
			(xy 417.471841 -221.030025) (xy 417.517199 -220.997574) (xy 417.566799 -220.972073) (xy 417.619583 -220.954066)
			(xy 417.674426 -220.943936) (xy 417.73016 -220.941899) (xy 417.785597 -220.947999) (xy 417.839554 -220.962105)
			(xy 417.890883 -220.983917) (xy 417.938489 -221.012971) (xy 417.981357 -221.048646) (xy 418.018574 -221.090183)
			(xy 418.049347 -221.136696) (xy 418.073019 -221.187193) (xy 418.089087 -221.2406) (xy 418.097207 -221.295776)
			(xy 418.097716 -221.323662) (xy 418.097207 -221.351548) (xy 418.089087 -221.406724) (xy 418.073019 -221.460131)
			(xy 418.049347 -221.510628) (xy 418.018574 -221.557141) (xy 417.981357 -221.598678) (xy 417.938489 -221.634353)
			(xy 417.890883 -221.663407) (xy 417.839554 -221.685219) (xy 417.785597 -221.699325) (xy 417.73016 -221.705425)
			(xy 417.674426 -221.703388) (xy 417.619583 -221.693258) (xy 417.566799 -221.675251) (xy 417.517199 -221.64975)
			(xy 417.471841 -221.617299) (xy 417.431692 -221.57859) (xy 417.397606 -221.534447) (xy 417.37031 -221.485812)
			(xy 417.350387 -221.433721) (xy 417.338261 -221.379284) (xy 417.33419 -221.323662) (xy 378.049497 -221.323662)
			(xy 378.055124 -221.324678) (xy 378.081252 -221.329867) (xy 378.131852 -221.346522) (xy 378.17965 -221.370037)
			(xy 378.223724 -221.399957) (xy 378.26322 -221.435702) (xy 378.297374 -221.476582) (xy 378.325525 -221.521806)
			(xy 378.34713 -221.570498) (xy 378.361769 -221.621717) (xy 378.369159 -221.674471) (xy 378.369576 -221.701106)
			(xy 378.369576 -221.955106) (xy 380.780034 -221.955106) (xy 380.784105 -221.899484) (xy 380.796231 -221.845047)
			(xy 380.816154 -221.792956) (xy 380.84345 -221.744321) (xy 380.877536 -221.700178) (xy 380.917685 -221.661469)
			(xy 380.963043 -221.629018) (xy 381.012643 -221.603517) (xy 381.065427 -221.58551) (xy 381.12027 -221.57538)
			(xy 381.176004 -221.573343) (xy 381.231441 -221.579443) (xy 381.285398 -221.593549) (xy 381.336727 -221.615361)
			(xy 381.384333 -221.644415) (xy 381.427201 -221.68009) (xy 381.464418 -221.721627) (xy 381.495191 -221.76814)
			(xy 381.518863 -221.818637) (xy 381.534931 -221.872044) (xy 381.543051 -221.92722) (xy 381.543286 -221.94012)
			(xy 385.30479 -221.94012) (xy 385.308861 -221.884498) (xy 385.320987 -221.830061) (xy 385.34091 -221.77797)
			(xy 385.368206 -221.729335) (xy 385.402292 -221.685192) (xy 385.442441 -221.646483) (xy 385.487799 -221.614032)
			(xy 385.537399 -221.588531) (xy 385.590183 -221.570524) (xy 385.645026 -221.560394) (xy 385.70076 -221.558357)
			(xy 385.756197 -221.564457) (xy 385.810154 -221.578563) (xy 385.861483 -221.600375) (xy 385.909089 -221.629429)
			(xy 385.951957 -221.665104) (xy 385.989174 -221.706641) (xy 386.019947 -221.753154) (xy 386.043619 -221.803651)
			(xy 386.059687 -221.857058) (xy 386.067807 -221.912234) (xy 386.068316 -221.94012) (xy 386.067807 -221.968006)
			(xy 386.059687 -222.023182) (xy 386.043619 -222.076589) (xy 386.033769 -222.0976) (xy 451.742046 -222.0976)
			(xy 451.746117 -222.041978) (xy 451.758243 -221.987541) (xy 451.778166 -221.93545) (xy 451.805462 -221.886815)
			(xy 451.839548 -221.842672) (xy 451.879697 -221.803963) (xy 451.925055 -221.771512) (xy 451.974655 -221.746011)
			(xy 452.027439 -221.728004) (xy 452.082282 -221.717874) (xy 452.138016 -221.715837) (xy 452.193453 -221.721937)
			(xy 452.24741 -221.736043) (xy 452.298739 -221.757855) (xy 452.346345 -221.786909) (xy 452.389213 -221.822584)
			(xy 452.42643 -221.864121) (xy 452.457203 -221.910634) (xy 452.480875 -221.961131) (xy 452.496943 -222.014538)
			(xy 452.505063 -222.069714) (xy 452.505572 -222.0976) (xy 452.505063 -222.125486) (xy 452.496943 -222.180662)
			(xy 452.480875 -222.234069) (xy 452.457203 -222.284566) (xy 452.42643 -222.331079) (xy 452.389213 -222.372616)
			(xy 452.346345 -222.408291) (xy 452.298739 -222.437345) (xy 452.24741 -222.459157) (xy 452.193453 -222.473263)
			(xy 452.138016 -222.479363) (xy 452.082282 -222.477326) (xy 452.027439 -222.467196) (xy 451.974655 -222.449189)
			(xy 451.925055 -222.423688) (xy 451.879697 -222.391237) (xy 451.839548 -222.352528) (xy 451.805462 -222.308385)
			(xy 451.778166 -222.25975) (xy 451.758243 -222.207659) (xy 451.746117 -222.153222) (xy 451.742046 -222.0976)
			(xy 386.033769 -222.0976) (xy 386.019947 -222.127086) (xy 385.989174 -222.173599) (xy 385.951957 -222.215136)
			(xy 385.909089 -222.250811) (xy 385.861483 -222.279865) (xy 385.810154 -222.301677) (xy 385.756197 -222.315783)
			(xy 385.70076 -222.321883) (xy 385.645026 -222.319846) (xy 385.590183 -222.309716) (xy 385.537399 -222.291709)
			(xy 385.487799 -222.266208) (xy 385.442441 -222.233757) (xy 385.402292 -222.195048) (xy 385.368206 -222.150905)
			(xy 385.34091 -222.10227) (xy 385.320987 -222.050179) (xy 385.308861 -221.995742) (xy 385.30479 -221.94012)
			(xy 381.543286 -221.94012) (xy 381.54356 -221.955106) (xy 381.543051 -221.982992) (xy 381.534931 -222.038168)
			(xy 381.518863 -222.091575) (xy 381.495191 -222.142072) (xy 381.464418 -222.188585) (xy 381.427201 -222.230122)
			(xy 381.384333 -222.265797) (xy 381.336727 -222.294851) (xy 381.285398 -222.316663) (xy 381.231441 -222.330769)
			(xy 381.176004 -222.336869) (xy 381.12027 -222.334832) (xy 381.065427 -222.324702) (xy 381.012643 -222.306695)
			(xy 380.963043 -222.281194) (xy 380.917685 -222.248743) (xy 380.877536 -222.210034) (xy 380.84345 -222.165891)
			(xy 380.816154 -222.117256) (xy 380.796231 -222.065165) (xy 380.784105 -222.010728) (xy 380.780034 -221.955106)
			(xy 378.369576 -221.955106) (xy 378.369576 -222.189802) (xy 378.368987 -222.219863) (xy 378.359588 -222.279245)
			(xy 378.341019 -222.336428) (xy 378.313739 -222.390004) (xy 378.278419 -222.438657) (xy 378.257562 -222.460312)
			(xy 378.12726 -222.590868) (xy 378.119098 -222.599954) (xy 378.11167 -222.62318) (xy 378.113036 -222.635318)
			(xy 378.128784 -222.729044) (xy 378.143516 -222.748602) (xy 378.154438 -222.753936) (xy 378.178294 -222.766048)
			(xy 378.222665 -222.795943) (xy 378.262439 -222.831726) (xy 378.296842 -222.872701) (xy 378.325201 -222.918068)
			(xy 378.346966 -222.966943) (xy 378.361711 -223.018373) (xy 378.369148 -223.071355) (xy 378.369576 -223.098106)
			(xy 378.369576 -225.848164) (xy 378.370049 -225.858067) (xy 378.377544 -225.8764) (xy 378.391401 -225.890552)
			(xy 378.40031 -225.8949) (xy 378.400564 -225.8949) (xy 378.41005 -225.89844) (xy 378.430281 -225.898534)
			(xy 378.448987 -225.890827) (xy 378.456444 -225.883978) (xy 380.781052 -223.559624) (xy 380.802723 -223.538771)
			(xy 380.851359 -223.503399) (xy 380.904925 -223.476062) (xy 380.962105 -223.457432) (xy 381.021494 -223.447966)
			(xy 381.051562 -223.447356) (xy 385.230878 -223.447356) (xy 385.24232 -223.44683) (xy 385.26294 -223.43691)
			(xy 385.270502 -223.428306) (xy 385.319778 -223.367092) (xy 385.325795 -223.35897) (xy 385.331438 -223.33958)
			(xy 385.3307 -223.3295) (xy 385.329938 -223.323658) (xy 385.32943 -223.321118) (xy 385.32943 -223.320864)
			(xy 385.328414 -223.315784) (xy 385.324797 -223.297068) (xy 385.32085 -223.259152) (xy 385.32054 -223.240092)
			(xy 385.321027 -223.212779) (xy 385.328798 -223.158709) (xy 385.344182 -223.106294) (xy 385.366865 -223.056601)
			(xy 385.396386 -223.010639) (xy 385.432144 -222.969344) (xy 385.473413 -222.933555) (xy 385.519353 -222.904)
			(xy 385.56903 -222.881281) (xy 385.621433 -222.865859) (xy 385.675498 -222.858047) (xy 385.70281 -222.857568)
			(xy 417.78936 -222.857568) (xy 417.819419 -222.858162) (xy 417.878795 -222.86757) (xy 417.935971 -222.886147)
			(xy 417.989539 -222.913434) (xy 418.038182 -222.948761) (xy 418.05987 -222.969582) (xy 418.406841 -223.316546)
			(xy 443.32982 -223.316546) (xy 443.333891 -223.260924) (xy 443.346017 -223.206487) (xy 443.36594 -223.154396)
			(xy 443.393236 -223.105761) (xy 443.427322 -223.061618) (xy 443.467471 -223.022909) (xy 443.512829 -222.990458)
			(xy 443.562429 -222.964957) (xy 443.615213 -222.94695) (xy 443.670056 -222.93682) (xy 443.72579 -222.934783)
			(xy 443.781227 -222.940883) (xy 443.835184 -222.954989) (xy 443.886513 -222.976801) (xy 443.934119 -223.005855)
			(xy 443.976987 -223.04153) (xy 444.014204 -223.083067) (xy 444.044977 -223.12958) (xy 444.068649 -223.180077)
			(xy 444.084717 -223.233484) (xy 444.092837 -223.28866) (xy 444.093346 -223.316546) (xy 444.092837 -223.344432)
			(xy 444.084717 -223.399608) (xy 444.068649 -223.453015) (xy 444.044977 -223.503512) (xy 444.014204 -223.550025)
			(xy 443.976987 -223.591562) (xy 443.934119 -223.627237) (xy 443.886513 -223.656291) (xy 443.835184 -223.678103)
			(xy 443.781227 -223.692209) (xy 443.72579 -223.698309) (xy 443.670056 -223.696272) (xy 443.615213 -223.686142)
			(xy 443.562429 -223.668135) (xy 443.512829 -223.642634) (xy 443.467471 -223.610183) (xy 443.427322 -223.571474)
			(xy 443.393236 -223.527331) (xy 443.36594 -223.478696) (xy 443.346017 -223.426605) (xy 443.333891 -223.372168)
			(xy 443.32982 -223.316546) (xy 418.406841 -223.316546) (xy 419.791168 -224.700846) (xy 443.326518 -224.700846)
			(xy 443.330589 -224.645224) (xy 443.342715 -224.590787) (xy 443.362638 -224.538696) (xy 443.389934 -224.490061)
			(xy 443.42402 -224.445918) (xy 443.464169 -224.407209) (xy 443.509527 -224.374758) (xy 443.559127 -224.349257)
			(xy 443.611911 -224.33125) (xy 443.666754 -224.32112) (xy 443.722488 -224.319083) (xy 443.777925 -224.325183)
			(xy 443.831882 -224.339289) (xy 443.883211 -224.361101) (xy 443.930817 -224.390155) (xy 443.973685 -224.42583)
			(xy 444.010902 -224.467367) (xy 444.041675 -224.51388) (xy 444.065347 -224.564377) (xy 444.081415 -224.617784)
			(xy 444.089535 -224.67296) (xy 444.090044 -224.700846) (xy 444.089535 -224.728732) (xy 444.081415 -224.783908)
			(xy 444.065347 -224.837315) (xy 444.041675 -224.887812) (xy 444.010902 -224.934325) (xy 443.973685 -224.975862)
			(xy 443.930817 -225.011537) (xy 443.883211 -225.040591) (xy 443.831882 -225.062403) (xy 443.777925 -225.076509)
			(xy 443.722488 -225.082609) (xy 443.666754 -225.080572) (xy 443.611911 -225.070442) (xy 443.559127 -225.052435)
			(xy 443.509527 -225.026934) (xy 443.464169 -224.994483) (xy 443.42402 -224.955774) (xy 443.389934 -224.911631)
			(xy 443.362638 -224.862996) (xy 443.342715 -224.810905) (xy 443.330589 -224.756468) (xy 443.326518 -224.700846)
			(xy 419.791168 -224.700846) (xy 421.771899 -226.681538) (xy 457.325982 -226.681538) (xy 457.330053 -226.625916)
			(xy 457.342179 -226.571479) (xy 457.362102 -226.519388) (xy 457.389398 -226.470753) (xy 457.423484 -226.42661)
			(xy 457.463633 -226.387901) (xy 457.508991 -226.35545) (xy 457.558591 -226.329949) (xy 457.611375 -226.311942)
			(xy 457.666218 -226.301812) (xy 457.721952 -226.299775) (xy 457.777389 -226.305875) (xy 457.831346 -226.319981)
			(xy 457.882675 -226.341793) (xy 457.930281 -226.370847) (xy 457.973149 -226.406522) (xy 458.010366 -226.448059)
			(xy 458.041139 -226.494572) (xy 458.064811 -226.545069) (xy 458.080879 -226.598476) (xy 458.088999 -226.653652)
			(xy 458.089508 -226.681538) (xy 458.088999 -226.709424) (xy 458.080879 -226.7646) (xy 458.064811 -226.818007)
			(xy 458.041139 -226.868504) (xy 458.010366 -226.915017) (xy 457.973149 -226.956554) (xy 457.930281 -226.992229)
			(xy 457.882675 -227.021283) (xy 457.831346 -227.043095) (xy 457.777389 -227.057201) (xy 457.721952 -227.063301)
			(xy 457.666218 -227.061264) (xy 457.611375 -227.051134) (xy 457.558591 -227.033127) (xy 457.508991 -227.007626)
			(xy 457.463633 -226.975175) (xy 457.423484 -226.936466) (xy 457.389398 -226.892323) (xy 457.362102 -226.843688)
			(xy 457.342179 -226.791597) (xy 457.330053 -226.73716) (xy 457.325982 -226.681538) (xy 421.771899 -226.681538)
			(xy 423.758249 -228.667848) (xy 442.823618 -228.667848) (xy 442.823618 -228.613352) (xy 442.831374 -228.55941)
			(xy 442.846727 -228.50712) (xy 442.869366 -228.457548) (xy 442.898829 -228.411703) (xy 442.934517 -228.370517)
			(xy 442.975703 -228.334829) (xy 443.021548 -228.305366) (xy 443.07112 -228.282727) (xy 443.12341 -228.267374)
			(xy 443.177352 -228.259618) (xy 443.2046 -228.259132) (xy 443.233517 -228.259638) (xy 443.29069 -228.268368)
			(xy 443.345889 -228.285628) (xy 443.397851 -228.311022) (xy 443.445385 -228.343968) (xy 443.487401 -228.383711)
			(xy 443.50559 -228.406198) (xy 443.513212 -228.41499) (xy 443.534101 -228.425182) (xy 443.545722 -228.425756)
			(xy 443.625478 -228.425756) (xy 443.637109 -228.425205) (xy 443.658019 -228.415026) (xy 443.66561 -228.406198)
			(xy 443.683795 -228.383709) (xy 443.725816 -228.343975) (xy 443.773352 -228.311036) (xy 443.825315 -228.285649)
			(xy 443.880513 -228.268394) (xy 443.937684 -228.259666) (xy 443.9666 -228.259132) (xy 443.993854 -228.259538)
			(xy 444.047807 -228.267295) (xy 444.100108 -228.282652) (xy 444.14969 -228.305295) (xy 444.195545 -228.334765)
			(xy 444.23674 -228.37046) (xy 444.272435 -228.411655) (xy 444.301905 -228.45751) (xy 444.324548 -228.507092)
			(xy 444.339905 -228.559393) (xy 444.347662 -228.613346) (xy 444.347662 -228.667854) (xy 444.339905 -228.721807)
			(xy 444.324548 -228.774108) (xy 444.301905 -228.82369) (xy 444.272435 -228.869545) (xy 444.23674 -228.91074)
			(xy 444.195545 -228.946435) (xy 444.14969 -228.975905) (xy 444.100108 -228.998548) (xy 444.047807 -229.013905)
			(xy 443.993854 -229.021662) (xy 443.9666 -229.022148) (xy 443.937682 -229.021649) (xy 443.880509 -229.012919)
			(xy 443.825309 -228.995658) (xy 443.773347 -228.970263) (xy 443.725814 -228.937315) (xy 443.683799 -228.89757)
			(xy 443.66561 -228.875082) (xy 443.657992 -228.866286) (xy 443.637099 -228.856097) (xy 443.625478 -228.855524)
			(xy 443.545722 -228.855524) (xy 443.534092 -228.856082) (xy 443.513182 -228.866256) (xy 443.50559 -228.875082)
			(xy 443.4874 -228.897567) (xy 443.445381 -228.937302) (xy 443.397846 -228.970242) (xy 443.345884 -228.99563)
			(xy 443.290686 -229.012886) (xy 443.233516 -229.021614) (xy 443.2046 -229.022148) (xy 443.177352 -229.021582)
			(xy 443.12341 -229.013826) (xy 443.07112 -228.998473) (xy 443.021548 -228.975834) (xy 442.975703 -228.946371)
			(xy 442.934517 -228.910683) (xy 442.898829 -228.869497) (xy 442.869366 -228.823652) (xy 442.846727 -228.77408)
			(xy 442.831374 -228.72179) (xy 442.823618 -228.667848) (xy 423.758249 -228.667848) (xy 424.21238 -229.12197)
			(xy 444.350392 -229.12197) (xy 444.354463 -229.066348) (xy 444.366589 -229.011911) (xy 444.386512 -228.95982)
			(xy 444.413808 -228.911185) (xy 444.447894 -228.867042) (xy 444.488043 -228.828333) (xy 444.533401 -228.795882)
			(xy 444.583001 -228.770381) (xy 444.635785 -228.752374) (xy 444.690628 -228.742244) (xy 444.746362 -228.740207)
			(xy 444.801799 -228.746307) (xy 444.855756 -228.760413) (xy 444.907085 -228.782225) (xy 444.954691 -228.811279)
			(xy 444.997559 -228.846954) (xy 445.034776 -228.888491) (xy 445.065549 -228.935004) (xy 445.089221 -228.985501)
			(xy 445.105289 -229.038908) (xy 445.113409 -229.094084) (xy 445.113918 -229.12197) (xy 445.113409 -229.149856)
			(xy 445.105289 -229.205032) (xy 445.089221 -229.258439) (xy 445.065549 -229.308936) (xy 445.034776 -229.355449)
			(xy 444.997559 -229.396986) (xy 444.954691 -229.432661) (xy 444.907085 -229.461715) (xy 444.855756 -229.483527)
			(xy 444.801799 -229.497633) (xy 444.746362 -229.503733) (xy 444.690628 -229.501696) (xy 444.635785 -229.491566)
			(xy 444.583001 -229.473559) (xy 444.533401 -229.448058) (xy 444.488043 -229.415607) (xy 444.447894 -229.376898)
			(xy 444.413808 -229.332755) (xy 444.386512 -229.28412) (xy 444.366589 -229.232029) (xy 444.354463 -229.177592)
			(xy 444.350392 -229.12197) (xy 424.21238 -229.12197) (xy 425.443034 -230.3526) (xy 461.872582 -230.3526)
			(xy 461.876653 -230.296978) (xy 461.888779 -230.242541) (xy 461.908702 -230.19045) (xy 461.935998 -230.141815)
			(xy 461.970084 -230.097672) (xy 462.010233 -230.058963) (xy 462.055591 -230.026512) (xy 462.105191 -230.001011)
			(xy 462.157975 -229.983004) (xy 462.212818 -229.972874) (xy 462.268552 -229.970837) (xy 462.323989 -229.976937)
			(xy 462.377946 -229.991043) (xy 462.429275 -230.012855) (xy 462.476881 -230.041909) (xy 462.519749 -230.077584)
			(xy 462.556966 -230.119121) (xy 462.587739 -230.165634) (xy 462.611411 -230.216131) (xy 462.627479 -230.269538)
			(xy 462.635599 -230.324714) (xy 462.636108 -230.3526) (xy 462.635599 -230.380486) (xy 462.627479 -230.435662)
			(xy 462.611411 -230.489069) (xy 462.587739 -230.539566) (xy 462.556966 -230.586079) (xy 462.519749 -230.627616)
			(xy 462.476881 -230.663291) (xy 462.429275 -230.692345) (xy 462.377946 -230.714157) (xy 462.323989 -230.728263)
			(xy 462.268552 -230.734363) (xy 462.212818 -230.732326) (xy 462.157975 -230.722196) (xy 462.105191 -230.704189)
			(xy 462.055591 -230.678688) (xy 462.010233 -230.646237) (xy 461.970084 -230.607528) (xy 461.935998 -230.563385)
			(xy 461.908702 -230.51475) (xy 461.888779 -230.462659) (xy 461.876653 -230.408222) (xy 461.872582 -230.3526)
			(xy 425.443034 -230.3526) (xy 427.784961 -232.69448) (xy 451.24192 -232.69448) (xy 451.245991 -232.638858)
			(xy 451.258117 -232.584421) (xy 451.27804 -232.53233) (xy 451.305336 -232.483695) (xy 451.339422 -232.439552)
			(xy 451.379571 -232.400843) (xy 451.424929 -232.368392) (xy 451.474529 -232.342891) (xy 451.527313 -232.324884)
			(xy 451.582156 -232.314754) (xy 451.63789 -232.312717) (xy 451.693327 -232.318817) (xy 451.747284 -232.332923)
			(xy 451.798613 -232.354735) (xy 451.846219 -232.383789) (xy 451.889087 -232.419464) (xy 451.926304 -232.461001)
			(xy 451.957077 -232.507514) (xy 451.980749 -232.558011) (xy 451.996817 -232.611418) (xy 452.004937 -232.666594)
			(xy 452.005446 -232.69448) (xy 452.004937 -232.722366) (xy 451.996817 -232.777542) (xy 451.980749 -232.830949)
			(xy 451.957077 -232.881446) (xy 451.926304 -232.927959) (xy 451.889087 -232.969496) (xy 451.846219 -233.005171)
			(xy 451.798613 -233.034225) (xy 451.747284 -233.056037) (xy 451.693327 -233.070143) (xy 451.63789 -233.076243)
			(xy 451.582156 -233.074206) (xy 451.527313 -233.064076) (xy 451.474529 -233.046069) (xy 451.424929 -233.020568)
			(xy 451.379571 -232.988117) (xy 451.339422 -232.949408) (xy 451.305336 -232.905265) (xy 451.27804 -232.85663)
			(xy 451.258117 -232.804539) (xy 451.245991 -232.750102) (xy 451.24192 -232.69448) (xy 427.784961 -232.69448)
			(xy 428.23709 -233.1466) (xy 442.035182 -233.1466) (xy 442.039253 -233.090978) (xy 442.051379 -233.036541)
			(xy 442.071302 -232.98445) (xy 442.098598 -232.935815) (xy 442.132684 -232.891672) (xy 442.172833 -232.852963)
			(xy 442.218191 -232.820512) (xy 442.267791 -232.795011) (xy 442.320575 -232.777004) (xy 442.375418 -232.766874)
			(xy 442.431152 -232.764837) (xy 442.486589 -232.770937) (xy 442.540546 -232.785043) (xy 442.591875 -232.806855)
			(xy 442.639481 -232.835909) (xy 442.682349 -232.871584) (xy 442.719566 -232.913121) (xy 442.750339 -232.959634)
			(xy 442.774011 -233.010131) (xy 442.790079 -233.063538) (xy 442.798199 -233.118714) (xy 442.798708 -233.1466)
			(xy 442.798199 -233.174486) (xy 442.790079 -233.229662) (xy 442.775866 -233.276902) (xy 443.9318 -233.276902)
			(xy 443.935871 -233.22128) (xy 443.947997 -233.166843) (xy 443.96792 -233.114752) (xy 443.995216 -233.066117)
			(xy 444.029302 -233.021974) (xy 444.069451 -232.983265) (xy 444.114809 -232.950814) (xy 444.164409 -232.925313)
			(xy 444.217193 -232.907306) (xy 444.272036 -232.897176) (xy 444.32777 -232.895139) (xy 444.383207 -232.901239)
			(xy 444.437164 -232.915345) (xy 444.488493 -232.937157) (xy 444.536099 -232.966211) (xy 444.578967 -233.001886)
			(xy 444.616184 -233.043423) (xy 444.646957 -233.089936) (xy 444.670629 -233.140433) (xy 444.686697 -233.19384)
			(xy 444.694817 -233.249016) (xy 444.695326 -233.276902) (xy 444.694817 -233.304788) (xy 444.686697 -233.359964)
			(xy 444.670629 -233.413371) (xy 444.646957 -233.463868) (xy 444.616184 -233.510381) (xy 444.578967 -233.551918)
			(xy 444.536099 -233.587593) (xy 444.488493 -233.616647) (xy 444.437164 -233.638459) (xy 444.383207 -233.652565)
			(xy 444.32777 -233.658665) (xy 444.272036 -233.656628) (xy 444.217193 -233.646498) (xy 444.164409 -233.628491)
			(xy 444.114809 -233.60299) (xy 444.069451 -233.570539) (xy 444.029302 -233.53183) (xy 443.995216 -233.487687)
			(xy 443.96792 -233.439052) (xy 443.947997 -233.386961) (xy 443.935871 -233.332524) (xy 443.9318 -233.276902)
			(xy 442.775866 -233.276902) (xy 442.774011 -233.283069) (xy 442.750339 -233.333566) (xy 442.719566 -233.380079)
			(xy 442.682349 -233.421616) (xy 442.639481 -233.457291) (xy 442.591875 -233.486345) (xy 442.540546 -233.508157)
			(xy 442.486589 -233.522263) (xy 442.431152 -233.528363) (xy 442.375418 -233.526326) (xy 442.320575 -233.516196)
			(xy 442.267791 -233.498189) (xy 442.218191 -233.472688) (xy 442.172833 -233.440237) (xy 442.132684 -233.401528)
			(xy 442.098598 -233.357385) (xy 442.071302 -233.30875) (xy 442.051379 -233.256659) (xy 442.039253 -233.202222)
			(xy 442.035182 -233.1466) (xy 428.23709 -233.1466) (xy 429.746389 -234.655869) (xy 448.021157 -234.655869)
			(xy 448.021157 -234.595931) (xy 448.028981 -234.536505) (xy 448.044494 -234.478608) (xy 448.067432 -234.423232)
			(xy 448.097401 -234.371324) (xy 448.13389 -234.323771) (xy 448.176273 -234.281388) (xy 448.223825 -234.2449)
			(xy 448.275734 -234.214931) (xy 448.33111 -234.191993) (xy 448.389007 -234.17648) (xy 448.448433 -234.168657)
			(xy 448.478402 -234.168188) (xy 449.342002 -234.168188) (xy 449.371969 -234.168686) (xy 449.431391 -234.176509)
			(xy 449.489283 -234.192022) (xy 449.544656 -234.214958) (xy 449.596561 -234.244925) (xy 449.64411 -234.281411)
			(xy 449.68649 -234.323792) (xy 449.722976 -234.371341) (xy 449.752943 -234.423246) (xy 449.775879 -234.478618)
			(xy 449.791391 -234.536511) (xy 449.799214 -234.595933) (xy 449.799214 -234.655867) (xy 449.791391 -234.715289)
			(xy 449.775879 -234.773182) (xy 449.752943 -234.828554) (xy 449.749404 -234.834684) (xy 450.697598 -234.834684)
			(xy 450.701669 -234.779062) (xy 450.713795 -234.724625) (xy 450.733718 -234.672534) (xy 450.761014 -234.623899)
			(xy 450.7951 -234.579756) (xy 450.835249 -234.541047) (xy 450.880607 -234.508596) (xy 450.930207 -234.483095)
			(xy 450.982991 -234.465088) (xy 451.037834 -234.454958) (xy 451.093568 -234.452921) (xy 451.149005 -234.459021)
			(xy 451.202962 -234.473127) (xy 451.254291 -234.494939) (xy 451.301897 -234.523993) (xy 451.344765 -234.559668)
			(xy 451.381982 -234.601205) (xy 451.412755 -234.647718) (xy 451.436427 -234.698215) (xy 451.452495 -234.751622)
			(xy 451.460615 -234.806798) (xy 451.461124 -234.834684) (xy 451.460615 -234.86257) (xy 451.452495 -234.917746)
			(xy 451.436427 -234.971153) (xy 451.412755 -235.02165) (xy 451.381982 -235.068163) (xy 451.344765 -235.1097)
			(xy 451.301897 -235.145375) (xy 451.254291 -235.174429) (xy 451.202962 -235.196241) (xy 451.149005 -235.210347)
			(xy 451.093568 -235.216447) (xy 451.037834 -235.21441) (xy 450.982991 -235.20428) (xy 450.930207 -235.186273)
			(xy 450.880607 -235.160772) (xy 450.835249 -235.128321) (xy 450.7951 -235.089612) (xy 450.761014 -235.045469)
			(xy 450.733718 -234.996834) (xy 450.713795 -234.944743) (xy 450.701669 -234.890306) (xy 450.697598 -234.834684)
			(xy 449.749404 -234.834684) (xy 449.722976 -234.880459) (xy 449.68649 -234.928008) (xy 449.64411 -234.970389)
			(xy 449.596561 -235.006875) (xy 449.544656 -235.036842) (xy 449.489283 -235.059778) (xy 449.431391 -235.075291)
			(xy 449.371969 -235.083114) (xy 449.342002 -235.083604) (xy 448.478402 -235.083604) (xy 448.448433 -235.083143)
			(xy 448.389007 -235.07532) (xy 448.33111 -235.059807) (xy 448.275734 -235.036869) (xy 448.223825 -235.0069)
			(xy 448.176273 -234.970412) (xy 448.13389 -234.928029) (xy 448.097401 -234.880476) (xy 448.067432 -234.828568)
			(xy 448.044494 -234.773192) (xy 448.028981 -234.715295) (xy 448.021157 -234.655869) (xy 429.746389 -234.655869)
			(xy 430.881028 -235.790486) (xy 430.888427 -235.79733) (xy 430.907026 -235.805056) (xy 430.917096 -235.805472)
			(xy 443.80785 -235.805472) (xy 443.837922 -235.806052) (xy 443.897318 -235.815502) (xy 443.954504 -235.834131)
			(xy 444.008071 -235.86148) (xy 444.056697 -235.896874) (xy 444.07836 -235.91774) (xy 444.39078 -236.229906)
			(xy 444.398183 -236.236739) (xy 444.416781 -236.244443) (xy 444.426848 -236.244892) (xy 444.498476 -236.244892)
			(xy 444.50854 -236.244455) (xy 444.527123 -236.23672) (xy 444.534544 -236.229906) (xy 444.556146 -236.209059)
			(xy 444.604686 -236.17374) (xy 444.658158 -236.146456) (xy 444.715242 -236.127881) (xy 444.774531 -236.118474)
			(xy 444.804546 -236.117892) (xy 444.8048 -236.117892) (xy 444.832051 -236.118378) (xy 444.885999 -236.126134)
			(xy 444.938294 -236.141489) (xy 444.987871 -236.164131) (xy 445.033721 -236.193597) (xy 445.074912 -236.229288)
			(xy 445.110603 -236.270479) (xy 445.140069 -236.316329) (xy 445.162711 -236.365906) (xy 445.169316 -236.388402)
			(xy 450.160898 -236.388402) (xy 450.161419 -236.359485) (xy 450.170147 -236.302314) (xy 450.187405 -236.247115)
			(xy 450.212796 -236.195154) (xy 450.245739 -236.14762) (xy 450.285479 -236.105603) (xy 450.307964 -236.087412)
			(xy 450.316766 -236.079801) (xy 450.32695 -236.058903) (xy 450.327522 -236.04728) (xy 450.327522 -235.967524)
			(xy 450.326947 -235.955897) (xy 450.316783 -235.934987) (xy 450.307964 -235.927392) (xy 450.285469 -235.909215)
			(xy 450.245736 -235.867191) (xy 450.2128 -235.819653) (xy 450.187414 -235.767689) (xy 450.170159 -235.71249)
			(xy 450.161432 -235.655319) (xy 450.160898 -235.626402) (xy 450.161384 -235.599151) (xy 450.16914 -235.545203)
			(xy 450.184495 -235.492908) (xy 450.207137 -235.443331) (xy 450.236603 -235.397481) (xy 450.272294 -235.35629)
			(xy 450.313485 -235.320599) (xy 450.359335 -235.291133) (xy 450.408912 -235.268491) (xy 450.461207 -235.253136)
			(xy 450.515155 -235.24538) (xy 450.569657 -235.24538) (xy 450.623605 -235.253136) (xy 450.6759 -235.268491)
			(xy 450.725477 -235.291133) (xy 450.771327 -235.320599) (xy 450.812518 -235.35629) (xy 450.848209 -235.397481)
			(xy 450.877675 -235.443331) (xy 450.900317 -235.492908) (xy 450.915672 -235.545203) (xy 450.923428 -235.599151)
			(xy 450.923914 -235.626402) (xy 450.92343 -235.655321) (xy 450.914698 -235.712495) (xy 450.897436 -235.767696)
			(xy 450.872038 -235.819658) (xy 450.839087 -235.867191) (xy 450.799338 -235.909204) (xy 450.776848 -235.927392)
			(xy 450.768046 -235.935003) (xy 450.757861 -235.955901) (xy 450.75729 -235.967524) (xy 450.75729 -236.04728)
			(xy 450.757859 -236.058908) (xy 450.768027 -236.079818) (xy 450.776848 -236.087412) (xy 450.799347 -236.105584)
			(xy 450.839079 -236.147609) (xy 450.872015 -236.195149) (xy 450.8974 -236.247113) (xy 450.914654 -236.302313)
			(xy 450.92338 -236.359485) (xy 450.923914 -236.388402) (xy 450.923428 -236.415653) (xy 450.915672 -236.469601)
			(xy 450.900317 -236.521896) (xy 450.877675 -236.571473) (xy 450.848209 -236.617323) (xy 450.812518 -236.658514)
			(xy 450.771327 -236.694205) (xy 450.725477 -236.723671) (xy 450.6759 -236.746313) (xy 450.623605 -236.761668)
			(xy 450.569657 -236.769424) (xy 450.515155 -236.769424) (xy 450.461207 -236.761668) (xy 450.408912 -236.746313)
			(xy 450.359335 -236.723671) (xy 450.313485 -236.694205) (xy 450.272294 -236.658514) (xy 450.236603 -236.617323)
			(xy 450.207137 -236.571473) (xy 450.184495 -236.521896) (xy 450.16914 -236.469601) (xy 450.161384 -236.415653)
			(xy 450.160898 -236.388402) (xy 445.169316 -236.388402) (xy 445.178066 -236.418201) (xy 445.185822 -236.472149)
			(xy 445.186308 -236.4994) (xy 445.186308 -236.499654) (xy 445.18575 -236.529671) (xy 445.17635 -236.588965)
			(xy 445.157775 -236.646053) (xy 445.130483 -236.699525) (xy 445.095149 -236.74806) (xy 445.074294 -236.769656)
			(xy 445.067457 -236.777058) (xy 445.059744 -236.795656) (xy 445.059308 -236.805724) (xy 445.059308 -236.877606)
			(xy 445.059733 -236.887676) (xy 445.067449 -236.906278) (xy 445.074294 -236.913674) (xy 445.189356 -237.028736)
			(xy 445.189864 -237.029244) (xy 445.195706 -237.034832) (xy 445.203055 -237.041321) (xy 445.221218 -237.048652)
			(xy 445.231012 -237.049056) (xy 450.906642 -237.049056) (xy 450.916518 -237.048593) (xy 450.934816 -237.04115)
			(xy 450.942202 -237.034578) (xy 450.942456 -237.034324) (xy 451.69709 -236.27969) (xy 451.703936 -236.272291)
			(xy 451.711668 -236.253693) (xy 451.712076 -236.243622) (xy 451.712076 -234.442) (xy 451.712665 -234.41194)
			(xy 451.722066 -234.352558) (xy 451.740636 -234.295377) (xy 451.767918 -234.241803) (xy 451.803242 -234.193153)
			(xy 451.82409 -234.17149) (xy 452.53529 -233.46029) (xy 452.556941 -233.439423) (xy 452.605583 -233.404076)
			(xy 452.659158 -233.376777) (xy 452.716345 -233.358201) (xy 452.775735 -233.348805) (xy 452.8058 -233.348276)
			(xy 453.77862 -233.348276) (xy 453.80868 -233.348867) (xy 453.86806 -233.35827) (xy 453.925239 -233.376842)
			(xy 453.978811 -233.404126) (xy 454.027458 -233.439451) (xy 454.04913 -233.46029) (xy 456.299062 -235.710222)
			(xy 456.319924 -235.731875) (xy 456.355263 -235.780519) (xy 456.382553 -235.834095) (xy 456.401122 -235.891281)
			(xy 456.410512 -235.950669) (xy 456.411076 -235.980732) (xy 456.411076 -235.986574) (xy 456.411491 -235.9966)
			(xy 456.419155 -236.01513) (xy 456.433328 -236.029317) (xy 456.45185 -236.036999) (xy 456.461876 -236.037374)
			(xy 456.46594 -236.037374) (xy 456.470004 -236.036612) (xy 456.484952 -236.034362) (xy 456.515086 -236.031944)
			(xy 456.530202 -236.031786) (xy 456.53071 -236.031786) (xy 456.557961 -236.032272) (xy 456.611909 -236.04003)
			(xy 456.664203 -236.055387) (xy 456.71378 -236.078029) (xy 456.75963 -236.107496) (xy 456.800819 -236.143188)
			(xy 456.83651 -236.184378) (xy 456.865976 -236.230229) (xy 456.888617 -236.279806) (xy 456.903972 -236.332101)
			(xy 456.911728 -236.386049) (xy 456.911728 -236.440551) (xy 456.903972 -236.494499) (xy 456.888617 -236.546794)
			(xy 456.865976 -236.596371) (xy 456.83651 -236.642222) (xy 456.800819 -236.683412) (xy 456.75963 -236.719104)
			(xy 456.71378 -236.748571) (xy 456.664203 -236.771213) (xy 456.611909 -236.78657) (xy 456.557961 -236.794328)
			(xy 456.53071 -236.794802) (xy 456.530456 -236.794802) (xy 456.498667 -236.794149) (xy 456.435978 -236.783556)
			(xy 456.405742 -236.77372) (xy 456.401678 -236.77245) (xy 456.392534 -236.770926) (xy 456.384493 -236.769803)
			(xy 456.368436 -236.772149) (xy 456.361038 -236.775498) (xy 456.347322 -236.782102) (xy 456.342527 -236.784719)
			(xy 456.334075 -236.791638) (xy 456.330558 -236.795818) (xy 456.330304 -236.796072) (xy 456.33005 -236.796326)
			(xy 456.328272 -236.798612) (xy 456.321395 -236.807234) (xy 456.306781 -236.823755) (xy 456.299062 -236.831632)
			(xy 456.049126 -237.081568) (xy 456.027454 -237.10242) (xy 455.978818 -237.13779) (xy 455.925252 -237.165124)
			(xy 455.868072 -237.183752) (xy 455.808684 -237.193214) (xy 455.778616 -237.193836) (xy 455.006964 -237.193836)
			(xy 454.976892 -237.193257) (xy 454.917494 -237.183809) (xy 454.860306 -237.165182) (xy 454.806738 -237.137835)
			(xy 454.758109 -237.102442) (xy 454.736454 -237.081568) (xy 454.271888 -236.617002) (xy 454.251035 -236.595331)
			(xy 454.215663 -236.546696) (xy 454.188328 -236.49313) (xy 454.169701 -236.435949) (xy 454.16024 -236.37656)
			(xy 454.15962 -236.346492) (xy 454.160109 -236.318484) (xy 454.168276 -236.263068) (xy 454.184434 -236.209434)
			(xy 454.208239 -236.158729) (xy 454.239181 -236.112035) (xy 454.276599 -236.070351) (xy 454.319695 -236.034568)
			(xy 454.367546 -236.005449) (xy 454.419132 -235.983616) (xy 454.446132 -235.97616) (xy 454.45934 -235.972858)
			(xy 454.478644 -235.953554) (xy 454.505568 -235.855256) (xy 454.507919 -235.844474) (xy 454.504247 -235.822738)
			(xy 454.498456 -235.813346) (xy 454.495662 -235.809282) (xy 453.37349 -234.68711) (xy 453.366091 -234.680264)
			(xy 453.347493 -234.672532) (xy 453.337422 -234.672124) (xy 453.214232 -234.672124) (xy 453.204168 -234.67256)
			(xy 453.185584 -234.680295) (xy 453.178164 -234.68711) (xy 453.00011 -234.865164) (xy 452.993273 -234.872566)
			(xy 452.98556 -234.891164) (xy 452.985124 -234.901232) (xy 452.985124 -236.601) (xy 452.984535 -236.63106)
			(xy 452.975134 -236.690442) (xy 452.956564 -236.747623) (xy 452.929282 -236.801197) (xy 452.893958 -236.849847)
			(xy 452.87311 -236.87151) (xy 451.842124 -237.902496) (xy 451.835443 -237.909908) (xy 451.827851 -237.92834)
			(xy 451.827853 -237.948274) (xy 451.835451 -237.966704) (xy 451.842124 -237.974124) (xy 452.05777 -238.18977)
			(xy 452.065171 -238.196609) (xy 452.083769 -238.204322) (xy 452.093838 -238.204756)
		)
		(stroke
			(width 0)
			(type solid)
		)
		(fill yes)
		(layer "In13.Cu")
		(net "GND")
	)
	(gr_poly
		(pts
			(xy 256.581402 -339.92566) (xy 256.591471 -339.925235) (xy 256.610071 -339.917516) (xy 256.61747 -339.910674)
			(xy 257.21437 -339.313774) (xy 257.221216 -339.306376) (xy 257.228945 -339.287777) (xy 257.229356 -339.277706)
			(xy 257.229356 -322.108068) (xy 257.227832 -322.101464) (xy 257.200741 -321.994965) (xy 257.155191 -321.77996)
			(xy 257.119584 -321.563086) (xy 257.106166 -321.454018) (xy 257.09587 -321.362051) (xy 257.081531 -321.177526)
			(xy 257.074355 -320.992584) (xy 257.073908 -320.900044) (xy 257.07431 -320.816088) (xy 257.080281 -320.648282)
			(xy 257.085846 -320.56451) (xy 257.094211 -320.454986) (xy 257.119751 -320.236793) (xy 257.155298 -320.020006)
			(xy 257.200777 -319.805083) (xy 257.227832 -319.698624) (xy 257.229356 -319.692274) (xy 257.229356 -317.57366)
			(xy 257.229788 -317.563594) (xy 257.237519 -317.545006) (xy 257.244342 -317.537592) (xy 261.087108 -313.694826)
			(xy 261.093942 -313.687423) (xy 261.101648 -313.668825) (xy 261.102094 -313.658758) (xy 261.102094 -311.291224)
			(xy 261.101419 -311.279157) (xy 261.090405 -311.257684) (xy 261.081012 -311.250076) (xy 261.004304 -311.19445)
			(xy 260.980682 -311.190894) (xy 260.968744 -311.194704) (xy 260.939835 -311.203603) (xy 260.880114 -311.213181)
			(xy 260.849872 -311.213754) (xy 260.822619 -311.213266) (xy 260.768668 -311.205506) (xy 260.71637 -311.190146)
			(xy 260.66679 -311.167501) (xy 260.620938 -311.13803) (xy 260.579746 -311.102334) (xy 260.544053 -311.06114)
			(xy 260.514586 -311.015285) (xy 260.491944 -310.965704) (xy 260.476589 -310.913405) (xy 260.468832 -310.859453)
			(xy 260.468832 -310.804947) (xy 260.476589 -310.750995) (xy 260.491944 -310.698696) (xy 260.514586 -310.649115)
			(xy 260.544053 -310.60326) (xy 260.579746 -310.562066) (xy 260.620938 -310.52637) (xy 260.66679 -310.496899)
			(xy 260.71637 -310.474254) (xy 260.768668 -310.458894) (xy 260.822619 -310.451134) (xy 260.849872 -310.450738)
			(xy 260.87911 -310.451268) (xy 260.936901 -310.460194) (xy 260.964934 -310.468518) (xy 260.968744 -310.469788)
			(xy 260.977634 -310.471058) (xy 260.98761 -310.472125) (xy 261.007093 -310.46742) (xy 261.01548 -310.461914)
			(xy 261.081012 -310.414416) (xy 261.090397 -310.406804) (xy 261.101405 -310.385331) (xy 261.102094 -310.373268)
			(xy 261.102094 -310.239664) (xy 261.10057 -310.233568) (xy 261.093547 -310.20416) (xy 261.086026 -310.144166)
			(xy 261.085584 -310.113934) (xy 261.085584 -308.809136) (xy 261.085069 -308.798863) (xy 261.076958 -308.779979)
			(xy 261.069836 -308.77256) (xy 261.063232 -308.76621) (xy 260.973062 -308.725824) (xy 260.962513 -308.721803)
			(xy 260.939971 -308.72232) (xy 260.929628 -308.72684) (xy 260.916166 -308.733444) (xy 260.911086 -308.738016)
			(xy 260.890126 -308.75566) (xy 260.844104 -308.785388) (xy 260.794307 -308.808233) (xy 260.741755 -308.823725)
			(xy 260.687528 -308.831546) (xy 260.660134 -308.831996) (xy 260.63288 -308.831535) (xy 260.578928 -308.823782)
			(xy 260.526627 -308.80843) (xy 260.477044 -308.78579) (xy 260.431188 -308.756324) (xy 260.389993 -308.720631)
			(xy 260.354297 -308.679439) (xy 260.324827 -308.633585) (xy 260.302182 -308.584005) (xy 260.286825 -308.531706)
			(xy 260.279067 -308.477754) (xy 260.279067 -308.423246) (xy 260.286825 -308.369294) (xy 260.302182 -308.316995)
			(xy 260.324827 -308.267415) (xy 260.354297 -308.221561) (xy 260.389993 -308.180369) (xy 260.431188 -308.144676)
			(xy 260.477044 -308.11521) (xy 260.526627 -308.09257) (xy 260.578928 -308.077218) (xy 260.63288 -308.069465)
			(xy 260.660134 -308.06898) (xy 260.687528 -308.069435) (xy 260.741758 -308.07724) (xy 260.794311 -308.092729)
			(xy 260.844106 -308.115581) (xy 260.890116 -308.145326) (xy 260.911086 -308.16296) (xy 260.916166 -308.167532)
			(xy 260.930136 -308.17439) (xy 260.940388 -308.178778) (xy 260.962658 -308.179168) (xy 260.973062 -308.175152)
			(xy 261.055358 -308.138322) (xy 261.064145 -308.133939) (xy 261.077786 -308.11984) (xy 261.085132 -308.101649)
			(xy 261.085584 -308.09184) (xy 261.085584 -299.560488) (xy 261.085169 -299.551776) (xy 261.079243 -299.535383)
			(xy 261.068203 -299.521894) (xy 261.060946 -299.517054) (xy 260.97484 -299.465238) (xy 260.948424 -299.464476)
			(xy 260.936486 -299.470826) (xy 260.908887 -299.48473) (xy 260.850311 -299.504413) (xy 260.789329 -299.514404)
			(xy 260.758432 -299.515022) (xy 260.757924 -299.515022) (xy 260.73067 -299.514561) (xy 260.676715 -299.506807)
			(xy 260.624414 -299.491453) (xy 260.57483 -299.468812) (xy 260.528972 -299.439345) (xy 260.487776 -299.403651)
			(xy 260.452078 -299.362458) (xy 260.422606 -299.316604) (xy 260.39996 -299.267022) (xy 260.384601 -299.214722)
			(xy 260.376842 -299.160768) (xy 260.376416 -299.133514) (xy 260.376876 -299.106919) (xy 260.384261 -299.054245)
			(xy 260.39889 -299.003107) (xy 260.42048 -298.954496) (xy 260.448612 -298.909355) (xy 260.48274 -298.868558)
			(xy 260.522204 -298.832896) (xy 260.566238 -298.803061) (xy 260.613989 -298.779631) (xy 260.664532 -298.76306)
			(xy 260.716886 -298.753669) (xy 260.743446 -298.75226) (xy 260.758432 -298.751752) (xy 260.788375 -298.752375)
			(xy 260.847517 -298.761795) (xy 260.904468 -298.78032) (xy 260.931406 -298.793408) (xy 260.93674 -298.796202)
			(xy 260.94944 -298.799504) (xy 260.959316 -298.801438) (xy 260.979197 -298.798448) (xy 260.988048 -298.793662)
			(xy 261.060946 -298.749974) (xy 261.068259 -298.745192) (xy 261.079353 -298.731709) (xy 261.085236 -298.71527)
			(xy 261.085584 -298.70654) (xy 261.085584 -296.360088) (xy 261.085169 -296.351376) (xy 261.079243 -296.334983)
			(xy 261.068203 -296.321494) (xy 261.060946 -296.316654) (xy 260.97484 -296.264838) (xy 260.948424 -296.264076)
			(xy 260.936486 -296.270426) (xy 260.908887 -296.28433) (xy 260.850311 -296.304013) (xy 260.789329 -296.314004)
			(xy 260.758432 -296.314622) (xy 260.757924 -296.314622) (xy 260.73067 -296.314161) (xy 260.676715 -296.306407)
			(xy 260.624414 -296.291053) (xy 260.57483 -296.268412) (xy 260.528972 -296.238945) (xy 260.487776 -296.203251)
			(xy 260.452078 -296.162058) (xy 260.422606 -296.116204) (xy 260.39996 -296.066622) (xy 260.384601 -296.014322)
			(xy 260.376842 -295.960368) (xy 260.376416 -295.933114) (xy 260.376876 -295.906519) (xy 260.384261 -295.853845)
			(xy 260.39889 -295.802707) (xy 260.42048 -295.754096) (xy 260.448612 -295.708955) (xy 260.48274 -295.668158)
			(xy 260.522204 -295.632496) (xy 260.566238 -295.602661) (xy 260.613989 -295.579231) (xy 260.664532 -295.56266)
			(xy 260.716886 -295.553269) (xy 260.743446 -295.55186) (xy 260.758432 -295.551352) (xy 260.788375 -295.551975)
			(xy 260.847517 -295.561395) (xy 260.904468 -295.57992) (xy 260.931406 -295.593008) (xy 260.93674 -295.595802)
			(xy 260.94944 -295.599104) (xy 260.959316 -295.601038) (xy 260.979197 -295.598048) (xy 260.988048 -295.593262)
			(xy 261.060946 -295.549574) (xy 261.068259 -295.544792) (xy 261.079353 -295.531309) (xy 261.085236 -295.51487)
			(xy 261.085584 -295.50614) (xy 261.085584 -293.159688) (xy 261.085169 -293.150976) (xy 261.079243 -293.134583)
			(xy 261.068203 -293.121094) (xy 261.060946 -293.116254) (xy 260.97484 -293.064438) (xy 260.948424 -293.063676)
			(xy 260.936486 -293.070026) (xy 260.908887 -293.08393) (xy 260.850311 -293.103613) (xy 260.789329 -293.113604)
			(xy 260.758432 -293.114222) (xy 260.757924 -293.114222) (xy 260.73067 -293.113761) (xy 260.676715 -293.106007)
			(xy 260.624414 -293.090653) (xy 260.57483 -293.068012) (xy 260.528972 -293.038545) (xy 260.487776 -293.002851)
			(xy 260.452078 -292.961658) (xy 260.422606 -292.915804) (xy 260.39996 -292.866222) (xy 260.384601 -292.813922)
			(xy 260.376842 -292.759968) (xy 260.376416 -292.732714) (xy 260.376876 -292.706119) (xy 260.384261 -292.653445)
			(xy 260.39889 -292.602307) (xy 260.42048 -292.553696) (xy 260.448612 -292.508555) (xy 260.48274 -292.467758)
			(xy 260.522204 -292.432096) (xy 260.566238 -292.402261) (xy 260.613989 -292.378831) (xy 260.664532 -292.36226)
			(xy 260.716886 -292.352869) (xy 260.743446 -292.35146) (xy 260.758432 -292.350952) (xy 260.788375 -292.351575)
			(xy 260.847517 -292.360995) (xy 260.904468 -292.37952) (xy 260.931406 -292.392608) (xy 260.93674 -292.395402)
			(xy 260.94944 -292.398704) (xy 260.959316 -292.400638) (xy 260.979197 -292.397648) (xy 260.988048 -292.392862)
			(xy 261.060946 -292.349174) (xy 261.068259 -292.344392) (xy 261.079353 -292.330909) (xy 261.085236 -292.31447)
			(xy 261.085584 -292.30574) (xy 261.085584 -289.959288) (xy 261.085169 -289.950576) (xy 261.079243 -289.934183)
			(xy 261.068203 -289.920694) (xy 261.060946 -289.915854) (xy 260.97484 -289.864038) (xy 260.948424 -289.863276)
			(xy 260.936486 -289.869626) (xy 260.908887 -289.88353) (xy 260.850311 -289.903213) (xy 260.789329 -289.913204)
			(xy 260.758432 -289.913822) (xy 260.757924 -289.913822) (xy 260.73067 -289.913361) (xy 260.676715 -289.905607)
			(xy 260.624414 -289.890253) (xy 260.57483 -289.867612) (xy 260.528972 -289.838145) (xy 260.487776 -289.802451)
			(xy 260.452078 -289.761258) (xy 260.422606 -289.715404) (xy 260.39996 -289.665822) (xy 260.384601 -289.613522)
			(xy 260.376842 -289.559568) (xy 260.376416 -289.532314) (xy 260.376876 -289.505719) (xy 260.384261 -289.453045)
			(xy 260.39889 -289.401907) (xy 260.42048 -289.353296) (xy 260.448612 -289.308155) (xy 260.48274 -289.267358)
			(xy 260.522204 -289.231696) (xy 260.566238 -289.201861) (xy 260.613989 -289.178431) (xy 260.664532 -289.16186)
			(xy 260.716886 -289.152469) (xy 260.743446 -289.15106) (xy 260.758432 -289.150552) (xy 260.788375 -289.151175)
			(xy 260.847517 -289.160595) (xy 260.904468 -289.17912) (xy 260.931406 -289.192208) (xy 260.93674 -289.195002)
			(xy 260.94944 -289.198304) (xy 260.959316 -289.200238) (xy 260.979197 -289.197248) (xy 260.988048 -289.192462)
			(xy 261.060946 -289.148774) (xy 261.068259 -289.143992) (xy 261.079353 -289.130509) (xy 261.085236 -289.11407)
			(xy 261.085584 -289.10534) (xy 261.085584 -286.758888) (xy 261.085169 -286.750176) (xy 261.079243 -286.733783)
			(xy 261.068203 -286.720294) (xy 261.060946 -286.715454) (xy 260.97484 -286.663638) (xy 260.948424 -286.662876)
			(xy 260.936486 -286.669226) (xy 260.908887 -286.68313) (xy 260.850311 -286.702813) (xy 260.789329 -286.712804)
			(xy 260.758432 -286.713422) (xy 260.757924 -286.713422) (xy 260.73067 -286.712961) (xy 260.676715 -286.705207)
			(xy 260.624414 -286.689853) (xy 260.57483 -286.667212) (xy 260.528972 -286.637745) (xy 260.487776 -286.602051)
			(xy 260.452078 -286.560858) (xy 260.422606 -286.515004) (xy 260.39996 -286.465422) (xy 260.384601 -286.413122)
			(xy 260.376842 -286.359168) (xy 260.376416 -286.331914) (xy 260.376876 -286.305319) (xy 260.384261 -286.252645)
			(xy 260.39889 -286.201507) (xy 260.42048 -286.152896) (xy 260.448612 -286.107755) (xy 260.48274 -286.066958)
			(xy 260.522204 -286.031296) (xy 260.566238 -286.001461) (xy 260.613989 -285.978031) (xy 260.664532 -285.96146)
			(xy 260.716886 -285.952069) (xy 260.743446 -285.95066) (xy 260.758432 -285.950152) (xy 260.788375 -285.950775)
			(xy 260.847517 -285.960195) (xy 260.904468 -285.97872) (xy 260.931406 -285.991808) (xy 260.93674 -285.994602)
			(xy 260.94944 -285.997904) (xy 260.959316 -285.999838) (xy 260.979197 -285.996848) (xy 260.988048 -285.992062)
			(xy 261.060946 -285.948374) (xy 261.068259 -285.943592) (xy 261.079353 -285.930109) (xy 261.085236 -285.91367)
			(xy 261.085584 -285.90494) (xy 261.085584 -284.294834) (xy 261.085052 -284.284844) (xy 261.077346 -284.266405)
			(xy 261.070598 -284.25902) (xy 260.21157 -283.399992) (xy 260.204158 -283.393308) (xy 260.185725 -283.385711)
			(xy 260.165787 -283.385711) (xy 260.147354 -283.393308) (xy 260.139942 -283.399992) (xy 260.139688 -283.400246)
			(xy 260.118064 -283.421228) (xy 260.069431 -283.456792) (xy 260.015815 -283.484273) (xy 259.958546 -283.502989)
			(xy 259.899048 -283.512475) (xy 259.868924 -283.513022) (xy 259.84167 -283.512561) (xy 259.787715 -283.504807)
			(xy 259.735414 -283.489453) (xy 259.68583 -283.466812) (xy 259.639972 -283.437345) (xy 259.598776 -283.401651)
			(xy 259.563078 -283.360458) (xy 259.533606 -283.314604) (xy 259.51096 -283.265022) (xy 259.495601 -283.212722)
			(xy 259.487842 -283.158768) (xy 259.487416 -283.131514) (xy 259.487984 -283.10139) (xy 259.497455 -283.04189)
			(xy 259.516162 -282.984619) (xy 259.543642 -282.931002) (xy 259.579209 -282.882372) (xy 259.600192 -282.86075)
			(xy 259.600446 -282.860496) (xy 259.607129 -282.853085) (xy 259.614723 -282.834654) (xy 259.614718 -282.81472)
			(xy 259.607114 -282.796293) (xy 259.600446 -282.788868) (xy 258.854702 -282.043124) (xy 258.85394 -282.042362)
			(xy 258.847997 -282.037012) (xy 258.833623 -282.030025) (xy 258.825746 -282.028646) (xy 258.814824 -282.028392)
			(xy 258.72694 -282.03525) (xy 258.707636 -282.045918) (xy 258.701032 -282.055062) (xy 258.682907 -282.078754)
			(xy 258.64054 -282.120743) (xy 258.592159 -282.155633) (xy 258.538942 -282.182578) (xy 258.482183 -282.200921)
			(xy 258.423262 -282.210216) (xy 258.393438 -282.210764) (xy 258.366185 -282.210303) (xy 258.312232 -282.20255)
			(xy 258.259932 -282.187197) (xy 258.21035 -282.164556) (xy 258.164495 -282.135089) (xy 258.123301 -282.099394)
			(xy 258.087608 -282.0582) (xy 258.058141 -282.012345) (xy 258.035501 -281.962762) (xy 258.020148 -281.910462)
			(xy 258.012396 -281.856509) (xy 258.01193 -281.829256) (xy 258.012501 -281.799431) (xy 258.021775 -281.740506)
			(xy 258.040105 -281.683742) (xy 258.067045 -281.630522) (xy 258.101938 -281.582142) (xy 258.143935 -281.539781)
			(xy 258.167632 -281.521662) (xy 258.176776 -281.515058) (xy 258.187444 -281.495754) (xy 258.194302 -281.40787)
			(xy 258.194048 -281.396948) (xy 258.19262 -281.389088) (xy 258.185635 -281.374729) (xy 258.180332 -281.368754)
			(xy 258.17957 -281.367992) (xy 249.429778 -272.6182) (xy 249.422666 -272.610834) (xy 249.40387 -272.603214)
			(xy 242.913916 -272.603214) (xy 242.893088 -272.613374) (xy 242.885722 -272.622772) (xy 242.8367 -272.685764)
			(xy 242.830057 -272.695093) (xy 242.825151 -272.717442) (xy 242.827302 -272.72869) (xy 242.827302 -272.729452)
			(xy 242.832638 -272.752193) (xy 242.838371 -272.798552) (xy 242.838732 -272.821908) (xy 242.838732 -272.822416)
			(xy 242.838245 -272.849667) (xy 242.830487 -272.903614) (xy 242.815131 -272.955909) (xy 242.792489 -273.005485)
			(xy 242.763023 -273.051335) (xy 242.727331 -273.092526) (xy 242.686142 -273.128218) (xy 242.640292 -273.157685)
			(xy 242.590716 -273.180328) (xy 242.538422 -273.195685) (xy 242.484475 -273.203445) (xy 242.457224 -273.203924)
			(xy 242.428485 -273.203404) (xy 242.371657 -273.194783) (xy 242.316765 -273.177733) (xy 242.265054 -273.15264)
			(xy 242.217693 -273.120071) (xy 242.196366 -273.1008) (xy 242.189254 -273.093942) (xy 242.171474 -273.087084)
			(xy 242.082574 -273.087084) (xy 242.064794 -273.093942) (xy 242.057682 -273.1008) (xy 242.036355 -273.12007)
			(xy 241.988992 -273.152635) (xy 241.937281 -273.177726) (xy 241.88239 -273.194776) (xy 241.825563 -273.203398)
			(xy 241.768085 -273.203398) (xy 241.711258 -273.194776) (xy 241.656367 -273.177726) (xy 241.604656 -273.152635)
			(xy 241.557293 -273.12007) (xy 241.535966 -273.1008) (xy 241.528854 -273.093942) (xy 241.511074 -273.087084)
			(xy 241.422174 -273.087084) (xy 241.404394 -273.093942) (xy 241.397282 -273.1008) (xy 241.375955 -273.12007)
			(xy 241.328592 -273.152635) (xy 241.276881 -273.177726) (xy 241.22199 -273.194776) (xy 241.165163 -273.203398)
			(xy 241.107685 -273.203398) (xy 241.050858 -273.194776) (xy 240.995967 -273.177726) (xy 240.944256 -273.152635)
			(xy 240.896893 -273.12007) (xy 240.875566 -273.1008) (xy 240.868454 -273.093942) (xy 240.850674 -273.087084)
			(xy 240.761774 -273.087084) (xy 240.743994 -273.093942) (xy 240.736882 -273.1008) (xy 240.715555 -273.12007)
			(xy 240.668192 -273.152635) (xy 240.616481 -273.177726) (xy 240.56159 -273.194776) (xy 240.504763 -273.203398)
			(xy 240.447285 -273.203398) (xy 240.390458 -273.194776) (xy 240.335567 -273.177726) (xy 240.283856 -273.152635)
			(xy 240.236493 -273.12007) (xy 240.215166 -273.1008) (xy 240.208054 -273.093942) (xy 240.190274 -273.087084)
			(xy 240.101374 -273.087084) (xy 240.083594 -273.093942) (xy 240.076482 -273.1008) (xy 240.055155 -273.120071)
			(xy 240.007793 -273.152637) (xy 239.956081 -273.177731) (xy 239.901191 -273.194783) (xy 239.844363 -273.203408)
			(xy 239.815624 -273.203924) (xy 239.78837 -273.203463) (xy 239.734415 -273.195709) (xy 239.682113 -273.180355)
			(xy 239.632529 -273.157714) (xy 239.586672 -273.128247) (xy 239.545475 -273.092553) (xy 239.509777 -273.05136)
			(xy 239.480305 -273.005506) (xy 239.457659 -272.955924) (xy 239.4423 -272.903624) (xy 239.43454 -272.84967)
			(xy 239.434116 -272.822416) (xy 239.434116 -272.821908) (xy 239.434485 -272.798553) (xy 239.440218 -272.752195)
			(xy 239.445546 -272.729452) (xy 239.445546 -272.72869) (xy 239.447562 -272.717439) (xy 239.442681 -272.695143)
			(xy 239.436148 -272.685764) (xy 239.387126 -272.622772) (xy 239.379534 -272.613945) (xy 239.358624 -272.603766)
			(xy 239.346994 -272.603214) (xy 239.245648 -272.603214) (xy 239.233797 -272.603823) (xy 239.212592 -272.614409)
			(xy 239.205008 -272.623534) (xy 239.149128 -272.698718) (xy 239.14481 -272.721832) (xy 239.148366 -272.73377)
			(xy 239.155731 -272.760277) (xy 239.163639 -272.814721) (xy 239.164114 -272.842228) (xy 239.163626 -272.869478)
			(xy 239.155867 -272.923423) (xy 239.140509 -272.975715) (xy 239.117866 -273.025289) (xy 239.0884 -273.071136)
			(xy 239.052708 -273.112324) (xy 239.011519 -273.148013) (xy 238.96567 -273.177477) (xy 238.916094 -273.200117)
			(xy 238.863802 -273.215471) (xy 238.809856 -273.223228) (xy 238.782606 -273.223736) (xy 238.753867 -273.223215)
			(xy 238.69704 -273.214592) (xy 238.64215 -273.197541) (xy 238.59044 -273.172446) (xy 238.54308 -273.139877)
			(xy 238.521748 -273.120612) (xy 238.514636 -273.114008) (xy 238.49711 -273.106896) (xy 238.407702 -273.106896)
			(xy 238.390176 -273.114008) (xy 238.383064 -273.120612) (xy 238.361737 -273.139882) (xy 238.314374 -273.172447)
			(xy 238.262663 -273.197538) (xy 238.207772 -273.214588) (xy 238.150945 -273.22321) (xy 238.093467 -273.22321)
			(xy 238.03664 -273.214588) (xy 237.981749 -273.197538) (xy 237.930038 -273.172447) (xy 237.882675 -273.139882)
			(xy 237.861348 -273.120612) (xy 237.854236 -273.114008) (xy 237.83671 -273.106896) (xy 237.747302 -273.106896)
			(xy 237.729776 -273.114008) (xy 237.722664 -273.120612) (xy 237.701337 -273.139882) (xy 237.653974 -273.172447)
			(xy 237.602263 -273.197538) (xy 237.547372 -273.214588) (xy 237.490545 -273.22321) (xy 237.433067 -273.22321)
			(xy 237.37624 -273.214588) (xy 237.321349 -273.197538) (xy 237.269638 -273.172447) (xy 237.222275 -273.139882)
			(xy 237.200948 -273.120612) (xy 237.193836 -273.114008) (xy 237.17631 -273.106896) (xy 237.086902 -273.106896)
			(xy 237.069376 -273.114008) (xy 237.062264 -273.120612) (xy 237.040937 -273.139882) (xy 236.993573 -273.172445)
			(xy 236.941862 -273.197534) (xy 236.886971 -273.214584) (xy 236.830145 -273.223206) (xy 236.801406 -273.223736)
			(xy 236.774154 -273.223251) (xy 236.720204 -273.215495) (xy 236.667907 -273.200141) (xy 236.618327 -273.1775)
			(xy 236.572474 -273.148035) (xy 236.531281 -273.112343) (xy 236.495586 -273.071153) (xy 236.466116 -273.025303)
			(xy 236.443471 -272.975725) (xy 236.428112 -272.923429) (xy 236.420352 -272.86948) (xy 236.419898 -272.842228)
			(xy 236.420378 -272.814721) (xy 236.428276 -272.760276) (xy 236.435646 -272.73377) (xy 236.439202 -272.721832)
			(xy 236.434884 -272.698718) (xy 236.379004 -272.623534) (xy 236.3714 -272.614433) (xy 236.350208 -272.603849)
			(xy 236.338364 -272.603214) (xy 228.410008 -272.603214) (xy 228.399937 -272.603636) (xy 228.381332 -272.61135)
			(xy 228.37394 -272.6182) (xy 228.195632 -272.796508) (xy 228.188783 -272.803905) (xy 228.181047 -272.822504)
			(xy 228.180646 -272.832576) (xy 228.180646 -273.447256) (xy 228.19614 -273.472148) (xy 228.209602 -273.478498)
			(xy 228.233611 -273.490485) (xy 228.278302 -273.520192) (xy 228.318389 -273.555867) (xy 228.353081 -273.596808)
			(xy 228.381694 -273.642206) (xy 228.403664 -273.691166) (xy 228.418557 -273.742721) (xy 228.426078 -273.795855)
			(xy 228.426079 -273.829526) (xy 228.564946 -273.829526) (xy 228.569017 -273.773904) (xy 228.581143 -273.719467)
			(xy 228.601066 -273.667376) (xy 228.628362 -273.618741) (xy 228.662448 -273.574598) (xy 228.702597 -273.535889)
			(xy 228.747955 -273.503438) (xy 228.797555 -273.477937) (xy 228.850339 -273.45993) (xy 228.905182 -273.4498)
			(xy 228.960916 -273.447763) (xy 229.016353 -273.453863) (xy 229.07031 -273.467969) (xy 229.121639 -273.489781)
			(xy 229.169245 -273.518835) (xy 229.212113 -273.55451) (xy 229.24933 -273.596047) (xy 229.280103 -273.64256)
			(xy 229.303775 -273.693057) (xy 229.319843 -273.746464) (xy 229.327963 -273.80164) (xy 229.328472 -273.829526)
			(xy 229.327963 -273.857412) (xy 229.319843 -273.912588) (xy 229.303775 -273.965995) (xy 229.280103 -274.016492)
			(xy 229.24933 -274.063005) (xy 229.212113 -274.104542) (xy 229.169245 -274.140217) (xy 229.121639 -274.169271)
			(xy 229.07031 -274.191083) (xy 229.016353 -274.205189) (xy 228.960916 -274.211289) (xy 228.905182 -274.209252)
			(xy 228.850339 -274.199122) (xy 228.797555 -274.181115) (xy 228.747955 -274.155614) (xy 228.702597 -274.123163)
			(xy 228.662448 -274.084454) (xy 228.628362 -274.040311) (xy 228.601066 -273.991676) (xy 228.581143 -273.939585)
			(xy 228.569017 -273.885148) (xy 228.564946 -273.829526) (xy 228.426079 -273.829526) (xy 228.42608 -273.849518)
			(xy 228.418562 -273.902652) (xy 228.403674 -273.954208) (xy 228.381708 -274.003169) (xy 228.353097 -274.048569)
			(xy 228.318408 -274.089513) (xy 228.278324 -274.125192) (xy 228.233635 -274.154901) (xy 228.209602 -274.166838)
			(xy 228.19614 -274.173188) (xy 228.180646 -274.19808) (xy 228.180646 -274.768056) (xy 228.824788 -274.768056)
			(xy 228.828859 -274.712434) (xy 228.840985 -274.657997) (xy 228.860908 -274.605906) (xy 228.888204 -274.557271)
			(xy 228.92229 -274.513128) (xy 228.962439 -274.474419) (xy 229.007797 -274.441968) (xy 229.057397 -274.416467)
			(xy 229.110181 -274.39846) (xy 229.165024 -274.38833) (xy 229.220758 -274.386293) (xy 229.276195 -274.392393)
			(xy 229.330152 -274.406499) (xy 229.381481 -274.428311) (xy 229.429087 -274.457365) (xy 229.465161 -274.487386)
			(xy 232.472228 -274.487386) (xy 232.476299 -274.431764) (xy 232.488425 -274.377327) (xy 232.508348 -274.325236)
			(xy 232.535644 -274.276601) (xy 232.56973 -274.232458) (xy 232.609879 -274.193749) (xy 232.655237 -274.161298)
			(xy 232.704837 -274.135797) (xy 232.757621 -274.11779) (xy 232.812464 -274.10766) (xy 232.868198 -274.105623)
			(xy 232.923635 -274.111723) (xy 232.977592 -274.125829) (xy 233.028921 -274.147641) (xy 233.076527 -274.176695)
			(xy 233.119395 -274.21237) (xy 233.156612 -274.253907) (xy 233.187385 -274.30042) (xy 233.211057 -274.350917)
			(xy 233.227125 -274.404324) (xy 233.235245 -274.4595) (xy 233.235754 -274.487386) (xy 233.235245 -274.515272)
			(xy 233.227125 -274.570448) (xy 233.211057 -274.623855) (xy 233.206923 -274.632674) (xy 242.945156 -274.632674)
			(xy 242.949227 -274.577052) (xy 242.961353 -274.522615) (xy 242.981276 -274.470524) (xy 243.008572 -274.421889)
			(xy 243.042658 -274.377746) (xy 243.082807 -274.339037) (xy 243.128165 -274.306586) (xy 243.177765 -274.281085)
			(xy 243.230549 -274.263078) (xy 243.285392 -274.252948) (xy 243.341126 -274.250911) (xy 243.396563 -274.257011)
			(xy 243.45052 -274.271117) (xy 243.501849 -274.292929) (xy 243.549455 -274.321983) (xy 243.592323 -274.357658)
			(xy 243.62954 -274.399195) (xy 243.660313 -274.445708) (xy 243.683985 -274.496205) (xy 243.700053 -274.549612)
			(xy 243.708173 -274.604788) (xy 243.708682 -274.632674) (xy 243.708173 -274.66056) (xy 243.700053 -274.715736)
			(xy 243.684312 -274.768056) (xy 245.074946 -274.768056) (xy 245.079017 -274.712434) (xy 245.091143 -274.657997)
			(xy 245.111066 -274.605906) (xy 245.138362 -274.557271) (xy 245.172448 -274.513128) (xy 245.212597 -274.474419)
			(xy 245.257955 -274.441968) (xy 245.307555 -274.416467) (xy 245.360339 -274.39846) (xy 245.415182 -274.38833)
			(xy 245.470916 -274.386293) (xy 245.526353 -274.392393) (xy 245.58031 -274.406499) (xy 245.631639 -274.428311)
			(xy 245.679245 -274.457365) (xy 245.715319 -274.487386) (xy 248.722386 -274.487386) (xy 248.726457 -274.431764)
			(xy 248.738583 -274.377327) (xy 248.758506 -274.325236) (xy 248.785802 -274.276601) (xy 248.819888 -274.232458)
			(xy 248.860037 -274.193749) (xy 248.905395 -274.161298) (xy 248.954995 -274.135797) (xy 249.007779 -274.11779)
			(xy 249.062622 -274.10766) (xy 249.118356 -274.105623) (xy 249.173793 -274.111723) (xy 249.22775 -274.125829)
			(xy 249.279079 -274.147641) (xy 249.326685 -274.176695) (xy 249.369553 -274.21237) (xy 249.40677 -274.253907)
			(xy 249.437543 -274.30042) (xy 249.461215 -274.350917) (xy 249.477283 -274.404324) (xy 249.485403 -274.4595)
			(xy 249.485912 -274.487386) (xy 249.485403 -274.515272) (xy 249.477283 -274.570448) (xy 249.461215 -274.623855)
			(xy 249.437543 -274.674352) (xy 249.40677 -274.720865) (xy 249.369553 -274.762402) (xy 249.326685 -274.798077)
			(xy 249.279079 -274.827131) (xy 249.22775 -274.848943) (xy 249.173793 -274.863049) (xy 249.118356 -274.869149)
			(xy 249.062622 -274.867112) (xy 249.007779 -274.856982) (xy 248.954995 -274.838975) (xy 248.905395 -274.813474)
			(xy 248.860037 -274.781023) (xy 248.819888 -274.742314) (xy 248.785802 -274.698171) (xy 248.758506 -274.649536)
			(xy 248.738583 -274.597445) (xy 248.726457 -274.543008) (xy 248.722386 -274.487386) (xy 245.715319 -274.487386)
			(xy 245.722113 -274.49304) (xy 245.75933 -274.534577) (xy 245.790103 -274.58109) (xy 245.813775 -274.631587)
			(xy 245.829843 -274.684994) (xy 245.837963 -274.74017) (xy 245.838472 -274.768056) (xy 245.837963 -274.795942)
			(xy 245.829843 -274.851118) (xy 245.813775 -274.904525) (xy 245.790103 -274.955022) (xy 245.75933 -275.001535)
			(xy 245.722113 -275.043072) (xy 245.679245 -275.078747) (xy 245.631639 -275.107801) (xy 245.58031 -275.129613)
			(xy 245.526353 -275.143719) (xy 245.470916 -275.149819) (xy 245.415182 -275.147782) (xy 245.360339 -275.137652)
			(xy 245.307555 -275.119645) (xy 245.257955 -275.094144) (xy 245.212597 -275.061693) (xy 245.172448 -275.022984)
			(xy 245.138362 -274.978841) (xy 245.111066 -274.930206) (xy 245.091143 -274.878115) (xy 245.079017 -274.823678)
			(xy 245.074946 -274.768056) (xy 243.684312 -274.768056) (xy 243.683985 -274.769143) (xy 243.660313 -274.81964)
			(xy 243.62954 -274.866153) (xy 243.592323 -274.90769) (xy 243.549455 -274.943365) (xy 243.501849 -274.972419)
			(xy 243.45052 -274.994231) (xy 243.396563 -275.008337) (xy 243.341126 -275.014437) (xy 243.285392 -275.0124)
			(xy 243.230549 -275.00227) (xy 243.177765 -274.984263) (xy 243.128165 -274.958762) (xy 243.082807 -274.926311)
			(xy 243.042658 -274.887602) (xy 243.008572 -274.843459) (xy 242.981276 -274.794824) (xy 242.961353 -274.742733)
			(xy 242.949227 -274.688296) (xy 242.945156 -274.632674) (xy 233.206923 -274.632674) (xy 233.187385 -274.674352)
			(xy 233.156612 -274.720865) (xy 233.119395 -274.762402) (xy 233.076527 -274.798077) (xy 233.028921 -274.827131)
			(xy 232.977592 -274.848943) (xy 232.923635 -274.863049) (xy 232.868198 -274.869149) (xy 232.812464 -274.867112)
			(xy 232.757621 -274.856982) (xy 232.704837 -274.838975) (xy 232.655237 -274.813474) (xy 232.609879 -274.781023)
			(xy 232.56973 -274.742314) (xy 232.535644 -274.698171) (xy 232.508348 -274.649536) (xy 232.488425 -274.597445)
			(xy 232.476299 -274.543008) (xy 232.472228 -274.487386) (xy 229.465161 -274.487386) (xy 229.471955 -274.49304)
			(xy 229.509172 -274.534577) (xy 229.539945 -274.58109) (xy 229.563617 -274.631587) (xy 229.579685 -274.684994)
			(xy 229.587805 -274.74017) (xy 229.588314 -274.768056) (xy 229.587805 -274.795942) (xy 229.579685 -274.851118)
			(xy 229.563617 -274.904525) (xy 229.539945 -274.955022) (xy 229.509172 -275.001535) (xy 229.471955 -275.043072)
			(xy 229.429087 -275.078747) (xy 229.381481 -275.107801) (xy 229.330152 -275.129613) (xy 229.276195 -275.143719)
			(xy 229.220758 -275.149819) (xy 229.165024 -275.147782) (xy 229.110181 -275.137652) (xy 229.057397 -275.119645)
			(xy 229.007797 -275.094144) (xy 228.962439 -275.061693) (xy 228.92229 -275.022984) (xy 228.888204 -274.978841)
			(xy 228.860908 -274.930206) (xy 228.840985 -274.878115) (xy 228.828859 -274.823678) (xy 228.824788 -274.768056)
			(xy 228.180646 -274.768056) (xy 228.180646 -275.204936) (xy 230.320594 -275.204936) (xy 230.324665 -275.149314)
			(xy 230.336791 -275.094877) (xy 230.356714 -275.042786) (xy 230.38401 -274.994151) (xy 230.418096 -274.950008)
			(xy 230.458245 -274.911299) (xy 230.503603 -274.878848) (xy 230.553203 -274.853347) (xy 230.605987 -274.83534)
			(xy 230.66083 -274.82521) (xy 230.716564 -274.823173) (xy 230.772001 -274.829273) (xy 230.825958 -274.843379)
			(xy 230.877287 -274.865191) (xy 230.924893 -274.894245) (xy 230.967761 -274.92992) (xy 231.004978 -274.971457)
			(xy 231.035751 -275.01797) (xy 231.059423 -275.068467) (xy 231.075491 -275.121874) (xy 231.083611 -275.17705)
			(xy 231.08412 -275.204936) (xy 231.083611 -275.232822) (xy 231.075491 -275.287998) (xy 231.059423 -275.341405)
			(xy 231.035751 -275.391902) (xy 231.004978 -275.438415) (xy 230.967761 -275.479952) (xy 230.924893 -275.515627)
			(xy 230.897325 -275.532452) (xy 239.418342 -275.532452) (xy 239.418342 -275.477948) (xy 239.426098 -275.423998)
			(xy 239.441453 -275.3717) (xy 239.464094 -275.322121) (xy 239.49356 -275.276268) (xy 239.529252 -275.235074)
			(xy 239.570442 -275.199379) (xy 239.616293 -275.169909) (xy 239.66587 -275.147264) (xy 239.718166 -275.131905)
			(xy 239.772116 -275.124144) (xy 239.799368 -275.123656) (xy 239.826738 -275.124127) (xy 239.880918 -275.131942)
			(xy 239.933421 -275.147429) (xy 239.983168 -275.17027) (xy 240.029135 -275.199994) (xy 240.050066 -275.217636)
			(xy 240.057178 -275.223732) (xy 240.074196 -275.230082) (xy 240.15954 -275.230082) (xy 240.176558 -275.223732)
			(xy 240.18367 -275.217636) (xy 240.204607 -275.200003) (xy 240.250578 -275.170289) (xy 240.300324 -275.147451)
			(xy 240.352824 -275.131959) (xy 240.406999 -275.12413) (xy 240.434368 -275.123656) (xy 240.46162 -275.124189)
			(xy 240.515569 -275.131942) (xy 240.567866 -275.147293) (xy 240.617445 -275.169932) (xy 240.663298 -275.199396)
			(xy 240.669692 -275.204936) (xy 246.570752 -275.204936) (xy 246.574823 -275.149314) (xy 246.586949 -275.094877)
			(xy 246.606872 -275.042786) (xy 246.634168 -274.994151) (xy 246.668254 -274.950008) (xy 246.708403 -274.911299)
			(xy 246.753761 -274.878848) (xy 246.803361 -274.853347) (xy 246.856145 -274.83534) (xy 246.910988 -274.82521)
			(xy 246.966722 -274.823173) (xy 247.022159 -274.829273) (xy 247.076116 -274.843379) (xy 247.127445 -274.865191)
			(xy 247.175051 -274.894245) (xy 247.217919 -274.92992) (xy 247.255136 -274.971457) (xy 247.285909 -275.01797)
			(xy 247.309581 -275.068467) (xy 247.325649 -275.121874) (xy 247.333769 -275.17705) (xy 247.334278 -275.204936)
			(xy 247.333769 -275.232822) (xy 247.325649 -275.287998) (xy 247.309581 -275.341405) (xy 247.285909 -275.391902)
			(xy 247.255136 -275.438415) (xy 247.217919 -275.479952) (xy 247.175051 -275.515627) (xy 247.127445 -275.544681)
			(xy 247.076116 -275.566493) (xy 247.022159 -275.580599) (xy 246.966722 -275.586699) (xy 246.910988 -275.584662)
			(xy 246.856145 -275.574532) (xy 246.803361 -275.556525) (xy 246.753761 -275.531024) (xy 246.708403 -275.498573)
			(xy 246.668254 -275.459864) (xy 246.634168 -275.415721) (xy 246.606872 -275.367086) (xy 246.586949 -275.314995)
			(xy 246.574823 -275.260558) (xy 246.570752 -275.204936) (xy 240.669692 -275.204936) (xy 240.704491 -275.235087)
			(xy 240.740184 -275.276276) (xy 240.769653 -275.322127) (xy 240.792295 -275.371704) (xy 240.807652 -275.424)
			(xy 240.815409 -275.477948) (xy 240.815409 -275.532452) (xy 240.807652 -275.5864) (xy 240.792295 -275.638696)
			(xy 240.769653 -275.688273) (xy 240.740184 -275.734124) (xy 240.704491 -275.775313) (xy 240.663298 -275.811004)
			(xy 240.617445 -275.840468) (xy 240.567866 -275.863107) (xy 240.515569 -275.878458) (xy 240.46162 -275.886211)
			(xy 240.434368 -275.886672) (xy 240.406997 -275.886232) (xy 240.352816 -275.878409) (xy 240.300313 -275.862914)
			(xy 240.250566 -275.840066) (xy 240.204601 -275.810336) (xy 240.18367 -275.792692) (xy 240.176558 -275.786596)
			(xy 240.15954 -275.780246) (xy 240.074196 -275.780246) (xy 240.057178 -275.786596) (xy 240.050066 -275.792692)
			(xy 240.029119 -275.810312) (xy 239.98315 -275.840027) (xy 239.933407 -275.862867) (xy 239.880909 -275.878362)
			(xy 239.826736 -275.886195) (xy 239.799368 -275.886672) (xy 239.772116 -275.886256) (xy 239.718166 -275.878495)
			(xy 239.66587 -275.863136) (xy 239.616293 -275.840491) (xy 239.570442 -275.811021) (xy 239.529252 -275.775326)
			(xy 239.49356 -275.734132) (xy 239.464094 -275.688279) (xy 239.441453 -275.638699) (xy 239.426098 -275.586402)
			(xy 239.418342 -275.532452) (xy 230.897325 -275.532452) (xy 230.877287 -275.544681) (xy 230.825958 -275.566493)
			(xy 230.772001 -275.580599) (xy 230.716564 -275.586699) (xy 230.66083 -275.584662) (xy 230.605987 -275.574532)
			(xy 230.553203 -275.556525) (xy 230.503603 -275.531024) (xy 230.458245 -275.498573) (xy 230.418096 -275.459864)
			(xy 230.38401 -275.415721) (xy 230.356714 -275.367086) (xy 230.336791 -275.314995) (xy 230.324665 -275.260558)
			(xy 230.320594 -275.204936) (xy 228.180646 -275.204936) (xy 228.180646 -276.03831) (xy 228.18022 -276.048378)
			(xy 228.172497 -276.066975) (xy 228.16566 -276.074378) (xy 227.720652 -276.519386) (xy 230.452928 -276.519386)
			(xy 230.456999 -276.463764) (xy 230.469125 -276.409327) (xy 230.489048 -276.357236) (xy 230.516344 -276.308601)
			(xy 230.55043 -276.264458) (xy 230.590579 -276.225749) (xy 230.635937 -276.193298) (xy 230.685537 -276.167797)
			(xy 230.738321 -276.14979) (xy 230.793164 -276.13966) (xy 230.848898 -276.137623) (xy 230.904335 -276.143723)
			(xy 230.958292 -276.157829) (xy 231.009621 -276.179641) (xy 231.057227 -276.208695) (xy 231.100095 -276.24437)
			(xy 231.137312 -276.285907) (xy 231.168085 -276.33242) (xy 231.191757 -276.382917) (xy 231.207825 -276.436324)
			(xy 231.215945 -276.4915) (xy 231.216454 -276.519386) (xy 232.472228 -276.519386) (xy 232.476299 -276.463764)
			(xy 232.488425 -276.409327) (xy 232.508348 -276.357236) (xy 232.535644 -276.308601) (xy 232.56973 -276.264458)
			(xy 232.609879 -276.225749) (xy 232.655237 -276.193298) (xy 232.704837 -276.167797) (xy 232.757621 -276.14979)
			(xy 232.812464 -276.13966) (xy 232.868198 -276.137623) (xy 232.923635 -276.143723) (xy 232.977592 -276.157829)
			(xy 233.028921 -276.179641) (xy 233.076527 -276.208695) (xy 233.119395 -276.24437) (xy 233.156612 -276.285907)
			(xy 233.187385 -276.33242) (xy 233.211057 -276.382917) (xy 233.227125 -276.436324) (xy 233.235245 -276.4915)
			(xy 233.235754 -276.519386) (xy 233.235245 -276.547272) (xy 233.227125 -276.602448) (xy 233.211057 -276.655855)
			(xy 233.187385 -276.706352) (xy 233.156612 -276.752865) (xy 233.119395 -276.794402) (xy 233.076527 -276.830077)
			(xy 233.028921 -276.859131) (xy 232.977592 -276.880943) (xy 232.923635 -276.895049) (xy 232.868198 -276.901149)
			(xy 232.812464 -276.899112) (xy 232.757621 -276.888982) (xy 232.704837 -276.870975) (xy 232.655237 -276.845474)
			(xy 232.609879 -276.813023) (xy 232.56973 -276.774314) (xy 232.535644 -276.730171) (xy 232.508348 -276.681536)
			(xy 232.488425 -276.629445) (xy 232.476299 -276.575008) (xy 232.472228 -276.519386) (xy 231.216454 -276.519386)
			(xy 231.215945 -276.547272) (xy 231.207825 -276.602448) (xy 231.191757 -276.655855) (xy 231.168085 -276.706352)
			(xy 231.137312 -276.752865) (xy 231.100095 -276.794402) (xy 231.057227 -276.830077) (xy 231.009621 -276.859131)
			(xy 230.958292 -276.880943) (xy 230.904335 -276.895049) (xy 230.848898 -276.901149) (xy 230.793164 -276.899112)
			(xy 230.738321 -276.888982) (xy 230.685537 -276.870975) (xy 230.635937 -276.845474) (xy 230.590579 -276.813023)
			(xy 230.55043 -276.774314) (xy 230.516344 -276.730171) (xy 230.489048 -276.681536) (xy 230.469125 -276.629445)
			(xy 230.456999 -276.575008) (xy 230.452928 -276.519386) (xy 227.720652 -276.519386) (xy 227.026724 -277.213314)
			(xy 227.470206 -277.213314) (xy 227.474277 -277.157692) (xy 227.486403 -277.103255) (xy 227.506326 -277.051164)
			(xy 227.533622 -277.002529) (xy 227.567708 -276.958386) (xy 227.607857 -276.919677) (xy 227.653215 -276.887226)
			(xy 227.702815 -276.861725) (xy 227.755599 -276.843718) (xy 227.810442 -276.833588) (xy 227.866176 -276.831551)
			(xy 227.921613 -276.837651) (xy 227.97557 -276.851757) (xy 228.026899 -276.873569) (xy 228.074505 -276.902623)
			(xy 228.117373 -276.938298) (xy 228.15459 -276.979835) (xy 228.185363 -277.026348) (xy 228.209035 -277.076845)
			(xy 228.225103 -277.130252) (xy 228.233223 -277.185428) (xy 228.233523 -277.201884) (xy 228.659688 -277.201884)
			(xy 228.663759 -277.146262) (xy 228.675885 -277.091825) (xy 228.695808 -277.039734) (xy 228.723104 -276.991099)
			(xy 228.75719 -276.946956) (xy 228.797339 -276.908247) (xy 228.842697 -276.875796) (xy 228.892297 -276.850295)
			(xy 228.945081 -276.832288) (xy 228.999924 -276.822158) (xy 229.055658 -276.820121) (xy 229.111095 -276.826221)
			(xy 229.165052 -276.840327) (xy 229.216381 -276.862139) (xy 229.263987 -276.891193) (xy 229.306855 -276.926868)
			(xy 229.344072 -276.968405) (xy 229.374845 -277.014918) (xy 229.398517 -277.065415) (xy 229.414585 -277.118822)
			(xy 229.422705 -277.173998) (xy 229.423214 -277.201884) (xy 229.422705 -277.22977) (xy 229.414585 -277.284946)
			(xy 229.398517 -277.338353) (xy 229.374845 -277.38885) (xy 229.344072 -277.435363) (xy 229.306855 -277.4769)
			(xy 229.263987 -277.512575) (xy 229.216381 -277.541629) (xy 229.165052 -277.563441) (xy 229.111095 -277.577547)
			(xy 229.055658 -277.583647) (xy 228.999924 -277.58161) (xy 228.945081 -277.57148) (xy 228.892297 -277.553473)
			(xy 228.842697 -277.527972) (xy 228.797339 -277.495521) (xy 228.75719 -277.456812) (xy 228.723104 -277.412669)
			(xy 228.695808 -277.364034) (xy 228.675885 -277.311943) (xy 228.663759 -277.257506) (xy 228.659688 -277.201884)
			(xy 228.233523 -277.201884) (xy 228.233732 -277.213314) (xy 228.233223 -277.2412) (xy 228.225103 -277.296376)
			(xy 228.209035 -277.349783) (xy 228.185363 -277.40028) (xy 228.15459 -277.446793) (xy 228.117373 -277.48833)
			(xy 228.074505 -277.524005) (xy 228.026899 -277.553059) (xy 227.97557 -277.574871) (xy 227.921613 -277.588977)
			(xy 227.866176 -277.595077) (xy 227.810442 -277.59304) (xy 227.755599 -277.58291) (xy 227.702815 -277.564903)
			(xy 227.653215 -277.539402) (xy 227.607857 -277.506951) (xy 227.567708 -277.468242) (xy 227.533622 -277.424099)
			(xy 227.506326 -277.375464) (xy 227.486403 -277.323373) (xy 227.474277 -277.268936) (xy 227.470206 -277.213314)
			(xy 227.026724 -277.213314) (xy 226.497134 -277.742904) (xy 226.489209 -277.751601) (xy 226.481657 -277.773853)
			(xy 226.482656 -277.785576) (xy 226.48317 -277.789386) (xy 230.452928 -277.789386) (xy 230.456999 -277.733764)
			(xy 230.469125 -277.679327) (xy 230.489048 -277.627236) (xy 230.516344 -277.578601) (xy 230.55043 -277.534458)
			(xy 230.590579 -277.495749) (xy 230.635937 -277.463298) (xy 230.685537 -277.437797) (xy 230.738321 -277.41979)
			(xy 230.793164 -277.40966) (xy 230.848898 -277.407623) (xy 230.904335 -277.413723) (xy 230.958292 -277.427829)
			(xy 231.009621 -277.449641) (xy 231.057227 -277.478695) (xy 231.100095 -277.51437) (xy 231.120063 -277.536656)
			(xy 232.472228 -277.536656) (xy 232.476299 -277.481034) (xy 232.488425 -277.426597) (xy 232.508348 -277.374506)
			(xy 232.535644 -277.325871) (xy 232.56973 -277.281728) (xy 232.609879 -277.243019) (xy 232.655237 -277.210568)
			(xy 232.704837 -277.185067) (xy 232.757621 -277.16706) (xy 232.812464 -277.15693) (xy 232.868198 -277.154893)
			(xy 232.923635 -277.160993) (xy 232.977592 -277.175099) (xy 233.028921 -277.196911) (xy 233.063289 -277.217886)
			(xy 236.252004 -277.217886) (xy 236.252461 -277.190515) (xy 236.260281 -277.136336) (xy 236.275772 -277.083833)
			(xy 236.298616 -277.034086) (xy 236.328342 -276.988119) (xy 236.345984 -276.967188) (xy 236.35208 -276.960076)
			(xy 236.35843 -276.943058) (xy 236.35843 -276.857714) (xy 236.35208 -276.840696) (xy 236.345984 -276.833584)
			(xy 236.328368 -276.812633) (xy 236.298654 -276.766665) (xy 236.275813 -276.716922) (xy 236.260317 -276.664426)
			(xy 236.252482 -276.610254) (xy 236.252004 -276.582886) (xy 236.252465 -276.555634) (xy 236.260224 -276.501685)
			(xy 236.275581 -276.449389) (xy 236.298225 -276.399811) (xy 236.327694 -276.35396) (xy 236.363388 -276.312769)
			(xy 236.404581 -276.277078) (xy 236.450433 -276.247612) (xy 236.500013 -276.224972) (xy 236.55231 -276.209618)
			(xy 236.60626 -276.201863) (xy 236.633512 -276.201378) (xy 236.662251 -276.2019) (xy 236.719078 -276.210524)
			(xy 236.773969 -276.227575) (xy 236.82568 -276.252667) (xy 236.873043 -276.285231) (xy 236.89437 -276.304502)
			(xy 236.901482 -276.311106) (xy 236.919008 -276.318218) (xy 237.008416 -276.318218) (xy 237.025942 -276.311106)
			(xy 237.033054 -276.304502) (xy 237.054381 -276.285232) (xy 237.101744 -276.252667) (xy 237.153455 -276.227576)
			(xy 237.208346 -276.210526) (xy 237.265173 -276.201904) (xy 237.322651 -276.201904) (xy 237.379478 -276.210526)
			(xy 237.434369 -276.227576) (xy 237.48608 -276.252667) (xy 237.533443 -276.285232) (xy 237.55477 -276.304502)
			(xy 237.561882 -276.311106) (xy 237.579408 -276.318218) (xy 237.668816 -276.318218) (xy 237.686342 -276.311106)
			(xy 237.693454 -276.304502) (xy 237.714781 -276.285232) (xy 237.762144 -276.252667) (xy 237.813855 -276.227576)
			(xy 237.868746 -276.210526) (xy 237.925573 -276.201904) (xy 237.983051 -276.201904) (xy 238.039878 -276.210526)
			(xy 238.094769 -276.227576) (xy 238.14648 -276.252667) (xy 238.193843 -276.285232) (xy 238.21517 -276.304502)
			(xy 238.222282 -276.311106) (xy 238.239808 -276.318218) (xy 238.329216 -276.318218) (xy 238.346742 -276.311106)
			(xy 238.353854 -276.304502) (xy 238.375186 -276.285237) (xy 238.422545 -276.252667) (xy 238.474256 -276.227573)
			(xy 238.529146 -276.210521) (xy 238.585973 -276.201899) (xy 238.614712 -276.201378) (xy 238.641963 -276.201867)
			(xy 238.69591 -276.209624) (xy 238.748204 -276.22498) (xy 238.79778 -276.247622) (xy 238.84363 -276.277088)
			(xy 238.884819 -276.312779) (xy 238.920511 -276.353969) (xy 238.930183 -276.369018) (xy 241.385088 -276.369018)
			(xy 241.389159 -276.313396) (xy 241.401285 -276.258959) (xy 241.421208 -276.206868) (xy 241.448504 -276.158233)
			(xy 241.48259 -276.11409) (xy 241.522739 -276.075381) (xy 241.568097 -276.04293) (xy 241.617697 -276.017429)
			(xy 241.670481 -275.999422) (xy 241.725324 -275.989292) (xy 241.781058 -275.987255) (xy 241.836495 -275.993355)
			(xy 241.890452 -276.007461) (xy 241.941781 -276.029273) (xy 241.989387 -276.058327) (xy 242.032255 -276.094002)
			(xy 242.069472 -276.135539) (xy 242.100245 -276.182052) (xy 242.123917 -276.232549) (xy 242.139985 -276.285956)
			(xy 242.148105 -276.341132) (xy 242.148614 -276.369018) (xy 242.148105 -276.396904) (xy 242.139985 -276.45208)
			(xy 242.123917 -276.505487) (xy 242.117401 -276.519386) (xy 246.703086 -276.519386) (xy 246.707157 -276.463764)
			(xy 246.719283 -276.409327) (xy 246.739206 -276.357236) (xy 246.766502 -276.308601) (xy 246.800588 -276.264458)
			(xy 246.840737 -276.225749) (xy 246.886095 -276.193298) (xy 246.935695 -276.167797) (xy 246.988479 -276.14979)
			(xy 247.043322 -276.13966) (xy 247.099056 -276.137623) (xy 247.154493 -276.143723) (xy 247.20845 -276.157829)
			(xy 247.259779 -276.179641) (xy 247.307385 -276.208695) (xy 247.350253 -276.24437) (xy 247.38747 -276.285907)
			(xy 247.418243 -276.33242) (xy 247.441915 -276.382917) (xy 247.457983 -276.436324) (xy 247.466103 -276.4915)
			(xy 247.466612 -276.519386) (xy 248.722386 -276.519386) (xy 248.726457 -276.463764) (xy 248.738583 -276.409327)
			(xy 248.758506 -276.357236) (xy 248.785802 -276.308601) (xy 248.819888 -276.264458) (xy 248.860037 -276.225749)
			(xy 248.905395 -276.193298) (xy 248.954995 -276.167797) (xy 249.007779 -276.14979) (xy 249.062622 -276.13966)
			(xy 249.118356 -276.137623) (xy 249.173793 -276.143723) (xy 249.22775 -276.157829) (xy 249.279079 -276.179641)
			(xy 249.326685 -276.208695) (xy 249.369553 -276.24437) (xy 249.40677 -276.285907) (xy 249.437543 -276.33242)
			(xy 249.461215 -276.382917) (xy 249.477283 -276.436324) (xy 249.485403 -276.4915) (xy 249.485912 -276.519386)
			(xy 249.485403 -276.547272) (xy 249.477283 -276.602448) (xy 249.461215 -276.655855) (xy 249.437543 -276.706352)
			(xy 249.40677 -276.752865) (xy 249.369553 -276.794402) (xy 249.326685 -276.830077) (xy 249.279079 -276.859131)
			(xy 249.22775 -276.880943) (xy 249.173793 -276.895049) (xy 249.118356 -276.901149) (xy 249.062622 -276.899112)
			(xy 249.007779 -276.888982) (xy 248.954995 -276.870975) (xy 248.905395 -276.845474) (xy 248.860037 -276.813023)
			(xy 248.819888 -276.774314) (xy 248.785802 -276.730171) (xy 248.758506 -276.681536) (xy 248.738583 -276.629445)
			(xy 248.726457 -276.575008) (xy 248.722386 -276.519386) (xy 247.466612 -276.519386) (xy 247.466103 -276.547272)
			(xy 247.457983 -276.602448) (xy 247.441915 -276.655855) (xy 247.418243 -276.706352) (xy 247.38747 -276.752865)
			(xy 247.350253 -276.794402) (xy 247.307385 -276.830077) (xy 247.259779 -276.859131) (xy 247.20845 -276.880943)
			(xy 247.154493 -276.895049) (xy 247.099056 -276.901149) (xy 247.043322 -276.899112) (xy 246.988479 -276.888982)
			(xy 246.935695 -276.870975) (xy 246.886095 -276.845474) (xy 246.840737 -276.813023) (xy 246.800588 -276.774314)
			(xy 246.766502 -276.730171) (xy 246.739206 -276.681536) (xy 246.719283 -276.629445) (xy 246.707157 -276.575008)
			(xy 246.703086 -276.519386) (xy 242.117401 -276.519386) (xy 242.100245 -276.555984) (xy 242.069472 -276.602497)
			(xy 242.032255 -276.644034) (xy 241.989387 -276.679709) (xy 241.941781 -276.708763) (xy 241.890452 -276.730575)
			(xy 241.836495 -276.744681) (xy 241.781058 -276.750781) (xy 241.725324 -276.748744) (xy 241.670481 -276.738614)
			(xy 241.617697 -276.720607) (xy 241.568097 -276.695106) (xy 241.522739 -276.662655) (xy 241.48259 -276.623946)
			(xy 241.448504 -276.579803) (xy 241.421208 -276.531168) (xy 241.401285 -276.479077) (xy 241.389159 -276.42464)
			(xy 241.385088 -276.369018) (xy 238.930183 -276.369018) (xy 238.949977 -276.399818) (xy 238.972619 -276.449394)
			(xy 238.987975 -276.501688) (xy 238.995733 -276.555635) (xy 238.99622 -276.582886) (xy 238.995765 -276.610257)
			(xy 238.987948 -276.664437) (xy 238.972457 -276.716941) (xy 238.949612 -276.766688) (xy 238.919884 -276.812654)
			(xy 238.90224 -276.833584) (xy 238.896144 -276.840696) (xy 238.889794 -276.857714) (xy 238.889794 -276.943058)
			(xy 238.896144 -276.960076) (xy 238.90224 -276.967188) (xy 238.919894 -276.988108) (xy 238.949602 -277.034085)
			(xy 238.972435 -277.083836) (xy 238.987922 -277.136339) (xy 238.995748 -277.190516) (xy 238.996141 -277.213314)
			(xy 243.720364 -277.213314) (xy 243.724435 -277.157692) (xy 243.736561 -277.103255) (xy 243.756484 -277.051164)
			(xy 243.78378 -277.002529) (xy 243.817866 -276.958386) (xy 243.858015 -276.919677) (xy 243.903373 -276.887226)
			(xy 243.952973 -276.861725) (xy 244.005757 -276.843718) (xy 244.0606 -276.833588) (xy 244.116334 -276.831551)
			(xy 244.171771 -276.837651) (xy 244.225728 -276.851757) (xy 244.277057 -276.873569) (xy 244.324663 -276.902623)
			(xy 244.367531 -276.938298) (xy 244.404748 -276.979835) (xy 244.435521 -277.026348) (xy 244.459193 -277.076845)
			(xy 244.475261 -277.130252) (xy 244.483381 -277.185428) (xy 244.483681 -277.201884) (xy 244.909846 -277.201884)
			(xy 244.913917 -277.146262) (xy 244.926043 -277.091825) (xy 244.945966 -277.039734) (xy 244.973262 -276.991099)
			(xy 245.007348 -276.946956) (xy 245.047497 -276.908247) (xy 245.092855 -276.875796) (xy 245.142455 -276.850295)
			(xy 245.195239 -276.832288) (xy 245.250082 -276.822158) (xy 245.305816 -276.820121) (xy 245.361253 -276.826221)
			(xy 245.41521 -276.840327) (xy 245.466539 -276.862139) (xy 245.514145 -276.891193) (xy 245.557013 -276.926868)
			(xy 245.59423 -276.968405) (xy 245.625003 -277.014918) (xy 245.648675 -277.065415) (xy 245.664743 -277.118822)
			(xy 245.672863 -277.173998) (xy 245.673372 -277.201884) (xy 245.672863 -277.22977) (xy 245.664743 -277.284946)
			(xy 245.648675 -277.338353) (xy 245.625003 -277.38885) (xy 245.59423 -277.435363) (xy 245.557013 -277.4769)
			(xy 245.514145 -277.512575) (xy 245.466539 -277.541629) (xy 245.41521 -277.563441) (xy 245.361253 -277.577547)
			(xy 245.305816 -277.583647) (xy 245.250082 -277.58161) (xy 245.195239 -277.57148) (xy 245.142455 -277.553473)
			(xy 245.092855 -277.527972) (xy 245.047497 -277.495521) (xy 245.007348 -277.456812) (xy 244.973262 -277.412669)
			(xy 244.945966 -277.364034) (xy 244.926043 -277.311943) (xy 244.913917 -277.257506) (xy 244.909846 -277.201884)
			(xy 244.483681 -277.201884) (xy 244.48389 -277.213314) (xy 244.483381 -277.2412) (xy 244.475261 -277.296376)
			(xy 244.459193 -277.349783) (xy 244.435521 -277.40028) (xy 244.404748 -277.446793) (xy 244.367531 -277.48833)
			(xy 244.324663 -277.524005) (xy 244.277057 -277.553059) (xy 244.225728 -277.574871) (xy 244.171771 -277.588977)
			(xy 244.116334 -277.595077) (xy 244.0606 -277.59304) (xy 244.005757 -277.58291) (xy 243.952973 -277.564903)
			(xy 243.903373 -277.539402) (xy 243.858015 -277.506951) (xy 243.817866 -277.468242) (xy 243.78378 -277.424099)
			(xy 243.756484 -277.375464) (xy 243.736561 -277.323373) (xy 243.724435 -277.268936) (xy 243.720364 -277.213314)
			(xy 238.996141 -277.213314) (xy 238.99622 -277.217886) (xy 238.995732 -277.245138) (xy 238.987977 -277.299087)
			(xy 238.972623 -277.351384) (xy 238.949983 -277.400963) (xy 238.920518 -277.446816) (xy 238.884827 -277.488008)
			(xy 238.843637 -277.523702) (xy 238.797786 -277.553171) (xy 238.748208 -277.575814) (xy 238.695913 -277.591171)
			(xy 238.641964 -277.59893) (xy 238.614712 -277.599394) (xy 238.585973 -277.598865) (xy 238.529146 -277.590244)
			(xy 238.474255 -277.573195) (xy 238.422543 -277.548105) (xy 238.375181 -277.51554) (xy 238.353854 -277.49627)
			(xy 238.346742 -277.489666) (xy 238.329216 -277.482554) (xy 238.239808 -277.482554) (xy 238.222282 -277.489666)
			(xy 238.21517 -277.49627) (xy 238.193843 -277.51554) (xy 238.14648 -277.548105) (xy 238.094769 -277.573196)
			(xy 238.039878 -277.590246) (xy 237.983051 -277.598868) (xy 237.925573 -277.598868) (xy 237.868746 -277.590246)
			(xy 237.813855 -277.573196) (xy 237.762144 -277.548105) (xy 237.714781 -277.51554) (xy 237.693454 -277.49627)
			(xy 237.686342 -277.489666) (xy 237.668816 -277.482554) (xy 237.579408 -277.482554) (xy 237.561882 -277.489666)
			(xy 237.55477 -277.49627) (xy 237.533443 -277.51554) (xy 237.48608 -277.548105) (xy 237.434369 -277.573196)
			(xy 237.379478 -277.590246) (xy 237.322651 -277.598868) (xy 237.265173 -277.598868) (xy 237.208346 -277.590246)
			(xy 237.153455 -277.573196) (xy 237.101744 -277.548105) (xy 237.054381 -277.51554) (xy 237.033054 -277.49627)
			(xy 237.025942 -277.489666) (xy 237.008416 -277.482554) (xy 236.919008 -277.482554) (xy 236.901482 -277.489666)
			(xy 236.89437 -277.49627) (xy 236.873039 -277.515536) (xy 236.825678 -277.548103) (xy 236.773967 -277.573196)
			(xy 236.719077 -277.590248) (xy 236.662251 -277.598872) (xy 236.633512 -277.599394) (xy 236.606259 -277.598933)
			(xy 236.552307 -277.591178) (xy 236.500008 -277.575823) (xy 236.450427 -277.55318) (xy 236.404573 -277.523712)
			(xy 236.36338 -277.488018) (xy 236.327686 -277.446825) (xy 236.298219 -277.400971) (xy 236.275577 -277.35139)
			(xy 236.260222 -277.299091) (xy 236.252466 -277.245139) (xy 236.252004 -277.217886) (xy 233.063289 -277.217886)
			(xy 233.076527 -277.225965) (xy 233.119395 -277.26164) (xy 233.156612 -277.303177) (xy 233.187385 -277.34969)
			(xy 233.211057 -277.400187) (xy 233.227125 -277.453594) (xy 233.235245 -277.50877) (xy 233.235754 -277.536656)
			(xy 233.235245 -277.564542) (xy 233.227125 -277.619718) (xy 233.211057 -277.673125) (xy 233.187385 -277.723622)
			(xy 233.156612 -277.770135) (xy 233.139363 -277.789386) (xy 246.703086 -277.789386) (xy 246.707157 -277.733764)
			(xy 246.719283 -277.679327) (xy 246.739206 -277.627236) (xy 246.766502 -277.578601) (xy 246.800588 -277.534458)
			(xy 246.840737 -277.495749) (xy 246.886095 -277.463298) (xy 246.935695 -277.437797) (xy 246.988479 -277.41979)
			(xy 247.043322 -277.40966) (xy 247.099056 -277.407623) (xy 247.154493 -277.413723) (xy 247.20845 -277.427829)
			(xy 247.259779 -277.449641) (xy 247.307385 -277.478695) (xy 247.350253 -277.51437) (xy 247.370221 -277.536656)
			(xy 248.722386 -277.536656) (xy 248.726457 -277.481034) (xy 248.738583 -277.426597) (xy 248.758506 -277.374506)
			(xy 248.785802 -277.325871) (xy 248.819888 -277.281728) (xy 248.860037 -277.243019) (xy 248.905395 -277.210568)
			(xy 248.954995 -277.185067) (xy 249.007779 -277.16706) (xy 249.062622 -277.15693) (xy 249.118356 -277.154893)
			(xy 249.173793 -277.160993) (xy 249.22775 -277.175099) (xy 249.279079 -277.196911) (xy 249.326685 -277.225965)
			(xy 249.369553 -277.26164) (xy 249.40677 -277.303177) (xy 249.437543 -277.34969) (xy 249.461215 -277.400187)
			(xy 249.477283 -277.453594) (xy 249.485403 -277.50877) (xy 249.485912 -277.536656) (xy 249.485403 -277.564542)
			(xy 249.477283 -277.619718) (xy 249.461215 -277.673125) (xy 249.437543 -277.723622) (xy 249.40677 -277.770135)
			(xy 249.369553 -277.811672) (xy 249.326685 -277.847347) (xy 249.279079 -277.876401) (xy 249.22775 -277.898213)
			(xy 249.173793 -277.912319) (xy 249.118356 -277.918419) (xy 249.062622 -277.916382) (xy 249.007779 -277.906252)
			(xy 248.954995 -277.888245) (xy 248.905395 -277.862744) (xy 248.860037 -277.830293) (xy 248.819888 -277.791584)
			(xy 248.785802 -277.747441) (xy 248.758506 -277.698806) (xy 248.738583 -277.646715) (xy 248.726457 -277.592278)
			(xy 248.722386 -277.536656) (xy 247.370221 -277.536656) (xy 247.38747 -277.555907) (xy 247.418243 -277.60242)
			(xy 247.441915 -277.652917) (xy 247.457983 -277.706324) (xy 247.466103 -277.7615) (xy 247.466612 -277.789386)
			(xy 247.466103 -277.817272) (xy 247.457983 -277.872448) (xy 247.441915 -277.925855) (xy 247.418243 -277.976352)
			(xy 247.38747 -278.022865) (xy 247.350253 -278.064402) (xy 247.307385 -278.100077) (xy 247.259779 -278.129131)
			(xy 247.20845 -278.150943) (xy 247.154493 -278.165049) (xy 247.099056 -278.171149) (xy 247.043322 -278.169112)
			(xy 246.988479 -278.158982) (xy 246.935695 -278.140975) (xy 246.886095 -278.115474) (xy 246.840737 -278.083023)
			(xy 246.800588 -278.044314) (xy 246.766502 -278.000171) (xy 246.739206 -277.951536) (xy 246.719283 -277.899445)
			(xy 246.707157 -277.845008) (xy 246.703086 -277.789386) (xy 233.139363 -277.789386) (xy 233.119395 -277.811672)
			(xy 233.076527 -277.847347) (xy 233.028921 -277.876401) (xy 232.977592 -277.898213) (xy 232.923635 -277.912319)
			(xy 232.868198 -277.918419) (xy 232.812464 -277.916382) (xy 232.757621 -277.906252) (xy 232.704837 -277.888245)
			(xy 232.655237 -277.862744) (xy 232.609879 -277.830293) (xy 232.56973 -277.791584) (xy 232.535644 -277.747441)
			(xy 232.508348 -277.698806) (xy 232.488425 -277.646715) (xy 232.476299 -277.592278) (xy 232.472228 -277.536656)
			(xy 231.120063 -277.536656) (xy 231.137312 -277.555907) (xy 231.168085 -277.60242) (xy 231.191757 -277.652917)
			(xy 231.207825 -277.706324) (xy 231.215945 -277.7615) (xy 231.216454 -277.789386) (xy 231.215945 -277.817272)
			(xy 231.207825 -277.872448) (xy 231.191757 -277.925855) (xy 231.168085 -277.976352) (xy 231.137312 -278.022865)
			(xy 231.100095 -278.064402) (xy 231.057227 -278.100077) (xy 231.009621 -278.129131) (xy 230.958292 -278.150943)
			(xy 230.904335 -278.165049) (xy 230.848898 -278.171149) (xy 230.793164 -278.169112) (xy 230.738321 -278.158982)
			(xy 230.685537 -278.140975) (xy 230.635937 -278.115474) (xy 230.590579 -278.083023) (xy 230.55043 -278.044314)
			(xy 230.516344 -278.000171) (xy 230.489048 -277.951536) (xy 230.469125 -277.899445) (xy 230.456999 -277.845008)
			(xy 230.452928 -277.789386) (xy 226.48317 -277.789386) (xy 226.49307 -277.862792) (xy 226.49453 -277.870982)
			(xy 226.501923 -277.885872) (xy 226.507548 -277.892002) (xy 226.517962 -277.902416) (xy 226.52355 -277.905718)
			(xy 226.547459 -277.920596) (xy 226.591025 -277.956274) (xy 226.628879 -277.997963) (xy 226.660201 -278.044759)
			(xy 226.684312 -278.095648) (xy 226.700688 -278.149525) (xy 226.708975 -278.205223) (xy 226.709478 -278.233378)
			(xy 226.708985 -278.260971) (xy 226.701026 -278.315581) (xy 226.685285 -278.368475) (xy 226.679976 -278.379936)
			(xy 227.470206 -278.379936) (xy 227.474277 -278.324314) (xy 227.486403 -278.269877) (xy 227.506326 -278.217786)
			(xy 227.533622 -278.169151) (xy 227.567708 -278.125008) (xy 227.607857 -278.086299) (xy 227.653215 -278.053848)
			(xy 227.702815 -278.028347) (xy 227.755599 -278.01034) (xy 227.810442 -278.00021) (xy 227.866176 -277.998173)
			(xy 227.921613 -278.004273) (xy 227.97557 -278.018379) (xy 228.026899 -278.040191) (xy 228.074505 -278.069245)
			(xy 228.117373 -278.10492) (xy 228.15459 -278.146457) (xy 228.185363 -278.19297) (xy 228.209035 -278.243467)
			(xy 228.225103 -278.296874) (xy 228.233223 -278.35205) (xy 228.233528 -278.36876) (xy 228.648258 -278.36876)
			(xy 228.652329 -278.313138) (xy 228.664455 -278.258701) (xy 228.684378 -278.20661) (xy 228.711674 -278.157975)
			(xy 228.74576 -278.113832) (xy 228.785909 -278.075123) (xy 228.831267 -278.042672) (xy 228.880867 -278.017171)
			(xy 228.933651 -277.999164) (xy 228.988494 -277.989034) (xy 229.044228 -277.986997) (xy 229.099665 -277.993097)
			(xy 229.153622 -278.007203) (xy 229.204951 -278.029015) (xy 229.252557 -278.058069) (xy 229.295425 -278.093744)
			(xy 229.332642 -278.135281) (xy 229.363415 -278.181794) (xy 229.387087 -278.232291) (xy 229.387414 -278.233378)
			(xy 242.19611 -278.233378) (xy 242.200181 -278.177756) (xy 242.212307 -278.123319) (xy 242.23223 -278.071228)
			(xy 242.259526 -278.022593) (xy 242.293612 -277.97845) (xy 242.333761 -277.939741) (xy 242.379119 -277.90729)
			(xy 242.428719 -277.881789) (xy 242.481503 -277.863782) (xy 242.536346 -277.853652) (xy 242.59208 -277.851615)
			(xy 242.647517 -277.857715) (xy 242.701474 -277.871821) (xy 242.752803 -277.893633) (xy 242.800409 -277.922687)
			(xy 242.843277 -277.958362) (xy 242.880494 -277.999899) (xy 242.911267 -278.046412) (xy 242.934939 -278.096909)
			(xy 242.951007 -278.150316) (xy 242.959127 -278.205492) (xy 242.959636 -278.233378) (xy 242.959127 -278.261264)
			(xy 242.951007 -278.31644) (xy 242.934939 -278.369847) (xy 242.930209 -278.379936) (xy 243.720364 -278.379936)
			(xy 243.724435 -278.324314) (xy 243.736561 -278.269877) (xy 243.756484 -278.217786) (xy 243.78378 -278.169151)
			(xy 243.817866 -278.125008) (xy 243.858015 -278.086299) (xy 243.903373 -278.053848) (xy 243.952973 -278.028347)
			(xy 244.005757 -278.01034) (xy 244.0606 -278.00021) (xy 244.116334 -277.998173) (xy 244.171771 -278.004273)
			(xy 244.225728 -278.018379) (xy 244.277057 -278.040191) (xy 244.324663 -278.069245) (xy 244.367531 -278.10492)
			(xy 244.404748 -278.146457) (xy 244.435521 -278.19297) (xy 244.459193 -278.243467) (xy 244.475261 -278.296874)
			(xy 244.483381 -278.35205) (xy 244.483686 -278.36876) (xy 244.898416 -278.36876) (xy 244.902487 -278.313138)
			(xy 244.914613 -278.258701) (xy 244.934536 -278.20661) (xy 244.961832 -278.157975) (xy 244.995918 -278.113832)
			(xy 245.036067 -278.075123) (xy 245.081425 -278.042672) (xy 245.131025 -278.017171) (xy 245.183809 -277.999164)
			(xy 245.238652 -277.989034) (xy 245.294386 -277.986997) (xy 245.349823 -277.993097) (xy 245.40378 -278.007203)
			(xy 245.455109 -278.029015) (xy 245.502715 -278.058069) (xy 245.545583 -278.093744) (xy 245.5828 -278.135281)
			(xy 245.613573 -278.181794) (xy 245.637245 -278.232291) (xy 245.653313 -278.285698) (xy 245.661433 -278.340874)
			(xy 245.661942 -278.36876) (xy 245.661433 -278.396646) (xy 245.653313 -278.451822) (xy 245.637245 -278.505229)
			(xy 245.613573 -278.555726) (xy 245.5828 -278.602239) (xy 245.545583 -278.643776) (xy 245.502715 -278.679451)
			(xy 245.455109 -278.708505) (xy 245.40378 -278.730317) (xy 245.349823 -278.744423) (xy 245.294386 -278.750523)
			(xy 245.238652 -278.748486) (xy 245.183809 -278.738356) (xy 245.131025 -278.720349) (xy 245.081425 -278.694848)
			(xy 245.036067 -278.662397) (xy 244.995918 -278.623688) (xy 244.961832 -278.579545) (xy 244.934536 -278.53091)
			(xy 244.914613 -278.478819) (xy 244.902487 -278.424382) (xy 244.898416 -278.36876) (xy 244.483686 -278.36876)
			(xy 244.48389 -278.379936) (xy 244.483381 -278.407822) (xy 244.475261 -278.462998) (xy 244.459193 -278.516405)
			(xy 244.435521 -278.566902) (xy 244.404748 -278.613415) (xy 244.367531 -278.654952) (xy 244.324663 -278.690627)
			(xy 244.277057 -278.719681) (xy 244.225728 -278.741493) (xy 244.171771 -278.755599) (xy 244.116334 -278.761699)
			(xy 244.0606 -278.759662) (xy 244.005757 -278.749532) (xy 243.952973 -278.731525) (xy 243.903373 -278.706024)
			(xy 243.858015 -278.673573) (xy 243.817866 -278.634864) (xy 243.78378 -278.590721) (xy 243.756484 -278.542086)
			(xy 243.736561 -278.489995) (xy 243.724435 -278.435558) (xy 243.720364 -278.379936) (xy 242.930209 -278.379936)
			(xy 242.911267 -278.420344) (xy 242.880494 -278.466857) (xy 242.843277 -278.508394) (xy 242.800409 -278.544069)
			(xy 242.752803 -278.573123) (xy 242.701474 -278.594935) (xy 242.647517 -278.609041) (xy 242.59208 -278.615141)
			(xy 242.536346 -278.613104) (xy 242.481503 -278.602974) (xy 242.428719 -278.584967) (xy 242.379119 -278.559466)
			(xy 242.333761 -278.527015) (xy 242.293612 -278.488306) (xy 242.259526 -278.444163) (xy 242.23223 -278.395528)
			(xy 242.212307 -278.343437) (xy 242.200181 -278.289) (xy 242.19611 -278.233378) (xy 229.387414 -278.233378)
			(xy 229.403155 -278.285698) (xy 229.411275 -278.340874) (xy 229.411784 -278.36876) (xy 229.411275 -278.396646)
			(xy 229.403155 -278.451822) (xy 229.387087 -278.505229) (xy 229.363415 -278.555726) (xy 229.332642 -278.602239)
			(xy 229.295425 -278.643776) (xy 229.252557 -278.679451) (xy 229.204951 -278.708505) (xy 229.153622 -278.730317)
			(xy 229.099665 -278.744423) (xy 229.044228 -278.750523) (xy 228.988494 -278.748486) (xy 228.933651 -278.738356)
			(xy 228.880867 -278.720349) (xy 228.831267 -278.694848) (xy 228.785909 -278.662397) (xy 228.74576 -278.623688)
			(xy 228.711674 -278.579545) (xy 228.684378 -278.53091) (xy 228.664455 -278.478819) (xy 228.652329 -278.424382)
			(xy 228.648258 -278.36876) (xy 228.233528 -278.36876) (xy 228.233732 -278.379936) (xy 228.233223 -278.407822)
			(xy 228.225103 -278.462998) (xy 228.209035 -278.516405) (xy 228.185363 -278.566902) (xy 228.15459 -278.613415)
			(xy 228.117373 -278.654952) (xy 228.074505 -278.690627) (xy 228.026899 -278.719681) (xy 227.97557 -278.741493)
			(xy 227.921613 -278.755599) (xy 227.866176 -278.761699) (xy 227.810442 -278.759662) (xy 227.755599 -278.749532)
			(xy 227.702815 -278.731525) (xy 227.653215 -278.706024) (xy 227.607857 -278.673573) (xy 227.567708 -278.634864)
			(xy 227.533622 -278.590721) (xy 227.506326 -278.542086) (xy 227.486403 -278.489995) (xy 227.474277 -278.435558)
			(xy 227.470206 -278.379936) (xy 226.679976 -278.379936) (xy 226.662091 -278.41855) (xy 226.631926 -278.464763)
			(xy 226.595421 -278.50615) (xy 226.553335 -278.541848) (xy 226.506547 -278.571113) (xy 226.456032 -278.593334)
			(xy 226.42957 -278.60117) (xy 226.412806 -278.605742) (xy 226.392232 -278.63292) (xy 226.392232 -279.567386)
			(xy 230.452928 -279.567386) (xy 230.456999 -279.511764) (xy 230.469125 -279.457327) (xy 230.489048 -279.405236)
			(xy 230.516344 -279.356601) (xy 230.55043 -279.312458) (xy 230.590579 -279.273749) (xy 230.635937 -279.241298)
			(xy 230.685537 -279.215797) (xy 230.738321 -279.19779) (xy 230.793164 -279.18766) (xy 230.848898 -279.185623)
			(xy 230.904335 -279.191723) (xy 230.958292 -279.205829) (xy 231.009621 -279.227641) (xy 231.057227 -279.256695)
			(xy 231.100095 -279.29237) (xy 231.137312 -279.333907) (xy 231.168085 -279.38042) (xy 231.191757 -279.430917)
			(xy 231.207825 -279.484324) (xy 231.215945 -279.5395) (xy 231.216454 -279.567386) (xy 231.215945 -279.595272)
			(xy 231.207825 -279.650448) (xy 231.191757 -279.703855) (xy 231.168085 -279.754352) (xy 231.137312 -279.800865)
			(xy 231.100095 -279.842402) (xy 231.057227 -279.878077) (xy 231.009621 -279.907131) (xy 230.958292 -279.928943)
			(xy 230.904335 -279.943049) (xy 230.848898 -279.949149) (xy 230.793164 -279.947112) (xy 230.738321 -279.936982)
			(xy 230.685537 -279.918975) (xy 230.635937 -279.893474) (xy 230.590579 -279.861023) (xy 230.55043 -279.822314)
			(xy 230.516344 -279.778171) (xy 230.489048 -279.729536) (xy 230.469125 -279.677445) (xy 230.456999 -279.623008)
			(xy 230.452928 -279.567386) (xy 226.392232 -279.567386) (xy 226.392232 -280.302208) (xy 226.392657 -280.312277)
			(xy 226.400377 -280.330876) (xy 226.407218 -280.338276) (xy 226.969828 -280.900886) (xy 226.977227 -280.90773)
			(xy 226.995826 -280.915456) (xy 227.005896 -280.915872) (xy 228.830124 -280.915872) (xy 228.834188 -280.915618)
			(xy 228.846677 -280.913951) (xy 228.867866 -280.900374) (xy 228.874574 -280.88971) (xy 228.876352 -280.886408)
			(xy 228.91496 -280.802588) (xy 228.918651 -280.793601) (xy 228.919662 -280.774216) (xy 228.913363 -280.755855)
			(xy 228.90734 -280.748232) (xy 228.890193 -280.727422) (xy 228.861323 -280.681881) (xy 228.839165 -280.632724)
			(xy 228.824162 -280.580933) (xy 228.816615 -280.527543) (xy 228.816154 -280.500582) (xy 228.816154 -280.492454)
			(xy 228.817259 -280.464301) (xy 228.826728 -280.408763) (xy 228.84426 -280.35522) (xy 228.869475 -280.304837)
			(xy 228.901823 -280.258709) (xy 228.940603 -280.217839) (xy 228.98497 -280.183115) (xy 229.033961 -280.155292)
			(xy 229.08651 -280.134975) (xy 229.141475 -280.122606) (xy 229.197662 -280.118452) (xy 229.253849 -280.122606)
			(xy 229.308814 -280.134975) (xy 229.361363 -280.155292) (xy 229.410354 -280.183115) (xy 229.454721 -280.217839)
			(xy 229.493501 -280.258709) (xy 229.525849 -280.304837) (xy 229.551064 -280.35522) (xy 229.568596 -280.408763)
			(xy 229.578065 -280.464301) (xy 229.57917 -280.492454) (xy 229.57917 -280.498296) (xy 229.57917 -280.500582)
			(xy 229.578695 -280.527538) (xy 229.571095 -280.580911) (xy 229.556071 -280.632687) (xy 229.533922 -280.681839)
			(xy 229.505087 -280.727391) (xy 229.487984 -280.748232) (xy 229.482014 -280.75588) (xy 229.475766 -280.774231)
			(xy 229.476727 -280.793594) (xy 229.480364 -280.802588) (xy 229.518972 -280.886408) (xy 229.52075 -280.88971)
			(xy 229.527432 -280.900401) (xy 229.548633 -280.913981) (xy 229.561136 -280.915618) (xy 229.5652 -280.915872)
			(xy 232.429812 -280.915872) (xy 232.438601 -280.915501) (xy 232.455141 -280.909547) (xy 232.468689 -280.898346)
			(xy 232.4735 -280.89098) (xy 232.525062 -280.804112) (xy 232.52557 -280.777696) (xy 232.518966 -280.765758)
			(xy 232.504402 -280.737591) (xy 232.483788 -280.67763) (xy 232.473347 -280.615089) (xy 232.472738 -280.583386)
			(xy 232.473121 -280.557441) (xy 232.480046 -280.506018) (xy 232.493877 -280.456007) (xy 232.503726 -280.432002)
			(xy 232.514427 -280.40838) (xy 232.541278 -280.364016) (xy 232.573881 -280.323689) (xy 232.611636 -280.28814)
			(xy 232.632504 -280.272744) (xy 232.637584 -280.268934) (xy 232.645712 -280.259536) (xy 232.648506 -280.253694)
			(xy 232.650281 -280.249953) (xy 232.652714 -280.24204) (xy 232.653332 -280.237946) (xy 232.664254 -280.154126)
			(xy 232.658412 -280.13406) (xy 232.651554 -280.125678) (xy 232.63516 -280.105104) (xy 232.607587 -280.060303)
			(xy 232.586436 -280.012136) (xy 232.572107 -279.961518) (xy 232.564873 -279.909411) (xy 232.564432 -279.883108)
			(xy 232.564432 -279.878028) (xy 232.565527 -279.846053) (xy 232.577077 -279.783131) (xy 232.598969 -279.72302)
			(xy 232.614216 -279.694894) (xy 232.628305 -279.671055) (xy 232.662287 -279.627335) (xy 232.702217 -279.58897)
			(xy 232.724452 -279.572466) (xy 232.727754 -279.569926) (xy 232.734358 -279.563322) (xy 232.740522 -279.556561)
			(xy 232.748058 -279.539902) (xy 232.74909 -279.53081) (xy 232.74909 -279.523698) (xy 232.741978 -279.424384)
			(xy 232.727246 -279.402286) (xy 232.715054 -279.39619) (xy 232.691697 -279.383956) (xy 232.648293 -279.354022)
			(xy 232.609422 -279.318398) (xy 232.575826 -279.277761) (xy 232.548144 -279.232887) (xy 232.526904 -279.184629)
			(xy 232.512508 -279.133906) (xy 232.505233 -279.081685) (xy 232.504742 -279.055322) (xy 232.505228 -279.028071)
			(xy 232.512984 -278.974123) (xy 232.528339 -278.921828) (xy 232.550981 -278.872251) (xy 232.580447 -278.826401)
			(xy 232.616138 -278.78521) (xy 232.657329 -278.749519) (xy 232.703179 -278.720053) (xy 232.752756 -278.697411)
			(xy 232.805051 -278.682056) (xy 232.858999 -278.6743) (xy 232.913501 -278.6743) (xy 232.967449 -278.682056)
			(xy 233.019744 -278.697411) (xy 233.069321 -278.720053) (xy 233.115171 -278.749519) (xy 233.156362 -278.78521)
			(xy 233.192053 -278.826401) (xy 233.221519 -278.872251) (xy 233.244161 -278.921828) (xy 233.259516 -278.974123)
			(xy 233.267272 -279.028071) (xy 233.267758 -279.055322) (xy 233.267411 -279.075896) (xy 240.6302 -279.075896)
			(xy 240.634271 -279.020274) (xy 240.646397 -278.965837) (xy 240.66632 -278.913746) (xy 240.693616 -278.865111)
			(xy 240.727702 -278.820968) (xy 240.767851 -278.782259) (xy 240.813209 -278.749808) (xy 240.862809 -278.724307)
			(xy 240.915593 -278.7063) (xy 240.970436 -278.69617) (xy 241.02617 -278.694133) (xy 241.081607 -278.700233)
			(xy 241.135564 -278.714339) (xy 241.186893 -278.736151) (xy 241.234499 -278.765205) (xy 241.277367 -278.80088)
			(xy 241.314584 -278.842417) (xy 241.345357 -278.88893) (xy 241.369029 -278.939427) (xy 241.385097 -278.992834)
			(xy 241.393217 -279.04801) (xy 241.393726 -279.075896) (xy 241.393217 -279.103782) (xy 241.385097 -279.158958)
			(xy 241.369029 -279.212365) (xy 241.345357 -279.262862) (xy 241.314584 -279.309375) (xy 241.277367 -279.350912)
			(xy 241.234499 -279.386587) (xy 241.186893 -279.415641) (xy 241.135564 -279.437453) (xy 241.081607 -279.451559)
			(xy 241.02617 -279.457659) (xy 240.970436 -279.455622) (xy 240.915593 -279.445492) (xy 240.862809 -279.427485)
			(xy 240.813209 -279.401984) (xy 240.767851 -279.369533) (xy 240.727702 -279.330824) (xy 240.693616 -279.286681)
			(xy 240.66632 -279.238046) (xy 240.646397 -279.185955) (xy 240.634271 -279.131518) (xy 240.6302 -279.075896)
			(xy 233.267411 -279.075896) (xy 233.267321 -279.081258) (xy 233.26029 -279.132652) (xy 233.246362 -279.18262)
			(xy 233.225793 -279.23024) (xy 233.198961 -279.274634) (xy 233.166363 -279.314984) (xy 233.128599 -279.350546)
			(xy 233.107738 -279.365964) (xy 233.104436 -279.368504) (xy 233.097832 -279.375108) (xy 233.091659 -279.381866)
			(xy 233.084102 -279.398523) (xy 233.0831 -279.40762) (xy 233.0831 -279.414732) (xy 233.090212 -279.514046)
			(xy 233.104944 -279.536144) (xy 233.117136 -279.54224) (xy 233.140496 -279.554473) (xy 233.159225 -279.567386)
			(xy 246.703086 -279.567386) (xy 246.707157 -279.511764) (xy 246.719283 -279.457327) (xy 246.739206 -279.405236)
			(xy 246.766502 -279.356601) (xy 246.800588 -279.312458) (xy 246.840737 -279.273749) (xy 246.886095 -279.241298)
			(xy 246.935695 -279.215797) (xy 246.988479 -279.19779) (xy 247.043322 -279.18766) (xy 247.099056 -279.185623)
			(xy 247.154493 -279.191723) (xy 247.20845 -279.205829) (xy 247.259779 -279.227641) (xy 247.307385 -279.256695)
			(xy 247.350253 -279.29237) (xy 247.38747 -279.333907) (xy 247.418243 -279.38042) (xy 247.441915 -279.430917)
			(xy 247.457983 -279.484324) (xy 247.466103 -279.5395) (xy 247.466612 -279.567386) (xy 247.466103 -279.595272)
			(xy 247.457983 -279.650448) (xy 247.441915 -279.703855) (xy 247.418243 -279.754352) (xy 247.38747 -279.800865)
			(xy 247.350253 -279.842402) (xy 247.307385 -279.878077) (xy 247.259779 -279.907131) (xy 247.20845 -279.928943)
			(xy 247.154493 -279.943049) (xy 247.099056 -279.949149) (xy 247.043322 -279.947112) (xy 246.988479 -279.936982)
			(xy 246.935695 -279.918975) (xy 246.886095 -279.893474) (xy 246.840737 -279.861023) (xy 246.800588 -279.822314)
			(xy 246.766502 -279.778171) (xy 246.739206 -279.729536) (xy 246.719283 -279.677445) (xy 246.707157 -279.623008)
			(xy 246.703086 -279.567386) (xy 233.159225 -279.567386) (xy 233.183907 -279.584404) (xy 233.222785 -279.620026)
			(xy 233.25639 -279.660662) (xy 233.284081 -279.705536) (xy 233.30533 -279.753794) (xy 233.319735 -279.804519)
			(xy 233.32702 -279.856743) (xy 233.327448 -279.883108) (xy 233.327066 -279.909053) (xy 233.320141 -279.960476)
			(xy 233.306311 -280.010487) (xy 233.29646 -280.034492) (xy 233.285754 -280.05811) (xy 233.259758 -280.10104)
			(xy 240.634264 -280.10104) (xy 240.638335 -280.045418) (xy 240.650461 -279.990981) (xy 240.670384 -279.93889)
			(xy 240.69768 -279.890255) (xy 240.731766 -279.846112) (xy 240.771915 -279.807403) (xy 240.817273 -279.774952)
			(xy 240.866873 -279.749451) (xy 240.919657 -279.731444) (xy 240.9745 -279.721314) (xy 241.030234 -279.719277)
			(xy 241.085671 -279.725377) (xy 241.139628 -279.739483) (xy 241.190957 -279.761295) (xy 241.238563 -279.790349)
			(xy 241.281431 -279.826024) (xy 241.318648 -279.867561) (xy 241.349421 -279.914074) (xy 241.373093 -279.964571)
			(xy 241.389161 -280.017978) (xy 241.397281 -280.073154) (xy 241.39779 -280.10104) (xy 241.397281 -280.128926)
			(xy 241.389161 -280.184102) (xy 241.373093 -280.237509) (xy 241.349421 -280.288006) (xy 241.318648 -280.334519)
			(xy 241.281431 -280.376056) (xy 241.238563 -280.411731) (xy 241.190957 -280.440785) (xy 241.139628 -280.462597)
			(xy 241.085671 -280.476703) (xy 241.030234 -280.482803) (xy 240.9745 -280.480766) (xy 240.919657 -280.470636)
			(xy 240.866873 -280.452629) (xy 240.817273 -280.427128) (xy 240.771915 -280.394677) (xy 240.731766 -280.355968)
			(xy 240.69768 -280.311825) (xy 240.670384 -280.26319) (xy 240.650461 -280.211099) (xy 240.638335 -280.156662)
			(xy 240.634264 -280.10104) (xy 233.259758 -280.10104) (xy 233.258895 -280.102466) (xy 233.226285 -280.142784)
			(xy 233.188526 -280.178323) (xy 233.167682 -280.19375) (xy 233.162602 -280.19756) (xy 233.154474 -280.206958)
			(xy 233.15168 -280.2128) (xy 233.149913 -280.216543) (xy 233.147495 -280.224458) (xy 233.146854 -280.228548)
			(xy 233.135932 -280.312368) (xy 233.141774 -280.332434) (xy 233.148632 -280.340816) (xy 233.165027 -280.361389)
			(xy 233.192602 -280.406191) (xy 233.213755 -280.454358) (xy 233.228084 -280.504975) (xy 233.235319 -280.557083)
			(xy 233.235754 -280.583386) (xy 233.235754 -280.588466) (xy 233.235111 -280.61155) (xy 233.228924 -280.657314)
			(xy 233.217256 -280.701996) (xy 233.209084 -280.723594) (xy 233.20476 -280.734388) (xy 233.194974 -280.755485)
			(xy 233.189526 -280.765758) (xy 233.185633 -280.773602) (xy 233.182892 -280.790883) (xy 233.186163 -280.808072)
			(xy 233.190288 -280.815796) (xy 233.234992 -280.89098) (xy 233.239789 -280.898358) (xy 233.253342 -280.909565)
			(xy 233.269887 -280.915523) (xy 233.27868 -280.915872) (xy 245.080282 -280.915872) (xy 245.084346 -280.915618)
			(xy 245.096827 -280.913939) (xy 245.117995 -280.900351) (xy 245.124732 -280.88971) (xy 245.12651 -280.886408)
			(xy 245.165118 -280.802588) (xy 245.168812 -280.793602) (xy 245.169823 -280.774216) (xy 245.16352 -280.755857)
			(xy 245.157498 -280.748232) (xy 245.140353 -280.727421) (xy 245.111486 -280.68188) (xy 245.08933 -280.632722)
			(xy 245.074329 -280.580931) (xy 245.066783 -280.527542) (xy 245.066312 -280.500582) (xy 245.066312 -280.492454)
			(xy 245.067417 -280.464301) (xy 245.076886 -280.408763) (xy 245.094418 -280.35522) (xy 245.119633 -280.304837)
			(xy 245.151981 -280.258709) (xy 245.190761 -280.217839) (xy 245.235128 -280.183115) (xy 245.284119 -280.155292)
			(xy 245.336668 -280.134975) (xy 245.391633 -280.122606) (xy 245.44782 -280.118452) (xy 245.504007 -280.122606)
			(xy 245.558972 -280.134975) (xy 245.611521 -280.155292) (xy 245.660512 -280.183115) (xy 245.704879 -280.217839)
			(xy 245.743659 -280.258709) (xy 245.776007 -280.304837) (xy 245.801222 -280.35522) (xy 245.818754 -280.408763)
			(xy 245.828223 -280.464301) (xy 245.829328 -280.492454) (xy 245.829328 -280.498296) (xy 245.829328 -280.500582)
			(xy 245.828853 -280.527537) (xy 245.821252 -280.58091) (xy 245.820533 -280.583386) (xy 248.722896 -280.583386)
			(xy 248.723344 -280.557488) (xy 248.730348 -280.506168) (xy 248.744227 -280.456266) (xy 248.764725 -280.408699)
			(xy 248.791465 -280.364339) (xy 248.823957 -280.324002) (xy 248.861604 -280.288428) (xy 248.882408 -280.272998)
			(xy 248.891044 -280.266902) (xy 248.901966 -280.248868) (xy 248.914412 -280.154126) (xy 248.90857 -280.13406)
			(xy 248.901712 -280.125932) (xy 248.885274 -280.105359) (xy 248.857678 -280.060508) (xy 248.836521 -280.012284)
			(xy 248.822206 -279.961606) (xy 248.815008 -279.909439) (xy 248.81459 -279.883108) (xy 248.814996 -279.856894)
			(xy 248.82217 -279.80496) (xy 248.836383 -279.754496) (xy 248.857368 -279.706452) (xy 248.884731 -279.661732)
			(xy 248.917956 -279.621177) (xy 248.956419 -279.58555) (xy 248.977658 -279.57018) (xy 248.988834 -279.56256)
			(xy 249.000264 -279.538684) (xy 248.992136 -279.424384) (xy 248.977404 -279.402286) (xy 248.965212 -279.39619)
			(xy 248.941836 -279.383984) (xy 248.89841 -279.354065) (xy 248.859521 -279.318446) (xy 248.825911 -279.277809)
			(xy 248.798222 -279.232927) (xy 248.776983 -279.184659) (xy 248.762597 -279.133923) (xy 248.755341 -279.08169)
			(xy 248.7549 -279.055322) (xy 248.755386 -279.028071) (xy 248.763142 -278.974123) (xy 248.778497 -278.921828)
			(xy 248.801139 -278.872251) (xy 248.830605 -278.826401) (xy 248.866296 -278.78521) (xy 248.907487 -278.749519)
			(xy 248.953337 -278.720053) (xy 249.002914 -278.697411) (xy 249.055209 -278.682056) (xy 249.109157 -278.6743)
			(xy 249.163659 -278.6743) (xy 249.217607 -278.682056) (xy 249.269902 -278.697411) (xy 249.319479 -278.720053)
			(xy 249.365329 -278.749519) (xy 249.40652 -278.78521) (xy 249.429284 -278.811482) (xy 250.954284 -278.811482)
			(xy 250.958355 -278.75586) (xy 250.970481 -278.701423) (xy 250.990404 -278.649332) (xy 251.0177 -278.600697)
			(xy 251.051786 -278.556554) (xy 251.091935 -278.517845) (xy 251.137293 -278.485394) (xy 251.186893 -278.459893)
			(xy 251.239677 -278.441886) (xy 251.29452 -278.431756) (xy 251.350254 -278.429719) (xy 251.405691 -278.435819)
			(xy 251.459648 -278.449925) (xy 251.510977 -278.471737) (xy 251.558583 -278.500791) (xy 251.601451 -278.536466)
			(xy 251.638668 -278.578003) (xy 251.669441 -278.624516) (xy 251.693113 -278.675013) (xy 251.709181 -278.72842)
			(xy 251.717301 -278.783596) (xy 251.71781 -278.811482) (xy 251.717301 -278.839368) (xy 251.709181 -278.894544)
			(xy 251.693113 -278.947951) (xy 251.669441 -278.998448) (xy 251.638668 -279.044961) (xy 251.601451 -279.086498)
			(xy 251.558583 -279.122173) (xy 251.510977 -279.151227) (xy 251.459648 -279.173039) (xy 251.405691 -279.187145)
			(xy 251.350254 -279.193245) (xy 251.29452 -279.191208) (xy 251.239677 -279.181078) (xy 251.186893 -279.163071)
			(xy 251.137293 -279.13757) (xy 251.091935 -279.105119) (xy 251.051786 -279.06641) (xy 251.0177 -279.022267)
			(xy 250.990404 -278.973632) (xy 250.970481 -278.921541) (xy 250.958355 -278.867104) (xy 250.954284 -278.811482)
			(xy 249.429284 -278.811482) (xy 249.442211 -278.826401) (xy 249.471677 -278.872251) (xy 249.494319 -278.921828)
			(xy 249.509674 -278.974123) (xy 249.51743 -279.028071) (xy 249.517916 -279.055322) (xy 249.517455 -279.081534)
			(xy 249.510291 -279.133466) (xy 249.496087 -279.183928) (xy 249.47511 -279.231972) (xy 249.447756 -279.276693)
			(xy 249.414539 -279.31725) (xy 249.376084 -279.352879) (xy 249.354848 -279.36825) (xy 249.343672 -279.37587)
			(xy 249.332242 -279.399746) (xy 249.34037 -279.514046) (xy 249.355102 -279.536144) (xy 249.367294 -279.54224)
			(xy 249.390684 -279.554421) (xy 249.434111 -279.584344) (xy 249.472999 -279.619966) (xy 249.506608 -279.660607)
			(xy 249.534295 -279.705492) (xy 249.555532 -279.753764) (xy 249.569914 -279.804503) (xy 249.577167 -279.856739)
			(xy 249.577606 -279.883108) (xy 249.577153 -279.909006) (xy 249.570149 -279.960326) (xy 249.556271 -280.010227)
			(xy 249.535775 -280.057795) (xy 249.509035 -280.102154) (xy 249.476544 -280.142491) (xy 249.438897 -280.178066)
			(xy 249.418094 -280.193496) (xy 249.409458 -280.199592) (xy 249.398536 -280.217626) (xy 249.38609 -280.312368)
			(xy 249.391932 -280.332434) (xy 249.39879 -280.340562) (xy 249.415225 -280.361137) (xy 249.442822 -280.405988)
			(xy 249.46398 -280.454211) (xy 249.478295 -280.504889) (xy 249.485494 -280.557055) (xy 249.485912 -280.583386)
			(xy 249.485426 -280.610637) (xy 249.47767 -280.664585) (xy 249.462315 -280.71688) (xy 249.439673 -280.766457)
			(xy 249.410207 -280.812307) (xy 249.374516 -280.853498) (xy 249.333325 -280.889189) (xy 249.287475 -280.918655)
			(xy 249.237898 -280.941297) (xy 249.185603 -280.956652) (xy 249.131655 -280.964408) (xy 249.077153 -280.964408)
			(xy 249.023205 -280.956652) (xy 248.97091 -280.941297) (xy 248.921333 -280.918655) (xy 248.875483 -280.889189)
			(xy 248.834292 -280.853498) (xy 248.798601 -280.812307) (xy 248.769135 -280.766457) (xy 248.746493 -280.71688)
			(xy 248.731138 -280.664585) (xy 248.723382 -280.610637) (xy 248.722896 -280.583386) (xy 245.820533 -280.583386)
			(xy 245.806227 -280.632685) (xy 245.784076 -280.681836) (xy 245.755238 -280.727386) (xy 245.738142 -280.748232)
			(xy 245.732176 -280.755881) (xy 245.725934 -280.774232) (xy 245.726893 -280.793591) (xy 245.730522 -280.802588)
			(xy 245.76913 -280.886408) (xy 245.770908 -280.88971) (xy 245.777587 -280.900408) (xy 245.798786 -280.914005)
			(xy 245.811294 -280.915618) (xy 245.815358 -280.915872) (xy 246.739156 -280.915872) (xy 246.749222 -280.916305)
			(xy 246.767815 -280.92403) (xy 246.775224 -280.930858) (xy 247.186958 -281.342592) (xy 247.19788 -281.35072)
			(xy 247.203468 -281.354022) (xy 247.210072 -281.3558) (xy 247.237453 -281.363694) (xy 247.288888 -281.388207)
			(xy 247.334897 -281.421817) (xy 247.354852 -281.44216) (xy 247.355868 -281.443176) (xy 247.462802 -281.55011)
			(xy 250.225812 -281.55011) (xy 250.229883 -281.494488) (xy 250.242009 -281.440051) (xy 250.261932 -281.38796)
			(xy 250.289228 -281.339325) (xy 250.323314 -281.295182) (xy 250.363463 -281.256473) (xy 250.408821 -281.224022)
			(xy 250.458421 -281.198521) (xy 250.511205 -281.180514) (xy 250.566048 -281.170384) (xy 250.621782 -281.168347)
			(xy 250.677219 -281.174447) (xy 250.731176 -281.188553) (xy 250.782505 -281.210365) (xy 250.830111 -281.239419)
			(xy 250.872979 -281.275094) (xy 250.910196 -281.316631) (xy 250.940969 -281.363144) (xy 250.964641 -281.413641)
			(xy 250.980709 -281.467048) (xy 250.988829 -281.522224) (xy 250.989338 -281.55011) (xy 250.988829 -281.577996)
			(xy 250.980709 -281.633172) (xy 250.964641 -281.686579) (xy 250.940969 -281.737076) (xy 250.910196 -281.783589)
			(xy 250.872979 -281.825126) (xy 250.830111 -281.860801) (xy 250.782505 -281.889855) (xy 250.731176 -281.911667)
			(xy 250.677219 -281.925773) (xy 250.621782 -281.931873) (xy 250.566048 -281.929836) (xy 250.511205 -281.919706)
			(xy 250.458421 -281.901699) (xy 250.408821 -281.876198) (xy 250.363463 -281.843747) (xy 250.323314 -281.805038)
			(xy 250.289228 -281.760895) (xy 250.261932 -281.71226) (xy 250.242009 -281.660169) (xy 250.229883 -281.605732)
			(xy 250.225812 -281.55011) (xy 247.462802 -281.55011) (xy 249.044206 -283.131514) (xy 258.01142 -283.131514)
			(xy 258.015491 -283.075892) (xy 258.027617 -283.021455) (xy 258.04754 -282.969364) (xy 258.074836 -282.920729)
			(xy 258.108922 -282.876586) (xy 258.149071 -282.837877) (xy 258.194429 -282.805426) (xy 258.244029 -282.779925)
			(xy 258.296813 -282.761918) (xy 258.351656 -282.751788) (xy 258.40739 -282.749751) (xy 258.462827 -282.755851)
			(xy 258.516784 -282.769957) (xy 258.568113 -282.791769) (xy 258.615719 -282.820823) (xy 258.658587 -282.856498)
			(xy 258.695804 -282.898035) (xy 258.726577 -282.944548) (xy 258.750249 -282.995045) (xy 258.766317 -283.048452)
			(xy 258.774437 -283.103628) (xy 258.774946 -283.131514) (xy 258.774437 -283.1594) (xy 258.766317 -283.214576)
			(xy 258.750249 -283.267983) (xy 258.726577 -283.31848) (xy 258.695804 -283.364993) (xy 258.658587 -283.40653)
			(xy 258.615719 -283.442205) (xy 258.568113 -283.471259) (xy 258.516784 -283.493071) (xy 258.462827 -283.507177)
			(xy 258.40739 -283.513277) (xy 258.351656 -283.51124) (xy 258.296813 -283.50111) (xy 258.244029 -283.483103)
			(xy 258.194429 -283.457602) (xy 258.149071 -283.425151) (xy 258.108922 -283.386442) (xy 258.074836 -283.342299)
			(xy 258.04754 -283.293664) (xy 258.027617 -283.241573) (xy 258.015491 -283.187136) (xy 258.01142 -283.131514)
			(xy 249.044206 -283.131514) (xy 249.708162 -283.79547) (xy 249.709178 -283.796486) (xy 249.729533 -283.816431)
			(xy 249.763161 -283.862433) (xy 249.787664 -283.913877) (xy 249.795538 -283.941266) (xy 249.797316 -283.94787)
			(xy 249.800618 -283.953458) (xy 249.808746 -283.96438) (xy 250.550426 -284.705806) (xy 250.557279 -284.713201)
			(xy 250.565023 -284.7318) (xy 250.565412 -284.741874) (xy 250.565412 -285.029656) (xy 258.01142 -285.029656)
			(xy 258.015491 -284.974034) (xy 258.027617 -284.919597) (xy 258.04754 -284.867506) (xy 258.074836 -284.818871)
			(xy 258.108922 -284.774728) (xy 258.149071 -284.736019) (xy 258.194429 -284.703568) (xy 258.244029 -284.678067)
			(xy 258.296813 -284.66006) (xy 258.351656 -284.64993) (xy 258.40739 -284.647893) (xy 258.462827 -284.653993)
			(xy 258.516784 -284.668099) (xy 258.568113 -284.689911) (xy 258.615719 -284.718965) (xy 258.658587 -284.75464)
			(xy 258.695804 -284.796177) (xy 258.726577 -284.84269) (xy 258.750249 -284.893187) (xy 258.766317 -284.946594)
			(xy 258.774437 -285.00177) (xy 258.774946 -285.029656) (xy 259.496558 -285.029656) (xy 259.500629 -284.974034)
			(xy 259.512755 -284.919597) (xy 259.532678 -284.867506) (xy 259.559974 -284.818871) (xy 259.59406 -284.774728)
			(xy 259.634209 -284.736019) (xy 259.679567 -284.703568) (xy 259.729167 -284.678067) (xy 259.781951 -284.66006)
			(xy 259.836794 -284.64993) (xy 259.892528 -284.647893) (xy 259.947965 -284.653993) (xy 260.001922 -284.668099)
			(xy 260.053251 -284.689911) (xy 260.100857 -284.718965) (xy 260.143725 -284.75464) (xy 260.180942 -284.796177)
			(xy 260.211715 -284.84269) (xy 260.235387 -284.893187) (xy 260.251455 -284.946594) (xy 260.259575 -285.00177)
			(xy 260.260084 -285.029656) (xy 260.259575 -285.057542) (xy 260.251455 -285.112718) (xy 260.235387 -285.166125)
			(xy 260.211715 -285.216622) (xy 260.180942 -285.263135) (xy 260.143725 -285.304672) (xy 260.100857 -285.340347)
			(xy 260.053251 -285.369401) (xy 260.001922 -285.391213) (xy 259.947965 -285.405319) (xy 259.892528 -285.411419)
			(xy 259.836794 -285.409382) (xy 259.781951 -285.399252) (xy 259.729167 -285.381245) (xy 259.679567 -285.355744)
			(xy 259.634209 -285.323293) (xy 259.59406 -285.284584) (xy 259.559974 -285.240441) (xy 259.532678 -285.191806)
			(xy 259.512755 -285.139715) (xy 259.500629 -285.085278) (xy 259.496558 -285.029656) (xy 258.774946 -285.029656)
			(xy 258.774437 -285.057542) (xy 258.766317 -285.112718) (xy 258.750249 -285.166125) (xy 258.726577 -285.216622)
			(xy 258.695804 -285.263135) (xy 258.658587 -285.304672) (xy 258.615719 -285.340347) (xy 258.568113 -285.369401)
			(xy 258.516784 -285.391213) (xy 258.462827 -285.405319) (xy 258.40739 -285.411419) (xy 258.351656 -285.409382)
			(xy 258.296813 -285.399252) (xy 258.244029 -285.381245) (xy 258.194429 -285.355744) (xy 258.149071 -285.323293)
			(xy 258.108922 -285.284584) (xy 258.074836 -285.240441) (xy 258.04754 -285.191806) (xy 258.027617 -285.139715)
			(xy 258.015491 -285.085278) (xy 258.01142 -285.029656) (xy 250.565412 -285.029656) (xy 250.565412 -286.608012)
			(xy 251.525784 -286.608012) (xy 251.529855 -286.55239) (xy 251.541981 -286.497953) (xy 251.561904 -286.445862)
			(xy 251.5892 -286.397227) (xy 251.623286 -286.353084) (xy 251.663435 -286.314375) (xy 251.708793 -286.281924)
			(xy 251.758393 -286.256423) (xy 251.811177 -286.238416) (xy 251.86602 -286.228286) (xy 251.921754 -286.226249)
			(xy 251.977191 -286.232349) (xy 252.031148 -286.246455) (xy 252.082477 -286.268267) (xy 252.130083 -286.297321)
			(xy 252.171651 -286.331914) (xy 258.01142 -286.331914) (xy 258.015491 -286.276292) (xy 258.027617 -286.221855)
			(xy 258.04754 -286.169764) (xy 258.074836 -286.121129) (xy 258.108922 -286.076986) (xy 258.149071 -286.038277)
			(xy 258.194429 -286.005826) (xy 258.244029 -285.980325) (xy 258.296813 -285.962318) (xy 258.351656 -285.952188)
			(xy 258.40739 -285.950151) (xy 258.462827 -285.956251) (xy 258.516784 -285.970357) (xy 258.568113 -285.992169)
			(xy 258.615719 -286.021223) (xy 258.658587 -286.056898) (xy 258.695804 -286.098435) (xy 258.726577 -286.144948)
			(xy 258.750249 -286.195445) (xy 258.766317 -286.248852) (xy 258.774437 -286.304028) (xy 258.774946 -286.331914)
			(xy 259.486906 -286.331914) (xy 259.490977 -286.276292) (xy 259.503103 -286.221855) (xy 259.523026 -286.169764)
			(xy 259.550322 -286.121129) (xy 259.584408 -286.076986) (xy 259.624557 -286.038277) (xy 259.669915 -286.005826)
			(xy 259.719515 -285.980325) (xy 259.772299 -285.962318) (xy 259.827142 -285.952188) (xy 259.882876 -285.950151)
			(xy 259.938313 -285.956251) (xy 259.99227 -285.970357) (xy 260.043599 -285.992169) (xy 260.091205 -286.021223)
			(xy 260.134073 -286.056898) (xy 260.17129 -286.098435) (xy 260.202063 -286.144948) (xy 260.225735 -286.195445)
			(xy 260.241803 -286.248852) (xy 260.249923 -286.304028) (xy 260.250432 -286.331914) (xy 260.249923 -286.3598)
			(xy 260.241803 -286.414976) (xy 260.225735 -286.468383) (xy 260.202063 -286.51888) (xy 260.17129 -286.565393)
			(xy 260.134073 -286.60693) (xy 260.091205 -286.642605) (xy 260.043599 -286.671659) (xy 259.99227 -286.693471)
			(xy 259.938313 -286.707577) (xy 259.882876 -286.713677) (xy 259.827142 -286.71164) (xy 259.772299 -286.70151)
			(xy 259.719515 -286.683503) (xy 259.669915 -286.658002) (xy 259.624557 -286.625551) (xy 259.584408 -286.586842)
			(xy 259.550322 -286.542699) (xy 259.523026 -286.494064) (xy 259.503103 -286.441973) (xy 259.490977 -286.387536)
			(xy 259.486906 -286.331914) (xy 258.774946 -286.331914) (xy 258.774437 -286.3598) (xy 258.766317 -286.414976)
			(xy 258.750249 -286.468383) (xy 258.726577 -286.51888) (xy 258.695804 -286.565393) (xy 258.658587 -286.60693)
			(xy 258.615719 -286.642605) (xy 258.568113 -286.671659) (xy 258.516784 -286.693471) (xy 258.462827 -286.707577)
			(xy 258.40739 -286.713677) (xy 258.351656 -286.71164) (xy 258.296813 -286.70151) (xy 258.244029 -286.683503)
			(xy 258.194429 -286.658002) (xy 258.149071 -286.625551) (xy 258.108922 -286.586842) (xy 258.074836 -286.542699)
			(xy 258.04754 -286.494064) (xy 258.027617 -286.441973) (xy 258.015491 -286.387536) (xy 258.01142 -286.331914)
			(xy 252.171651 -286.331914) (xy 252.172951 -286.332996) (xy 252.210168 -286.374533) (xy 252.240941 -286.421046)
			(xy 252.264613 -286.471543) (xy 252.280681 -286.52495) (xy 252.288801 -286.580126) (xy 252.28931 -286.608012)
			(xy 252.288801 -286.635898) (xy 252.280681 -286.691074) (xy 252.264613 -286.744481) (xy 252.240941 -286.794978)
			(xy 252.210168 -286.841491) (xy 252.172951 -286.883028) (xy 252.130083 -286.918703) (xy 252.082477 -286.947757)
			(xy 252.031148 -286.969569) (xy 251.977191 -286.983675) (xy 251.921754 -286.989775) (xy 251.86602 -286.987738)
			(xy 251.811177 -286.977608) (xy 251.758393 -286.959601) (xy 251.708793 -286.9341) (xy 251.663435 -286.901649)
			(xy 251.623286 -286.86294) (xy 251.5892 -286.818797) (xy 251.561904 -286.770162) (xy 251.541981 -286.718071)
			(xy 251.529855 -286.663634) (xy 251.525784 -286.608012) (xy 250.565412 -286.608012) (xy 250.565412 -287.009332)
			(xy 250.565835 -287.018139) (xy 250.571883 -287.034687) (xy 250.583157 -287.048227) (xy 250.590558 -287.05302)
			(xy 250.67768 -287.104328) (xy 250.704604 -287.104582) (xy 250.716542 -287.097978) (xy 250.737906 -287.086498)
			(xy 250.782918 -287.06844) (xy 250.829858 -287.056238) (xy 250.877966 -287.050088) (xy 250.902216 -287.049718)
			(xy 250.929465 -287.050205) (xy 250.983407 -287.057963) (xy 251.035696 -287.073319) (xy 251.085268 -287.095959)
			(xy 251.131113 -287.125424) (xy 251.172299 -287.161113) (xy 251.207986 -287.2023) (xy 251.237449 -287.248146)
			(xy 251.260087 -287.297719) (xy 251.269754 -287.330642) (xy 252.350268 -287.330642) (xy 252.354339 -287.27502)
			(xy 252.366465 -287.220583) (xy 252.386388 -287.168492) (xy 252.413684 -287.119857) (xy 252.44777 -287.075714)
			(xy 252.487919 -287.037005) (xy 252.533277 -287.004554) (xy 252.582877 -286.979053) (xy 252.635661 -286.961046)
			(xy 252.690504 -286.950916) (xy 252.746238 -286.948879) (xy 252.801675 -286.954979) (xy 252.855632 -286.969085)
			(xy 252.906961 -286.990897) (xy 252.954567 -287.019951) (xy 252.997435 -287.055626) (xy 253.034652 -287.097163)
			(xy 253.065425 -287.143676) (xy 253.089097 -287.194173) (xy 253.105165 -287.24758) (xy 253.113285 -287.302756)
			(xy 253.113794 -287.330642) (xy 253.113285 -287.358528) (xy 253.105165 -287.413704) (xy 253.089097 -287.467111)
			(xy 253.065425 -287.517608) (xy 253.034652 -287.564121) (xy 252.997435 -287.605658) (xy 252.954567 -287.641333)
			(xy 252.906961 -287.670387) (xy 252.855632 -287.692199) (xy 252.801675 -287.706305) (xy 252.746238 -287.712405)
			(xy 252.690504 -287.710368) (xy 252.635661 -287.700238) (xy 252.582877 -287.682231) (xy 252.533277 -287.65673)
			(xy 252.487919 -287.624279) (xy 252.44777 -287.58557) (xy 252.413684 -287.541427) (xy 252.386388 -287.492792)
			(xy 252.366465 -287.440701) (xy 252.354339 -287.386264) (xy 252.350268 -287.330642) (xy 251.269754 -287.330642)
			(xy 251.27544 -287.350009) (xy 251.283196 -287.403951) (xy 251.283196 -287.458449) (xy 251.27544 -287.512391)
			(xy 251.260087 -287.564681) (xy 251.237449 -287.614254) (xy 251.207986 -287.6601) (xy 251.172299 -287.701287)
			(xy 251.131113 -287.736976) (xy 251.085268 -287.766441) (xy 251.035696 -287.789081) (xy 250.983407 -287.804437)
			(xy 250.929465 -287.812195) (xy 250.902216 -287.812734) (xy 250.877966 -287.812356) (xy 250.829858 -287.806209)
			(xy 250.782917 -287.794011) (xy 250.737902 -287.77596) (xy 250.716542 -287.764474) (xy 250.704604 -287.75787)
			(xy 250.67768 -287.758124) (xy 250.590558 -287.809432) (xy 250.583133 -287.814196) (xy 250.571839 -287.827731)
			(xy 250.565836 -287.844306) (xy 250.565412 -287.85312) (xy 250.565412 -288.132012) (xy 251.525784 -288.132012)
			(xy 251.529855 -288.07639) (xy 251.541981 -288.021953) (xy 251.561904 -287.969862) (xy 251.5892 -287.921227)
			(xy 251.623286 -287.877084) (xy 251.663435 -287.838375) (xy 251.708793 -287.805924) (xy 251.758393 -287.780423)
			(xy 251.811177 -287.762416) (xy 251.86602 -287.752286) (xy 251.921754 -287.750249) (xy 251.977191 -287.756349)
			(xy 252.031148 -287.770455) (xy 252.082477 -287.792267) (xy 252.130083 -287.821321) (xy 252.172951 -287.856996)
			(xy 252.210168 -287.898533) (xy 252.240941 -287.945046) (xy 252.264613 -287.995543) (xy 252.280681 -288.04895)
			(xy 252.288801 -288.104126) (xy 252.28931 -288.132012) (xy 252.288801 -288.159898) (xy 252.280681 -288.215074)
			(xy 252.276174 -288.230056) (xy 258.01142 -288.230056) (xy 258.015491 -288.174434) (xy 258.027617 -288.119997)
			(xy 258.04754 -288.067906) (xy 258.074836 -288.019271) (xy 258.108922 -287.975128) (xy 258.149071 -287.936419)
			(xy 258.194429 -287.903968) (xy 258.244029 -287.878467) (xy 258.296813 -287.86046) (xy 258.351656 -287.85033)
			(xy 258.40739 -287.848293) (xy 258.462827 -287.854393) (xy 258.516784 -287.868499) (xy 258.568113 -287.890311)
			(xy 258.615719 -287.919365) (xy 258.658587 -287.95504) (xy 258.695804 -287.996577) (xy 258.726577 -288.04309)
			(xy 258.750249 -288.093587) (xy 258.766317 -288.146994) (xy 258.774437 -288.20217) (xy 258.774946 -288.230056)
			(xy 259.496558 -288.230056) (xy 259.500629 -288.174434) (xy 259.512755 -288.119997) (xy 259.532678 -288.067906)
			(xy 259.559974 -288.019271) (xy 259.59406 -287.975128) (xy 259.634209 -287.936419) (xy 259.679567 -287.903968)
			(xy 259.729167 -287.878467) (xy 259.781951 -287.86046) (xy 259.836794 -287.85033) (xy 259.892528 -287.848293)
			(xy 259.947965 -287.854393) (xy 260.001922 -287.868499) (xy 260.053251 -287.890311) (xy 260.100857 -287.919365)
			(xy 260.143725 -287.95504) (xy 260.180942 -287.996577) (xy 260.211715 -288.04309) (xy 260.235387 -288.093587)
			(xy 260.251455 -288.146994) (xy 260.259575 -288.20217) (xy 260.260084 -288.230056) (xy 260.259575 -288.257942)
			(xy 260.251455 -288.313118) (xy 260.235387 -288.366525) (xy 260.211715 -288.417022) (xy 260.180942 -288.463535)
			(xy 260.143725 -288.505072) (xy 260.100857 -288.540747) (xy 260.053251 -288.569801) (xy 260.001922 -288.591613)
			(xy 259.947965 -288.605719) (xy 259.892528 -288.611819) (xy 259.836794 -288.609782) (xy 259.781951 -288.599652)
			(xy 259.729167 -288.581645) (xy 259.679567 -288.556144) (xy 259.634209 -288.523693) (xy 259.59406 -288.484984)
			(xy 259.559974 -288.440841) (xy 259.532678 -288.392206) (xy 259.512755 -288.340115) (xy 259.500629 -288.285678)
			(xy 259.496558 -288.230056) (xy 258.774946 -288.230056) (xy 258.774437 -288.257942) (xy 258.766317 -288.313118)
			(xy 258.750249 -288.366525) (xy 258.726577 -288.417022) (xy 258.695804 -288.463535) (xy 258.658587 -288.505072)
			(xy 258.615719 -288.540747) (xy 258.568113 -288.569801) (xy 258.516784 -288.591613) (xy 258.462827 -288.605719)
			(xy 258.40739 -288.611819) (xy 258.351656 -288.609782) (xy 258.296813 -288.599652) (xy 258.244029 -288.581645)
			(xy 258.194429 -288.556144) (xy 258.149071 -288.523693) (xy 258.108922 -288.484984) (xy 258.074836 -288.440841)
			(xy 258.04754 -288.392206) (xy 258.027617 -288.340115) (xy 258.015491 -288.285678) (xy 258.01142 -288.230056)
			(xy 252.276174 -288.230056) (xy 252.264613 -288.268481) (xy 252.240941 -288.318978) (xy 252.210168 -288.365491)
			(xy 252.172951 -288.407028) (xy 252.130083 -288.442703) (xy 252.082477 -288.471757) (xy 252.031148 -288.493569)
			(xy 251.977191 -288.507675) (xy 251.921754 -288.513775) (xy 251.86602 -288.511738) (xy 251.811177 -288.501608)
			(xy 251.758393 -288.483601) (xy 251.708793 -288.4581) (xy 251.663435 -288.425649) (xy 251.623286 -288.38694)
			(xy 251.5892 -288.342797) (xy 251.561904 -288.294162) (xy 251.541981 -288.242071) (xy 251.529855 -288.187634)
			(xy 251.525784 -288.132012) (xy 250.565412 -288.132012) (xy 250.565412 -288.627058) (xy 250.565816 -288.636713)
			(xy 250.572959 -288.654651) (xy 250.58627 -288.668636) (xy 250.594876 -288.673032) (xy 250.692158 -288.71799)
			(xy 250.721622 -288.713926) (xy 250.732798 -288.704274) (xy 250.753608 -288.687126) (xy 250.799148 -288.658252)
			(xy 250.848305 -288.636089) (xy 250.900096 -288.621079) (xy 250.953486 -288.613524) (xy 250.980448 -288.613088)
			(xy 251.007697 -288.613577) (xy 251.06164 -288.621339) (xy 251.11393 -288.636699) (xy 251.163502 -288.659343)
			(xy 251.209347 -288.688811) (xy 251.250531 -288.724503) (xy 251.286218 -288.765692) (xy 251.31568 -288.811541)
			(xy 251.338318 -288.861115) (xy 251.347977 -288.894012) (xy 252.4285 -288.894012) (xy 252.432571 -288.83839)
			(xy 252.444697 -288.783953) (xy 252.46462 -288.731862) (xy 252.491916 -288.683227) (xy 252.526002 -288.639084)
			(xy 252.566151 -288.600375) (xy 252.611509 -288.567924) (xy 252.661109 -288.542423) (xy 252.713893 -288.524416)
			(xy 252.768736 -288.514286) (xy 252.82447 -288.512249) (xy 252.879907 -288.518349) (xy 252.933864 -288.532455)
			(xy 252.985193 -288.554267) (xy 253.032799 -288.583321) (xy 253.075667 -288.618996) (xy 253.112884 -288.660533)
			(xy 253.143657 -288.707046) (xy 253.167329 -288.757543) (xy 253.183397 -288.81095) (xy 253.191517 -288.866126)
			(xy 253.192026 -288.894012) (xy 253.191517 -288.921898) (xy 253.183397 -288.977074) (xy 253.167329 -289.030481)
			(xy 253.143657 -289.080978) (xy 253.112884 -289.127491) (xy 253.075667 -289.169028) (xy 253.032799 -289.204703)
			(xy 252.985193 -289.233757) (xy 252.933864 -289.255569) (xy 252.879907 -289.269675) (xy 252.82447 -289.275775)
			(xy 252.768736 -289.273738) (xy 252.713893 -289.263608) (xy 252.661109 -289.245601) (xy 252.611509 -289.2201)
			(xy 252.566151 -289.187649) (xy 252.526002 -289.14894) (xy 252.491916 -289.104797) (xy 252.46462 -289.056162)
			(xy 252.444697 -289.004071) (xy 252.432571 -288.949634) (xy 252.4285 -288.894012) (xy 251.347977 -288.894012)
			(xy 251.353671 -288.913407) (xy 251.361426 -288.967351) (xy 251.361426 -289.021849) (xy 251.353671 -289.075793)
			(xy 251.338318 -289.128085) (xy 251.31568 -289.177659) (xy 251.286218 -289.223508) (xy 251.250531 -289.264697)
			(xy 251.209347 -289.300389) (xy 251.163502 -289.329857) (xy 251.11393 -289.352501) (xy 251.06164 -289.367861)
			(xy 251.007697 -289.375623) (xy 250.980448 -289.376104) (xy 250.953492 -289.375631) (xy 250.900118 -289.368033)
			(xy 250.848341 -289.353011) (xy 250.799188 -289.330861) (xy 250.753636 -289.302025) (xy 250.732798 -289.284918)
			(xy 250.721622 -289.275266) (xy 250.692158 -289.271202) (xy 250.594876 -289.31616) (xy 250.586321 -289.320612)
			(xy 250.573083 -289.334615) (xy 250.565913 -289.352501) (xy 250.565412 -289.362134) (xy 250.565412 -289.656012)
			(xy 251.525784 -289.656012) (xy 251.529855 -289.60039) (xy 251.541981 -289.545953) (xy 251.561904 -289.493862)
			(xy 251.5892 -289.445227) (xy 251.623286 -289.401084) (xy 251.663435 -289.362375) (xy 251.708793 -289.329924)
			(xy 251.758393 -289.304423) (xy 251.811177 -289.286416) (xy 251.86602 -289.276286) (xy 251.921754 -289.274249)
			(xy 251.977191 -289.280349) (xy 252.031148 -289.294455) (xy 252.082477 -289.316267) (xy 252.130083 -289.345321)
			(xy 252.172951 -289.380996) (xy 252.210168 -289.422533) (xy 252.240941 -289.469046) (xy 252.264613 -289.519543)
			(xy 252.268455 -289.532314) (xy 258.01142 -289.532314) (xy 258.015491 -289.476692) (xy 258.027617 -289.422255)
			(xy 258.04754 -289.370164) (xy 258.074836 -289.321529) (xy 258.108922 -289.277386) (xy 258.149071 -289.238677)
			(xy 258.194429 -289.206226) (xy 258.244029 -289.180725) (xy 258.296813 -289.162718) (xy 258.351656 -289.152588)
			(xy 258.40739 -289.150551) (xy 258.462827 -289.156651) (xy 258.516784 -289.170757) (xy 258.568113 -289.192569)
			(xy 258.615719 -289.221623) (xy 258.658587 -289.257298) (xy 258.695804 -289.298835) (xy 258.726577 -289.345348)
			(xy 258.750249 -289.395845) (xy 258.766317 -289.449252) (xy 258.774437 -289.504428) (xy 258.774946 -289.532314)
			(xy 259.486906 -289.532314) (xy 259.490977 -289.476692) (xy 259.503103 -289.422255) (xy 259.523026 -289.370164)
			(xy 259.550322 -289.321529) (xy 259.584408 -289.277386) (xy 259.624557 -289.238677) (xy 259.669915 -289.206226)
			(xy 259.719515 -289.180725) (xy 259.772299 -289.162718) (xy 259.827142 -289.152588) (xy 259.882876 -289.150551)
			(xy 259.938313 -289.156651) (xy 259.99227 -289.170757) (xy 260.043599 -289.192569) (xy 260.091205 -289.221623)
			(xy 260.134073 -289.257298) (xy 260.17129 -289.298835) (xy 260.202063 -289.345348) (xy 260.225735 -289.395845)
			(xy 260.241803 -289.449252) (xy 260.249923 -289.504428) (xy 260.250432 -289.532314) (xy 260.249923 -289.5602)
			(xy 260.241803 -289.615376) (xy 260.225735 -289.668783) (xy 260.202063 -289.71928) (xy 260.17129 -289.765793)
			(xy 260.134073 -289.80733) (xy 260.091205 -289.843005) (xy 260.043599 -289.872059) (xy 259.99227 -289.893871)
			(xy 259.938313 -289.907977) (xy 259.882876 -289.914077) (xy 259.827142 -289.91204) (xy 259.772299 -289.90191)
			(xy 259.719515 -289.883903) (xy 259.669915 -289.858402) (xy 259.624557 -289.825951) (xy 259.584408 -289.787242)
			(xy 259.550322 -289.743099) (xy 259.523026 -289.694464) (xy 259.503103 -289.642373) (xy 259.490977 -289.587936)
			(xy 259.486906 -289.532314) (xy 258.774946 -289.532314) (xy 258.774437 -289.5602) (xy 258.766317 -289.615376)
			(xy 258.750249 -289.668783) (xy 258.726577 -289.71928) (xy 258.695804 -289.765793) (xy 258.658587 -289.80733)
			(xy 258.615719 -289.843005) (xy 258.568113 -289.872059) (xy 258.516784 -289.893871) (xy 258.462827 -289.907977)
			(xy 258.40739 -289.914077) (xy 258.351656 -289.91204) (xy 258.296813 -289.90191) (xy 258.244029 -289.883903)
			(xy 258.194429 -289.858402) (xy 258.149071 -289.825951) (xy 258.108922 -289.787242) (xy 258.074836 -289.743099)
			(xy 258.04754 -289.694464) (xy 258.027617 -289.642373) (xy 258.015491 -289.587936) (xy 258.01142 -289.532314)
			(xy 252.268455 -289.532314) (xy 252.280681 -289.57295) (xy 252.288801 -289.628126) (xy 252.28931 -289.656012)
			(xy 252.288801 -289.683898) (xy 252.280681 -289.739074) (xy 252.264613 -289.792481) (xy 252.240941 -289.842978)
			(xy 252.210168 -289.889491) (xy 252.172951 -289.931028) (xy 252.130083 -289.966703) (xy 252.082477 -289.995757)
			(xy 252.031148 -290.017569) (xy 251.977191 -290.031675) (xy 251.921754 -290.037775) (xy 251.86602 -290.035738)
			(xy 251.811177 -290.025608) (xy 251.758393 -290.007601) (xy 251.708793 -289.9821) (xy 251.663435 -289.949649)
			(xy 251.623286 -289.91094) (xy 251.5892 -289.866797) (xy 251.561904 -289.818162) (xy 251.541981 -289.766071)
			(xy 251.529855 -289.711634) (xy 251.525784 -289.656012) (xy 250.565412 -289.656012) (xy 250.565412 -291.430456)
			(xy 258.01142 -291.430456) (xy 258.015491 -291.374834) (xy 258.027617 -291.320397) (xy 258.04754 -291.268306)
			(xy 258.074836 -291.219671) (xy 258.108922 -291.175528) (xy 258.149071 -291.136819) (xy 258.194429 -291.104368)
			(xy 258.244029 -291.078867) (xy 258.296813 -291.06086) (xy 258.351656 -291.05073) (xy 258.40739 -291.048693)
			(xy 258.462827 -291.054793) (xy 258.516784 -291.068899) (xy 258.568113 -291.090711) (xy 258.615719 -291.119765)
			(xy 258.658587 -291.15544) (xy 258.695804 -291.196977) (xy 258.726577 -291.24349) (xy 258.750249 -291.293987)
			(xy 258.766317 -291.347394) (xy 258.774437 -291.40257) (xy 258.774946 -291.430456) (xy 259.496558 -291.430456)
			(xy 259.500629 -291.374834) (xy 259.512755 -291.320397) (xy 259.532678 -291.268306) (xy 259.559974 -291.219671)
			(xy 259.59406 -291.175528) (xy 259.634209 -291.136819) (xy 259.679567 -291.104368) (xy 259.729167 -291.078867)
			(xy 259.781951 -291.06086) (xy 259.836794 -291.05073) (xy 259.892528 -291.048693) (xy 259.947965 -291.054793)
			(xy 260.001922 -291.068899) (xy 260.053251 -291.090711) (xy 260.100857 -291.119765) (xy 260.143725 -291.15544)
			(xy 260.180942 -291.196977) (xy 260.211715 -291.24349) (xy 260.235387 -291.293987) (xy 260.251455 -291.347394)
			(xy 260.259575 -291.40257) (xy 260.260084 -291.430456) (xy 260.259575 -291.458342) (xy 260.251455 -291.513518)
			(xy 260.235387 -291.566925) (xy 260.211715 -291.617422) (xy 260.180942 -291.663935) (xy 260.143725 -291.705472)
			(xy 260.100857 -291.741147) (xy 260.053251 -291.770201) (xy 260.001922 -291.792013) (xy 259.947965 -291.806119)
			(xy 259.892528 -291.812219) (xy 259.836794 -291.810182) (xy 259.781951 -291.800052) (xy 259.729167 -291.782045)
			(xy 259.679567 -291.756544) (xy 259.634209 -291.724093) (xy 259.59406 -291.685384) (xy 259.559974 -291.641241)
			(xy 259.532678 -291.592606) (xy 259.512755 -291.540515) (xy 259.500629 -291.486078) (xy 259.496558 -291.430456)
			(xy 258.774946 -291.430456) (xy 258.774437 -291.458342) (xy 258.766317 -291.513518) (xy 258.750249 -291.566925)
			(xy 258.726577 -291.617422) (xy 258.695804 -291.663935) (xy 258.658587 -291.705472) (xy 258.615719 -291.741147)
			(xy 258.568113 -291.770201) (xy 258.516784 -291.792013) (xy 258.462827 -291.806119) (xy 258.40739 -291.812219)
			(xy 258.351656 -291.810182) (xy 258.296813 -291.800052) (xy 258.244029 -291.782045) (xy 258.194429 -291.756544)
			(xy 258.149071 -291.724093) (xy 258.108922 -291.685384) (xy 258.074836 -291.641241) (xy 258.04754 -291.592606)
			(xy 258.027617 -291.540515) (xy 258.015491 -291.486078) (xy 258.01142 -291.430456) (xy 250.565412 -291.430456)
			(xy 250.565412 -292.732714) (xy 258.01142 -292.732714) (xy 258.015491 -292.677092) (xy 258.027617 -292.622655)
			(xy 258.04754 -292.570564) (xy 258.074836 -292.521929) (xy 258.108922 -292.477786) (xy 258.149071 -292.439077)
			(xy 258.194429 -292.406626) (xy 258.244029 -292.381125) (xy 258.296813 -292.363118) (xy 258.351656 -292.352988)
			(xy 258.40739 -292.350951) (xy 258.462827 -292.357051) (xy 258.516784 -292.371157) (xy 258.568113 -292.392969)
			(xy 258.615719 -292.422023) (xy 258.658587 -292.457698) (xy 258.695804 -292.499235) (xy 258.726577 -292.545748)
			(xy 258.750249 -292.596245) (xy 258.766317 -292.649652) (xy 258.774437 -292.704828) (xy 258.774946 -292.732714)
			(xy 259.486906 -292.732714) (xy 259.490977 -292.677092) (xy 259.503103 -292.622655) (xy 259.523026 -292.570564)
			(xy 259.550322 -292.521929) (xy 259.584408 -292.477786) (xy 259.624557 -292.439077) (xy 259.669915 -292.406626)
			(xy 259.719515 -292.381125) (xy 259.772299 -292.363118) (xy 259.827142 -292.352988) (xy 259.882876 -292.350951)
			(xy 259.938313 -292.357051) (xy 259.99227 -292.371157) (xy 260.043599 -292.392969) (xy 260.091205 -292.422023)
			(xy 260.134073 -292.457698) (xy 260.17129 -292.499235) (xy 260.202063 -292.545748) (xy 260.225735 -292.596245)
			(xy 260.241803 -292.649652) (xy 260.249923 -292.704828) (xy 260.250432 -292.732714) (xy 260.249923 -292.7606)
			(xy 260.241803 -292.815776) (xy 260.225735 -292.869183) (xy 260.202063 -292.91968) (xy 260.17129 -292.966193)
			(xy 260.134073 -293.00773) (xy 260.091205 -293.043405) (xy 260.043599 -293.072459) (xy 259.99227 -293.094271)
			(xy 259.938313 -293.108377) (xy 259.882876 -293.114477) (xy 259.827142 -293.11244) (xy 259.772299 -293.10231)
			(xy 259.719515 -293.084303) (xy 259.669915 -293.058802) (xy 259.624557 -293.026351) (xy 259.584408 -292.987642)
			(xy 259.550322 -292.943499) (xy 259.523026 -292.894864) (xy 259.503103 -292.842773) (xy 259.490977 -292.788336)
			(xy 259.486906 -292.732714) (xy 258.774946 -292.732714) (xy 258.774437 -292.7606) (xy 258.766317 -292.815776)
			(xy 258.750249 -292.869183) (xy 258.726577 -292.91968) (xy 258.695804 -292.966193) (xy 258.658587 -293.00773)
			(xy 258.615719 -293.043405) (xy 258.568113 -293.072459) (xy 258.516784 -293.094271) (xy 258.462827 -293.108377)
			(xy 258.40739 -293.114477) (xy 258.351656 -293.11244) (xy 258.296813 -293.10231) (xy 258.244029 -293.084303)
			(xy 258.194429 -293.058802) (xy 258.149071 -293.026351) (xy 258.108922 -292.987642) (xy 258.074836 -292.943499)
			(xy 258.04754 -292.894864) (xy 258.027617 -292.842773) (xy 258.015491 -292.788336) (xy 258.01142 -292.732714)
			(xy 250.565412 -292.732714) (xy 250.565412 -294.092376) (xy 250.565849 -294.10244) (xy 250.573584 -294.121023)
			(xy 250.580398 -294.128444) (xy 250.798838 -294.346884) (xy 250.830842 -294.351964) (xy 250.845574 -294.344598)
			(xy 250.923386 -294.306526) (xy 251.082271 -294.23745) (xy 251.244486 -294.176608) (xy 251.409606 -294.124158)
			(xy 251.577198 -294.08024) (xy 251.74682 -294.044968) (xy 251.918026 -294.018436) (xy 252.090368 -294.000712)
			(xy 252.263391 -293.991845) (xy 252.350016 -293.991284) (xy 252.429673 -293.991743) (xy 252.58881 -293.999234)
			(xy 252.747418 -294.01422) (xy 252.905143 -294.036665) (xy 253.061634 -294.06652) (xy 253.216544 -294.103719)
			(xy 253.369528 -294.148179) (xy 253.520246 -294.199801) (xy 253.668364 -294.258471) (xy 253.813551 -294.324058)
			(xy 253.955485 -294.396415) (xy 254.09385 -294.475383) (xy 254.228339 -294.560786) (xy 254.327972 -294.630856)
			(xy 258.01142 -294.630856) (xy 258.015491 -294.575234) (xy 258.027617 -294.520797) (xy 258.04754 -294.468706)
			(xy 258.074836 -294.420071) (xy 258.108922 -294.375928) (xy 258.149071 -294.337219) (xy 258.194429 -294.304768)
			(xy 258.244029 -294.279267) (xy 258.296813 -294.26126) (xy 258.351656 -294.25113) (xy 258.40739 -294.249093)
			(xy 258.462827 -294.255193) (xy 258.516784 -294.269299) (xy 258.568113 -294.291111) (xy 258.615719 -294.320165)
			(xy 258.658587 -294.35584) (xy 258.695804 -294.397377) (xy 258.726577 -294.44389) (xy 258.750249 -294.494387)
			(xy 258.766317 -294.547794) (xy 258.774437 -294.60297) (xy 258.774946 -294.630856) (xy 259.496558 -294.630856)
			(xy 259.500629 -294.575234) (xy 259.512755 -294.520797) (xy 259.532678 -294.468706) (xy 259.559974 -294.420071)
			(xy 259.59406 -294.375928) (xy 259.634209 -294.337219) (xy 259.679567 -294.304768) (xy 259.729167 -294.279267)
			(xy 259.781951 -294.26126) (xy 259.836794 -294.25113) (xy 259.892528 -294.249093) (xy 259.947965 -294.255193)
			(xy 260.001922 -294.269299) (xy 260.053251 -294.291111) (xy 260.100857 -294.320165) (xy 260.143725 -294.35584)
			(xy 260.180942 -294.397377) (xy 260.211715 -294.44389) (xy 260.235387 -294.494387) (xy 260.251455 -294.547794)
			(xy 260.259575 -294.60297) (xy 260.260084 -294.630856) (xy 260.259575 -294.658742) (xy 260.251455 -294.713918)
			(xy 260.235387 -294.767325) (xy 260.211715 -294.817822) (xy 260.180942 -294.864335) (xy 260.143725 -294.905872)
			(xy 260.100857 -294.941547) (xy 260.053251 -294.970601) (xy 260.001922 -294.992413) (xy 259.947965 -295.006519)
			(xy 259.892528 -295.012619) (xy 259.836794 -295.010582) (xy 259.781951 -295.000452) (xy 259.729167 -294.982445)
			(xy 259.679567 -294.956944) (xy 259.634209 -294.924493) (xy 259.59406 -294.885784) (xy 259.559974 -294.841641)
			(xy 259.532678 -294.793006) (xy 259.512755 -294.740915) (xy 259.500629 -294.686478) (xy 259.496558 -294.630856)
			(xy 258.774946 -294.630856) (xy 258.774437 -294.658742) (xy 258.766317 -294.713918) (xy 258.750249 -294.767325)
			(xy 258.726577 -294.817822) (xy 258.695804 -294.864335) (xy 258.658587 -294.905872) (xy 258.615719 -294.941547)
			(xy 258.568113 -294.970601) (xy 258.516784 -294.992413) (xy 258.462827 -295.006519) (xy 258.40739 -295.012619)
			(xy 258.351656 -295.010582) (xy 258.296813 -295.000452) (xy 258.244029 -294.982445) (xy 258.194429 -294.956944)
			(xy 258.149071 -294.924493) (xy 258.108922 -294.885784) (xy 258.074836 -294.841641) (xy 258.04754 -294.793006)
			(xy 258.027617 -294.740915) (xy 258.015491 -294.686478) (xy 258.01142 -294.630856) (xy 254.327972 -294.630856)
			(xy 254.358652 -294.652433) (xy 254.484501 -294.750122) (xy 254.545338 -294.801544) (xy 254.607615 -294.855333)
			(xy 254.727469 -294.968117) (xy 254.84169 -295.086603) (xy 254.950007 -295.210509) (xy 255.052163 -295.339542)
			(xy 255.147916 -295.473396) (xy 255.237038 -295.611752) (xy 255.319318 -295.754284) (xy 255.394561 -295.900653)
			(xy 255.409297 -295.933114) (xy 258.01142 -295.933114) (xy 258.015491 -295.877492) (xy 258.027617 -295.823055)
			(xy 258.04754 -295.770964) (xy 258.074836 -295.722329) (xy 258.108922 -295.678186) (xy 258.149071 -295.639477)
			(xy 258.194429 -295.607026) (xy 258.244029 -295.581525) (xy 258.296813 -295.563518) (xy 258.351656 -295.553388)
			(xy 258.40739 -295.551351) (xy 258.462827 -295.557451) (xy 258.516784 -295.571557) (xy 258.568113 -295.593369)
			(xy 258.615719 -295.622423) (xy 258.658587 -295.658098) (xy 258.695804 -295.699635) (xy 258.726577 -295.746148)
			(xy 258.750249 -295.796645) (xy 258.766317 -295.850052) (xy 258.774437 -295.905228) (xy 258.774946 -295.933114)
			(xy 259.486906 -295.933114) (xy 259.490977 -295.877492) (xy 259.503103 -295.823055) (xy 259.523026 -295.770964)
			(xy 259.550322 -295.722329) (xy 259.584408 -295.678186) (xy 259.624557 -295.639477) (xy 259.669915 -295.607026)
			(xy 259.719515 -295.581525) (xy 259.772299 -295.563518) (xy 259.827142 -295.553388) (xy 259.882876 -295.551351)
			(xy 259.938313 -295.557451) (xy 259.99227 -295.571557) (xy 260.043599 -295.593369) (xy 260.091205 -295.622423)
			(xy 260.134073 -295.658098) (xy 260.17129 -295.699635) (xy 260.202063 -295.746148) (xy 260.225735 -295.796645)
			(xy 260.241803 -295.850052) (xy 260.249923 -295.905228) (xy 260.250432 -295.933114) (xy 260.249923 -295.961)
			(xy 260.241803 -296.016176) (xy 260.225735 -296.069583) (xy 260.202063 -296.12008) (xy 260.17129 -296.166593)
			(xy 260.134073 -296.20813) (xy 260.091205 -296.243805) (xy 260.043599 -296.272859) (xy 259.99227 -296.294671)
			(xy 259.938313 -296.308777) (xy 259.882876 -296.314877) (xy 259.827142 -296.31284) (xy 259.772299 -296.30271)
			(xy 259.719515 -296.284703) (xy 259.669915 -296.259202) (xy 259.624557 -296.226751) (xy 259.584408 -296.188042)
			(xy 259.550322 -296.143899) (xy 259.523026 -296.095264) (xy 259.503103 -296.043173) (xy 259.490977 -295.988736)
			(xy 259.486906 -295.933114) (xy 258.774946 -295.933114) (xy 258.774437 -295.961) (xy 258.766317 -296.016176)
			(xy 258.750249 -296.069583) (xy 258.726577 -296.12008) (xy 258.695804 -296.166593) (xy 258.658587 -296.20813)
			(xy 258.615719 -296.243805) (xy 258.568113 -296.272859) (xy 258.516784 -296.294671) (xy 258.462827 -296.308777)
			(xy 258.40739 -296.314877) (xy 258.351656 -296.31284) (xy 258.296813 -296.30271) (xy 258.244029 -296.284703)
			(xy 258.194429 -296.259202) (xy 258.149071 -296.226751) (xy 258.108922 -296.188042) (xy 258.074836 -296.143899)
			(xy 258.04754 -296.095264) (xy 258.027617 -296.043173) (xy 258.015491 -295.988736) (xy 258.01142 -295.933114)
			(xy 255.409297 -295.933114) (xy 255.462589 -296.050512) (xy 255.52324 -296.203505) (xy 255.57637 -296.359269)
			(xy 255.621853 -296.517435) (xy 255.659582 -296.677629) (xy 255.689467 -296.839469) (xy 255.711437 -297.002572)
			(xy 255.72544 -297.166552) (xy 255.731442 -297.331018) (xy 255.72943 -297.495582) (xy 255.719409 -297.659853)
			(xy 255.701401 -297.823441) (xy 255.700153 -297.831256) (xy 258.01142 -297.831256) (xy 258.015491 -297.775634)
			(xy 258.027617 -297.721197) (xy 258.04754 -297.669106) (xy 258.074836 -297.620471) (xy 258.108922 -297.576328)
			(xy 258.149071 -297.537619) (xy 258.194429 -297.505168) (xy 258.244029 -297.479667) (xy 258.296813 -297.46166)
			(xy 258.351656 -297.45153) (xy 258.40739 -297.449493) (xy 258.462827 -297.455593) (xy 258.516784 -297.469699)
			(xy 258.568113 -297.491511) (xy 258.615719 -297.520565) (xy 258.658587 -297.55624) (xy 258.695804 -297.597777)
			(xy 258.726577 -297.64429) (xy 258.750249 -297.694787) (xy 258.766317 -297.748194) (xy 258.774437 -297.80337)
			(xy 258.774946 -297.831256) (xy 258.774437 -297.859142) (xy 258.766317 -297.914318) (xy 258.750249 -297.967725)
			(xy 258.726577 -298.018222) (xy 258.695804 -298.064735) (xy 258.658587 -298.106272) (xy 258.615719 -298.141947)
			(xy 258.568113 -298.171001) (xy 258.516784 -298.192813) (xy 258.462827 -298.206919) (xy 258.40739 -298.213019)
			(xy 258.351656 -298.210982) (xy 258.296813 -298.200852) (xy 258.244029 -298.182845) (xy 258.194429 -298.157344)
			(xy 258.149071 -298.124893) (xy 258.108922 -298.086184) (xy 258.074836 -298.042041) (xy 258.04754 -297.993406)
			(xy 258.027617 -297.941315) (xy 258.015491 -297.886878) (xy 258.01142 -297.831256) (xy 255.700153 -297.831256)
			(xy 255.67545 -297.985959) (xy 255.641617 -298.14702) (xy 255.599983 -298.306243) (xy 255.550646 -298.46325)
			(xy 255.493724 -298.617669) (xy 255.429351 -298.769133) (xy 255.357679 -298.917284) (xy 255.27888 -299.061769)
			(xy 255.235091 -299.133514) (xy 258.01142 -299.133514) (xy 258.015491 -299.077892) (xy 258.027617 -299.023455)
			(xy 258.04754 -298.971364) (xy 258.074836 -298.922729) (xy 258.108922 -298.878586) (xy 258.149071 -298.839877)
			(xy 258.194429 -298.807426) (xy 258.244029 -298.781925) (xy 258.296813 -298.763918) (xy 258.351656 -298.753788)
			(xy 258.40739 -298.751751) (xy 258.462827 -298.757851) (xy 258.516784 -298.771957) (xy 258.568113 -298.793769)
			(xy 258.615719 -298.822823) (xy 258.658587 -298.858498) (xy 258.695804 -298.900035) (xy 258.726577 -298.946548)
			(xy 258.750249 -298.997045) (xy 258.766317 -299.050452) (xy 258.774437 -299.105628) (xy 258.774946 -299.133514)
			(xy 259.487416 -299.133514) (xy 259.487921 -299.105172) (xy 259.496306 -299.049112) (xy 259.512894 -298.994909)
			(xy 259.53732 -298.943758) (xy 259.569045 -298.896784) (xy 259.607372 -298.855021) (xy 259.651457 -298.819389)
			(xy 259.67563 -298.804584) (xy 259.68821 -298.796603) (xy 259.708492 -298.774803) (xy 259.721622 -298.748078)
			(xy 259.726483 -298.718702) (xy 259.722662 -298.689172) (xy 259.710483 -298.662001) (xy 259.690983 -298.639499)
			(xy 259.678678 -298.631102) (xy 259.655814 -298.615989) (xy 259.614221 -298.580303) (xy 259.578163 -298.539032)
			(xy 259.548382 -298.493025) (xy 259.525492 -298.44323) (xy 259.509964 -298.390672) (xy 259.502116 -298.336432)
			(xy 259.50164 -298.30903) (xy 259.502126 -298.281779) (xy 259.509882 -298.227831) (xy 259.525237 -298.175536)
			(xy 259.547879 -298.125959) (xy 259.577345 -298.080109) (xy 259.613036 -298.038918) (xy 259.654227 -298.003227)
			(xy 259.700077 -297.973761) (xy 259.749654 -297.951119) (xy 259.801949 -297.935764) (xy 259.855897 -297.928008)
			(xy 259.910399 -297.928008) (xy 259.964347 -297.935764) (xy 260.016642 -297.951119) (xy 260.066219 -297.973761)
			(xy 260.112069 -298.003227) (xy 260.15326 -298.038918) (xy 260.188951 -298.080109) (xy 260.218417 -298.125959)
			(xy 260.241059 -298.175536) (xy 260.256414 -298.227831) (xy 260.26417 -298.281779) (xy 260.264656 -298.30903)
			(xy 260.264121 -298.337371) (xy 260.255743 -298.393431) (xy 260.239161 -298.447633) (xy 260.214741 -298.498785)
			(xy 260.18302 -298.54576) (xy 260.144696 -298.587523) (xy 260.100614 -298.623155) (xy 260.076442 -298.63796)
			(xy 260.063824 -298.645884) (xy 260.043544 -298.667698) (xy 260.030419 -298.694434) (xy 260.025564 -298.72382)
			(xy 260.029393 -298.753358) (xy 260.041578 -298.780535) (xy 260.061086 -298.803043) (xy 260.073394 -298.811442)
			(xy 260.096271 -298.826535) (xy 260.137866 -298.862224) (xy 260.173924 -298.903498) (xy 260.203704 -298.949508)
			(xy 260.226592 -298.999306) (xy 260.242117 -299.051868) (xy 260.249959 -299.106111) (xy 260.250432 -299.133514)
			(xy 260.249946 -299.160765) (xy 260.24219 -299.214713) (xy 260.226835 -299.267008) (xy 260.204193 -299.316585)
			(xy 260.174727 -299.362435) (xy 260.139036 -299.403626) (xy 260.097845 -299.439317) (xy 260.051995 -299.468783)
			(xy 260.002418 -299.491425) (xy 259.950123 -299.50678) (xy 259.896175 -299.514536) (xy 259.841673 -299.514536)
			(xy 259.787725 -299.50678) (xy 259.73543 -299.491425) (xy 259.685853 -299.468783) (xy 259.640003 -299.439317)
			(xy 259.598812 -299.403626) (xy 259.563121 -299.362435) (xy 259.533655 -299.316585) (xy 259.511013 -299.267008)
			(xy 259.495658 -299.214713) (xy 259.487902 -299.160765) (xy 259.487416 -299.133514) (xy 258.774946 -299.133514)
			(xy 258.774437 -299.1614) (xy 258.766317 -299.216576) (xy 258.750249 -299.269983) (xy 258.726577 -299.32048)
			(xy 258.695804 -299.366993) (xy 258.658587 -299.40853) (xy 258.615719 -299.444205) (xy 258.568113 -299.473259)
			(xy 258.516784 -299.495071) (xy 258.462827 -299.509177) (xy 258.40739 -299.515277) (xy 258.351656 -299.51324)
			(xy 258.296813 -299.50311) (xy 258.244029 -299.485103) (xy 258.194429 -299.459602) (xy 258.149071 -299.427151)
			(xy 258.108922 -299.388442) (xy 258.074836 -299.344299) (xy 258.04754 -299.295664) (xy 258.027617 -299.243573)
			(xy 258.015491 -299.189136) (xy 258.01142 -299.133514) (xy 255.235091 -299.133514) (xy 255.19314 -299.202247)
			(xy 255.100662 -299.338383) (xy 255.001665 -299.469856) (xy 254.896385 -299.596353) (xy 254.785071 -299.717574)
			(xy 254.667987 -299.833232) (xy 254.545411 -299.943052) (xy 254.417634 -300.046774) (xy 254.284958 -300.144152)
			(xy 254.147698 -300.234955) (xy 254.006181 -300.318967) (xy 253.86074 -300.39599) (xy 253.711723 -300.46584)
			(xy 253.559481 -300.528353) (xy 253.404376 -300.583379) (xy 253.246776 -300.630788) (xy 253.087055 -300.670468)
			(xy 252.925591 -300.702324) (xy 252.762768 -300.726282) (xy 252.598972 -300.742283) (xy 252.43459 -300.750291)
			(xy 252.352302 -300.750732) (xy 252.269019 -300.750223) (xy 252.102655 -300.742016) (xy 251.936898 -300.725621)
			(xy 251.77215 -300.701079) (xy 251.608811 -300.66845) (xy 251.447278 -300.627811) (xy 251.287944 -300.579263)
			(xy 251.131195 -300.522923) (xy 251.054108 -300.491398) (xy 251.04217 -300.486318) (xy 251.017024 -300.488858)
			(xy 250.935998 -300.54296) (xy 250.925923 -300.55047) (xy 250.914039 -300.572578) (xy 250.913392 -300.585124)
			(xy 250.913392 -301.031656) (xy 258.01142 -301.031656) (xy 258.015491 -300.976034) (xy 258.027617 -300.921597)
			(xy 258.04754 -300.869506) (xy 258.074836 -300.820871) (xy 258.108922 -300.776728) (xy 258.149071 -300.738019)
			(xy 258.194429 -300.705568) (xy 258.244029 -300.680067) (xy 258.296813 -300.66206) (xy 258.351656 -300.65193)
			(xy 258.40739 -300.649893) (xy 258.462827 -300.655993) (xy 258.516784 -300.670099) (xy 258.568113 -300.691911)
			(xy 258.615719 -300.720965) (xy 258.658587 -300.75664) (xy 258.695804 -300.798177) (xy 258.726577 -300.84469)
			(xy 258.750249 -300.895187) (xy 258.766317 -300.948594) (xy 258.767028 -300.953424) (xy 259.495288 -300.953424)
			(xy 259.499359 -300.897802) (xy 259.511485 -300.843365) (xy 259.531408 -300.791274) (xy 259.558704 -300.742639)
			(xy 259.59279 -300.698496) (xy 259.632939 -300.659787) (xy 259.678297 -300.627336) (xy 259.727897 -300.601835)
			(xy 259.780681 -300.583828) (xy 259.835524 -300.573698) (xy 259.891258 -300.571661) (xy 259.946695 -300.577761)
			(xy 260.000652 -300.591867) (xy 260.051981 -300.613679) (xy 260.099587 -300.642733) (xy 260.142455 -300.678408)
			(xy 260.179672 -300.719945) (xy 260.210445 -300.766458) (xy 260.234117 -300.816955) (xy 260.250185 -300.870362)
			(xy 260.258305 -300.925538) (xy 260.258814 -300.953424) (xy 260.258305 -300.98131) (xy 260.250185 -301.036486)
			(xy 260.234117 -301.089893) (xy 260.210445 -301.14039) (xy 260.179672 -301.186903) (xy 260.142455 -301.22844)
			(xy 260.099587 -301.264115) (xy 260.051981 -301.293169) (xy 260.000652 -301.314981) (xy 259.946695 -301.329087)
			(xy 259.891258 -301.335187) (xy 259.835524 -301.33315) (xy 259.780681 -301.32302) (xy 259.727897 -301.305013)
			(xy 259.678297 -301.279512) (xy 259.632939 -301.247061) (xy 259.59279 -301.208352) (xy 259.558704 -301.164209)
			(xy 259.531408 -301.115574) (xy 259.511485 -301.063483) (xy 259.499359 -301.009046) (xy 259.495288 -300.953424)
			(xy 258.767028 -300.953424) (xy 258.774437 -301.00377) (xy 258.774946 -301.031656) (xy 258.774437 -301.059542)
			(xy 258.766317 -301.114718) (xy 258.750249 -301.168125) (xy 258.726577 -301.218622) (xy 258.695804 -301.265135)
			(xy 258.658587 -301.306672) (xy 258.615719 -301.342347) (xy 258.568113 -301.371401) (xy 258.516784 -301.393213)
			(xy 258.462827 -301.407319) (xy 258.40739 -301.413419) (xy 258.351656 -301.411382) (xy 258.296813 -301.401252)
			(xy 258.244029 -301.383245) (xy 258.194429 -301.357744) (xy 258.149071 -301.325293) (xy 258.108922 -301.286584)
			(xy 258.074836 -301.242441) (xy 258.04754 -301.193806) (xy 258.027617 -301.141715) (xy 258.015491 -301.087278)
			(xy 258.01142 -301.031656) (xy 250.913392 -301.031656) (xy 250.913392 -306.244344) (xy 258.80912 -306.244344)
			(xy 258.809122 -306.189831) (xy 258.816882 -306.135873) (xy 258.832242 -306.083569) (xy 258.85489 -306.033984)
			(xy 258.884365 -305.988127) (xy 258.920065 -305.946931) (xy 258.961266 -305.911235) (xy 259.007127 -305.881767)
			(xy 259.056715 -305.859125) (xy 259.109021 -305.843772) (xy 259.16298 -305.836018) (xy 259.190236 -305.835558)
			(xy 259.219446 -305.836574) (xy 259.233236 -305.837162) (xy 259.260291 -305.831747) (xy 259.28491 -305.81929)
			(xy 259.305298 -305.800699) (xy 259.319966 -305.77733) (xy 259.327847 -305.750888) (xy 259.328363 -305.723302)
			(xy 259.325364 -305.709828) (xy 259.31965 -305.686238) (xy 259.313536 -305.638086) (xy 259.313172 -305.613816)
			(xy 259.313638 -305.586561) (xy 259.321393 -305.532607) (xy 259.336748 -305.480305) (xy 259.35939 -305.430721)
			(xy 259.388859 -305.384864) (xy 259.424554 -305.343668) (xy 259.465748 -305.307971) (xy 259.511603 -305.2785)
			(xy 259.561186 -305.255855) (xy 259.613487 -305.240497) (xy 259.667441 -305.232739) (xy 259.721951 -305.232739)
			(xy 259.775905 -305.240496) (xy 259.828206 -305.255852) (xy 259.877789 -305.278496) (xy 259.923645 -305.307966)
			(xy 259.964841 -305.343662) (xy 260.000536 -305.384858) (xy 260.030006 -305.430714) (xy 260.052649 -305.480298)
			(xy 260.068005 -305.532599) (xy 260.075762 -305.586553) (xy 260.075761 -305.641063) (xy 260.068002 -305.695017)
			(xy 260.052643 -305.747317) (xy 260.029998 -305.7969) (xy 260.000527 -305.842755) (xy 259.964829 -305.883949)
			(xy 259.923633 -305.919643) (xy 259.877775 -305.949111) (xy 259.828191 -305.971753) (xy 259.775889 -305.987108)
			(xy 259.721935 -305.994863) (xy 259.69468 -305.995324) (xy 259.66547 -305.994308) (xy 259.65168 -305.993757)
			(xy 259.62463 -305.999167) (xy 259.600013 -306.011618) (xy 259.579627 -306.030203) (xy 259.564957 -306.053565)
			(xy 259.557075 -306.080001) (xy 259.556555 -306.107583) (xy 259.559552 -306.121054) (xy 259.565263 -306.144645)
			(xy 259.571379 -306.192797) (xy 259.571744 -306.217066) (xy 259.571281 -306.244322) (xy 259.563528 -306.298281)
			(xy 259.548174 -306.350587) (xy 259.525532 -306.400175) (xy 259.496063 -306.446036) (xy 259.460368 -306.487236)
			(xy 259.419172 -306.522937) (xy 259.373314 -306.552411) (xy 259.323729 -306.575058) (xy 259.271425 -306.590418)
			(xy 259.217467 -306.598178) (xy 259.162954 -306.59818) (xy 259.108996 -306.590423) (xy 259.056691 -306.575066)
			(xy 259.007105 -306.552421) (xy 258.961245 -306.522949) (xy 258.920047 -306.487251) (xy 258.884349 -306.446053)
			(xy 258.854878 -306.400194) (xy 258.832233 -306.350607) (xy 258.816877 -306.298302) (xy 258.80912 -306.244344)
			(xy 250.913392 -306.244344) (xy 250.913392 -309.414926) (xy 259.199886 -309.414926) (xy 259.203957 -309.359304)
			(xy 259.216083 -309.304867) (xy 259.236006 -309.252776) (xy 259.263302 -309.204141) (xy 259.297388 -309.159998)
			(xy 259.337537 -309.121289) (xy 259.382895 -309.088838) (xy 259.432495 -309.063337) (xy 259.485279 -309.04533)
			(xy 259.540122 -309.0352) (xy 259.595856 -309.033163) (xy 259.651293 -309.039263) (xy 259.70525 -309.053369)
			(xy 259.756579 -309.075181) (xy 259.804185 -309.104235) (xy 259.847053 -309.13991) (xy 259.88427 -309.181447)
			(xy 259.915043 -309.22796) (xy 259.938715 -309.278457) (xy 259.954783 -309.331864) (xy 259.962903 -309.38704)
			(xy 259.963412 -309.414926) (xy 259.962903 -309.442812) (xy 259.954783 -309.497988) (xy 259.938715 -309.551395)
			(xy 259.915043 -309.601892) (xy 259.88427 -309.648405) (xy 259.847053 -309.689942) (xy 259.804185 -309.725617)
			(xy 259.756579 -309.754671) (xy 259.70525 -309.776483) (xy 259.651293 -309.790589) (xy 259.595856 -309.796689)
			(xy 259.540122 -309.794652) (xy 259.485279 -309.784522) (xy 259.432495 -309.766515) (xy 259.382895 -309.741014)
			(xy 259.337537 -309.708563) (xy 259.297388 -309.669854) (xy 259.263302 -309.625711) (xy 259.236006 -309.577076)
			(xy 259.216083 -309.524985) (xy 259.203957 -309.470548) (xy 259.199886 -309.414926) (xy 250.913392 -309.414926)
			(xy 250.913392 -322.635626) (xy 250.912964 -322.645694) (xy 250.905242 -322.664291) (xy 250.898406 -322.671694)
			(xy 247.203468 -326.366632) (xy 248.21464 -326.366632) (xy 248.218711 -326.31101) (xy 248.230837 -326.256573)
			(xy 248.25076 -326.204482) (xy 248.278056 -326.155847) (xy 248.312142 -326.111704) (xy 248.352291 -326.072995)
			(xy 248.397649 -326.040544) (xy 248.447249 -326.015043) (xy 248.500033 -325.997036) (xy 248.554876 -325.986906)
			(xy 248.61061 -325.984869) (xy 248.666047 -325.990969) (xy 248.720004 -326.005075) (xy 248.771333 -326.026887)
			(xy 248.818939 -326.055941) (xy 248.861807 -326.091616) (xy 248.899024 -326.133153) (xy 248.929797 -326.179666)
			(xy 248.953469 -326.230163) (xy 248.969537 -326.28357) (xy 248.977657 -326.338746) (xy 248.978166 -326.366632)
			(xy 248.977657 -326.394518) (xy 248.969537 -326.449694) (xy 248.953469 -326.503101) (xy 248.929797 -326.553598)
			(xy 248.899024 -326.600111) (xy 248.861807 -326.641648) (xy 248.818939 -326.677323) (xy 248.771333 -326.706377)
			(xy 248.720004 -326.728189) (xy 248.666047 -326.742295) (xy 248.61061 -326.748395) (xy 248.554876 -326.746358)
			(xy 248.500033 -326.736228) (xy 248.447249 -326.718221) (xy 248.397649 -326.69272) (xy 248.352291 -326.660269)
			(xy 248.312142 -326.62156) (xy 248.278056 -326.577417) (xy 248.25076 -326.528782) (xy 248.230837 -326.476691)
			(xy 248.218711 -326.422254) (xy 248.21464 -326.366632) (xy 247.203468 -326.366632) (xy 247.114822 -326.455278)
			(xy 247.10742 -326.462115) (xy 247.088822 -326.469824) (xy 247.078754 -326.470264) (xy 228.648768 -326.470264)
			(xy 228.638702 -326.470695) (xy 228.620112 -326.478424) (xy 228.6127 -326.48525) (xy 227.808282 -327.289668)
			(xy 227.801437 -327.297066) (xy 227.793715 -327.315665) (xy 227.793296 -327.325736) (xy 227.793296 -327.38695)
			(xy 248.284236 -327.38695) (xy 248.288307 -327.331328) (xy 248.300433 -327.276891) (xy 248.320356 -327.2248)
			(xy 248.347652 -327.176165) (xy 248.381738 -327.132022) (xy 248.421887 -327.093313) (xy 248.467245 -327.060862)
			(xy 248.516845 -327.035361) (xy 248.569629 -327.017354) (xy 248.624472 -327.007224) (xy 248.680206 -327.005187)
			(xy 248.735643 -327.011287) (xy 248.7896 -327.025393) (xy 248.840929 -327.047205) (xy 248.888535 -327.076259)
			(xy 248.931403 -327.111934) (xy 248.96862 -327.153471) (xy 248.999393 -327.199984) (xy 249.023065 -327.250481)
			(xy 249.039133 -327.303888) (xy 249.047253 -327.359064) (xy 249.047762 -327.38695) (xy 249.047253 -327.414836)
			(xy 249.039133 -327.470012) (xy 249.023065 -327.523419) (xy 248.999393 -327.573916) (xy 248.96862 -327.620429)
			(xy 248.931403 -327.661966) (xy 248.888535 -327.697641) (xy 248.840929 -327.726695) (xy 248.7896 -327.748507)
			(xy 248.735643 -327.762613) (xy 248.680206 -327.768713) (xy 248.624472 -327.766676) (xy 248.569629 -327.756546)
			(xy 248.516845 -327.738539) (xy 248.467245 -327.713038) (xy 248.421887 -327.680587) (xy 248.381738 -327.641878)
			(xy 248.347652 -327.597735) (xy 248.320356 -327.5491) (xy 248.300433 -327.497009) (xy 248.288307 -327.442572)
			(xy 248.284236 -327.38695) (xy 227.793296 -327.38695) (xy 227.793296 -327.9013) (xy 247.264172 -327.9013)
			(xy 247.268243 -327.845678) (xy 247.280369 -327.791241) (xy 247.300292 -327.73915) (xy 247.327588 -327.690515)
			(xy 247.361674 -327.646372) (xy 247.401823 -327.607663) (xy 247.447181 -327.575212) (xy 247.496781 -327.549711)
			(xy 247.549565 -327.531704) (xy 247.604408 -327.521574) (xy 247.660142 -327.519537) (xy 247.715579 -327.525637)
			(xy 247.769536 -327.539743) (xy 247.820865 -327.561555) (xy 247.868471 -327.590609) (xy 247.911339 -327.626284)
			(xy 247.948556 -327.667821) (xy 247.979329 -327.714334) (xy 248.003001 -327.764831) (xy 248.019069 -327.818238)
			(xy 248.027189 -327.873414) (xy 248.027698 -327.9013) (xy 248.027189 -327.929186) (xy 248.019069 -327.984362)
			(xy 248.003001 -328.037769) (xy 247.979329 -328.088266) (xy 247.948556 -328.134779) (xy 247.911339 -328.176316)
			(xy 247.868471 -328.211991) (xy 247.820865 -328.241045) (xy 247.769536 -328.262857) (xy 247.715579 -328.276963)
			(xy 247.660142 -328.283063) (xy 247.604408 -328.281026) (xy 247.549565 -328.270896) (xy 247.496781 -328.252889)
			(xy 247.447181 -328.227388) (xy 247.401823 -328.194937) (xy 247.361674 -328.156228) (xy 247.327588 -328.112085)
			(xy 247.300292 -328.06345) (xy 247.280369 -328.011359) (xy 247.268243 -327.956922) (xy 247.264172 -327.9013)
			(xy 227.793296 -327.9013) (xy 227.793296 -330.156312) (xy 228.957124 -330.156312) (xy 228.95761 -330.129347)
			(xy 228.96519 -330.075952) (xy 228.980216 -330.024157) (xy 229.002387 -329.974994) (xy 229.031262 -329.929445)
			(xy 229.066264 -329.888417) (xy 229.106697 -329.852728) (xy 229.151753 -329.823089) (xy 229.200534 -329.800093)
			(xy 229.252069 -329.784196) (xy 229.305328 -329.775717) (xy 229.332282 -329.774804) (xy 229.343966 -329.77455)
			(xy 229.365048 -329.763882) (xy 229.427278 -329.679808) (xy 229.431342 -329.65644) (xy 229.42804 -329.64501)
			(xy 229.421029 -329.619094) (xy 229.413509 -329.565936) (xy 229.413054 -329.539092) (xy 229.41357 -329.511842)
			(xy 229.421327 -329.457898) (xy 229.436681 -329.405606) (xy 229.45932 -329.356031) (xy 229.488784 -329.310183)
			(xy 229.524472 -329.268993) (xy 229.565658 -329.233302) (xy 229.611505 -329.203835) (xy 229.661078 -329.181192)
			(xy 229.713368 -329.165833) (xy 229.767312 -329.158072) (xy 229.794562 -329.157584) (xy 229.823436 -329.158122)
			(xy 229.880522 -329.166843) (xy 229.906989 -329.17511) (xy 240.475768 -329.17511) (xy 240.479839 -329.119488)
			(xy 240.491965 -329.065051) (xy 240.511888 -329.01296) (xy 240.539184 -328.964325) (xy 240.57327 -328.920182)
			(xy 240.613419 -328.881473) (xy 240.658777 -328.849022) (xy 240.708377 -328.823521) (xy 240.761161 -328.805514)
			(xy 240.816004 -328.795384) (xy 240.871738 -328.793347) (xy 240.927175 -328.799447) (xy 240.981132 -328.813553)
			(xy 241.032461 -328.835365) (xy 241.080067 -328.864419) (xy 241.122935 -328.900094) (xy 241.160152 -328.941631)
			(xy 241.190925 -328.988144) (xy 241.214597 -329.038641) (xy 241.230665 -329.092048) (xy 241.238785 -329.147224)
			(xy 241.239294 -329.17511) (xy 241.238785 -329.202996) (xy 241.230665 -329.258172) (xy 241.214597 -329.311579)
			(xy 241.190925 -329.362076) (xy 241.160152 -329.408589) (xy 241.122935 -329.450126) (xy 241.080067 -329.485801)
			(xy 241.032461 -329.514855) (xy 240.981132 -329.536667) (xy 240.927175 -329.550773) (xy 240.871738 -329.556873)
			(xy 240.816004 -329.554836) (xy 240.761161 -329.544706) (xy 240.708377 -329.526699) (xy 240.658777 -329.501198)
			(xy 240.613419 -329.468747) (xy 240.57327 -329.430038) (xy 240.539184 -329.385895) (xy 240.511888 -329.33726)
			(xy 240.491965 -329.285169) (xy 240.479839 -329.230732) (xy 240.475768 -329.17511) (xy 229.906989 -329.17511)
			(xy 229.935643 -329.18406) (xy 229.987543 -329.209382) (xy 230.035038 -329.242231) (xy 230.077045 -329.281858)
			(xy 230.112605 -329.327359) (xy 230.140908 -329.377695) (xy 230.161307 -329.43172) (xy 230.173339 -329.488201)
			(xy 230.175562 -329.516994) (xy 230.17607 -329.526646) (xy 230.18369 -329.54341) (xy 230.245412 -329.604878)
			(xy 230.262176 -329.612244) (xy 230.271828 -329.612752) (xy 230.300777 -329.614757) (xy 230.357618 -329.626426)
			(xy 230.412035 -329.64657) (xy 230.462774 -329.674724) (xy 230.508662 -329.710238) (xy 230.548643 -329.752293)
			(xy 230.581792 -329.799918) (xy 230.607345 -329.852015) (xy 230.624712 -329.907381) (xy 230.633494 -329.964739)
			(xy 230.634032 -329.993752) (xy 230.6335 -330.021003) (xy 230.627636 -330.061824) (xy 230.958134 -330.061824)
			(xy 230.962205 -330.006202) (xy 230.974331 -329.951765) (xy 230.994254 -329.899674) (xy 231.02155 -329.851039)
			(xy 231.055636 -329.806896) (xy 231.095785 -329.768187) (xy 231.141143 -329.735736) (xy 231.190743 -329.710235)
			(xy 231.243527 -329.692228) (xy 231.29837 -329.682098) (xy 231.354104 -329.680061) (xy 231.409541 -329.686161)
			(xy 231.463498 -329.700267) (xy 231.514827 -329.722079) (xy 231.562433 -329.751133) (xy 231.605301 -329.786808)
			(xy 231.642518 -329.828345) (xy 231.673291 -329.874858) (xy 231.696963 -329.925355) (xy 231.713031 -329.978762)
			(xy 231.721151 -330.033938) (xy 231.72166 -330.061824) (xy 231.721151 -330.08971) (xy 231.713031 -330.144886)
			(xy 231.696963 -330.198293) (xy 231.673291 -330.24879) (xy 231.642518 -330.295303) (xy 231.605301 -330.33684)
			(xy 231.562433 -330.372515) (xy 231.514827 -330.401569) (xy 231.463498 -330.423381) (xy 231.409541 -330.437487)
			(xy 231.354104 -330.443587) (xy 231.29837 -330.44155) (xy 231.243527 -330.43142) (xy 231.190743 -330.413413)
			(xy 231.141143 -330.387912) (xy 231.095785 -330.355461) (xy 231.055636 -330.316752) (xy 231.02155 -330.272609)
			(xy 230.994254 -330.223974) (xy 230.974331 -330.171883) (xy 230.962205 -330.117446) (xy 230.958134 -330.061824)
			(xy 230.627636 -330.061824) (xy 230.62575 -330.07495) (xy 230.610402 -330.127245) (xy 230.587766 -330.176823)
			(xy 230.558306 -330.222675) (xy 230.522619 -330.263868) (xy 230.481433 -330.299562) (xy 230.435587 -330.329032)
			(xy 230.386012 -330.351676) (xy 230.33372 -330.367035) (xy 230.279774 -330.374795) (xy 230.252524 -330.37526)
			(xy 230.225283 -330.3748) (xy 230.171354 -330.367052) (xy 230.119076 -330.351711) (xy 230.069513 -330.329087)
			(xy 230.023672 -330.299643) (xy 229.982487 -330.263976) (xy 229.946795 -330.222812) (xy 229.917323 -330.176989)
			(xy 229.89467 -330.12744) (xy 229.879297 -330.075171) (xy 229.871516 -330.021247) (xy 229.871016 -329.994006)
			(xy 229.87061 -329.983934) (xy 229.862878 -329.965335) (xy 229.85603 -329.957938) (xy 229.817676 -329.919838)
			(xy 229.800912 -329.9206) (xy 229.789228 -329.920854) (xy 229.768146 -329.931522) (xy 229.705916 -330.015596)
			(xy 229.701852 -330.038964) (xy 229.705154 -330.050394) (xy 229.712166 -330.07631) (xy 229.719685 -330.129468)
			(xy 229.72014 -330.156312) (xy 229.719654 -330.183563) (xy 229.711898 -330.237511) (xy 229.696543 -330.289806)
			(xy 229.673901 -330.339383) (xy 229.644435 -330.385233) (xy 229.608744 -330.426424) (xy 229.567553 -330.462115)
			(xy 229.521703 -330.491581) (xy 229.472126 -330.514223) (xy 229.419831 -330.529578) (xy 229.365883 -330.537334)
			(xy 229.311381 -330.537334) (xy 229.257433 -330.529578) (xy 229.205138 -330.514223) (xy 229.155561 -330.491581)
			(xy 229.109711 -330.462115) (xy 229.06852 -330.426424) (xy 229.032829 -330.385233) (xy 229.003363 -330.339383)
			(xy 228.980721 -330.289806) (xy 228.965366 -330.237511) (xy 228.95761 -330.183563) (xy 228.957124 -330.156312)
			(xy 227.793296 -330.156312) (xy 227.793296 -331.037438) (xy 249.7615 -331.037438) (xy 249.765571 -330.981816)
			(xy 249.777697 -330.927379) (xy 249.79762 -330.875288) (xy 249.824916 -330.826653) (xy 249.859002 -330.78251)
			(xy 249.899151 -330.743801) (xy 249.944509 -330.71135) (xy 249.994109 -330.685849) (xy 250.046893 -330.667842)
			(xy 250.101736 -330.657712) (xy 250.15747 -330.655675) (xy 250.212907 -330.661775) (xy 250.266864 -330.675881)
			(xy 250.318193 -330.697693) (xy 250.365799 -330.726747) (xy 250.408667 -330.762422) (xy 250.445884 -330.803959)
			(xy 250.476167 -330.849732) (xy 250.668788 -330.849732) (xy 250.672859 -330.79411) (xy 250.684985 -330.739673)
			(xy 250.704908 -330.687582) (xy 250.732204 -330.638947) (xy 250.76629 -330.594804) (xy 250.806439 -330.556095)
			(xy 250.851797 -330.523644) (xy 250.901397 -330.498143) (xy 250.954181 -330.480136) (xy 251.009024 -330.470006)
			(xy 251.064758 -330.467969) (xy 251.120195 -330.474069) (xy 251.174152 -330.488175) (xy 251.225481 -330.509987)
			(xy 251.273087 -330.539041) (xy 251.315955 -330.574716) (xy 251.353172 -330.616253) (xy 251.383945 -330.662766)
			(xy 251.407617 -330.713263) (xy 251.423685 -330.76667) (xy 251.431805 -330.821846) (xy 251.432314 -330.849732)
			(xy 251.431805 -330.877618) (xy 251.423685 -330.932794) (xy 251.407617 -330.986201) (xy 251.383945 -331.036698)
			(xy 251.353172 -331.083211) (xy 251.315955 -331.124748) (xy 251.273087 -331.160423) (xy 251.225481 -331.189477)
			(xy 251.174152 -331.211289) (xy 251.120195 -331.225395) (xy 251.064758 -331.231495) (xy 251.009024 -331.229458)
			(xy 250.954181 -331.219328) (xy 250.901397 -331.201321) (xy 250.851797 -331.17582) (xy 250.806439 -331.143369)
			(xy 250.76629 -331.10466) (xy 250.732204 -331.060517) (xy 250.704908 -331.011882) (xy 250.684985 -330.959791)
			(xy 250.672859 -330.905354) (xy 250.668788 -330.849732) (xy 250.476167 -330.849732) (xy 250.476657 -330.850472)
			(xy 250.500329 -330.900969) (xy 250.516397 -330.954376) (xy 250.524517 -331.009552) (xy 250.525026 -331.037438)
			(xy 250.524517 -331.065324) (xy 250.516397 -331.1205) (xy 250.500329 -331.173907) (xy 250.476657 -331.224404)
			(xy 250.445884 -331.270917) (xy 250.408667 -331.312454) (xy 250.365799 -331.348129) (xy 250.318193 -331.377183)
			(xy 250.266864 -331.398995) (xy 250.212907 -331.413101) (xy 250.15747 -331.419201) (xy 250.101736 -331.417164)
			(xy 250.046893 -331.407034) (xy 249.994109 -331.389027) (xy 249.944509 -331.363526) (xy 249.899151 -331.331075)
			(xy 249.859002 -331.292366) (xy 249.824916 -331.248223) (xy 249.79762 -331.199588) (xy 249.777697 -331.147497)
			(xy 249.765571 -331.09306) (xy 249.7615 -331.037438) (xy 227.793296 -331.037438) (xy 227.793296 -331.878432)
			(xy 239.366296 -331.878432) (xy 239.370367 -331.82281) (xy 239.382493 -331.768373) (xy 239.402416 -331.716282)
			(xy 239.429712 -331.667647) (xy 239.463798 -331.623504) (xy 239.503947 -331.584795) (xy 239.549305 -331.552344)
			(xy 239.598905 -331.526843) (xy 239.651689 -331.508836) (xy 239.706532 -331.498706) (xy 239.762266 -331.496669)
			(xy 239.817703 -331.502769) (xy 239.87166 -331.516875) (xy 239.922989 -331.538687) (xy 239.970595 -331.567741)
			(xy 240.013463 -331.603416) (xy 240.05068 -331.644953) (xy 240.081453 -331.691466) (xy 240.105125 -331.741963)
			(xy 240.121193 -331.79537) (xy 240.129313 -331.850546) (xy 240.129822 -331.878432) (xy 240.129313 -331.906318)
			(xy 240.121193 -331.961494) (xy 240.105125 -332.014901) (xy 240.081453 -332.065398) (xy 240.05068 -332.111911)
			(xy 240.013463 -332.153448) (xy 239.970595 -332.189123) (xy 239.922989 -332.218177) (xy 239.87166 -332.239989)
			(xy 239.817703 -332.254095) (xy 239.762266 -332.260195) (xy 239.706532 -332.258158) (xy 239.651689 -332.248028)
			(xy 239.598905 -332.230021) (xy 239.549305 -332.20452) (xy 239.503947 -332.172069) (xy 239.463798 -332.13336)
			(xy 239.429712 -332.089217) (xy 239.402416 -332.040582) (xy 239.382493 -331.988491) (xy 239.370367 -331.934054)
			(xy 239.366296 -331.878432) (xy 227.793296 -331.878432) (xy 227.793296 -332.589752) (xy 228.949232 -332.589752)
			(xy 228.949232 -332.535248) (xy 228.956988 -332.481298) (xy 228.972342 -332.429001) (xy 228.994983 -332.379421)
			(xy 229.024448 -332.333567) (xy 229.060138 -332.292374) (xy 229.101327 -332.256678) (xy 229.147177 -332.227207)
			(xy 229.196754 -332.20456) (xy 229.249049 -332.189199) (xy 229.302998 -332.181435) (xy 229.33025 -332.180946)
			(xy 229.356964 -332.181383) (xy 229.409865 -332.188873) (xy 229.461204 -332.203671) (xy 229.509975 -332.225488)
			(xy 229.555226 -332.253897) (xy 229.596069 -332.288342) (xy 229.614222 -332.307946) (xy 229.621842 -332.316074)
			(xy 229.641654 -332.324964) (xy 229.74046 -332.323694) (xy 229.760272 -332.314296) (xy 229.767384 -332.305914)
			(xy 229.785598 -332.285247) (xy 229.826945 -332.248848) (xy 229.873099 -332.218775) (xy 229.923098 -332.195653)
			(xy 229.975904 -332.179965) (xy 230.030417 -332.172035) (xy 230.05796 -332.171548) (xy 230.085212 -332.172096)
			(xy 230.139161 -332.179848) (xy 230.191457 -332.195199) (xy 230.241037 -332.217836) (xy 230.28689 -332.2473)
			(xy 230.328082 -332.282989) (xy 230.363776 -332.324178) (xy 230.393244 -332.370028) (xy 230.415887 -332.419605)
			(xy 230.431244 -332.4719) (xy 230.439001 -332.525848) (xy 230.439001 -332.580352) (xy 230.431244 -332.6343)
			(xy 230.415887 -332.686595) (xy 230.393244 -332.736172) (xy 230.363776 -332.782022) (xy 230.328082 -332.823211)
			(xy 230.28689 -332.8589) (xy 230.241037 -332.888364) (xy 230.192421 -332.910561) (xy 236.030411 -332.910561)
			(xy 236.030411 -332.856047) (xy 236.038169 -332.802088) (xy 236.053527 -332.749782) (xy 236.076173 -332.700195)
			(xy 236.105646 -332.654335) (xy 236.141345 -332.613137) (xy 236.182545 -332.577439) (xy 236.228405 -332.547967)
			(xy 236.277994 -332.525323) (xy 236.3303 -332.509966) (xy 236.384259 -332.50221) (xy 236.411516 -332.501748)
			(xy 236.445736 -332.502553) (xy 236.513069 -332.514818) (xy 236.545374 -332.526132) (xy 236.558641 -332.530623)
			(xy 236.586546 -332.532919) (xy 236.614029 -332.527561) (xy 236.639028 -332.514951) (xy 236.659671 -332.496033)
			(xy 236.67441 -332.472227) (xy 236.68214 -332.445315) (xy 236.682282 -332.417315) (xy 236.678978 -332.403704)
			(xy 236.672448 -332.378619) (xy 236.665442 -332.32726) (xy 236.665008 -332.301342) (xy 236.66541 -332.274086)
			(xy 236.673162 -332.220127) (xy 236.688515 -332.167821) (xy 236.711155 -332.118232) (xy 236.740622 -332.072371)
			(xy 236.776316 -332.031169) (xy 236.81751 -331.995467) (xy 236.863366 -331.965991) (xy 236.91295 -331.943341)
			(xy 236.965253 -331.927978) (xy 237.01921 -331.920215) (xy 237.073723 -331.920211) (xy 237.127681 -331.927964)
			(xy 237.179987 -331.943318) (xy 237.229575 -331.965959) (xy 237.275436 -331.995427) (xy 237.316637 -332.031122)
			(xy 237.352338 -332.072317) (xy 237.381813 -332.118174) (xy 237.404462 -332.167759) (xy 237.419824 -332.220062)
			(xy 237.427585 -332.274019) (xy 237.427589 -332.328532) (xy 237.419834 -332.38249) (xy 237.404479 -332.434795)
			(xy 237.381837 -332.484383) (xy 237.352368 -332.530243) (xy 237.316672 -332.571443) (xy 237.275476 -332.607143)
			(xy 237.229619 -332.636617) (xy 237.180033 -332.659265) (xy 237.12773 -332.674626) (xy 237.073772 -332.682386)
			(xy 237.046516 -332.68285) (xy 237.012297 -332.682037) (xy 236.944964 -332.669777) (xy 236.912658 -332.658466)
			(xy 236.899379 -332.654013) (xy 236.871478 -332.651711) (xy 236.843999 -332.657063) (xy 236.819001 -332.669667)
			(xy 236.798359 -332.68858) (xy 236.783621 -332.712382) (xy 236.775891 -332.739289) (xy 236.775749 -332.767285)
			(xy 236.779054 -332.780894) (xy 236.780376 -332.785974) (xy 238.593374 -332.785974) (xy 238.597445 -332.730352)
			(xy 238.609571 -332.675915) (xy 238.629494 -332.623824) (xy 238.65679 -332.575189) (xy 238.690876 -332.531046)
			(xy 238.731025 -332.492337) (xy 238.776383 -332.459886) (xy 238.825983 -332.434385) (xy 238.878767 -332.416378)
			(xy 238.93361 -332.406248) (xy 238.989344 -332.404211) (xy 239.044781 -332.410311) (xy 239.098738 -332.424417)
			(xy 239.150067 -332.446229) (xy 239.197673 -332.475283) (xy 239.240541 -332.510958) (xy 239.277758 -332.552495)
			(xy 239.308531 -332.599008) (xy 239.332203 -332.649505) (xy 239.348271 -332.702912) (xy 239.356391 -332.758088)
			(xy 239.3569 -332.785974) (xy 239.356391 -332.81386) (xy 239.348271 -332.869036) (xy 239.332203 -332.922443)
			(xy 239.308531 -332.97294) (xy 239.277758 -333.019453) (xy 239.240541 -333.06099) (xy 239.197673 -333.096665)
			(xy 239.150067 -333.125719) (xy 239.098738 -333.147531) (xy 239.044781 -333.161637) (xy 238.989344 -333.167737)
			(xy 238.93361 -333.1657) (xy 238.878767 -333.15557) (xy 238.825983 -333.137563) (xy 238.776383 -333.112062)
			(xy 238.731025 -333.079611) (xy 238.690876 -333.040902) (xy 238.65679 -332.996759) (xy 238.629494 -332.948124)
			(xy 238.609571 -332.896033) (xy 238.597445 -332.841596) (xy 238.593374 -332.785974) (xy 236.780376 -332.785974)
			(xy 236.785584 -332.805979) (xy 236.79259 -332.857338) (xy 236.793024 -332.883256) (xy 236.792592 -332.910513)
			(xy 236.78484 -332.964473) (xy 236.769487 -333.01678) (xy 236.746846 -333.06637) (xy 236.717378 -333.112233)
			(xy 236.681683 -333.153435) (xy 236.640487 -333.189137) (xy 236.59463 -333.218614) (xy 236.545044 -333.241263)
			(xy 236.492739 -333.256625) (xy 236.438781 -333.264387) (xy 236.384267 -333.264391) (xy 236.330308 -333.256636)
			(xy 236.278001 -333.24128) (xy 236.228412 -333.218637) (xy 236.182551 -333.189166) (xy 236.141351 -333.153469)
			(xy 236.105651 -333.112271) (xy 236.076177 -333.066412) (xy 236.05353 -333.016825) (xy 236.03817 -332.96452)
			(xy 236.030411 -332.910561) (xy 230.192421 -332.910561) (xy 230.191457 -332.911001) (xy 230.139161 -332.926352)
			(xy 230.085212 -332.934104) (xy 230.05796 -332.934564) (xy 230.031246 -332.934117) (xy 229.978346 -332.926628)
			(xy 229.927007 -332.911832) (xy 229.878236 -332.890017) (xy 229.832985 -332.86161) (xy 229.792141 -332.827167)
			(xy 229.773988 -332.807564) (xy 229.766368 -332.799436) (xy 229.746556 -332.790546) (xy 229.64775 -332.791816)
			(xy 229.627938 -332.801214) (xy 229.620826 -332.809596) (xy 229.602609 -332.830261) (xy 229.561262 -332.866659)
			(xy 229.515109 -332.896732) (xy 229.46511 -332.919854) (xy 229.412305 -332.935543) (xy 229.357793 -332.943474)
			(xy 229.33025 -332.943962) (xy 229.302998 -332.943565) (xy 229.249049 -332.935801) (xy 229.196754 -332.92044)
			(xy 229.147177 -332.897793) (xy 229.101327 -332.868322) (xy 229.060138 -332.832626) (xy 229.024448 -332.791433)
			(xy 228.994983 -332.745579) (xy 228.972342 -332.695999) (xy 228.956988 -332.643702) (xy 228.949232 -332.589752)
			(xy 227.793296 -332.589752) (xy 227.793296 -334.367451) (xy 230.428778 -334.367451) (xy 230.428778 -334.312949)
			(xy 230.436534 -334.259001) (xy 230.451889 -334.206706) (xy 230.474531 -334.157129) (xy 230.503997 -334.111279)
			(xy 230.539688 -334.070088) (xy 230.580879 -334.034397) (xy 230.626729 -334.004931) (xy 230.676306 -333.982289)
			(xy 230.728601 -333.966934) (xy 230.782549 -333.959178) (xy 230.8098 -333.958692) (xy 230.837644 -333.959212)
			(xy 230.892732 -333.967366) (xy 230.919528 -333.974948) (xy 230.933923 -333.97882) (xy 230.963724 -333.978783)
			(xy 230.992248 -333.970151) (xy 231.017068 -333.953656) (xy 231.036074 -333.930703) (xy 231.047651 -333.903242)
			(xy 231.050812 -333.873609) (xy 231.04856 -333.85887) (xy 231.045567 -333.841563) (xy 231.042388 -333.806583)
			(xy 231.04221 -333.78902) (xy 231.042633 -333.761766) (xy 231.050388 -333.707811) (xy 231.065742 -333.65551)
			(xy 231.088383 -333.605926) (xy 231.117851 -333.560069) (xy 231.153544 -333.518872) (xy 231.194737 -333.483174)
			(xy 231.240591 -333.453702) (xy 231.290173 -333.431056) (xy 231.342473 -333.415696) (xy 231.396426 -333.407936)
			(xy 231.450935 -333.407934) (xy 231.504889 -333.415688) (xy 231.557191 -333.431042) (xy 231.606775 -333.453684)
			(xy 231.652632 -333.483151) (xy 231.693829 -333.518845) (xy 231.729526 -333.560038) (xy 231.758998 -333.605892)
			(xy 231.781644 -333.655474) (xy 231.797004 -333.707774) (xy 231.804764 -333.761727) (xy 231.804766 -333.816236)
			(xy 231.797012 -333.87019) (xy 231.781657 -333.922491) (xy 231.759016 -333.972075) (xy 231.729549 -334.017932)
			(xy 231.693855 -334.059129) (xy 231.652662 -334.094827) (xy 231.606808 -334.124298) (xy 231.557226 -334.146945)
			(xy 231.504926 -334.162304) (xy 231.450972 -334.170064) (xy 231.423718 -334.170528) (xy 231.395874 -334.170025)
			(xy 231.340786 -334.161859) (xy 231.31399 -334.154272) (xy 231.299572 -334.150513) (xy 231.269792 -334.150548)
			(xy 231.241287 -334.159169) (xy 231.21648 -334.175645) (xy 231.197478 -334.198575) (xy 231.185896 -334.22601)
			(xy 231.182718 -334.25562) (xy 231.184958 -334.27035) (xy 231.187953 -334.287656) (xy 231.191131 -334.322637)
			(xy 231.191308 -334.3402) (xy 231.190822 -334.367451) (xy 231.183066 -334.421399) (xy 231.167711 -334.473694)
			(xy 231.145069 -334.523271) (xy 231.115603 -334.569121) (xy 231.079912 -334.610312) (xy 231.038721 -334.646003)
			(xy 230.992871 -334.675469) (xy 230.943294 -334.698111) (xy 230.890999 -334.713466) (xy 230.837051 -334.721222)
			(xy 230.782549 -334.721222) (xy 230.728601 -334.713466) (xy 230.676306 -334.698111) (xy 230.626729 -334.675469)
			(xy 230.580879 -334.646003) (xy 230.539688 -334.610312) (xy 230.503997 -334.569121) (xy 230.474531 -334.523271)
			(xy 230.451889 -334.473694) (xy 230.436534 -334.421399) (xy 230.428778 -334.367451) (xy 227.793296 -334.367451)
			(xy 227.793296 -335.467706) (xy 239.44656 -335.467706) (xy 239.450631 -335.412084) (xy 239.462757 -335.357647)
			(xy 239.48268 -335.305556) (xy 239.509976 -335.256921) (xy 239.544062 -335.212778) (xy 239.584211 -335.174069)
			(xy 239.629569 -335.141618) (xy 239.679169 -335.116117) (xy 239.731953 -335.09811) (xy 239.786796 -335.08798)
			(xy 239.84253 -335.085943) (xy 239.897967 -335.092043) (xy 239.951924 -335.106149) (xy 240.003253 -335.127961)
			(xy 240.050859 -335.157015) (xy 240.093727 -335.19269) (xy 240.130944 -335.234227) (xy 240.161717 -335.28074)
			(xy 240.185389 -335.331237) (xy 240.201457 -335.384644) (xy 240.209577 -335.43982) (xy 240.210086 -335.467706)
			(xy 240.209577 -335.495592) (xy 240.201457 -335.550768) (xy 240.185389 -335.604175) (xy 240.161717 -335.654672)
			(xy 240.130944 -335.701185) (xy 240.110281 -335.724246) (xy 240.910362 -335.724246) (xy 240.914433 -335.668624)
			(xy 240.926559 -335.614187) (xy 240.946482 -335.562096) (xy 240.973778 -335.513461) (xy 241.007864 -335.469318)
			(xy 241.048013 -335.430609) (xy 241.093371 -335.398158) (xy 241.142971 -335.372657) (xy 241.195755 -335.35465)
			(xy 241.250598 -335.34452) (xy 241.306332 -335.342483) (xy 241.361769 -335.348583) (xy 241.415726 -335.362689)
			(xy 241.467055 -335.384501) (xy 241.514661 -335.413555) (xy 241.557529 -335.44923) (xy 241.577952 -335.472024)
			(xy 251.205236 -335.472024) (xy 251.209307 -335.416402) (xy 251.221433 -335.361965) (xy 251.241356 -335.309874)
			(xy 251.268652 -335.261239) (xy 251.302738 -335.217096) (xy 251.342887 -335.178387) (xy 251.388245 -335.145936)
			(xy 251.437845 -335.120435) (xy 251.490629 -335.102428) (xy 251.545472 -335.092298) (xy 251.601206 -335.090261)
			(xy 251.656643 -335.096361) (xy 251.7106 -335.110467) (xy 251.761929 -335.132279) (xy 251.809535 -335.161333)
			(xy 251.852403 -335.197008) (xy 251.88962 -335.238545) (xy 251.920393 -335.285058) (xy 251.944065 -335.335555)
			(xy 251.960133 -335.388962) (xy 251.968253 -335.444138) (xy 251.968762 -335.472024) (xy 251.968253 -335.49991)
			(xy 251.960133 -335.555086) (xy 251.944065 -335.608493) (xy 251.920393 -335.65899) (xy 251.88962 -335.705503)
			(xy 251.852403 -335.74704) (xy 251.809535 -335.782715) (xy 251.761929 -335.811769) (xy 251.7106 -335.833581)
			(xy 251.656643 -335.847687) (xy 251.601206 -335.853787) (xy 251.545472 -335.85175) (xy 251.490629 -335.84162)
			(xy 251.437845 -335.823613) (xy 251.388245 -335.798112) (xy 251.342887 -335.765661) (xy 251.302738 -335.726952)
			(xy 251.268652 -335.682809) (xy 251.241356 -335.634174) (xy 251.221433 -335.582083) (xy 251.209307 -335.527646)
			(xy 251.205236 -335.472024) (xy 241.577952 -335.472024) (xy 241.594746 -335.490767) (xy 241.625519 -335.53728)
			(xy 241.649191 -335.587777) (xy 241.665259 -335.641184) (xy 241.673379 -335.69636) (xy 241.673888 -335.724246)
			(xy 241.673379 -335.752132) (xy 241.665259 -335.807308) (xy 241.649191 -335.860715) (xy 241.625519 -335.911212)
			(xy 241.594746 -335.957725) (xy 241.557529 -335.999262) (xy 241.514661 -336.034937) (xy 241.467055 -336.063991)
			(xy 241.415726 -336.085803) (xy 241.361769 -336.099909) (xy 241.306332 -336.106009) (xy 241.250598 -336.103972)
			(xy 241.195755 -336.093842) (xy 241.142971 -336.075835) (xy 241.093371 -336.050334) (xy 241.048013 -336.017883)
			(xy 241.007864 -335.979174) (xy 240.973778 -335.935031) (xy 240.946482 -335.886396) (xy 240.926559 -335.834305)
			(xy 240.914433 -335.779868) (xy 240.910362 -335.724246) (xy 240.110281 -335.724246) (xy 240.093727 -335.742722)
			(xy 240.050859 -335.778397) (xy 240.003253 -335.807451) (xy 239.951924 -335.829263) (xy 239.897967 -335.843369)
			(xy 239.84253 -335.849469) (xy 239.786796 -335.847432) (xy 239.731953 -335.837302) (xy 239.679169 -335.819295)
			(xy 239.629569 -335.793794) (xy 239.584211 -335.761343) (xy 239.544062 -335.722634) (xy 239.509976 -335.678491)
			(xy 239.48268 -335.629856) (xy 239.462757 -335.577765) (xy 239.450631 -335.523328) (xy 239.44656 -335.467706)
			(xy 227.793296 -335.467706) (xy 227.793296 -337.266026) (xy 234.403392 -337.266026) (xy 234.403392 -336.402426)
			(xy 234.403951 -336.372455) (xy 234.411769 -336.313024) (xy 234.427274 -336.255122) (xy 234.450202 -336.199738)
			(xy 234.48016 -336.147818) (xy 234.516636 -336.100252) (xy 234.559006 -336.057851) (xy 234.606547 -336.021341)
			(xy 234.658445 -335.991346) (xy 234.713813 -335.968379) (xy 234.771704 -335.952833) (xy 234.831129 -335.944973)
			(xy 234.8611 -335.944464) (xy 234.890743 -335.944952) (xy 234.949525 -335.952676) (xy 235.006824 -335.967906)
			(xy 235.061684 -335.990387) (xy 235.087668 -336.004662) (xy 235.096084 -336.008902) (xy 235.114711 -336.01164)
			(xy 235.12399 -336.009996) (xy 235.154216 -336.003138) (xy 235.163199 -336.000682) (xy 235.178708 -335.990408)
			(xy 235.184442 -335.983072) (xy 235.199873 -335.962231) (xy 235.235442 -335.924496) (xy 235.275797 -335.89193)
			(xy 235.320193 -335.865134) (xy 235.367811 -335.844601) (xy 235.417773 -335.830712) (xy 235.469156 -335.823723)
			(xy 235.495084 -335.823306) (xy 235.522339 -335.82374) (xy 235.576293 -335.831495) (xy 235.628595 -335.84685)
			(xy 235.678179 -335.869493) (xy 235.724036 -335.898962) (xy 235.765232 -335.934657) (xy 235.800929 -335.975851)
			(xy 235.830399 -336.021707) (xy 235.853044 -336.07129) (xy 235.868401 -336.123591) (xy 235.876159 -336.177545)
			(xy 235.876159 -336.232055) (xy 235.868401 -336.286009) (xy 235.853044 -336.33831) (xy 235.830399 -336.387893)
			(xy 235.800929 -336.433749) (xy 235.765232 -336.474943) (xy 235.724036 -336.510638) (xy 235.678179 -336.540107)
			(xy 235.637048 -336.55889) (xy 240.234214 -336.55889) (xy 240.238285 -336.503268) (xy 240.250411 -336.448831)
			(xy 240.270334 -336.39674) (xy 240.29763 -336.348105) (xy 240.331716 -336.303962) (xy 240.371865 -336.265253)
			(xy 240.417223 -336.232802) (xy 240.466823 -336.207301) (xy 240.519607 -336.189294) (xy 240.57445 -336.179164)
			(xy 240.630184 -336.177127) (xy 240.685621 -336.183227) (xy 240.739578 -336.197333) (xy 240.790907 -336.219145)
			(xy 240.838513 -336.248199) (xy 240.881381 -336.283874) (xy 240.918598 -336.325411) (xy 240.949371 -336.371924)
			(xy 240.973043 -336.422421) (xy 240.989111 -336.475828) (xy 240.997231 -336.531004) (xy 240.99774 -336.55889)
			(xy 240.997231 -336.586776) (xy 240.989111 -336.641952) (xy 240.973043 -336.695359) (xy 240.949371 -336.745856)
			(xy 240.918598 -336.792369) (xy 240.881381 -336.833906) (xy 240.838513 -336.869581) (xy 240.790907 -336.898635)
			(xy 240.739578 -336.920447) (xy 240.685621 -336.934553) (xy 240.630184 -336.940653) (xy 240.57445 -336.938616)
			(xy 240.519607 -336.928486) (xy 240.466823 -336.910479) (xy 240.417223 -336.884978) (xy 240.371865 -336.852527)
			(xy 240.331716 -336.813818) (xy 240.29763 -336.769675) (xy 240.270334 -336.72104) (xy 240.250411 -336.668949)
			(xy 240.238285 -336.614512) (xy 240.234214 -336.55889) (xy 235.637048 -336.55889) (xy 235.628595 -336.56275)
			(xy 235.576293 -336.578105) (xy 235.522339 -336.58586) (xy 235.495084 -336.586322) (xy 235.480291 -336.58619)
			(xy 235.450793 -336.583899) (xy 235.436156 -336.58175) (xy 235.425234 -336.579972) (xy 235.403898 -336.586068)
			(xy 235.336588 -336.643472) (xy 235.328578 -336.651055) (xy 235.319353 -336.671064) (xy 235.318808 -336.68208)
			(xy 235.318808 -336.986372) (xy 235.319359 -336.997389) (xy 235.328569 -337.017406) (xy 235.336588 -337.02498)
			(xy 235.403898 -337.082384) (xy 235.425234 -337.08848) (xy 235.436156 -337.086702) (xy 235.450794 -337.08456)
			(xy 235.480291 -337.082273) (xy 235.495084 -337.08213) (xy 235.52234 -337.082516) (xy 235.576298 -337.090272)
			(xy 235.628603 -337.105628) (xy 235.678191 -337.128272) (xy 235.72405 -337.157742) (xy 235.765249 -337.19344)
			(xy 235.800948 -337.234637) (xy 235.830421 -337.280495) (xy 235.853066 -337.330082) (xy 235.868425 -337.382386)
			(xy 235.876183 -337.436344) (xy 235.876183 -337.490856) (xy 235.868425 -337.544814) (xy 235.853066 -337.597118)
			(xy 235.830421 -337.646705) (xy 235.800948 -337.692563) (xy 235.765249 -337.73376) (xy 235.72405 -337.769458)
			(xy 235.678191 -337.798928) (xy 235.628603 -337.821572) (xy 235.576298 -337.836928) (xy 235.52234 -337.844684)
			(xy 235.495084 -337.845146) (xy 235.469156 -337.844748) (xy 235.417777 -337.837738) (xy 235.36782 -337.823837)
			(xy 235.320204 -337.8033) (xy 235.275808 -337.776506) (xy 235.235448 -337.743947) (xy 235.199868 -337.706224)
			(xy 235.184442 -337.68538) (xy 235.178684 -337.678065) (xy 235.163194 -337.66777) (xy 235.154216 -337.665314)
			(xy 235.12399 -337.658456) (xy 235.114711 -337.65673) (xy 235.096051 -337.659457) (xy 235.087668 -337.66379)
			(xy 235.061696 -337.678093) (xy 235.006843 -337.700603) (xy 234.949538 -337.715827) (xy 234.890746 -337.72351)
			(xy 234.8611 -337.723988) (xy 234.83112 -337.723538) (xy 234.771672 -337.715709) (xy 234.713756 -337.700184)
			(xy 234.658363 -337.67723) (xy 234.606441 -337.647239) (xy 234.55888 -337.610725) (xy 234.516494 -337.568314)
			(xy 234.480009 -337.520731) (xy 234.450049 -337.468791) (xy 234.427128 -337.413384) (xy 234.411638 -337.355459)
			(xy 234.403844 -337.296007) (xy 234.403392 -337.266026) (xy 227.793296 -337.266026) (xy 227.793296 -338.729828)
			(xy 227.793724 -338.739896) (xy 227.801445 -338.758493) (xy 227.808282 -338.765896) (xy 228.95306 -339.910674)
			(xy 228.960461 -339.917514) (xy 228.979059 -339.92523) (xy 228.989128 -339.92566)
		)
		(stroke
			(width 0)
			(type solid)
		)
		(fill yes)
		(layer "In13.Cu")
		(net "P3V3_AUX")
	)
	(gr_poly
		(pts
			(xy 379.644656 -287.020762) (xy 379.648974 -287.00349) (xy 379.655533 -286.978428) (xy 379.67451 -286.930224)
			(xy 379.699841 -286.885034) (xy 379.731059 -286.843691) (xy 379.767589 -286.806958) (xy 379.787912 -286.790892)
			(xy 379.790452 -286.78886) (xy 379.79477 -286.784542) (xy 379.801445 -286.777262) (xy 379.809145 -286.759095)
			(xy 379.809756 -286.749236) (xy 379.811026 -286.657796) (xy 379.80112 -286.636714) (xy 379.791976 -286.629348)
			(xy 379.770153 -286.611117) (xy 379.731625 -286.569293) (xy 379.699725 -286.52222) (xy 379.675157 -286.470937)
			(xy 379.658465 -286.416579) (xy 379.650017 -286.360346) (xy 379.649482 -286.331914) (xy 379.649968 -286.304663)
			(xy 379.657724 -286.250715) (xy 379.673079 -286.19842) (xy 379.695721 -286.148843) (xy 379.725187 -286.102993)
			(xy 379.760878 -286.061802) (xy 379.802069 -286.026111) (xy 379.847919 -285.996645) (xy 379.897496 -285.974003)
			(xy 379.949791 -285.958648) (xy 380.003739 -285.950892) (xy 380.058241 -285.950892) (xy 380.112189 -285.958648)
			(xy 380.164484 -285.974003) (xy 380.214061 -285.996645) (xy 380.259911 -286.026111) (xy 380.301102 -286.061802)
			(xy 380.336793 -286.102993) (xy 380.366259 -286.148843) (xy 380.388901 -286.19842) (xy 380.404256 -286.250715)
			(xy 380.412012 -286.304663) (xy 380.412498 -286.331914) (xy 380.411945 -286.361071) (xy 380.40307 -286.418706)
			(xy 380.38553 -286.47432) (xy 380.359732 -286.526618) (xy 380.326278 -286.574382) (xy 380.285946 -286.6165)
			(xy 380.263146 -286.634682) (xy 380.260352 -286.636714) (xy 380.254002 -286.643064) (xy 380.252224 -286.645096)
			(xy 380.247082 -286.651947) (xy 380.241239 -286.668038) (xy 380.240794 -286.676592) (xy 380.239524 -286.768286)
			(xy 380.24943 -286.789368) (xy 380.258828 -286.796734) (xy 380.278022 -286.812676) (xy 380.312482 -286.848759)
			(xy 380.341937 -286.889032) (xy 380.36588 -286.932807) (xy 380.383902 -286.979334) (xy 380.390146 -287.00349)
			(xy 380.394464 -287.020762) (xy 380.421642 -287.042352) (xy 381.014478 -287.042352) (xy 381.041656 -287.020762)
			(xy 381.045974 -287.00349) (xy 381.053161 -286.976185) (xy 381.074484 -286.923905) (xy 381.10328 -286.87534)
			(xy 381.138921 -286.831549) (xy 381.180627 -286.79349) (xy 381.227487 -286.761995) (xy 381.278478 -286.737751)
			(xy 381.332485 -286.721288) (xy 381.388329 -286.712965) (xy 381.444791 -286.712965) (xy 381.500635 -286.721288)
			(xy 381.554642 -286.737751) (xy 381.605633 -286.761995) (xy 381.652493 -286.79349) (xy 381.694199 -286.831549)
			(xy 381.72984 -286.87534) (xy 381.758636 -286.923905) (xy 381.779959 -286.976185) (xy 381.787146 -287.00349)
			(xy 381.791464 -287.020762) (xy 381.818642 -287.042352) (xy 381.900938 -287.042352) (xy 381.928116 -287.020762)
			(xy 381.932434 -287.00349) (xy 381.939621 -286.976185) (xy 381.960944 -286.923905) (xy 381.98974 -286.87534)
			(xy 382.025381 -286.831549) (xy 382.067087 -286.79349) (xy 382.113947 -286.761995) (xy 382.164938 -286.737751)
			(xy 382.218945 -286.721288) (xy 382.274789 -286.712965) (xy 382.331251 -286.712965) (xy 382.387095 -286.721288)
			(xy 382.441102 -286.737751) (xy 382.492093 -286.761995) (xy 382.538953 -286.79349) (xy 382.580659 -286.831549)
			(xy 382.6163 -286.87534) (xy 382.645096 -286.923905) (xy 382.666419 -286.976185) (xy 382.673606 -287.00349)
			(xy 382.677924 -287.020762) (xy 382.705102 -287.042352) (xy 384.273298 -287.042352) (xy 384.283367 -287.041928)
			(xy 384.301968 -287.034209) (xy 384.309366 -287.027366) (xy 384.311144 -287.025588) (xy 384.361436 -286.966406)
			(xy 384.365246 -286.961326) (xy 384.369114 -286.954997) (xy 384.373383 -286.940799) (xy 384.373628 -286.933386)
			(xy 384.373628 -286.92475) (xy 384.37312 -286.92094) (xy 384.371466 -286.909518) (xy 384.369684 -286.886506)
			(xy 384.369564 -286.874966) (xy 384.370086 -286.849711) (xy 384.378399 -286.799889) (xy 384.3948 -286.752115)
			(xy 384.418841 -286.707692) (xy 384.449865 -286.667832) (xy 384.487027 -286.633622) (xy 384.529313 -286.605996)
			(xy 384.575569 -286.585706) (xy 384.624534 -286.573306) (xy 384.674872 -286.569135) (xy 384.72521 -286.573306)
			(xy 384.774175 -286.585706) (xy 384.820431 -286.605996) (xy 384.862717 -286.633622) (xy 384.899879 -286.667832)
			(xy 384.930903 -286.707692) (xy 384.954944 -286.752115) (xy 384.971345 -286.799889) (xy 384.979658 -286.849711)
			(xy 384.98018 -286.874966) (xy 384.980049 -286.887342) (xy 384.978011 -286.912011) (xy 384.976116 -286.924242)
			(xy 384.974338 -286.935418) (xy 384.98018 -286.956754) (xy 385.037584 -287.024318) (xy 385.045175 -287.032449)
			(xy 385.065335 -287.04179) (xy 385.076446 -287.042352) (xy 385.223258 -287.042352) (xy 385.233322 -287.041917)
			(xy 385.251907 -287.034182) (xy 385.259326 -287.027366) (xy 385.261104 -287.025588) (xy 385.311396 -286.966406)
			(xy 385.315206 -286.961326) (xy 385.319076 -286.954998) (xy 385.323349 -286.940799) (xy 385.323588 -286.933386)
			(xy 385.323588 -286.92475) (xy 385.32308 -286.92094) (xy 385.321426 -286.909518) (xy 385.319645 -286.886506)
			(xy 385.319524 -286.874966) (xy 385.320046 -286.849711) (xy 385.328359 -286.799889) (xy 385.34476 -286.752115)
			(xy 385.368801 -286.707692) (xy 385.399825 -286.667832) (xy 385.436987 -286.633622) (xy 385.479273 -286.605996)
			(xy 385.525529 -286.585706) (xy 385.574494 -286.573306) (xy 385.624832 -286.569135) (xy 385.67517 -286.573306)
			(xy 385.724135 -286.585706) (xy 385.770391 -286.605996) (xy 385.812677 -286.633622) (xy 385.849839 -286.667832)
			(xy 385.880863 -286.707692) (xy 385.904904 -286.752115) (xy 385.921305 -286.799889) (xy 385.929618 -286.849711)
			(xy 385.93014 -286.874966) (xy 385.930009 -286.887342) (xy 385.927971 -286.912011) (xy 385.926076 -286.924242)
			(xy 385.924298 -286.935418) (xy 385.93014 -286.956754) (xy 385.987544 -287.024318) (xy 385.995133 -287.032455)
			(xy 386.015292 -287.041812) (xy 386.026406 -287.042352) (xy 396.570454 -287.042352) (xy 396.580519 -287.041918)
			(xy 396.599104 -287.034184) (xy 396.606522 -287.027366) (xy 396.712694 -286.921194) (xy 396.720568 -286.901128)
			(xy 396.72006 -286.890206) (xy 396.719552 -286.874966) (xy 396.719552 -286.874712) (xy 396.720043 -286.850747)
			(xy 396.727577 -286.803412) (xy 396.742414 -286.757836) (xy 396.76419 -286.715137) (xy 396.79237 -286.676366)
			(xy 396.826261 -286.642473) (xy 396.865032 -286.614293) (xy 396.90773 -286.592516) (xy 396.953306 -286.577678)
			(xy 397.000641 -286.570144) (xy 397.024606 -286.569658) (xy 397.02486 -286.569658) (xy 397.0401 -286.570166)
			(xy 397.045427 -286.570237) (xy 397.055925 -286.568442) (xy 397.060928 -286.56661) (xy 397.071088 -286.5628)
			(xy 397.310864 -286.323024) (xy 397.317556 -286.315617) (xy 397.325152 -286.297181) (xy 397.325596 -286.28721)
			(xy 397.325596 -286.2072) (xy 397.32585 -286.202374) (xy 397.32585 -286.201358) (xy 397.32585 -285.650432)
			(xy 397.32585 -285.648146) (xy 397.32585 -285.64713) (xy 397.325596 -285.642304) (xy 397.325596 -285.25724)
			(xy 397.32585 -285.252414) (xy 397.32585 -285.251398) (xy 397.32585 -284.700472) (xy 397.32585 -284.698186)
			(xy 397.32585 -284.69717) (xy 397.325596 -284.692344) (xy 397.325596 -284.30728) (xy 397.32585 -284.302454)
			(xy 397.32585 -284.301438) (xy 397.32585 -283.750512) (xy 397.32585 -283.748226) (xy 397.32585 -283.74721)
			(xy 397.325596 -283.742384) (xy 397.325596 -283.429456) (xy 397.325088 -283.42209) (xy 397.322956 -283.41109)
			(xy 397.310702 -283.392364) (xy 397.301466 -283.386022) (xy 397.30045 -283.385514) (xy 397.225266 -283.341572)
			(xy 397.219467 -283.33838) (xy 397.206732 -283.33478) (xy 397.20012 -283.33446) (xy 397.186658 -283.33446)
			(xy 397.174974 -283.341064) (xy 397.17472 -283.341064) (xy 397.15176 -283.353341) (xy 397.102699 -283.37076)
			(xy 397.051398 -283.379628) (xy 397.025368 -283.38018) (xy 397.02486 -283.38018) (xy 396.999609 -283.379655)
			(xy 396.949797 -283.371337) (xy 396.902033 -283.354934) (xy 396.85762 -283.330894) (xy 396.81777 -283.299872)
			(xy 396.783568 -283.262715) (xy 396.755948 -283.220435) (xy 396.735664 -283.174186) (xy 396.723267 -283.125229)
			(xy 396.719097 -283.0749) (xy 396.723267 -283.024571) (xy 396.735664 -282.975614) (xy 396.755948 -282.929365)
			(xy 396.783568 -282.887085) (xy 396.81777 -282.849928) (xy 396.85762 -282.818906) (xy 396.902033 -282.794866)
			(xy 396.949797 -282.778463) (xy 396.999609 -282.770145) (xy 397.02486 -282.769564) (xy 397.025368 -282.769564)
			(xy 397.047585 -282.769977) (xy 397.091546 -282.776444) (xy 397.134105 -282.789217) (xy 397.1544 -282.798266)
			(xy 397.161512 -282.801568) (xy 397.163544 -282.802584) (xy 397.169112 -282.805389) (xy 397.181188 -282.80848)
			(xy 397.18742 -282.80868) (xy 397.210788 -282.80868) (xy 397.217597 -282.808462) (xy 397.230729 -282.804856)
			(xy 397.236696 -282.801568) (xy 397.300704 -282.763976) (xy 397.308108 -282.759147) (xy 397.319331 -282.745509)
			(xy 397.325249 -282.728867) (xy 397.325596 -282.720034) (xy 397.325596 -282.40736) (xy 397.32585 -282.402534)
			(xy 397.32585 -282.401518) (xy 397.32585 -281.958288) (xy 397.325257 -281.946239) (xy 397.314388 -281.924742)
			(xy 397.305022 -281.91714) (xy 397.284361 -281.901448) (xy 397.24773 -281.864711) (xy 397.217284 -281.822705)
			(xy 397.19377 -281.776461) (xy 397.177764 -281.727113) (xy 397.16966 -281.675871) (xy 397.169132 -281.649932)
			(xy 397.169543 -281.625829) (xy 397.176553 -281.578136) (xy 397.183102 -281.554936) (xy 397.185738 -281.544266)
			(xy 397.182668 -281.522525) (xy 397.170787 -281.50406) (xy 397.152273 -281.492257) (xy 397.13052 -281.489278)
			(xy 397.119856 -281.491944) (xy 397.106679 -281.495713) (xy 397.079847 -281.501305) (xy 397.066262 -281.50312)
			(xy 397.065754 -281.503374) (xy 397.059658 -281.504136) (xy 397.024606 -281.505914) (xy 396.998613 -281.505405)
			(xy 396.947265 -281.497277) (xy 396.897821 -281.481219) (xy 396.851496 -281.457626) (xy 396.809429 -281.42708)
			(xy 396.772658 -281.390332) (xy 396.742084 -281.348285) (xy 396.718463 -281.301975) (xy 396.702373 -281.252541)
			(xy 396.694212 -281.201199) (xy 396.693644 -281.175206) (xy 396.693644 -280.224992) (xy 396.694154 -280.199004)
			(xy 396.702285 -280.147668) (xy 396.718346 -280.098235) (xy 396.741942 -280.051923) (xy 396.772491 -280.009872)
			(xy 396.809242 -279.973117) (xy 396.851289 -279.942563) (xy 396.897598 -279.918962) (xy 396.947029 -279.902895)
			(xy 396.998364 -279.894757) (xy 397.024352 -279.894284) (xy 397.024606 -279.894284) (xy 397.034024 -279.894319)
			(xy 397.052832 -279.895334) (xy 397.062198 -279.896316) (xy 397.073882 -279.897586) (xy 397.095472 -279.89022)
			(xy 397.16837 -279.81783) (xy 397.17599 -279.79624) (xy 397.17472 -279.784556) (xy 397.172688 -279.749504)
			(xy 397.173174 -279.724039) (xy 397.181072 -279.673724) (xy 397.196677 -279.625243) (xy 397.219612 -279.579769)
			(xy 397.249321 -279.538401) (xy 397.285087 -279.502142) (xy 397.305276 -279.486614) (xy 397.314493 -279.478998)
			(xy 397.325211 -279.457661) (xy 397.32585 -279.44572) (xy 397.32585 -279.108154) (xy 397.325249 -279.096109)
			(xy 397.314372 -279.074624) (xy 397.305022 -279.067006) (xy 397.284358 -279.051316) (xy 397.247721 -279.014583)
			(xy 397.21727 -278.972579) (xy 397.193753 -278.926334) (xy 397.177747 -278.876984) (xy 397.169644 -278.825739)
			(xy 397.169644 -278.773858) (xy 397.177747 -278.722614) (xy 397.193754 -278.673264) (xy 397.217271 -278.627019)
			(xy 397.247722 -278.585015) (xy 397.28436 -278.548282) (xy 397.305022 -278.53259) (xy 397.314326 -278.524937)
			(xy 397.32519 -278.503471) (xy 397.32585 -278.491442) (xy 397.32585 -278.158194) (xy 397.325258 -278.146144)
			(xy 397.31439 -278.124645) (xy 397.305022 -278.117046) (xy 397.284355 -278.101357) (xy 397.247711 -278.064622)
			(xy 397.217254 -278.022616) (xy 397.193731 -277.976368) (xy 397.17772 -277.927014) (xy 397.169613 -277.875765)
			(xy 397.16961 -277.823879) (xy 397.17771 -277.772629) (xy 397.193714 -277.723273) (xy 397.217231 -277.677022)
			(xy 397.247682 -277.635012) (xy 397.284321 -277.598273) (xy 397.305022 -277.58263) (xy 397.314332 -277.57498)
			(xy 397.325213 -277.553514) (xy 397.32585 -277.541482) (xy 397.32585 -277.208234) (xy 397.325245 -277.196191)
			(xy 397.314363 -277.174713) (xy 397.305022 -277.167086) (xy 397.28436 -277.151396) (xy 397.247725 -277.114664)
			(xy 397.217277 -277.07266) (xy 397.193763 -277.026417) (xy 397.17776 -276.977068) (xy 397.169659 -276.925826)
			(xy 397.169661 -276.873948) (xy 397.177766 -276.822706) (xy 397.193773 -276.773359) (xy 397.217291 -276.727118)
			(xy 397.247742 -276.685117) (xy 397.284379 -276.648387) (xy 397.305022 -276.63267) (xy 397.314322 -276.625016)
			(xy 397.325178 -276.603549) (xy 397.32585 -276.591522) (xy 397.32585 -276.253702) (xy 397.325198 -276.24177)
			(xy 397.31446 -276.220456) (xy 397.305276 -276.212808) (xy 397.285086 -276.19728) (xy 397.249318 -276.161021)
			(xy 397.219606 -276.119654) (xy 397.196668 -276.07418) (xy 397.18106 -276.025699) (xy 397.173159 -275.975384)
			(xy 397.172688 -275.949918) (xy 397.17472 -275.915374) (xy 397.17599 -275.90369) (xy 397.168116 -275.8821)
			(xy 397.095218 -275.809964) (xy 397.073628 -275.802344) (xy 397.061944 -275.803868) (xy 397.05264 -275.804836)
			(xy 397.03396 -275.80585) (xy 397.024606 -275.8059) (xy 396.998597 -275.805391) (xy 396.947221 -275.797255)
			(xy 396.897749 -275.781183) (xy 396.8514 -275.757569) (xy 396.809316 -275.726997) (xy 396.772532 -275.690218)
			(xy 396.741954 -275.648137) (xy 396.718334 -275.601792) (xy 396.702255 -275.552322) (xy 396.694113 -275.500946)
			(xy 396.693644 -275.474938) (xy 396.693644 -274.524978) (xy 396.693679 -274.51556) (xy 396.694695 -274.496753)
			(xy 396.695676 -274.487386) (xy 396.6972 -274.475956) (xy 396.68958 -274.454366) (xy 396.617444 -274.381468)
			(xy 396.595854 -274.373848) (xy 396.58417 -274.374864) (xy 396.54988 -274.376896) (xy 396.524166 -274.376416)
			(xy 396.473373 -274.368368) (xy 396.424464 -274.352473) (xy 396.378643 -274.329122) (xy 396.33704 -274.298891)
			(xy 396.300678 -274.262524) (xy 396.270453 -274.220916) (xy 396.247109 -274.175092) (xy 396.231221 -274.12618)
			(xy 396.22318 -274.075386) (xy 396.223185 -274.023958) (xy 396.231234 -273.973165) (xy 396.24713 -273.924256)
			(xy 396.270482 -273.878436) (xy 396.300714 -273.836834) (xy 396.337082 -273.800473) (xy 396.378691 -273.770249)
			(xy 396.424515 -273.746906) (xy 396.473427 -273.731019) (xy 396.524222 -273.722979) (xy 396.57565 -273.722985)
			(xy 396.626443 -273.731036) (xy 396.675351 -273.746933) (xy 396.721171 -273.770286) (xy 396.762772 -273.800519)
			(xy 396.799133 -273.836888) (xy 396.829356 -273.878498) (xy 396.852697 -273.924323) (xy 396.868583 -273.973235)
			(xy 396.876621 -274.02403) (xy 396.877032 -274.049744) (xy 396.875 -274.084288) (xy 396.87373 -274.095972)
			(xy 396.881604 -274.117562) (xy 396.954248 -274.189952) (xy 396.975838 -274.197318) (xy 396.987522 -274.196048)
			(xy 396.9967 -274.195094) (xy 397.015125 -274.194079) (xy 397.024352 -274.194016) (xy 397.024606 -274.194016)
			(xy 397.05788 -274.195794) (xy 397.058134 -274.196048) (xy 397.059404 -274.196048) (xy 397.070834 -274.197318)
			(xy 397.092424 -274.189698) (xy 397.16456 -274.117562) (xy 397.17218 -274.095972) (xy 397.17091 -274.084288)
			(xy 397.169132 -274.049744) (xy 397.169635 -274.023803) (xy 397.177734 -273.972556) (xy 397.193739 -273.923204)
			(xy 397.217258 -273.876958) (xy 397.247713 -273.834954) (xy 397.284356 -273.798224) (xy 397.305022 -273.782536)
			(xy 397.314333 -273.774886) (xy 397.325217 -273.75342) (xy 397.32585 -273.741388) (xy 397.32585 -273.40814)
			(xy 397.325246 -273.396096) (xy 397.314366 -273.374616) (xy 397.305022 -273.366992) (xy 397.284359 -273.351302)
			(xy 397.247724 -273.314569) (xy 397.217275 -273.272566) (xy 397.19376 -273.226322) (xy 397.177756 -273.176973)
			(xy 397.169655 -273.12573) (xy 397.169656 -273.073851) (xy 397.17776 -273.022609) (xy 397.193767 -272.973261)
			(xy 397.217285 -272.927018) (xy 397.247736 -272.885016) (xy 397.284373 -272.848285) (xy 397.305022 -272.832576)
			(xy 397.314323 -272.824922) (xy 397.325181 -272.803456) (xy 397.32585 -272.791428) (xy 397.32585 -271.715484)
			(xy 397.32585 -271.713198) (xy 397.32585 -271.712182) (xy 397.325596 -271.707356) (xy 397.325596 -261.6073)
			(xy 397.32585 -261.602474) (xy 397.32585 -261.601458) (xy 397.32585 -250.530868) (xy 397.32542 -250.520802)
			(xy 397.317691 -250.50221) (xy 397.310864 -250.4948) (xy 396.451836 -249.635772) (xy 396.444438 -249.628928)
			(xy 396.425838 -249.621205) (xy 396.415768 -249.620786) (xy 388.583424 -249.620786) (xy 388.573399 -249.621201)
			(xy 388.554871 -249.628866) (xy 388.540688 -249.643039) (xy 388.533009 -249.661561) (xy 388.532624 -249.671586)
			(xy 388.532624 -250.155456) (xy 388.532052 -250.18553) (xy 388.522614 -250.244935) (xy 388.503995 -250.30213)
			(xy 388.476655 -250.355707) (xy 388.441267 -250.404344) (xy 388.420356 -250.425966) (xy 388.03072 -250.815602)
			(xy 388.02394 -250.823026) (xy 388.016344 -250.841623) (xy 388.015988 -250.85167) (xy 388.015988 -251.15266)
			(xy 388.015877 -251.158502) (xy 388.516366 -251.158502) (xy 388.520437 -251.10288) (xy 388.532563 -251.048443)
			(xy 388.552486 -250.996352) (xy 388.579782 -250.947717) (xy 388.613868 -250.903574) (xy 388.654017 -250.864865)
			(xy 388.699375 -250.832414) (xy 388.748975 -250.806913) (xy 388.801759 -250.788906) (xy 388.856602 -250.778776)
			(xy 388.912336 -250.776739) (xy 388.967773 -250.782839) (xy 389.02173 -250.796945) (xy 389.073059 -250.818757)
			(xy 389.120665 -250.847811) (xy 389.163533 -250.883486) (xy 389.20075 -250.925023) (xy 389.231523 -250.971536)
			(xy 389.255195 -251.022033) (xy 389.271263 -251.07544) (xy 389.279383 -251.130616) (xy 389.279892 -251.158502)
			(xy 389.279383 -251.186388) (xy 389.271263 -251.241564) (xy 389.255195 -251.294971) (xy 389.231523 -251.345468)
			(xy 389.20075 -251.391981) (xy 389.163533 -251.433518) (xy 389.120665 -251.469193) (xy 389.073059 -251.498247)
			(xy 389.02173 -251.520059) (xy 388.967773 -251.534165) (xy 388.912336 -251.540265) (xy 388.856602 -251.538228)
			(xy 388.801759 -251.528098) (xy 388.748975 -251.510091) (xy 388.699375 -251.48459) (xy 388.654017 -251.452139)
			(xy 388.613868 -251.41343) (xy 388.579782 -251.369287) (xy 388.552486 -251.320652) (xy 388.532563 -251.268561)
			(xy 388.520437 -251.214124) (xy 388.516366 -251.158502) (xy 388.015877 -251.158502) (xy 388.015415 -251.182734)
			(xy 388.005976 -251.242137) (xy 387.987356 -251.299331) (xy 387.960013 -251.352906) (xy 387.924622 -251.40154)
			(xy 387.90372 -251.42317) (xy 386.716524 -252.610366) (xy 386.694872 -252.631231) (xy 386.646229 -252.666575)
			(xy 386.592654 -252.693871) (xy 386.535467 -252.712447) (xy 386.476078 -252.721843) (xy 386.446014 -252.72238)
			(xy 371.741954 -252.72238) (xy 371.711894 -252.721788) (xy 371.652516 -252.712382) (xy 371.595337 -252.693809)
			(xy 371.541766 -252.666526) (xy 371.493118 -252.631202) (xy 371.471444 -252.610366) (xy 370.447316 -251.586238)
			(xy 370.426459 -251.564569) (xy 370.39108 -251.515935) (xy 370.363738 -251.46237) (xy 370.345104 -251.405188)
			(xy 370.335638 -251.345798) (xy 370.335048 -251.315728) (xy 370.335539 -251.288567) (xy 370.343264 -251.234797)
			(xy 370.358533 -251.182664) (xy 370.369338 -251.15774) (xy 370.375942 -251.143008) (xy 370.370354 -251.112274)
			(xy 369.919758 -250.661932) (xy 369.912324 -250.655216) (xy 369.893824 -250.64758) (xy 369.87381 -250.64758)
			(xy 369.85531 -250.655216) (xy 369.847876 -250.661932) (xy 368.129566 -252.380242) (xy 368.1222 -252.387354)
			(xy 368.11458 -252.40615) (xy 368.11458 -253.620778) (xy 369.687346 -253.620778) (xy 369.691417 -253.565156)
			(xy 369.703543 -253.510719) (xy 369.723466 -253.458628) (xy 369.750762 -253.409993) (xy 369.784848 -253.36585)
			(xy 369.824997 -253.327141) (xy 369.870355 -253.29469) (xy 369.919955 -253.269189) (xy 369.972739 -253.251182)
			(xy 370.027582 -253.241052) (xy 370.083316 -253.239015) (xy 370.138753 -253.245115) (xy 370.19271 -253.259221)
			(xy 370.244039 -253.281033) (xy 370.291645 -253.310087) (xy 370.334513 -253.345762) (xy 370.37173 -253.387299)
			(xy 370.402503 -253.433812) (xy 370.413111 -253.45644) (xy 387.500366 -253.45644) (xy 387.504437 -253.400818)
			(xy 387.516563 -253.346381) (xy 387.536486 -253.29429) (xy 387.563782 -253.245655) (xy 387.597868 -253.201512)
			(xy 387.638017 -253.162803) (xy 387.683375 -253.130352) (xy 387.732975 -253.104851) (xy 387.785759 -253.086844)
			(xy 387.840602 -253.076714) (xy 387.896336 -253.074677) (xy 387.951773 -253.080777) (xy 388.00573 -253.094883)
			(xy 388.057059 -253.116695) (xy 388.104665 -253.145749) (xy 388.147533 -253.181424) (xy 388.18475 -253.222961)
			(xy 388.215523 -253.269474) (xy 388.239195 -253.319971) (xy 388.255263 -253.373378) (xy 388.263383 -253.428554)
			(xy 388.263892 -253.45644) (xy 388.263383 -253.484326) (xy 388.255263 -253.539502) (xy 388.239195 -253.592909)
			(xy 388.215523 -253.643406) (xy 388.18475 -253.689919) (xy 388.147533 -253.731456) (xy 388.104665 -253.767131)
			(xy 388.057059 -253.796185) (xy 388.00573 -253.817997) (xy 387.951773 -253.832103) (xy 387.896336 -253.838203)
			(xy 387.840602 -253.836166) (xy 387.785759 -253.826036) (xy 387.732975 -253.808029) (xy 387.683375 -253.782528)
			(xy 387.638017 -253.750077) (xy 387.597868 -253.711368) (xy 387.563782 -253.667225) (xy 387.536486 -253.61859)
			(xy 387.516563 -253.566499) (xy 387.504437 -253.512062) (xy 387.500366 -253.45644) (xy 370.413111 -253.45644)
			(xy 370.426175 -253.484309) (xy 370.442243 -253.537716) (xy 370.450363 -253.592892) (xy 370.450872 -253.620778)
			(xy 370.450363 -253.648664) (xy 370.442243 -253.70384) (xy 370.426175 -253.757247) (xy 370.402503 -253.807744)
			(xy 370.37173 -253.854257) (xy 370.334513 -253.895794) (xy 370.291645 -253.931469) (xy 370.244039 -253.960523)
			(xy 370.19271 -253.982335) (xy 370.138753 -253.996441) (xy 370.083316 -254.002541) (xy 370.027582 -254.000504)
			(xy 369.972739 -253.990374) (xy 369.919955 -253.972367) (xy 369.870355 -253.946866) (xy 369.824997 -253.914415)
			(xy 369.784848 -253.875706) (xy 369.750762 -253.831563) (xy 369.723466 -253.782928) (xy 369.703543 -253.730837)
			(xy 369.691417 -253.6764) (xy 369.687346 -253.620778) (xy 368.11458 -253.620778) (xy 368.11458 -254.148844)
			(xy 368.115011 -254.158911) (xy 368.122734 -254.177506) (xy 368.129566 -254.184912) (xy 368.567716 -254.623062)
			(xy 374.28373 -254.623062) (xy 374.287801 -254.56744) (xy 374.299927 -254.513003) (xy 374.31985 -254.460912)
			(xy 374.347146 -254.412277) (xy 374.381232 -254.368134) (xy 374.421381 -254.329425) (xy 374.466739 -254.296974)
			(xy 374.516339 -254.271473) (xy 374.569123 -254.253466) (xy 374.623966 -254.243336) (xy 374.6797 -254.241299)
			(xy 374.735137 -254.247399) (xy 374.789094 -254.261505) (xy 374.840423 -254.283317) (xy 374.888029 -254.312371)
			(xy 374.930897 -254.348046) (xy 374.968114 -254.389583) (xy 374.998887 -254.436096) (xy 375.022559 -254.486593)
			(xy 375.032515 -254.519684) (xy 377.383546 -254.519684) (xy 377.387617 -254.464062) (xy 377.399743 -254.409625)
			(xy 377.419666 -254.357534) (xy 377.446962 -254.308899) (xy 377.481048 -254.264756) (xy 377.521197 -254.226047)
			(xy 377.566555 -254.193596) (xy 377.616155 -254.168095) (xy 377.668939 -254.150088) (xy 377.723782 -254.139958)
			(xy 377.779516 -254.137921) (xy 377.834953 -254.144021) (xy 377.88891 -254.158127) (xy 377.940239 -254.179939)
			(xy 377.987845 -254.208993) (xy 378.030713 -254.244668) (xy 378.06793 -254.286205) (xy 378.098703 -254.332718)
			(xy 378.122375 -254.383215) (xy 378.138443 -254.436622) (xy 378.146563 -254.491798) (xy 378.147072 -254.519684)
			(xy 378.146563 -254.54757) (xy 378.138443 -254.602746) (xy 378.122375 -254.656153) (xy 378.098703 -254.70665)
			(xy 378.06793 -254.753163) (xy 378.030713 -254.7947) (xy 377.987845 -254.830375) (xy 377.940239 -254.859429)
			(xy 377.88891 -254.881241) (xy 377.834953 -254.895347) (xy 377.779516 -254.901447) (xy 377.723782 -254.89941)
			(xy 377.668939 -254.88928) (xy 377.616155 -254.871273) (xy 377.566555 -254.845772) (xy 377.521197 -254.813321)
			(xy 377.481048 -254.774612) (xy 377.446962 -254.730469) (xy 377.419666 -254.681834) (xy 377.399743 -254.629743)
			(xy 377.387617 -254.575306) (xy 377.383546 -254.519684) (xy 375.032515 -254.519684) (xy 375.038627 -254.54)
			(xy 375.046747 -254.595176) (xy 375.047256 -254.623062) (xy 375.046747 -254.650948) (xy 375.038627 -254.706124)
			(xy 375.022559 -254.759531) (xy 374.998887 -254.810028) (xy 374.968114 -254.856541) (xy 374.930897 -254.898078)
			(xy 374.888029 -254.933753) (xy 374.840423 -254.962807) (xy 374.789094 -254.984619) (xy 374.735137 -254.998725)
			(xy 374.6797 -255.004825) (xy 374.623966 -255.002788) (xy 374.569123 -254.992658) (xy 374.516339 -254.974651)
			(xy 374.466739 -254.94915) (xy 374.421381 -254.916699) (xy 374.381232 -254.87799) (xy 374.347146 -254.833847)
			(xy 374.31985 -254.785212) (xy 374.299927 -254.733121) (xy 374.287801 -254.678684) (xy 374.28373 -254.623062)
			(xy 368.567716 -254.623062) (xy 369.167918 -255.223264) (xy 378.137672 -255.223264) (xy 378.141743 -255.167642)
			(xy 378.153869 -255.113205) (xy 378.173792 -255.061114) (xy 378.201088 -255.012479) (xy 378.235174 -254.968336)
			(xy 378.275323 -254.929627) (xy 378.320681 -254.897176) (xy 378.370281 -254.871675) (xy 378.423065 -254.853668)
			(xy 378.477908 -254.843538) (xy 378.533642 -254.841501) (xy 378.589079 -254.847601) (xy 378.643036 -254.861707)
			(xy 378.694365 -254.883519) (xy 378.741971 -254.912573) (xy 378.784839 -254.948248) (xy 378.822056 -254.989785)
			(xy 378.852829 -255.036298) (xy 378.876501 -255.086795) (xy 378.892569 -255.140202) (xy 378.900689 -255.195378)
			(xy 378.901198 -255.223264) (xy 378.900689 -255.25115) (xy 378.892569 -255.306326) (xy 378.876501 -255.359733)
			(xy 378.852829 -255.41023) (xy 378.822056 -255.456743) (xy 378.784839 -255.49828) (xy 378.741971 -255.533955)
			(xy 378.694365 -255.563009) (xy 378.643036 -255.584821) (xy 378.589079 -255.598927) (xy 378.533642 -255.605027)
			(xy 378.477908 -255.60299) (xy 378.423065 -255.59286) (xy 378.370281 -255.574853) (xy 378.320681 -255.549352)
			(xy 378.275323 -255.516901) (xy 378.235174 -255.478192) (xy 378.201088 -255.434049) (xy 378.173792 -255.385414)
			(xy 378.153869 -255.333323) (xy 378.141743 -255.278886) (xy 378.137672 -255.223264) (xy 369.167918 -255.223264)
			(xy 369.256818 -255.312164) (xy 369.270265 -255.326023) (xy 369.294202 -255.356325) (xy 369.30457 -255.372616)
			(xy 369.307618 -255.377696) (xy 369.3287 -255.398778) (xy 369.335498 -255.406128) (xy 369.343202 -255.42459)
			(xy 369.343686 -255.434592) (xy 369.343686 -255.464564) (xy 369.344956 -255.470406) (xy 369.349198 -255.489235)
			(xy 369.35378 -255.527561) (xy 369.3541 -255.54686) (xy 369.3541 -255.910588) (xy 370.17655 -255.910588)
			(xy 370.180621 -255.854966) (xy 370.192747 -255.800529) (xy 370.21267 -255.748438) (xy 370.239966 -255.699803)
			(xy 370.274052 -255.65566) (xy 370.314201 -255.616951) (xy 370.359559 -255.5845) (xy 370.409159 -255.558999)
			(xy 370.461943 -255.540992) (xy 370.516786 -255.530862) (xy 370.57252 -255.528825) (xy 370.627957 -255.534925)
			(xy 370.681914 -255.549031) (xy 370.733243 -255.570843) (xy 370.780849 -255.599897) (xy 370.823717 -255.635572)
			(xy 370.860934 -255.677109) (xy 370.868531 -255.688592) (xy 371.895114 -255.688592) (xy 371.899185 -255.63297)
			(xy 371.911311 -255.578533) (xy 371.931234 -255.526442) (xy 371.95853 -255.477807) (xy 371.992616 -255.433664)
			(xy 372.032765 -255.394955) (xy 372.078123 -255.362504) (xy 372.127723 -255.337003) (xy 372.180507 -255.318996)
			(xy 372.23535 -255.308866) (xy 372.291084 -255.306829) (xy 372.346521 -255.312929) (xy 372.400478 -255.327035)
			(xy 372.451807 -255.348847) (xy 372.499413 -255.377901) (xy 372.542281 -255.413576) (xy 372.579498 -255.455113)
			(xy 372.610271 -255.501626) (xy 372.633943 -255.552123) (xy 372.650011 -255.60553) (xy 372.658131 -255.660706)
			(xy 372.65864 -255.688592) (xy 372.658131 -255.716478) (xy 372.650011 -255.771654) (xy 372.633943 -255.825061)
			(xy 372.610271 -255.875558) (xy 372.579498 -255.922071) (xy 372.542281 -255.963608) (xy 372.499413 -255.999283)
			(xy 372.451807 -256.028337) (xy 372.400478 -256.050149) (xy 372.346521 -256.064255) (xy 372.291084 -256.070355)
			(xy 372.23535 -256.068318) (xy 372.180507 -256.058188) (xy 372.127723 -256.040181) (xy 372.078123 -256.01468)
			(xy 372.032765 -255.982229) (xy 371.992616 -255.94352) (xy 371.95853 -255.899377) (xy 371.931234 -255.850742)
			(xy 371.911311 -255.798651) (xy 371.899185 -255.744214) (xy 371.895114 -255.688592) (xy 370.868531 -255.688592)
			(xy 370.891707 -255.723622) (xy 370.915379 -255.774119) (xy 370.931447 -255.827526) (xy 370.939567 -255.882702)
			(xy 370.940076 -255.910588) (xy 370.939567 -255.938474) (xy 370.931447 -255.99365) (xy 370.915379 -256.047057)
			(xy 370.891707 -256.097554) (xy 370.884664 -256.1082) (xy 374.28373 -256.1082) (xy 374.287801 -256.052578)
			(xy 374.299927 -255.998141) (xy 374.31985 -255.94605) (xy 374.347146 -255.897415) (xy 374.381232 -255.853272)
			(xy 374.421381 -255.814563) (xy 374.466739 -255.782112) (xy 374.516339 -255.756611) (xy 374.569123 -255.738604)
			(xy 374.623966 -255.728474) (xy 374.6797 -255.726437) (xy 374.735137 -255.732537) (xy 374.789094 -255.746643)
			(xy 374.840423 -255.768455) (xy 374.888029 -255.797509) (xy 374.930897 -255.833184) (xy 374.968114 -255.874721)
			(xy 374.998887 -255.921234) (xy 375.022559 -255.971731) (xy 375.038627 -256.025138) (xy 375.046747 -256.080314)
			(xy 375.047256 -256.1082) (xy 375.046747 -256.136086) (xy 375.038627 -256.191262) (xy 375.022559 -256.244669)
			(xy 374.998887 -256.295166) (xy 374.968114 -256.341679) (xy 374.930897 -256.383216) (xy 374.888029 -256.418891)
			(xy 374.840423 -256.447945) (xy 374.789094 -256.469757) (xy 374.735137 -256.483863) (xy 374.6797 -256.489963)
			(xy 374.623966 -256.487926) (xy 374.569123 -256.477796) (xy 374.516339 -256.459789) (xy 374.466739 -256.434288)
			(xy 374.421381 -256.401837) (xy 374.381232 -256.363128) (xy 374.347146 -256.318985) (xy 374.31985 -256.27035)
			(xy 374.299927 -256.218259) (xy 374.287801 -256.163822) (xy 374.28373 -256.1082) (xy 370.884664 -256.1082)
			(xy 370.860934 -256.144067) (xy 370.823717 -256.185604) (xy 370.780849 -256.221279) (xy 370.733243 -256.250333)
			(xy 370.681914 -256.272145) (xy 370.627957 -256.286251) (xy 370.57252 -256.292351) (xy 370.516786 -256.290314)
			(xy 370.461943 -256.280184) (xy 370.409159 -256.262177) (xy 370.359559 -256.236676) (xy 370.314201 -256.204225)
			(xy 370.274052 -256.165516) (xy 370.239966 -256.121373) (xy 370.21267 -256.072738) (xy 370.192747 -256.020647)
			(xy 370.180621 -255.96621) (xy 370.17655 -255.910588) (xy 369.3541 -255.910588) (xy 369.3541 -257.474212)
			(xy 370.2718 -257.474212) (xy 370.275871 -257.41859) (xy 370.287997 -257.364153) (xy 370.30792 -257.312062)
			(xy 370.335216 -257.263427) (xy 370.369302 -257.219284) (xy 370.409451 -257.180575) (xy 370.454809 -257.148124)
			(xy 370.504409 -257.122623) (xy 370.557193 -257.104616) (xy 370.612036 -257.094486) (xy 370.66777 -257.092449)
			(xy 370.723207 -257.098549) (xy 370.777164 -257.112655) (xy 370.828493 -257.134467) (xy 370.834144 -257.137916)
			(xy 382.596136 -257.137916) (xy 382.596671 -257.108533) (xy 382.605701 -257.050465) (xy 382.623533 -256.994471)
			(xy 382.649745 -256.941875) (xy 382.683717 -256.893924) (xy 382.724644 -256.851753) (xy 382.747774 -256.833624)
			(xy 382.757172 -256.826258) (xy 382.767586 -256.805684) (xy 382.76911 -256.701798) (xy 382.759204 -256.680716)
			(xy 382.75006 -256.67335) (xy 382.728198 -256.655161) (xy 382.68966 -256.613337) (xy 382.657756 -256.566258)
			(xy 382.633192 -256.514965) (xy 382.616511 -256.460595) (xy 382.608084 -256.404352) (xy 382.607566 -256.375916)
			(xy 382.608052 -256.348665) (xy 382.615808 -256.294717) (xy 382.631163 -256.242422) (xy 382.653805 -256.192845)
			(xy 382.683271 -256.146995) (xy 382.718962 -256.105804) (xy 382.760153 -256.070113) (xy 382.806003 -256.040647)
			(xy 382.85558 -256.018005) (xy 382.907875 -256.00265) (xy 382.961823 -255.994894) (xy 383.016325 -255.994894)
			(xy 383.070273 -256.00265) (xy 383.122568 -256.018005) (xy 383.172145 -256.040647) (xy 383.217995 -256.070113)
			(xy 383.259186 -256.105804) (xy 383.294877 -256.146995) (xy 383.324343 -256.192845) (xy 383.346985 -256.242422)
			(xy 383.36234 -256.294717) (xy 383.370096 -256.348665) (xy 383.370582 -256.375916) (xy 383.370063 -256.405299)
			(xy 383.361029 -256.463367) (xy 383.343193 -256.519362) (xy 383.316978 -256.571958) (xy 383.283003 -256.619908)
			(xy 383.242074 -256.662079) (xy 383.218944 -256.680208) (xy 383.209546 -256.687574) (xy 383.199132 -256.708148)
			(xy 383.197608 -256.812034) (xy 383.207514 -256.833116) (xy 383.216658 -256.840482) (xy 383.238471 -256.858728)
			(xy 383.277015 -256.900538) (xy 383.308928 -256.947604) (xy 383.333501 -256.998886) (xy 383.350191 -257.053247)
			(xy 383.358629 -257.109483) (xy 383.359152 -257.137916) (xy 383.992626 -257.137916) (xy 383.996697 -257.082294)
			(xy 384.008823 -257.027857) (xy 384.028746 -256.975766) (xy 384.056042 -256.927131) (xy 384.090128 -256.882988)
			(xy 384.130277 -256.844279) (xy 384.175635 -256.811828) (xy 384.225235 -256.786327) (xy 384.278019 -256.76832)
			(xy 384.332862 -256.75819) (xy 384.388596 -256.756153) (xy 384.444033 -256.762253) (xy 384.49799 -256.776359)
			(xy 384.549319 -256.798171) (xy 384.596925 -256.827225) (xy 384.639793 -256.8629) (xy 384.67701 -256.904437)
			(xy 384.707783 -256.95095) (xy 384.731455 -257.001447) (xy 384.747523 -257.054854) (xy 384.755643 -257.11003)
			(xy 384.756152 -257.137916) (xy 384.755643 -257.165802) (xy 384.747523 -257.220978) (xy 384.731455 -257.274385)
			(xy 384.707783 -257.324882) (xy 384.67701 -257.371395) (xy 384.639793 -257.412932) (xy 384.596925 -257.448607)
			(xy 384.549319 -257.477661) (xy 384.49799 -257.499473) (xy 384.444033 -257.513579) (xy 384.388596 -257.519679)
			(xy 384.332862 -257.517642) (xy 384.278019 -257.507512) (xy 384.225235 -257.489505) (xy 384.175635 -257.464004)
			(xy 384.130277 -257.431553) (xy 384.090128 -257.392844) (xy 384.056042 -257.348701) (xy 384.028746 -257.300066)
			(xy 384.008823 -257.247975) (xy 383.996697 -257.193538) (xy 383.992626 -257.137916) (xy 383.359152 -257.137916)
			(xy 383.358666 -257.165167) (xy 383.35091 -257.219115) (xy 383.335555 -257.27141) (xy 383.312913 -257.320987)
			(xy 383.283447 -257.366837) (xy 383.247756 -257.408028) (xy 383.206565 -257.443719) (xy 383.160715 -257.473185)
			(xy 383.111138 -257.495827) (xy 383.058843 -257.511182) (xy 383.004895 -257.518938) (xy 382.950393 -257.518938)
			(xy 382.896445 -257.511182) (xy 382.84415 -257.495827) (xy 382.794573 -257.473185) (xy 382.748723 -257.443719)
			(xy 382.707532 -257.408028) (xy 382.671841 -257.366837) (xy 382.642375 -257.320987) (xy 382.619733 -257.27141)
			(xy 382.604378 -257.219115) (xy 382.596622 -257.165167) (xy 382.596136 -257.137916) (xy 370.834144 -257.137916)
			(xy 370.876099 -257.163521) (xy 370.918967 -257.199196) (xy 370.956184 -257.240733) (xy 370.986957 -257.287246)
			(xy 371.010629 -257.337743) (xy 371.026697 -257.39115) (xy 371.034817 -257.446326) (xy 371.035326 -257.474212)
			(xy 371.034817 -257.502098) (xy 371.026697 -257.557274) (xy 371.010629 -257.610681) (xy 370.986957 -257.661178)
			(xy 370.956184 -257.707691) (xy 370.918967 -257.749228) (xy 370.876099 -257.784903) (xy 370.828493 -257.813957)
			(xy 370.777164 -257.835769) (xy 370.723207 -257.849875) (xy 370.66777 -257.855975) (xy 370.612036 -257.853938)
			(xy 370.557193 -257.843808) (xy 370.504409 -257.825801) (xy 370.454809 -257.8003) (xy 370.409451 -257.767849)
			(xy 370.369302 -257.72914) (xy 370.335216 -257.684997) (xy 370.30792 -257.636362) (xy 370.287997 -257.584271)
			(xy 370.275871 -257.529834) (xy 370.2718 -257.474212) (xy 369.3541 -257.474212) (xy 369.3541 -258.649978)
			(xy 371.226332 -258.649978) (xy 371.230403 -258.594356) (xy 371.242529 -258.539919) (xy 371.262452 -258.487828)
			(xy 371.289748 -258.439193) (xy 371.323834 -258.39505) (xy 371.363983 -258.356341) (xy 371.409341 -258.32389)
			(xy 371.458941 -258.298389) (xy 371.511725 -258.280382) (xy 371.566568 -258.270252) (xy 371.622302 -258.268215)
			(xy 371.675403 -258.274058) (xy 377.069602 -258.274058) (xy 377.073673 -258.218436) (xy 377.085799 -258.163999)
			(xy 377.105722 -258.111908) (xy 377.133018 -258.063273) (xy 377.167104 -258.01913) (xy 377.207253 -257.980421)
			(xy 377.252611 -257.94797) (xy 377.302211 -257.922469) (xy 377.354995 -257.904462) (xy 377.409838 -257.894332)
			(xy 377.465572 -257.892295) (xy 377.521009 -257.898395) (xy 377.574966 -257.912501) (xy 377.626295 -257.934313)
			(xy 377.673901 -257.963367) (xy 377.716769 -257.999042) (xy 377.753986 -258.040579) (xy 377.784759 -258.087092)
			(xy 377.808431 -258.137589) (xy 377.824499 -258.190996) (xy 377.832619 -258.246172) (xy 377.833128 -258.274058)
			(xy 378.55474 -258.274058) (xy 378.558811 -258.218436) (xy 378.570937 -258.163999) (xy 378.59086 -258.111908)
			(xy 378.618156 -258.063273) (xy 378.652242 -258.01913) (xy 378.692391 -257.980421) (xy 378.737749 -257.94797)
			(xy 378.787349 -257.922469) (xy 378.840133 -257.904462) (xy 378.894976 -257.894332) (xy 378.95071 -257.892295)
			(xy 379.006147 -257.898395) (xy 379.060104 -257.912501) (xy 379.111433 -257.934313) (xy 379.159039 -257.963367)
			(xy 379.201907 -257.999042) (xy 379.239124 -258.040579) (xy 379.269897 -258.087092) (xy 379.293569 -258.137589)
			(xy 379.309637 -258.190996) (xy 379.317757 -258.246172) (xy 379.318266 -258.274058) (xy 379.317757 -258.301944)
			(xy 379.309637 -258.35712) (xy 379.293569 -258.410527) (xy 379.269897 -258.461024) (xy 379.239124 -258.507537)
			(xy 379.201907 -258.549074) (xy 379.159039 -258.584749) (xy 379.111433 -258.613803) (xy 379.060104 -258.635615)
			(xy 379.006147 -258.649721) (xy 378.95071 -258.655821) (xy 378.894976 -258.653784) (xy 378.840133 -258.643654)
			(xy 378.787349 -258.625647) (xy 378.737749 -258.600146) (xy 378.692391 -258.567695) (xy 378.652242 -258.528986)
			(xy 378.618156 -258.484843) (xy 378.59086 -258.436208) (xy 378.570937 -258.384117) (xy 378.558811 -258.32968)
			(xy 378.55474 -258.274058) (xy 377.833128 -258.274058) (xy 377.832619 -258.301944) (xy 377.824499 -258.35712)
			(xy 377.808431 -258.410527) (xy 377.784759 -258.461024) (xy 377.753986 -258.507537) (xy 377.716769 -258.549074)
			(xy 377.673901 -258.584749) (xy 377.626295 -258.613803) (xy 377.574966 -258.635615) (xy 377.521009 -258.649721)
			(xy 377.465572 -258.655821) (xy 377.409838 -258.653784) (xy 377.354995 -258.643654) (xy 377.302211 -258.625647)
			(xy 377.252611 -258.600146) (xy 377.207253 -258.567695) (xy 377.167104 -258.528986) (xy 377.133018 -258.484843)
			(xy 377.105722 -258.436208) (xy 377.085799 -258.384117) (xy 377.073673 -258.32968) (xy 377.069602 -258.274058)
			(xy 371.675403 -258.274058) (xy 371.677739 -258.274315) (xy 371.731696 -258.288421) (xy 371.783025 -258.310233)
			(xy 371.830631 -258.339287) (xy 371.873499 -258.374962) (xy 371.910716 -258.416499) (xy 371.941489 -258.463012)
			(xy 371.965161 -258.513509) (xy 371.981229 -258.566916) (xy 371.989349 -258.622092) (xy 371.989858 -258.649978)
			(xy 371.989349 -258.677864) (xy 371.987397 -258.691126) (xy 372.710708 -258.691126) (xy 372.714779 -258.635504)
			(xy 372.726905 -258.581067) (xy 372.746828 -258.528976) (xy 372.774124 -258.480341) (xy 372.80821 -258.436198)
			(xy 372.848359 -258.397489) (xy 372.893717 -258.365038) (xy 372.943317 -258.339537) (xy 372.996101 -258.32153)
			(xy 373.050944 -258.3114) (xy 373.106678 -258.309363) (xy 373.162115 -258.315463) (xy 373.216072 -258.329569)
			(xy 373.267401 -258.351381) (xy 373.315007 -258.380435) (xy 373.357875 -258.41611) (xy 373.395092 -258.457647)
			(xy 373.425865 -258.50416) (xy 373.449537 -258.554657) (xy 373.465605 -258.608064) (xy 373.473725 -258.66324)
			(xy 373.474234 -258.691126) (xy 373.473725 -258.719012) (xy 373.465605 -258.774188) (xy 373.449537 -258.827595)
			(xy 373.425865 -258.878092) (xy 373.395092 -258.924605) (xy 373.357875 -258.966142) (xy 373.315007 -259.001817)
			(xy 373.267401 -259.030871) (xy 373.216072 -259.052683) (xy 373.162115 -259.066789) (xy 373.106678 -259.072889)
			(xy 373.050944 -259.070852) (xy 372.996101 -259.060722) (xy 372.943317 -259.042715) (xy 372.893717 -259.017214)
			(xy 372.848359 -258.984763) (xy 372.80821 -258.946054) (xy 372.774124 -258.901911) (xy 372.746828 -258.853276)
			(xy 372.726905 -258.801185) (xy 372.714779 -258.746748) (xy 372.710708 -258.691126) (xy 371.987397 -258.691126)
			(xy 371.981229 -258.73304) (xy 371.965161 -258.786447) (xy 371.941489 -258.836944) (xy 371.910716 -258.883457)
			(xy 371.873499 -258.924994) (xy 371.830631 -258.960669) (xy 371.783025 -258.989723) (xy 371.731696 -259.011535)
			(xy 371.677739 -259.025641) (xy 371.622302 -259.031741) (xy 371.566568 -259.029704) (xy 371.511725 -259.019574)
			(xy 371.458941 -259.001567) (xy 371.409341 -258.976066) (xy 371.363983 -258.943615) (xy 371.323834 -258.904906)
			(xy 371.289748 -258.860763) (xy 371.262452 -258.812128) (xy 371.242529 -258.760037) (xy 371.230403 -258.7056)
			(xy 371.226332 -258.649978) (xy 369.3541 -258.649978) (xy 369.3541 -259.94487) (xy 369.513102 -259.94487)
			(xy 369.517173 -259.889248) (xy 369.529299 -259.834811) (xy 369.549222 -259.78272) (xy 369.576518 -259.734085)
			(xy 369.610604 -259.689942) (xy 369.650753 -259.651233) (xy 369.696111 -259.618782) (xy 369.745711 -259.593281)
			(xy 369.798495 -259.575274) (xy 369.853338 -259.565144) (xy 369.909072 -259.563107) (xy 369.964509 -259.569207)
			(xy 370.018466 -259.583313) (xy 370.069795 -259.605125) (xy 370.117401 -259.634179) (xy 370.160269 -259.669854)
			(xy 370.197486 -259.711391) (xy 370.228259 -259.757904) (xy 370.251931 -259.808401) (xy 370.267999 -259.861808)
			(xy 370.276119 -259.916984) (xy 370.276628 -259.94487) (xy 370.276119 -259.972756) (xy 370.267999 -260.027932)
			(xy 370.255162 -260.0706) (xy 371.942866 -260.0706) (xy 371.946937 -260.014978) (xy 371.959063 -259.960541)
			(xy 371.978986 -259.90845) (xy 372.006282 -259.859815) (xy 372.040368 -259.815672) (xy 372.080517 -259.776963)
			(xy 372.125875 -259.744512) (xy 372.175475 -259.719011) (xy 372.228259 -259.701004) (xy 372.283102 -259.690874)
			(xy 372.338836 -259.688837) (xy 372.394273 -259.694937) (xy 372.44823 -259.709043) (xy 372.499559 -259.730855)
			(xy 372.547165 -259.759909) (xy 372.590033 -259.795584) (xy 372.62725 -259.837121) (xy 372.658023 -259.883634)
			(xy 372.681695 -259.934131) (xy 372.697763 -259.987538) (xy 372.705883 -260.042714) (xy 372.706392 -260.0706)
			(xy 372.705883 -260.098486) (xy 372.697763 -260.153662) (xy 372.695701 -260.160516) (xy 376.181872 -260.160516)
			(xy 376.185943 -260.104894) (xy 376.198069 -260.050457) (xy 376.217992 -259.998366) (xy 376.245288 -259.949731)
			(xy 376.279374 -259.905588) (xy 376.319523 -259.866879) (xy 376.364881 -259.834428) (xy 376.414481 -259.808927)
			(xy 376.467265 -259.79092) (xy 376.522108 -259.78079) (xy 376.577842 -259.778753) (xy 376.633279 -259.784853)
			(xy 376.687236 -259.798959) (xy 376.738565 -259.820771) (xy 376.786171 -259.849825) (xy 376.829039 -259.8855)
			(xy 376.866256 -259.927037) (xy 376.897029 -259.97355) (xy 376.920701 -260.024047) (xy 376.936769 -260.077454)
			(xy 376.944889 -260.13263) (xy 376.945398 -260.160516) (xy 376.944889 -260.188402) (xy 376.936769 -260.243578)
			(xy 376.920701 -260.296985) (xy 376.901326 -260.338316) (xy 382.596136 -260.338316) (xy 382.596671 -260.308933)
			(xy 382.605701 -260.250865) (xy 382.623533 -260.194871) (xy 382.649745 -260.142275) (xy 382.683717 -260.094324)
			(xy 382.724644 -260.052153) (xy 382.747774 -260.034024) (xy 382.757172 -260.026658) (xy 382.767586 -260.006084)
			(xy 382.76911 -259.902198) (xy 382.759204 -259.881116) (xy 382.75006 -259.87375) (xy 382.728198 -259.855561)
			(xy 382.68966 -259.813737) (xy 382.657756 -259.766658) (xy 382.633192 -259.715365) (xy 382.616511 -259.660995)
			(xy 382.608084 -259.604752) (xy 382.607566 -259.576316) (xy 382.608052 -259.549065) (xy 382.615808 -259.495117)
			(xy 382.631163 -259.442822) (xy 382.653805 -259.393245) (xy 382.683271 -259.347395) (xy 382.718962 -259.306204)
			(xy 382.760153 -259.270513) (xy 382.806003 -259.241047) (xy 382.85558 -259.218405) (xy 382.907875 -259.20305)
			(xy 382.961823 -259.195294) (xy 383.016325 -259.195294) (xy 383.070273 -259.20305) (xy 383.122568 -259.218405)
			(xy 383.172145 -259.241047) (xy 383.217995 -259.270513) (xy 383.259186 -259.306204) (xy 383.294877 -259.347395)
			(xy 383.324343 -259.393245) (xy 383.326982 -259.399024) (xy 386.435598 -259.399024) (xy 386.439669 -259.343402)
			(xy 386.451795 -259.288965) (xy 386.471718 -259.236874) (xy 386.499014 -259.188239) (xy 386.5331 -259.144096)
			(xy 386.573249 -259.105387) (xy 386.618607 -259.072936) (xy 386.668207 -259.047435) (xy 386.720991 -259.029428)
			(xy 386.775834 -259.019298) (xy 386.831568 -259.017261) (xy 386.887005 -259.023361) (xy 386.940962 -259.037467)
			(xy 386.992291 -259.059279) (xy 387.039897 -259.088333) (xy 387.082765 -259.124008) (xy 387.119982 -259.165545)
			(xy 387.150755 -259.212058) (xy 387.174427 -259.262555) (xy 387.190495 -259.315962) (xy 387.198615 -259.371138)
			(xy 387.199124 -259.399024) (xy 387.198615 -259.42691) (xy 387.190495 -259.482086) (xy 387.174427 -259.535493)
			(xy 387.150755 -259.58599) (xy 387.119982 -259.632503) (xy 387.082765 -259.67404) (xy 387.039897 -259.709715)
			(xy 386.992291 -259.738769) (xy 386.940962 -259.760581) (xy 386.887005 -259.774687) (xy 386.831568 -259.780787)
			(xy 386.775834 -259.77875) (xy 386.720991 -259.76862) (xy 386.668207 -259.750613) (xy 386.618607 -259.725112)
			(xy 386.573249 -259.692661) (xy 386.5331 -259.653952) (xy 386.499014 -259.609809) (xy 386.471718 -259.561174)
			(xy 386.451795 -259.509083) (xy 386.439669 -259.454646) (xy 386.435598 -259.399024) (xy 383.326982 -259.399024)
			(xy 383.346985 -259.442822) (xy 383.36234 -259.495117) (xy 383.370096 -259.549065) (xy 383.370582 -259.576316)
			(xy 383.370063 -259.605699) (xy 383.361029 -259.663767) (xy 383.343193 -259.719762) (xy 383.316978 -259.772358)
			(xy 383.283003 -259.820308) (xy 383.242074 -259.862479) (xy 383.218944 -259.880608) (xy 383.209546 -259.887974)
			(xy 383.199132 -259.908548) (xy 383.197608 -260.012434) (xy 383.207514 -260.033516) (xy 383.216658 -260.040882)
			(xy 383.238471 -260.059128) (xy 383.277015 -260.100938) (xy 383.308928 -260.148004) (xy 383.333501 -260.199286)
			(xy 383.350191 -260.253647) (xy 383.358629 -260.309883) (xy 383.359152 -260.338316) (xy 383.992626 -260.338316)
			(xy 383.996697 -260.282694) (xy 384.008823 -260.228257) (xy 384.028746 -260.176166) (xy 384.056042 -260.127531)
			(xy 384.090128 -260.083388) (xy 384.130277 -260.044679) (xy 384.175635 -260.012228) (xy 384.225235 -259.986727)
			(xy 384.278019 -259.96872) (xy 384.332862 -259.95859) (xy 384.388596 -259.956553) (xy 384.444033 -259.962653)
			(xy 384.49799 -259.976759) (xy 384.549319 -259.998571) (xy 384.596925 -260.027625) (xy 384.639793 -260.0633)
			(xy 384.67701 -260.104837) (xy 384.707783 -260.15135) (xy 384.731455 -260.201847) (xy 384.747523 -260.255254)
			(xy 384.755643 -260.31043) (xy 384.756152 -260.338316) (xy 384.755643 -260.366202) (xy 384.754663 -260.37286)
			(xy 387.427722 -260.37286) (xy 387.431793 -260.317238) (xy 387.443919 -260.262801) (xy 387.463842 -260.21071)
			(xy 387.491138 -260.162075) (xy 387.525224 -260.117932) (xy 387.565373 -260.079223) (xy 387.610731 -260.046772)
			(xy 387.660331 -260.021271) (xy 387.713115 -260.003264) (xy 387.767958 -259.993134) (xy 387.823692 -259.991097)
			(xy 387.879129 -259.997197) (xy 387.933086 -260.011303) (xy 387.984415 -260.033115) (xy 388.032021 -260.062169)
			(xy 388.074889 -260.097844) (xy 388.112106 -260.139381) (xy 388.142879 -260.185894) (xy 388.166551 -260.236391)
			(xy 388.182619 -260.289798) (xy 388.190739 -260.344974) (xy 388.191248 -260.37286) (xy 388.190739 -260.400746)
			(xy 388.182619 -260.455922) (xy 388.166551 -260.509329) (xy 388.142879 -260.559826) (xy 388.112106 -260.606339)
			(xy 388.074889 -260.647876) (xy 388.032021 -260.683551) (xy 387.984415 -260.712605) (xy 387.933086 -260.734417)
			(xy 387.879129 -260.748523) (xy 387.823692 -260.754623) (xy 387.767958 -260.752586) (xy 387.713115 -260.742456)
			(xy 387.660331 -260.724449) (xy 387.610731 -260.698948) (xy 387.565373 -260.666497) (xy 387.525224 -260.627788)
			(xy 387.491138 -260.583645) (xy 387.463842 -260.53501) (xy 387.443919 -260.482919) (xy 387.431793 -260.428482)
			(xy 387.427722 -260.37286) (xy 384.754663 -260.37286) (xy 384.747523 -260.421378) (xy 384.731455 -260.474785)
			(xy 384.707783 -260.525282) (xy 384.67701 -260.571795) (xy 384.639793 -260.613332) (xy 384.596925 -260.649007)
			(xy 384.549319 -260.678061) (xy 384.49799 -260.699873) (xy 384.444033 -260.713979) (xy 384.388596 -260.720079)
			(xy 384.332862 -260.718042) (xy 384.278019 -260.707912) (xy 384.225235 -260.689905) (xy 384.175635 -260.664404)
			(xy 384.130277 -260.631953) (xy 384.090128 -260.593244) (xy 384.056042 -260.549101) (xy 384.028746 -260.500466)
			(xy 384.008823 -260.448375) (xy 383.996697 -260.393938) (xy 383.992626 -260.338316) (xy 383.359152 -260.338316)
			(xy 383.358666 -260.365567) (xy 383.35091 -260.419515) (xy 383.335555 -260.47181) (xy 383.312913 -260.521387)
			(xy 383.283447 -260.567237) (xy 383.247756 -260.608428) (xy 383.206565 -260.644119) (xy 383.160715 -260.673585)
			(xy 383.111138 -260.696227) (xy 383.058843 -260.711582) (xy 383.004895 -260.719338) (xy 382.950393 -260.719338)
			(xy 382.896445 -260.711582) (xy 382.84415 -260.696227) (xy 382.794573 -260.673585) (xy 382.748723 -260.644119)
			(xy 382.707532 -260.608428) (xy 382.671841 -260.567237) (xy 382.642375 -260.521387) (xy 382.619733 -260.47181)
			(xy 382.604378 -260.419515) (xy 382.596622 -260.365567) (xy 382.596136 -260.338316) (xy 376.901326 -260.338316)
			(xy 376.897029 -260.347482) (xy 376.866256 -260.393995) (xy 376.829039 -260.435532) (xy 376.786171 -260.471207)
			(xy 376.738565 -260.500261) (xy 376.687236 -260.522073) (xy 376.633279 -260.536179) (xy 376.577842 -260.542279)
			(xy 376.522108 -260.540242) (xy 376.467265 -260.530112) (xy 376.414481 -260.512105) (xy 376.364881 -260.486604)
			(xy 376.319523 -260.454153) (xy 376.279374 -260.415444) (xy 376.245288 -260.371301) (xy 376.217992 -260.322666)
			(xy 376.198069 -260.270575) (xy 376.185943 -260.216138) (xy 376.181872 -260.160516) (xy 372.695701 -260.160516)
			(xy 372.681695 -260.207069) (xy 372.658023 -260.257566) (xy 372.62725 -260.304079) (xy 372.590033 -260.345616)
			(xy 372.547165 -260.381291) (xy 372.499559 -260.410345) (xy 372.44823 -260.432157) (xy 372.394273 -260.446263)
			(xy 372.338836 -260.452363) (xy 372.283102 -260.450326) (xy 372.228259 -260.440196) (xy 372.175475 -260.422189)
			(xy 372.125875 -260.396688) (xy 372.080517 -260.364237) (xy 372.040368 -260.325528) (xy 372.006282 -260.281385)
			(xy 371.978986 -260.23275) (xy 371.959063 -260.180659) (xy 371.946937 -260.126222) (xy 371.942866 -260.0706)
			(xy 370.255162 -260.0706) (xy 370.251931 -260.081339) (xy 370.228259 -260.131836) (xy 370.197486 -260.178349)
			(xy 370.160269 -260.219886) (xy 370.117401 -260.255561) (xy 370.069795 -260.284615) (xy 370.018466 -260.306427)
			(xy 369.964509 -260.320533) (xy 369.909072 -260.326633) (xy 369.853338 -260.324596) (xy 369.798495 -260.314466)
			(xy 369.745711 -260.296459) (xy 369.696111 -260.270958) (xy 369.650753 -260.238507) (xy 369.610604 -260.199798)
			(xy 369.576518 -260.155655) (xy 369.549222 -260.10702) (xy 369.529299 -260.054929) (xy 369.517173 -260.000492)
			(xy 369.513102 -259.94487) (xy 369.3541 -259.94487) (xy 369.3541 -261.207758) (xy 370.377464 -261.207758)
			(xy 370.381535 -261.152136) (xy 370.393661 -261.097699) (xy 370.413584 -261.045608) (xy 370.44088 -260.996973)
			(xy 370.474966 -260.95283) (xy 370.515115 -260.914121) (xy 370.560473 -260.88167) (xy 370.610073 -260.856169)
			(xy 370.662857 -260.838162) (xy 370.7177 -260.828032) (xy 370.773434 -260.825995) (xy 370.828871 -260.832095)
			(xy 370.882828 -260.846201) (xy 370.934157 -260.868013) (xy 370.981763 -260.897067) (xy 371.024631 -260.932742)
			(xy 371.061848 -260.974279) (xy 371.092621 -261.020792) (xy 371.116293 -261.071289) (xy 371.132361 -261.124696)
			(xy 371.140481 -261.179872) (xy 371.14099 -261.207758) (xy 371.140481 -261.235644) (xy 371.132361 -261.29082)
			(xy 371.116293 -261.344227) (xy 371.092621 -261.394724) (xy 371.061848 -261.441237) (xy 371.024631 -261.482774)
			(xy 370.981763 -261.518449) (xy 370.934157 -261.547503) (xy 370.882828 -261.569315) (xy 370.828871 -261.583421)
			(xy 370.773434 -261.589521) (xy 370.7177 -261.587484) (xy 370.662857 -261.577354) (xy 370.610073 -261.559347)
			(xy 370.560473 -261.533846) (xy 370.515115 -261.501395) (xy 370.474966 -261.462686) (xy 370.44088 -261.418543)
			(xy 370.413584 -261.369908) (xy 370.393661 -261.317817) (xy 370.381535 -261.26338) (xy 370.377464 -261.207758)
			(xy 369.3541 -261.207758) (xy 369.3541 -261.559802) (xy 369.354575 -261.569769) (xy 369.362146 -261.58821)
			(xy 369.368832 -261.595616) (xy 369.591171 -261.817955) (xy 373.819343 -261.817955) (xy 373.819343 -261.763445)
			(xy 373.827101 -261.709491) (xy 373.842458 -261.65719) (xy 373.865103 -261.607607) (xy 373.894574 -261.561751)
			(xy 373.930271 -261.520557) (xy 373.971467 -261.484862) (xy 374.017324 -261.455393) (xy 374.066909 -261.432751)
			(xy 374.11921 -261.417396) (xy 374.173165 -261.409642) (xy 374.20042 -261.40918) (xy 374.229336 -261.409726)
			(xy 374.286508 -261.418445) (xy 374.341707 -261.435695) (xy 374.39367 -261.461082) (xy 374.441204 -261.494022)
			(xy 374.48322 -261.533761) (xy 374.50141 -261.556246) (xy 374.508964 -261.565015) (xy 374.529729 -261.575193)
			(xy 374.541288 -261.575804) (xy 374.621552 -261.575804) (xy 374.633116 -261.575205) (xy 374.653887 -261.56503)
			(xy 374.66143 -261.556246) (xy 374.67959 -261.533737) (xy 374.721618 -261.494006) (xy 374.76916 -261.461071)
			(xy 374.821127 -261.435688) (xy 374.876329 -261.418437) (xy 374.933502 -261.409713) (xy 374.96242 -261.40918)
			(xy 374.989669 -261.409692) (xy 375.043613 -261.41745) (xy 375.095904 -261.432807) (xy 375.145477 -261.455448)
			(xy 375.175055 -261.474458) (xy 377.069602 -261.474458) (xy 377.073673 -261.418836) (xy 377.085799 -261.364399)
			(xy 377.105722 -261.312308) (xy 377.133018 -261.263673) (xy 377.167104 -261.21953) (xy 377.207253 -261.180821)
			(xy 377.252611 -261.14837) (xy 377.302211 -261.122869) (xy 377.354995 -261.104862) (xy 377.409838 -261.094732)
			(xy 377.465572 -261.092695) (xy 377.521009 -261.098795) (xy 377.574966 -261.112901) (xy 377.626295 -261.134713)
			(xy 377.673901 -261.163767) (xy 377.716769 -261.199442) (xy 377.753986 -261.240979) (xy 377.784759 -261.287492)
			(xy 377.808431 -261.337989) (xy 377.824499 -261.391396) (xy 377.832619 -261.446572) (xy 377.833128 -261.474458)
			(xy 378.55474 -261.474458) (xy 378.558811 -261.418836) (xy 378.570937 -261.364399) (xy 378.59086 -261.312308)
			(xy 378.618156 -261.263673) (xy 378.652242 -261.21953) (xy 378.692391 -261.180821) (xy 378.737749 -261.14837)
			(xy 378.787349 -261.122869) (xy 378.840133 -261.104862) (xy 378.894976 -261.094732) (xy 378.95071 -261.092695)
			(xy 379.006147 -261.098795) (xy 379.060104 -261.112901) (xy 379.111433 -261.134713) (xy 379.159039 -261.163767)
			(xy 379.201907 -261.199442) (xy 379.239124 -261.240979) (xy 379.269897 -261.287492) (xy 379.293569 -261.337989)
			(xy 379.309637 -261.391396) (xy 379.317757 -261.446572) (xy 379.318266 -261.474458) (xy 379.317757 -261.502344)
			(xy 379.309637 -261.55752) (xy 379.293569 -261.610927) (xy 379.269897 -261.661424) (xy 379.239124 -261.707937)
			(xy 379.201907 -261.749474) (xy 379.159039 -261.785149) (xy 379.111433 -261.814203) (xy 379.060104 -261.836015)
			(xy 379.006147 -261.850121) (xy 378.95071 -261.856221) (xy 378.894976 -261.854184) (xy 378.840133 -261.844054)
			(xy 378.787349 -261.826047) (xy 378.737749 -261.800546) (xy 378.692391 -261.768095) (xy 378.652242 -261.729386)
			(xy 378.618156 -261.685243) (xy 378.59086 -261.636608) (xy 378.570937 -261.584517) (xy 378.558811 -261.53008)
			(xy 378.55474 -261.474458) (xy 377.833128 -261.474458) (xy 377.832619 -261.502344) (xy 377.824499 -261.55752)
			(xy 377.808431 -261.610927) (xy 377.784759 -261.661424) (xy 377.753986 -261.707937) (xy 377.716769 -261.749474)
			(xy 377.673901 -261.785149) (xy 377.626295 -261.814203) (xy 377.574966 -261.836015) (xy 377.521009 -261.850121)
			(xy 377.465572 -261.856221) (xy 377.409838 -261.854184) (xy 377.354995 -261.844054) (xy 377.302211 -261.826047)
			(xy 377.252611 -261.800546) (xy 377.207253 -261.768095) (xy 377.167104 -261.729386) (xy 377.133018 -261.685243)
			(xy 377.105722 -261.636608) (xy 377.085799 -261.584517) (xy 377.073673 -261.53008) (xy 377.069602 -261.474458)
			(xy 375.175055 -261.474458) (xy 375.191323 -261.484914) (xy 375.23251 -261.520604) (xy 375.268198 -261.561793)
			(xy 375.297662 -261.607641) (xy 375.3203 -261.657215) (xy 375.335654 -261.709506) (xy 375.34341 -261.763451)
			(xy 375.34341 -261.817949) (xy 375.335654 -261.871894) (xy 375.3203 -261.924185) (xy 375.297662 -261.973759)
			(xy 375.268198 -262.019607) (xy 375.23251 -262.060796) (xy 375.191323 -262.096486) (xy 375.145477 -262.125952)
			(xy 375.095904 -262.148593) (xy 375.043613 -262.16395) (xy 374.989669 -262.171708) (xy 374.96242 -262.172196)
			(xy 374.933504 -262.171665) (xy 374.876333 -262.162939) (xy 374.821134 -262.145683) (xy 374.769173 -262.120294)
			(xy 374.721638 -262.087353) (xy 374.679621 -262.047614) (xy 374.66143 -262.02513) (xy 374.653863 -262.016374)
			(xy 374.633108 -262.00619) (xy 374.621552 -262.005572) (xy 374.541288 -262.005572) (xy 374.529715 -262.00611)
			(xy 374.508943 -262.016325) (xy 374.50141 -262.02513) (xy 374.483221 -262.047615) (xy 374.4412 -262.087349)
			(xy 374.393664 -262.120287) (xy 374.341703 -262.145674) (xy 374.286505 -262.162931) (xy 374.229336 -262.17166)
			(xy 374.20042 -262.172196) (xy 374.173165 -262.171758) (xy 374.11921 -262.164004) (xy 374.066909 -262.148649)
			(xy 374.017324 -262.126007) (xy 373.971467 -262.096538) (xy 373.930271 -262.060843) (xy 373.894574 -262.019649)
			(xy 373.865103 -261.973793) (xy 373.842458 -261.92421) (xy 373.827101 -261.871909) (xy 373.819343 -261.817955)
			(xy 369.591171 -261.817955) (xy 370.888768 -263.115552) (xy 370.896178 -263.122236) (xy 370.914614 -263.129821)
			(xy 370.924582 -263.130284) (xy 381.509524 -263.130284) (xy 381.51866 -263.129898) (xy 381.535766 -263.123477)
			(xy 381.54953 -263.11146) (xy 381.554228 -263.103614) (xy 381.589788 -263.03732) (xy 381.594188 -263.02825)
			(xy 381.596168 -263.008204) (xy 381.593598 -262.998458) (xy 381.588772 -262.982964) (xy 381.584708 -262.976868)
			(xy 381.570696 -262.953849) (xy 381.548577 -262.904709) (xy 381.533579 -262.852949) (xy 381.526002 -262.799596)
			(xy 381.525526 -262.772652) (xy 381.525526 -262.764524) (xy 381.526542 -262.74903) (xy 381.528852 -262.720325)
			(xy 381.541023 -262.664041) (xy 381.561514 -262.610225) (xy 381.589862 -262.560101) (xy 381.62542 -262.514806)
			(xy 381.667383 -262.47537) (xy 381.714796 -262.442688) (xy 381.766582 -262.417504) (xy 381.821565 -262.400389)
			(xy 381.878495 -262.391733) (xy 381.907288 -262.391144) (xy 381.934541 -262.391629) (xy 381.988493 -262.399384)
			(xy 382.040792 -262.414737) (xy 382.090373 -262.437377) (xy 382.136229 -262.466842) (xy 382.177424 -262.502533)
			(xy 382.213122 -262.543723) (xy 382.242594 -262.589574) (xy 382.265242 -262.639152) (xy 382.280603 -262.691449)
			(xy 382.288367 -262.745399) (xy 382.288796 -262.772652) (xy 382.288796 -262.787892) (xy 382.287404 -262.812897)
			(xy 382.27888 -262.862246) (xy 382.263971 -262.910056) (xy 382.242935 -262.955504) (xy 382.229868 -262.976868)
			(xy 382.225804 -262.982964) (xy 382.220978 -262.998458) (xy 382.218557 -263.008218) (xy 382.219951 -263.022334)
			(xy 386.231128 -263.022334) (xy 386.235199 -262.966712) (xy 386.247325 -262.912275) (xy 386.267248 -262.860184)
			(xy 386.294544 -262.811549) (xy 386.32863 -262.767406) (xy 386.368779 -262.728697) (xy 386.414137 -262.696246)
			(xy 386.463737 -262.670745) (xy 386.516521 -262.652738) (xy 386.571364 -262.642608) (xy 386.627098 -262.640571)
			(xy 386.682535 -262.646671) (xy 386.736492 -262.660777) (xy 386.787821 -262.682589) (xy 386.835427 -262.711643)
			(xy 386.878295 -262.747318) (xy 386.915512 -262.788855) (xy 386.946285 -262.835368) (xy 386.969957 -262.885865)
			(xy 386.986025 -262.939272) (xy 386.994145 -262.994448) (xy 386.994654 -263.022334) (xy 386.994145 -263.05022)
			(xy 386.986025 -263.105396) (xy 386.969957 -263.158803) (xy 386.946285 -263.2093) (xy 386.915512 -263.255813)
			(xy 386.878295 -263.29735) (xy 386.835427 -263.333025) (xy 386.787821 -263.362079) (xy 386.736492 -263.383891)
			(xy 386.682535 -263.397997) (xy 386.627098 -263.404097) (xy 386.571364 -263.40206) (xy 386.516521 -263.39193)
			(xy 386.463737 -263.373923) (xy 386.414137 -263.348422) (xy 386.368779 -263.315971) (xy 386.32863 -263.277262)
			(xy 386.294544 -263.233119) (xy 386.267248 -263.184484) (xy 386.247325 -263.132393) (xy 386.235199 -263.077956)
			(xy 386.231128 -263.022334) (xy 382.219951 -263.022334) (xy 382.220531 -263.028208) (xy 382.224788 -263.03732)
			(xy 382.260348 -263.103614) (xy 382.265021 -263.111482) (xy 382.278792 -263.123512) (xy 382.295909 -263.129945)
			(xy 382.305052 -263.130284) (xy 384.029458 -263.130284) (xy 384.048755 -263.130627) (xy 384.087077 -263.135215)
			(xy 384.105912 -263.139428) (xy 384.111754 -263.140698) (xy 384.141726 -263.140698) (xy 384.151711 -263.14124)
			(xy 384.170137 -263.14896) (xy 384.17754 -263.155684) (xy 384.198622 -263.176766) (xy 384.203702 -263.179814)
			(xy 384.220002 -263.19017) (xy 384.250308 -263.214105) (xy 384.264154 -263.227566) (xy 385.40436 -264.367772)
			(xy 386.190488 -264.367772) (xy 386.194559 -264.31215) (xy 386.206685 -264.257713) (xy 386.226608 -264.205622)
			(xy 386.253904 -264.156987) (xy 386.28799 -264.112844) (xy 386.328139 -264.074135) (xy 386.373497 -264.041684)
			(xy 386.423097 -264.016183) (xy 386.475881 -263.998176) (xy 386.530724 -263.988046) (xy 386.586458 -263.986009)
			(xy 386.641895 -263.992109) (xy 386.695852 -264.006215) (xy 386.747181 -264.028027) (xy 386.794787 -264.057081)
			(xy 386.837655 -264.092756) (xy 386.874872 -264.134293) (xy 386.905645 -264.180806) (xy 386.929317 -264.231303)
			(xy 386.945385 -264.28471) (xy 386.953505 -264.339886) (xy 386.954014 -264.367772) (xy 386.953505 -264.395658)
			(xy 386.945385 -264.450834) (xy 386.929317 -264.504241) (xy 386.905645 -264.554738) (xy 386.874872 -264.601251)
			(xy 386.853299 -264.625328) (xy 388.763 -264.625328) (xy 388.767071 -264.569706) (xy 388.779197 -264.515269)
			(xy 388.79912 -264.463178) (xy 388.826416 -264.414543) (xy 388.860502 -264.3704) (xy 388.900651 -264.331691)
			(xy 388.946009 -264.29924) (xy 388.995609 -264.273739) (xy 389.048393 -264.255732) (xy 389.103236 -264.245602)
			(xy 389.15897 -264.243565) (xy 389.214407 -264.249665) (xy 389.268364 -264.263771) (xy 389.319693 -264.285583)
			(xy 389.367299 -264.314637) (xy 389.410167 -264.350312) (xy 389.447384 -264.391849) (xy 389.478157 -264.438362)
			(xy 389.501829 -264.488859) (xy 389.517897 -264.542266) (xy 389.526017 -264.597442) (xy 389.526526 -264.625328)
			(xy 389.526017 -264.653214) (xy 389.517897 -264.70839) (xy 389.501829 -264.761797) (xy 389.478157 -264.812294)
			(xy 389.447384 -264.858807) (xy 389.410167 -264.900344) (xy 389.367299 -264.936019) (xy 389.319693 -264.965073)
			(xy 389.268364 -264.986885) (xy 389.214407 -265.000991) (xy 389.15897 -265.007091) (xy 389.103236 -265.005054)
			(xy 389.048393 -264.994924) (xy 388.995609 -264.976917) (xy 388.946009 -264.951416) (xy 388.900651 -264.918965)
			(xy 388.860502 -264.880256) (xy 388.826416 -264.836113) (xy 388.79912 -264.787478) (xy 388.779197 -264.735387)
			(xy 388.767071 -264.68095) (xy 388.763 -264.625328) (xy 386.853299 -264.625328) (xy 386.837655 -264.642788)
			(xy 386.794787 -264.678463) (xy 386.747181 -264.707517) (xy 386.695852 -264.729329) (xy 386.641895 -264.743435)
			(xy 386.586458 -264.749535) (xy 386.530724 -264.747498) (xy 386.475881 -264.737368) (xy 386.423097 -264.719361)
			(xy 386.373497 -264.69386) (xy 386.328139 -264.661409) (xy 386.28799 -264.6227) (xy 386.253904 -264.578557)
			(xy 386.226608 -264.529922) (xy 386.206685 -264.477831) (xy 386.194559 -264.423394) (xy 386.190488 -264.367772)
			(xy 385.40436 -264.367772) (xy 386.774436 -265.737848) (xy 388.73252 -265.737848) (xy 388.736591 -265.682226)
			(xy 388.748717 -265.627789) (xy 388.76864 -265.575698) (xy 388.795936 -265.527063) (xy 388.830022 -265.48292)
			(xy 388.870171 -265.444211) (xy 388.915529 -265.41176) (xy 388.965129 -265.386259) (xy 389.017913 -265.368252)
			(xy 389.072756 -265.358122) (xy 389.12849 -265.356085) (xy 389.183927 -265.362185) (xy 389.237884 -265.376291)
			(xy 389.289213 -265.398103) (xy 389.336819 -265.427157) (xy 389.379687 -265.462832) (xy 389.416904 -265.504369)
			(xy 389.447677 -265.550882) (xy 389.471349 -265.601379) (xy 389.487417 -265.654786) (xy 389.495537 -265.709962)
			(xy 389.496046 -265.737848) (xy 389.495537 -265.765734) (xy 389.487417 -265.82091) (xy 389.471349 -265.874317)
			(xy 389.447677 -265.924814) (xy 389.416904 -265.971327) (xy 389.379687 -266.012864) (xy 389.336819 -266.048539)
			(xy 389.289213 -266.077593) (xy 389.237884 -266.099405) (xy 389.183927 -266.113511) (xy 389.12849 -266.119611)
			(xy 389.072756 -266.117574) (xy 389.017913 -266.107444) (xy 388.965129 -266.089437) (xy 388.915529 -266.063936)
			(xy 388.870171 -266.031485) (xy 388.830022 -265.992776) (xy 388.795936 -265.948633) (xy 388.76864 -265.899998)
			(xy 388.748717 -265.847907) (xy 388.736591 -265.79347) (xy 388.73252 -265.737848) (xy 386.774436 -265.737848)
			(xy 386.805678 -265.76909) (xy 386.813027 -265.775889) (xy 386.83149 -265.783595) (xy 386.841492 -265.784076)
			(xy 387.7056 -265.784076) (xy 387.731675 -265.784545) (xy 387.783188 -265.792674) (xy 387.832794 -265.808763)
			(xy 387.879271 -265.832416) (xy 387.921476 -265.863049) (xy 387.940296 -265.881104) (xy 388.628128 -266.568936)
			(xy 388.635541 -266.575612) (xy 388.653977 -266.583178) (xy 388.663942 -266.583668) (xy 388.923022 -266.583668)
			(xy 388.93496 -266.580874) (xy 388.940548 -266.57808) (xy 388.968076 -266.564246) (xy 389.02649 -266.544672)
			(xy 389.087291 -266.534747) (xy 389.118094 -266.534138) (xy 389.145344 -266.534601) (xy 389.199289 -266.542356)
			(xy 389.251581 -266.55771) (xy 389.301156 -266.580349) (xy 389.347004 -266.609814) (xy 389.388193 -266.645503)
			(xy 389.423883 -266.686691) (xy 389.453348 -266.732539) (xy 389.475988 -266.782113) (xy 389.491343 -266.834405)
			(xy 389.499099 -266.88835) (xy 389.499099 -266.94285) (xy 389.491343 -266.996795) (xy 389.475988 -267.049087)
			(xy 389.453348 -267.098661) (xy 389.423883 -267.144509) (xy 389.388193 -267.185697) (xy 389.347004 -267.221386)
			(xy 389.301156 -267.250851) (xy 389.251581 -267.27349) (xy 389.199289 -267.288844) (xy 389.145344 -267.296599)
			(xy 389.118094 -267.297154) (xy 389.087292 -267.296542) (xy 389.026495 -267.286603) (xy 388.968081 -267.267034)
			(xy 388.940548 -267.253212) (xy 388.93496 -267.250418) (xy 388.923022 -267.247624) (xy 388.505446 -267.247624)
			(xy 388.486409 -267.247317) (xy 388.448596 -267.242858) (xy 388.430008 -267.238734) (xy 388.424166 -267.237464)
			(xy 388.41045 -267.237464) (xy 388.403592 -267.23721) (xy 388.298182 -267.23721) (xy 388.288196 -267.236669)
			(xy 388.269768 -267.228953) (xy 388.262368 -267.222224) (xy 388.192264 -267.15212) (xy 388.191248 -267.151358)
			(xy 388.182866 -267.14323) (xy 387.93928 -266.899644) (xy 387.935724 -266.896088) (xy 387.93547 -266.895834)
			(xy 387.9342 -266.894564) (xy 387.860794 -266.82065) (xy 387.853992 -266.813302) (xy 387.846279 -266.794839)
			(xy 387.845808 -266.784836) (xy 387.845808 -266.774422) (xy 387.845371 -266.764358) (xy 387.837638 -266.745773)
			(xy 387.830822 -266.738354) (xy 387.56336 -266.470638) (xy 387.555961 -266.463794) (xy 387.537363 -266.456068)
			(xy 387.527292 -266.455652) (xy 386.589016 -266.455652) (xy 386.579028 -266.455116) (xy 386.560597 -266.447401)
			(xy 386.553202 -266.440666) (xy 386.51815 -266.405614) (xy 386.509006 -266.398248) (xy 386.492644 -266.387898)
			(xy 386.46221 -266.363962) (xy 386.4483 -266.350496) (xy 383.906776 -263.808972) (xy 383.899364 -263.802295)
			(xy 383.880928 -263.794725) (xy 383.870962 -263.79424) (xy 383.410714 -263.79424) (xy 383.400681 -263.794593)
			(xy 383.382114 -263.802187) (xy 383.367921 -263.816363) (xy 383.363724 -263.825482) (xy 383.357882 -263.83996)
			(xy 383.363724 -263.869678) (xy 386.457444 -266.963398) (xy 386.956044 -266.963398) (xy 386.960115 -266.907776)
			(xy 386.972241 -266.853339) (xy 386.992164 -266.801248) (xy 387.01946 -266.752613) (xy 387.053546 -266.70847)
			(xy 387.093695 -266.669761) (xy 387.139053 -266.63731) (xy 387.188653 -266.611809) (xy 387.241437 -266.593802)
			(xy 387.29628 -266.583672) (xy 387.352014 -266.581635) (xy 387.407451 -266.587735) (xy 387.461408 -266.601841)
			(xy 387.512737 -266.623653) (xy 387.560343 -266.652707) (xy 387.603211 -266.688382) (xy 387.640428 -266.729919)
			(xy 387.671201 -266.776432) (xy 387.694873 -266.826929) (xy 387.710941 -266.880336) (xy 387.719061 -266.935512)
			(xy 387.71957 -266.963398) (xy 387.719061 -266.991284) (xy 387.710941 -267.04646) (xy 387.694873 -267.099867)
			(xy 387.671201 -267.150364) (xy 387.640428 -267.196877) (xy 387.603211 -267.238414) (xy 387.560343 -267.274089)
			(xy 387.512737 -267.303143) (xy 387.461408 -267.324955) (xy 387.407451 -267.339061) (xy 387.352014 -267.345161)
			(xy 387.29628 -267.343124) (xy 387.241437 -267.332994) (xy 387.188653 -267.314987) (xy 387.139053 -267.289486)
			(xy 387.093695 -267.257035) (xy 387.053546 -267.218326) (xy 387.01946 -267.174183) (xy 386.992164 -267.125548)
			(xy 386.972241 -267.073457) (xy 386.960115 -267.01902) (xy 386.956044 -266.963398) (xy 386.457444 -266.963398)
			(xy 387.486398 -267.992352) (xy 387.49381 -267.999031) (xy 387.512245 -268.006606) (xy 387.522212 -268.007084)
			(xy 388.93115 -268.007084) (xy 388.943088 -268.00429) (xy 388.948676 -268.001242) (xy 388.976208 -267.987419)
			(xy 389.034623 -267.967857) (xy 389.095421 -267.957924) (xy 389.126222 -267.9573) (xy 389.153493 -267.957788)
			(xy 389.20748 -267.965553) (xy 389.259812 -267.980922) (xy 389.309424 -268.003581) (xy 389.355307 -268.033071)
			(xy 389.396526 -268.06879) (xy 389.432242 -268.110011) (xy 389.461729 -268.155895) (xy 389.484386 -268.205509)
			(xy 389.499752 -268.257842) (xy 389.507514 -268.311829) (xy 389.507514 -268.366371) (xy 389.499752 -268.420358)
			(xy 389.484386 -268.472691) (xy 389.461729 -268.522305) (xy 389.432242 -268.568189) (xy 389.396526 -268.60941)
			(xy 389.355307 -268.645129) (xy 389.309424 -268.674619) (xy 389.259812 -268.697278) (xy 389.20748 -268.712647)
			(xy 389.153493 -268.720412) (xy 389.126222 -268.720824) (xy 389.09542 -268.720213) (xy 389.034624 -268.710273)
			(xy 388.976213 -268.690697) (xy 388.948676 -268.676882) (xy 388.943088 -268.673834) (xy 388.93115 -268.67104)
			(xy 387.363716 -268.67104) (xy 387.344418 -268.670701) (xy 387.306094 -268.666122) (xy 387.287262 -268.661896)
			(xy 387.28142 -268.660626) (xy 387.17728 -268.660626) (xy 387.167294 -268.660086) (xy 387.148864 -268.65237)
			(xy 387.141466 -268.64564) (xy 387.114288 -268.618462) (xy 387.072378 -268.576806) (xy 387.071362 -268.575536)
			(xy 387.068568 -268.572996) (xy 387.061964 -268.566646) (xy 386.182616 -267.687044) (xy 386.083302 -267.58773)
			(xy 386.076469 -267.581504) (xy 386.059608 -267.573966) (xy 386.04117 -267.572874) (xy 386.032248 -267.575284)
			(xy 385.932426 -267.60678) (xy 385.913884 -267.628116) (xy 385.911598 -267.64234) (xy 385.906627 -267.668645)
			(xy 385.890295 -267.719626) (xy 385.867007 -267.767829) (xy 385.837219 -267.812309) (xy 385.801514 -267.852196)
			(xy 385.760591 -267.886708) (xy 385.715252 -267.915171) (xy 385.666383 -267.937027) (xy 385.614942 -267.951848)
			(xy 385.561936 -267.959344) (xy 385.53517 -267.95984) (xy 385.507903 -267.959352) (xy 385.453923 -267.951586)
			(xy 385.401599 -267.936218) (xy 385.351994 -267.91356) (xy 385.306118 -267.884073) (xy 385.264906 -267.848357)
			(xy 385.229196 -267.80714) (xy 385.199715 -267.761261) (xy 385.177064 -267.711652) (xy 385.161703 -267.659326)
			(xy 385.153945 -267.605345) (xy 385.153408 -267.578078) (xy 385.153854 -267.551306) (xy 385.161324 -267.498285)
			(xy 385.176129 -267.446829) (xy 385.197979 -267.397945) (xy 385.226444 -267.352594) (xy 385.260967 -267.311666)
			(xy 385.30087 -267.275962) (xy 385.34537 -267.246184) (xy 385.393594 -267.222915) (xy 385.444596 -267.206613)
			(xy 385.470908 -267.20165) (xy 385.485386 -267.19911) (xy 385.506468 -267.180822) (xy 385.537964 -267.081)
			(xy 385.540346 -267.072073) (xy 385.539268 -267.053642) (xy 385.531727 -267.03679) (xy 385.525518 -267.029946)
			(xy 382.66243 -264.167112) (xy 382.655023 -264.160422) (xy 382.636586 -264.152827) (xy 382.626616 -264.15238)
			(xy 370.617496 -264.15238) (xy 370.591409 -264.151894) (xy 370.539877 -264.143727) (xy 370.490259 -264.127595)
			(xy 370.443777 -264.103896) (xy 370.401578 -264.073214) (xy 370.3828 -264.055098) (xy 368.429286 -262.101584)
			(xy 368.411172 -262.082804) (xy 368.380485 -262.040607) (xy 368.356783 -261.994126) (xy 368.340649 -261.944508)
			(xy 368.332483 -261.892976) (xy 368.332004 -261.866888) (xy 368.332004 -255.853946) (xy 368.33152 -255.843983)
			(xy 368.323936 -255.825555) (xy 368.317272 -255.818132) (xy 368.233452 -255.734058) (xy 368.226086 -255.727416)
			(xy 368.207787 -255.719814) (xy 368.187972 -255.719666) (xy 368.178588 -255.722882) (xy 368.164709 -255.728988)
			(xy 368.141064 -255.747941) (xy 368.124028 -255.773004) (xy 368.115104 -255.801964) (xy 368.11458 -255.817116)
			(xy 368.11458 -270.89989) (xy 375.182393 -270.89989) (xy 375.186382 -270.75135) (xy 375.198339 -270.603237)
			(xy 375.218229 -270.45598) (xy 375.245994 -270.310004) (xy 375.281555 -270.165727) (xy 375.324809 -270.023568)
			(xy 375.375631 -269.883935) (xy 375.433875 -269.747232) (xy 375.499373 -269.613852) (xy 375.571936 -269.48418)
			(xy 375.651354 -269.35859) (xy 375.737399 -269.237443) (xy 375.829823 -269.12109) (xy 375.928359 -269.009866)
			(xy 376.032723 -268.904091) (xy 376.142615 -268.804071) (xy 376.257716 -268.710093) (xy 376.377696 -268.622429)
			(xy 376.502209 -268.541332) (xy 376.630895 -268.467035) (xy 376.763384 -268.399753) (xy 376.899293 -268.339679)
			(xy 377.038231 -268.286987) (xy 377.179797 -268.241828) (xy 377.323583 -268.204333) (xy 377.469174 -268.174611)
			(xy 377.61615 -268.152746) (xy 377.764089 -268.138802) (xy 377.912562 -268.132818) (xy 378.061143 -268.134813)
			(xy 378.209402 -268.144781) (xy 378.356913 -268.162692) (xy 378.503249 -268.188495) (xy 378.64799 -268.222115)
			(xy 378.790717 -268.263457) (xy 378.93102 -268.3124) (xy 379.068493 -268.368803) (xy 379.20274 -268.432504)
			(xy 379.333375 -268.50332) (xy 379.46002 -268.581045) (xy 379.58231 -268.665456) (xy 379.699893 -268.756309)
			(xy 379.81243 -268.853343) (xy 379.919597 -268.956278) (xy 380.021084 -269.064817) (xy 380.116598 -269.178646)
			(xy 380.205865 -269.297439) (xy 380.288626 -269.420851) (xy 380.364644 -269.548529) (xy 380.433699 -269.680102)
			(xy 380.495592 -269.815193) (xy 380.546165 -269.943326) (xy 388.630666 -269.943326) (xy 388.634737 -269.887704)
			(xy 388.646863 -269.833267) (xy 388.666786 -269.781176) (xy 388.694082 -269.732541) (xy 388.728168 -269.688398)
			(xy 388.768317 -269.649689) (xy 388.813675 -269.617238) (xy 388.863275 -269.591737) (xy 388.916059 -269.57373)
			(xy 388.970902 -269.5636) (xy 389.026636 -269.561563) (xy 389.082073 -269.567663) (xy 389.13603 -269.581769)
			(xy 389.187359 -269.603581) (xy 389.234965 -269.632635) (xy 389.277833 -269.66831) (xy 389.31505 -269.709847)
			(xy 389.345823 -269.75636) (xy 389.369495 -269.806857) (xy 389.385563 -269.860264) (xy 389.393683 -269.91544)
			(xy 389.394192 -269.943326) (xy 389.393683 -269.971212) (xy 389.385563 -270.026388) (xy 389.369495 -270.079795)
			(xy 389.345823 -270.130292) (xy 389.31505 -270.176805) (xy 389.277833 -270.218342) (xy 389.234965 -270.254017)
			(xy 389.187359 -270.283071) (xy 389.13603 -270.304883) (xy 389.082073 -270.318989) (xy 389.026636 -270.325089)
			(xy 388.970902 -270.323052) (xy 388.916059 -270.312922) (xy 388.863275 -270.294915) (xy 388.813675 -270.269414)
			(xy 388.768317 -270.236963) (xy 388.728168 -270.198254) (xy 388.694082 -270.154111) (xy 388.666786 -270.105476)
			(xy 388.646863 -270.053385) (xy 388.634737 -269.998948) (xy 388.630666 -269.943326) (xy 380.546165 -269.943326)
			(xy 380.550145 -269.95341) (xy 380.5972 -270.094357) (xy 380.636622 -270.237627) (xy 380.668296 -270.382806)
			(xy 380.692132 -270.529475) (xy 380.708061 -270.677213) (xy 380.716037 -270.825593) (xy 380.716536 -270.89989)
			(xy 380.716037 -270.974187) (xy 380.708061 -271.122567) (xy 380.692132 -271.270305) (xy 380.668296 -271.416974)
			(xy 380.636622 -271.562153) (xy 380.5972 -271.705423) (xy 380.550145 -271.84637) (xy 380.495592 -271.984587)
			(xy 380.433699 -272.119678) (xy 380.364644 -272.251251) (xy 380.288626 -272.378929) (xy 380.205865 -272.502341)
			(xy 380.116598 -272.621134) (xy 380.113519 -272.624804) (xy 386.269242 -272.624804) (xy 386.273202 -272.57575)
			(xy 386.284979 -272.527966) (xy 386.30427 -272.48269) (xy 386.330573 -272.441094) (xy 386.363208 -272.404257)
			(xy 386.401329 -272.373132) (xy 386.44395 -272.348525) (xy 386.489966 -272.331073) (xy 386.538185 -272.321229)
			(xy 386.58736 -272.319248) (xy 386.636215 -272.32518) (xy 386.683486 -272.338872) (xy 386.727948 -272.35997)
			(xy 386.768451 -272.387926) (xy 386.803944 -272.422018) (xy 386.833509 -272.461362) (xy 386.85638 -272.504939)
			(xy 386.871964 -272.55162) (xy 386.879859 -272.600197) (xy 386.880354 -272.624804) (xy 388.169162 -272.624804)
			(xy 388.173122 -272.57575) (xy 388.184899 -272.527966) (xy 388.20419 -272.48269) (xy 388.230493 -272.441094)
			(xy 388.263128 -272.404257) (xy 388.301249 -272.373132) (xy 388.34387 -272.348525) (xy 388.389886 -272.331073)
			(xy 388.438105 -272.321229) (xy 388.48728 -272.319248) (xy 388.536135 -272.32518) (xy 388.583406 -272.338872)
			(xy 388.627868 -272.35997) (xy 388.668371 -272.387926) (xy 388.703864 -272.422018) (xy 388.733429 -272.461362)
			(xy 388.7563 -272.504939) (xy 388.771884 -272.55162) (xy 388.779779 -272.600197) (xy 388.780274 -272.624804)
			(xy 390.069082 -272.624804) (xy 390.073042 -272.57575) (xy 390.084819 -272.527966) (xy 390.10411 -272.48269)
			(xy 390.130413 -272.441094) (xy 390.163048 -272.404257) (xy 390.201169 -272.373132) (xy 390.24379 -272.348525)
			(xy 390.289806 -272.331073) (xy 390.338025 -272.321229) (xy 390.3872 -272.319248) (xy 390.436055 -272.32518)
			(xy 390.483326 -272.338872) (xy 390.527788 -272.35997) (xy 390.568291 -272.387926) (xy 390.603784 -272.422018)
			(xy 390.633349 -272.461362) (xy 390.65622 -272.504939) (xy 390.671804 -272.55162) (xy 390.679699 -272.600197)
			(xy 390.680194 -272.624804) (xy 390.679699 -272.649411) (xy 390.671804 -272.697988) (xy 390.65622 -272.744669)
			(xy 390.633349 -272.788246) (xy 390.603784 -272.82759) (xy 390.568291 -272.861682) (xy 390.527788 -272.889638)
			(xy 390.483326 -272.910736) (xy 390.436055 -272.924428) (xy 390.3872 -272.93036) (xy 390.338025 -272.928379)
			(xy 390.289806 -272.918535) (xy 390.24379 -272.901083) (xy 390.201169 -272.876476) (xy 390.163048 -272.845351)
			(xy 390.130413 -272.808514) (xy 390.10411 -272.766918) (xy 390.084819 -272.721642) (xy 390.073042 -272.673858)
			(xy 390.069082 -272.624804) (xy 388.780274 -272.624804) (xy 388.779779 -272.649411) (xy 388.771884 -272.697988)
			(xy 388.7563 -272.744669) (xy 388.733429 -272.788246) (xy 388.703864 -272.82759) (xy 388.668371 -272.861682)
			(xy 388.627868 -272.889638) (xy 388.583406 -272.910736) (xy 388.536135 -272.924428) (xy 388.48728 -272.93036)
			(xy 388.438105 -272.928379) (xy 388.389886 -272.918535) (xy 388.34387 -272.901083) (xy 388.301249 -272.876476)
			(xy 388.263128 -272.845351) (xy 388.230493 -272.808514) (xy 388.20419 -272.766918) (xy 388.184899 -272.721642)
			(xy 388.173122 -272.673858) (xy 388.169162 -272.624804) (xy 386.880354 -272.624804) (xy 386.879859 -272.649411)
			(xy 386.871964 -272.697988) (xy 386.85638 -272.744669) (xy 386.833509 -272.788246) (xy 386.803944 -272.82759)
			(xy 386.768451 -272.861682) (xy 386.727948 -272.889638) (xy 386.683486 -272.910736) (xy 386.636215 -272.924428)
			(xy 386.58736 -272.93036) (xy 386.538185 -272.928379) (xy 386.489966 -272.918535) (xy 386.44395 -272.901083)
			(xy 386.401329 -272.876476) (xy 386.363208 -272.845351) (xy 386.330573 -272.808514) (xy 386.30427 -272.766918)
			(xy 386.284979 -272.721642) (xy 386.273202 -272.673858) (xy 386.269242 -272.624804) (xy 380.113519 -272.624804)
			(xy 380.021084 -272.734963) (xy 379.919597 -272.843502) (xy 379.81243 -272.946437) (xy 379.699893 -273.043471)
			(xy 379.59374 -273.125492) (xy 392.423138 -273.125492) (xy 392.423138 -273.074076) (xy 392.431181 -273.023294)
			(xy 392.447069 -272.974395) (xy 392.470412 -272.928583) (xy 392.500633 -272.886987) (xy 392.536989 -272.850631)
			(xy 392.578585 -272.82041) (xy 392.624397 -272.797067) (xy 392.673296 -272.781179) (xy 392.724078 -272.773136)
			(xy 392.775494 -272.773136) (xy 392.826276 -272.781179) (xy 392.875175 -272.797067) (xy 392.920987 -272.82041)
			(xy 392.962583 -272.850631) (xy 392.998939 -272.886987) (xy 393.02916 -272.928583) (xy 393.052503 -272.974395)
			(xy 393.068391 -273.023294) (xy 393.076434 -273.074076) (xy 393.076938 -273.099784) (xy 393.076434 -273.125492)
			(xy 394.323312 -273.125492) (xy 394.323312 -273.074076) (xy 394.331355 -273.023294) (xy 394.347243 -272.974395)
			(xy 394.370586 -272.928583) (xy 394.400807 -272.886987) (xy 394.437163 -272.850631) (xy 394.478759 -272.82041)
			(xy 394.524571 -272.797067) (xy 394.57347 -272.781179) (xy 394.624252 -272.773136) (xy 394.675668 -272.773136)
			(xy 394.72645 -272.781179) (xy 394.775349 -272.797067) (xy 394.821161 -272.82041) (xy 394.862757 -272.850631)
			(xy 394.899113 -272.886987) (xy 394.929334 -272.928583) (xy 394.952677 -272.974395) (xy 394.968565 -273.023294)
			(xy 394.976608 -273.074076) (xy 394.977112 -273.099784) (xy 394.976608 -273.125492) (xy 396.223232 -273.125492)
			(xy 396.223232 -273.074076) (xy 396.231275 -273.023294) (xy 396.247163 -272.974395) (xy 396.270506 -272.928583)
			(xy 396.300727 -272.886987) (xy 396.337083 -272.850631) (xy 396.378679 -272.82041) (xy 396.424491 -272.797067)
			(xy 396.47339 -272.781179) (xy 396.524172 -272.773136) (xy 396.575588 -272.773136) (xy 396.62637 -272.781179)
			(xy 396.675269 -272.797067) (xy 396.721081 -272.82041) (xy 396.762677 -272.850631) (xy 396.799033 -272.886987)
			(xy 396.829254 -272.928583) (xy 396.852597 -272.974395) (xy 396.868485 -273.023294) (xy 396.876528 -273.074076)
			(xy 396.877032 -273.099784) (xy 396.876528 -273.125492) (xy 396.868485 -273.176274) (xy 396.852597 -273.225173)
			(xy 396.829254 -273.270985) (xy 396.799033 -273.312581) (xy 396.762677 -273.348937) (xy 396.721081 -273.379158)
			(xy 396.675269 -273.402501) (xy 396.62637 -273.418389) (xy 396.575588 -273.426432) (xy 396.524172 -273.426432)
			(xy 396.47339 -273.418389) (xy 396.424491 -273.402501) (xy 396.378679 -273.379158) (xy 396.337083 -273.348937)
			(xy 396.300727 -273.312581) (xy 396.270506 -273.270985) (xy 396.247163 -273.225173) (xy 396.231275 -273.176274)
			(xy 396.223232 -273.125492) (xy 394.976608 -273.125492) (xy 394.968565 -273.176274) (xy 394.952677 -273.225173)
			(xy 394.929334 -273.270985) (xy 394.899113 -273.312581) (xy 394.862757 -273.348937) (xy 394.821161 -273.379158)
			(xy 394.775349 -273.402501) (xy 394.72645 -273.418389) (xy 394.675668 -273.426432) (xy 394.624252 -273.426432)
			(xy 394.57347 -273.418389) (xy 394.524571 -273.402501) (xy 394.478759 -273.379158) (xy 394.437163 -273.348937)
			(xy 394.400807 -273.312581) (xy 394.370586 -273.270985) (xy 394.347243 -273.225173) (xy 394.331355 -273.176274)
			(xy 394.323312 -273.125492) (xy 393.076434 -273.125492) (xy 393.068391 -273.176274) (xy 393.052503 -273.225173)
			(xy 393.02916 -273.270985) (xy 392.998939 -273.312581) (xy 392.962583 -273.348937) (xy 392.920987 -273.379158)
			(xy 392.875175 -273.402501) (xy 392.826276 -273.418389) (xy 392.775494 -273.426432) (xy 392.724078 -273.426432)
			(xy 392.673296 -273.418389) (xy 392.624397 -273.402501) (xy 392.578585 -273.379158) (xy 392.536989 -273.348937)
			(xy 392.500633 -273.312581) (xy 392.470412 -273.270985) (xy 392.447069 -273.225173) (xy 392.431181 -273.176274)
			(xy 392.423138 -273.125492) (xy 379.59374 -273.125492) (xy 379.58231 -273.134324) (xy 379.46002 -273.218735)
			(xy 379.333375 -273.29646) (xy 379.20274 -273.367276) (xy 379.068493 -273.430977) (xy 378.93102 -273.48738)
			(xy 378.790717 -273.536323) (xy 378.658005 -273.574764) (xy 388.169162 -273.574764) (xy 388.173122 -273.52571)
			(xy 388.184899 -273.477926) (xy 388.20419 -273.43265) (xy 388.230493 -273.391054) (xy 388.263128 -273.354217)
			(xy 388.301249 -273.323092) (xy 388.34387 -273.298485) (xy 388.389886 -273.281033) (xy 388.438105 -273.271189)
			(xy 388.48728 -273.269208) (xy 388.536135 -273.27514) (xy 388.583406 -273.288832) (xy 388.627868 -273.30993)
			(xy 388.668371 -273.337886) (xy 388.703864 -273.371978) (xy 388.733429 -273.411322) (xy 388.7563 -273.454899)
			(xy 388.771884 -273.50158) (xy 388.779779 -273.550157) (xy 388.780274 -273.574764) (xy 390.069082 -273.574764)
			(xy 390.073042 -273.52571) (xy 390.084819 -273.477926) (xy 390.10411 -273.43265) (xy 390.130413 -273.391054)
			(xy 390.163048 -273.354217) (xy 390.201169 -273.323092) (xy 390.24379 -273.298485) (xy 390.289806 -273.281033)
			(xy 390.338025 -273.271189) (xy 390.3872 -273.269208) (xy 390.436055 -273.27514) (xy 390.483326 -273.288832)
			(xy 390.527788 -273.30993) (xy 390.568291 -273.337886) (xy 390.603784 -273.371978) (xy 390.633349 -273.411322)
			(xy 390.65622 -273.454899) (xy 390.671804 -273.50158) (xy 390.679699 -273.550157) (xy 390.680194 -273.574764)
			(xy 390.679699 -273.599371) (xy 390.671804 -273.647948) (xy 390.65622 -273.694629) (xy 390.633349 -273.738206)
			(xy 390.603784 -273.77755) (xy 390.568291 -273.811642) (xy 390.527788 -273.839598) (xy 390.483326 -273.860696)
			(xy 390.436055 -273.874388) (xy 390.3872 -273.88032) (xy 390.338025 -273.878339) (xy 390.289806 -273.868495)
			(xy 390.24379 -273.851043) (xy 390.201169 -273.826436) (xy 390.163048 -273.795311) (xy 390.130413 -273.758474)
			(xy 390.10411 -273.716878) (xy 390.084819 -273.671602) (xy 390.073042 -273.623818) (xy 390.069082 -273.574764)
			(xy 388.780274 -273.574764) (xy 388.779779 -273.599371) (xy 388.771884 -273.647948) (xy 388.7563 -273.694629)
			(xy 388.733429 -273.738206) (xy 388.703864 -273.77755) (xy 388.668371 -273.811642) (xy 388.627868 -273.839598)
			(xy 388.583406 -273.860696) (xy 388.536135 -273.874388) (xy 388.48728 -273.88032) (xy 388.438105 -273.878339)
			(xy 388.389886 -273.868495) (xy 388.34387 -273.851043) (xy 388.301249 -273.826436) (xy 388.263128 -273.795311)
			(xy 388.230493 -273.758474) (xy 388.20419 -273.716878) (xy 388.184899 -273.671602) (xy 388.173122 -273.623818)
			(xy 388.169162 -273.574764) (xy 378.658005 -273.574764) (xy 378.64799 -273.577665) (xy 378.503249 -273.611285)
			(xy 378.356913 -273.637088) (xy 378.209402 -273.654999) (xy 378.061143 -273.664967) (xy 377.912562 -273.666962)
			(xy 377.764089 -273.660978) (xy 377.61615 -273.647034) (xy 377.469174 -273.625169) (xy 377.323583 -273.595447)
			(xy 377.179797 -273.557952) (xy 377.038231 -273.512793) (xy 376.899293 -273.460101) (xy 376.763384 -273.400027)
			(xy 376.630895 -273.332745) (xy 376.502209 -273.258448) (xy 376.377696 -273.177351) (xy 376.257716 -273.089687)
			(xy 376.142615 -272.995709) (xy 376.032723 -272.895689) (xy 375.928359 -272.789914) (xy 375.829823 -272.67869)
			(xy 375.737399 -272.562337) (xy 375.651354 -272.44119) (xy 375.571936 -272.3156) (xy 375.499373 -272.185928)
			(xy 375.433875 -272.052548) (xy 375.375631 -271.915845) (xy 375.324809 -271.776212) (xy 375.281555 -271.634053)
			(xy 375.245994 -271.489776) (xy 375.218229 -271.3438) (xy 375.198339 -271.196543) (xy 375.186382 -271.04843)
			(xy 375.182393 -270.89989) (xy 368.11458 -270.89989) (xy 368.11458 -274.075452) (xy 392.423138 -274.075452)
			(xy 392.423138 -274.024036) (xy 392.431181 -273.973254) (xy 392.447069 -273.924355) (xy 392.470412 -273.878543)
			(xy 392.500633 -273.836947) (xy 392.536989 -273.800591) (xy 392.578585 -273.77037) (xy 392.624397 -273.747027)
			(xy 392.673296 -273.731139) (xy 392.724078 -273.723096) (xy 392.775494 -273.723096) (xy 392.826276 -273.731139)
			(xy 392.875175 -273.747027) (xy 392.920987 -273.77037) (xy 392.962583 -273.800591) (xy 392.998939 -273.836947)
			(xy 393.02916 -273.878543) (xy 393.052503 -273.924355) (xy 393.068391 -273.973254) (xy 393.076434 -274.024036)
			(xy 393.076938 -274.049744) (xy 393.076434 -274.075452) (xy 394.323312 -274.075452) (xy 394.323312 -274.024036)
			(xy 394.331355 -273.973254) (xy 394.347243 -273.924355) (xy 394.370586 -273.878543) (xy 394.400807 -273.836947)
			(xy 394.437163 -273.800591) (xy 394.478759 -273.77037) (xy 394.524571 -273.747027) (xy 394.57347 -273.731139)
			(xy 394.624252 -273.723096) (xy 394.675668 -273.723096) (xy 394.72645 -273.731139) (xy 394.775349 -273.747027)
			(xy 394.821161 -273.77037) (xy 394.862757 -273.800591) (xy 394.899113 -273.836947) (xy 394.929334 -273.878543)
			(xy 394.952677 -273.924355) (xy 394.968565 -273.973254) (xy 394.976608 -274.024036) (xy 394.977112 -274.049744)
			(xy 394.976608 -274.075452) (xy 394.968565 -274.126234) (xy 394.952677 -274.175133) (xy 394.929334 -274.220945)
			(xy 394.899113 -274.262541) (xy 394.862757 -274.298897) (xy 394.821161 -274.329118) (xy 394.775349 -274.352461)
			(xy 394.72645 -274.368349) (xy 394.675668 -274.376392) (xy 394.624252 -274.376392) (xy 394.57347 -274.368349)
			(xy 394.524571 -274.352461) (xy 394.478759 -274.329118) (xy 394.437163 -274.298897) (xy 394.400807 -274.262541)
			(xy 394.370586 -274.220945) (xy 394.347243 -274.175133) (xy 394.331355 -274.126234) (xy 394.323312 -274.075452)
			(xy 393.076434 -274.075452) (xy 393.068391 -274.126234) (xy 393.052503 -274.175133) (xy 393.02916 -274.220945)
			(xy 392.998939 -274.262541) (xy 392.962583 -274.298897) (xy 392.920987 -274.329118) (xy 392.875175 -274.352461)
			(xy 392.826276 -274.368349) (xy 392.775494 -274.376392) (xy 392.724078 -274.376392) (xy 392.673296 -274.368349)
			(xy 392.624397 -274.352461) (xy 392.578585 -274.329118) (xy 392.536989 -274.298897) (xy 392.500633 -274.262541)
			(xy 392.470412 -274.220945) (xy 392.447069 -274.175133) (xy 392.431181 -274.126234) (xy 392.423138 -274.075452)
			(xy 368.11458 -274.075452) (xy 368.11458 -274.524978) (xy 387.219202 -274.524978) (xy 387.223162 -274.475924)
			(xy 387.234939 -274.42814) (xy 387.25423 -274.382864) (xy 387.280533 -274.341268) (xy 387.313168 -274.304431)
			(xy 387.351289 -274.273306) (xy 387.39391 -274.248699) (xy 387.439926 -274.231247) (xy 387.488145 -274.221403)
			(xy 387.53732 -274.219422) (xy 387.586175 -274.225354) (xy 387.633446 -274.239046) (xy 387.677908 -274.260144)
			(xy 387.718411 -274.2881) (xy 387.753904 -274.322192) (xy 387.783469 -274.361536) (xy 387.80634 -274.405113)
			(xy 387.821924 -274.451794) (xy 387.829819 -274.500371) (xy 387.830314 -274.524978) (xy 389.119122 -274.524978)
			(xy 389.123082 -274.475924) (xy 389.134859 -274.42814) (xy 389.15415 -274.382864) (xy 389.180453 -274.341268)
			(xy 389.213088 -274.304431) (xy 389.251209 -274.273306) (xy 389.29383 -274.248699) (xy 389.339846 -274.231247)
			(xy 389.388065 -274.221403) (xy 389.43724 -274.219422) (xy 389.486095 -274.225354) (xy 389.533366 -274.239046)
			(xy 389.577828 -274.260144) (xy 389.618331 -274.2881) (xy 389.653824 -274.322192) (xy 389.683389 -274.361536)
			(xy 389.70626 -274.405113) (xy 389.721844 -274.451794) (xy 389.729739 -274.500371) (xy 389.730234 -274.524978)
			(xy 391.019042 -274.524978) (xy 391.023002 -274.475924) (xy 391.034779 -274.42814) (xy 391.05407 -274.382864)
			(xy 391.080373 -274.341268) (xy 391.113008 -274.304431) (xy 391.151129 -274.273306) (xy 391.19375 -274.248699)
			(xy 391.239766 -274.231247) (xy 391.287985 -274.221403) (xy 391.33716 -274.219422) (xy 391.386015 -274.225354)
			(xy 391.433286 -274.239046) (xy 391.477748 -274.260144) (xy 391.518251 -274.2881) (xy 391.553744 -274.322192)
			(xy 391.583309 -274.361536) (xy 391.60618 -274.405113) (xy 391.621764 -274.451794) (xy 391.629659 -274.500371)
			(xy 391.630154 -274.524978) (xy 391.629659 -274.549585) (xy 391.621764 -274.598162) (xy 391.60618 -274.644843)
			(xy 391.583309 -274.68842) (xy 391.553744 -274.727764) (xy 391.518251 -274.761856) (xy 391.477748 -274.789812)
			(xy 391.433286 -274.81091) (xy 391.386015 -274.824602) (xy 391.33716 -274.830534) (xy 391.287985 -274.828553)
			(xy 391.239766 -274.818709) (xy 391.19375 -274.801257) (xy 391.151129 -274.77665) (xy 391.113008 -274.745525)
			(xy 391.080373 -274.708688) (xy 391.05407 -274.667092) (xy 391.034779 -274.621816) (xy 391.023002 -274.574032)
			(xy 391.019042 -274.524978) (xy 389.730234 -274.524978) (xy 389.729739 -274.549585) (xy 389.721844 -274.598162)
			(xy 389.70626 -274.644843) (xy 389.683389 -274.68842) (xy 389.653824 -274.727764) (xy 389.618331 -274.761856)
			(xy 389.577828 -274.789812) (xy 389.533366 -274.81091) (xy 389.486095 -274.824602) (xy 389.43724 -274.830534)
			(xy 389.388065 -274.828553) (xy 389.339846 -274.818709) (xy 389.29383 -274.801257) (xy 389.251209 -274.77665)
			(xy 389.213088 -274.745525) (xy 389.180453 -274.708688) (xy 389.15415 -274.667092) (xy 389.134859 -274.621816)
			(xy 389.123082 -274.574032) (xy 389.119122 -274.524978) (xy 387.830314 -274.524978) (xy 387.829819 -274.549585)
			(xy 387.821924 -274.598162) (xy 387.80634 -274.644843) (xy 387.783469 -274.68842) (xy 387.753904 -274.727764)
			(xy 387.718411 -274.761856) (xy 387.677908 -274.789812) (xy 387.633446 -274.81091) (xy 387.586175 -274.824602)
			(xy 387.53732 -274.830534) (xy 387.488145 -274.828553) (xy 387.439926 -274.818709) (xy 387.39391 -274.801257)
			(xy 387.351289 -274.77665) (xy 387.313168 -274.745525) (xy 387.280533 -274.708688) (xy 387.25423 -274.667092)
			(xy 387.234939 -274.621816) (xy 387.223162 -274.574032) (xy 387.219202 -274.524978) (xy 368.11458 -274.524978)
			(xy 368.11458 -275.025666) (xy 393.373352 -275.025666) (xy 393.373352 -274.97425) (xy 393.381395 -274.923468)
			(xy 393.397283 -274.874569) (xy 393.420626 -274.828757) (xy 393.450847 -274.787161) (xy 393.487203 -274.750805)
			(xy 393.528799 -274.720584) (xy 393.574611 -274.697241) (xy 393.62351 -274.681353) (xy 393.674292 -274.67331)
			(xy 393.725708 -274.67331) (xy 393.77649 -274.681353) (xy 393.825389 -274.697241) (xy 393.871201 -274.720584)
			(xy 393.912797 -274.750805) (xy 393.949153 -274.787161) (xy 393.979374 -274.828757) (xy 394.002717 -274.874569)
			(xy 394.018605 -274.923468) (xy 394.026648 -274.97425) (xy 394.027152 -274.999958) (xy 394.026648 -275.025666)
			(xy 395.273272 -275.025666) (xy 395.273272 -274.97425) (xy 395.281315 -274.923468) (xy 395.297203 -274.874569)
			(xy 395.320546 -274.828757) (xy 395.350767 -274.787161) (xy 395.387123 -274.750805) (xy 395.428719 -274.720584)
			(xy 395.474531 -274.697241) (xy 395.52343 -274.681353) (xy 395.574212 -274.67331) (xy 395.625628 -274.67331)
			(xy 395.67641 -274.681353) (xy 395.725309 -274.697241) (xy 395.771121 -274.720584) (xy 395.812717 -274.750805)
			(xy 395.849073 -274.787161) (xy 395.879294 -274.828757) (xy 395.902637 -274.874569) (xy 395.918525 -274.923468)
			(xy 395.926568 -274.97425) (xy 395.927072 -274.999958) (xy 395.926568 -275.025666) (xy 395.918525 -275.076448)
			(xy 395.902637 -275.125347) (xy 395.879294 -275.171159) (xy 395.849073 -275.212755) (xy 395.812717 -275.249111)
			(xy 395.771121 -275.279332) (xy 395.725309 -275.302675) (xy 395.67641 -275.318563) (xy 395.625628 -275.326606)
			(xy 395.574212 -275.326606) (xy 395.52343 -275.318563) (xy 395.474531 -275.302675) (xy 395.428719 -275.279332)
			(xy 395.387123 -275.249111) (xy 395.350767 -275.212755) (xy 395.320546 -275.171159) (xy 395.297203 -275.125347)
			(xy 395.281315 -275.076448) (xy 395.273272 -275.025666) (xy 394.026648 -275.025666) (xy 394.018605 -275.076448)
			(xy 394.002717 -275.125347) (xy 393.979374 -275.171159) (xy 393.949153 -275.212755) (xy 393.912797 -275.249111)
			(xy 393.871201 -275.279332) (xy 393.825389 -275.302675) (xy 393.77649 -275.318563) (xy 393.725708 -275.326606)
			(xy 393.674292 -275.326606) (xy 393.62351 -275.318563) (xy 393.574611 -275.302675) (xy 393.528799 -275.279332)
			(xy 393.487203 -275.249111) (xy 393.450847 -275.212755) (xy 393.420626 -275.171159) (xy 393.397283 -275.125347)
			(xy 393.381395 -275.076448) (xy 393.373352 -275.025666) (xy 368.11458 -275.025666) (xy 368.11458 -275.474938)
			(xy 387.219202 -275.474938) (xy 387.223162 -275.425884) (xy 387.234939 -275.3781) (xy 387.25423 -275.332824)
			(xy 387.280533 -275.291228) (xy 387.313168 -275.254391) (xy 387.351289 -275.223266) (xy 387.39391 -275.198659)
			(xy 387.439926 -275.181207) (xy 387.488145 -275.171363) (xy 387.53732 -275.169382) (xy 387.586175 -275.175314)
			(xy 387.633446 -275.189006) (xy 387.677908 -275.210104) (xy 387.718411 -275.23806) (xy 387.753904 -275.272152)
			(xy 387.783469 -275.311496) (xy 387.80634 -275.355073) (xy 387.821924 -275.401754) (xy 387.829819 -275.450331)
			(xy 387.830314 -275.474938) (xy 389.119122 -275.474938) (xy 389.123082 -275.425884) (xy 389.134859 -275.3781)
			(xy 389.15415 -275.332824) (xy 389.180453 -275.291228) (xy 389.213088 -275.254391) (xy 389.251209 -275.223266)
			(xy 389.29383 -275.198659) (xy 389.339846 -275.181207) (xy 389.388065 -275.171363) (xy 389.43724 -275.169382)
			(xy 389.486095 -275.175314) (xy 389.533366 -275.189006) (xy 389.577828 -275.210104) (xy 389.618331 -275.23806)
			(xy 389.653824 -275.272152) (xy 389.683389 -275.311496) (xy 389.70626 -275.355073) (xy 389.721844 -275.401754)
			(xy 389.729739 -275.450331) (xy 389.730234 -275.474938) (xy 391.019042 -275.474938) (xy 391.023002 -275.425884)
			(xy 391.034779 -275.3781) (xy 391.05407 -275.332824) (xy 391.080373 -275.291228) (xy 391.113008 -275.254391)
			(xy 391.151129 -275.223266) (xy 391.19375 -275.198659) (xy 391.239766 -275.181207) (xy 391.287985 -275.171363)
			(xy 391.33716 -275.169382) (xy 391.386015 -275.175314) (xy 391.433286 -275.189006) (xy 391.477748 -275.210104)
			(xy 391.518251 -275.23806) (xy 391.553744 -275.272152) (xy 391.583309 -275.311496) (xy 391.60618 -275.355073)
			(xy 391.621764 -275.401754) (xy 391.629659 -275.450331) (xy 391.630154 -275.474938) (xy 391.629659 -275.499545)
			(xy 391.621764 -275.548122) (xy 391.60618 -275.594803) (xy 391.583309 -275.63838) (xy 391.553744 -275.677724)
			(xy 391.518251 -275.711816) (xy 391.477748 -275.739772) (xy 391.433286 -275.76087) (xy 391.386015 -275.774562)
			(xy 391.33716 -275.780494) (xy 391.287985 -275.778513) (xy 391.239766 -275.768669) (xy 391.19375 -275.751217)
			(xy 391.151129 -275.72661) (xy 391.113008 -275.695485) (xy 391.080373 -275.658648) (xy 391.05407 -275.617052)
			(xy 391.034779 -275.571776) (xy 391.023002 -275.523992) (xy 391.019042 -275.474938) (xy 389.730234 -275.474938)
			(xy 389.729739 -275.499545) (xy 389.721844 -275.548122) (xy 389.70626 -275.594803) (xy 389.683389 -275.63838)
			(xy 389.653824 -275.677724) (xy 389.618331 -275.711816) (xy 389.577828 -275.739772) (xy 389.533366 -275.76087)
			(xy 389.486095 -275.774562) (xy 389.43724 -275.780494) (xy 389.388065 -275.778513) (xy 389.339846 -275.768669)
			(xy 389.29383 -275.751217) (xy 389.251209 -275.72661) (xy 389.213088 -275.695485) (xy 389.180453 -275.658648)
			(xy 389.15415 -275.617052) (xy 389.134859 -275.571776) (xy 389.123082 -275.523992) (xy 389.119122 -275.474938)
			(xy 387.830314 -275.474938) (xy 387.829819 -275.499545) (xy 387.821924 -275.548122) (xy 387.80634 -275.594803)
			(xy 387.783469 -275.63838) (xy 387.753904 -275.677724) (xy 387.718411 -275.711816) (xy 387.677908 -275.739772)
			(xy 387.633446 -275.76087) (xy 387.586175 -275.774562) (xy 387.53732 -275.780494) (xy 387.488145 -275.778513)
			(xy 387.439926 -275.768669) (xy 387.39391 -275.751217) (xy 387.351289 -275.72661) (xy 387.313168 -275.695485)
			(xy 387.280533 -275.658648) (xy 387.25423 -275.617052) (xy 387.234939 -275.571776) (xy 387.223162 -275.523992)
			(xy 387.219202 -275.474938) (xy 368.11458 -275.474938) (xy 368.11458 -275.975626) (xy 393.373352 -275.975626)
			(xy 393.373352 -275.92421) (xy 393.381395 -275.873428) (xy 393.397283 -275.824529) (xy 393.420626 -275.778717)
			(xy 393.450847 -275.737121) (xy 393.487203 -275.700765) (xy 393.528799 -275.670544) (xy 393.574611 -275.647201)
			(xy 393.62351 -275.631313) (xy 393.674292 -275.62327) (xy 393.725708 -275.62327) (xy 393.77649 -275.631313)
			(xy 393.825389 -275.647201) (xy 393.871201 -275.670544) (xy 393.912797 -275.700765) (xy 393.949153 -275.737121)
			(xy 393.979374 -275.778717) (xy 394.002717 -275.824529) (xy 394.018605 -275.873428) (xy 394.026648 -275.92421)
			(xy 394.027152 -275.949918) (xy 394.026648 -275.975626) (xy 395.273272 -275.975626) (xy 395.273272 -275.92421)
			(xy 395.281315 -275.873428) (xy 395.297203 -275.824529) (xy 395.320546 -275.778717) (xy 395.350767 -275.737121)
			(xy 395.387123 -275.700765) (xy 395.428719 -275.670544) (xy 395.474531 -275.647201) (xy 395.52343 -275.631313)
			(xy 395.574212 -275.62327) (xy 395.625628 -275.62327) (xy 395.67641 -275.631313) (xy 395.725309 -275.647201)
			(xy 395.771121 -275.670544) (xy 395.812717 -275.700765) (xy 395.849073 -275.737121) (xy 395.879294 -275.778717)
			(xy 395.902637 -275.824529) (xy 395.918525 -275.873428) (xy 395.926568 -275.92421) (xy 395.927072 -275.949918)
			(xy 395.926568 -275.975626) (xy 395.918525 -276.026408) (xy 395.902637 -276.075307) (xy 395.879294 -276.121119)
			(xy 395.849073 -276.162715) (xy 395.812717 -276.199071) (xy 395.771121 -276.229292) (xy 395.725309 -276.252635)
			(xy 395.67641 -276.268523) (xy 395.625628 -276.276566) (xy 395.574212 -276.276566) (xy 395.52343 -276.268523)
			(xy 395.474531 -276.252635) (xy 395.428719 -276.229292) (xy 395.387123 -276.199071) (xy 395.350767 -276.162715)
			(xy 395.320546 -276.121119) (xy 395.297203 -276.075307) (xy 395.281315 -276.026408) (xy 395.273272 -275.975626)
			(xy 394.026648 -275.975626) (xy 394.018605 -276.026408) (xy 394.002717 -276.075307) (xy 393.979374 -276.121119)
			(xy 393.949153 -276.162715) (xy 393.912797 -276.199071) (xy 393.871201 -276.229292) (xy 393.825389 -276.252635)
			(xy 393.77649 -276.268523) (xy 393.725708 -276.276566) (xy 393.674292 -276.276566) (xy 393.62351 -276.268523)
			(xy 393.574611 -276.252635) (xy 393.528799 -276.229292) (xy 393.487203 -276.199071) (xy 393.450847 -276.162715)
			(xy 393.420626 -276.121119) (xy 393.397283 -276.075307) (xy 393.381395 -276.026408) (xy 393.373352 -275.975626)
			(xy 368.11458 -275.975626) (xy 368.11458 -276.424898) (xy 384.369068 -276.424898) (xy 384.373028 -276.375844)
			(xy 384.384805 -276.32806) (xy 384.404096 -276.282784) (xy 384.430399 -276.241188) (xy 384.463034 -276.204351)
			(xy 384.501155 -276.173226) (xy 384.543776 -276.148619) (xy 384.589792 -276.131167) (xy 384.638011 -276.121323)
			(xy 384.687186 -276.119342) (xy 384.736041 -276.125274) (xy 384.783312 -276.138966) (xy 384.827774 -276.160064)
			(xy 384.868277 -276.18802) (xy 384.90377 -276.222112) (xy 384.933335 -276.261456) (xy 384.956206 -276.305033)
			(xy 384.97179 -276.351714) (xy 384.979685 -276.400291) (xy 384.98018 -276.424898) (xy 385.319028 -276.424898)
			(xy 385.322988 -276.375844) (xy 385.334765 -276.32806) (xy 385.354056 -276.282784) (xy 385.380359 -276.241188)
			(xy 385.412994 -276.204351) (xy 385.451115 -276.173226) (xy 385.493736 -276.148619) (xy 385.539752 -276.131167)
			(xy 385.587971 -276.121323) (xy 385.637146 -276.119342) (xy 385.686001 -276.125274) (xy 385.733272 -276.138966)
			(xy 385.777734 -276.160064) (xy 385.818237 -276.18802) (xy 385.85373 -276.222112) (xy 385.883295 -276.261456)
			(xy 385.906166 -276.305033) (xy 385.92175 -276.351714) (xy 385.929645 -276.400291) (xy 385.93014 -276.424898)
			(xy 385.929645 -276.449505) (xy 385.92175 -276.498082) (xy 385.906166 -276.544763) (xy 385.883295 -276.58834)
			(xy 385.85373 -276.627684) (xy 385.818237 -276.661776) (xy 385.777734 -276.689732) (xy 385.733272 -276.71083)
			(xy 385.686001 -276.724522) (xy 385.637146 -276.730454) (xy 385.587971 -276.728473) (xy 385.539752 -276.718629)
			(xy 385.493736 -276.701177) (xy 385.451115 -276.67657) (xy 385.412994 -276.645445) (xy 385.380359 -276.608608)
			(xy 385.354056 -276.567012) (xy 385.334765 -276.521736) (xy 385.322988 -276.473952) (xy 385.319028 -276.424898)
			(xy 384.98018 -276.424898) (xy 384.979685 -276.449505) (xy 384.97179 -276.498082) (xy 384.956206 -276.544763)
			(xy 384.933335 -276.58834) (xy 384.90377 -276.627684) (xy 384.868277 -276.661776) (xy 384.827774 -276.689732)
			(xy 384.783312 -276.71083) (xy 384.736041 -276.724522) (xy 384.687186 -276.730454) (xy 384.638011 -276.728473)
			(xy 384.589792 -276.718629) (xy 384.543776 -276.701177) (xy 384.501155 -276.67657) (xy 384.463034 -276.645445)
			(xy 384.430399 -276.608608) (xy 384.404096 -276.567012) (xy 384.384805 -276.521736) (xy 384.373028 -276.473952)
			(xy 384.369068 -276.424898) (xy 368.11458 -276.424898) (xy 368.11458 -277.374858) (xy 386.269242 -277.374858)
			(xy 386.273202 -277.325804) (xy 386.284979 -277.27802) (xy 386.30427 -277.232744) (xy 386.330573 -277.191148)
			(xy 386.363208 -277.154311) (xy 386.401329 -277.123186) (xy 386.44395 -277.098579) (xy 386.489966 -277.081127)
			(xy 386.538185 -277.071283) (xy 386.58736 -277.069302) (xy 386.636215 -277.075234) (xy 386.683486 -277.088926)
			(xy 386.727948 -277.110024) (xy 386.768451 -277.13798) (xy 386.803944 -277.172072) (xy 386.833509 -277.211416)
			(xy 386.85638 -277.254993) (xy 386.871964 -277.301674) (xy 386.879859 -277.350251) (xy 386.880354 -277.374858)
			(xy 388.169162 -277.374858) (xy 388.173122 -277.325804) (xy 388.184899 -277.27802) (xy 388.20419 -277.232744)
			(xy 388.230493 -277.191148) (xy 388.263128 -277.154311) (xy 388.301249 -277.123186) (xy 388.34387 -277.098579)
			(xy 388.389886 -277.081127) (xy 388.438105 -277.071283) (xy 388.48728 -277.069302) (xy 388.536135 -277.075234)
			(xy 388.583406 -277.088926) (xy 388.627868 -277.110024) (xy 388.668371 -277.13798) (xy 388.703864 -277.172072)
			(xy 388.733429 -277.211416) (xy 388.7563 -277.254993) (xy 388.771884 -277.301674) (xy 388.779779 -277.350251)
			(xy 388.780274 -277.374858) (xy 390.069082 -277.374858) (xy 390.073042 -277.325804) (xy 390.084819 -277.27802)
			(xy 390.10411 -277.232744) (xy 390.130413 -277.191148) (xy 390.163048 -277.154311) (xy 390.201169 -277.123186)
			(xy 390.24379 -277.098579) (xy 390.289806 -277.081127) (xy 390.338025 -277.071283) (xy 390.3872 -277.069302)
			(xy 390.436055 -277.075234) (xy 390.483326 -277.088926) (xy 390.527788 -277.110024) (xy 390.568291 -277.13798)
			(xy 390.603784 -277.172072) (xy 390.633349 -277.211416) (xy 390.65622 -277.254993) (xy 390.671804 -277.301674)
			(xy 390.679699 -277.350251) (xy 390.680194 -277.374858) (xy 390.679699 -277.399465) (xy 390.671804 -277.448042)
			(xy 390.65622 -277.494723) (xy 390.633349 -277.5383) (xy 390.603784 -277.577644) (xy 390.568291 -277.611736)
			(xy 390.527788 -277.639692) (xy 390.483326 -277.66079) (xy 390.436055 -277.674482) (xy 390.3872 -277.680414)
			(xy 390.338025 -277.678433) (xy 390.289806 -277.668589) (xy 390.24379 -277.651137) (xy 390.201169 -277.62653)
			(xy 390.163048 -277.595405) (xy 390.130413 -277.558568) (xy 390.10411 -277.516972) (xy 390.084819 -277.471696)
			(xy 390.073042 -277.423912) (xy 390.069082 -277.374858) (xy 388.780274 -277.374858) (xy 388.779779 -277.399465)
			(xy 388.771884 -277.448042) (xy 388.7563 -277.494723) (xy 388.733429 -277.5383) (xy 388.703864 -277.577644)
			(xy 388.668371 -277.611736) (xy 388.627868 -277.639692) (xy 388.583406 -277.66079) (xy 388.536135 -277.674482)
			(xy 388.48728 -277.680414) (xy 388.438105 -277.678433) (xy 388.389886 -277.668589) (xy 388.34387 -277.651137)
			(xy 388.301249 -277.62653) (xy 388.263128 -277.595405) (xy 388.230493 -277.558568) (xy 388.20419 -277.516972)
			(xy 388.184899 -277.471696) (xy 388.173122 -277.423912) (xy 388.169162 -277.374858) (xy 386.880354 -277.374858)
			(xy 386.879859 -277.399465) (xy 386.871964 -277.448042) (xy 386.85638 -277.494723) (xy 386.833509 -277.5383)
			(xy 386.803944 -277.577644) (xy 386.768451 -277.611736) (xy 386.727948 -277.639692) (xy 386.683486 -277.66079)
			(xy 386.636215 -277.674482) (xy 386.58736 -277.680414) (xy 386.538185 -277.678433) (xy 386.489966 -277.668589)
			(xy 386.44395 -277.651137) (xy 386.401329 -277.62653) (xy 386.363208 -277.595405) (xy 386.330573 -277.558568)
			(xy 386.30427 -277.516972) (xy 386.284979 -277.471696) (xy 386.273202 -277.423912) (xy 386.269242 -277.374858)
			(xy 368.11458 -277.374858) (xy 368.11458 -277.875546) (xy 392.423138 -277.875546) (xy 392.423138 -277.82413)
			(xy 392.431181 -277.773348) (xy 392.447069 -277.724449) (xy 392.470412 -277.678637) (xy 392.500633 -277.637041)
			(xy 392.536989 -277.600685) (xy 392.578585 -277.570464) (xy 392.624397 -277.547121) (xy 392.673296 -277.531233)
			(xy 392.724078 -277.52319) (xy 392.775494 -277.52319) (xy 392.826276 -277.531233) (xy 392.875175 -277.547121)
			(xy 392.920987 -277.570464) (xy 392.962583 -277.600685) (xy 392.998939 -277.637041) (xy 393.02916 -277.678637)
			(xy 393.052503 -277.724449) (xy 393.068391 -277.773348) (xy 393.076434 -277.82413) (xy 393.076938 -277.849838)
			(xy 393.076434 -277.875546) (xy 394.323312 -277.875546) (xy 394.323312 -277.82413) (xy 394.331355 -277.773348)
			(xy 394.347243 -277.724449) (xy 394.370586 -277.678637) (xy 394.400807 -277.637041) (xy 394.437163 -277.600685)
			(xy 394.478759 -277.570464) (xy 394.524571 -277.547121) (xy 394.57347 -277.531233) (xy 394.624252 -277.52319)
			(xy 394.675668 -277.52319) (xy 394.72645 -277.531233) (xy 394.775349 -277.547121) (xy 394.821161 -277.570464)
			(xy 394.862757 -277.600685) (xy 394.899113 -277.637041) (xy 394.929334 -277.678637) (xy 394.952677 -277.724449)
			(xy 394.968565 -277.773348) (xy 394.976608 -277.82413) (xy 394.977112 -277.849838) (xy 394.976608 -277.875546)
			(xy 396.223232 -277.875546) (xy 396.223232 -277.82413) (xy 396.231275 -277.773348) (xy 396.247163 -277.724449)
			(xy 396.270506 -277.678637) (xy 396.300727 -277.637041) (xy 396.337083 -277.600685) (xy 396.378679 -277.570464)
			(xy 396.424491 -277.547121) (xy 396.47339 -277.531233) (xy 396.524172 -277.52319) (xy 396.575588 -277.52319)
			(xy 396.62637 -277.531233) (xy 396.675269 -277.547121) (xy 396.721081 -277.570464) (xy 396.762677 -277.600685)
			(xy 396.799033 -277.637041) (xy 396.829254 -277.678637) (xy 396.852597 -277.724449) (xy 396.868485 -277.773348)
			(xy 396.876528 -277.82413) (xy 396.877032 -277.849838) (xy 396.876528 -277.875546) (xy 396.868485 -277.926328)
			(xy 396.852597 -277.975227) (xy 396.829254 -278.021039) (xy 396.799033 -278.062635) (xy 396.762677 -278.098991)
			(xy 396.721081 -278.129212) (xy 396.675269 -278.152555) (xy 396.62637 -278.168443) (xy 396.575588 -278.176486)
			(xy 396.524172 -278.176486) (xy 396.47339 -278.168443) (xy 396.424491 -278.152555) (xy 396.378679 -278.129212)
			(xy 396.337083 -278.098991) (xy 396.300727 -278.062635) (xy 396.270506 -278.021039) (xy 396.247163 -277.975227)
			(xy 396.231275 -277.926328) (xy 396.223232 -277.875546) (xy 394.976608 -277.875546) (xy 394.968565 -277.926328)
			(xy 394.952677 -277.975227) (xy 394.929334 -278.021039) (xy 394.899113 -278.062635) (xy 394.862757 -278.098991)
			(xy 394.821161 -278.129212) (xy 394.775349 -278.152555) (xy 394.72645 -278.168443) (xy 394.675668 -278.176486)
			(xy 394.624252 -278.176486) (xy 394.57347 -278.168443) (xy 394.524571 -278.152555) (xy 394.478759 -278.129212)
			(xy 394.437163 -278.098991) (xy 394.400807 -278.062635) (xy 394.370586 -278.021039) (xy 394.347243 -277.975227)
			(xy 394.331355 -277.926328) (xy 394.323312 -277.875546) (xy 393.076434 -277.875546) (xy 393.068391 -277.926328)
			(xy 393.052503 -277.975227) (xy 393.02916 -278.021039) (xy 392.998939 -278.062635) (xy 392.962583 -278.098991)
			(xy 392.920987 -278.129212) (xy 392.875175 -278.152555) (xy 392.826276 -278.168443) (xy 392.775494 -278.176486)
			(xy 392.724078 -278.176486) (xy 392.673296 -278.168443) (xy 392.624397 -278.152555) (xy 392.578585 -278.129212)
			(xy 392.536989 -278.098991) (xy 392.500633 -278.062635) (xy 392.470412 -278.021039) (xy 392.447069 -277.975227)
			(xy 392.431181 -277.926328) (xy 392.423138 -277.875546) (xy 368.11458 -277.875546) (xy 368.11458 -278.324818)
			(xy 386.269242 -278.324818) (xy 386.273202 -278.275764) (xy 386.284979 -278.22798) (xy 386.30427 -278.182704)
			(xy 386.330573 -278.141108) (xy 386.363208 -278.104271) (xy 386.401329 -278.073146) (xy 386.44395 -278.048539)
			(xy 386.489966 -278.031087) (xy 386.538185 -278.021243) (xy 386.58736 -278.019262) (xy 386.636215 -278.025194)
			(xy 386.683486 -278.038886) (xy 386.727948 -278.059984) (xy 386.768451 -278.08794) (xy 386.803944 -278.122032)
			(xy 386.833509 -278.161376) (xy 386.85638 -278.204953) (xy 386.871964 -278.251634) (xy 386.879859 -278.300211)
			(xy 386.880354 -278.324818) (xy 388.169162 -278.324818) (xy 388.173122 -278.275764) (xy 388.184899 -278.22798)
			(xy 388.20419 -278.182704) (xy 388.230493 -278.141108) (xy 388.263128 -278.104271) (xy 388.301249 -278.073146)
			(xy 388.34387 -278.048539) (xy 388.389886 -278.031087) (xy 388.438105 -278.021243) (xy 388.48728 -278.019262)
			(xy 388.536135 -278.025194) (xy 388.583406 -278.038886) (xy 388.627868 -278.059984) (xy 388.668371 -278.08794)
			(xy 388.703864 -278.122032) (xy 388.733429 -278.161376) (xy 388.7563 -278.204953) (xy 388.771884 -278.251634)
			(xy 388.779779 -278.300211) (xy 388.780274 -278.324818) (xy 390.069082 -278.324818) (xy 390.073042 -278.275764)
			(xy 390.084819 -278.22798) (xy 390.10411 -278.182704) (xy 390.130413 -278.141108) (xy 390.163048 -278.104271)
			(xy 390.201169 -278.073146) (xy 390.24379 -278.048539) (xy 390.289806 -278.031087) (xy 390.338025 -278.021243)
			(xy 390.3872 -278.019262) (xy 390.436055 -278.025194) (xy 390.483326 -278.038886) (xy 390.527788 -278.059984)
			(xy 390.568291 -278.08794) (xy 390.603784 -278.122032) (xy 390.633349 -278.161376) (xy 390.65622 -278.204953)
			(xy 390.671804 -278.251634) (xy 390.679699 -278.300211) (xy 390.680194 -278.324818) (xy 390.679699 -278.349425)
			(xy 390.671804 -278.398002) (xy 390.65622 -278.444683) (xy 390.633349 -278.48826) (xy 390.603784 -278.527604)
			(xy 390.568291 -278.561696) (xy 390.527788 -278.589652) (xy 390.483326 -278.61075) (xy 390.436055 -278.624442)
			(xy 390.3872 -278.630374) (xy 390.338025 -278.628393) (xy 390.289806 -278.618549) (xy 390.24379 -278.601097)
			(xy 390.201169 -278.57649) (xy 390.163048 -278.545365) (xy 390.130413 -278.508528) (xy 390.10411 -278.466932)
			(xy 390.084819 -278.421656) (xy 390.073042 -278.373872) (xy 390.069082 -278.324818) (xy 388.780274 -278.324818)
			(xy 388.779779 -278.349425) (xy 388.771884 -278.398002) (xy 388.7563 -278.444683) (xy 388.733429 -278.48826)
			(xy 388.703864 -278.527604) (xy 388.668371 -278.561696) (xy 388.627868 -278.589652) (xy 388.583406 -278.61075)
			(xy 388.536135 -278.624442) (xy 388.48728 -278.630374) (xy 388.438105 -278.628393) (xy 388.389886 -278.618549)
			(xy 388.34387 -278.601097) (xy 388.301249 -278.57649) (xy 388.263128 -278.545365) (xy 388.230493 -278.508528)
			(xy 388.20419 -278.466932) (xy 388.184899 -278.421656) (xy 388.173122 -278.373872) (xy 388.169162 -278.324818)
			(xy 386.880354 -278.324818) (xy 386.879859 -278.349425) (xy 386.871964 -278.398002) (xy 386.85638 -278.444683)
			(xy 386.833509 -278.48826) (xy 386.803944 -278.527604) (xy 386.768451 -278.561696) (xy 386.727948 -278.589652)
			(xy 386.683486 -278.61075) (xy 386.636215 -278.624442) (xy 386.58736 -278.630374) (xy 386.538185 -278.628393)
			(xy 386.489966 -278.618549) (xy 386.44395 -278.601097) (xy 386.401329 -278.57649) (xy 386.363208 -278.545365)
			(xy 386.330573 -278.508528) (xy 386.30427 -278.466932) (xy 386.284979 -278.421656) (xy 386.273202 -278.373872)
			(xy 386.269242 -278.324818) (xy 368.11458 -278.324818) (xy 368.11458 -278.825506) (xy 392.423138 -278.825506)
			(xy 392.423138 -278.77409) (xy 392.431181 -278.723308) (xy 392.447069 -278.674409) (xy 392.470412 -278.628597)
			(xy 392.500633 -278.587001) (xy 392.536989 -278.550645) (xy 392.578585 -278.520424) (xy 392.624397 -278.497081)
			(xy 392.673296 -278.481193) (xy 392.724078 -278.47315) (xy 392.775494 -278.47315) (xy 392.826276 -278.481193)
			(xy 392.875175 -278.497081) (xy 392.920987 -278.520424) (xy 392.962583 -278.550645) (xy 392.998939 -278.587001)
			(xy 393.02916 -278.628597) (xy 393.052503 -278.674409) (xy 393.068391 -278.723308) (xy 393.076434 -278.77409)
			(xy 393.076938 -278.799798) (xy 393.076434 -278.825506) (xy 394.323312 -278.825506) (xy 394.323312 -278.77409)
			(xy 394.331355 -278.723308) (xy 394.347243 -278.674409) (xy 394.370586 -278.628597) (xy 394.400807 -278.587001)
			(xy 394.437163 -278.550645) (xy 394.478759 -278.520424) (xy 394.524571 -278.497081) (xy 394.57347 -278.481193)
			(xy 394.624252 -278.47315) (xy 394.675668 -278.47315) (xy 394.72645 -278.481193) (xy 394.775349 -278.497081)
			(xy 394.821161 -278.520424) (xy 394.862757 -278.550645) (xy 394.899113 -278.587001) (xy 394.929334 -278.628597)
			(xy 394.952677 -278.674409) (xy 394.968565 -278.723308) (xy 394.976608 -278.77409) (xy 394.977112 -278.799798)
			(xy 394.976608 -278.825506) (xy 396.223232 -278.825506) (xy 396.223232 -278.77409) (xy 396.231275 -278.723308)
			(xy 396.247163 -278.674409) (xy 396.270506 -278.628597) (xy 396.300727 -278.587001) (xy 396.337083 -278.550645)
			(xy 396.378679 -278.520424) (xy 396.424491 -278.497081) (xy 396.47339 -278.481193) (xy 396.524172 -278.47315)
			(xy 396.575588 -278.47315) (xy 396.62637 -278.481193) (xy 396.675269 -278.497081) (xy 396.721081 -278.520424)
			(xy 396.762677 -278.550645) (xy 396.799033 -278.587001) (xy 396.829254 -278.628597) (xy 396.852597 -278.674409)
			(xy 396.868485 -278.723308) (xy 396.876528 -278.77409) (xy 396.877032 -278.799798) (xy 396.876528 -278.825506)
			(xy 396.868485 -278.876288) (xy 396.852597 -278.925187) (xy 396.829254 -278.970999) (xy 396.799033 -279.012595)
			(xy 396.762677 -279.048951) (xy 396.721081 -279.079172) (xy 396.675269 -279.102515) (xy 396.62637 -279.118403)
			(xy 396.575588 -279.126446) (xy 396.524172 -279.126446) (xy 396.47339 -279.118403) (xy 396.424491 -279.102515)
			(xy 396.378679 -279.079172) (xy 396.337083 -279.048951) (xy 396.300727 -279.012595) (xy 396.270506 -278.970999)
			(xy 396.247163 -278.925187) (xy 396.231275 -278.876288) (xy 396.223232 -278.825506) (xy 394.976608 -278.825506)
			(xy 394.968565 -278.876288) (xy 394.952677 -278.925187) (xy 394.929334 -278.970999) (xy 394.899113 -279.012595)
			(xy 394.862757 -279.048951) (xy 394.821161 -279.079172) (xy 394.775349 -279.102515) (xy 394.72645 -279.118403)
			(xy 394.675668 -279.126446) (xy 394.624252 -279.126446) (xy 394.57347 -279.118403) (xy 394.524571 -279.102515)
			(xy 394.478759 -279.079172) (xy 394.437163 -279.048951) (xy 394.400807 -279.012595) (xy 394.370586 -278.970999)
			(xy 394.347243 -278.925187) (xy 394.331355 -278.876288) (xy 394.323312 -278.825506) (xy 393.076434 -278.825506)
			(xy 393.068391 -278.876288) (xy 393.052503 -278.925187) (xy 393.02916 -278.970999) (xy 392.998939 -279.012595)
			(xy 392.962583 -279.048951) (xy 392.920987 -279.079172) (xy 392.875175 -279.102515) (xy 392.826276 -279.118403)
			(xy 392.775494 -279.126446) (xy 392.724078 -279.126446) (xy 392.673296 -279.118403) (xy 392.624397 -279.102515)
			(xy 392.578585 -279.079172) (xy 392.536989 -279.048951) (xy 392.500633 -279.012595) (xy 392.470412 -278.970999)
			(xy 392.447069 -278.925187) (xy 392.431181 -278.876288) (xy 392.423138 -278.825506) (xy 368.11458 -278.825506)
			(xy 368.11458 -279.274778) (xy 384.369068 -279.274778) (xy 384.373028 -279.225724) (xy 384.384805 -279.17794)
			(xy 384.404096 -279.132664) (xy 384.430399 -279.091068) (xy 384.463034 -279.054231) (xy 384.501155 -279.023106)
			(xy 384.543776 -278.998499) (xy 384.589792 -278.981047) (xy 384.638011 -278.971203) (xy 384.687186 -278.969222)
			(xy 384.736041 -278.975154) (xy 384.783312 -278.988846) (xy 384.827774 -279.009944) (xy 384.868277 -279.0379)
			(xy 384.90377 -279.071992) (xy 384.933335 -279.111336) (xy 384.956206 -279.154913) (xy 384.97179 -279.201594)
			(xy 384.979685 -279.250171) (xy 384.98018 -279.274778) (xy 385.319028 -279.274778) (xy 385.322988 -279.225724)
			(xy 385.334765 -279.17794) (xy 385.354056 -279.132664) (xy 385.380359 -279.091068) (xy 385.412994 -279.054231)
			(xy 385.451115 -279.023106) (xy 385.493736 -278.998499) (xy 385.539752 -278.981047) (xy 385.587971 -278.971203)
			(xy 385.637146 -278.969222) (xy 385.686001 -278.975154) (xy 385.733272 -278.988846) (xy 385.777734 -279.009944)
			(xy 385.818237 -279.0379) (xy 385.85373 -279.071992) (xy 385.883295 -279.111336) (xy 385.906166 -279.154913)
			(xy 385.92175 -279.201594) (xy 385.929645 -279.250171) (xy 385.93014 -279.274778) (xy 387.219202 -279.274778)
			(xy 387.223162 -279.225724) (xy 387.234939 -279.17794) (xy 387.25423 -279.132664) (xy 387.280533 -279.091068)
			(xy 387.313168 -279.054231) (xy 387.351289 -279.023106) (xy 387.39391 -278.998499) (xy 387.439926 -278.981047)
			(xy 387.488145 -278.971203) (xy 387.53732 -278.969222) (xy 387.586175 -278.975154) (xy 387.633446 -278.988846)
			(xy 387.677908 -279.009944) (xy 387.718411 -279.0379) (xy 387.753904 -279.071992) (xy 387.783469 -279.111336)
			(xy 387.80634 -279.154913) (xy 387.821924 -279.201594) (xy 387.829819 -279.250171) (xy 387.830314 -279.274778)
			(xy 389.119122 -279.274778) (xy 389.123082 -279.225724) (xy 389.134859 -279.17794) (xy 389.15415 -279.132664)
			(xy 389.180453 -279.091068) (xy 389.213088 -279.054231) (xy 389.251209 -279.023106) (xy 389.29383 -278.998499)
			(xy 389.339846 -278.981047) (xy 389.388065 -278.971203) (xy 389.43724 -278.969222) (xy 389.486095 -278.975154)
			(xy 389.533366 -278.988846) (xy 389.577828 -279.009944) (xy 389.618331 -279.0379) (xy 389.653824 -279.071992)
			(xy 389.683389 -279.111336) (xy 389.70626 -279.154913) (xy 389.721844 -279.201594) (xy 389.729739 -279.250171)
			(xy 389.730234 -279.274778) (xy 389.729739 -279.299385) (xy 389.721844 -279.347962) (xy 389.70626 -279.394643)
			(xy 389.683389 -279.43822) (xy 389.653824 -279.477564) (xy 389.618331 -279.511656) (xy 389.577828 -279.539612)
			(xy 389.533366 -279.56071) (xy 389.486095 -279.574402) (xy 389.43724 -279.580334) (xy 389.388065 -279.578353)
			(xy 389.339846 -279.568509) (xy 389.29383 -279.551057) (xy 389.251209 -279.52645) (xy 389.213088 -279.495325)
			(xy 389.180453 -279.458488) (xy 389.15415 -279.416892) (xy 389.134859 -279.371616) (xy 389.123082 -279.323832)
			(xy 389.119122 -279.274778) (xy 387.830314 -279.274778) (xy 387.829819 -279.299385) (xy 387.821924 -279.347962)
			(xy 387.80634 -279.394643) (xy 387.783469 -279.43822) (xy 387.753904 -279.477564) (xy 387.718411 -279.511656)
			(xy 387.677908 -279.539612) (xy 387.633446 -279.56071) (xy 387.586175 -279.574402) (xy 387.53732 -279.580334)
			(xy 387.488145 -279.578353) (xy 387.439926 -279.568509) (xy 387.39391 -279.551057) (xy 387.351289 -279.52645)
			(xy 387.313168 -279.495325) (xy 387.280533 -279.458488) (xy 387.25423 -279.416892) (xy 387.234939 -279.371616)
			(xy 387.223162 -279.323832) (xy 387.219202 -279.274778) (xy 385.93014 -279.274778) (xy 385.929645 -279.299385)
			(xy 385.92175 -279.347962) (xy 385.906166 -279.394643) (xy 385.883295 -279.43822) (xy 385.85373 -279.477564)
			(xy 385.818237 -279.511656) (xy 385.777734 -279.539612) (xy 385.733272 -279.56071) (xy 385.686001 -279.574402)
			(xy 385.637146 -279.580334) (xy 385.587971 -279.578353) (xy 385.539752 -279.568509) (xy 385.493736 -279.551057)
			(xy 385.451115 -279.52645) (xy 385.412994 -279.495325) (xy 385.380359 -279.458488) (xy 385.354056 -279.416892)
			(xy 385.334765 -279.371616) (xy 385.322988 -279.323832) (xy 385.319028 -279.274778) (xy 384.98018 -279.274778)
			(xy 384.979685 -279.299385) (xy 384.97179 -279.347962) (xy 384.956206 -279.394643) (xy 384.933335 -279.43822)
			(xy 384.90377 -279.477564) (xy 384.868277 -279.511656) (xy 384.827774 -279.539612) (xy 384.783312 -279.56071)
			(xy 384.736041 -279.574402) (xy 384.687186 -279.580334) (xy 384.638011 -279.578353) (xy 384.589792 -279.568509)
			(xy 384.543776 -279.551057) (xy 384.501155 -279.52645) (xy 384.463034 -279.495325) (xy 384.430399 -279.458488)
			(xy 384.404096 -279.416892) (xy 384.384805 -279.371616) (xy 384.373028 -279.323832) (xy 384.369068 -279.274778)
			(xy 368.11458 -279.274778) (xy 368.11458 -280.693114) (xy 379.638052 -280.693114) (xy 379.638619 -280.663733)
			(xy 379.647646 -280.605668) (xy 379.665474 -280.549675) (xy 379.691681 -280.49708) (xy 379.725646 -280.449128)
			(xy 379.766565 -280.406954) (xy 379.78969 -280.388822) (xy 379.799088 -280.381456) (xy 379.809502 -280.360882)
			(xy 379.811026 -280.256996) (xy 379.80112 -280.235914) (xy 379.791976 -280.228548) (xy 379.770116 -280.210356)
			(xy 379.731578 -280.168534) (xy 379.699673 -280.121455) (xy 379.675108 -280.070163) (xy 379.658427 -280.015793)
			(xy 379.65 -279.95955) (xy 379.649482 -279.931114) (xy 379.649968 -279.903863) (xy 379.657724 -279.849915)
			(xy 379.673079 -279.79762) (xy 379.695721 -279.748043) (xy 379.725187 -279.702193) (xy 379.760878 -279.661002)
			(xy 379.802069 -279.625311) (xy 379.847919 -279.595845) (xy 379.897496 -279.573203) (xy 379.949791 -279.557848)
			(xy 380.003739 -279.550092) (xy 380.058241 -279.550092) (xy 380.112189 -279.557848) (xy 380.164484 -279.573203)
			(xy 380.214061 -279.595845) (xy 380.259911 -279.625311) (xy 380.301102 -279.661002) (xy 380.336793 -279.702193)
			(xy 380.366259 -279.748043) (xy 380.378667 -279.775212) (xy 393.373352 -279.775212) (xy 393.373352 -279.723796)
			(xy 393.381395 -279.673014) (xy 393.397283 -279.624115) (xy 393.420626 -279.578303) (xy 393.450847 -279.536707)
			(xy 393.487203 -279.500351) (xy 393.528799 -279.47013) (xy 393.574611 -279.446787) (xy 393.62351 -279.430899)
			(xy 393.674292 -279.422856) (xy 393.725708 -279.422856) (xy 393.77649 -279.430899) (xy 393.825389 -279.446787)
			(xy 393.871201 -279.47013) (xy 393.912797 -279.500351) (xy 393.949153 -279.536707) (xy 393.979374 -279.578303)
			(xy 394.002717 -279.624115) (xy 394.018605 -279.673014) (xy 394.026648 -279.723796) (xy 394.027152 -279.749504)
			(xy 394.026648 -279.775212) (xy 395.273272 -279.775212) (xy 395.273272 -279.723796) (xy 395.281315 -279.673014)
			(xy 395.297203 -279.624115) (xy 395.320546 -279.578303) (xy 395.350767 -279.536707) (xy 395.387123 -279.500351)
			(xy 395.428719 -279.47013) (xy 395.474531 -279.446787) (xy 395.52343 -279.430899) (xy 395.574212 -279.422856)
			(xy 395.625628 -279.422856) (xy 395.67641 -279.430899) (xy 395.725309 -279.446787) (xy 395.771121 -279.47013)
			(xy 395.812717 -279.500351) (xy 395.849073 -279.536707) (xy 395.879294 -279.578303) (xy 395.902637 -279.624115)
			(xy 395.918525 -279.673014) (xy 395.926568 -279.723796) (xy 395.927072 -279.749504) (xy 395.926568 -279.775212)
			(xy 395.918525 -279.825994) (xy 395.902637 -279.874893) (xy 395.879294 -279.920705) (xy 395.849073 -279.962301)
			(xy 395.812717 -279.998657) (xy 395.771121 -280.028878) (xy 395.725309 -280.052221) (xy 395.67641 -280.068109)
			(xy 395.625628 -280.076152) (xy 395.574212 -280.076152) (xy 395.52343 -280.068109) (xy 395.474531 -280.052221)
			(xy 395.428719 -280.028878) (xy 395.387123 -279.998657) (xy 395.350767 -279.962301) (xy 395.320546 -279.920705)
			(xy 395.297203 -279.874893) (xy 395.281315 -279.825994) (xy 395.273272 -279.775212) (xy 394.026648 -279.775212)
			(xy 394.018605 -279.825994) (xy 394.002717 -279.874893) (xy 393.979374 -279.920705) (xy 393.949153 -279.962301)
			(xy 393.912797 -279.998657) (xy 393.871201 -280.028878) (xy 393.825389 -280.052221) (xy 393.77649 -280.068109)
			(xy 393.725708 -280.076152) (xy 393.674292 -280.076152) (xy 393.62351 -280.068109) (xy 393.574611 -280.052221)
			(xy 393.528799 -280.028878) (xy 393.487203 -279.998657) (xy 393.450847 -279.962301) (xy 393.420626 -279.920705)
			(xy 393.397283 -279.874893) (xy 393.381395 -279.825994) (xy 393.373352 -279.775212) (xy 380.378667 -279.775212)
			(xy 380.388901 -279.79762) (xy 380.404256 -279.849915) (xy 380.412012 -279.903863) (xy 380.412498 -279.931114)
			(xy 380.411971 -279.960497) (xy 380.402938 -280.018564) (xy 380.385103 -280.074559) (xy 380.358889 -280.127154)
			(xy 380.324916 -280.175105) (xy 380.283989 -280.217276) (xy 380.274469 -280.224738) (xy 387.219202 -280.224738)
			(xy 387.223162 -280.175684) (xy 387.234939 -280.1279) (xy 387.25423 -280.082624) (xy 387.280533 -280.041028)
			(xy 387.313168 -280.004191) (xy 387.351289 -279.973066) (xy 387.39391 -279.948459) (xy 387.439926 -279.931007)
			(xy 387.488145 -279.921163) (xy 387.53732 -279.919182) (xy 387.586175 -279.925114) (xy 387.633446 -279.938806)
			(xy 387.677908 -279.959904) (xy 387.718411 -279.98786) (xy 387.753904 -280.021952) (xy 387.783469 -280.061296)
			(xy 387.80634 -280.104873) (xy 387.821924 -280.151554) (xy 387.829819 -280.200131) (xy 387.830314 -280.224738)
			(xy 389.119122 -280.224738) (xy 389.123082 -280.175684) (xy 389.134859 -280.1279) (xy 389.15415 -280.082624)
			(xy 389.180453 -280.041028) (xy 389.213088 -280.004191) (xy 389.251209 -279.973066) (xy 389.29383 -279.948459)
			(xy 389.339846 -279.931007) (xy 389.388065 -279.921163) (xy 389.43724 -279.919182) (xy 389.486095 -279.925114)
			(xy 389.533366 -279.938806) (xy 389.577828 -279.959904) (xy 389.618331 -279.98786) (xy 389.653824 -280.021952)
			(xy 389.683389 -280.061296) (xy 389.70626 -280.104873) (xy 389.721844 -280.151554) (xy 389.729739 -280.200131)
			(xy 389.730234 -280.224738) (xy 391.019042 -280.224738) (xy 391.023002 -280.175684) (xy 391.034779 -280.1279)
			(xy 391.05407 -280.082624) (xy 391.080373 -280.041028) (xy 391.113008 -280.004191) (xy 391.151129 -279.973066)
			(xy 391.19375 -279.948459) (xy 391.239766 -279.931007) (xy 391.287985 -279.921163) (xy 391.33716 -279.919182)
			(xy 391.386015 -279.925114) (xy 391.433286 -279.938806) (xy 391.477748 -279.959904) (xy 391.518251 -279.98786)
			(xy 391.553744 -280.021952) (xy 391.583309 -280.061296) (xy 391.60618 -280.104873) (xy 391.621764 -280.151554)
			(xy 391.629659 -280.200131) (xy 391.630154 -280.224738) (xy 391.629659 -280.249345) (xy 391.621764 -280.297922)
			(xy 391.60618 -280.344603) (xy 391.583309 -280.38818) (xy 391.553744 -280.427524) (xy 391.518251 -280.461616)
			(xy 391.477748 -280.489572) (xy 391.433286 -280.51067) (xy 391.386015 -280.524362) (xy 391.33716 -280.530294)
			(xy 391.287985 -280.528313) (xy 391.239766 -280.518469) (xy 391.19375 -280.501017) (xy 391.151129 -280.47641)
			(xy 391.113008 -280.445285) (xy 391.080373 -280.408448) (xy 391.05407 -280.366852) (xy 391.034779 -280.321576)
			(xy 391.023002 -280.273792) (xy 391.019042 -280.224738) (xy 389.730234 -280.224738) (xy 389.729739 -280.249345)
			(xy 389.721844 -280.297922) (xy 389.70626 -280.344603) (xy 389.683389 -280.38818) (xy 389.653824 -280.427524)
			(xy 389.618331 -280.461616) (xy 389.577828 -280.489572) (xy 389.533366 -280.51067) (xy 389.486095 -280.524362)
			(xy 389.43724 -280.530294) (xy 389.388065 -280.528313) (xy 389.339846 -280.518469) (xy 389.29383 -280.501017)
			(xy 389.251209 -280.47641) (xy 389.213088 -280.445285) (xy 389.180453 -280.408448) (xy 389.15415 -280.366852)
			(xy 389.134859 -280.321576) (xy 389.123082 -280.273792) (xy 389.119122 -280.224738) (xy 387.830314 -280.224738)
			(xy 387.829819 -280.249345) (xy 387.821924 -280.297922) (xy 387.80634 -280.344603) (xy 387.783469 -280.38818)
			(xy 387.753904 -280.427524) (xy 387.718411 -280.461616) (xy 387.677908 -280.489572) (xy 387.633446 -280.51067)
			(xy 387.586175 -280.524362) (xy 387.53732 -280.530294) (xy 387.488145 -280.528313) (xy 387.439926 -280.518469)
			(xy 387.39391 -280.501017) (xy 387.351289 -280.47641) (xy 387.313168 -280.445285) (xy 387.280533 -280.408448)
			(xy 387.25423 -280.366852) (xy 387.234939 -280.321576) (xy 387.223162 -280.273792) (xy 387.219202 -280.224738)
			(xy 380.274469 -280.224738) (xy 380.26086 -280.235406) (xy 380.251462 -280.242772) (xy 380.241048 -280.263346)
			(xy 380.239524 -280.367232) (xy 380.24943 -280.388314) (xy 380.258574 -280.39568) (xy 380.280389 -280.413924)
			(xy 380.318933 -280.455734) (xy 380.350844 -280.502801) (xy 380.375417 -280.554084) (xy 380.392107 -280.608445)
			(xy 380.400545 -280.664681) (xy 380.401068 -280.693114) (xy 381.034542 -280.693114) (xy 381.038613 -280.637492)
			(xy 381.050739 -280.583055) (xy 381.070662 -280.530964) (xy 381.097958 -280.482329) (xy 381.132044 -280.438186)
			(xy 381.172193 -280.399477) (xy 381.217551 -280.367026) (xy 381.267151 -280.341525) (xy 381.319935 -280.323518)
			(xy 381.374778 -280.313388) (xy 381.430512 -280.311351) (xy 381.485949 -280.317451) (xy 381.539906 -280.331557)
			(xy 381.591235 -280.353369) (xy 381.638841 -280.382423) (xy 381.681709 -280.418098) (xy 381.718926 -280.459635)
			(xy 381.749699 -280.506148) (xy 381.773371 -280.556645) (xy 381.789439 -280.610052) (xy 381.797559 -280.665228)
			(xy 381.798068 -280.693114) (xy 381.797559 -280.721) (xy 381.796908 -280.725426) (xy 393.373352 -280.725426)
			(xy 393.373352 -280.67401) (xy 393.381395 -280.623228) (xy 393.397283 -280.574329) (xy 393.420626 -280.528517)
			(xy 393.450847 -280.486921) (xy 393.487203 -280.450565) (xy 393.528799 -280.420344) (xy 393.574611 -280.397001)
			(xy 393.62351 -280.381113) (xy 393.674292 -280.37307) (xy 393.725708 -280.37307) (xy 393.77649 -280.381113)
			(xy 393.825389 -280.397001) (xy 393.871201 -280.420344) (xy 393.912797 -280.450565) (xy 393.949153 -280.486921)
			(xy 393.979374 -280.528517) (xy 394.002717 -280.574329) (xy 394.018605 -280.623228) (xy 394.026648 -280.67401)
			(xy 394.027152 -280.699718) (xy 394.026648 -280.725426) (xy 395.273272 -280.725426) (xy 395.273272 -280.67401)
			(xy 395.281315 -280.623228) (xy 395.297203 -280.574329) (xy 395.320546 -280.528517) (xy 395.350767 -280.486921)
			(xy 395.387123 -280.450565) (xy 395.428719 -280.420344) (xy 395.474531 -280.397001) (xy 395.52343 -280.381113)
			(xy 395.574212 -280.37307) (xy 395.625628 -280.37307) (xy 395.67641 -280.381113) (xy 395.725309 -280.397001)
			(xy 395.771121 -280.420344) (xy 395.812717 -280.450565) (xy 395.849073 -280.486921) (xy 395.879294 -280.528517)
			(xy 395.902637 -280.574329) (xy 395.918525 -280.623228) (xy 395.926568 -280.67401) (xy 395.927072 -280.699718)
			(xy 395.926568 -280.725426) (xy 395.918525 -280.776208) (xy 395.902637 -280.825107) (xy 395.879294 -280.870919)
			(xy 395.849073 -280.912515) (xy 395.812717 -280.948871) (xy 395.771121 -280.979092) (xy 395.725309 -281.002435)
			(xy 395.67641 -281.018323) (xy 395.625628 -281.026366) (xy 395.574212 -281.026366) (xy 395.52343 -281.018323)
			(xy 395.474531 -281.002435) (xy 395.428719 -280.979092) (xy 395.387123 -280.948871) (xy 395.350767 -280.912515)
			(xy 395.320546 -280.870919) (xy 395.297203 -280.825107) (xy 395.281315 -280.776208) (xy 395.273272 -280.725426)
			(xy 394.026648 -280.725426) (xy 394.018605 -280.776208) (xy 394.002717 -280.825107) (xy 393.979374 -280.870919)
			(xy 393.949153 -280.912515) (xy 393.912797 -280.948871) (xy 393.871201 -280.979092) (xy 393.825389 -281.002435)
			(xy 393.77649 -281.018323) (xy 393.725708 -281.026366) (xy 393.674292 -281.026366) (xy 393.62351 -281.018323)
			(xy 393.574611 -281.002435) (xy 393.528799 -280.979092) (xy 393.487203 -280.948871) (xy 393.450847 -280.912515)
			(xy 393.420626 -280.870919) (xy 393.397283 -280.825107) (xy 393.381395 -280.776208) (xy 393.373352 -280.725426)
			(xy 381.796908 -280.725426) (xy 381.789439 -280.776176) (xy 381.773371 -280.829583) (xy 381.749699 -280.88008)
			(xy 381.718926 -280.926593) (xy 381.681709 -280.96813) (xy 381.638841 -281.003805) (xy 381.591235 -281.032859)
			(xy 381.539906 -281.054671) (xy 381.485949 -281.068777) (xy 381.430512 -281.074877) (xy 381.374778 -281.07284)
			(xy 381.319935 -281.06271) (xy 381.267151 -281.044703) (xy 381.217551 -281.019202) (xy 381.172193 -280.986751)
			(xy 381.132044 -280.948042) (xy 381.097958 -280.903899) (xy 381.070662 -280.855264) (xy 381.050739 -280.803173)
			(xy 381.038613 -280.748736) (xy 381.034542 -280.693114) (xy 380.401068 -280.693114) (xy 380.400582 -280.720365)
			(xy 380.392826 -280.774313) (xy 380.377471 -280.826608) (xy 380.354829 -280.876185) (xy 380.325363 -280.922035)
			(xy 380.289672 -280.963226) (xy 380.248481 -280.998917) (xy 380.202631 -281.028383) (xy 380.153054 -281.051025)
			(xy 380.100759 -281.06638) (xy 380.046811 -281.074136) (xy 379.992309 -281.074136) (xy 379.938361 -281.06638)
			(xy 379.886066 -281.051025) (xy 379.836489 -281.028383) (xy 379.790639 -280.998917) (xy 379.749448 -280.963226)
			(xy 379.713757 -280.922035) (xy 379.684291 -280.876185) (xy 379.661649 -280.826608) (xy 379.646294 -280.774313)
			(xy 379.638538 -280.720365) (xy 379.638052 -280.693114) (xy 368.11458 -280.693114) (xy 368.11458 -281.174952)
			(xy 384.369068 -281.174952) (xy 384.373028 -281.125898) (xy 384.384805 -281.078114) (xy 384.404096 -281.032838)
			(xy 384.430399 -280.991242) (xy 384.463034 -280.954405) (xy 384.501155 -280.92328) (xy 384.543776 -280.898673)
			(xy 384.589792 -280.881221) (xy 384.638011 -280.871377) (xy 384.687186 -280.869396) (xy 384.736041 -280.875328)
			(xy 384.783312 -280.88902) (xy 384.827774 -280.910118) (xy 384.868277 -280.938074) (xy 384.90377 -280.972166)
			(xy 384.933335 -281.01151) (xy 384.956206 -281.055087) (xy 384.97179 -281.101768) (xy 384.979685 -281.150345)
			(xy 384.98018 -281.174952) (xy 385.319028 -281.174952) (xy 385.322988 -281.125898) (xy 385.334765 -281.078114)
			(xy 385.354056 -281.032838) (xy 385.380359 -280.991242) (xy 385.412994 -280.954405) (xy 385.451115 -280.92328)
			(xy 385.493736 -280.898673) (xy 385.539752 -280.881221) (xy 385.587971 -280.871377) (xy 385.637146 -280.869396)
			(xy 385.686001 -280.875328) (xy 385.733272 -280.88902) (xy 385.777734 -280.910118) (xy 385.818237 -280.938074)
			(xy 385.85373 -280.972166) (xy 385.883295 -281.01151) (xy 385.906166 -281.055087) (xy 385.92175 -281.101768)
			(xy 385.929645 -281.150345) (xy 385.93014 -281.174952) (xy 385.929645 -281.199559) (xy 385.92175 -281.248136)
			(xy 385.906166 -281.294817) (xy 385.883295 -281.338394) (xy 385.85373 -281.377738) (xy 385.818237 -281.41183)
			(xy 385.777734 -281.439786) (xy 385.733272 -281.460884) (xy 385.686001 -281.474576) (xy 385.637146 -281.480508)
			(xy 385.587971 -281.478527) (xy 385.539752 -281.468683) (xy 385.493736 -281.451231) (xy 385.451115 -281.426624)
			(xy 385.412994 -281.395499) (xy 385.380359 -281.358662) (xy 385.354056 -281.317066) (xy 385.334765 -281.27179)
			(xy 385.322988 -281.224006) (xy 385.319028 -281.174952) (xy 384.98018 -281.174952) (xy 384.979685 -281.199559)
			(xy 384.97179 -281.248136) (xy 384.956206 -281.294817) (xy 384.933335 -281.338394) (xy 384.90377 -281.377738)
			(xy 384.868277 -281.41183) (xy 384.827774 -281.439786) (xy 384.783312 -281.460884) (xy 384.736041 -281.474576)
			(xy 384.687186 -281.480508) (xy 384.638011 -281.478527) (xy 384.589792 -281.468683) (xy 384.543776 -281.451231)
			(xy 384.501155 -281.426624) (xy 384.463034 -281.395499) (xy 384.430399 -281.358662) (xy 384.404096 -281.317066)
			(xy 384.384805 -281.27179) (xy 384.373028 -281.224006) (xy 384.369068 -281.174952) (xy 368.11458 -281.174952)
			(xy 368.11458 -281.829256) (xy 374.111518 -281.829256) (xy 374.115589 -281.773634) (xy 374.127715 -281.719197)
			(xy 374.147638 -281.667106) (xy 374.174934 -281.618471) (xy 374.20902 -281.574328) (xy 374.249169 -281.535619)
			(xy 374.294527 -281.503168) (xy 374.344127 -281.477667) (xy 374.396911 -281.45966) (xy 374.451754 -281.44953)
			(xy 374.507488 -281.447493) (xy 374.562925 -281.453593) (xy 374.616882 -281.467699) (xy 374.668211 -281.489511)
			(xy 374.715817 -281.518565) (xy 374.758685 -281.55424) (xy 374.795902 -281.595777) (xy 374.826675 -281.64229)
			(xy 374.850347 -281.692787) (xy 374.866415 -281.746194) (xy 374.874535 -281.80137) (xy 374.875044 -281.829256)
			(xy 375.596656 -281.829256) (xy 375.600727 -281.773634) (xy 375.612853 -281.719197) (xy 375.632776 -281.667106)
			(xy 375.660072 -281.618471) (xy 375.694158 -281.574328) (xy 375.734307 -281.535619) (xy 375.779665 -281.503168)
			(xy 375.829265 -281.477667) (xy 375.882049 -281.45966) (xy 375.936892 -281.44953) (xy 375.992626 -281.447493)
			(xy 376.048063 -281.453593) (xy 376.10202 -281.467699) (xy 376.153349 -281.489511) (xy 376.200955 -281.518565)
			(xy 376.243823 -281.55424) (xy 376.28104 -281.595777) (xy 376.311813 -281.64229) (xy 376.335485 -281.692787)
			(xy 376.351553 -281.746194) (xy 376.359673 -281.80137) (xy 376.360182 -281.829256) (xy 376.359673 -281.857142)
			(xy 376.351553 -281.912318) (xy 376.335485 -281.965725) (xy 376.311813 -282.016222) (xy 376.28104 -282.062735)
			(xy 376.243823 -282.104272) (xy 376.219021 -282.124912) (xy 386.269242 -282.124912) (xy 386.273202 -282.075858)
			(xy 386.284979 -282.028074) (xy 386.30427 -281.982798) (xy 386.330573 -281.941202) (xy 386.363208 -281.904365)
			(xy 386.401329 -281.87324) (xy 386.44395 -281.848633) (xy 386.489966 -281.831181) (xy 386.538185 -281.821337)
			(xy 386.58736 -281.819356) (xy 386.636215 -281.825288) (xy 386.683486 -281.83898) (xy 386.727948 -281.860078)
			(xy 386.768451 -281.888034) (xy 386.803944 -281.922126) (xy 386.833509 -281.96147) (xy 386.85638 -282.005047)
			(xy 386.871964 -282.051728) (xy 386.879859 -282.100305) (xy 386.880354 -282.124912) (xy 387.219202 -282.124912)
			(xy 387.223162 -282.075858) (xy 387.234939 -282.028074) (xy 387.25423 -281.982798) (xy 387.280533 -281.941202)
			(xy 387.313168 -281.904365) (xy 387.351289 -281.87324) (xy 387.39391 -281.848633) (xy 387.439926 -281.831181)
			(xy 387.488145 -281.821337) (xy 387.53732 -281.819356) (xy 387.586175 -281.825288) (xy 387.633446 -281.83898)
			(xy 387.677908 -281.860078) (xy 387.718411 -281.888034) (xy 387.753904 -281.922126) (xy 387.783469 -281.96147)
			(xy 387.80634 -282.005047) (xy 387.821924 -282.051728) (xy 387.829819 -282.100305) (xy 387.830314 -282.124912)
			(xy 389.119122 -282.124912) (xy 389.123082 -282.075858) (xy 389.134859 -282.028074) (xy 389.15415 -281.982798)
			(xy 389.180453 -281.941202) (xy 389.213088 -281.904365) (xy 389.251209 -281.87324) (xy 389.29383 -281.848633)
			(xy 389.339846 -281.831181) (xy 389.388065 -281.821337) (xy 389.43724 -281.819356) (xy 389.486095 -281.825288)
			(xy 389.533366 -281.83898) (xy 389.577828 -281.860078) (xy 389.618331 -281.888034) (xy 389.653824 -281.922126)
			(xy 389.683389 -281.96147) (xy 389.70626 -282.005047) (xy 389.721844 -282.051728) (xy 389.729739 -282.100305)
			(xy 389.730234 -282.124912) (xy 390.069082 -282.124912) (xy 390.073042 -282.075858) (xy 390.084819 -282.028074)
			(xy 390.10411 -281.982798) (xy 390.130413 -281.941202) (xy 390.163048 -281.904365) (xy 390.201169 -281.87324)
			(xy 390.24379 -281.848633) (xy 390.289806 -281.831181) (xy 390.338025 -281.821337) (xy 390.3872 -281.819356)
			(xy 390.436055 -281.825288) (xy 390.483326 -281.83898) (xy 390.527788 -281.860078) (xy 390.568291 -281.888034)
			(xy 390.603784 -281.922126) (xy 390.633349 -281.96147) (xy 390.65622 -282.005047) (xy 390.671804 -282.051728)
			(xy 390.679699 -282.100305) (xy 390.680194 -282.124912) (xy 390.679699 -282.149519) (xy 390.671804 -282.198096)
			(xy 390.65622 -282.244777) (xy 390.633349 -282.288354) (xy 390.603784 -282.327698) (xy 390.568291 -282.36179)
			(xy 390.527788 -282.389746) (xy 390.483326 -282.410844) (xy 390.436055 -282.424536) (xy 390.3872 -282.430468)
			(xy 390.338025 -282.428487) (xy 390.289806 -282.418643) (xy 390.24379 -282.401191) (xy 390.201169 -282.376584)
			(xy 390.163048 -282.345459) (xy 390.130413 -282.308622) (xy 390.10411 -282.267026) (xy 390.084819 -282.22175)
			(xy 390.073042 -282.173966) (xy 390.069082 -282.124912) (xy 389.730234 -282.124912) (xy 389.729739 -282.149519)
			(xy 389.721844 -282.198096) (xy 389.70626 -282.244777) (xy 389.683389 -282.288354) (xy 389.653824 -282.327698)
			(xy 389.618331 -282.36179) (xy 389.577828 -282.389746) (xy 389.533366 -282.410844) (xy 389.486095 -282.424536)
			(xy 389.43724 -282.430468) (xy 389.388065 -282.428487) (xy 389.339846 -282.418643) (xy 389.29383 -282.401191)
			(xy 389.251209 -282.376584) (xy 389.213088 -282.345459) (xy 389.180453 -282.308622) (xy 389.15415 -282.267026)
			(xy 389.134859 -282.22175) (xy 389.123082 -282.173966) (xy 389.119122 -282.124912) (xy 387.830314 -282.124912)
			(xy 387.829819 -282.149519) (xy 387.821924 -282.198096) (xy 387.80634 -282.244777) (xy 387.783469 -282.288354)
			(xy 387.753904 -282.327698) (xy 387.718411 -282.36179) (xy 387.677908 -282.389746) (xy 387.633446 -282.410844)
			(xy 387.586175 -282.424536) (xy 387.53732 -282.430468) (xy 387.488145 -282.428487) (xy 387.439926 -282.418643)
			(xy 387.39391 -282.401191) (xy 387.351289 -282.376584) (xy 387.313168 -282.345459) (xy 387.280533 -282.308622)
			(xy 387.25423 -282.267026) (xy 387.234939 -282.22175) (xy 387.223162 -282.173966) (xy 387.219202 -282.124912)
			(xy 386.880354 -282.124912) (xy 386.879859 -282.149519) (xy 386.871964 -282.198096) (xy 386.85638 -282.244777)
			(xy 386.833509 -282.288354) (xy 386.803944 -282.327698) (xy 386.768451 -282.36179) (xy 386.727948 -282.389746)
			(xy 386.683486 -282.410844) (xy 386.636215 -282.424536) (xy 386.58736 -282.430468) (xy 386.538185 -282.428487)
			(xy 386.489966 -282.418643) (xy 386.44395 -282.401191) (xy 386.401329 -282.376584) (xy 386.363208 -282.345459)
			(xy 386.330573 -282.308622) (xy 386.30427 -282.267026) (xy 386.284979 -282.22175) (xy 386.273202 -282.173966)
			(xy 386.269242 -282.124912) (xy 376.219021 -282.124912) (xy 376.200955 -282.139947) (xy 376.153349 -282.169001)
			(xy 376.10202 -282.190813) (xy 376.048063 -282.204919) (xy 375.992626 -282.211019) (xy 375.936892 -282.208982)
			(xy 375.882049 -282.198852) (xy 375.829265 -282.180845) (xy 375.779665 -282.155344) (xy 375.734307 -282.122893)
			(xy 375.694158 -282.084184) (xy 375.660072 -282.040041) (xy 375.632776 -281.991406) (xy 375.612853 -281.939315)
			(xy 375.600727 -281.884878) (xy 375.596656 -281.829256) (xy 374.875044 -281.829256) (xy 374.874535 -281.857142)
			(xy 374.866415 -281.912318) (xy 374.850347 -281.965725) (xy 374.826675 -282.016222) (xy 374.795902 -282.062735)
			(xy 374.758685 -282.104272) (xy 374.715817 -282.139947) (xy 374.668211 -282.169001) (xy 374.616882 -282.190813)
			(xy 374.562925 -282.204919) (xy 374.507488 -282.211019) (xy 374.451754 -282.208982) (xy 374.396911 -282.198852)
			(xy 374.344127 -282.180845) (xy 374.294527 -282.155344) (xy 374.249169 -282.122893) (xy 374.20902 -282.084184)
			(xy 374.174934 -282.040041) (xy 374.147638 -281.991406) (xy 374.127715 -281.939315) (xy 374.115589 -281.884878)
			(xy 374.111518 -281.829256) (xy 368.11458 -281.829256) (xy 368.11458 -284.138116) (xy 373.346978 -284.138116)
			(xy 373.351049 -284.082494) (xy 373.363175 -284.028057) (xy 373.383098 -283.975966) (xy 373.410394 -283.927331)
			(xy 373.44448 -283.883188) (xy 373.484629 -283.844479) (xy 373.529987 -283.812028) (xy 373.579587 -283.786527)
			(xy 373.632371 -283.76852) (xy 373.687214 -283.75839) (xy 373.742948 -283.756353) (xy 373.798385 -283.762453)
			(xy 373.852342 -283.776559) (xy 373.903671 -283.798371) (xy 373.951277 -283.827425) (xy 373.994145 -283.8631)
			(xy 374.021396 -283.893514) (xy 379.638052 -283.893514) (xy 379.638619 -283.864133) (xy 379.647646 -283.806068)
			(xy 379.665474 -283.750075) (xy 379.691681 -283.69748) (xy 379.725646 -283.649528) (xy 379.766565 -283.607354)
			(xy 379.78969 -283.589222) (xy 379.799088 -283.581856) (xy 379.809502 -283.561282) (xy 379.811026 -283.457396)
			(xy 379.80112 -283.436314) (xy 379.791976 -283.428948) (xy 379.770116 -283.410756) (xy 379.731578 -283.368934)
			(xy 379.699673 -283.321855) (xy 379.675108 -283.270563) (xy 379.658427 -283.216193) (xy 379.65 -283.15995)
			(xy 379.649482 -283.131514) (xy 379.649968 -283.104263) (xy 379.657724 -283.050315) (xy 379.673079 -282.99802)
			(xy 379.695721 -282.948443) (xy 379.725187 -282.902593) (xy 379.760878 -282.861402) (xy 379.802069 -282.825711)
			(xy 379.847919 -282.796245) (xy 379.897496 -282.773603) (xy 379.949791 -282.758248) (xy 380.003739 -282.750492)
			(xy 380.058241 -282.750492) (xy 380.112189 -282.758248) (xy 380.164484 -282.773603) (xy 380.214061 -282.796245)
			(xy 380.259911 -282.825711) (xy 380.301102 -282.861402) (xy 380.336793 -282.902593) (xy 380.366259 -282.948443)
			(xy 380.388901 -282.99802) (xy 380.404256 -283.050315) (xy 380.407787 -283.074872) (xy 384.369068 -283.074872)
			(xy 384.373028 -283.025818) (xy 384.384805 -282.978034) (xy 384.404096 -282.932758) (xy 384.430399 -282.891162)
			(xy 384.463034 -282.854325) (xy 384.501155 -282.8232) (xy 384.543776 -282.798593) (xy 384.589792 -282.781141)
			(xy 384.638011 -282.771297) (xy 384.687186 -282.769316) (xy 384.736041 -282.775248) (xy 384.783312 -282.78894)
			(xy 384.827774 -282.810038) (xy 384.868277 -282.837994) (xy 384.90377 -282.872086) (xy 384.933335 -282.91143)
			(xy 384.956206 -282.955007) (xy 384.97179 -283.001688) (xy 384.979685 -283.050265) (xy 384.98018 -283.074872)
			(xy 385.319028 -283.074872) (xy 385.322988 -283.025818) (xy 385.334765 -282.978034) (xy 385.354056 -282.932758)
			(xy 385.380359 -282.891162) (xy 385.412994 -282.854325) (xy 385.451115 -282.8232) (xy 385.493736 -282.798593)
			(xy 385.539752 -282.781141) (xy 385.587971 -282.771297) (xy 385.637146 -282.769316) (xy 385.686001 -282.775248)
			(xy 385.733272 -282.78894) (xy 385.777734 -282.810038) (xy 385.818237 -282.837994) (xy 385.85373 -282.872086)
			(xy 385.883295 -282.91143) (xy 385.906166 -282.955007) (xy 385.92175 -283.001688) (xy 385.929645 -283.050265)
			(xy 385.93014 -283.074872) (xy 391.019042 -283.074872) (xy 391.023002 -283.025818) (xy 391.034779 -282.978034)
			(xy 391.05407 -282.932758) (xy 391.080373 -282.891162) (xy 391.113008 -282.854325) (xy 391.151129 -282.8232)
			(xy 391.19375 -282.798593) (xy 391.239766 -282.781141) (xy 391.287985 -282.771297) (xy 391.33716 -282.769316)
			(xy 391.386015 -282.775248) (xy 391.433286 -282.78894) (xy 391.477748 -282.810038) (xy 391.518251 -282.837994)
			(xy 391.553744 -282.872086) (xy 391.583309 -282.91143) (xy 391.60618 -282.955007) (xy 391.621764 -283.001688)
			(xy 391.629659 -283.050265) (xy 391.630154 -283.074872) (xy 391.969002 -283.074872) (xy 391.972962 -283.025818)
			(xy 391.984739 -282.978034) (xy 392.00403 -282.932758) (xy 392.030333 -282.891162) (xy 392.062968 -282.854325)
			(xy 392.101089 -282.8232) (xy 392.14371 -282.798593) (xy 392.189726 -282.781141) (xy 392.237945 -282.771297)
			(xy 392.28712 -282.769316) (xy 392.335975 -282.775248) (xy 392.383246 -282.78894) (xy 392.427708 -282.810038)
			(xy 392.468211 -282.837994) (xy 392.503704 -282.872086) (xy 392.533269 -282.91143) (xy 392.55614 -282.955007)
			(xy 392.571724 -283.001688) (xy 392.579619 -283.050265) (xy 392.580114 -283.074872) (xy 394.819136 -283.074872)
			(xy 394.823096 -283.025818) (xy 394.834873 -282.978034) (xy 394.854164 -282.932758) (xy 394.880467 -282.891162)
			(xy 394.913102 -282.854325) (xy 394.951223 -282.8232) (xy 394.993844 -282.798593) (xy 395.03986 -282.781141)
			(xy 395.088079 -282.771297) (xy 395.137254 -282.769316) (xy 395.186109 -282.775248) (xy 395.23338 -282.78894)
			(xy 395.277842 -282.810038) (xy 395.318345 -282.837994) (xy 395.353838 -282.872086) (xy 395.383403 -282.91143)
			(xy 395.406274 -282.955007) (xy 395.421858 -283.001688) (xy 395.429753 -283.050265) (xy 395.430248 -283.074872)
			(xy 395.769096 -283.074872) (xy 395.773056 -283.025818) (xy 395.784833 -282.978034) (xy 395.804124 -282.932758)
			(xy 395.830427 -282.891162) (xy 395.863062 -282.854325) (xy 395.901183 -282.8232) (xy 395.943804 -282.798593)
			(xy 395.98982 -282.781141) (xy 396.038039 -282.771297) (xy 396.087214 -282.769316) (xy 396.136069 -282.775248)
			(xy 396.18334 -282.78894) (xy 396.227802 -282.810038) (xy 396.268305 -282.837994) (xy 396.303798 -282.872086)
			(xy 396.333363 -282.91143) (xy 396.356234 -282.955007) (xy 396.371818 -283.001688) (xy 396.379713 -283.050265)
			(xy 396.380208 -283.074872) (xy 396.379713 -283.099479) (xy 396.371818 -283.148056) (xy 396.356234 -283.194737)
			(xy 396.333363 -283.238314) (xy 396.303798 -283.277658) (xy 396.268305 -283.31175) (xy 396.227802 -283.339706)
			(xy 396.18334 -283.360804) (xy 396.136069 -283.374496) (xy 396.087214 -283.380428) (xy 396.038039 -283.378447)
			(xy 395.98982 -283.368603) (xy 395.943804 -283.351151) (xy 395.901183 -283.326544) (xy 395.863062 -283.295419)
			(xy 395.830427 -283.258582) (xy 395.804124 -283.216986) (xy 395.784833 -283.17171) (xy 395.773056 -283.123926)
			(xy 395.769096 -283.074872) (xy 395.430248 -283.074872) (xy 395.429753 -283.099479) (xy 395.421858 -283.148056)
			(xy 395.406274 -283.194737) (xy 395.383403 -283.238314) (xy 395.353838 -283.277658) (xy 395.318345 -283.31175)
			(xy 395.277842 -283.339706) (xy 395.23338 -283.360804) (xy 395.186109 -283.374496) (xy 395.137254 -283.380428)
			(xy 395.088079 -283.378447) (xy 395.03986 -283.368603) (xy 394.993844 -283.351151) (xy 394.951223 -283.326544)
			(xy 394.913102 -283.295419) (xy 394.880467 -283.258582) (xy 394.854164 -283.216986) (xy 394.834873 -283.17171)
			(xy 394.823096 -283.123926) (xy 394.819136 -283.074872) (xy 392.580114 -283.074872) (xy 392.579619 -283.099479)
			(xy 392.571724 -283.148056) (xy 392.55614 -283.194737) (xy 392.533269 -283.238314) (xy 392.503704 -283.277658)
			(xy 392.468211 -283.31175) (xy 392.427708 -283.339706) (xy 392.383246 -283.360804) (xy 392.335975 -283.374496)
			(xy 392.28712 -283.380428) (xy 392.237945 -283.378447) (xy 392.189726 -283.368603) (xy 392.14371 -283.351151)
			(xy 392.101089 -283.326544) (xy 392.062968 -283.295419) (xy 392.030333 -283.258582) (xy 392.00403 -283.216986)
			(xy 391.984739 -283.17171) (xy 391.972962 -283.123926) (xy 391.969002 -283.074872) (xy 391.630154 -283.074872)
			(xy 391.629659 -283.099479) (xy 391.621764 -283.148056) (xy 391.60618 -283.194737) (xy 391.583309 -283.238314)
			(xy 391.553744 -283.277658) (xy 391.518251 -283.31175) (xy 391.477748 -283.339706) (xy 391.433286 -283.360804)
			(xy 391.386015 -283.374496) (xy 391.33716 -283.380428) (xy 391.287985 -283.378447) (xy 391.239766 -283.368603)
			(xy 391.19375 -283.351151) (xy 391.151129 -283.326544) (xy 391.113008 -283.295419) (xy 391.080373 -283.258582)
			(xy 391.05407 -283.216986) (xy 391.034779 -283.17171) (xy 391.023002 -283.123926) (xy 391.019042 -283.074872)
			(xy 385.93014 -283.074872) (xy 385.929645 -283.099479) (xy 385.92175 -283.148056) (xy 385.906166 -283.194737)
			(xy 385.883295 -283.238314) (xy 385.85373 -283.277658) (xy 385.818237 -283.31175) (xy 385.777734 -283.339706)
			(xy 385.733272 -283.360804) (xy 385.686001 -283.374496) (xy 385.637146 -283.380428) (xy 385.587971 -283.378447)
			(xy 385.539752 -283.368603) (xy 385.493736 -283.351151) (xy 385.451115 -283.326544) (xy 385.412994 -283.295419)
			(xy 385.380359 -283.258582) (xy 385.354056 -283.216986) (xy 385.334765 -283.17171) (xy 385.322988 -283.123926)
			(xy 385.319028 -283.074872) (xy 384.98018 -283.074872) (xy 384.979685 -283.099479) (xy 384.97179 -283.148056)
			(xy 384.956206 -283.194737) (xy 384.933335 -283.238314) (xy 384.90377 -283.277658) (xy 384.868277 -283.31175)
			(xy 384.827774 -283.339706) (xy 384.783312 -283.360804) (xy 384.736041 -283.374496) (xy 384.687186 -283.380428)
			(xy 384.638011 -283.378447) (xy 384.589792 -283.368603) (xy 384.543776 -283.351151) (xy 384.501155 -283.326544)
			(xy 384.463034 -283.295419) (xy 384.430399 -283.258582) (xy 384.404096 -283.216986) (xy 384.384805 -283.17171)
			(xy 384.373028 -283.123926) (xy 384.369068 -283.074872) (xy 380.407787 -283.074872) (xy 380.412012 -283.104263)
			(xy 380.412498 -283.131514) (xy 380.411971 -283.160897) (xy 380.402938 -283.218964) (xy 380.385103 -283.274959)
			(xy 380.358889 -283.327554) (xy 380.324916 -283.375505) (xy 380.283989 -283.417676) (xy 380.26086 -283.435806)
			(xy 380.251462 -283.443172) (xy 380.241048 -283.463746) (xy 380.239524 -283.567632) (xy 380.24943 -283.588714)
			(xy 380.258574 -283.59608) (xy 380.280389 -283.614324) (xy 380.318933 -283.656134) (xy 380.350844 -283.703201)
			(xy 380.375417 -283.754484) (xy 380.392107 -283.808845) (xy 380.400545 -283.865081) (xy 380.401068 -283.893514)
			(xy 381.034542 -283.893514) (xy 381.038613 -283.837892) (xy 381.050739 -283.783455) (xy 381.070662 -283.731364)
			(xy 381.097958 -283.682729) (xy 381.132044 -283.638586) (xy 381.172193 -283.599877) (xy 381.217551 -283.567426)
			(xy 381.267151 -283.541925) (xy 381.319935 -283.523918) (xy 381.374778 -283.513788) (xy 381.430512 -283.511751)
			(xy 381.485949 -283.517851) (xy 381.539906 -283.531957) (xy 381.591235 -283.553769) (xy 381.638841 -283.582823)
			(xy 381.681709 -283.618498) (xy 381.718926 -283.660035) (xy 381.749699 -283.706548) (xy 381.773371 -283.757045)
			(xy 381.789439 -283.810452) (xy 381.797559 -283.865628) (xy 381.798068 -283.893514) (xy 381.797559 -283.9214)
			(xy 381.789439 -283.976576) (xy 381.774921 -284.024832) (xy 386.269242 -284.024832) (xy 386.273202 -283.975778)
			(xy 386.284979 -283.927994) (xy 386.30427 -283.882718) (xy 386.330573 -283.841122) (xy 386.363208 -283.804285)
			(xy 386.401329 -283.77316) (xy 386.44395 -283.748553) (xy 386.489966 -283.731101) (xy 386.538185 -283.721257)
			(xy 386.58736 -283.719276) (xy 386.636215 -283.725208) (xy 386.683486 -283.7389) (xy 386.727948 -283.759998)
			(xy 386.768451 -283.787954) (xy 386.803944 -283.822046) (xy 386.833509 -283.86139) (xy 386.85638 -283.904967)
			(xy 386.871964 -283.951648) (xy 386.879859 -284.000225) (xy 386.880354 -284.024832) (xy 387.219202 -284.024832)
			(xy 387.223162 -283.975778) (xy 387.234939 -283.927994) (xy 387.25423 -283.882718) (xy 387.280533 -283.841122)
			(xy 387.313168 -283.804285) (xy 387.351289 -283.77316) (xy 387.39391 -283.748553) (xy 387.439926 -283.731101)
			(xy 387.488145 -283.721257) (xy 387.53732 -283.719276) (xy 387.586175 -283.725208) (xy 387.633446 -283.7389)
			(xy 387.677908 -283.759998) (xy 387.718411 -283.787954) (xy 387.753904 -283.822046) (xy 387.783469 -283.86139)
			(xy 387.80634 -283.904967) (xy 387.821924 -283.951648) (xy 387.829819 -284.000225) (xy 387.830314 -284.024832)
			(xy 389.119122 -284.024832) (xy 389.123082 -283.975778) (xy 389.134859 -283.927994) (xy 389.15415 -283.882718)
			(xy 389.180453 -283.841122) (xy 389.213088 -283.804285) (xy 389.251209 -283.77316) (xy 389.29383 -283.748553)
			(xy 389.339846 -283.731101) (xy 389.388065 -283.721257) (xy 389.43724 -283.719276) (xy 389.486095 -283.725208)
			(xy 389.533366 -283.7389) (xy 389.577828 -283.759998) (xy 389.618331 -283.787954) (xy 389.653824 -283.822046)
			(xy 389.683389 -283.86139) (xy 389.70626 -283.904967) (xy 389.721844 -283.951648) (xy 389.729739 -284.000225)
			(xy 389.730234 -284.024832) (xy 390.069082 -284.024832) (xy 390.073042 -283.975778) (xy 390.084819 -283.927994)
			(xy 390.10411 -283.882718) (xy 390.130413 -283.841122) (xy 390.163048 -283.804285) (xy 390.201169 -283.77316)
			(xy 390.24379 -283.748553) (xy 390.289806 -283.731101) (xy 390.338025 -283.721257) (xy 390.3872 -283.719276)
			(xy 390.436055 -283.725208) (xy 390.483326 -283.7389) (xy 390.527788 -283.759998) (xy 390.568291 -283.787954)
			(xy 390.603784 -283.822046) (xy 390.633349 -283.86139) (xy 390.65622 -283.904967) (xy 390.671804 -283.951648)
			(xy 390.679699 -284.000225) (xy 390.680194 -284.024832) (xy 390.679699 -284.049439) (xy 390.671804 -284.098016)
			(xy 390.65622 -284.144697) (xy 390.633349 -284.188274) (xy 390.603784 -284.227618) (xy 390.568291 -284.26171)
			(xy 390.527788 -284.289666) (xy 390.483326 -284.310764) (xy 390.436055 -284.324456) (xy 390.3872 -284.330388)
			(xy 390.338025 -284.328407) (xy 390.289806 -284.318563) (xy 390.24379 -284.301111) (xy 390.201169 -284.276504)
			(xy 390.163048 -284.245379) (xy 390.130413 -284.208542) (xy 390.10411 -284.166946) (xy 390.084819 -284.12167)
			(xy 390.073042 -284.073886) (xy 390.069082 -284.024832) (xy 389.730234 -284.024832) (xy 389.729739 -284.049439)
			(xy 389.721844 -284.098016) (xy 389.70626 -284.144697) (xy 389.683389 -284.188274) (xy 389.653824 -284.227618)
			(xy 389.618331 -284.26171) (xy 389.577828 -284.289666) (xy 389.533366 -284.310764) (xy 389.486095 -284.324456)
			(xy 389.43724 -284.330388) (xy 389.388065 -284.328407) (xy 389.339846 -284.318563) (xy 389.29383 -284.301111)
			(xy 389.251209 -284.276504) (xy 389.213088 -284.245379) (xy 389.180453 -284.208542) (xy 389.15415 -284.166946)
			(xy 389.134859 -284.12167) (xy 389.123082 -284.073886) (xy 389.119122 -284.024832) (xy 387.830314 -284.024832)
			(xy 387.829819 -284.049439) (xy 387.821924 -284.098016) (xy 387.80634 -284.144697) (xy 387.783469 -284.188274)
			(xy 387.753904 -284.227618) (xy 387.718411 -284.26171) (xy 387.677908 -284.289666) (xy 387.633446 -284.310764)
			(xy 387.586175 -284.324456) (xy 387.53732 -284.330388) (xy 387.488145 -284.328407) (xy 387.439926 -284.318563)
			(xy 387.39391 -284.301111) (xy 387.351289 -284.276504) (xy 387.313168 -284.245379) (xy 387.280533 -284.208542)
			(xy 387.25423 -284.166946) (xy 387.234939 -284.12167) (xy 387.223162 -284.073886) (xy 387.219202 -284.024832)
			(xy 386.880354 -284.024832) (xy 386.879859 -284.049439) (xy 386.871964 -284.098016) (xy 386.85638 -284.144697)
			(xy 386.833509 -284.188274) (xy 386.803944 -284.227618) (xy 386.768451 -284.26171) (xy 386.727948 -284.289666)
			(xy 386.683486 -284.310764) (xy 386.636215 -284.324456) (xy 386.58736 -284.330388) (xy 386.538185 -284.328407)
			(xy 386.489966 -284.318563) (xy 386.44395 -284.301111) (xy 386.401329 -284.276504) (xy 386.363208 -284.245379)
			(xy 386.330573 -284.208542) (xy 386.30427 -284.166946) (xy 386.284979 -284.12167) (xy 386.273202 -284.073886)
			(xy 386.269242 -284.024832) (xy 381.774921 -284.024832) (xy 381.773371 -284.029983) (xy 381.749699 -284.08048)
			(xy 381.718926 -284.126993) (xy 381.681709 -284.16853) (xy 381.638841 -284.204205) (xy 381.591235 -284.233259)
			(xy 381.539906 -284.255071) (xy 381.485949 -284.269177) (xy 381.430512 -284.275277) (xy 381.374778 -284.27324)
			(xy 381.319935 -284.26311) (xy 381.267151 -284.245103) (xy 381.217551 -284.219602) (xy 381.172193 -284.187151)
			(xy 381.132044 -284.148442) (xy 381.097958 -284.104299) (xy 381.070662 -284.055664) (xy 381.050739 -284.003573)
			(xy 381.038613 -283.949136) (xy 381.034542 -283.893514) (xy 380.401068 -283.893514) (xy 380.400582 -283.920765)
			(xy 380.392826 -283.974713) (xy 380.377471 -284.027008) (xy 380.354829 -284.076585) (xy 380.325363 -284.122435)
			(xy 380.289672 -284.163626) (xy 380.248481 -284.199317) (xy 380.202631 -284.228783) (xy 380.153054 -284.251425)
			(xy 380.100759 -284.26678) (xy 380.046811 -284.274536) (xy 379.992309 -284.274536) (xy 379.938361 -284.26678)
			(xy 379.886066 -284.251425) (xy 379.836489 -284.228783) (xy 379.790639 -284.199317) (xy 379.749448 -284.163626)
			(xy 379.713757 -284.122435) (xy 379.684291 -284.076585) (xy 379.661649 -284.027008) (xy 379.646294 -283.974713)
			(xy 379.638538 -283.920765) (xy 379.638052 -283.893514) (xy 374.021396 -283.893514) (xy 374.031362 -283.904637)
			(xy 374.062135 -283.95115) (xy 374.085807 -284.001647) (xy 374.101875 -284.055054) (xy 374.109995 -284.11023)
			(xy 374.110504 -284.138116) (xy 374.109995 -284.166002) (xy 374.101875 -284.221178) (xy 374.085807 -284.274585)
			(xy 374.062135 -284.325082) (xy 374.031362 -284.371595) (xy 373.994145 -284.413132) (xy 373.951277 -284.448807)
			(xy 373.903671 -284.477861) (xy 373.852342 -284.499673) (xy 373.798385 -284.513779) (xy 373.742948 -284.519879)
			(xy 373.687214 -284.517842) (xy 373.632371 -284.507712) (xy 373.579587 -284.489705) (xy 373.529987 -284.464204)
			(xy 373.484629 -284.431753) (xy 373.44448 -284.393044) (xy 373.410394 -284.348901) (xy 373.383098 -284.300266)
			(xy 373.363175 -284.248175) (xy 373.351049 -284.193738) (xy 373.346978 -284.138116) (xy 368.11458 -284.138116)
			(xy 368.11458 -285.029656) (xy 374.111518 -285.029656) (xy 374.115589 -284.974034) (xy 374.127715 -284.919597)
			(xy 374.147638 -284.867506) (xy 374.174934 -284.818871) (xy 374.20902 -284.774728) (xy 374.249169 -284.736019)
			(xy 374.294527 -284.703568) (xy 374.344127 -284.678067) (xy 374.396911 -284.66006) (xy 374.451754 -284.64993)
			(xy 374.507488 -284.647893) (xy 374.562925 -284.653993) (xy 374.616882 -284.668099) (xy 374.668211 -284.689911)
			(xy 374.715817 -284.718965) (xy 374.758685 -284.75464) (xy 374.795902 -284.796177) (xy 374.826675 -284.84269)
			(xy 374.850347 -284.893187) (xy 374.866415 -284.946594) (xy 374.874535 -285.00177) (xy 374.875044 -285.029656)
			(xy 375.596656 -285.029656) (xy 375.600727 -284.974034) (xy 375.612853 -284.919597) (xy 375.632776 -284.867506)
			(xy 375.660072 -284.818871) (xy 375.694158 -284.774728) (xy 375.734307 -284.736019) (xy 375.779665 -284.703568)
			(xy 375.829265 -284.678067) (xy 375.882049 -284.66006) (xy 375.936892 -284.64993) (xy 375.992626 -284.647893)
			(xy 376.048063 -284.653993) (xy 376.10202 -284.668099) (xy 376.153349 -284.689911) (xy 376.200955 -284.718965)
			(xy 376.243823 -284.75464) (xy 376.28104 -284.796177) (xy 376.311813 -284.84269) (xy 376.335485 -284.893187)
			(xy 376.351553 -284.946594) (xy 376.355703 -284.974792) (xy 384.369068 -284.974792) (xy 384.373028 -284.925738)
			(xy 384.384805 -284.877954) (xy 384.404096 -284.832678) (xy 384.430399 -284.791082) (xy 384.463034 -284.754245)
			(xy 384.501155 -284.72312) (xy 384.543776 -284.698513) (xy 384.589792 -284.681061) (xy 384.638011 -284.671217)
			(xy 384.687186 -284.669236) (xy 384.736041 -284.675168) (xy 384.783312 -284.68886) (xy 384.827774 -284.709958)
			(xy 384.868277 -284.737914) (xy 384.90377 -284.772006) (xy 384.933335 -284.81135) (xy 384.956206 -284.854927)
			(xy 384.97179 -284.901608) (xy 384.979685 -284.950185) (xy 384.98018 -284.974792) (xy 385.319028 -284.974792)
			(xy 385.322988 -284.925738) (xy 385.334765 -284.877954) (xy 385.354056 -284.832678) (xy 385.380359 -284.791082)
			(xy 385.412994 -284.754245) (xy 385.451115 -284.72312) (xy 385.493736 -284.698513) (xy 385.539752 -284.681061)
			(xy 385.587971 -284.671217) (xy 385.637146 -284.669236) (xy 385.686001 -284.675168) (xy 385.733272 -284.68886)
			(xy 385.777734 -284.709958) (xy 385.818237 -284.737914) (xy 385.85373 -284.772006) (xy 385.883295 -284.81135)
			(xy 385.906166 -284.854927) (xy 385.92175 -284.901608) (xy 385.929645 -284.950185) (xy 385.93014 -284.974792)
			(xy 389.119122 -284.974792) (xy 389.123082 -284.925738) (xy 389.134859 -284.877954) (xy 389.15415 -284.832678)
			(xy 389.180453 -284.791082) (xy 389.213088 -284.754245) (xy 389.251209 -284.72312) (xy 389.29383 -284.698513)
			(xy 389.339846 -284.681061) (xy 389.388065 -284.671217) (xy 389.43724 -284.669236) (xy 389.486095 -284.675168)
			(xy 389.533366 -284.68886) (xy 389.577828 -284.709958) (xy 389.618331 -284.737914) (xy 389.653824 -284.772006)
			(xy 389.683389 -284.81135) (xy 389.70626 -284.854927) (xy 389.721844 -284.901608) (xy 389.729739 -284.950185)
			(xy 389.730234 -284.974792) (xy 389.729739 -284.999399) (xy 389.721844 -285.047976) (xy 389.70626 -285.094657)
			(xy 389.683389 -285.138234) (xy 389.653824 -285.177578) (xy 389.618331 -285.21167) (xy 389.577828 -285.239626)
			(xy 389.533366 -285.260724) (xy 389.486095 -285.274416) (xy 389.43724 -285.280348) (xy 389.388065 -285.278367)
			(xy 389.339846 -285.268523) (xy 389.29383 -285.251071) (xy 389.251209 -285.226464) (xy 389.213088 -285.195339)
			(xy 389.180453 -285.158502) (xy 389.15415 -285.116906) (xy 389.134859 -285.07163) (xy 389.123082 -285.023846)
			(xy 389.119122 -284.974792) (xy 385.93014 -284.974792) (xy 385.929645 -284.999399) (xy 385.92175 -285.047976)
			(xy 385.906166 -285.094657) (xy 385.883295 -285.138234) (xy 385.85373 -285.177578) (xy 385.818237 -285.21167)
			(xy 385.777734 -285.239626) (xy 385.733272 -285.260724) (xy 385.686001 -285.274416) (xy 385.637146 -285.280348)
			(xy 385.587971 -285.278367) (xy 385.539752 -285.268523) (xy 385.493736 -285.251071) (xy 385.451115 -285.226464)
			(xy 385.412994 -285.195339) (xy 385.380359 -285.158502) (xy 385.354056 -285.116906) (xy 385.334765 -285.07163)
			(xy 385.322988 -285.023846) (xy 385.319028 -284.974792) (xy 384.98018 -284.974792) (xy 384.979685 -284.999399)
			(xy 384.97179 -285.047976) (xy 384.956206 -285.094657) (xy 384.933335 -285.138234) (xy 384.90377 -285.177578)
			(xy 384.868277 -285.21167) (xy 384.827774 -285.239626) (xy 384.783312 -285.260724) (xy 384.736041 -285.274416)
			(xy 384.687186 -285.280348) (xy 384.638011 -285.278367) (xy 384.589792 -285.268523) (xy 384.543776 -285.251071)
			(xy 384.501155 -285.226464) (xy 384.463034 -285.195339) (xy 384.430399 -285.158502) (xy 384.404096 -285.116906)
			(xy 384.384805 -285.07163) (xy 384.373028 -285.023846) (xy 384.369068 -284.974792) (xy 376.355703 -284.974792)
			(xy 376.359673 -285.00177) (xy 376.360182 -285.029656) (xy 376.359673 -285.057542) (xy 376.351553 -285.112718)
			(xy 376.335485 -285.166125) (xy 376.311813 -285.216622) (xy 376.28104 -285.263135) (xy 376.243823 -285.304672)
			(xy 376.200955 -285.340347) (xy 376.153349 -285.369401) (xy 376.10202 -285.391213) (xy 376.048063 -285.405319)
			(xy 375.992626 -285.411419) (xy 375.936892 -285.409382) (xy 375.882049 -285.399252) (xy 375.829265 -285.381245)
			(xy 375.779665 -285.355744) (xy 375.734307 -285.323293) (xy 375.694158 -285.284584) (xy 375.660072 -285.240441)
			(xy 375.632776 -285.191806) (xy 375.612853 -285.139715) (xy 375.600727 -285.085278) (xy 375.596656 -285.029656)
			(xy 374.875044 -285.029656) (xy 374.874535 -285.057542) (xy 374.866415 -285.112718) (xy 374.850347 -285.166125)
			(xy 374.826675 -285.216622) (xy 374.795902 -285.263135) (xy 374.758685 -285.304672) (xy 374.715817 -285.340347)
			(xy 374.668211 -285.369401) (xy 374.616882 -285.391213) (xy 374.562925 -285.405319) (xy 374.507488 -285.411419)
			(xy 374.451754 -285.409382) (xy 374.396911 -285.399252) (xy 374.344127 -285.381245) (xy 374.294527 -285.355744)
			(xy 374.249169 -285.323293) (xy 374.20902 -285.284584) (xy 374.174934 -285.240441) (xy 374.147638 -285.191806)
			(xy 374.127715 -285.139715) (xy 374.115589 -285.085278) (xy 374.111518 -285.029656) (xy 368.11458 -285.029656)
			(xy 368.11458 -285.576518) (xy 368.115006 -285.586587) (xy 368.122723 -285.605189) (xy 368.129566 -285.612586)
			(xy 368.441732 -285.924752) (xy 386.269242 -285.924752) (xy 386.273202 -285.875698) (xy 386.284979 -285.827914)
			(xy 386.30427 -285.782638) (xy 386.330573 -285.741042) (xy 386.363208 -285.704205) (xy 386.401329 -285.67308)
			(xy 386.44395 -285.648473) (xy 386.489966 -285.631021) (xy 386.538185 -285.621177) (xy 386.58736 -285.619196)
			(xy 386.636215 -285.625128) (xy 386.683486 -285.63882) (xy 386.727948 -285.659918) (xy 386.768451 -285.687874)
			(xy 386.803944 -285.721966) (xy 386.833509 -285.76131) (xy 386.85638 -285.804887) (xy 386.871964 -285.851568)
			(xy 386.879859 -285.900145) (xy 386.880354 -285.924752) (xy 387.219202 -285.924752) (xy 387.223162 -285.875698)
			(xy 387.234939 -285.827914) (xy 387.25423 -285.782638) (xy 387.280533 -285.741042) (xy 387.313168 -285.704205)
			(xy 387.351289 -285.67308) (xy 387.39391 -285.648473) (xy 387.439926 -285.631021) (xy 387.488145 -285.621177)
			(xy 387.53732 -285.619196) (xy 387.586175 -285.625128) (xy 387.633446 -285.63882) (xy 387.677908 -285.659918)
			(xy 387.718411 -285.687874) (xy 387.753904 -285.721966) (xy 387.783469 -285.76131) (xy 387.80634 -285.804887)
			(xy 387.821924 -285.851568) (xy 387.829819 -285.900145) (xy 387.830314 -285.924752) (xy 387.829819 -285.949359)
			(xy 387.821924 -285.997936) (xy 387.80634 -286.044617) (xy 387.783469 -286.088194) (xy 387.753904 -286.127538)
			(xy 387.718411 -286.16163) (xy 387.677908 -286.189586) (xy 387.633446 -286.210684) (xy 387.586175 -286.224376)
			(xy 387.53732 -286.230308) (xy 387.488145 -286.228327) (xy 387.439926 -286.218483) (xy 387.39391 -286.201031)
			(xy 387.351289 -286.176424) (xy 387.313168 -286.145299) (xy 387.280533 -286.108462) (xy 387.25423 -286.066866)
			(xy 387.234939 -286.02159) (xy 387.223162 -285.973806) (xy 387.219202 -285.924752) (xy 386.880354 -285.924752)
			(xy 386.879859 -285.949359) (xy 386.871964 -285.997936) (xy 386.85638 -286.044617) (xy 386.833509 -286.088194)
			(xy 386.803944 -286.127538) (xy 386.768451 -286.16163) (xy 386.727948 -286.189586) (xy 386.683486 -286.210684)
			(xy 386.636215 -286.224376) (xy 386.58736 -286.230308) (xy 386.538185 -286.228327) (xy 386.489966 -286.218483)
			(xy 386.44395 -286.201031) (xy 386.401329 -286.176424) (xy 386.363208 -286.145299) (xy 386.330573 -286.108462)
			(xy 386.30427 -286.066866) (xy 386.284979 -286.02159) (xy 386.273202 -285.973806) (xy 386.269242 -285.924752)
			(xy 368.441732 -285.924752) (xy 369.544346 -287.027366) (xy 369.551745 -287.034209) (xy 369.570344 -287.041932)
			(xy 369.580414 -287.042352) (xy 379.617478 -287.042352)
		)
		(stroke
			(width 0)
			(type solid)
		)
		(fill yes)
		(layer "In13.Cu")
		(net "GND")
	)
	(gr_poly
		(pts
			(xy 147.44065 -287.045146) (xy 147.443952 -287.026858) (xy 147.449509 -286.998883) (xy 147.467825 -286.94487)
			(xy 147.493979 -286.894186) (xy 147.527388 -286.847961) (xy 147.567307 -286.807227) (xy 147.589748 -286.789622)
			(xy 147.599146 -286.782256) (xy 147.60956 -286.761682) (xy 147.611084 -286.657796) (xy 147.601178 -286.636714)
			(xy 147.592034 -286.629348) (xy 147.570208 -286.611118) (xy 147.531675 -286.569298) (xy 147.49977 -286.522225)
			(xy 147.475198 -286.470942) (xy 147.458503 -286.416582) (xy 147.450053 -286.360347) (xy 147.44954 -286.331914)
			(xy 147.450026 -286.304663) (xy 147.457782 -286.250715) (xy 147.473137 -286.19842) (xy 147.495779 -286.148843)
			(xy 147.525245 -286.102993) (xy 147.560936 -286.061802) (xy 147.602127 -286.026111) (xy 147.647977 -285.996645)
			(xy 147.697554 -285.974003) (xy 147.749849 -285.958648) (xy 147.803797 -285.950892) (xy 147.858299 -285.950892)
			(xy 147.912247 -285.958648) (xy 147.964542 -285.974003) (xy 148.014119 -285.996645) (xy 148.059969 -286.026111)
			(xy 148.10116 -286.061802) (xy 148.136851 -286.102993) (xy 148.166317 -286.148843) (xy 148.188959 -286.19842)
			(xy 148.204314 -286.250715) (xy 148.21207 -286.304663) (xy 148.212556 -286.331914) (xy 148.211991 -286.361293)
			(xy 148.20294 -286.41935) (xy 148.1851 -286.475335) (xy 148.158893 -286.527926) (xy 148.124936 -286.575879)
			(xy 148.084033 -286.618064) (xy 148.060918 -286.636206) (xy 148.05152 -286.643572) (xy 148.041106 -286.664146)
			(xy 148.039582 -286.768032) (xy 148.049488 -286.789114) (xy 148.058632 -286.79648) (xy 148.079678 -286.814002)
			(xy 148.117021 -286.854056) (xy 148.14826 -286.899033) (xy 148.172753 -286.948012) (xy 148.189998 -286.999988)
			(xy 148.195284 -287.026858) (xy 148.198586 -287.045146) (xy 148.226526 -287.068768) (xy 148.80971 -287.068768)
			(xy 148.83765 -287.045146) (xy 148.840952 -287.026858) (xy 148.84636 -286.999366) (xy 148.864166 -286.94624)
			(xy 148.889548 -286.896289) (xy 148.921962 -286.850587) (xy 148.96071 -286.810116) (xy 149.00496 -286.775746)
			(xy 149.05376 -286.748216) (xy 149.106061 -286.728117) (xy 149.160739 -286.715883) (xy 149.216618 -286.711775)
			(xy 149.272497 -286.715883) (xy 149.327175 -286.728117) (xy 149.379476 -286.748216) (xy 149.428276 -286.775746)
			(xy 149.472526 -286.810116) (xy 149.511274 -286.850587) (xy 149.543688 -286.896289) (xy 149.56907 -286.94624)
			(xy 149.586876 -286.999366) (xy 149.592284 -287.026858) (xy 149.595586 -287.045146) (xy 149.623526 -287.068768)
			(xy 149.69617 -287.068768) (xy 149.72411 -287.045146) (xy 149.727412 -287.026858) (xy 149.73282 -286.999366)
			(xy 149.750626 -286.94624) (xy 149.776008 -286.896289) (xy 149.808422 -286.850587) (xy 149.84717 -286.810116)
			(xy 149.89142 -286.775746) (xy 149.94022 -286.748216) (xy 149.992521 -286.728117) (xy 150.047199 -286.715883)
			(xy 150.103078 -286.711775) (xy 150.158957 -286.715883) (xy 150.213635 -286.728117) (xy 150.265936 -286.748216)
			(xy 150.314736 -286.775746) (xy 150.358986 -286.810116) (xy 150.397734 -286.850587) (xy 150.430148 -286.896289)
			(xy 150.45553 -286.94624) (xy 150.473336 -286.999366) (xy 150.478744 -287.026858) (xy 150.482046 -287.045146)
			(xy 150.509986 -287.068768) (xy 152.07869 -287.068768) (xy 152.090131 -287.06807) (xy 152.110705 -287.058037)
			(xy 152.118314 -287.049464) (xy 152.17521 -286.97809) (xy 152.18029 -286.955738) (xy 152.177496 -286.944054)
			(xy 152.173812 -286.92702) (xy 152.169871 -286.892392) (xy 152.169622 -286.874966) (xy 152.170144 -286.849711)
			(xy 152.178457 -286.799889) (xy 152.194858 -286.752115) (xy 152.218899 -286.707692) (xy 152.249923 -286.667832)
			(xy 152.287085 -286.633622) (xy 152.329371 -286.605996) (xy 152.375627 -286.585706) (xy 152.424592 -286.573306)
			(xy 152.47493 -286.569135) (xy 152.525268 -286.573306) (xy 152.574233 -286.585706) (xy 152.620489 -286.605996)
			(xy 152.662775 -286.633622) (xy 152.699937 -286.667832) (xy 152.730961 -286.707692) (xy 152.755002 -286.752115)
			(xy 152.771403 -286.799889) (xy 152.779716 -286.849711) (xy 152.780238 -286.874966) (xy 152.780016 -286.892393)
			(xy 152.776071 -286.927024) (xy 152.772364 -286.944054) (xy 152.76957 -286.955738) (xy 152.77465 -286.97809)
			(xy 152.831546 -287.049464) (xy 152.839074 -287.058138) (xy 152.8597 -287.068191) (xy 152.87117 -287.068768)
			(xy 153.02865 -287.068768) (xy 153.040095 -287.068078) (xy 153.060682 -287.058055) (xy 153.068274 -287.049464)
			(xy 153.12517 -286.97809) (xy 153.13025 -286.955738) (xy 153.127456 -286.944054) (xy 153.123771 -286.92702)
			(xy 153.119829 -286.892392) (xy 153.119582 -286.874966) (xy 153.120104 -286.849711) (xy 153.128417 -286.799889)
			(xy 153.144818 -286.752115) (xy 153.168859 -286.707692) (xy 153.199883 -286.667832) (xy 153.237045 -286.633622)
			(xy 153.279331 -286.605996) (xy 153.325587 -286.585706) (xy 153.374552 -286.573306) (xy 153.42489 -286.569135)
			(xy 153.475228 -286.573306) (xy 153.524193 -286.585706) (xy 153.570449 -286.605996) (xy 153.612735 -286.633622)
			(xy 153.649897 -286.667832) (xy 153.680921 -286.707692) (xy 153.704962 -286.752115) (xy 153.721363 -286.799889)
			(xy 153.729676 -286.849711) (xy 153.730198 -286.874966) (xy 153.729976 -286.892394) (xy 153.726032 -286.927024)
			(xy 153.722324 -286.944054) (xy 153.71953 -286.955738) (xy 153.72461 -286.97809) (xy 153.781506 -287.049464)
			(xy 153.789038 -287.058128) (xy 153.809664 -287.068157) (xy 153.82113 -287.068768) (xy 164.428678 -287.068768)
			(xy 164.44012 -287.068072) (xy 164.460698 -287.058043) (xy 164.468302 -287.049464) (xy 164.525198 -286.97809)
			(xy 164.530278 -286.955738) (xy 164.527484 -286.944054) (xy 164.5238 -286.92702) (xy 164.519859 -286.892392)
			(xy 164.51961 -286.874966) (xy 164.520083 -286.850977) (xy 164.527594 -286.803591) (xy 164.542424 -286.757962)
			(xy 164.56421 -286.715216) (xy 164.592414 -286.676403) (xy 164.626343 -286.64248) (xy 164.66516 -286.614283)
			(xy 164.70791 -286.592504) (xy 164.753541 -286.577681) (xy 164.800929 -286.570179) (xy 164.824918 -286.569658)
			(xy 164.84828 -286.570121) (xy 164.894457 -286.577261) (xy 164.916866 -286.583882) (xy 164.928804 -286.587692)
			(xy 164.952426 -286.583628) (xy 165.028372 -286.528002) (xy 165.037629 -286.520395) (xy 165.048483 -286.499069)
			(xy 165.0492 -286.487108) (xy 165.0492 -283.46273) (xy 165.048558 -283.450749) (xy 165.037684 -283.429401)
			(xy 165.028372 -283.421836) (xy 164.952426 -283.36621) (xy 164.928804 -283.362146) (xy 164.916866 -283.365956)
			(xy 164.894464 -283.372607) (xy 164.848283 -283.379744) (xy 164.824918 -283.38018) (xy 164.799662 -283.379689)
			(xy 164.749837 -283.371377) (xy 164.702061 -283.354978) (xy 164.657635 -283.330939) (xy 164.617773 -283.299914)
			(xy 164.58356 -283.262752) (xy 164.555931 -283.220465) (xy 164.53564 -283.174207) (xy 164.523239 -283.12524)
			(xy 164.519068 -283.0749) (xy 164.523239 -283.02456) (xy 164.53564 -282.975593) (xy 164.555931 -282.929335)
			(xy 164.58356 -282.887048) (xy 164.617773 -282.849886) (xy 164.657635 -282.818861) (xy 164.702061 -282.794822)
			(xy 164.749837 -282.778423) (xy 164.799662 -282.770111) (xy 164.824918 -282.769564) (xy 164.84828 -282.770028)
			(xy 164.894457 -282.777167) (xy 164.916866 -282.783788) (xy 164.928804 -282.787598) (xy 164.952426 -282.783534)
			(xy 165.028372 -282.727908) (xy 165.03763 -282.720301) (xy 165.048487 -282.698975) (xy 165.0492 -282.687014)
			(xy 165.0492 -281.883612) (xy 165.048813 -281.875256) (xy 165.043365 -281.859452) (xy 165.038532 -281.852624)
			(xy 165.022262 -281.830713) (xy 164.996369 -281.782676) (xy 164.978705 -281.731042) (xy 164.96975 -281.677211)
			(xy 164.969746 -281.62264) (xy 164.978693 -281.568807) (xy 164.996348 -281.517171) (xy 165.022234 -281.46913)
			(xy 165.038532 -281.44724) (xy 165.04344 -281.440453) (xy 165.048879 -281.424622) (xy 165.0492 -281.416252)
			(xy 165.0492 -280.927302) (xy 165.048891 -280.919108) (xy 165.043709 -280.903562) (xy 165.03904 -280.896822)
			(xy 165.023502 -280.875398) (xy 164.998826 -280.828582) (xy 164.982009 -280.778405) (xy 164.973488 -280.726175)
			(xy 164.973485 -280.673254) (xy 164.982002 -280.621023) (xy 164.998815 -280.570844) (xy 165.023486 -280.524026)
			(xy 165.03904 -280.502614) (xy 165.043714 -280.495875) (xy 165.048906 -280.480329) (xy 165.0492 -280.472134)
			(xy 165.0492 -279.977088) (xy 165.048889 -279.968895) (xy 165.043704 -279.953351) (xy 165.03904 -279.946608)
			(xy 165.023503 -279.925184) (xy 164.99883 -279.878369) (xy 164.982014 -279.828192) (xy 164.973495 -279.775963)
			(xy 164.973495 -279.723043) (xy 164.982013 -279.670814) (xy 164.998827 -279.620637) (xy 165.0235 -279.573821)
			(xy 165.03904 -279.5524) (xy 165.043712 -279.54566) (xy 165.0489 -279.530114) (xy 165.0492 -279.52192)
			(xy 165.0492 -279.033478) (xy 165.048823 -279.025118) (xy 165.043391 -279.009302) (xy 165.038532 -279.00249)
			(xy 165.022265 -278.980579) (xy 164.996377 -278.932543) (xy 164.978719 -278.880911) (xy 164.969769 -278.827082)
			(xy 164.969769 -278.772515) (xy 164.97872 -278.718686) (xy 164.996378 -278.667054) (xy 165.022266 -278.619018)
			(xy 165.038532 -278.597106) (xy 165.043449 -278.590322) (xy 165.048909 -278.574491) (xy 165.0492 -278.566118)
			(xy 165.0492 -278.083518) (xy 165.048814 -278.075162) (xy 165.043367 -278.059356) (xy 165.038532 -278.05253)
			(xy 165.022261 -278.030619) (xy 164.996367 -277.982582) (xy 164.978703 -277.930948) (xy 164.969747 -277.877116)
			(xy 164.969742 -277.822544) (xy 164.978688 -277.768711) (xy 164.996343 -277.717074) (xy 165.022229 -277.669032)
			(xy 165.038532 -277.647146) (xy 165.04344 -277.640359) (xy 165.048882 -277.624528) (xy 165.0492 -277.616158)
			(xy 165.0492 -277.133558) (xy 165.04882 -277.1252) (xy 165.043383 -277.109386) (xy 165.038532 -277.10257)
			(xy 165.022266 -277.080659) (xy 164.996382 -277.032623) (xy 164.978727 -276.980993) (xy 164.96978 -276.927166)
			(xy 164.969783 -276.8726) (xy 164.978736 -276.818774) (xy 164.996396 -276.767145) (xy 165.022285 -276.719112)
			(xy 165.038532 -276.697186) (xy 165.043446 -276.690401) (xy 165.0489 -276.67457) (xy 165.0492 -276.666198)
			(xy 165.0492 -276.177502) (xy 165.048891 -276.169308) (xy 165.043709 -276.153762) (xy 165.03904 -276.147022)
			(xy 165.023502 -276.125598) (xy 164.998826 -276.078782) (xy 164.982009 -276.028605) (xy 164.973488 -275.976375)
			(xy 164.973485 -275.923454) (xy 164.982002 -275.871223) (xy 164.998815 -275.821044) (xy 165.023486 -275.774226)
			(xy 165.03904 -275.752814) (xy 165.043714 -275.746075) (xy 165.048906 -275.730529) (xy 165.0492 -275.722334)
			(xy 165.0492 -275.227542) (xy 165.048897 -275.219346) (xy 165.043725 -275.203792) (xy 165.03904 -275.197062)
			(xy 165.023507 -275.175638) (xy 164.998841 -275.128824) (xy 164.982032 -275.07865) (xy 164.97352 -275.026424)
			(xy 164.973525 -274.973509) (xy 164.982049 -274.921285) (xy 164.998867 -274.871114) (xy 165.023543 -274.824305)
			(xy 165.03904 -274.802854) (xy 165.043705 -274.796113) (xy 165.048879 -274.780566) (xy 165.0492 -274.772374)
			(xy 165.0492 -274.283424) (xy 165.048815 -274.275068) (xy 165.04337 -274.259261) (xy 165.038532 -274.252436)
			(xy 165.022261 -274.230525) (xy 164.996366 -274.182487) (xy 164.978701 -274.130853) (xy 164.969744 -274.077021)
			(xy 164.969738 -274.022449) (xy 164.978684 -273.968614) (xy 164.996338 -273.916976) (xy 165.022223 -273.868934)
			(xy 165.038532 -273.847052) (xy 165.043441 -273.840266) (xy 165.048884 -273.824435) (xy 165.0492 -273.816064)
			(xy 165.0492 -273.333464) (xy 165.048821 -273.325105) (xy 165.043386 -273.309291) (xy 165.038532 -273.302476)
			(xy 165.022266 -273.280565) (xy 164.99638 -273.232529) (xy 164.978725 -273.180898) (xy 164.969777 -273.127071)
			(xy 164.969779 -273.072504) (xy 164.978731 -273.018677) (xy 164.996391 -272.967048) (xy 165.02228 -272.919014)
			(xy 165.038532 -272.897092) (xy 165.043447 -272.890307) (xy 165.048902 -272.874476) (xy 165.0492 -272.866104)
			(xy 165.0492 -269.48003) (xy 165.048764 -269.469965) (xy 165.041032 -269.45138) (xy 165.034214 -269.443962)
			(xy 165.027102 -269.43685) (xy 165.020263 -269.429449) (xy 165.012547 -269.410851) (xy 165.012116 -269.400782)
			(xy 165.012116 -264.961116) (xy 165.011678 -264.951052) (xy 165.003944 -264.932468) (xy 164.99713 -264.925048)
			(xy 164.309044 -264.236962) (xy 164.289994 -264.229342) (xy 164.279326 -264.22985) (xy 164.263324 -264.230104)
			(xy 157.05963 -264.230104) (xy 157.026753 -264.229624) (xy 156.961416 -264.222228) (xy 156.897316 -264.207571)
			(xy 156.835258 -264.185836) (xy 156.77602 -264.157297) (xy 156.720346 -264.122311) (xy 156.668934 -264.081317)
			(xy 156.645356 -264.0584) (xy 156.572712 -263.985756) (xy 156.565317 -263.978902) (xy 156.546718 -263.971154)
			(xy 156.536644 -263.97077) (xy 156.389578 -263.97077) (xy 156.37951 -263.970342) (xy 156.360914 -263.962619)
			(xy 156.35351 -263.955784) (xy 155.86456 -263.466834) (xy 155.857717 -263.459435) (xy 155.849997 -263.440836)
			(xy 155.849574 -263.430766) (xy 155.849574 -263.2837) (xy 155.84915 -263.27363) (xy 155.841433 -263.255028)
			(xy 155.834588 -263.247632) (xy 155.667964 -263.081008) (xy 155.645018 -263.057454) (xy 155.603998 -263.006055)
			(xy 155.568995 -262.950384) (xy 155.54045 -262.891141) (xy 155.518723 -262.829073) (xy 155.504087 -262.764962)
			(xy 155.496726 -262.699614) (xy 155.49626 -262.666734) (xy 155.49626 -257.33883) (xy 155.49674 -257.305953)
			(xy 155.504137 -257.240617) (xy 155.518795 -257.176518) (xy 155.540532 -257.114461) (xy 155.569073 -257.055225)
			(xy 155.604062 -256.999554) (xy 155.645058 -256.948145) (xy 155.667964 -256.924556) (xy 157.203902 -255.388618)
			(xy 157.210699 -255.381268) (xy 157.218402 -255.362805) (xy 157.218888 -255.352804) (xy 157.218888 -249.766074)
			(xy 157.218346 -249.756089) (xy 157.210624 -249.737665) (xy 157.203902 -249.73026) (xy 156.694124 -249.220482)
			(xy 156.686779 -249.213674) (xy 156.668315 -249.205957) (xy 156.65831 -249.205496) (xy 149.455124 -249.205496)
			(xy 149.42225 -249.205069) (xy 149.356911 -249.19774) (xy 149.292805 -249.183137) (xy 149.230739 -249.161444)
			(xy 149.171493 -249.132935) (xy 149.115814 -249.097969) (xy 149.064402 -249.056984) (xy 149.04085 -249.034046)
			(xy 148.903944 -248.89714) (xy 148.896539 -248.890445) (xy 148.878102 -248.88284) (xy 148.86813 -248.882408)
			(xy 142.95501 -248.882408) (xy 142.944407 -248.882949) (xy 142.924986 -248.891473) (xy 142.917418 -248.898918)
			(xy 142.859506 -248.962926) (xy 142.852902 -248.983246) (xy 142.853918 -248.994168) (xy 142.85595 -249.032522)
			(xy 142.855464 -249.059773) (xy 142.847708 -249.113721) (xy 142.832353 -249.166016) (xy 142.809711 -249.215593)
			(xy 142.780245 -249.261443) (xy 142.744554 -249.302634) (xy 142.703363 -249.338325) (xy 142.657513 -249.367791)
			(xy 142.607936 -249.390433) (xy 142.555641 -249.405788) (xy 142.501693 -249.413544) (xy 142.447191 -249.413544)
			(xy 142.393243 -249.405788) (xy 142.340948 -249.390433) (xy 142.291371 -249.367791) (xy 142.245521 -249.338325)
			(xy 142.20433 -249.302634) (xy 142.168639 -249.261443) (xy 142.139173 -249.215593) (xy 142.116531 -249.166016)
			(xy 142.101176 -249.113721) (xy 142.09342 -249.059773) (xy 142.092934 -249.032522) (xy 142.094966 -248.994168)
			(xy 142.095982 -248.983246) (xy 142.089378 -248.962926) (xy 142.031466 -248.898918) (xy 142.023968 -248.891373)
			(xy 142.004504 -248.882838) (xy 141.993874 -248.882408) (xy 141.93647 -248.882408) (xy 141.925537 -248.882918)
			(xy 141.905642 -248.891989) (xy 141.898116 -248.899934) (xy 141.840458 -248.966482) (xy 141.834362 -248.98731)
			(xy 141.83614 -248.998486) (xy 141.837949 -249.012002) (xy 141.839859 -249.039206) (xy 141.83995 -249.052842)
			(xy 141.839464 -249.080093) (xy 141.831708 -249.134041) (xy 141.816353 -249.186336) (xy 141.793711 -249.235913)
			(xy 141.764245 -249.281763) (xy 141.728554 -249.322954) (xy 141.687363 -249.358645) (xy 141.641513 -249.388111)
			(xy 141.591936 -249.410753) (xy 141.539641 -249.426108) (xy 141.485693 -249.433864) (xy 141.431191 -249.433864)
			(xy 141.377243 -249.426108) (xy 141.324948 -249.410753) (xy 141.275371 -249.388111) (xy 141.229521 -249.358645)
			(xy 141.18833 -249.322954) (xy 141.152639 -249.281763) (xy 141.123173 -249.235913) (xy 141.100531 -249.186336)
			(xy 141.085176 -249.134041) (xy 141.07742 -249.080093) (xy 141.076934 -249.052842) (xy 141.077039 -249.039207)
			(xy 141.078945 -249.012003) (xy 141.080744 -248.998486) (xy 141.082522 -248.98731) (xy 141.076426 -248.966482)
			(xy 141.018768 -248.899934) (xy 141.011217 -248.892016) (xy 140.991342 -248.882919) (xy 140.980414 -248.882408)
			(xy 137.719054 -248.882408) (xy 137.70909 -248.882891) (xy 137.690662 -248.890474) (xy 137.68324 -248.89714)
			(xy 137.662158 -248.918222) (xy 137.655309 -248.925619) (xy 137.647573 -248.944218) (xy 137.647172 -248.95429)
			(xy 137.647172 -249.73915) (xy 137.647363 -249.745589) (xy 137.650579 -249.758058) (xy 137.653522 -249.763788)
			(xy 137.668695 -249.79219) (xy 137.692551 -249.852002) (xy 137.708669 -249.914346) (xy 137.716792 -249.978225)
			(xy 137.717276 -250.010422) (xy 137.717276 -251.158502) (xy 140.060424 -251.158502) (xy 140.064495 -251.10288)
			(xy 140.076621 -251.048443) (xy 140.096544 -250.996352) (xy 140.12384 -250.947717) (xy 140.157926 -250.903574)
			(xy 140.198075 -250.864865) (xy 140.243433 -250.832414) (xy 140.293033 -250.806913) (xy 140.345817 -250.788906)
			(xy 140.40066 -250.778776) (xy 140.456394 -250.776739) (xy 140.511831 -250.782839) (xy 140.565788 -250.796945)
			(xy 140.617117 -250.818757) (xy 140.664723 -250.847811) (xy 140.707591 -250.883486) (xy 140.744808 -250.925023)
			(xy 140.775581 -250.971536) (xy 140.799253 -251.022033) (xy 140.815321 -251.07544) (xy 140.823441 -251.130616)
			(xy 140.82395 -251.158502) (xy 141.076424 -251.158502) (xy 141.080495 -251.10288) (xy 141.092621 -251.048443)
			(xy 141.112544 -250.996352) (xy 141.13984 -250.947717) (xy 141.173926 -250.903574) (xy 141.214075 -250.864865)
			(xy 141.259433 -250.832414) (xy 141.309033 -250.806913) (xy 141.361817 -250.788906) (xy 141.41666 -250.778776)
			(xy 141.472394 -250.776739) (xy 141.527831 -250.782839) (xy 141.581788 -250.796945) (xy 141.633117 -250.818757)
			(xy 141.680723 -250.847811) (xy 141.723591 -250.883486) (xy 141.760808 -250.925023) (xy 141.791581 -250.971536)
			(xy 141.815253 -251.022033) (xy 141.831321 -251.07544) (xy 141.839441 -251.130616) (xy 141.83995 -251.158502)
			(xy 142.092424 -251.158502) (xy 142.096495 -251.10288) (xy 142.108621 -251.048443) (xy 142.128544 -250.996352)
			(xy 142.15584 -250.947717) (xy 142.189926 -250.903574) (xy 142.230075 -250.864865) (xy 142.275433 -250.832414)
			(xy 142.325033 -250.806913) (xy 142.377817 -250.788906) (xy 142.43266 -250.778776) (xy 142.488394 -250.776739)
			(xy 142.543831 -250.782839) (xy 142.597788 -250.796945) (xy 142.649117 -250.818757) (xy 142.696723 -250.847811)
			(xy 142.739591 -250.883486) (xy 142.776808 -250.925023) (xy 142.807581 -250.971536) (xy 142.831253 -251.022033)
			(xy 142.847321 -251.07544) (xy 142.855441 -251.130616) (xy 142.85595 -251.158502) (xy 143.108424 -251.158502)
			(xy 143.112495 -251.10288) (xy 143.124621 -251.048443) (xy 143.144544 -250.996352) (xy 143.17184 -250.947717)
			(xy 143.205926 -250.903574) (xy 143.246075 -250.864865) (xy 143.291433 -250.832414) (xy 143.341033 -250.806913)
			(xy 143.393817 -250.788906) (xy 143.44866 -250.778776) (xy 143.504394 -250.776739) (xy 143.559831 -250.782839)
			(xy 143.613788 -250.796945) (xy 143.665117 -250.818757) (xy 143.712723 -250.847811) (xy 143.755591 -250.883486)
			(xy 143.792808 -250.925023) (xy 143.823581 -250.971536) (xy 143.847253 -251.022033) (xy 143.863321 -251.07544)
			(xy 143.871441 -251.130616) (xy 143.87195 -251.158502) (xy 144.124424 -251.158502) (xy 144.128495 -251.10288)
			(xy 144.140621 -251.048443) (xy 144.160544 -250.996352) (xy 144.18784 -250.947717) (xy 144.221926 -250.903574)
			(xy 144.262075 -250.864865) (xy 144.307433 -250.832414) (xy 144.357033 -250.806913) (xy 144.409817 -250.788906)
			(xy 144.46466 -250.778776) (xy 144.520394 -250.776739) (xy 144.575831 -250.782839) (xy 144.629788 -250.796945)
			(xy 144.681117 -250.818757) (xy 144.728723 -250.847811) (xy 144.771591 -250.883486) (xy 144.808808 -250.925023)
			(xy 144.839581 -250.971536) (xy 144.863253 -251.022033) (xy 144.879321 -251.07544) (xy 144.887441 -251.130616)
			(xy 144.88795 -251.158502) (xy 145.140424 -251.158502) (xy 145.144495 -251.10288) (xy 145.156621 -251.048443)
			(xy 145.176544 -250.996352) (xy 145.20384 -250.947717) (xy 145.237926 -250.903574) (xy 145.278075 -250.864865)
			(xy 145.323433 -250.832414) (xy 145.373033 -250.806913) (xy 145.425817 -250.788906) (xy 145.48066 -250.778776)
			(xy 145.536394 -250.776739) (xy 145.591831 -250.782839) (xy 145.645788 -250.796945) (xy 145.697117 -250.818757)
			(xy 145.744723 -250.847811) (xy 145.787591 -250.883486) (xy 145.824808 -250.925023) (xy 145.855581 -250.971536)
			(xy 145.879253 -251.022033) (xy 145.895321 -251.07544) (xy 145.903441 -251.130616) (xy 145.90395 -251.158502)
			(xy 146.156424 -251.158502) (xy 146.160495 -251.10288) (xy 146.172621 -251.048443) (xy 146.192544 -250.996352)
			(xy 146.21984 -250.947717) (xy 146.253926 -250.903574) (xy 146.294075 -250.864865) (xy 146.339433 -250.832414)
			(xy 146.389033 -250.806913) (xy 146.441817 -250.788906) (xy 146.49666 -250.778776) (xy 146.552394 -250.776739)
			(xy 146.607831 -250.782839) (xy 146.661788 -250.796945) (xy 146.713117 -250.818757) (xy 146.760723 -250.847811)
			(xy 146.803591 -250.883486) (xy 146.840808 -250.925023) (xy 146.871581 -250.971536) (xy 146.895253 -251.022033)
			(xy 146.911321 -251.07544) (xy 146.919441 -251.130616) (xy 146.91995 -251.158502) (xy 147.172424 -251.158502)
			(xy 147.176495 -251.10288) (xy 147.188621 -251.048443) (xy 147.208544 -250.996352) (xy 147.23584 -250.947717)
			(xy 147.269926 -250.903574) (xy 147.310075 -250.864865) (xy 147.355433 -250.832414) (xy 147.405033 -250.806913)
			(xy 147.457817 -250.788906) (xy 147.51266 -250.778776) (xy 147.568394 -250.776739) (xy 147.623831 -250.782839)
			(xy 147.677788 -250.796945) (xy 147.729117 -250.818757) (xy 147.776723 -250.847811) (xy 147.819591 -250.883486)
			(xy 147.856808 -250.925023) (xy 147.887581 -250.971536) (xy 147.911253 -251.022033) (xy 147.927321 -251.07544)
			(xy 147.935441 -251.130616) (xy 147.93595 -251.158502) (xy 148.188424 -251.158502) (xy 148.192495 -251.10288)
			(xy 148.204621 -251.048443) (xy 148.224544 -250.996352) (xy 148.25184 -250.947717) (xy 148.285926 -250.903574)
			(xy 148.326075 -250.864865) (xy 148.371433 -250.832414) (xy 148.421033 -250.806913) (xy 148.473817 -250.788906)
			(xy 148.52866 -250.778776) (xy 148.584394 -250.776739) (xy 148.639831 -250.782839) (xy 148.693788 -250.796945)
			(xy 148.745117 -250.818757) (xy 148.792723 -250.847811) (xy 148.835591 -250.883486) (xy 148.872808 -250.925023)
			(xy 148.903581 -250.971536) (xy 148.927253 -251.022033) (xy 148.943321 -251.07544) (xy 148.951441 -251.130616)
			(xy 148.95195 -251.158502) (xy 149.204424 -251.158502) (xy 149.208495 -251.10288) (xy 149.220621 -251.048443)
			(xy 149.240544 -250.996352) (xy 149.26784 -250.947717) (xy 149.301926 -250.903574) (xy 149.342075 -250.864865)
			(xy 149.387433 -250.832414) (xy 149.437033 -250.806913) (xy 149.489817 -250.788906) (xy 149.54466 -250.778776)
			(xy 149.600394 -250.776739) (xy 149.655831 -250.782839) (xy 149.709788 -250.796945) (xy 149.761117 -250.818757)
			(xy 149.808723 -250.847811) (xy 149.851591 -250.883486) (xy 149.888808 -250.925023) (xy 149.919581 -250.971536)
			(xy 149.943253 -251.022033) (xy 149.959321 -251.07544) (xy 149.967441 -251.130616) (xy 149.96795 -251.158502)
			(xy 150.220424 -251.158502) (xy 150.224495 -251.10288) (xy 150.236621 -251.048443) (xy 150.256544 -250.996352)
			(xy 150.28384 -250.947717) (xy 150.317926 -250.903574) (xy 150.358075 -250.864865) (xy 150.403433 -250.832414)
			(xy 150.453033 -250.806913) (xy 150.505817 -250.788906) (xy 150.56066 -250.778776) (xy 150.616394 -250.776739)
			(xy 150.671831 -250.782839) (xy 150.725788 -250.796945) (xy 150.777117 -250.818757) (xy 150.824723 -250.847811)
			(xy 150.867591 -250.883486) (xy 150.904808 -250.925023) (xy 150.935581 -250.971536) (xy 150.959253 -251.022033)
			(xy 150.975321 -251.07544) (xy 150.983441 -251.130616) (xy 150.98395 -251.158502) (xy 151.236424 -251.158502)
			(xy 151.240495 -251.10288) (xy 151.252621 -251.048443) (xy 151.272544 -250.996352) (xy 151.29984 -250.947717)
			(xy 151.333926 -250.903574) (xy 151.374075 -250.864865) (xy 151.419433 -250.832414) (xy 151.469033 -250.806913)
			(xy 151.521817 -250.788906) (xy 151.57666 -250.778776) (xy 151.632394 -250.776739) (xy 151.687831 -250.782839)
			(xy 151.741788 -250.796945) (xy 151.793117 -250.818757) (xy 151.840723 -250.847811) (xy 151.883591 -250.883486)
			(xy 151.920808 -250.925023) (xy 151.951581 -250.971536) (xy 151.975253 -251.022033) (xy 151.991321 -251.07544)
			(xy 151.999441 -251.130616) (xy 151.99995 -251.158502) (xy 152.252424 -251.158502) (xy 152.256495 -251.10288)
			(xy 152.268621 -251.048443) (xy 152.288544 -250.996352) (xy 152.31584 -250.947717) (xy 152.349926 -250.903574)
			(xy 152.390075 -250.864865) (xy 152.435433 -250.832414) (xy 152.485033 -250.806913) (xy 152.537817 -250.788906)
			(xy 152.59266 -250.778776) (xy 152.648394 -250.776739) (xy 152.703831 -250.782839) (xy 152.757788 -250.796945)
			(xy 152.809117 -250.818757) (xy 152.856723 -250.847811) (xy 152.899591 -250.883486) (xy 152.936808 -250.925023)
			(xy 152.967581 -250.971536) (xy 152.991253 -251.022033) (xy 153.007321 -251.07544) (xy 153.015441 -251.130616)
			(xy 153.01595 -251.158502) (xy 153.268424 -251.158502) (xy 153.272495 -251.10288) (xy 153.284621 -251.048443)
			(xy 153.304544 -250.996352) (xy 153.33184 -250.947717) (xy 153.365926 -250.903574) (xy 153.406075 -250.864865)
			(xy 153.451433 -250.832414) (xy 153.501033 -250.806913) (xy 153.553817 -250.788906) (xy 153.60866 -250.778776)
			(xy 153.664394 -250.776739) (xy 153.719831 -250.782839) (xy 153.773788 -250.796945) (xy 153.825117 -250.818757)
			(xy 153.872723 -250.847811) (xy 153.915591 -250.883486) (xy 153.952808 -250.925023) (xy 153.983581 -250.971536)
			(xy 154.007253 -251.022033) (xy 154.023321 -251.07544) (xy 154.031441 -251.130616) (xy 154.03195 -251.158502)
			(xy 154.284424 -251.158502) (xy 154.288495 -251.10288) (xy 154.300621 -251.048443) (xy 154.320544 -250.996352)
			(xy 154.34784 -250.947717) (xy 154.381926 -250.903574) (xy 154.422075 -250.864865) (xy 154.467433 -250.832414)
			(xy 154.517033 -250.806913) (xy 154.569817 -250.788906) (xy 154.62466 -250.778776) (xy 154.680394 -250.776739)
			(xy 154.735831 -250.782839) (xy 154.789788 -250.796945) (xy 154.841117 -250.818757) (xy 154.888723 -250.847811)
			(xy 154.931591 -250.883486) (xy 154.968808 -250.925023) (xy 154.999581 -250.971536) (xy 155.023253 -251.022033)
			(xy 155.039321 -251.07544) (xy 155.047441 -251.130616) (xy 155.04795 -251.158502) (xy 156.316424 -251.158502)
			(xy 156.320495 -251.10288) (xy 156.332621 -251.048443) (xy 156.352544 -250.996352) (xy 156.37984 -250.947717)
			(xy 156.413926 -250.903574) (xy 156.454075 -250.864865) (xy 156.499433 -250.832414) (xy 156.549033 -250.806913)
			(xy 156.601817 -250.788906) (xy 156.65666 -250.778776) (xy 156.712394 -250.776739) (xy 156.767831 -250.782839)
			(xy 156.821788 -250.796945) (xy 156.873117 -250.818757) (xy 156.920723 -250.847811) (xy 156.963591 -250.883486)
			(xy 157.000808 -250.925023) (xy 157.031581 -250.971536) (xy 157.055253 -251.022033) (xy 157.071321 -251.07544)
			(xy 157.079441 -251.130616) (xy 157.07995 -251.158502) (xy 157.079441 -251.186388) (xy 157.071321 -251.241564)
			(xy 157.055253 -251.294971) (xy 157.031581 -251.345468) (xy 157.000808 -251.391981) (xy 156.963591 -251.433518)
			(xy 156.920723 -251.469193) (xy 156.873117 -251.498247) (xy 156.821788 -251.520059) (xy 156.767831 -251.534165)
			(xy 156.712394 -251.540265) (xy 156.65666 -251.538228) (xy 156.601817 -251.528098) (xy 156.549033 -251.510091)
			(xy 156.499433 -251.48459) (xy 156.454075 -251.452139) (xy 156.413926 -251.41343) (xy 156.37984 -251.369287)
			(xy 156.352544 -251.320652) (xy 156.332621 -251.268561) (xy 156.320495 -251.214124) (xy 156.316424 -251.158502)
			(xy 155.04795 -251.158502) (xy 155.047441 -251.186388) (xy 155.039321 -251.241564) (xy 155.023253 -251.294971)
			(xy 154.999581 -251.345468) (xy 154.968808 -251.391981) (xy 154.931591 -251.433518) (xy 154.888723 -251.469193)
			(xy 154.841117 -251.498247) (xy 154.789788 -251.520059) (xy 154.735831 -251.534165) (xy 154.680394 -251.540265)
			(xy 154.62466 -251.538228) (xy 154.569817 -251.528098) (xy 154.517033 -251.510091) (xy 154.467433 -251.48459)
			(xy 154.422075 -251.452139) (xy 154.381926 -251.41343) (xy 154.34784 -251.369287) (xy 154.320544 -251.320652)
			(xy 154.300621 -251.268561) (xy 154.288495 -251.214124) (xy 154.284424 -251.158502) (xy 154.03195 -251.158502)
			(xy 154.031441 -251.186388) (xy 154.023321 -251.241564) (xy 154.007253 -251.294971) (xy 153.983581 -251.345468)
			(xy 153.952808 -251.391981) (xy 153.915591 -251.433518) (xy 153.872723 -251.469193) (xy 153.825117 -251.498247)
			(xy 153.773788 -251.520059) (xy 153.719831 -251.534165) (xy 153.664394 -251.540265) (xy 153.60866 -251.538228)
			(xy 153.553817 -251.528098) (xy 153.501033 -251.510091) (xy 153.451433 -251.48459) (xy 153.406075 -251.452139)
			(xy 153.365926 -251.41343) (xy 153.33184 -251.369287) (xy 153.304544 -251.320652) (xy 153.284621 -251.268561)
			(xy 153.272495 -251.214124) (xy 153.268424 -251.158502) (xy 153.01595 -251.158502) (xy 153.015441 -251.186388)
			(xy 153.007321 -251.241564) (xy 152.991253 -251.294971) (xy 152.967581 -251.345468) (xy 152.936808 -251.391981)
			(xy 152.899591 -251.433518) (xy 152.856723 -251.469193) (xy 152.809117 -251.498247) (xy 152.757788 -251.520059)
			(xy 152.703831 -251.534165) (xy 152.648394 -251.540265) (xy 152.59266 -251.538228) (xy 152.537817 -251.528098)
			(xy 152.485033 -251.510091) (xy 152.435433 -251.48459) (xy 152.390075 -251.452139) (xy 152.349926 -251.41343)
			(xy 152.31584 -251.369287) (xy 152.288544 -251.320652) (xy 152.268621 -251.268561) (xy 152.256495 -251.214124)
			(xy 152.252424 -251.158502) (xy 151.99995 -251.158502) (xy 151.999441 -251.186388) (xy 151.991321 -251.241564)
			(xy 151.975253 -251.294971) (xy 151.951581 -251.345468) (xy 151.920808 -251.391981) (xy 151.883591 -251.433518)
			(xy 151.840723 -251.469193) (xy 151.793117 -251.498247) (xy 151.741788 -251.520059) (xy 151.687831 -251.534165)
			(xy 151.632394 -251.540265) (xy 151.57666 -251.538228) (xy 151.521817 -251.528098) (xy 151.469033 -251.510091)
			(xy 151.419433 -251.48459) (xy 151.374075 -251.452139) (xy 151.333926 -251.41343) (xy 151.29984 -251.369287)
			(xy 151.272544 -251.320652) (xy 151.252621 -251.268561) (xy 151.240495 -251.214124) (xy 151.236424 -251.158502)
			(xy 150.98395 -251.158502) (xy 150.983441 -251.186388) (xy 150.975321 -251.241564) (xy 150.959253 -251.294971)
			(xy 150.935581 -251.345468) (xy 150.904808 -251.391981) (xy 150.867591 -251.433518) (xy 150.824723 -251.469193)
			(xy 150.777117 -251.498247) (xy 150.725788 -251.520059) (xy 150.671831 -251.534165) (xy 150.616394 -251.540265)
			(xy 150.56066 -251.538228) (xy 150.505817 -251.528098) (xy 150.453033 -251.510091) (xy 150.403433 -251.48459)
			(xy 150.358075 -251.452139) (xy 150.317926 -251.41343) (xy 150.28384 -251.369287) (xy 150.256544 -251.320652)
			(xy 150.236621 -251.268561) (xy 150.224495 -251.214124) (xy 150.220424 -251.158502) (xy 149.96795 -251.158502)
			(xy 149.967441 -251.186388) (xy 149.959321 -251.241564) (xy 149.943253 -251.294971) (xy 149.919581 -251.345468)
			(xy 149.888808 -251.391981) (xy 149.851591 -251.433518) (xy 149.808723 -251.469193) (xy 149.761117 -251.498247)
			(xy 149.709788 -251.520059) (xy 149.655831 -251.534165) (xy 149.600394 -251.540265) (xy 149.54466 -251.538228)
			(xy 149.489817 -251.528098) (xy 149.437033 -251.510091) (xy 149.387433 -251.48459) (xy 149.342075 -251.452139)
			(xy 149.301926 -251.41343) (xy 149.26784 -251.369287) (xy 149.240544 -251.320652) (xy 149.220621 -251.268561)
			(xy 149.208495 -251.214124) (xy 149.204424 -251.158502) (xy 148.95195 -251.158502) (xy 148.951441 -251.186388)
			(xy 148.943321 -251.241564) (xy 148.927253 -251.294971) (xy 148.903581 -251.345468) (xy 148.872808 -251.391981)
			(xy 148.835591 -251.433518) (xy 148.792723 -251.469193) (xy 148.745117 -251.498247) (xy 148.693788 -251.520059)
			(xy 148.639831 -251.534165) (xy 148.584394 -251.540265) (xy 148.52866 -251.538228) (xy 148.473817 -251.528098)
			(xy 148.421033 -251.510091) (xy 148.371433 -251.48459) (xy 148.326075 -251.452139) (xy 148.285926 -251.41343)
			(xy 148.25184 -251.369287) (xy 148.224544 -251.320652) (xy 148.204621 -251.268561) (xy 148.192495 -251.214124)
			(xy 148.188424 -251.158502) (xy 147.93595 -251.158502) (xy 147.935441 -251.186388) (xy 147.927321 -251.241564)
			(xy 147.911253 -251.294971) (xy 147.887581 -251.345468) (xy 147.856808 -251.391981) (xy 147.819591 -251.433518)
			(xy 147.776723 -251.469193) (xy 147.729117 -251.498247) (xy 147.677788 -251.520059) (xy 147.623831 -251.534165)
			(xy 147.568394 -251.540265) (xy 147.51266 -251.538228) (xy 147.457817 -251.528098) (xy 147.405033 -251.510091)
			(xy 147.355433 -251.48459) (xy 147.310075 -251.452139) (xy 147.269926 -251.41343) (xy 147.23584 -251.369287)
			(xy 147.208544 -251.320652) (xy 147.188621 -251.268561) (xy 147.176495 -251.214124) (xy 147.172424 -251.158502)
			(xy 146.91995 -251.158502) (xy 146.919441 -251.186388) (xy 146.911321 -251.241564) (xy 146.895253 -251.294971)
			(xy 146.871581 -251.345468) (xy 146.840808 -251.391981) (xy 146.803591 -251.433518) (xy 146.760723 -251.469193)
			(xy 146.713117 -251.498247) (xy 146.661788 -251.520059) (xy 146.607831 -251.534165) (xy 146.552394 -251.540265)
			(xy 146.49666 -251.538228) (xy 146.441817 -251.528098) (xy 146.389033 -251.510091) (xy 146.339433 -251.48459)
			(xy 146.294075 -251.452139) (xy 146.253926 -251.41343) (xy 146.21984 -251.369287) (xy 146.192544 -251.320652)
			(xy 146.172621 -251.268561) (xy 146.160495 -251.214124) (xy 146.156424 -251.158502) (xy 145.90395 -251.158502)
			(xy 145.903441 -251.186388) (xy 145.895321 -251.241564) (xy 145.879253 -251.294971) (xy 145.855581 -251.345468)
			(xy 145.824808 -251.391981) (xy 145.787591 -251.433518) (xy 145.744723 -251.469193) (xy 145.697117 -251.498247)
			(xy 145.645788 -251.520059) (xy 145.591831 -251.534165) (xy 145.536394 -251.540265) (xy 145.48066 -251.538228)
			(xy 145.425817 -251.528098) (xy 145.373033 -251.510091) (xy 145.323433 -251.48459) (xy 145.278075 -251.452139)
			(xy 145.237926 -251.41343) (xy 145.20384 -251.369287) (xy 145.176544 -251.320652) (xy 145.156621 -251.268561)
			(xy 145.144495 -251.214124) (xy 145.140424 -251.158502) (xy 144.88795 -251.158502) (xy 144.887441 -251.186388)
			(xy 144.879321 -251.241564) (xy 144.863253 -251.294971) (xy 144.839581 -251.345468) (xy 144.808808 -251.391981)
			(xy 144.771591 -251.433518) (xy 144.728723 -251.469193) (xy 144.681117 -251.498247) (xy 144.629788 -251.520059)
			(xy 144.575831 -251.534165) (xy 144.520394 -251.540265) (xy 144.46466 -251.538228) (xy 144.409817 -251.528098)
			(xy 144.357033 -251.510091) (xy 144.307433 -251.48459) (xy 144.262075 -251.452139) (xy 144.221926 -251.41343)
			(xy 144.18784 -251.369287) (xy 144.160544 -251.320652) (xy 144.140621 -251.268561) (xy 144.128495 -251.214124)
			(xy 144.124424 -251.158502) (xy 143.87195 -251.158502) (xy 143.871441 -251.186388) (xy 143.863321 -251.241564)
			(xy 143.847253 -251.294971) (xy 143.823581 -251.345468) (xy 143.792808 -251.391981) (xy 143.755591 -251.433518)
			(xy 143.712723 -251.469193) (xy 143.665117 -251.498247) (xy 143.613788 -251.520059) (xy 143.559831 -251.534165)
			(xy 143.504394 -251.540265) (xy 143.44866 -251.538228) (xy 143.393817 -251.528098) (xy 143.341033 -251.510091)
			(xy 143.291433 -251.48459) (xy 143.246075 -251.452139) (xy 143.205926 -251.41343) (xy 143.17184 -251.369287)
			(xy 143.144544 -251.320652) (xy 143.124621 -251.268561) (xy 143.112495 -251.214124) (xy 143.108424 -251.158502)
			(xy 142.85595 -251.158502) (xy 142.855441 -251.186388) (xy 142.847321 -251.241564) (xy 142.831253 -251.294971)
			(xy 142.807581 -251.345468) (xy 142.776808 -251.391981) (xy 142.739591 -251.433518) (xy 142.696723 -251.469193)
			(xy 142.649117 -251.498247) (xy 142.597788 -251.520059) (xy 142.543831 -251.534165) (xy 142.488394 -251.540265)
			(xy 142.43266 -251.538228) (xy 142.377817 -251.528098) (xy 142.325033 -251.510091) (xy 142.275433 -251.48459)
			(xy 142.230075 -251.452139) (xy 142.189926 -251.41343) (xy 142.15584 -251.369287) (xy 142.128544 -251.320652)
			(xy 142.108621 -251.268561) (xy 142.096495 -251.214124) (xy 142.092424 -251.158502) (xy 141.83995 -251.158502)
			(xy 141.839441 -251.186388) (xy 141.831321 -251.241564) (xy 141.815253 -251.294971) (xy 141.791581 -251.345468)
			(xy 141.760808 -251.391981) (xy 141.723591 -251.433518) (xy 141.680723 -251.469193) (xy 141.633117 -251.498247)
			(xy 141.581788 -251.520059) (xy 141.527831 -251.534165) (xy 141.472394 -251.540265) (xy 141.41666 -251.538228)
			(xy 141.361817 -251.528098) (xy 141.309033 -251.510091) (xy 141.259433 -251.48459) (xy 141.214075 -251.452139)
			(xy 141.173926 -251.41343) (xy 141.13984 -251.369287) (xy 141.112544 -251.320652) (xy 141.092621 -251.268561)
			(xy 141.080495 -251.214124) (xy 141.076424 -251.158502) (xy 140.82395 -251.158502) (xy 140.823441 -251.186388)
			(xy 140.815321 -251.241564) (xy 140.799253 -251.294971) (xy 140.775581 -251.345468) (xy 140.744808 -251.391981)
			(xy 140.707591 -251.433518) (xy 140.664723 -251.469193) (xy 140.617117 -251.498247) (xy 140.565788 -251.520059)
			(xy 140.511831 -251.534165) (xy 140.456394 -251.540265) (xy 140.40066 -251.538228) (xy 140.345817 -251.528098)
			(xy 140.293033 -251.510091) (xy 140.243433 -251.48459) (xy 140.198075 -251.452139) (xy 140.157926 -251.41343)
			(xy 140.12384 -251.369287) (xy 140.096544 -251.320652) (xy 140.076621 -251.268561) (xy 140.064495 -251.214124)
			(xy 140.060424 -251.158502) (xy 137.717276 -251.158502) (xy 137.717276 -253.14021) (xy 137.717752 -253.15096)
			(xy 137.726564 -253.17057) (xy 137.734294 -253.178056) (xy 137.798302 -253.235968) (xy 137.818622 -253.242572)
			(xy 137.829544 -253.241302) (xy 137.839485 -253.240335) (xy 137.859434 -253.239318) (xy 137.869422 -253.23927)
			(xy 137.896674 -253.239757) (xy 137.950622 -253.247517) (xy 138.002917 -253.262875) (xy 138.052495 -253.285518)
			(xy 138.098345 -253.314987) (xy 138.139535 -253.350681) (xy 138.175226 -253.391873) (xy 138.204692 -253.437725)
			(xy 138.213239 -253.45644) (xy 155.300424 -253.45644) (xy 155.304495 -253.400818) (xy 155.316621 -253.346381)
			(xy 155.336544 -253.29429) (xy 155.36384 -253.245655) (xy 155.397926 -253.201512) (xy 155.438075 -253.162803)
			(xy 155.483433 -253.130352) (xy 155.533033 -253.104851) (xy 155.585817 -253.086844) (xy 155.64066 -253.076714)
			(xy 155.696394 -253.074677) (xy 155.751831 -253.080777) (xy 155.805788 -253.094883) (xy 155.857117 -253.116695)
			(xy 155.904723 -253.145749) (xy 155.947591 -253.181424) (xy 155.984808 -253.222961) (xy 156.015581 -253.269474)
			(xy 156.039253 -253.319971) (xy 156.055321 -253.373378) (xy 156.063441 -253.428554) (xy 156.06395 -253.45644)
			(xy 156.063441 -253.484326) (xy 156.055321 -253.539502) (xy 156.039253 -253.592909) (xy 156.015581 -253.643406)
			(xy 155.984808 -253.689919) (xy 155.947591 -253.731456) (xy 155.904723 -253.767131) (xy 155.857117 -253.796185)
			(xy 155.805788 -253.817997) (xy 155.751831 -253.832103) (xy 155.696394 -253.838203) (xy 155.64066 -253.836166)
			(xy 155.585817 -253.826036) (xy 155.533033 -253.808029) (xy 155.483433 -253.782528) (xy 155.438075 -253.750077)
			(xy 155.397926 -253.711368) (xy 155.36384 -253.667225) (xy 155.336544 -253.61859) (xy 155.316621 -253.566499)
			(xy 155.304495 -253.512062) (xy 155.300424 -253.45644) (xy 138.213239 -253.45644) (xy 138.227333 -253.487303)
			(xy 138.242688 -253.539599) (xy 138.250444 -253.593548) (xy 138.250444 -253.648052) (xy 138.242688 -253.702001)
			(xy 138.227333 -253.754297) (xy 138.204692 -253.803875) (xy 138.175226 -253.849727) (xy 138.139535 -253.890919)
			(xy 138.098345 -253.926613) (xy 138.052495 -253.956082) (xy 138.002917 -253.978725) (xy 137.950622 -253.994083)
			(xy 137.896674 -254.001843) (xy 137.869422 -254.002286) (xy 137.859434 -254.002235) (xy 137.839485 -254.001221)
			(xy 137.829544 -254.000254) (xy 137.818622 -253.998984) (xy 137.798302 -254.005588) (xy 137.734294 -254.0635)
			(xy 137.726673 -254.071065) (xy 137.717872 -254.090625) (xy 137.717276 -254.101346) (xy 137.717276 -255.463548)
			(xy 137.717707 -255.473615) (xy 137.725431 -255.492209) (xy 137.732262 -255.499616) (xy 137.911332 -255.678432)
			(xy 137.919273 -255.685623) (xy 137.939226 -255.693356) (xy 137.94994 -255.693418) (xy 138.0363 -255.688846)
			(xy 138.055096 -255.679194) (xy 138.061954 -255.670558) (xy 138.080185 -255.648868) (xy 138.12196 -255.610591)
			(xy 138.168934 -255.578911) (xy 138.220075 -255.554521) (xy 138.274259 -255.537959) (xy 138.330296 -255.529588)
			(xy 138.358626 -255.52908) (xy 138.385876 -255.529568) (xy 138.439822 -255.537327) (xy 138.492114 -255.552684)
			(xy 138.541689 -255.575327) (xy 138.587537 -255.604794) (xy 138.628725 -255.640485) (xy 138.664415 -255.681674)
			(xy 138.668861 -255.688592) (xy 139.695172 -255.688592) (xy 139.699243 -255.63297) (xy 139.711369 -255.578533)
			(xy 139.731292 -255.526442) (xy 139.758588 -255.477807) (xy 139.792674 -255.433664) (xy 139.832823 -255.394955)
			(xy 139.878181 -255.362504) (xy 139.927781 -255.337003) (xy 139.980565 -255.318996) (xy 140.035408 -255.308866)
			(xy 140.091142 -255.306829) (xy 140.146579 -255.312929) (xy 140.200536 -255.327035) (xy 140.251865 -255.348847)
			(xy 140.299471 -255.377901) (xy 140.342339 -255.413576) (xy 140.379556 -255.455113) (xy 140.410329 -255.501626)
			(xy 140.434001 -255.552123) (xy 140.450069 -255.60553) (xy 140.458189 -255.660706) (xy 140.458698 -255.688592)
			(xy 140.458189 -255.716478) (xy 140.450069 -255.771654) (xy 140.434001 -255.825061) (xy 140.410329 -255.875558)
			(xy 140.379556 -255.922071) (xy 140.342339 -255.963608) (xy 140.299471 -255.999283) (xy 140.251865 -256.028337)
			(xy 140.200536 -256.050149) (xy 140.146579 -256.064255) (xy 140.091142 -256.070355) (xy 140.035408 -256.068318)
			(xy 139.980565 -256.058188) (xy 139.927781 -256.040181) (xy 139.878181 -256.01468) (xy 139.832823 -255.982229)
			(xy 139.792674 -255.94352) (xy 139.758588 -255.899377) (xy 139.731292 -255.850742) (xy 139.711369 -255.798651)
			(xy 139.699243 -255.744214) (xy 139.695172 -255.688592) (xy 138.668861 -255.688592) (xy 138.69388 -255.727523)
			(xy 138.716521 -255.777099) (xy 138.731876 -255.829392) (xy 138.739633 -255.883338) (xy 138.740134 -255.910588)
			(xy 138.740091 -255.921278) (xy 138.73895 -255.942627) (xy 138.737848 -255.95326) (xy 138.736578 -255.96342)
			(xy 138.742166 -255.982724) (xy 138.799824 -256.05486) (xy 138.817604 -256.064512) (xy 138.827764 -256.065528)
			(xy 138.861916 -256.069845) (xy 138.928706 -256.086509) (xy 138.992635 -256.112035) (xy 139.052535 -256.145955)
			(xy 139.107309 -256.187649) (xy 139.132056 -256.211578) (xy 139.400135 -256.479657) (xy 141.379325 -256.479657)
			(xy 141.379325 -256.425143) (xy 141.387084 -256.371183) (xy 141.402444 -256.318878) (xy 141.425091 -256.26929)
			(xy 141.454566 -256.223431) (xy 141.490268 -256.182234) (xy 141.53147 -256.146537) (xy 141.577332 -256.117068)
			(xy 141.626923 -256.094427) (xy 141.67923 -256.079074) (xy 141.733191 -256.071322) (xy 141.760448 -256.070862)
			(xy 141.786764 -256.071315) (xy 141.838897 -256.078537) (xy 141.889545 -256.092851) (xy 141.937747 -256.113985)
			(xy 141.982589 -256.14154) (xy 142.023221 -256.174993) (xy 142.041372 -256.194052) (xy 142.048909 -256.201436)
			(xy 142.068177 -256.209972) (xy 142.07871 -256.210562) (xy 142.153386 -256.210562) (xy 142.163938 -256.21005)
			(xy 142.183234 -256.201504) (xy 142.190724 -256.194052) (xy 142.208857 -256.174971) (xy 142.249477 -256.141491)
			(xy 142.294317 -256.113919) (xy 142.342525 -256.092781) (xy 142.393183 -256.078477) (xy 142.445328 -256.071281)
			(xy 142.471648 -256.070862) (xy 142.498895 -256.071411) (xy 142.552833 -256.079173) (xy 142.605118 -256.094531)
			(xy 142.654685 -256.117173) (xy 142.700526 -256.146638) (xy 142.741707 -256.182327) (xy 142.777391 -256.223513)
			(xy 142.80685 -256.269357) (xy 142.829486 -256.318927) (xy 142.844837 -256.371214) (xy 142.852592 -256.425153)
			(xy 142.852592 -256.479647) (xy 142.844837 -256.533586) (xy 142.829486 -256.585873) (xy 142.80685 -256.635443)
			(xy 142.777391 -256.681287) (xy 142.741707 -256.722473) (xy 142.700526 -256.758162) (xy 142.654685 -256.787627)
			(xy 142.605118 -256.810269) (xy 142.552833 -256.825627) (xy 142.498895 -256.833389) (xy 142.471648 -256.833878)
			(xy 142.445331 -256.833446) (xy 142.393196 -256.826223) (xy 142.342547 -256.811906) (xy 142.294345 -256.790768)
			(xy 142.249504 -256.763208) (xy 142.208873 -256.72975) (xy 142.190724 -256.710688) (xy 142.183197 -256.703293)
			(xy 142.163921 -256.694765) (xy 142.153386 -256.694178) (xy 142.07871 -256.694178) (xy 142.06816 -256.694705)
			(xy 142.048865 -256.703242) (xy 142.041372 -256.710688) (xy 142.023249 -256.729779) (xy 141.982626 -256.763256)
			(xy 141.937783 -256.790825) (xy 141.889573 -256.811962) (xy 141.838914 -256.826264) (xy 141.786768 -256.833459)
			(xy 141.760448 -256.833878) (xy 141.733191 -256.833478) (xy 141.67923 -256.825726) (xy 141.626923 -256.810373)
			(xy 141.577332 -256.787732) (xy 141.53147 -256.758263) (xy 141.490268 -256.722566) (xy 141.454566 -256.681369)
			(xy 141.425091 -256.63551) (xy 141.402444 -256.585923) (xy 141.387084 -256.533617) (xy 141.379325 -256.479657)
			(xy 139.400135 -256.479657) (xy 140.058394 -257.137916) (xy 150.396194 -257.137916) (xy 150.396746 -257.108534)
			(xy 150.405774 -257.050468) (xy 150.423604 -256.994474) (xy 150.449813 -256.941879) (xy 150.483782 -256.893927)
			(xy 150.524705 -256.851754) (xy 150.547832 -256.833624) (xy 150.55723 -256.826258) (xy 150.567644 -256.805684)
			(xy 150.569168 -256.701798) (xy 150.559262 -256.680716) (xy 150.550118 -256.67335) (xy 150.528267 -256.655147)
			(xy 150.489727 -256.613328) (xy 150.45782 -256.566252) (xy 150.433253 -256.514962) (xy 150.41657 -256.460593)
			(xy 150.408142 -256.404351) (xy 150.407624 -256.375916) (xy 150.40811 -256.348665) (xy 150.415866 -256.294717)
			(xy 150.431221 -256.242422) (xy 150.453863 -256.192845) (xy 150.483329 -256.146995) (xy 150.51902 -256.105804)
			(xy 150.560211 -256.070113) (xy 150.606061 -256.040647) (xy 150.655638 -256.018005) (xy 150.707933 -256.00265)
			(xy 150.761881 -255.994894) (xy 150.816383 -255.994894) (xy 150.870331 -256.00265) (xy 150.922626 -256.018005)
			(xy 150.972203 -256.040647) (xy 151.018053 -256.070113) (xy 151.059244 -256.105804) (xy 151.094935 -256.146995)
			(xy 151.124401 -256.192845) (xy 151.147043 -256.242422) (xy 151.162398 -256.294717) (xy 151.170154 -256.348665)
			(xy 151.17064 -256.375916) (xy 151.170098 -256.405298) (xy 151.161066 -256.463364) (xy 151.143233 -256.519357)
			(xy 151.117022 -256.571952) (xy 151.083052 -256.619904) (xy 151.042129 -256.662077) (xy 151.019002 -256.680208)
			(xy 151.009604 -256.687574) (xy 150.99919 -256.708148) (xy 150.997666 -256.812034) (xy 151.007572 -256.833116)
			(xy 151.016716 -256.840482) (xy 151.038541 -256.858714) (xy 151.077082 -256.900528) (xy 151.108991 -256.947598)
			(xy 151.133562 -256.998883) (xy 151.15025 -257.053245) (xy 151.158687 -257.109483) (xy 151.15921 -257.137916)
			(xy 151.792684 -257.137916) (xy 151.796755 -257.082294) (xy 151.808881 -257.027857) (xy 151.828804 -256.975766)
			(xy 151.8561 -256.927131) (xy 151.890186 -256.882988) (xy 151.930335 -256.844279) (xy 151.975693 -256.811828)
			(xy 152.025293 -256.786327) (xy 152.078077 -256.76832) (xy 152.13292 -256.75819) (xy 152.188654 -256.756153)
			(xy 152.244091 -256.762253) (xy 152.298048 -256.776359) (xy 152.349377 -256.798171) (xy 152.396983 -256.827225)
			(xy 152.439851 -256.8629) (xy 152.477068 -256.904437) (xy 152.507841 -256.95095) (xy 152.531513 -257.001447)
			(xy 152.547581 -257.054854) (xy 152.555701 -257.11003) (xy 152.55621 -257.137916) (xy 152.555701 -257.165802)
			(xy 152.547581 -257.220978) (xy 152.531513 -257.274385) (xy 152.507841 -257.324882) (xy 152.477068 -257.371395)
			(xy 152.439851 -257.412932) (xy 152.396983 -257.448607) (xy 152.349377 -257.477661) (xy 152.298048 -257.499473)
			(xy 152.244091 -257.513579) (xy 152.188654 -257.519679) (xy 152.13292 -257.517642) (xy 152.078077 -257.507512)
			(xy 152.025293 -257.489505) (xy 151.975693 -257.464004) (xy 151.930335 -257.431553) (xy 151.890186 -257.392844)
			(xy 151.8561 -257.348701) (xy 151.828804 -257.300066) (xy 151.808881 -257.247975) (xy 151.796755 -257.193538)
			(xy 151.792684 -257.137916) (xy 151.15921 -257.137916) (xy 151.158724 -257.165167) (xy 151.150968 -257.219115)
			(xy 151.135613 -257.27141) (xy 151.112971 -257.320987) (xy 151.083505 -257.366837) (xy 151.047814 -257.408028)
			(xy 151.006623 -257.443719) (xy 150.960773 -257.473185) (xy 150.911196 -257.495827) (xy 150.858901 -257.511182)
			(xy 150.804953 -257.518938) (xy 150.750451 -257.518938) (xy 150.696503 -257.511182) (xy 150.644208 -257.495827)
			(xy 150.594631 -257.473185) (xy 150.548781 -257.443719) (xy 150.50759 -257.408028) (xy 150.471899 -257.366837)
			(xy 150.442433 -257.320987) (xy 150.419791 -257.27141) (xy 150.404436 -257.219115) (xy 150.39668 -257.165167)
			(xy 150.396194 -257.137916) (xy 140.058394 -257.137916) (xy 141.194536 -258.274058) (xy 144.86966 -258.274058)
			(xy 144.873731 -258.218436) (xy 144.885857 -258.163999) (xy 144.90578 -258.111908) (xy 144.933076 -258.063273)
			(xy 144.967162 -258.01913) (xy 145.007311 -257.980421) (xy 145.052669 -257.94797) (xy 145.102269 -257.922469)
			(xy 145.155053 -257.904462) (xy 145.209896 -257.894332) (xy 145.26563 -257.892295) (xy 145.321067 -257.898395)
			(xy 145.375024 -257.912501) (xy 145.426353 -257.934313) (xy 145.473959 -257.963367) (xy 145.516827 -257.999042)
			(xy 145.554044 -258.040579) (xy 145.584817 -258.087092) (xy 145.608489 -258.137589) (xy 145.624557 -258.190996)
			(xy 145.632677 -258.246172) (xy 145.633186 -258.274058) (xy 146.354798 -258.274058) (xy 146.358869 -258.218436)
			(xy 146.370995 -258.163999) (xy 146.390918 -258.111908) (xy 146.418214 -258.063273) (xy 146.4523 -258.01913)
			(xy 146.492449 -257.980421) (xy 146.537807 -257.94797) (xy 146.587407 -257.922469) (xy 146.640191 -257.904462)
			(xy 146.695034 -257.894332) (xy 146.750768 -257.892295) (xy 146.806205 -257.898395) (xy 146.860162 -257.912501)
			(xy 146.911491 -257.934313) (xy 146.959097 -257.963367) (xy 147.001965 -257.999042) (xy 147.039182 -258.040579)
			(xy 147.069955 -258.087092) (xy 147.093627 -258.137589) (xy 147.109695 -258.190996) (xy 147.117815 -258.246172)
			(xy 147.118324 -258.274058) (xy 147.117815 -258.301944) (xy 147.109695 -258.35712) (xy 147.093627 -258.410527)
			(xy 147.069955 -258.461024) (xy 147.039182 -258.507537) (xy 147.001965 -258.549074) (xy 146.959097 -258.584749)
			(xy 146.911491 -258.613803) (xy 146.860162 -258.635615) (xy 146.806205 -258.649721) (xy 146.750768 -258.655821)
			(xy 146.695034 -258.653784) (xy 146.640191 -258.643654) (xy 146.587407 -258.625647) (xy 146.537807 -258.600146)
			(xy 146.492449 -258.567695) (xy 146.4523 -258.528986) (xy 146.418214 -258.484843) (xy 146.390918 -258.436208)
			(xy 146.370995 -258.384117) (xy 146.358869 -258.32968) (xy 146.354798 -258.274058) (xy 145.633186 -258.274058)
			(xy 145.632677 -258.301944) (xy 145.624557 -258.35712) (xy 145.608489 -258.410527) (xy 145.584817 -258.461024)
			(xy 145.554044 -258.507537) (xy 145.516827 -258.549074) (xy 145.473959 -258.584749) (xy 145.426353 -258.613803)
			(xy 145.375024 -258.635615) (xy 145.321067 -258.649721) (xy 145.26563 -258.655821) (xy 145.209896 -258.653784)
			(xy 145.155053 -258.643654) (xy 145.102269 -258.625647) (xy 145.052669 -258.600146) (xy 145.007311 -258.567695)
			(xy 144.967162 -258.528986) (xy 144.933076 -258.484843) (xy 144.90578 -258.436208) (xy 144.885857 -258.384117)
			(xy 144.873731 -258.32968) (xy 144.86966 -258.274058) (xy 141.194536 -258.274058) (xy 141.252194 -258.331716)
			(xy 141.275353 -258.35563) (xy 141.315899 -258.40843) (xy 141.349213 -258.466066) (xy 141.374725 -258.527555)
			(xy 141.392001 -258.591846) (xy 141.400745 -258.657841) (xy 141.401292 -258.691126) (xy 141.400845 -258.721852)
			(xy 141.393433 -258.782856) (xy 141.378719 -258.842522) (xy 141.35692 -258.899978) (xy 141.328353 -258.954387)
			(xy 141.293434 -259.004955) (xy 141.252673 -259.050944) (xy 141.206664 -259.091683) (xy 141.15608 -259.126578)
			(xy 141.101657 -259.15512) (xy 141.044191 -259.176892) (xy 140.984518 -259.191576) (xy 140.923511 -259.198959)
			(xy 140.892784 -259.19938) (xy 140.859506 -259.198835) (xy 140.793519 -259.19015) (xy 140.729229 -259.172928)
			(xy 140.667736 -259.147466) (xy 140.61009 -259.114199) (xy 140.557278 -259.073695) (xy 140.533374 -259.050536)
			(xy 138.995912 -257.513328) (xy 138.989275 -257.507206) (xy 138.972886 -257.499655) (xy 138.954898 -257.498231)
			(xy 138.946128 -257.500374) (xy 138.847322 -257.528314) (xy 138.828272 -257.54838) (xy 138.825224 -257.561842)
			(xy 138.818197 -257.589361) (xy 138.797109 -257.642095) (xy 138.768433 -257.691119) (xy 138.732805 -257.735349)
			(xy 138.691013 -257.773806) (xy 138.643979 -257.805641) (xy 138.592745 -257.830149) (xy 138.538443 -257.846789)
			(xy 138.482273 -257.855193) (xy 138.453876 -257.85572) (xy 138.426626 -257.855233) (xy 138.37268 -257.847473)
			(xy 138.320387 -257.832116) (xy 138.270812 -257.809474) (xy 138.224964 -257.780007) (xy 138.183776 -257.744316)
			(xy 138.148086 -257.703126) (xy 138.11862 -257.657277) (xy 138.09598 -257.607702) (xy 138.080624 -257.555408)
			(xy 138.072867 -257.501462) (xy 138.072368 -257.474212) (xy 138.072922 -257.444937) (xy 138.081904 -257.387079)
			(xy 138.099612 -257.331271) (xy 138.125633 -257.27882) (xy 138.159356 -257.230956) (xy 138.19999 -257.1888)
			(xy 138.22299 -257.170682) (xy 138.232388 -257.163316) (xy 138.242802 -257.142234) (xy 138.242802 -257.130296)
			(xy 138.242313 -257.120289) (xy 138.234653 -257.101798) (xy 138.2205 -257.087646) (xy 138.202009 -257.079986)
			(xy 138.192002 -257.079496) (xy 138.084814 -257.079496) (xy 138.055127 -257.079065) (xy 137.996159 -257.072126)
			(xy 137.938401 -257.058363) (xy 137.88264 -257.037965) (xy 137.829635 -257.01121) (xy 137.804652 -256.995168)
			(xy 137.792968 -256.987548) (xy 137.765028 -256.986278) (xy 137.673842 -257.0353) (xy 137.665985 -257.039979)
			(xy 137.653979 -257.053755) (xy 137.64757 -257.070867) (xy 137.647172 -257.080004) (xy 137.647172 -258.260596)
			(xy 137.669778 -258.288536) (xy 137.687558 -258.292092) (xy 137.714233 -258.298235) (xy 137.765607 -258.317132)
			(xy 137.813754 -258.343174) (xy 137.857688 -258.375826) (xy 137.896508 -258.414419) (xy 137.929417 -258.458161)
			(xy 137.95574 -258.506155) (xy 137.974938 -258.557417) (xy 137.986617 -258.610896) (xy 137.989423 -258.649978)
			(xy 139.02639 -258.649978) (xy 139.030461 -258.594356) (xy 139.042587 -258.539919) (xy 139.06251 -258.487828)
			(xy 139.089806 -258.439193) (xy 139.123892 -258.39505) (xy 139.164041 -258.356341) (xy 139.209399 -258.32389)
			(xy 139.258999 -258.298389) (xy 139.311783 -258.280382) (xy 139.366626 -258.270252) (xy 139.42236 -258.268215)
			(xy 139.477797 -258.274315) (xy 139.531754 -258.288421) (xy 139.583083 -258.310233) (xy 139.630689 -258.339287)
			(xy 139.673557 -258.374962) (xy 139.710774 -258.416499) (xy 139.741547 -258.463012) (xy 139.765219 -258.513509)
			(xy 139.781287 -258.566916) (xy 139.789407 -258.622092) (xy 139.789916 -258.649978) (xy 139.789407 -258.677864)
			(xy 139.781287 -258.73304) (xy 139.765219 -258.786447) (xy 139.741547 -258.836944) (xy 139.710774 -258.883457)
			(xy 139.673557 -258.924994) (xy 139.630689 -258.960669) (xy 139.583083 -258.989723) (xy 139.531754 -259.011535)
			(xy 139.477797 -259.025641) (xy 139.42236 -259.031741) (xy 139.366626 -259.029704) (xy 139.311783 -259.019574)
			(xy 139.258999 -259.001567) (xy 139.209399 -258.976066) (xy 139.164041 -258.943615) (xy 139.123892 -258.904906)
			(xy 139.089806 -258.860763) (xy 139.06251 -258.812128) (xy 139.042587 -258.760037) (xy 139.030461 -258.7056)
			(xy 139.02639 -258.649978) (xy 137.989423 -258.649978) (xy 137.990537 -258.665494) (xy 137.986619 -258.720093)
			(xy 137.974941 -258.773572) (xy 137.955745 -258.824834) (xy 137.929423 -258.872829) (xy 137.896515 -258.916572)
			(xy 137.857697 -258.955166) (xy 137.813764 -258.987819) (xy 137.765617 -259.013863) (xy 137.714245 -259.032762)
			(xy 137.687558 -259.038852) (xy 137.669778 -259.042408) (xy 137.647172 -259.070348) (xy 137.647172 -260.12902)
			(xy 137.647663 -260.139027) (xy 137.655325 -260.157517) (xy 137.669476 -260.17167) (xy 137.687965 -260.179335)
			(xy 137.697972 -260.17982) (xy 138.093196 -260.17982) (xy 138.103947 -260.179346) (xy 138.123561 -260.170537)
			(xy 138.131042 -260.162802) (xy 138.188954 -260.098794) (xy 138.195558 -260.078474) (xy 138.194288 -260.067552)
			(xy 138.193321 -260.057611) (xy 138.192305 -260.037662) (xy 138.192256 -260.027674) (xy 138.192742 -260.000423)
			(xy 138.200498 -259.946475) (xy 138.215853 -259.89418) (xy 138.238495 -259.844603) (xy 138.267961 -259.798753)
			(xy 138.303652 -259.757562) (xy 138.344843 -259.721871) (xy 138.390693 -259.692405) (xy 138.44027 -259.669763)
			(xy 138.492565 -259.654408) (xy 138.546513 -259.646652) (xy 138.601015 -259.646652) (xy 138.654963 -259.654408)
			(xy 138.707258 -259.669763) (xy 138.756835 -259.692405) (xy 138.802685 -259.721871) (xy 138.843876 -259.757562)
			(xy 138.879567 -259.798753) (xy 138.909033 -259.844603) (xy 138.931675 -259.89418) (xy 138.94703 -259.946475)
			(xy 138.954786 -260.000423) (xy 138.955272 -260.027674) (xy 138.955218 -260.037662) (xy 138.9542 -260.05761)
			(xy 138.95324 -260.067552) (xy 138.95197 -260.078474) (xy 138.958574 -260.098794) (xy 139.016486 -260.162802)
			(xy 139.02405 -260.170426) (xy 139.043609 -260.179233) (xy 139.054332 -260.17982) (xy 139.311888 -260.17982)
			(xy 139.321877 -260.179285) (xy 139.340314 -260.171577) (xy 139.347702 -260.164834) (xy 139.783312 -259.72897)
			(xy 139.806029 -259.70695) (xy 139.856221 -259.668435) (xy 139.911013 -259.636803) (xy 139.969467 -259.612598)
			(xy 140.030581 -259.596234) (xy 140.093308 -259.58799) (xy 140.124942 -259.587492) (xy 140.156565 -259.58799)
			(xy 140.21927 -259.596253) (xy 140.280358 -259.612634) (xy 140.338785 -259.63685) (xy 140.39355 -259.668488)
			(xy 140.443714 -259.707005) (xy 140.488421 -259.751743) (xy 140.526903 -259.801935) (xy 140.558502 -259.856722)
			(xy 140.582676 -259.915166) (xy 140.599013 -259.976266) (xy 140.607232 -260.038976) (xy 140.607796 -260.0706)
			(xy 140.60738 -260.096762) (xy 143.758918 -260.096762) (xy 143.762989 -260.04114) (xy 143.775115 -259.986703)
			(xy 143.795038 -259.934612) (xy 143.822334 -259.885977) (xy 143.85642 -259.841834) (xy 143.896569 -259.803125)
			(xy 143.941927 -259.770674) (xy 143.991527 -259.745173) (xy 144.044311 -259.727166) (xy 144.099154 -259.717036)
			(xy 144.154888 -259.714999) (xy 144.210325 -259.721099) (xy 144.264282 -259.735205) (xy 144.315611 -259.757017)
			(xy 144.363217 -259.786071) (xy 144.406085 -259.821746) (xy 144.443302 -259.863283) (xy 144.474075 -259.909796)
			(xy 144.497747 -259.960293) (xy 144.513815 -260.0137) (xy 144.521935 -260.068876) (xy 144.522444 -260.096762)
			(xy 144.521935 -260.124648) (xy 144.513815 -260.179824) (xy 144.497747 -260.233231) (xy 144.474075 -260.283728)
			(xy 144.443302 -260.330241) (xy 144.436067 -260.338316) (xy 150.396194 -260.338316) (xy 150.396746 -260.308934)
			(xy 150.405774 -260.250868) (xy 150.423604 -260.194874) (xy 150.449813 -260.142279) (xy 150.483782 -260.094327)
			(xy 150.524705 -260.052154) (xy 150.547832 -260.034024) (xy 150.55723 -260.026658) (xy 150.567644 -260.006084)
			(xy 150.569168 -259.902198) (xy 150.559262 -259.881116) (xy 150.550118 -259.87375) (xy 150.528267 -259.855547)
			(xy 150.489727 -259.813728) (xy 150.45782 -259.766652) (xy 150.433253 -259.715362) (xy 150.41657 -259.660993)
			(xy 150.408142 -259.604751) (xy 150.407624 -259.576316) (xy 150.40811 -259.549065) (xy 150.415866 -259.495117)
			(xy 150.431221 -259.442822) (xy 150.453863 -259.393245) (xy 150.483329 -259.347395) (xy 150.51902 -259.306204)
			(xy 150.560211 -259.270513) (xy 150.606061 -259.241047) (xy 150.655638 -259.218405) (xy 150.707933 -259.20305)
			(xy 150.761881 -259.195294) (xy 150.816383 -259.195294) (xy 150.870331 -259.20305) (xy 150.922626 -259.218405)
			(xy 150.972203 -259.241047) (xy 151.018053 -259.270513) (xy 151.059244 -259.306204) (xy 151.094935 -259.347395)
			(xy 151.124401 -259.393245) (xy 151.147043 -259.442822) (xy 151.162398 -259.495117) (xy 151.170154 -259.549065)
			(xy 151.17064 -259.576316) (xy 151.170098 -259.605698) (xy 151.161066 -259.663764) (xy 151.143233 -259.719757)
			(xy 151.117022 -259.772352) (xy 151.083052 -259.820304) (xy 151.042129 -259.862477) (xy 151.019002 -259.880608)
			(xy 151.009604 -259.887974) (xy 150.99919 -259.908548) (xy 150.997666 -260.012434) (xy 151.007572 -260.033516)
			(xy 151.016716 -260.040882) (xy 151.038541 -260.059114) (xy 151.077082 -260.100928) (xy 151.108991 -260.147998)
			(xy 151.133562 -260.199283) (xy 151.15025 -260.253645) (xy 151.158687 -260.309883) (xy 151.15921 -260.338316)
			(xy 151.792684 -260.338316) (xy 151.796755 -260.282694) (xy 151.808881 -260.228257) (xy 151.828804 -260.176166)
			(xy 151.8561 -260.127531) (xy 151.890186 -260.083388) (xy 151.930335 -260.044679) (xy 151.975693 -260.012228)
			(xy 152.025293 -259.986727) (xy 152.078077 -259.96872) (xy 152.13292 -259.95859) (xy 152.188654 -259.956553)
			(xy 152.244091 -259.962653) (xy 152.298048 -259.976759) (xy 152.349377 -259.998571) (xy 152.396983 -260.027625)
			(xy 152.439851 -260.0633) (xy 152.477068 -260.104837) (xy 152.507841 -260.15135) (xy 152.531513 -260.201847)
			(xy 152.547581 -260.255254) (xy 152.555701 -260.31043) (xy 152.55621 -260.338316) (xy 152.555701 -260.366202)
			(xy 152.547581 -260.421378) (xy 152.531513 -260.474785) (xy 152.507841 -260.525282) (xy 152.477068 -260.571795)
			(xy 152.439851 -260.613332) (xy 152.396983 -260.649007) (xy 152.349377 -260.678061) (xy 152.298048 -260.699873)
			(xy 152.244091 -260.713979) (xy 152.188654 -260.720079) (xy 152.13292 -260.718042) (xy 152.078077 -260.707912)
			(xy 152.025293 -260.689905) (xy 151.975693 -260.664404) (xy 151.930335 -260.631953) (xy 151.890186 -260.593244)
			(xy 151.8561 -260.549101) (xy 151.828804 -260.500466) (xy 151.808881 -260.448375) (xy 151.796755 -260.393938)
			(xy 151.792684 -260.338316) (xy 151.15921 -260.338316) (xy 151.158724 -260.365567) (xy 151.150968 -260.419515)
			(xy 151.135613 -260.47181) (xy 151.112971 -260.521387) (xy 151.083505 -260.567237) (xy 151.047814 -260.608428)
			(xy 151.006623 -260.644119) (xy 150.960773 -260.673585) (xy 150.911196 -260.696227) (xy 150.858901 -260.711582)
			(xy 150.804953 -260.719338) (xy 150.750451 -260.719338) (xy 150.696503 -260.711582) (xy 150.644208 -260.696227)
			(xy 150.594631 -260.673585) (xy 150.548781 -260.644119) (xy 150.50759 -260.608428) (xy 150.471899 -260.567237)
			(xy 150.442433 -260.521387) (xy 150.419791 -260.47181) (xy 150.404436 -260.419515) (xy 150.39668 -260.365567)
			(xy 150.396194 -260.338316) (xy 144.436067 -260.338316) (xy 144.406085 -260.371778) (xy 144.363217 -260.407453)
			(xy 144.315611 -260.436507) (xy 144.264282 -260.458319) (xy 144.210325 -260.472425) (xy 144.154888 -260.478525)
			(xy 144.099154 -260.476488) (xy 144.044311 -260.466358) (xy 143.991527 -260.448351) (xy 143.941927 -260.42285)
			(xy 143.896569 -260.390399) (xy 143.85642 -260.35169) (xy 143.822334 -260.307547) (xy 143.795038 -260.258912)
			(xy 143.775115 -260.206821) (xy 143.762989 -260.152384) (xy 143.758918 -260.096762) (xy 140.60738 -260.096762)
			(xy 140.607293 -260.102222) (xy 140.59907 -260.164929) (xy 140.582737 -260.226027) (xy 140.558574 -260.284473)
			(xy 140.526994 -260.339268) (xy 140.488537 -260.389475) (xy 140.466572 -260.41223) (xy 139.874498 -261.004304)
			(xy 139.851772 -261.026303) (xy 139.801568 -261.064778) (xy 139.74677 -261.09637) (xy 139.688318 -261.120538)
			(xy 139.62721 -261.136868) (xy 139.564494 -261.145082) (xy 139.532868 -261.145528) (xy 137.697972 -261.145528)
			(xy 137.68797 -261.146021) (xy 137.669493 -261.153687) (xy 137.655355 -261.16784) (xy 137.64771 -261.186326)
			(xy 137.647172 -261.196328) (xy 137.647172 -261.79025) (xy 141.61948 -261.79025) (xy 141.61948 -261.73575)
			(xy 141.627236 -261.681804) (xy 141.64259 -261.629512) (xy 141.665229 -261.579936) (xy 141.694693 -261.534087)
			(xy 141.730382 -261.492898) (xy 141.771569 -261.457206) (xy 141.817417 -261.42774) (xy 141.866991 -261.405097)
			(xy 141.919283 -261.38974) (xy 141.973228 -261.381981) (xy 142.000478 -261.381494) (xy 142.029396 -261.381992)
			(xy 142.08657 -261.39072) (xy 142.141771 -261.40798) (xy 142.193733 -261.433375) (xy 142.241266 -261.466324)
			(xy 142.28328 -261.506071) (xy 142.301468 -261.52856) (xy 142.309038 -261.537313) (xy 142.329791 -261.547499)
			(xy 142.341346 -261.548118) (xy 142.42161 -261.548118) (xy 142.433178 -261.547547) (xy 142.453948 -261.537352)
			(xy 142.461488 -261.52856) (xy 142.479676 -261.506074) (xy 142.521697 -261.466341) (xy 142.569233 -261.433403)
			(xy 142.621195 -261.408016) (xy 142.676393 -261.390759) (xy 142.733562 -261.38203) (xy 142.762478 -261.381494)
			(xy 142.788259 -261.381921) (xy 142.839351 -261.388863) (xy 142.889043 -261.402624) (xy 142.936429 -261.422951)
			(xy 142.980645 -261.449476) (xy 143.020886 -261.481715) (xy 143.056417 -261.51908) (xy 143.07185 -261.539736)
			(xy 143.078708 -261.549388) (xy 143.099282 -261.56031) (xy 143.203168 -261.56412) (xy 143.224504 -261.554722)
			(xy 143.232124 -261.545578) (xy 143.250359 -261.524629) (xy 143.291834 -261.487692) (xy 143.338226 -261.457159)
			(xy 143.388556 -261.433676) (xy 143.441758 -261.417737) (xy 143.496709 -261.409682) (xy 143.524478 -261.40918)
			(xy 143.553396 -261.409684) (xy 143.610569 -261.418411) (xy 143.66577 -261.43567) (xy 143.717732 -261.461064)
			(xy 143.765265 -261.494012) (xy 143.80728 -261.533758) (xy 143.825468 -261.556246) (xy 143.83304 -261.564997)
			(xy 143.853791 -261.575184) (xy 143.865346 -261.575804) (xy 143.94561 -261.575804) (xy 143.957178 -261.575238)
			(xy 143.977949 -261.56504) (xy 143.985488 -261.556246) (xy 144.003672 -261.533757) (xy 144.045695 -261.494025)
			(xy 144.093232 -261.461088) (xy 144.145194 -261.435701) (xy 144.200392 -261.418445) (xy 144.257562 -261.409716)
			(xy 144.286478 -261.40918) (xy 144.313731 -261.409666) (xy 144.367683 -261.41742) (xy 144.419981 -261.432774)
			(xy 144.469563 -261.455414) (xy 144.499198 -261.474458) (xy 144.86966 -261.474458) (xy 144.873731 -261.418836)
			(xy 144.885857 -261.364399) (xy 144.90578 -261.312308) (xy 144.933076 -261.263673) (xy 144.967162 -261.21953)
			(xy 145.007311 -261.180821) (xy 145.052669 -261.14837) (xy 145.102269 -261.122869) (xy 145.155053 -261.104862)
			(xy 145.209896 -261.094732) (xy 145.26563 -261.092695) (xy 145.321067 -261.098795) (xy 145.375024 -261.112901)
			(xy 145.426353 -261.134713) (xy 145.473959 -261.163767) (xy 145.516827 -261.199442) (xy 145.554044 -261.240979)
			(xy 145.584817 -261.287492) (xy 145.608489 -261.337989) (xy 145.624557 -261.391396) (xy 145.632677 -261.446572)
			(xy 145.633186 -261.474458) (xy 146.354798 -261.474458) (xy 146.358869 -261.418836) (xy 146.370995 -261.364399)
			(xy 146.390918 -261.312308) (xy 146.418214 -261.263673) (xy 146.4523 -261.21953) (xy 146.492449 -261.180821)
			(xy 146.537807 -261.14837) (xy 146.587407 -261.122869) (xy 146.640191 -261.104862) (xy 146.695034 -261.094732)
			(xy 146.750768 -261.092695) (xy 146.806205 -261.098795) (xy 146.860162 -261.112901) (xy 146.911491 -261.134713)
			(xy 146.959097 -261.163767) (xy 147.001965 -261.199442) (xy 147.039182 -261.240979) (xy 147.069955 -261.287492)
			(xy 147.093627 -261.337989) (xy 147.109695 -261.391396) (xy 147.117815 -261.446572) (xy 147.118324 -261.474458)
			(xy 147.117815 -261.502344) (xy 147.109695 -261.55752) (xy 147.093627 -261.610927) (xy 147.069955 -261.661424)
			(xy 147.039182 -261.707937) (xy 147.001965 -261.749474) (xy 146.959097 -261.785149) (xy 146.911491 -261.814203)
			(xy 146.860162 -261.836015) (xy 146.806205 -261.850121) (xy 146.750768 -261.856221) (xy 146.695034 -261.854184)
			(xy 146.640191 -261.844054) (xy 146.587407 -261.826047) (xy 146.537807 -261.800546) (xy 146.492449 -261.768095)
			(xy 146.4523 -261.729386) (xy 146.418214 -261.685243) (xy 146.390918 -261.636608) (xy 146.370995 -261.584517)
			(xy 146.358869 -261.53008) (xy 146.354798 -261.474458) (xy 145.633186 -261.474458) (xy 145.632677 -261.502344)
			(xy 145.624557 -261.55752) (xy 145.608489 -261.610927) (xy 145.584817 -261.661424) (xy 145.554044 -261.707937)
			(xy 145.516827 -261.749474) (xy 145.473959 -261.785149) (xy 145.426353 -261.814203) (xy 145.375024 -261.836015)
			(xy 145.321067 -261.850121) (xy 145.26563 -261.856221) (xy 145.209896 -261.854184) (xy 145.155053 -261.844054)
			(xy 145.102269 -261.826047) (xy 145.052669 -261.800546) (xy 145.007311 -261.768095) (xy 144.967162 -261.729386)
			(xy 144.933076 -261.685243) (xy 144.90578 -261.636608) (xy 144.885857 -261.584517) (xy 144.873731 -261.53008)
			(xy 144.86966 -261.474458) (xy 144.499198 -261.474458) (xy 144.515417 -261.484881) (xy 144.556611 -261.520573)
			(xy 144.592306 -261.561765) (xy 144.621775 -261.607618) (xy 144.644419 -261.657198) (xy 144.659775 -261.709496)
			(xy 144.667533 -261.763447) (xy 144.667533 -261.817953) (xy 144.659775 -261.871904) (xy 144.644419 -261.924202)
			(xy 144.621775 -261.973782) (xy 144.592306 -262.019635) (xy 144.556611 -262.060827) (xy 144.515417 -262.096519)
			(xy 144.469563 -262.125986) (xy 144.419981 -262.148626) (xy 144.367683 -262.16398) (xy 144.313731 -262.171734)
			(xy 144.286478 -262.172196) (xy 144.257563 -262.171623) (xy 144.200394 -262.162906) (xy 144.145197 -262.145659)
			(xy 144.093235 -262.120277) (xy 144.045699 -262.087343) (xy 144.00368 -262.047611) (xy 143.985488 -262.02513)
			(xy 143.977939 -262.016355) (xy 143.95717 -262.006182) (xy 143.94561 -262.005572) (xy 143.865346 -262.005572)
			(xy 143.853778 -262.006144) (xy 143.833005 -262.016335) (xy 143.825468 -262.02513) (xy 143.807303 -262.047635)
			(xy 143.765277 -262.087368) (xy 143.717736 -262.120303) (xy 143.66577 -262.145688) (xy 143.610568 -262.162939)
			(xy 143.553395 -262.171664) (xy 143.524478 -262.172196) (xy 143.498698 -262.171731) (xy 143.447607 -262.164796)
			(xy 143.397916 -262.151043) (xy 143.35053 -262.130721) (xy 143.306314 -262.104202) (xy 143.266072 -262.071968)
			(xy 143.230539 -262.034608) (xy 143.215106 -262.013954) (xy 143.208248 -262.004302) (xy 143.187674 -261.99338)
			(xy 143.083788 -261.98957) (xy 143.062452 -261.998968) (xy 143.054832 -262.008112) (xy 143.036618 -262.02908)
			(xy 142.995138 -262.066016) (xy 142.948742 -262.096546) (xy 142.898409 -262.120027) (xy 142.845203 -262.135961)
			(xy 142.790248 -262.144011) (xy 142.762478 -262.14451) (xy 142.733561 -262.14397) (xy 142.67639 -262.13525)
			(xy 142.62119 -262.117999) (xy 142.569227 -262.092611) (xy 142.521693 -262.05967) (xy 142.479677 -262.019929)
			(xy 142.461488 -261.997444) (xy 142.453937 -261.988672) (xy 142.43317 -261.978496) (xy 142.42161 -261.977886)
			(xy 142.341346 -261.977886) (xy 142.329782 -261.978488) (xy 142.309011 -261.988661) (xy 142.301468 -261.997444)
			(xy 142.283306 -262.019952) (xy 142.241279 -262.059684) (xy 142.193738 -262.092618) (xy 142.141771 -262.118002)
			(xy 142.086569 -262.135254) (xy 142.029396 -262.143978) (xy 142.000478 -262.14451) (xy 141.973228 -262.144019)
			(xy 141.919283 -262.13626) (xy 141.866991 -262.120903) (xy 141.817417 -262.09826) (xy 141.771569 -262.068794)
			(xy 141.730382 -262.033102) (xy 141.694693 -261.991913) (xy 141.665229 -261.946064) (xy 141.64259 -261.896488)
			(xy 141.627236 -261.844196) (xy 141.61948 -261.79025) (xy 137.647172 -261.79025) (xy 137.647172 -262.847836)
			(xy 148.939502 -262.847836) (xy 148.943573 -262.792214) (xy 148.955699 -262.737777) (xy 148.975622 -262.685686)
			(xy 149.002918 -262.637051) (xy 149.037004 -262.592908) (xy 149.077153 -262.554199) (xy 149.122511 -262.521748)
			(xy 149.172111 -262.496247) (xy 149.224895 -262.47824) (xy 149.279738 -262.46811) (xy 149.335472 -262.466073)
			(xy 149.390909 -262.472173) (xy 149.444866 -262.486279) (xy 149.496195 -262.508091) (xy 149.543801 -262.537145)
			(xy 149.586669 -262.57282) (xy 149.623886 -262.614357) (xy 149.654659 -262.66087) (xy 149.678331 -262.711367)
			(xy 149.694399 -262.764774) (xy 149.702519 -262.81995) (xy 149.703028 -262.847836) (xy 149.702519 -262.875722)
			(xy 149.694399 -262.930898) (xy 149.678331 -262.984305) (xy 149.654659 -263.034802) (xy 149.623886 -263.081315)
			(xy 149.586669 -263.122852) (xy 149.543801 -263.158527) (xy 149.496195 -263.187581) (xy 149.444866 -263.209393)
			(xy 149.390909 -263.223499) (xy 149.335472 -263.229599) (xy 149.279738 -263.227562) (xy 149.224895 -263.217432)
			(xy 149.172111 -263.199425) (xy 149.122511 -263.173924) (xy 149.077153 -263.141473) (xy 149.037004 -263.102764)
			(xy 149.002918 -263.058621) (xy 148.975622 -263.009986) (xy 148.955699 -262.957895) (xy 148.943573 -262.903458)
			(xy 148.939502 -262.847836) (xy 137.647172 -262.847836) (xy 137.647172 -263.37768) (xy 154.048204 -263.37768)
			(xy 154.052275 -263.322058) (xy 154.064401 -263.267621) (xy 154.084324 -263.21553) (xy 154.11162 -263.166895)
			(xy 154.145706 -263.122752) (xy 154.185855 -263.084043) (xy 154.231213 -263.051592) (xy 154.280813 -263.026091)
			(xy 154.333597 -263.008084) (xy 154.38844 -262.997954) (xy 154.444174 -262.995917) (xy 154.499611 -263.002017)
			(xy 154.553568 -263.016123) (xy 154.604897 -263.037935) (xy 154.652503 -263.066989) (xy 154.695371 -263.102664)
			(xy 154.732588 -263.144201) (xy 154.763361 -263.190714) (xy 154.787033 -263.241211) (xy 154.803101 -263.294618)
			(xy 154.811221 -263.349794) (xy 154.81173 -263.37768) (xy 154.811221 -263.405566) (xy 154.803101 -263.460742)
			(xy 154.787033 -263.514149) (xy 154.763361 -263.564646) (xy 154.732588 -263.611159) (xy 154.695371 -263.652696)
			(xy 154.652503 -263.688371) (xy 154.604897 -263.717425) (xy 154.553568 -263.739237) (xy 154.499611 -263.753343)
			(xy 154.444174 -263.759443) (xy 154.38844 -263.757406) (xy 154.333597 -263.747276) (xy 154.280813 -263.729269)
			(xy 154.231213 -263.703768) (xy 154.185855 -263.671317) (xy 154.145706 -263.632608) (xy 154.11162 -263.588465)
			(xy 154.084324 -263.53983) (xy 154.064401 -263.487739) (xy 154.052275 -263.433302) (xy 154.048204 -263.37768)
			(xy 137.647172 -263.37768) (xy 137.647172 -264.643616) (xy 153.652218 -264.643616) (xy 153.656289 -264.587994)
			(xy 153.668415 -264.533557) (xy 153.688338 -264.481466) (xy 153.715634 -264.432831) (xy 153.74972 -264.388688)
			(xy 153.789869 -264.349979) (xy 153.835227 -264.317528) (xy 153.884827 -264.292027) (xy 153.937611 -264.27402)
			(xy 153.992454 -264.26389) (xy 154.048188 -264.261853) (xy 154.103625 -264.267953) (xy 154.157582 -264.282059)
			(xy 154.208911 -264.303871) (xy 154.256517 -264.332925) (xy 154.299385 -264.3686) (xy 154.336602 -264.410137)
			(xy 154.367375 -264.45665) (xy 154.391047 -264.507147) (xy 154.407115 -264.560554) (xy 154.415235 -264.61573)
			(xy 154.415744 -264.643616) (xy 154.415235 -264.671502) (xy 154.407115 -264.726678) (xy 154.391047 -264.780085)
			(xy 154.367375 -264.830582) (xy 154.336602 -264.877095) (xy 154.299385 -264.918632) (xy 154.256517 -264.954307)
			(xy 154.208911 -264.983361) (xy 154.157582 -265.005173) (xy 154.103625 -265.019279) (xy 154.048188 -265.025379)
			(xy 153.992454 -265.023342) (xy 153.937611 -265.013212) (xy 153.884827 -264.995205) (xy 153.835227 -264.969704)
			(xy 153.789869 -264.937253) (xy 153.74972 -264.898544) (xy 153.715634 -264.854401) (xy 153.688338 -264.805766)
			(xy 153.668415 -264.753675) (xy 153.656289 -264.699238) (xy 153.652218 -264.643616) (xy 137.647172 -264.643616)
			(xy 137.647172 -265.16457) (xy 156.563058 -265.16457) (xy 156.567129 -265.108948) (xy 156.579255 -265.054511)
			(xy 156.599178 -265.00242) (xy 156.626474 -264.953785) (xy 156.66056 -264.909642) (xy 156.700709 -264.870933)
			(xy 156.746067 -264.838482) (xy 156.795667 -264.812981) (xy 156.848451 -264.794974) (xy 156.903294 -264.784844)
			(xy 156.959028 -264.782807) (xy 157.014465 -264.788907) (xy 157.068422 -264.803013) (xy 157.119751 -264.824825)
			(xy 157.167357 -264.853879) (xy 157.210225 -264.889554) (xy 157.247442 -264.931091) (xy 157.278215 -264.977604)
			(xy 157.301887 -265.028101) (xy 157.317955 -265.081508) (xy 157.326075 -265.136684) (xy 157.326584 -265.16457)
			(xy 157.326075 -265.192456) (xy 157.317955 -265.247632) (xy 157.301887 -265.301039) (xy 157.278215 -265.351536)
			(xy 157.247442 -265.398049) (xy 157.210225 -265.439586) (xy 157.167357 -265.475261) (xy 157.119751 -265.504315)
			(xy 157.068422 -265.526127) (xy 157.014465 -265.540233) (xy 156.959028 -265.546333) (xy 156.903294 -265.544296)
			(xy 156.848451 -265.534166) (xy 156.795667 -265.516159) (xy 156.746067 -265.490658) (xy 156.700709 -265.458207)
			(xy 156.66056 -265.419498) (xy 156.626474 -265.375355) (xy 156.599178 -265.32672) (xy 156.579255 -265.274629)
			(xy 156.567129 -265.220192) (xy 156.563058 -265.16457) (xy 137.647172 -265.16457) (xy 137.647172 -266.517882)
			(xy 156.497018 -266.517882) (xy 156.501089 -266.46226) (xy 156.513215 -266.407823) (xy 156.533138 -266.355732)
			(xy 156.560434 -266.307097) (xy 156.59452 -266.262954) (xy 156.634669 -266.224245) (xy 156.680027 -266.191794)
			(xy 156.729627 -266.166293) (xy 156.782411 -266.148286) (xy 156.837254 -266.138156) (xy 156.892988 -266.136119)
			(xy 156.948425 -266.142219) (xy 157.002382 -266.156325) (xy 157.053711 -266.178137) (xy 157.101317 -266.207191)
			(xy 157.144185 -266.242866) (xy 157.181402 -266.284403) (xy 157.212175 -266.330916) (xy 157.235847 -266.381413)
			(xy 157.251915 -266.43482) (xy 157.260035 -266.489996) (xy 157.260544 -266.517882) (xy 157.260035 -266.545768)
			(xy 157.251915 -266.600944) (xy 157.235847 -266.654351) (xy 157.212175 -266.704848) (xy 157.181402 -266.751361)
			(xy 157.144185 -266.792898) (xy 157.101317 -266.828573) (xy 157.053711 -266.857627) (xy 157.002382 -266.879439)
			(xy 156.948425 -266.893545) (xy 156.892988 -266.899645) (xy 156.837254 -266.897608) (xy 156.782411 -266.887478)
			(xy 156.729627 -266.869471) (xy 156.680027 -266.84397) (xy 156.634669 -266.811519) (xy 156.59452 -266.77281)
			(xy 156.560434 -266.728667) (xy 156.533138 -266.680032) (xy 156.513215 -266.627941) (xy 156.501089 -266.573504)
			(xy 156.497018 -266.517882) (xy 137.647172 -266.517882) (xy 137.647172 -266.963398) (xy 154.756102 -266.963398)
			(xy 154.760173 -266.907776) (xy 154.772299 -266.853339) (xy 154.792222 -266.801248) (xy 154.819518 -266.752613)
			(xy 154.853604 -266.70847) (xy 154.893753 -266.669761) (xy 154.939111 -266.63731) (xy 154.988711 -266.611809)
			(xy 155.041495 -266.593802) (xy 155.096338 -266.583672) (xy 155.152072 -266.581635) (xy 155.207509 -266.587735)
			(xy 155.261466 -266.601841) (xy 155.312795 -266.623653) (xy 155.360401 -266.652707) (xy 155.403269 -266.688382)
			(xy 155.440486 -266.729919) (xy 155.471259 -266.776432) (xy 155.494931 -266.826929) (xy 155.510999 -266.880336)
			(xy 155.519119 -266.935512) (xy 155.519628 -266.963398) (xy 155.519119 -266.991284) (xy 155.510999 -267.04646)
			(xy 155.494931 -267.099867) (xy 155.471259 -267.150364) (xy 155.440486 -267.196877) (xy 155.403269 -267.238414)
			(xy 155.360401 -267.274089) (xy 155.312795 -267.303143) (xy 155.261466 -267.324955) (xy 155.207509 -267.339061)
			(xy 155.152072 -267.345161) (xy 155.096338 -267.343124) (xy 155.041495 -267.332994) (xy 154.988711 -267.314987)
			(xy 154.939111 -267.289486) (xy 154.893753 -267.257035) (xy 154.853604 -267.218326) (xy 154.819518 -267.174183)
			(xy 154.792222 -267.125548) (xy 154.772299 -267.073457) (xy 154.760173 -267.01902) (xy 154.756102 -266.963398)
			(xy 137.647172 -266.963398) (xy 137.647172 -267.578078) (xy 152.95321 -267.578078) (xy 152.957281 -267.522456)
			(xy 152.969407 -267.468019) (xy 152.98933 -267.415928) (xy 153.016626 -267.367293) (xy 153.050712 -267.32315)
			(xy 153.090861 -267.284441) (xy 153.136219 -267.25199) (xy 153.185819 -267.226489) (xy 153.238603 -267.208482)
			(xy 153.293446 -267.198352) (xy 153.34918 -267.196315) (xy 153.404617 -267.202415) (xy 153.458574 -267.216521)
			(xy 153.509903 -267.238333) (xy 153.557509 -267.267387) (xy 153.600377 -267.303062) (xy 153.637594 -267.344599)
			(xy 153.668367 -267.391112) (xy 153.692039 -267.441609) (xy 153.708107 -267.495016) (xy 153.716227 -267.550192)
			(xy 153.716736 -267.578078) (xy 153.716227 -267.605964) (xy 153.708107 -267.66114) (xy 153.692039 -267.714547)
			(xy 153.668367 -267.765044) (xy 153.637594 -267.811557) (xy 153.600377 -267.853094) (xy 153.557509 -267.888769)
			(xy 153.509903 -267.917823) (xy 153.458574 -267.939635) (xy 153.404617 -267.953741) (xy 153.34918 -267.959841)
			(xy 153.293446 -267.957804) (xy 153.238603 -267.947674) (xy 153.185819 -267.929667) (xy 153.136219 -267.904166)
			(xy 153.090861 -267.871715) (xy 153.050712 -267.833006) (xy 153.016626 -267.788863) (xy 152.98933 -267.740228)
			(xy 152.969407 -267.688137) (xy 152.957281 -267.6337) (xy 152.95321 -267.578078) (xy 137.647172 -267.578078)
			(xy 137.647172 -268.04366) (xy 137.646737 -268.053725) (xy 137.639004 -268.072311) (xy 137.632186 -268.079728)
			(xy 136.332722 -269.379192) (xy 136.325872 -269.386589) (xy 136.318131 -269.405187) (xy 136.317736 -269.41526)
			(xy 136.317736 -270.89989) (xy 142.982451 -270.89989) (xy 142.98644 -270.75135) (xy 142.998397 -270.603237)
			(xy 143.018287 -270.45598) (xy 143.046052 -270.310004) (xy 143.081613 -270.165727) (xy 143.124867 -270.023568)
			(xy 143.175689 -269.883935) (xy 143.233933 -269.747232) (xy 143.299431 -269.613852) (xy 143.371994 -269.48418)
			(xy 143.451412 -269.35859) (xy 143.537457 -269.237443) (xy 143.629881 -269.12109) (xy 143.728417 -269.009866)
			(xy 143.832781 -268.904091) (xy 143.942673 -268.804071) (xy 144.057774 -268.710093) (xy 144.177754 -268.622429)
			(xy 144.302267 -268.541332) (xy 144.430953 -268.467035) (xy 144.563442 -268.399753) (xy 144.699351 -268.339679)
			(xy 144.838289 -268.286987) (xy 144.979855 -268.241828) (xy 145.123641 -268.204333) (xy 145.269232 -268.174611)
			(xy 145.416208 -268.152746) (xy 145.564147 -268.138802) (xy 145.71262 -268.132818) (xy 145.861201 -268.134813)
			(xy 146.00946 -268.144781) (xy 146.156971 -268.162692) (xy 146.303307 -268.188495) (xy 146.448048 -268.222115)
			(xy 146.590775 -268.263457) (xy 146.731078 -268.3124) (xy 146.868551 -268.368803) (xy 147.002798 -268.432504)
			(xy 147.133433 -268.50332) (xy 147.260078 -268.581045) (xy 147.382368 -268.665456) (xy 147.499951 -268.756309)
			(xy 147.612488 -268.853343) (xy 147.719655 -268.956278) (xy 147.821142 -269.064817) (xy 147.916656 -269.178646)
			(xy 148.005923 -269.297439) (xy 148.088684 -269.420851) (xy 148.164702 -269.548529) (xy 148.233757 -269.680102)
			(xy 148.29565 -269.815193) (xy 148.350203 -269.95341) (xy 148.361422 -269.987014) (xy 155.308552 -269.987014)
			(xy 155.312623 -269.931392) (xy 155.324749 -269.876955) (xy 155.344672 -269.824864) (xy 155.371968 -269.776229)
			(xy 155.406054 -269.732086) (xy 155.446203 -269.693377) (xy 155.491561 -269.660926) (xy 155.541161 -269.635425)
			(xy 155.593945 -269.617418) (xy 155.648788 -269.607288) (xy 155.704522 -269.605251) (xy 155.759959 -269.611351)
			(xy 155.813916 -269.625457) (xy 155.865245 -269.647269) (xy 155.912851 -269.676323) (xy 155.955719 -269.711998)
			(xy 155.992936 -269.753535) (xy 156.023709 -269.800048) (xy 156.047381 -269.850545) (xy 156.063449 -269.903952)
			(xy 156.071569 -269.959128) (xy 156.072078 -269.987014) (xy 156.071569 -270.0149) (xy 156.063449 -270.070076)
			(xy 156.047381 -270.123483) (xy 156.023709 -270.17398) (xy 155.992936 -270.220493) (xy 155.955719 -270.26203)
			(xy 155.912851 -270.297705) (xy 155.865245 -270.326759) (xy 155.813916 -270.348571) (xy 155.759959 -270.362677)
			(xy 155.704522 -270.368777) (xy 155.648788 -270.36674) (xy 155.593945 -270.35661) (xy 155.541161 -270.338603)
			(xy 155.491561 -270.313102) (xy 155.446203 -270.280651) (xy 155.406054 -270.241942) (xy 155.371968 -270.197799)
			(xy 155.344672 -270.149164) (xy 155.324749 -270.097073) (xy 155.312623 -270.042636) (xy 155.308552 -269.987014)
			(xy 148.361422 -269.987014) (xy 148.397258 -270.094357) (xy 148.43668 -270.237627) (xy 148.468354 -270.382806)
			(xy 148.49219 -270.529475) (xy 148.508119 -270.677213) (xy 148.516095 -270.825593) (xy 148.516594 -270.89989)
			(xy 148.516095 -270.974187) (xy 148.508119 -271.122567) (xy 148.49219 -271.270305) (xy 148.468354 -271.416974)
			(xy 148.43668 -271.562153) (xy 148.397258 -271.705423) (xy 148.350203 -271.84637) (xy 148.29565 -271.984587)
			(xy 148.233757 -272.119678) (xy 148.164702 -272.251251) (xy 148.088684 -272.378929) (xy 148.005923 -272.502341)
			(xy 147.916656 -272.621134) (xy 147.913577 -272.624804) (xy 154.0693 -272.624804) (xy 154.07326 -272.57575)
			(xy 154.085037 -272.527966) (xy 154.104328 -272.48269) (xy 154.130631 -272.441094) (xy 154.163266 -272.404257)
			(xy 154.201387 -272.373132) (xy 154.244008 -272.348525) (xy 154.290024 -272.331073) (xy 154.338243 -272.321229)
			(xy 154.387418 -272.319248) (xy 154.436273 -272.32518) (xy 154.483544 -272.338872) (xy 154.528006 -272.35997)
			(xy 154.568509 -272.387926) (xy 154.604002 -272.422018) (xy 154.633567 -272.461362) (xy 154.656438 -272.504939)
			(xy 154.672022 -272.55162) (xy 154.679917 -272.600197) (xy 154.680412 -272.624804) (xy 155.96922 -272.624804)
			(xy 155.97318 -272.57575) (xy 155.984957 -272.527966) (xy 156.004248 -272.48269) (xy 156.030551 -272.441094)
			(xy 156.063186 -272.404257) (xy 156.101307 -272.373132) (xy 156.143928 -272.348525) (xy 156.189944 -272.331073)
			(xy 156.238163 -272.321229) (xy 156.287338 -272.319248) (xy 156.336193 -272.32518) (xy 156.383464 -272.338872)
			(xy 156.427926 -272.35997) (xy 156.468429 -272.387926) (xy 156.503922 -272.422018) (xy 156.533487 -272.461362)
			(xy 156.556358 -272.504939) (xy 156.571942 -272.55162) (xy 156.579837 -272.600197) (xy 156.580332 -272.624804)
			(xy 157.86914 -272.624804) (xy 157.8731 -272.57575) (xy 157.884877 -272.527966) (xy 157.904168 -272.48269)
			(xy 157.930471 -272.441094) (xy 157.963106 -272.404257) (xy 158.001227 -272.373132) (xy 158.043848 -272.348525)
			(xy 158.089864 -272.331073) (xy 158.138083 -272.321229) (xy 158.187258 -272.319248) (xy 158.236113 -272.32518)
			(xy 158.283384 -272.338872) (xy 158.327846 -272.35997) (xy 158.368349 -272.387926) (xy 158.403842 -272.422018)
			(xy 158.433407 -272.461362) (xy 158.456278 -272.504939) (xy 158.471862 -272.55162) (xy 158.479757 -272.600197)
			(xy 158.480252 -272.624804) (xy 158.479757 -272.649411) (xy 158.471862 -272.697988) (xy 158.456278 -272.744669)
			(xy 158.433407 -272.788246) (xy 158.403842 -272.82759) (xy 158.368349 -272.861682) (xy 158.327846 -272.889638)
			(xy 158.283384 -272.910736) (xy 158.236113 -272.924428) (xy 158.187258 -272.93036) (xy 158.138083 -272.928379)
			(xy 158.089864 -272.918535) (xy 158.043848 -272.901083) (xy 158.001227 -272.876476) (xy 157.963106 -272.845351)
			(xy 157.930471 -272.808514) (xy 157.904168 -272.766918) (xy 157.884877 -272.721642) (xy 157.8731 -272.673858)
			(xy 157.86914 -272.624804) (xy 156.580332 -272.624804) (xy 156.579837 -272.649411) (xy 156.571942 -272.697988)
			(xy 156.556358 -272.744669) (xy 156.533487 -272.788246) (xy 156.503922 -272.82759) (xy 156.468429 -272.861682)
			(xy 156.427926 -272.889638) (xy 156.383464 -272.910736) (xy 156.336193 -272.924428) (xy 156.287338 -272.93036)
			(xy 156.238163 -272.928379) (xy 156.189944 -272.918535) (xy 156.143928 -272.901083) (xy 156.101307 -272.876476)
			(xy 156.063186 -272.845351) (xy 156.030551 -272.808514) (xy 156.004248 -272.766918) (xy 155.984957 -272.721642)
			(xy 155.97318 -272.673858) (xy 155.96922 -272.624804) (xy 154.680412 -272.624804) (xy 154.679917 -272.649411)
			(xy 154.672022 -272.697988) (xy 154.656438 -272.744669) (xy 154.633567 -272.788246) (xy 154.604002 -272.82759)
			(xy 154.568509 -272.861682) (xy 154.528006 -272.889638) (xy 154.483544 -272.910736) (xy 154.436273 -272.924428)
			(xy 154.387418 -272.93036) (xy 154.338243 -272.928379) (xy 154.290024 -272.918535) (xy 154.244008 -272.901083)
			(xy 154.201387 -272.876476) (xy 154.163266 -272.845351) (xy 154.130631 -272.808514) (xy 154.104328 -272.766918)
			(xy 154.085037 -272.721642) (xy 154.07326 -272.673858) (xy 154.0693 -272.624804) (xy 147.913577 -272.624804)
			(xy 147.821142 -272.734963) (xy 147.719655 -272.843502) (xy 147.612488 -272.946437) (xy 147.499951 -273.043471)
			(xy 147.393798 -273.125492) (xy 160.223196 -273.125492) (xy 160.223196 -273.074076) (xy 160.231239 -273.023294)
			(xy 160.247127 -272.974395) (xy 160.27047 -272.928583) (xy 160.300691 -272.886987) (xy 160.337047 -272.850631)
			(xy 160.378643 -272.82041) (xy 160.424455 -272.797067) (xy 160.473354 -272.781179) (xy 160.524136 -272.773136)
			(xy 160.575552 -272.773136) (xy 160.626334 -272.781179) (xy 160.675233 -272.797067) (xy 160.721045 -272.82041)
			(xy 160.762641 -272.850631) (xy 160.798997 -272.886987) (xy 160.829218 -272.928583) (xy 160.852561 -272.974395)
			(xy 160.868449 -273.023294) (xy 160.876492 -273.074076) (xy 160.876996 -273.099784) (xy 160.876492 -273.125492)
			(xy 162.12337 -273.125492) (xy 162.12337 -273.074076) (xy 162.131413 -273.023294) (xy 162.147301 -272.974395)
			(xy 162.170644 -272.928583) (xy 162.200865 -272.886987) (xy 162.237221 -272.850631) (xy 162.278817 -272.82041)
			(xy 162.324629 -272.797067) (xy 162.373528 -272.781179) (xy 162.42431 -272.773136) (xy 162.475726 -272.773136)
			(xy 162.526508 -272.781179) (xy 162.575407 -272.797067) (xy 162.621219 -272.82041) (xy 162.662815 -272.850631)
			(xy 162.699171 -272.886987) (xy 162.729392 -272.928583) (xy 162.752735 -272.974395) (xy 162.768623 -273.023294)
			(xy 162.776666 -273.074076) (xy 162.77717 -273.099784) (xy 162.776666 -273.125492) (xy 164.02329 -273.125492)
			(xy 164.02329 -273.074076) (xy 164.031333 -273.023294) (xy 164.047221 -272.974395) (xy 164.070564 -272.928583)
			(xy 164.100785 -272.886987) (xy 164.137141 -272.850631) (xy 164.178737 -272.82041) (xy 164.224549 -272.797067)
			(xy 164.273448 -272.781179) (xy 164.32423 -272.773136) (xy 164.375646 -272.773136) (xy 164.426428 -272.781179)
			(xy 164.475327 -272.797067) (xy 164.521139 -272.82041) (xy 164.562735 -272.850631) (xy 164.599091 -272.886987)
			(xy 164.629312 -272.928583) (xy 164.652655 -272.974395) (xy 164.668543 -273.023294) (xy 164.676586 -273.074076)
			(xy 164.67709 -273.099784) (xy 164.676586 -273.125492) (xy 164.668543 -273.176274) (xy 164.652655 -273.225173)
			(xy 164.629312 -273.270985) (xy 164.599091 -273.312581) (xy 164.562735 -273.348937) (xy 164.521139 -273.379158)
			(xy 164.475327 -273.402501) (xy 164.426428 -273.418389) (xy 164.375646 -273.426432) (xy 164.32423 -273.426432)
			(xy 164.273448 -273.418389) (xy 164.224549 -273.402501) (xy 164.178737 -273.379158) (xy 164.137141 -273.348937)
			(xy 164.100785 -273.312581) (xy 164.070564 -273.270985) (xy 164.047221 -273.225173) (xy 164.031333 -273.176274)
			(xy 164.02329 -273.125492) (xy 162.776666 -273.125492) (xy 162.768623 -273.176274) (xy 162.752735 -273.225173)
			(xy 162.729392 -273.270985) (xy 162.699171 -273.312581) (xy 162.662815 -273.348937) (xy 162.621219 -273.379158)
			(xy 162.575407 -273.402501) (xy 162.526508 -273.418389) (xy 162.475726 -273.426432) (xy 162.42431 -273.426432)
			(xy 162.373528 -273.418389) (xy 162.324629 -273.402501) (xy 162.278817 -273.379158) (xy 162.237221 -273.348937)
			(xy 162.200865 -273.312581) (xy 162.170644 -273.270985) (xy 162.147301 -273.225173) (xy 162.131413 -273.176274)
			(xy 162.12337 -273.125492) (xy 160.876492 -273.125492) (xy 160.868449 -273.176274) (xy 160.852561 -273.225173)
			(xy 160.829218 -273.270985) (xy 160.798997 -273.312581) (xy 160.762641 -273.348937) (xy 160.721045 -273.379158)
			(xy 160.675233 -273.402501) (xy 160.626334 -273.418389) (xy 160.575552 -273.426432) (xy 160.524136 -273.426432)
			(xy 160.473354 -273.418389) (xy 160.424455 -273.402501) (xy 160.378643 -273.379158) (xy 160.337047 -273.348937)
			(xy 160.300691 -273.312581) (xy 160.27047 -273.270985) (xy 160.247127 -273.225173) (xy 160.231239 -273.176274)
			(xy 160.223196 -273.125492) (xy 147.393798 -273.125492) (xy 147.382368 -273.134324) (xy 147.260078 -273.218735)
			(xy 147.133433 -273.29646) (xy 147.002798 -273.367276) (xy 146.868551 -273.430977) (xy 146.731078 -273.48738)
			(xy 146.590775 -273.536323) (xy 146.458063 -273.574764) (xy 155.96922 -273.574764) (xy 155.97318 -273.52571)
			(xy 155.984957 -273.477926) (xy 156.004248 -273.43265) (xy 156.030551 -273.391054) (xy 156.063186 -273.354217)
			(xy 156.101307 -273.323092) (xy 156.143928 -273.298485) (xy 156.189944 -273.281033) (xy 156.238163 -273.271189)
			(xy 156.287338 -273.269208) (xy 156.336193 -273.27514) (xy 156.383464 -273.288832) (xy 156.427926 -273.30993)
			(xy 156.468429 -273.337886) (xy 156.503922 -273.371978) (xy 156.533487 -273.411322) (xy 156.556358 -273.454899)
			(xy 156.571942 -273.50158) (xy 156.579837 -273.550157) (xy 156.580332 -273.574764) (xy 157.86914 -273.574764)
			(xy 157.8731 -273.52571) (xy 157.884877 -273.477926) (xy 157.904168 -273.43265) (xy 157.930471 -273.391054)
			(xy 157.963106 -273.354217) (xy 158.001227 -273.323092) (xy 158.043848 -273.298485) (xy 158.089864 -273.281033)
			(xy 158.138083 -273.271189) (xy 158.187258 -273.269208) (xy 158.236113 -273.27514) (xy 158.283384 -273.288832)
			(xy 158.327846 -273.30993) (xy 158.368349 -273.337886) (xy 158.403842 -273.371978) (xy 158.433407 -273.411322)
			(xy 158.456278 -273.454899) (xy 158.471862 -273.50158) (xy 158.479757 -273.550157) (xy 158.480252 -273.574764)
			(xy 158.479757 -273.599371) (xy 158.471862 -273.647948) (xy 158.456278 -273.694629) (xy 158.433407 -273.738206)
			(xy 158.403842 -273.77755) (xy 158.368349 -273.811642) (xy 158.327846 -273.839598) (xy 158.283384 -273.860696)
			(xy 158.236113 -273.874388) (xy 158.187258 -273.88032) (xy 158.138083 -273.878339) (xy 158.089864 -273.868495)
			(xy 158.043848 -273.851043) (xy 158.001227 -273.826436) (xy 157.963106 -273.795311) (xy 157.930471 -273.758474)
			(xy 157.904168 -273.716878) (xy 157.884877 -273.671602) (xy 157.8731 -273.623818) (xy 157.86914 -273.574764)
			(xy 156.580332 -273.574764) (xy 156.579837 -273.599371) (xy 156.571942 -273.647948) (xy 156.556358 -273.694629)
			(xy 156.533487 -273.738206) (xy 156.503922 -273.77755) (xy 156.468429 -273.811642) (xy 156.427926 -273.839598)
			(xy 156.383464 -273.860696) (xy 156.336193 -273.874388) (xy 156.287338 -273.88032) (xy 156.238163 -273.878339)
			(xy 156.189944 -273.868495) (xy 156.143928 -273.851043) (xy 156.101307 -273.826436) (xy 156.063186 -273.795311)
			(xy 156.030551 -273.758474) (xy 156.004248 -273.716878) (xy 155.984957 -273.671602) (xy 155.97318 -273.623818)
			(xy 155.96922 -273.574764) (xy 146.458063 -273.574764) (xy 146.448048 -273.577665) (xy 146.303307 -273.611285)
			(xy 146.156971 -273.637088) (xy 146.00946 -273.654999) (xy 145.861201 -273.664967) (xy 145.71262 -273.666962)
			(xy 145.564147 -273.660978) (xy 145.416208 -273.647034) (xy 145.269232 -273.625169) (xy 145.123641 -273.595447)
			(xy 144.979855 -273.557952) (xy 144.838289 -273.512793) (xy 144.699351 -273.460101) (xy 144.563442 -273.400027)
			(xy 144.430953 -273.332745) (xy 144.302267 -273.258448) (xy 144.177754 -273.177351) (xy 144.057774 -273.089687)
			(xy 143.942673 -272.995709) (xy 143.832781 -272.895689) (xy 143.728417 -272.789914) (xy 143.629881 -272.67869)
			(xy 143.537457 -272.562337) (xy 143.451412 -272.44119) (xy 143.371994 -272.3156) (xy 143.299431 -272.185928)
			(xy 143.233933 -272.052548) (xy 143.175689 -271.915845) (xy 143.124867 -271.776212) (xy 143.081613 -271.634053)
			(xy 143.046052 -271.489776) (xy 143.018287 -271.3438) (xy 142.998397 -271.196543) (xy 142.98644 -271.04843)
			(xy 142.982451 -270.89989) (xy 136.317736 -270.89989) (xy 136.317736 -272.58264) (xy 136.318187 -272.592427)
			(xy 136.325524 -272.610574) (xy 136.339118 -272.624658) (xy 136.356994 -272.632633) (xy 136.366758 -272.63344)
			(xy 136.449087 -272.636778) (xy 136.613306 -272.650485) (xy 136.776662 -272.672182) (xy 136.938765 -272.701817)
			(xy 137.099231 -272.73932) (xy 137.257678 -272.784601) (xy 137.413729 -272.837552) (xy 137.567013 -272.898049)
			(xy 137.717166 -272.965947) (xy 137.863829 -273.041084) (xy 138.006656 -273.123281) (xy 138.145305 -273.212344)
			(xy 138.279447 -273.308061) (xy 138.408763 -273.410203) (xy 138.532946 -273.518529) (xy 138.651701 -273.632779)
			(xy 138.764744 -273.752684) (xy 138.871807 -273.877957) (xy 138.972636 -274.0083) (xy 139.019534 -274.075452)
			(xy 160.223196 -274.075452) (xy 160.223196 -274.024036) (xy 160.231239 -273.973254) (xy 160.247127 -273.924355)
			(xy 160.27047 -273.878543) (xy 160.300691 -273.836947) (xy 160.337047 -273.800591) (xy 160.378643 -273.77037)
			(xy 160.424455 -273.747027) (xy 160.473354 -273.731139) (xy 160.524136 -273.723096) (xy 160.575552 -273.723096)
			(xy 160.626334 -273.731139) (xy 160.675233 -273.747027) (xy 160.721045 -273.77037) (xy 160.762641 -273.800591)
			(xy 160.798997 -273.836947) (xy 160.829218 -273.878543) (xy 160.852561 -273.924355) (xy 160.868449 -273.973254)
			(xy 160.876492 -274.024036) (xy 160.876996 -274.049744) (xy 160.876492 -274.075452) (xy 162.12337 -274.075452)
			(xy 162.12337 -274.024036) (xy 162.131413 -273.973254) (xy 162.147301 -273.924355) (xy 162.170644 -273.878543)
			(xy 162.200865 -273.836947) (xy 162.237221 -273.800591) (xy 162.278817 -273.77037) (xy 162.324629 -273.747027)
			(xy 162.373528 -273.731139) (xy 162.42431 -273.723096) (xy 162.475726 -273.723096) (xy 162.526508 -273.731139)
			(xy 162.575407 -273.747027) (xy 162.621219 -273.77037) (xy 162.662815 -273.800591) (xy 162.699171 -273.836947)
			(xy 162.729392 -273.878543) (xy 162.752735 -273.924355) (xy 162.768623 -273.973254) (xy 162.776666 -274.024036)
			(xy 162.77717 -274.049744) (xy 162.776666 -274.075452) (xy 164.02329 -274.075452) (xy 164.02329 -274.024036)
			(xy 164.031333 -273.973254) (xy 164.047221 -273.924355) (xy 164.070564 -273.878543) (xy 164.100785 -273.836947)
			(xy 164.137141 -273.800591) (xy 164.178737 -273.77037) (xy 164.224549 -273.747027) (xy 164.273448 -273.731139)
			(xy 164.32423 -273.723096) (xy 164.375646 -273.723096) (xy 164.426428 -273.731139) (xy 164.475327 -273.747027)
			(xy 164.521139 -273.77037) (xy 164.562735 -273.800591) (xy 164.599091 -273.836947) (xy 164.629312 -273.878543)
			(xy 164.652655 -273.924355) (xy 164.668543 -273.973254) (xy 164.676586 -274.024036) (xy 164.67709 -274.049744)
			(xy 164.676586 -274.075452) (xy 164.668543 -274.126234) (xy 164.652655 -274.175133) (xy 164.629312 -274.220945)
			(xy 164.599091 -274.262541) (xy 164.562735 -274.298897) (xy 164.521139 -274.329118) (xy 164.475327 -274.352461)
			(xy 164.426428 -274.368349) (xy 164.375646 -274.376392) (xy 164.32423 -274.376392) (xy 164.273448 -274.368349)
			(xy 164.224549 -274.352461) (xy 164.178737 -274.329118) (xy 164.137141 -274.298897) (xy 164.100785 -274.262541)
			(xy 164.070564 -274.220945) (xy 164.047221 -274.175133) (xy 164.031333 -274.126234) (xy 164.02329 -274.075452)
			(xy 162.776666 -274.075452) (xy 162.768623 -274.126234) (xy 162.752735 -274.175133) (xy 162.729392 -274.220945)
			(xy 162.699171 -274.262541) (xy 162.662815 -274.298897) (xy 162.621219 -274.329118) (xy 162.575407 -274.352461)
			(xy 162.526508 -274.368349) (xy 162.475726 -274.376392) (xy 162.42431 -274.376392) (xy 162.373528 -274.368349)
			(xy 162.324629 -274.352461) (xy 162.278817 -274.329118) (xy 162.237221 -274.298897) (xy 162.200865 -274.262541)
			(xy 162.170644 -274.220945) (xy 162.147301 -274.175133) (xy 162.131413 -274.126234) (xy 162.12337 -274.075452)
			(xy 160.876492 -274.075452) (xy 160.868449 -274.126234) (xy 160.852561 -274.175133) (xy 160.829218 -274.220945)
			(xy 160.798997 -274.262541) (xy 160.762641 -274.298897) (xy 160.721045 -274.329118) (xy 160.675233 -274.352461)
			(xy 160.626334 -274.368349) (xy 160.575552 -274.376392) (xy 160.524136 -274.376392) (xy 160.473354 -274.368349)
			(xy 160.424455 -274.352461) (xy 160.378643 -274.329118) (xy 160.337047 -274.298897) (xy 160.300691 -274.262541)
			(xy 160.27047 -274.220945) (xy 160.247127 -274.175133) (xy 160.231239 -274.126234) (xy 160.223196 -274.075452)
			(xy 139.019534 -274.075452) (xy 139.06699 -274.143404) (xy 139.154645 -274.282947) (xy 139.235393 -274.426598)
			(xy 139.284543 -274.524978) (xy 155.01926 -274.524978) (xy 155.02322 -274.475924) (xy 155.034997 -274.42814)
			(xy 155.054288 -274.382864) (xy 155.080591 -274.341268) (xy 155.113226 -274.304431) (xy 155.151347 -274.273306)
			(xy 155.193968 -274.248699) (xy 155.239984 -274.231247) (xy 155.288203 -274.221403) (xy 155.337378 -274.219422)
			(xy 155.386233 -274.225354) (xy 155.433504 -274.239046) (xy 155.477966 -274.260144) (xy 155.518469 -274.2881)
			(xy 155.553962 -274.322192) (xy 155.583527 -274.361536) (xy 155.606398 -274.405113) (xy 155.621982 -274.451794)
			(xy 155.629877 -274.500371) (xy 155.630372 -274.524978) (xy 156.91918 -274.524978) (xy 156.92314 -274.475924)
			(xy 156.934917 -274.42814) (xy 156.954208 -274.382864) (xy 156.980511 -274.341268) (xy 157.013146 -274.304431)
			(xy 157.051267 -274.273306) (xy 157.093888 -274.248699) (xy 157.139904 -274.231247) (xy 157.188123 -274.221403)
			(xy 157.237298 -274.219422) (xy 157.286153 -274.225354) (xy 157.333424 -274.239046) (xy 157.377886 -274.260144)
			(xy 157.418389 -274.2881) (xy 157.453882 -274.322192) (xy 157.483447 -274.361536) (xy 157.506318 -274.405113)
			(xy 157.521902 -274.451794) (xy 157.529797 -274.500371) (xy 157.530292 -274.524978) (xy 158.8191 -274.524978)
			(xy 158.82306 -274.475924) (xy 158.834837 -274.42814) (xy 158.854128 -274.382864) (xy 158.880431 -274.341268)
			(xy 158.913066 -274.304431) (xy 158.951187 -274.273306) (xy 158.993808 -274.248699) (xy 159.039824 -274.231247)
			(xy 159.088043 -274.221403) (xy 159.137218 -274.219422) (xy 159.186073 -274.225354) (xy 159.233344 -274.239046)
			(xy 159.277806 -274.260144) (xy 159.318309 -274.2881) (xy 159.353802 -274.322192) (xy 159.383367 -274.361536)
			(xy 159.406238 -274.405113) (xy 159.421822 -274.451794) (xy 159.429717 -274.500371) (xy 159.430212 -274.524978)
			(xy 159.429717 -274.549585) (xy 159.421822 -274.598162) (xy 159.406238 -274.644843) (xy 159.383367 -274.68842)
			(xy 159.353802 -274.727764) (xy 159.318309 -274.761856) (xy 159.277806 -274.789812) (xy 159.233344 -274.81091)
			(xy 159.186073 -274.824602) (xy 159.137218 -274.830534) (xy 159.088043 -274.828553) (xy 159.039824 -274.818709)
			(xy 158.993808 -274.801257) (xy 158.951187 -274.77665) (xy 158.913066 -274.745525) (xy 158.880431 -274.708688)
			(xy 158.854128 -274.667092) (xy 158.834837 -274.621816) (xy 158.82306 -274.574032) (xy 158.8191 -274.524978)
			(xy 157.530292 -274.524978) (xy 157.529797 -274.549585) (xy 157.521902 -274.598162) (xy 157.506318 -274.644843)
			(xy 157.483447 -274.68842) (xy 157.453882 -274.727764) (xy 157.418389 -274.761856) (xy 157.377886 -274.789812)
			(xy 157.333424 -274.81091) (xy 157.286153 -274.824602) (xy 157.237298 -274.830534) (xy 157.188123 -274.828553)
			(xy 157.139904 -274.818709) (xy 157.093888 -274.801257) (xy 157.051267 -274.77665) (xy 157.013146 -274.745525)
			(xy 156.980511 -274.708688) (xy 156.954208 -274.667092) (xy 156.934917 -274.621816) (xy 156.92314 -274.574032)
			(xy 156.91918 -274.524978) (xy 155.630372 -274.524978) (xy 155.629877 -274.549585) (xy 155.621982 -274.598162)
			(xy 155.606398 -274.644843) (xy 155.583527 -274.68842) (xy 155.553962 -274.727764) (xy 155.518469 -274.761856)
			(xy 155.477966 -274.789812) (xy 155.433504 -274.81091) (xy 155.386233 -274.824602) (xy 155.337378 -274.830534)
			(xy 155.288203 -274.828553) (xy 155.239984 -274.818709) (xy 155.193968 -274.801257) (xy 155.151347 -274.77665)
			(xy 155.113226 -274.745525) (xy 155.080591 -274.708688) (xy 155.054288 -274.667092) (xy 155.034997 -274.621816)
			(xy 155.02322 -274.574032) (xy 155.01926 -274.524978) (xy 139.284543 -274.524978) (xy 139.309042 -274.574015)
			(xy 139.375417 -274.724846) (xy 139.434359 -274.878735) (xy 139.482564 -275.025666) (xy 161.17341 -275.025666)
			(xy 161.17341 -274.97425) (xy 161.181453 -274.923468) (xy 161.197341 -274.874569) (xy 161.220684 -274.828757)
			(xy 161.250905 -274.787161) (xy 161.287261 -274.750805) (xy 161.328857 -274.720584) (xy 161.374669 -274.697241)
			(xy 161.423568 -274.681353) (xy 161.47435 -274.67331) (xy 161.525766 -274.67331) (xy 161.576548 -274.681353)
			(xy 161.625447 -274.697241) (xy 161.671259 -274.720584) (xy 161.712855 -274.750805) (xy 161.749211 -274.787161)
			(xy 161.779432 -274.828757) (xy 161.802775 -274.874569) (xy 161.818663 -274.923468) (xy 161.826706 -274.97425)
			(xy 161.82721 -274.999958) (xy 161.826706 -275.025666) (xy 163.07333 -275.025666) (xy 163.07333 -274.97425)
			(xy 163.081373 -274.923468) (xy 163.097261 -274.874569) (xy 163.120604 -274.828757) (xy 163.150825 -274.787161)
			(xy 163.187181 -274.750805) (xy 163.228777 -274.720584) (xy 163.274589 -274.697241) (xy 163.323488 -274.681353)
			(xy 163.37427 -274.67331) (xy 163.425686 -274.67331) (xy 163.476468 -274.681353) (xy 163.525367 -274.697241)
			(xy 163.571179 -274.720584) (xy 163.612775 -274.750805) (xy 163.649131 -274.787161) (xy 163.679352 -274.828757)
			(xy 163.702695 -274.874569) (xy 163.718583 -274.923468) (xy 163.726626 -274.97425) (xy 163.72713 -274.999958)
			(xy 163.726626 -275.025666) (xy 163.718583 -275.076448) (xy 163.702695 -275.125347) (xy 163.679352 -275.171159)
			(xy 163.649131 -275.212755) (xy 163.612775 -275.249111) (xy 163.571179 -275.279332) (xy 163.525367 -275.302675)
			(xy 163.476468 -275.318563) (xy 163.425686 -275.326606) (xy 163.37427 -275.326606) (xy 163.323488 -275.318563)
			(xy 163.274589 -275.302675) (xy 163.228777 -275.279332) (xy 163.187181 -275.249111) (xy 163.150825 -275.212755)
			(xy 163.120604 -275.171159) (xy 163.097261 -275.125347) (xy 163.081373 -275.076448) (xy 163.07333 -275.025666)
			(xy 161.826706 -275.025666) (xy 161.818663 -275.076448) (xy 161.802775 -275.125347) (xy 161.779432 -275.171159)
			(xy 161.749211 -275.212755) (xy 161.712855 -275.249111) (xy 161.671259 -275.279332) (xy 161.625447 -275.302675)
			(xy 161.576548 -275.318563) (xy 161.525766 -275.326606) (xy 161.47435 -275.326606) (xy 161.423568 -275.318563)
			(xy 161.374669 -275.302675) (xy 161.328857 -275.279332) (xy 161.287261 -275.249111) (xy 161.250905 -275.212755)
			(xy 161.220684 -275.171159) (xy 161.197341 -275.125347) (xy 161.181453 -275.076448) (xy 161.17341 -275.025666)
			(xy 139.482564 -275.025666) (xy 139.485729 -275.035314) (xy 139.529405 -275.194211) (xy 139.565281 -275.355048)
			(xy 139.585948 -275.474938) (xy 155.01926 -275.474938) (xy 155.02322 -275.425884) (xy 155.034997 -275.3781)
			(xy 155.054288 -275.332824) (xy 155.080591 -275.291228) (xy 155.113226 -275.254391) (xy 155.151347 -275.223266)
			(xy 155.193968 -275.198659) (xy 155.239984 -275.181207) (xy 155.288203 -275.171363) (xy 155.337378 -275.169382)
			(xy 155.386233 -275.175314) (xy 155.433504 -275.189006) (xy 155.477966 -275.210104) (xy 155.518469 -275.23806)
			(xy 155.553962 -275.272152) (xy 155.583527 -275.311496) (xy 155.606398 -275.355073) (xy 155.621982 -275.401754)
			(xy 155.629877 -275.450331) (xy 155.630372 -275.474938) (xy 156.91918 -275.474938) (xy 156.92314 -275.425884)
			(xy 156.934917 -275.3781) (xy 156.954208 -275.332824) (xy 156.980511 -275.291228) (xy 157.013146 -275.254391)
			(xy 157.051267 -275.223266) (xy 157.093888 -275.198659) (xy 157.139904 -275.181207) (xy 157.188123 -275.171363)
			(xy 157.237298 -275.169382) (xy 157.286153 -275.175314) (xy 157.333424 -275.189006) (xy 157.377886 -275.210104)
			(xy 157.418389 -275.23806) (xy 157.453882 -275.272152) (xy 157.483447 -275.311496) (xy 157.506318 -275.355073)
			(xy 157.521902 -275.401754) (xy 157.529797 -275.450331) (xy 157.530292 -275.474938) (xy 158.8191 -275.474938)
			(xy 158.82306 -275.425884) (xy 158.834837 -275.3781) (xy 158.854128 -275.332824) (xy 158.880431 -275.291228)
			(xy 158.913066 -275.254391) (xy 158.951187 -275.223266) (xy 158.993808 -275.198659) (xy 159.039824 -275.181207)
			(xy 159.088043 -275.171363) (xy 159.137218 -275.169382) (xy 159.186073 -275.175314) (xy 159.233344 -275.189006)
			(xy 159.277806 -275.210104) (xy 159.318309 -275.23806) (xy 159.353802 -275.272152) (xy 159.383367 -275.311496)
			(xy 159.406238 -275.355073) (xy 159.421822 -275.401754) (xy 159.429717 -275.450331) (xy 159.430212 -275.474938)
			(xy 159.429717 -275.499545) (xy 159.421822 -275.548122) (xy 159.406238 -275.594803) (xy 159.383367 -275.63838)
			(xy 159.353802 -275.677724) (xy 159.318309 -275.711816) (xy 159.277806 -275.739772) (xy 159.233344 -275.76087)
			(xy 159.186073 -275.774562) (xy 159.137218 -275.780494) (xy 159.088043 -275.778513) (xy 159.039824 -275.768669)
			(xy 158.993808 -275.751217) (xy 158.951187 -275.72661) (xy 158.913066 -275.695485) (xy 158.880431 -275.658648)
			(xy 158.854128 -275.617052) (xy 158.834837 -275.571776) (xy 158.82306 -275.523992) (xy 158.8191 -275.474938)
			(xy 157.530292 -275.474938) (xy 157.529797 -275.499545) (xy 157.521902 -275.548122) (xy 157.506318 -275.594803)
			(xy 157.483447 -275.63838) (xy 157.453882 -275.677724) (xy 157.418389 -275.711816) (xy 157.377886 -275.739772)
			(xy 157.333424 -275.76087) (xy 157.286153 -275.774562) (xy 157.237298 -275.780494) (xy 157.188123 -275.778513)
			(xy 157.139904 -275.768669) (xy 157.093888 -275.751217) (xy 157.051267 -275.72661) (xy 157.013146 -275.695485)
			(xy 156.980511 -275.658648) (xy 156.954208 -275.617052) (xy 156.934917 -275.571776) (xy 156.92314 -275.523992)
			(xy 156.91918 -275.474938) (xy 155.630372 -275.474938) (xy 155.629877 -275.499545) (xy 155.621982 -275.548122)
			(xy 155.606398 -275.594803) (xy 155.583527 -275.63838) (xy 155.553962 -275.677724) (xy 155.518469 -275.711816)
			(xy 155.477966 -275.739772) (xy 155.433504 -275.76087) (xy 155.386233 -275.774562) (xy 155.337378 -275.780494)
			(xy 155.288203 -275.778513) (xy 155.239984 -275.768669) (xy 155.193968 -275.751217) (xy 155.151347 -275.72661)
			(xy 155.113226 -275.695485) (xy 155.080591 -275.658648) (xy 155.054288 -275.617052) (xy 155.034997 -275.571776)
			(xy 155.02322 -275.523992) (xy 155.01926 -275.474938) (xy 139.585948 -275.474938) (xy 139.593275 -275.517443)
			(xy 139.613317 -275.68101) (xy 139.625362 -275.845359) (xy 139.628539 -275.975626) (xy 161.17341 -275.975626)
			(xy 161.17341 -275.92421) (xy 161.181453 -275.873428) (xy 161.197341 -275.824529) (xy 161.220684 -275.778717)
			(xy 161.250905 -275.737121) (xy 161.287261 -275.700765) (xy 161.328857 -275.670544) (xy 161.374669 -275.647201)
			(xy 161.423568 -275.631313) (xy 161.47435 -275.62327) (xy 161.525766 -275.62327) (xy 161.576548 -275.631313)
			(xy 161.625447 -275.647201) (xy 161.671259 -275.670544) (xy 161.712855 -275.700765) (xy 161.749211 -275.737121)
			(xy 161.779432 -275.778717) (xy 161.802775 -275.824529) (xy 161.818663 -275.873428) (xy 161.826706 -275.92421)
			(xy 161.82721 -275.949918) (xy 161.826706 -275.975626) (xy 163.07333 -275.975626) (xy 163.07333 -275.92421)
			(xy 163.081373 -275.873428) (xy 163.097261 -275.824529) (xy 163.120604 -275.778717) (xy 163.150825 -275.737121)
			(xy 163.187181 -275.700765) (xy 163.228777 -275.670544) (xy 163.274589 -275.647201) (xy 163.323488 -275.631313)
			(xy 163.37427 -275.62327) (xy 163.425686 -275.62327) (xy 163.476468 -275.631313) (xy 163.525367 -275.647201)
			(xy 163.571179 -275.670544) (xy 163.612775 -275.700765) (xy 163.649131 -275.737121) (xy 163.679352 -275.778717)
			(xy 163.702695 -275.824529) (xy 163.718583 -275.873428) (xy 163.726626 -275.92421) (xy 163.72713 -275.949918)
			(xy 163.726626 -275.975626) (xy 163.718583 -276.026408) (xy 163.702695 -276.075307) (xy 163.679352 -276.121119)
			(xy 163.649131 -276.162715) (xy 163.612775 -276.199071) (xy 163.571179 -276.229292) (xy 163.525367 -276.252635)
			(xy 163.476468 -276.268523) (xy 163.425686 -276.276566) (xy 163.37427 -276.276566) (xy 163.323488 -276.268523)
			(xy 163.274589 -276.252635) (xy 163.228777 -276.229292) (xy 163.187181 -276.199071) (xy 163.150825 -276.162715)
			(xy 163.120604 -276.121119) (xy 163.097261 -276.075307) (xy 163.081373 -276.026408) (xy 163.07333 -275.975626)
			(xy 161.826706 -275.975626) (xy 161.818663 -276.026408) (xy 161.802775 -276.075307) (xy 161.779432 -276.121119)
			(xy 161.749211 -276.162715) (xy 161.712855 -276.199071) (xy 161.671259 -276.229292) (xy 161.625447 -276.252635)
			(xy 161.576548 -276.268523) (xy 161.525766 -276.276566) (xy 161.47435 -276.276566) (xy 161.423568 -276.268523)
			(xy 161.374669 -276.252635) (xy 161.328857 -276.229292) (xy 161.287261 -276.199071) (xy 161.250905 -276.162715)
			(xy 161.220684 -276.121119) (xy 161.197341 -276.075307) (xy 161.181453 -276.026408) (xy 161.17341 -275.975626)
			(xy 139.628539 -275.975626) (xy 139.62938 -276.010101) (xy 139.625362 -276.174842) (xy 139.613317 -276.339191)
			(xy 139.602815 -276.424898) (xy 152.169126 -276.424898) (xy 152.173086 -276.375844) (xy 152.184863 -276.32806)
			(xy 152.204154 -276.282784) (xy 152.230457 -276.241188) (xy 152.263092 -276.204351) (xy 152.301213 -276.173226)
			(xy 152.343834 -276.148619) (xy 152.38985 -276.131167) (xy 152.438069 -276.121323) (xy 152.487244 -276.119342)
			(xy 152.536099 -276.125274) (xy 152.58337 -276.138966) (xy 152.627832 -276.160064) (xy 152.668335 -276.18802)
			(xy 152.703828 -276.222112) (xy 152.733393 -276.261456) (xy 152.756264 -276.305033) (xy 152.771848 -276.351714)
			(xy 152.779743 -276.400291) (xy 152.780238 -276.424898) (xy 153.119086 -276.424898) (xy 153.123046 -276.375844)
			(xy 153.134823 -276.32806) (xy 153.154114 -276.282784) (xy 153.180417 -276.241188) (xy 153.213052 -276.204351)
			(xy 153.251173 -276.173226) (xy 153.293794 -276.148619) (xy 153.33981 -276.131167) (xy 153.388029 -276.121323)
			(xy 153.437204 -276.119342) (xy 153.486059 -276.125274) (xy 153.53333 -276.138966) (xy 153.577792 -276.160064)
			(xy 153.618295 -276.18802) (xy 153.653788 -276.222112) (xy 153.683353 -276.261456) (xy 153.706224 -276.305033)
			(xy 153.721808 -276.351714) (xy 153.729703 -276.400291) (xy 153.730198 -276.424898) (xy 153.729703 -276.449505)
			(xy 153.721808 -276.498082) (xy 153.706224 -276.544763) (xy 153.683353 -276.58834) (xy 153.653788 -276.627684)
			(xy 153.618295 -276.661776) (xy 153.577792 -276.689732) (xy 153.53333 -276.71083) (xy 153.486059 -276.724522)
			(xy 153.437204 -276.730454) (xy 153.388029 -276.728473) (xy 153.33981 -276.718629) (xy 153.293794 -276.701177)
			(xy 153.251173 -276.67657) (xy 153.213052 -276.645445) (xy 153.180417 -276.608608) (xy 153.154114 -276.567012)
			(xy 153.134823 -276.521736) (xy 153.123046 -276.473952) (xy 153.119086 -276.424898) (xy 152.780238 -276.424898)
			(xy 152.779743 -276.449505) (xy 152.771848 -276.498082) (xy 152.756264 -276.544763) (xy 152.733393 -276.58834)
			(xy 152.703828 -276.627684) (xy 152.668335 -276.661776) (xy 152.627832 -276.689732) (xy 152.58337 -276.71083)
			(xy 152.536099 -276.724522) (xy 152.487244 -276.730454) (xy 152.438069 -276.728473) (xy 152.38985 -276.718629)
			(xy 152.343834 -276.701177) (xy 152.301213 -276.67657) (xy 152.263092 -276.645445) (xy 152.230457 -276.608608)
			(xy 152.204154 -276.567012) (xy 152.184863 -276.521736) (xy 152.173086 -276.473952) (xy 152.169126 -276.424898)
			(xy 139.602815 -276.424898) (xy 139.593274 -276.502758) (xy 139.565281 -276.665153) (xy 139.529404 -276.82599)
			(xy 139.485729 -276.984888) (xy 139.434359 -277.141466) (xy 139.375417 -277.295355) (xy 139.340431 -277.374858)
			(xy 154.0693 -277.374858) (xy 154.07326 -277.325804) (xy 154.085037 -277.27802) (xy 154.104328 -277.232744)
			(xy 154.130631 -277.191148) (xy 154.163266 -277.154311) (xy 154.201387 -277.123186) (xy 154.244008 -277.098579)
			(xy 154.290024 -277.081127) (xy 154.338243 -277.071283) (xy 154.387418 -277.069302) (xy 154.436273 -277.075234)
			(xy 154.483544 -277.088926) (xy 154.528006 -277.110024) (xy 154.568509 -277.13798) (xy 154.604002 -277.172072)
			(xy 154.633567 -277.211416) (xy 154.656438 -277.254993) (xy 154.672022 -277.301674) (xy 154.679917 -277.350251)
			(xy 154.680412 -277.374858) (xy 155.96922 -277.374858) (xy 155.97318 -277.325804) (xy 155.984957 -277.27802)
			(xy 156.004248 -277.232744) (xy 156.030551 -277.191148) (xy 156.063186 -277.154311) (xy 156.101307 -277.123186)
			(xy 156.143928 -277.098579) (xy 156.189944 -277.081127) (xy 156.238163 -277.071283) (xy 156.287338 -277.069302)
			(xy 156.336193 -277.075234) (xy 156.383464 -277.088926) (xy 156.427926 -277.110024) (xy 156.468429 -277.13798)
			(xy 156.503922 -277.172072) (xy 156.533487 -277.211416) (xy 156.556358 -277.254993) (xy 156.571942 -277.301674)
			(xy 156.579837 -277.350251) (xy 156.580332 -277.374858) (xy 157.86914 -277.374858) (xy 157.8731 -277.325804)
			(xy 157.884877 -277.27802) (xy 157.904168 -277.232744) (xy 157.930471 -277.191148) (xy 157.963106 -277.154311)
			(xy 158.001227 -277.123186) (xy 158.043848 -277.098579) (xy 158.089864 -277.081127) (xy 158.138083 -277.071283)
			(xy 158.187258 -277.069302) (xy 158.236113 -277.075234) (xy 158.283384 -277.088926) (xy 158.327846 -277.110024)
			(xy 158.368349 -277.13798) (xy 158.403842 -277.172072) (xy 158.433407 -277.211416) (xy 158.456278 -277.254993)
			(xy 158.471862 -277.301674) (xy 158.479757 -277.350251) (xy 158.480252 -277.374858) (xy 158.479757 -277.399465)
			(xy 158.471862 -277.448042) (xy 158.456278 -277.494723) (xy 158.433407 -277.5383) (xy 158.403842 -277.577644)
			(xy 158.368349 -277.611736) (xy 158.327846 -277.639692) (xy 158.283384 -277.66079) (xy 158.236113 -277.674482)
			(xy 158.187258 -277.680414) (xy 158.138083 -277.678433) (xy 158.089864 -277.668589) (xy 158.043848 -277.651137)
			(xy 158.001227 -277.62653) (xy 157.963106 -277.595405) (xy 157.930471 -277.558568) (xy 157.904168 -277.516972)
			(xy 157.884877 -277.471696) (xy 157.8731 -277.423912) (xy 157.86914 -277.374858) (xy 156.580332 -277.374858)
			(xy 156.579837 -277.399465) (xy 156.571942 -277.448042) (xy 156.556358 -277.494723) (xy 156.533487 -277.5383)
			(xy 156.503922 -277.577644) (xy 156.468429 -277.611736) (xy 156.427926 -277.639692) (xy 156.383464 -277.66079)
			(xy 156.336193 -277.674482) (xy 156.287338 -277.680414) (xy 156.238163 -277.678433) (xy 156.189944 -277.668589)
			(xy 156.143928 -277.651137) (xy 156.101307 -277.62653) (xy 156.063186 -277.595405) (xy 156.030551 -277.558568)
			(xy 156.004248 -277.516972) (xy 155.984957 -277.471696) (xy 155.97318 -277.423912) (xy 155.96922 -277.374858)
			(xy 154.680412 -277.374858) (xy 154.679917 -277.399465) (xy 154.672022 -277.448042) (xy 154.656438 -277.494723)
			(xy 154.633567 -277.5383) (xy 154.604002 -277.577644) (xy 154.568509 -277.611736) (xy 154.528006 -277.639692)
			(xy 154.483544 -277.66079) (xy 154.436273 -277.674482) (xy 154.387418 -277.680414) (xy 154.338243 -277.678433)
			(xy 154.290024 -277.668589) (xy 154.244008 -277.651137) (xy 154.201387 -277.62653) (xy 154.163266 -277.595405)
			(xy 154.130631 -277.558568) (xy 154.104328 -277.516972) (xy 154.085037 -277.471696) (xy 154.07326 -277.423912)
			(xy 154.0693 -277.374858) (xy 139.340431 -277.374858) (xy 139.309042 -277.446186) (xy 139.235393 -277.593603)
			(xy 139.154645 -277.737254) (xy 139.067775 -277.875546) (xy 160.223196 -277.875546) (xy 160.223196 -277.82413)
			(xy 160.231239 -277.773348) (xy 160.247127 -277.724449) (xy 160.27047 -277.678637) (xy 160.300691 -277.637041)
			(xy 160.337047 -277.600685) (xy 160.378643 -277.570464) (xy 160.424455 -277.547121) (xy 160.473354 -277.531233)
			(xy 160.524136 -277.52319) (xy 160.575552 -277.52319) (xy 160.626334 -277.531233) (xy 160.675233 -277.547121)
			(xy 160.721045 -277.570464) (xy 160.762641 -277.600685) (xy 160.798997 -277.637041) (xy 160.829218 -277.678637)
			(xy 160.852561 -277.724449) (xy 160.868449 -277.773348) (xy 160.876492 -277.82413) (xy 160.876996 -277.849838)
			(xy 160.876492 -277.875546) (xy 162.12337 -277.875546) (xy 162.12337 -277.82413) (xy 162.131413 -277.773348)
			(xy 162.147301 -277.724449) (xy 162.170644 -277.678637) (xy 162.200865 -277.637041) (xy 162.237221 -277.600685)
			(xy 162.278817 -277.570464) (xy 162.324629 -277.547121) (xy 162.373528 -277.531233) (xy 162.42431 -277.52319)
			(xy 162.475726 -277.52319) (xy 162.526508 -277.531233) (xy 162.575407 -277.547121) (xy 162.621219 -277.570464)
			(xy 162.662815 -277.600685) (xy 162.699171 -277.637041) (xy 162.729392 -277.678637) (xy 162.752735 -277.724449)
			(xy 162.768623 -277.773348) (xy 162.776666 -277.82413) (xy 162.77717 -277.849838) (xy 162.776666 -277.875546)
			(xy 164.02329 -277.875546) (xy 164.02329 -277.82413) (xy 164.031333 -277.773348) (xy 164.047221 -277.724449)
			(xy 164.070564 -277.678637) (xy 164.100785 -277.637041) (xy 164.137141 -277.600685) (xy 164.178737 -277.570464)
			(xy 164.224549 -277.547121) (xy 164.273448 -277.531233) (xy 164.32423 -277.52319) (xy 164.375646 -277.52319)
			(xy 164.426428 -277.531233) (xy 164.475327 -277.547121) (xy 164.521139 -277.570464) (xy 164.562735 -277.600685)
			(xy 164.599091 -277.637041) (xy 164.629312 -277.678637) (xy 164.652655 -277.724449) (xy 164.668543 -277.773348)
			(xy 164.676586 -277.82413) (xy 164.67709 -277.849838) (xy 164.676586 -277.875546) (xy 164.668543 -277.926328)
			(xy 164.652655 -277.975227) (xy 164.629312 -278.021039) (xy 164.599091 -278.062635) (xy 164.562735 -278.098991)
			(xy 164.521139 -278.129212) (xy 164.475327 -278.152555) (xy 164.426428 -278.168443) (xy 164.375646 -278.176486)
			(xy 164.32423 -278.176486) (xy 164.273448 -278.168443) (xy 164.224549 -278.152555) (xy 164.178737 -278.129212)
			(xy 164.137141 -278.098991) (xy 164.100785 -278.062635) (xy 164.070564 -278.021039) (xy 164.047221 -277.975227)
			(xy 164.031333 -277.926328) (xy 164.02329 -277.875546) (xy 162.776666 -277.875546) (xy 162.768623 -277.926328)
			(xy 162.752735 -277.975227) (xy 162.729392 -278.021039) (xy 162.699171 -278.062635) (xy 162.662815 -278.098991)
			(xy 162.621219 -278.129212) (xy 162.575407 -278.152555) (xy 162.526508 -278.168443) (xy 162.475726 -278.176486)
			(xy 162.42431 -278.176486) (xy 162.373528 -278.168443) (xy 162.324629 -278.152555) (xy 162.278817 -278.129212)
			(xy 162.237221 -278.098991) (xy 162.200865 -278.062635) (xy 162.170644 -278.021039) (xy 162.147301 -277.975227)
			(xy 162.131413 -277.926328) (xy 162.12337 -277.875546) (xy 160.876492 -277.875546) (xy 160.868449 -277.926328)
			(xy 160.852561 -277.975227) (xy 160.829218 -278.021039) (xy 160.798997 -278.062635) (xy 160.762641 -278.098991)
			(xy 160.721045 -278.129212) (xy 160.675233 -278.152555) (xy 160.626334 -278.168443) (xy 160.575552 -278.176486)
			(xy 160.524136 -278.176486) (xy 160.473354 -278.168443) (xy 160.424455 -278.152555) (xy 160.378643 -278.129212)
			(xy 160.337047 -278.098991) (xy 160.300691 -278.062635) (xy 160.27047 -278.021039) (xy 160.247127 -277.975227)
			(xy 160.231239 -277.926328) (xy 160.223196 -277.875546) (xy 139.067775 -277.875546) (xy 139.066989 -277.876797)
			(xy 138.972635 -278.011901) (xy 138.871806 -278.142244) (xy 138.764743 -278.267517) (xy 138.710721 -278.324818)
			(xy 154.0693 -278.324818) (xy 154.07326 -278.275764) (xy 154.085037 -278.22798) (xy 154.104328 -278.182704)
			(xy 154.130631 -278.141108) (xy 154.163266 -278.104271) (xy 154.201387 -278.073146) (xy 154.244008 -278.048539)
			(xy 154.290024 -278.031087) (xy 154.338243 -278.021243) (xy 154.387418 -278.019262) (xy 154.436273 -278.025194)
			(xy 154.483544 -278.038886) (xy 154.528006 -278.059984) (xy 154.568509 -278.08794) (xy 154.604002 -278.122032)
			(xy 154.633567 -278.161376) (xy 154.656438 -278.204953) (xy 154.672022 -278.251634) (xy 154.679917 -278.300211)
			(xy 154.680412 -278.324818) (xy 155.96922 -278.324818) (xy 155.97318 -278.275764) (xy 155.984957 -278.22798)
			(xy 156.004248 -278.182704) (xy 156.030551 -278.141108) (xy 156.063186 -278.104271) (xy 156.101307 -278.073146)
			(xy 156.143928 -278.048539) (xy 156.189944 -278.031087) (xy 156.238163 -278.021243) (xy 156.287338 -278.019262)
			(xy 156.336193 -278.025194) (xy 156.383464 -278.038886) (xy 156.427926 -278.059984) (xy 156.468429 -278.08794)
			(xy 156.503922 -278.122032) (xy 156.533487 -278.161376) (xy 156.556358 -278.204953) (xy 156.571942 -278.251634)
			(xy 156.579837 -278.300211) (xy 156.580332 -278.324818) (xy 157.86914 -278.324818) (xy 157.8731 -278.275764)
			(xy 157.884877 -278.22798) (xy 157.904168 -278.182704) (xy 157.930471 -278.141108) (xy 157.963106 -278.104271)
			(xy 158.001227 -278.073146) (xy 158.043848 -278.048539) (xy 158.089864 -278.031087) (xy 158.138083 -278.021243)
			(xy 158.187258 -278.019262) (xy 158.236113 -278.025194) (xy 158.283384 -278.038886) (xy 158.327846 -278.059984)
			(xy 158.368349 -278.08794) (xy 158.403842 -278.122032) (xy 158.433407 -278.161376) (xy 158.456278 -278.204953)
			(xy 158.471862 -278.251634) (xy 158.479757 -278.300211) (xy 158.480252 -278.324818) (xy 158.479757 -278.349425)
			(xy 158.471862 -278.398002) (xy 158.456278 -278.444683) (xy 158.433407 -278.48826) (xy 158.403842 -278.527604)
			(xy 158.368349 -278.561696) (xy 158.327846 -278.589652) (xy 158.283384 -278.61075) (xy 158.236113 -278.624442)
			(xy 158.187258 -278.630374) (xy 158.138083 -278.628393) (xy 158.089864 -278.618549) (xy 158.043848 -278.601097)
			(xy 158.001227 -278.57649) (xy 157.963106 -278.545365) (xy 157.930471 -278.508528) (xy 157.904168 -278.466932)
			(xy 157.884877 -278.421656) (xy 157.8731 -278.373872) (xy 157.86914 -278.324818) (xy 156.580332 -278.324818)
			(xy 156.579837 -278.349425) (xy 156.571942 -278.398002) (xy 156.556358 -278.444683) (xy 156.533487 -278.48826)
			(xy 156.503922 -278.527604) (xy 156.468429 -278.561696) (xy 156.427926 -278.589652) (xy 156.383464 -278.61075)
			(xy 156.336193 -278.624442) (xy 156.287338 -278.630374) (xy 156.238163 -278.628393) (xy 156.189944 -278.618549)
			(xy 156.143928 -278.601097) (xy 156.101307 -278.57649) (xy 156.063186 -278.545365) (xy 156.030551 -278.508528)
			(xy 156.004248 -278.466932) (xy 155.984957 -278.421656) (xy 155.97318 -278.373872) (xy 155.96922 -278.324818)
			(xy 154.680412 -278.324818) (xy 154.679917 -278.349425) (xy 154.672022 -278.398002) (xy 154.656438 -278.444683)
			(xy 154.633567 -278.48826) (xy 154.604002 -278.527604) (xy 154.568509 -278.561696) (xy 154.528006 -278.589652)
			(xy 154.483544 -278.61075) (xy 154.436273 -278.624442) (xy 154.387418 -278.630374) (xy 154.338243 -278.628393)
			(xy 154.290024 -278.618549) (xy 154.244008 -278.601097) (xy 154.201387 -278.57649) (xy 154.163266 -278.545365)
			(xy 154.130631 -278.508528) (xy 154.104328 -278.466932) (xy 154.085037 -278.421656) (xy 154.07326 -278.373872)
			(xy 154.0693 -278.324818) (xy 138.710721 -278.324818) (xy 138.6517 -278.387421) (xy 138.532946 -278.501672)
			(xy 138.408763 -278.609997) (xy 138.279446 -278.71214) (xy 138.145304 -278.807856) (xy 138.117827 -278.825506)
			(xy 160.223196 -278.825506) (xy 160.223196 -278.77409) (xy 160.231239 -278.723308) (xy 160.247127 -278.674409)
			(xy 160.27047 -278.628597) (xy 160.300691 -278.587001) (xy 160.337047 -278.550645) (xy 160.378643 -278.520424)
			(xy 160.424455 -278.497081) (xy 160.473354 -278.481193) (xy 160.524136 -278.47315) (xy 160.575552 -278.47315)
			(xy 160.626334 -278.481193) (xy 160.675233 -278.497081) (xy 160.721045 -278.520424) (xy 160.762641 -278.550645)
			(xy 160.798997 -278.587001) (xy 160.829218 -278.628597) (xy 160.852561 -278.674409) (xy 160.868449 -278.723308)
			(xy 160.876492 -278.77409) (xy 160.876996 -278.799798) (xy 160.876492 -278.825506) (xy 162.12337 -278.825506)
			(xy 162.12337 -278.77409) (xy 162.131413 -278.723308) (xy 162.147301 -278.674409) (xy 162.170644 -278.628597)
			(xy 162.200865 -278.587001) (xy 162.237221 -278.550645) (xy 162.278817 -278.520424) (xy 162.324629 -278.497081)
			(xy 162.373528 -278.481193) (xy 162.42431 -278.47315) (xy 162.475726 -278.47315) (xy 162.526508 -278.481193)
			(xy 162.575407 -278.497081) (xy 162.621219 -278.520424) (xy 162.662815 -278.550645) (xy 162.699171 -278.587001)
			(xy 162.729392 -278.628597) (xy 162.752735 -278.674409) (xy 162.768623 -278.723308) (xy 162.776666 -278.77409)
			(xy 162.77717 -278.799798) (xy 162.776666 -278.825506) (xy 164.02329 -278.825506) (xy 164.02329 -278.77409)
			(xy 164.031333 -278.723308) (xy 164.047221 -278.674409) (xy 164.070564 -278.628597) (xy 164.100785 -278.587001)
			(xy 164.137141 -278.550645) (xy 164.178737 -278.520424) (xy 164.224549 -278.497081) (xy 164.273448 -278.481193)
			(xy 164.32423 -278.47315) (xy 164.375646 -278.47315) (xy 164.426428 -278.481193) (xy 164.475327 -278.497081)
			(xy 164.521139 -278.520424) (xy 164.562735 -278.550645) (xy 164.599091 -278.587001) (xy 164.629312 -278.628597)
			(xy 164.652655 -278.674409) (xy 164.668543 -278.723308) (xy 164.676586 -278.77409) (xy 164.67709 -278.799798)
			(xy 164.676586 -278.825506) (xy 164.668543 -278.876288) (xy 164.652655 -278.925187) (xy 164.629312 -278.970999)
			(xy 164.599091 -279.012595) (xy 164.562735 -279.048951) (xy 164.521139 -279.079172) (xy 164.475327 -279.102515)
			(xy 164.426428 -279.118403) (xy 164.375646 -279.126446) (xy 164.32423 -279.126446) (xy 164.273448 -279.118403)
			(xy 164.224549 -279.102515) (xy 164.178737 -279.079172) (xy 164.137141 -279.048951) (xy 164.100785 -279.012595)
			(xy 164.070564 -278.970999) (xy 164.047221 -278.925187) (xy 164.031333 -278.876288) (xy 164.02329 -278.825506)
			(xy 162.776666 -278.825506) (xy 162.768623 -278.876288) (xy 162.752735 -278.925187) (xy 162.729392 -278.970999)
			(xy 162.699171 -279.012595) (xy 162.662815 -279.048951) (xy 162.621219 -279.079172) (xy 162.575407 -279.102515)
			(xy 162.526508 -279.118403) (xy 162.475726 -279.126446) (xy 162.42431 -279.126446) (xy 162.373528 -279.118403)
			(xy 162.324629 -279.102515) (xy 162.278817 -279.079172) (xy 162.237221 -279.048951) (xy 162.200865 -279.012595)
			(xy 162.170644 -278.970999) (xy 162.147301 -278.925187) (xy 162.131413 -278.876288) (xy 162.12337 -278.825506)
			(xy 160.876492 -278.825506) (xy 160.868449 -278.876288) (xy 160.852561 -278.925187) (xy 160.829218 -278.970999)
			(xy 160.798997 -279.012595) (xy 160.762641 -279.048951) (xy 160.721045 -279.079172) (xy 160.675233 -279.102515)
			(xy 160.626334 -279.118403) (xy 160.575552 -279.126446) (xy 160.524136 -279.126446) (xy 160.473354 -279.118403)
			(xy 160.424455 -279.102515) (xy 160.378643 -279.079172) (xy 160.337047 -279.048951) (xy 160.300691 -279.012595)
			(xy 160.27047 -278.970999) (xy 160.247127 -278.925187) (xy 160.231239 -278.876288) (xy 160.223196 -278.825506)
			(xy 138.117827 -278.825506) (xy 138.006655 -278.896919) (xy 137.863828 -278.979117) (xy 137.717165 -279.054254)
			(xy 137.567012 -279.122151) (xy 137.413728 -279.182648) (xy 137.257677 -279.2356) (xy 137.120586 -279.274778)
			(xy 152.169126 -279.274778) (xy 152.173086 -279.225724) (xy 152.184863 -279.17794) (xy 152.204154 -279.132664)
			(xy 152.230457 -279.091068) (xy 152.263092 -279.054231) (xy 152.301213 -279.023106) (xy 152.343834 -278.998499)
			(xy 152.38985 -278.981047) (xy 152.438069 -278.971203) (xy 152.487244 -278.969222) (xy 152.536099 -278.975154)
			(xy 152.58337 -278.988846) (xy 152.627832 -279.009944) (xy 152.668335 -279.0379) (xy 152.703828 -279.071992)
			(xy 152.733393 -279.111336) (xy 152.756264 -279.154913) (xy 152.771848 -279.201594) (xy 152.779743 -279.250171)
			(xy 152.780238 -279.274778) (xy 153.119086 -279.274778) (xy 153.123046 -279.225724) (xy 153.134823 -279.17794)
			(xy 153.154114 -279.132664) (xy 153.180417 -279.091068) (xy 153.213052 -279.054231) (xy 153.251173 -279.023106)
			(xy 153.293794 -278.998499) (xy 153.33981 -278.981047) (xy 153.388029 -278.971203) (xy 153.437204 -278.969222)
			(xy 153.486059 -278.975154) (xy 153.53333 -278.988846) (xy 153.577792 -279.009944) (xy 153.618295 -279.0379)
			(xy 153.653788 -279.071992) (xy 153.683353 -279.111336) (xy 153.706224 -279.154913) (xy 153.721808 -279.201594)
			(xy 153.729703 -279.250171) (xy 153.730198 -279.274778) (xy 155.01926 -279.274778) (xy 155.02322 -279.225724)
			(xy 155.034997 -279.17794) (xy 155.054288 -279.132664) (xy 155.080591 -279.091068) (xy 155.113226 -279.054231)
			(xy 155.151347 -279.023106) (xy 155.193968 -278.998499) (xy 155.239984 -278.981047) (xy 155.288203 -278.971203)
			(xy 155.337378 -278.969222) (xy 155.386233 -278.975154) (xy 155.433504 -278.988846) (xy 155.477966 -279.009944)
			(xy 155.518469 -279.0379) (xy 155.553962 -279.071992) (xy 155.583527 -279.111336) (xy 155.606398 -279.154913)
			(xy 155.621982 -279.201594) (xy 155.629877 -279.250171) (xy 155.630372 -279.274778) (xy 156.91918 -279.274778)
			(xy 156.92314 -279.225724) (xy 156.934917 -279.17794) (xy 156.954208 -279.132664) (xy 156.980511 -279.091068)
			(xy 157.013146 -279.054231) (xy 157.051267 -279.023106) (xy 157.093888 -278.998499) (xy 157.139904 -278.981047)
			(xy 157.188123 -278.971203) (xy 157.237298 -278.969222) (xy 157.286153 -278.975154) (xy 157.333424 -278.988846)
			(xy 157.377886 -279.009944) (xy 157.418389 -279.0379) (xy 157.453882 -279.071992) (xy 157.483447 -279.111336)
			(xy 157.506318 -279.154913) (xy 157.521902 -279.201594) (xy 157.529797 -279.250171) (xy 157.530292 -279.274778)
			(xy 157.529797 -279.299385) (xy 157.521902 -279.347962) (xy 157.506318 -279.394643) (xy 157.483447 -279.43822)
			(xy 157.453882 -279.477564) (xy 157.418389 -279.511656) (xy 157.377886 -279.539612) (xy 157.333424 -279.56071)
			(xy 157.286153 -279.574402) (xy 157.237298 -279.580334) (xy 157.188123 -279.578353) (xy 157.139904 -279.568509)
			(xy 157.093888 -279.551057) (xy 157.051267 -279.52645) (xy 157.013146 -279.495325) (xy 156.980511 -279.458488)
			(xy 156.954208 -279.416892) (xy 156.934917 -279.371616) (xy 156.92314 -279.323832) (xy 156.91918 -279.274778)
			(xy 155.630372 -279.274778) (xy 155.629877 -279.299385) (xy 155.621982 -279.347962) (xy 155.606398 -279.394643)
			(xy 155.583527 -279.43822) (xy 155.553962 -279.477564) (xy 155.518469 -279.511656) (xy 155.477966 -279.539612)
			(xy 155.433504 -279.56071) (xy 155.386233 -279.574402) (xy 155.337378 -279.580334) (xy 155.288203 -279.578353)
			(xy 155.239984 -279.568509) (xy 155.193968 -279.551057) (xy 155.151347 -279.52645) (xy 155.113226 -279.495325)
			(xy 155.080591 -279.458488) (xy 155.054288 -279.416892) (xy 155.034997 -279.371616) (xy 155.02322 -279.323832)
			(xy 155.01926 -279.274778) (xy 153.730198 -279.274778) (xy 153.729703 -279.299385) (xy 153.721808 -279.347962)
			(xy 153.706224 -279.394643) (xy 153.683353 -279.43822) (xy 153.653788 -279.477564) (xy 153.618295 -279.511656)
			(xy 153.577792 -279.539612) (xy 153.53333 -279.56071) (xy 153.486059 -279.574402) (xy 153.437204 -279.580334)
			(xy 153.388029 -279.578353) (xy 153.33981 -279.568509) (xy 153.293794 -279.551057) (xy 153.251173 -279.52645)
			(xy 153.213052 -279.495325) (xy 153.180417 -279.458488) (xy 153.154114 -279.416892) (xy 153.134823 -279.371616)
			(xy 153.123046 -279.323832) (xy 153.119086 -279.274778) (xy 152.780238 -279.274778) (xy 152.779743 -279.299385)
			(xy 152.771848 -279.347962) (xy 152.756264 -279.394643) (xy 152.733393 -279.43822) (xy 152.703828 -279.477564)
			(xy 152.668335 -279.511656) (xy 152.627832 -279.539612) (xy 152.58337 -279.56071) (xy 152.536099 -279.574402)
			(xy 152.487244 -279.580334) (xy 152.438069 -279.578353) (xy 152.38985 -279.568509) (xy 152.343834 -279.551057)
			(xy 152.301213 -279.52645) (xy 152.263092 -279.495325) (xy 152.230457 -279.458488) (xy 152.204154 -279.416892)
			(xy 152.184863 -279.371616) (xy 152.173086 -279.323832) (xy 152.169126 -279.274778) (xy 137.120586 -279.274778)
			(xy 137.09923 -279.280881) (xy 136.938764 -279.318383) (xy 136.776661 -279.348018) (xy 136.613305 -279.369715)
			(xy 136.449086 -279.383422) (xy 136.366758 -279.386792) (xy 136.356988 -279.387575) (xy 136.339099 -279.39554)
			(xy 136.325505 -279.409635) (xy 136.318192 -279.4278) (xy 136.317736 -279.437592) (xy 136.317736 -280.693114)
			(xy 147.43811 -280.693114) (xy 147.438654 -280.663732) (xy 147.447683 -280.605665) (xy 147.465514 -280.549671)
			(xy 147.491725 -280.497075) (xy 147.525695 -280.449124) (xy 147.56662 -280.406952) (xy 147.589748 -280.388822)
			(xy 147.599146 -280.381456) (xy 147.60956 -280.360882) (xy 147.611084 -280.256996) (xy 147.601178 -280.235914)
			(xy 147.592034 -280.228548) (xy 147.570186 -280.210342) (xy 147.531644 -280.168524) (xy 147.499736 -280.121449)
			(xy 147.475169 -280.070159) (xy 147.458486 -280.015791) (xy 147.450058 -279.959549) (xy 147.44954 -279.931114)
			(xy 147.450026 -279.903863) (xy 147.457782 -279.849915) (xy 147.473137 -279.79762) (xy 147.495779 -279.748043)
			(xy 147.525245 -279.702193) (xy 147.560936 -279.661002) (xy 147.602127 -279.625311) (xy 147.647977 -279.595845)
			(xy 147.697554 -279.573203) (xy 147.749849 -279.557848) (xy 147.803797 -279.550092) (xy 147.858299 -279.550092)
			(xy 147.912247 -279.557848) (xy 147.964542 -279.573203) (xy 148.014119 -279.595845) (xy 148.059969 -279.625311)
			(xy 148.10116 -279.661002) (xy 148.136851 -279.702193) (xy 148.166317 -279.748043) (xy 148.178725 -279.775212)
			(xy 161.17341 -279.775212) (xy 161.17341 -279.723796) (xy 161.181453 -279.673014) (xy 161.197341 -279.624115)
			(xy 161.220684 -279.578303) (xy 161.250905 -279.536707) (xy 161.287261 -279.500351) (xy 161.328857 -279.47013)
			(xy 161.374669 -279.446787) (xy 161.423568 -279.430899) (xy 161.47435 -279.422856) (xy 161.525766 -279.422856)
			(xy 161.576548 -279.430899) (xy 161.625447 -279.446787) (xy 161.671259 -279.47013) (xy 161.712855 -279.500351)
			(xy 161.749211 -279.536707) (xy 161.779432 -279.578303) (xy 161.802775 -279.624115) (xy 161.818663 -279.673014)
			(xy 161.826706 -279.723796) (xy 161.82721 -279.749504) (xy 161.826706 -279.775212) (xy 163.07333 -279.775212)
			(xy 163.07333 -279.723796) (xy 163.081373 -279.673014) (xy 163.097261 -279.624115) (xy 163.120604 -279.578303)
			(xy 163.150825 -279.536707) (xy 163.187181 -279.500351) (xy 163.228777 -279.47013) (xy 163.274589 -279.446787)
			(xy 163.323488 -279.430899) (xy 163.37427 -279.422856) (xy 163.425686 -279.422856) (xy 163.476468 -279.430899)
			(xy 163.525367 -279.446787) (xy 163.571179 -279.47013) (xy 163.612775 -279.500351) (xy 163.649131 -279.536707)
			(xy 163.679352 -279.578303) (xy 163.702695 -279.624115) (xy 163.718583 -279.673014) (xy 163.726626 -279.723796)
			(xy 163.72713 -279.749504) (xy 163.726626 -279.775212) (xy 163.718583 -279.825994) (xy 163.702695 -279.874893)
			(xy 163.679352 -279.920705) (xy 163.649131 -279.962301) (xy 163.612775 -279.998657) (xy 163.571179 -280.028878)
			(xy 163.525367 -280.052221) (xy 163.476468 -280.068109) (xy 163.425686 -280.076152) (xy 163.37427 -280.076152)
			(xy 163.323488 -280.068109) (xy 163.274589 -280.052221) (xy 163.228777 -280.028878) (xy 163.187181 -279.998657)
			(xy 163.150825 -279.962301) (xy 163.120604 -279.920705) (xy 163.097261 -279.874893) (xy 163.081373 -279.825994)
			(xy 163.07333 -279.775212) (xy 161.826706 -279.775212) (xy 161.818663 -279.825994) (xy 161.802775 -279.874893)
			(xy 161.779432 -279.920705) (xy 161.749211 -279.962301) (xy 161.712855 -279.998657) (xy 161.671259 -280.028878)
			(xy 161.625447 -280.052221) (xy 161.576548 -280.068109) (xy 161.525766 -280.076152) (xy 161.47435 -280.076152)
			(xy 161.423568 -280.068109) (xy 161.374669 -280.052221) (xy 161.328857 -280.028878) (xy 161.287261 -279.998657)
			(xy 161.250905 -279.962301) (xy 161.220684 -279.920705) (xy 161.197341 -279.874893) (xy 161.181453 -279.825994)
			(xy 161.17341 -279.775212) (xy 148.178725 -279.775212) (xy 148.188959 -279.79762) (xy 148.204314 -279.849915)
			(xy 148.21207 -279.903863) (xy 148.212556 -279.931114) (xy 148.212006 -279.960496) (xy 148.202975 -280.018561)
			(xy 148.185143 -280.074554) (xy 148.158933 -280.127149) (xy 148.124966 -280.175101) (xy 148.084044 -280.217274)
			(xy 148.074524 -280.224738) (xy 155.01926 -280.224738) (xy 155.02322 -280.175684) (xy 155.034997 -280.1279)
			(xy 155.054288 -280.082624) (xy 155.080591 -280.041028) (xy 155.113226 -280.004191) (xy 155.151347 -279.973066)
			(xy 155.193968 -279.948459) (xy 155.239984 -279.931007) (xy 155.288203 -279.921163) (xy 155.337378 -279.919182)
			(xy 155.386233 -279.925114) (xy 155.433504 -279.938806) (xy 155.477966 -279.959904) (xy 155.518469 -279.98786)
			(xy 155.553962 -280.021952) (xy 155.583527 -280.061296) (xy 155.606398 -280.104873) (xy 155.621982 -280.151554)
			(xy 155.629877 -280.200131) (xy 155.630372 -280.224738) (xy 156.91918 -280.224738) (xy 156.92314 -280.175684)
			(xy 156.934917 -280.1279) (xy 156.954208 -280.082624) (xy 156.980511 -280.041028) (xy 157.013146 -280.004191)
			(xy 157.051267 -279.973066) (xy 157.093888 -279.948459) (xy 157.139904 -279.931007) (xy 157.188123 -279.921163)
			(xy 157.237298 -279.919182) (xy 157.286153 -279.925114) (xy 157.333424 -279.938806) (xy 157.377886 -279.959904)
			(xy 157.418389 -279.98786) (xy 157.453882 -280.021952) (xy 157.483447 -280.061296) (xy 157.506318 -280.104873)
			(xy 157.521902 -280.151554) (xy 157.529797 -280.200131) (xy 157.530292 -280.224738) (xy 158.8191 -280.224738)
			(xy 158.82306 -280.175684) (xy 158.834837 -280.1279) (xy 158.854128 -280.082624) (xy 158.880431 -280.041028)
			(xy 158.913066 -280.004191) (xy 158.951187 -279.973066) (xy 158.993808 -279.948459) (xy 159.039824 -279.931007)
			(xy 159.088043 -279.921163) (xy 159.137218 -279.919182) (xy 159.186073 -279.925114) (xy 159.233344 -279.938806)
			(xy 159.277806 -279.959904) (xy 159.318309 -279.98786) (xy 159.353802 -280.021952) (xy 159.383367 -280.061296)
			(xy 159.406238 -280.104873) (xy 159.421822 -280.151554) (xy 159.429717 -280.200131) (xy 159.430212 -280.224738)
			(xy 159.429717 -280.249345) (xy 159.421822 -280.297922) (xy 159.406238 -280.344603) (xy 159.383367 -280.38818)
			(xy 159.353802 -280.427524) (xy 159.318309 -280.461616) (xy 159.277806 -280.489572) (xy 159.233344 -280.51067)
			(xy 159.186073 -280.524362) (xy 159.137218 -280.530294) (xy 159.088043 -280.528313) (xy 159.039824 -280.518469)
			(xy 158.993808 -280.501017) (xy 158.951187 -280.47641) (xy 158.913066 -280.445285) (xy 158.880431 -280.408448)
			(xy 158.854128 -280.366852) (xy 158.834837 -280.321576) (xy 158.82306 -280.273792) (xy 158.8191 -280.224738)
			(xy 157.530292 -280.224738) (xy 157.529797 -280.249345) (xy 157.521902 -280.297922) (xy 157.506318 -280.344603)
			(xy 157.483447 -280.38818) (xy 157.453882 -280.427524) (xy 157.418389 -280.461616) (xy 157.377886 -280.489572)
			(xy 157.333424 -280.51067) (xy 157.286153 -280.524362) (xy 157.237298 -280.530294) (xy 157.188123 -280.528313)
			(xy 157.139904 -280.518469) (xy 157.093888 -280.501017) (xy 157.051267 -280.47641) (xy 157.013146 -280.445285)
			(xy 156.980511 -280.408448) (xy 156.954208 -280.366852) (xy 156.934917 -280.321576) (xy 156.92314 -280.273792)
			(xy 156.91918 -280.224738) (xy 155.630372 -280.224738) (xy 155.629877 -280.249345) (xy 155.621982 -280.297922)
			(xy 155.606398 -280.344603) (xy 155.583527 -280.38818) (xy 155.553962 -280.427524) (xy 155.518469 -280.461616)
			(xy 155.477966 -280.489572) (xy 155.433504 -280.51067) (xy 155.386233 -280.524362) (xy 155.337378 -280.530294)
			(xy 155.288203 -280.528313) (xy 155.239984 -280.518469) (xy 155.193968 -280.501017) (xy 155.151347 -280.47641)
			(xy 155.113226 -280.445285) (xy 155.080591 -280.408448) (xy 155.054288 -280.366852) (xy 155.034997 -280.321576)
			(xy 155.02322 -280.273792) (xy 155.01926 -280.224738) (xy 148.074524 -280.224738) (xy 148.060918 -280.235406)
			(xy 148.05152 -280.242772) (xy 148.041106 -280.263346) (xy 148.039582 -280.367232) (xy 148.049488 -280.388314)
			(xy 148.058632 -280.39568) (xy 148.080459 -280.413909) (xy 148.118999 -280.455724) (xy 148.150908 -280.502795)
			(xy 148.175478 -280.55408) (xy 148.192166 -280.608443) (xy 148.200603 -280.664681) (xy 148.201126 -280.693114)
			(xy 148.8346 -280.693114) (xy 148.838671 -280.637492) (xy 148.850797 -280.583055) (xy 148.87072 -280.530964)
			(xy 148.898016 -280.482329) (xy 148.932102 -280.438186) (xy 148.972251 -280.399477) (xy 149.017609 -280.367026)
			(xy 149.067209 -280.341525) (xy 149.119993 -280.323518) (xy 149.174836 -280.313388) (xy 149.23057 -280.311351)
			(xy 149.286007 -280.317451) (xy 149.339964 -280.331557) (xy 149.391293 -280.353369) (xy 149.438899 -280.382423)
			(xy 149.481767 -280.418098) (xy 149.518984 -280.459635) (xy 149.549757 -280.506148) (xy 149.573429 -280.556645)
			(xy 149.589497 -280.610052) (xy 149.597617 -280.665228) (xy 149.598126 -280.693114) (xy 149.597617 -280.721)
			(xy 149.596966 -280.725426) (xy 161.17341 -280.725426) (xy 161.17341 -280.67401) (xy 161.181453 -280.623228)
			(xy 161.197341 -280.574329) (xy 161.220684 -280.528517) (xy 161.250905 -280.486921) (xy 161.287261 -280.450565)
			(xy 161.328857 -280.420344) (xy 161.374669 -280.397001) (xy 161.423568 -280.381113) (xy 161.47435 -280.37307)
			(xy 161.525766 -280.37307) (xy 161.576548 -280.381113) (xy 161.625447 -280.397001) (xy 161.671259 -280.420344)
			(xy 161.712855 -280.450565) (xy 161.749211 -280.486921) (xy 161.779432 -280.528517) (xy 161.802775 -280.574329)
			(xy 161.818663 -280.623228) (xy 161.826706 -280.67401) (xy 161.82721 -280.699718) (xy 161.826706 -280.725426)
			(xy 163.07333 -280.725426) (xy 163.07333 -280.67401) (xy 163.081373 -280.623228) (xy 163.097261 -280.574329)
			(xy 163.120604 -280.528517) (xy 163.150825 -280.486921) (xy 163.187181 -280.450565) (xy 163.228777 -280.420344)
			(xy 163.274589 -280.397001) (xy 163.323488 -280.381113) (xy 163.37427 -280.37307) (xy 163.425686 -280.37307)
			(xy 163.476468 -280.381113) (xy 163.525367 -280.397001) (xy 163.571179 -280.420344) (xy 163.612775 -280.450565)
			(xy 163.649131 -280.486921) (xy 163.679352 -280.528517) (xy 163.702695 -280.574329) (xy 163.718583 -280.623228)
			(xy 163.726626 -280.67401) (xy 163.72713 -280.699718) (xy 163.726626 -280.725426) (xy 163.718583 -280.776208)
			(xy 163.702695 -280.825107) (xy 163.679352 -280.870919) (xy 163.649131 -280.912515) (xy 163.612775 -280.948871)
			(xy 163.571179 -280.979092) (xy 163.525367 -281.002435) (xy 163.476468 -281.018323) (xy 163.425686 -281.026366)
			(xy 163.37427 -281.026366) (xy 163.323488 -281.018323) (xy 163.274589 -281.002435) (xy 163.228777 -280.979092)
			(xy 163.187181 -280.948871) (xy 163.150825 -280.912515) (xy 163.120604 -280.870919) (xy 163.097261 -280.825107)
			(xy 163.081373 -280.776208) (xy 163.07333 -280.725426) (xy 161.826706 -280.725426) (xy 161.818663 -280.776208)
			(xy 161.802775 -280.825107) (xy 161.779432 -280.870919) (xy 161.749211 -280.912515) (xy 161.712855 -280.948871)
			(xy 161.671259 -280.979092) (xy 161.625447 -281.002435) (xy 161.576548 -281.018323) (xy 161.525766 -281.026366)
			(xy 161.47435 -281.026366) (xy 161.423568 -281.018323) (xy 161.374669 -281.002435) (xy 161.328857 -280.979092)
			(xy 161.287261 -280.948871) (xy 161.250905 -280.912515) (xy 161.220684 -280.870919) (xy 161.197341 -280.825107)
			(xy 161.181453 -280.776208) (xy 161.17341 -280.725426) (xy 149.596966 -280.725426) (xy 149.589497 -280.776176)
			(xy 149.573429 -280.829583) (xy 149.549757 -280.88008) (xy 149.518984 -280.926593) (xy 149.481767 -280.96813)
			(xy 149.438899 -281.003805) (xy 149.391293 -281.032859) (xy 149.339964 -281.054671) (xy 149.286007 -281.068777)
			(xy 149.23057 -281.074877) (xy 149.174836 -281.07284) (xy 149.119993 -281.06271) (xy 149.067209 -281.044703)
			(xy 149.017609 -281.019202) (xy 148.972251 -280.986751) (xy 148.932102 -280.948042) (xy 148.898016 -280.903899)
			(xy 148.87072 -280.855264) (xy 148.850797 -280.803173) (xy 148.838671 -280.748736) (xy 148.8346 -280.693114)
			(xy 148.201126 -280.693114) (xy 148.20064 -280.720365) (xy 148.192884 -280.774313) (xy 148.177529 -280.826608)
			(xy 148.154887 -280.876185) (xy 148.125421 -280.922035) (xy 148.08973 -280.963226) (xy 148.048539 -280.998917)
			(xy 148.002689 -281.028383) (xy 147.953112 -281.051025) (xy 147.900817 -281.06638) (xy 147.846869 -281.074136)
			(xy 147.792367 -281.074136) (xy 147.738419 -281.06638) (xy 147.686124 -281.051025) (xy 147.636547 -281.028383)
			(xy 147.590697 -280.998917) (xy 147.549506 -280.963226) (xy 147.513815 -280.922035) (xy 147.484349 -280.876185)
			(xy 147.461707 -280.826608) (xy 147.446352 -280.774313) (xy 147.438596 -280.720365) (xy 147.43811 -280.693114)
			(xy 136.317736 -280.693114) (xy 136.317736 -281.174952) (xy 152.169126 -281.174952) (xy 152.173086 -281.125898)
			(xy 152.184863 -281.078114) (xy 152.204154 -281.032838) (xy 152.230457 -280.991242) (xy 152.263092 -280.954405)
			(xy 152.301213 -280.92328) (xy 152.343834 -280.898673) (xy 152.38985 -280.881221) (xy 152.438069 -280.871377)
			(xy 152.487244 -280.869396) (xy 152.536099 -280.875328) (xy 152.58337 -280.88902) (xy 152.627832 -280.910118)
			(xy 152.668335 -280.938074) (xy 152.703828 -280.972166) (xy 152.733393 -281.01151) (xy 152.756264 -281.055087)
			(xy 152.771848 -281.101768) (xy 152.779743 -281.150345) (xy 152.780238 -281.174952) (xy 153.119086 -281.174952)
			(xy 153.123046 -281.125898) (xy 153.134823 -281.078114) (xy 153.154114 -281.032838) (xy 153.180417 -280.991242)
			(xy 153.213052 -280.954405) (xy 153.251173 -280.92328) (xy 153.293794 -280.898673) (xy 153.33981 -280.881221)
			(xy 153.388029 -280.871377) (xy 153.437204 -280.869396) (xy 153.486059 -280.875328) (xy 153.53333 -280.88902)
			(xy 153.577792 -280.910118) (xy 153.618295 -280.938074) (xy 153.653788 -280.972166) (xy 153.683353 -281.01151)
			(xy 153.706224 -281.055087) (xy 153.721808 -281.101768) (xy 153.729703 -281.150345) (xy 153.730198 -281.174952)
			(xy 153.729703 -281.199559) (xy 153.721808 -281.248136) (xy 153.706224 -281.294817) (xy 153.683353 -281.338394)
			(xy 153.653788 -281.377738) (xy 153.618295 -281.41183) (xy 153.577792 -281.439786) (xy 153.53333 -281.460884)
			(xy 153.486059 -281.474576) (xy 153.437204 -281.480508) (xy 153.388029 -281.478527) (xy 153.33981 -281.468683)
			(xy 153.293794 -281.451231) (xy 153.251173 -281.426624) (xy 153.213052 -281.395499) (xy 153.180417 -281.358662)
			(xy 153.154114 -281.317066) (xy 153.134823 -281.27179) (xy 153.123046 -281.224006) (xy 153.119086 -281.174952)
			(xy 152.780238 -281.174952) (xy 152.779743 -281.199559) (xy 152.771848 -281.248136) (xy 152.756264 -281.294817)
			(xy 152.733393 -281.338394) (xy 152.703828 -281.377738) (xy 152.668335 -281.41183) (xy 152.627832 -281.439786)
			(xy 152.58337 -281.460884) (xy 152.536099 -281.474576) (xy 152.487244 -281.480508) (xy 152.438069 -281.478527)
			(xy 152.38985 -281.468683) (xy 152.343834 -281.451231) (xy 152.301213 -281.426624) (xy 152.263092 -281.395499)
			(xy 152.230457 -281.358662) (xy 152.204154 -281.317066) (xy 152.184863 -281.27179) (xy 152.173086 -281.224006)
			(xy 152.169126 -281.174952) (xy 136.317736 -281.174952) (xy 136.317736 -281.829256) (xy 141.911576 -281.829256)
			(xy 141.915647 -281.773634) (xy 141.927773 -281.719197) (xy 141.947696 -281.667106) (xy 141.974992 -281.618471)
			(xy 142.009078 -281.574328) (xy 142.049227 -281.535619) (xy 142.094585 -281.503168) (xy 142.144185 -281.477667)
			(xy 142.196969 -281.45966) (xy 142.251812 -281.44953) (xy 142.307546 -281.447493) (xy 142.362983 -281.453593)
			(xy 142.41694 -281.467699) (xy 142.468269 -281.489511) (xy 142.515875 -281.518565) (xy 142.558743 -281.55424)
			(xy 142.59596 -281.595777) (xy 142.626733 -281.64229) (xy 142.650405 -281.692787) (xy 142.666473 -281.746194)
			(xy 142.674593 -281.80137) (xy 142.675102 -281.829256) (xy 143.396714 -281.829256) (xy 143.400785 -281.773634)
			(xy 143.412911 -281.719197) (xy 143.432834 -281.667106) (xy 143.46013 -281.618471) (xy 143.494216 -281.574328)
			(xy 143.534365 -281.535619) (xy 143.579723 -281.503168) (xy 143.629323 -281.477667) (xy 143.682107 -281.45966)
			(xy 143.73695 -281.44953) (xy 143.792684 -281.447493) (xy 143.848121 -281.453593) (xy 143.902078 -281.467699)
			(xy 143.953407 -281.489511) (xy 144.001013 -281.518565) (xy 144.043881 -281.55424) (xy 144.081098 -281.595777)
			(xy 144.111871 -281.64229) (xy 144.135543 -281.692787) (xy 144.151611 -281.746194) (xy 144.159731 -281.80137)
			(xy 144.16024 -281.829256) (xy 144.159731 -281.857142) (xy 144.151611 -281.912318) (xy 144.135543 -281.965725)
			(xy 144.111871 -282.016222) (xy 144.081098 -282.062735) (xy 144.043881 -282.104272) (xy 144.019079 -282.124912)
			(xy 154.0693 -282.124912) (xy 154.07326 -282.075858) (xy 154.085037 -282.028074) (xy 154.104328 -281.982798)
			(xy 154.130631 -281.941202) (xy 154.163266 -281.904365) (xy 154.201387 -281.87324) (xy 154.244008 -281.848633)
			(xy 154.290024 -281.831181) (xy 154.338243 -281.821337) (xy 154.387418 -281.819356) (xy 154.436273 -281.825288)
			(xy 154.483544 -281.83898) (xy 154.528006 -281.860078) (xy 154.568509 -281.888034) (xy 154.604002 -281.922126)
			(xy 154.633567 -281.96147) (xy 154.656438 -282.005047) (xy 154.672022 -282.051728) (xy 154.679917 -282.100305)
			(xy 154.680412 -282.124912) (xy 155.01926 -282.124912) (xy 155.02322 -282.075858) (xy 155.034997 -282.028074)
			(xy 155.054288 -281.982798) (xy 155.080591 -281.941202) (xy 155.113226 -281.904365) (xy 155.151347 -281.87324)
			(xy 155.193968 -281.848633) (xy 155.239984 -281.831181) (xy 155.288203 -281.821337) (xy 155.337378 -281.819356)
			(xy 155.386233 -281.825288) (xy 155.433504 -281.83898) (xy 155.477966 -281.860078) (xy 155.518469 -281.888034)
			(xy 155.553962 -281.922126) (xy 155.583527 -281.96147) (xy 155.606398 -282.005047) (xy 155.621982 -282.051728)
			(xy 155.629877 -282.100305) (xy 155.630372 -282.124912) (xy 156.91918 -282.124912) (xy 156.92314 -282.075858)
			(xy 156.934917 -282.028074) (xy 156.954208 -281.982798) (xy 156.980511 -281.941202) (xy 157.013146 -281.904365)
			(xy 157.051267 -281.87324) (xy 157.093888 -281.848633) (xy 157.139904 -281.831181) (xy 157.188123 -281.821337)
			(xy 157.237298 -281.819356) (xy 157.286153 -281.825288) (xy 157.333424 -281.83898) (xy 157.377886 -281.860078)
			(xy 157.418389 -281.888034) (xy 157.453882 -281.922126) (xy 157.483447 -281.96147) (xy 157.506318 -282.005047)
			(xy 157.521902 -282.051728) (xy 157.529797 -282.100305) (xy 157.530292 -282.124912) (xy 157.86914 -282.124912)
			(xy 157.8731 -282.075858) (xy 157.884877 -282.028074) (xy 157.904168 -281.982798) (xy 157.930471 -281.941202)
			(xy 157.963106 -281.904365) (xy 158.001227 -281.87324) (xy 158.043848 -281.848633) (xy 158.089864 -281.831181)
			(xy 158.138083 -281.821337) (xy 158.187258 -281.819356) (xy 158.236113 -281.825288) (xy 158.283384 -281.83898)
			(xy 158.327846 -281.860078) (xy 158.368349 -281.888034) (xy 158.403842 -281.922126) (xy 158.433407 -281.96147)
			(xy 158.456278 -282.005047) (xy 158.471862 -282.051728) (xy 158.479757 -282.100305) (xy 158.480252 -282.124912)
			(xy 158.479757 -282.149519) (xy 158.471862 -282.198096) (xy 158.456278 -282.244777) (xy 158.433407 -282.288354)
			(xy 158.403842 -282.327698) (xy 158.368349 -282.36179) (xy 158.327846 -282.389746) (xy 158.283384 -282.410844)
			(xy 158.236113 -282.424536) (xy 158.187258 -282.430468) (xy 158.138083 -282.428487) (xy 158.089864 -282.418643)
			(xy 158.043848 -282.401191) (xy 158.001227 -282.376584) (xy 157.963106 -282.345459) (xy 157.930471 -282.308622)
			(xy 157.904168 -282.267026) (xy 157.884877 -282.22175) (xy 157.8731 -282.173966) (xy 157.86914 -282.124912)
			(xy 157.530292 -282.124912) (xy 157.529797 -282.149519) (xy 157.521902 -282.198096) (xy 157.506318 -282.244777)
			(xy 157.483447 -282.288354) (xy 157.453882 -282.327698) (xy 157.418389 -282.36179) (xy 157.377886 -282.389746)
			(xy 157.333424 -282.410844) (xy 157.286153 -282.424536) (xy 157.237298 -282.430468) (xy 157.188123 -282.428487)
			(xy 157.139904 -282.418643) (xy 157.093888 -282.401191) (xy 157.051267 -282.376584) (xy 157.013146 -282.345459)
			(xy 156.980511 -282.308622) (xy 156.954208 -282.267026) (xy 156.934917 -282.22175) (xy 156.92314 -282.173966)
			(xy 156.91918 -282.124912) (xy 155.630372 -282.124912) (xy 155.629877 -282.149519) (xy 155.621982 -282.198096)
			(xy 155.606398 -282.244777) (xy 155.583527 -282.288354) (xy 155.553962 -282.327698) (xy 155.518469 -282.36179)
			(xy 155.477966 -282.389746) (xy 155.433504 -282.410844) (xy 155.386233 -282.424536) (xy 155.337378 -282.430468)
			(xy 155.288203 -282.428487) (xy 155.239984 -282.418643) (xy 155.193968 -282.401191) (xy 155.151347 -282.376584)
			(xy 155.113226 -282.345459) (xy 155.080591 -282.308622) (xy 155.054288 -282.267026) (xy 155.034997 -282.22175)
			(xy 155.02322 -282.173966) (xy 155.01926 -282.124912) (xy 154.680412 -282.124912) (xy 154.679917 -282.149519)
			(xy 154.672022 -282.198096) (xy 154.656438 -282.244777) (xy 154.633567 -282.288354) (xy 154.604002 -282.327698)
			(xy 154.568509 -282.36179) (xy 154.528006 -282.389746) (xy 154.483544 -282.410844) (xy 154.436273 -282.424536)
			(xy 154.387418 -282.430468) (xy 154.338243 -282.428487) (xy 154.290024 -282.418643) (xy 154.244008 -282.401191)
			(xy 154.201387 -282.376584) (xy 154.163266 -282.345459) (xy 154.130631 -282.308622) (xy 154.104328 -282.267026)
			(xy 154.085037 -282.22175) (xy 154.07326 -282.173966) (xy 154.0693 -282.124912) (xy 144.019079 -282.124912)
			(xy 144.001013 -282.139947) (xy 143.953407 -282.169001) (xy 143.902078 -282.190813) (xy 143.848121 -282.204919)
			(xy 143.792684 -282.211019) (xy 143.73695 -282.208982) (xy 143.682107 -282.198852) (xy 143.629323 -282.180845)
			(xy 143.579723 -282.155344) (xy 143.534365 -282.122893) (xy 143.494216 -282.084184) (xy 143.46013 -282.040041)
			(xy 143.432834 -281.991406) (xy 143.412911 -281.939315) (xy 143.400785 -281.884878) (xy 143.396714 -281.829256)
			(xy 142.675102 -281.829256) (xy 142.674593 -281.857142) (xy 142.666473 -281.912318) (xy 142.650405 -281.965725)
			(xy 142.626733 -282.016222) (xy 142.59596 -282.062735) (xy 142.558743 -282.104272) (xy 142.515875 -282.139947)
			(xy 142.468269 -282.169001) (xy 142.41694 -282.190813) (xy 142.362983 -282.204919) (xy 142.307546 -282.211019)
			(xy 142.251812 -282.208982) (xy 142.196969 -282.198852) (xy 142.144185 -282.180845) (xy 142.094585 -282.155344)
			(xy 142.049227 -282.122893) (xy 142.009078 -282.084184) (xy 141.974992 -282.040041) (xy 141.947696 -281.991406)
			(xy 141.927773 -281.939315) (xy 141.915647 -281.884878) (xy 141.911576 -281.829256) (xy 136.317736 -281.829256)
			(xy 136.317736 -284.061154) (xy 140.967204 -284.061154) (xy 140.971275 -284.005532) (xy 140.983401 -283.951095)
			(xy 141.003324 -283.899004) (xy 141.03062 -283.850369) (xy 141.064706 -283.806226) (xy 141.104855 -283.767517)
			(xy 141.150213 -283.735066) (xy 141.199813 -283.709565) (xy 141.252597 -283.691558) (xy 141.30744 -283.681428)
			(xy 141.363174 -283.679391) (xy 141.418611 -283.685491) (xy 141.472568 -283.699597) (xy 141.523897 -283.721409)
			(xy 141.571503 -283.750463) (xy 141.614371 -283.786138) (xy 141.651588 -283.827675) (xy 141.682361 -283.874188)
			(xy 141.691421 -283.893514) (xy 147.43811 -283.893514) (xy 147.438654 -283.864132) (xy 147.447683 -283.806065)
			(xy 147.465514 -283.750071) (xy 147.491725 -283.697475) (xy 147.525695 -283.649524) (xy 147.56662 -283.607352)
			(xy 147.589748 -283.589222) (xy 147.599146 -283.581856) (xy 147.60956 -283.561282) (xy 147.611084 -283.457396)
			(xy 147.601178 -283.436314) (xy 147.592034 -283.428948) (xy 147.570186 -283.410742) (xy 147.531644 -283.368924)
			(xy 147.499736 -283.321849) (xy 147.475169 -283.270559) (xy 147.458486 -283.216191) (xy 147.450058 -283.159949)
			(xy 147.44954 -283.131514) (xy 147.450026 -283.104263) (xy 147.457782 -283.050315) (xy 147.473137 -282.99802)
			(xy 147.495779 -282.948443) (xy 147.525245 -282.902593) (xy 147.560936 -282.861402) (xy 147.602127 -282.825711)
			(xy 147.647977 -282.796245) (xy 147.697554 -282.773603) (xy 147.749849 -282.758248) (xy 147.803797 -282.750492)
			(xy 147.858299 -282.750492) (xy 147.912247 -282.758248) (xy 147.964542 -282.773603) (xy 148.014119 -282.796245)
			(xy 148.059969 -282.825711) (xy 148.10116 -282.861402) (xy 148.136851 -282.902593) (xy 148.166317 -282.948443)
			(xy 148.188959 -282.99802) (xy 148.204314 -283.050315) (xy 148.207845 -283.074872) (xy 152.169126 -283.074872)
			(xy 152.173086 -283.025818) (xy 152.184863 -282.978034) (xy 152.204154 -282.932758) (xy 152.230457 -282.891162)
			(xy 152.263092 -282.854325) (xy 152.301213 -282.8232) (xy 152.343834 -282.798593) (xy 152.38985 -282.781141)
			(xy 152.438069 -282.771297) (xy 152.487244 -282.769316) (xy 152.536099 -282.775248) (xy 152.58337 -282.78894)
			(xy 152.627832 -282.810038) (xy 152.668335 -282.837994) (xy 152.703828 -282.872086) (xy 152.733393 -282.91143)
			(xy 152.756264 -282.955007) (xy 152.771848 -283.001688) (xy 152.779743 -283.050265) (xy 152.780238 -283.074872)
			(xy 153.119086 -283.074872) (xy 153.123046 -283.025818) (xy 153.134823 -282.978034) (xy 153.154114 -282.932758)
			(xy 153.180417 -282.891162) (xy 153.213052 -282.854325) (xy 153.251173 -282.8232) (xy 153.293794 -282.798593)
			(xy 153.33981 -282.781141) (xy 153.388029 -282.771297) (xy 153.437204 -282.769316) (xy 153.486059 -282.775248)
			(xy 153.53333 -282.78894) (xy 153.577792 -282.810038) (xy 153.618295 -282.837994) (xy 153.653788 -282.872086)
			(xy 153.683353 -282.91143) (xy 153.706224 -282.955007) (xy 153.721808 -283.001688) (xy 153.729703 -283.050265)
			(xy 153.730198 -283.074872) (xy 158.8191 -283.074872) (xy 158.82306 -283.025818) (xy 158.834837 -282.978034)
			(xy 158.854128 -282.932758) (xy 158.880431 -282.891162) (xy 158.913066 -282.854325) (xy 158.951187 -282.8232)
			(xy 158.993808 -282.798593) (xy 159.039824 -282.781141) (xy 159.088043 -282.771297) (xy 159.137218 -282.769316)
			(xy 159.186073 -282.775248) (xy 159.233344 -282.78894) (xy 159.277806 -282.810038) (xy 159.318309 -282.837994)
			(xy 159.353802 -282.872086) (xy 159.383367 -282.91143) (xy 159.406238 -282.955007) (xy 159.421822 -283.001688)
			(xy 159.429717 -283.050265) (xy 159.430212 -283.074872) (xy 159.76906 -283.074872) (xy 159.77302 -283.025818)
			(xy 159.784797 -282.978034) (xy 159.804088 -282.932758) (xy 159.830391 -282.891162) (xy 159.863026 -282.854325)
			(xy 159.901147 -282.8232) (xy 159.943768 -282.798593) (xy 159.989784 -282.781141) (xy 160.038003 -282.771297)
			(xy 160.087178 -282.769316) (xy 160.136033 -282.775248) (xy 160.183304 -282.78894) (xy 160.227766 -282.810038)
			(xy 160.268269 -282.837994) (xy 160.303762 -282.872086) (xy 160.333327 -282.91143) (xy 160.356198 -282.955007)
			(xy 160.371782 -283.001688) (xy 160.379677 -283.050265) (xy 160.380172 -283.074872) (xy 162.619194 -283.074872)
			(xy 162.623154 -283.025818) (xy 162.634931 -282.978034) (xy 162.654222 -282.932758) (xy 162.680525 -282.891162)
			(xy 162.71316 -282.854325) (xy 162.751281 -282.8232) (xy 162.793902 -282.798593) (xy 162.839918 -282.781141)
			(xy 162.888137 -282.771297) (xy 162.937312 -282.769316) (xy 162.986167 -282.775248) (xy 163.033438 -282.78894)
			(xy 163.0779 -282.810038) (xy 163.118403 -282.837994) (xy 163.153896 -282.872086) (xy 163.183461 -282.91143)
			(xy 163.206332 -282.955007) (xy 163.221916 -283.001688) (xy 163.229811 -283.050265) (xy 163.230306 -283.074872)
			(xy 163.569154 -283.074872) (xy 163.573114 -283.025818) (xy 163.584891 -282.978034) (xy 163.604182 -282.932758)
			(xy 163.630485 -282.891162) (xy 163.66312 -282.854325) (xy 163.701241 -282.8232) (xy 163.743862 -282.798593)
			(xy 163.789878 -282.781141) (xy 163.838097 -282.771297) (xy 163.887272 -282.769316) (xy 163.936127 -282.775248)
			(xy 163.983398 -282.78894) (xy 164.02786 -282.810038) (xy 164.068363 -282.837994) (xy 164.103856 -282.872086)
			(xy 164.133421 -282.91143) (xy 164.156292 -282.955007) (xy 164.171876 -283.001688) (xy 164.179771 -283.050265)
			(xy 164.180266 -283.074872) (xy 164.179771 -283.099479) (xy 164.171876 -283.148056) (xy 164.156292 -283.194737)
			(xy 164.133421 -283.238314) (xy 164.103856 -283.277658) (xy 164.068363 -283.31175) (xy 164.02786 -283.339706)
			(xy 163.983398 -283.360804) (xy 163.936127 -283.374496) (xy 163.887272 -283.380428) (xy 163.838097 -283.378447)
			(xy 163.789878 -283.368603) (xy 163.743862 -283.351151) (xy 163.701241 -283.326544) (xy 163.66312 -283.295419)
			(xy 163.630485 -283.258582) (xy 163.604182 -283.216986) (xy 163.584891 -283.17171) (xy 163.573114 -283.123926)
			(xy 163.569154 -283.074872) (xy 163.230306 -283.074872) (xy 163.229811 -283.099479) (xy 163.221916 -283.148056)
			(xy 163.206332 -283.194737) (xy 163.183461 -283.238314) (xy 163.153896 -283.277658) (xy 163.118403 -283.31175)
			(xy 163.0779 -283.339706) (xy 163.033438 -283.360804) (xy 162.986167 -283.374496) (xy 162.937312 -283.380428)
			(xy 162.888137 -283.378447) (xy 162.839918 -283.368603) (xy 162.793902 -283.351151) (xy 162.751281 -283.326544)
			(xy 162.71316 -283.295419) (xy 162.680525 -283.258582) (xy 162.654222 -283.216986) (xy 162.634931 -283.17171)
			(xy 162.623154 -283.123926) (xy 162.619194 -283.074872) (xy 160.380172 -283.074872) (xy 160.379677 -283.099479)
			(xy 160.371782 -283.148056) (xy 160.356198 -283.194737) (xy 160.333327 -283.238314) (xy 160.303762 -283.277658)
			(xy 160.268269 -283.31175) (xy 160.227766 -283.339706) (xy 160.183304 -283.360804) (xy 160.136033 -283.374496)
			(xy 160.087178 -283.380428) (xy 160.038003 -283.378447) (xy 159.989784 -283.368603) (xy 159.943768 -283.351151)
			(xy 159.901147 -283.326544) (xy 159.863026 -283.295419) (xy 159.830391 -283.258582) (xy 159.804088 -283.216986)
			(xy 159.784797 -283.17171) (xy 159.77302 -283.123926) (xy 159.76906 -283.074872) (xy 159.430212 -283.074872)
			(xy 159.429717 -283.099479) (xy 159.421822 -283.148056) (xy 159.406238 -283.194737) (xy 159.383367 -283.238314)
			(xy 159.353802 -283.277658) (xy 159.318309 -283.31175) (xy 159.277806 -283.339706) (xy 159.233344 -283.360804)
			(xy 159.186073 -283.374496) (xy 159.137218 -283.380428) (xy 159.088043 -283.378447) (xy 159.039824 -283.368603)
			(xy 158.993808 -283.351151) (xy 158.951187 -283.326544) (xy 158.913066 -283.295419) (xy 158.880431 -283.258582)
			(xy 158.854128 -283.216986) (xy 158.834837 -283.17171) (xy 158.82306 -283.123926) (xy 158.8191 -283.074872)
			(xy 153.730198 -283.074872) (xy 153.729703 -283.099479) (xy 153.721808 -283.148056) (xy 153.706224 -283.194737)
			(xy 153.683353 -283.238314) (xy 153.653788 -283.277658) (xy 153.618295 -283.31175) (xy 153.577792 -283.339706)
			(xy 153.53333 -283.360804) (xy 153.486059 -283.374496) (xy 153.437204 -283.380428) (xy 153.388029 -283.378447)
			(xy 153.33981 -283.368603) (xy 153.293794 -283.351151) (xy 153.251173 -283.326544) (xy 153.213052 -283.295419)
			(xy 153.180417 -283.258582) (xy 153.154114 -283.216986) (xy 153.134823 -283.17171) (xy 153.123046 -283.123926)
			(xy 153.119086 -283.074872) (xy 152.780238 -283.074872) (xy 152.779743 -283.099479) (xy 152.771848 -283.148056)
			(xy 152.756264 -283.194737) (xy 152.733393 -283.238314) (xy 152.703828 -283.277658) (xy 152.668335 -283.31175)
			(xy 152.627832 -283.339706) (xy 152.58337 -283.360804) (xy 152.536099 -283.374496) (xy 152.487244 -283.380428)
			(xy 152.438069 -283.378447) (xy 152.38985 -283.368603) (xy 152.343834 -283.351151) (xy 152.301213 -283.326544)
			(xy 152.263092 -283.295419) (xy 152.230457 -283.258582) (xy 152.204154 -283.216986) (xy 152.184863 -283.17171)
			(xy 152.173086 -283.123926) (xy 152.169126 -283.074872) (xy 148.207845 -283.074872) (xy 148.21207 -283.104263)
			(xy 148.212556 -283.131514) (xy 148.212006 -283.160896) (xy 148.202975 -283.218961) (xy 148.185143 -283.274954)
			(xy 148.158933 -283.327549) (xy 148.124966 -283.375501) (xy 148.084044 -283.417674) (xy 148.060918 -283.435806)
			(xy 148.05152 -283.443172) (xy 148.041106 -283.463746) (xy 148.039582 -283.567632) (xy 148.049488 -283.588714)
			(xy 148.058632 -283.59608) (xy 148.080459 -283.614309) (xy 148.118999 -283.656124) (xy 148.150908 -283.703195)
			(xy 148.175478 -283.75448) (xy 148.192166 -283.808843) (xy 148.200603 -283.865081) (xy 148.201126 -283.893514)
			(xy 148.8346 -283.893514) (xy 148.838671 -283.837892) (xy 148.850797 -283.783455) (xy 148.87072 -283.731364)
			(xy 148.898016 -283.682729) (xy 148.932102 -283.638586) (xy 148.972251 -283.599877) (xy 149.017609 -283.567426)
			(xy 149.067209 -283.541925) (xy 149.119993 -283.523918) (xy 149.174836 -283.513788) (xy 149.23057 -283.511751)
			(xy 149.286007 -283.517851) (xy 149.339964 -283.531957) (xy 149.391293 -283.553769) (xy 149.438899 -283.582823)
			(xy 149.481767 -283.618498) (xy 149.518984 -283.660035) (xy 149.549757 -283.706548) (xy 149.573429 -283.757045)
			(xy 149.589497 -283.810452) (xy 149.597617 -283.865628) (xy 149.598126 -283.893514) (xy 149.597617 -283.9214)
			(xy 149.589497 -283.976576) (xy 149.574979 -284.024832) (xy 154.0693 -284.024832) (xy 154.07326 -283.975778)
			(xy 154.085037 -283.927994) (xy 154.104328 -283.882718) (xy 154.130631 -283.841122) (xy 154.163266 -283.804285)
			(xy 154.201387 -283.77316) (xy 154.244008 -283.748553) (xy 154.290024 -283.731101) (xy 154.338243 -283.721257)
			(xy 154.387418 -283.719276) (xy 154.436273 -283.725208) (xy 154.483544 -283.7389) (xy 154.528006 -283.759998)
			(xy 154.568509 -283.787954) (xy 154.604002 -283.822046) (xy 154.633567 -283.86139) (xy 154.656438 -283.904967)
			(xy 154.672022 -283.951648) (xy 154.679917 -284.000225) (xy 154.680412 -284.024832) (xy 155.01926 -284.024832)
			(xy 155.02322 -283.975778) (xy 155.034997 -283.927994) (xy 155.054288 -283.882718) (xy 155.080591 -283.841122)
			(xy 155.113226 -283.804285) (xy 155.151347 -283.77316) (xy 155.193968 -283.748553) (xy 155.239984 -283.731101)
			(xy 155.288203 -283.721257) (xy 155.337378 -283.719276) (xy 155.386233 -283.725208) (xy 155.433504 -283.7389)
			(xy 155.477966 -283.759998) (xy 155.518469 -283.787954) (xy 155.553962 -283.822046) (xy 155.583527 -283.86139)
			(xy 155.606398 -283.904967) (xy 155.621982 -283.951648) (xy 155.629877 -284.000225) (xy 155.630372 -284.024832)
			(xy 156.91918 -284.024832) (xy 156.92314 -283.975778) (xy 156.934917 -283.927994) (xy 156.954208 -283.882718)
			(xy 156.980511 -283.841122) (xy 157.013146 -283.804285) (xy 157.051267 -283.77316) (xy 157.093888 -283.748553)
			(xy 157.139904 -283.731101) (xy 157.188123 -283.721257) (xy 157.237298 -283.719276) (xy 157.286153 -283.725208)
			(xy 157.333424 -283.7389) (xy 157.377886 -283.759998) (xy 157.418389 -283.787954) (xy 157.453882 -283.822046)
			(xy 157.483447 -283.86139) (xy 157.506318 -283.904967) (xy 157.521902 -283.951648) (xy 157.529797 -284.000225)
			(xy 157.530292 -284.024832) (xy 157.86914 -284.024832) (xy 157.8731 -283.975778) (xy 157.884877 -283.927994)
			(xy 157.904168 -283.882718) (xy 157.930471 -283.841122) (xy 157.963106 -283.804285) (xy 158.001227 -283.77316)
			(xy 158.043848 -283.748553) (xy 158.089864 -283.731101) (xy 158.138083 -283.721257) (xy 158.187258 -283.719276)
			(xy 158.236113 -283.725208) (xy 158.283384 -283.7389) (xy 158.327846 -283.759998) (xy 158.368349 -283.787954)
			(xy 158.403842 -283.822046) (xy 158.433407 -283.86139) (xy 158.456278 -283.904967) (xy 158.471862 -283.951648)
			(xy 158.479757 -284.000225) (xy 158.480252 -284.024832) (xy 158.479757 -284.049439) (xy 158.471862 -284.098016)
			(xy 158.456278 -284.144697) (xy 158.433407 -284.188274) (xy 158.403842 -284.227618) (xy 158.368349 -284.26171)
			(xy 158.327846 -284.289666) (xy 158.283384 -284.310764) (xy 158.236113 -284.324456) (xy 158.187258 -284.330388)
			(xy 158.138083 -284.328407) (xy 158.089864 -284.318563) (xy 158.043848 -284.301111) (xy 158.001227 -284.276504)
			(xy 157.963106 -284.245379) (xy 157.930471 -284.208542) (xy 157.904168 -284.166946) (xy 157.884877 -284.12167)
			(xy 157.8731 -284.073886) (xy 157.86914 -284.024832) (xy 157.530292 -284.024832) (xy 157.529797 -284.049439)
			(xy 157.521902 -284.098016) (xy 157.506318 -284.144697) (xy 157.483447 -284.188274) (xy 157.453882 -284.227618)
			(xy 157.418389 -284.26171) (xy 157.377886 -284.289666) (xy 157.333424 -284.310764) (xy 157.286153 -284.324456)
			(xy 157.237298 -284.330388) (xy 157.188123 -284.328407) (xy 157.139904 -284.318563) (xy 157.093888 -284.301111)
			(xy 157.051267 -284.276504) (xy 157.013146 -284.245379) (xy 156.980511 -284.208542) (xy 156.954208 -284.166946)
			(xy 156.934917 -284.12167) (xy 156.92314 -284.073886) (xy 156.91918 -284.024832) (xy 155.630372 -284.024832)
			(xy 155.629877 -284.049439) (xy 155.621982 -284.098016) (xy 155.606398 -284.144697) (xy 155.583527 -284.188274)
			(xy 155.553962 -284.227618) (xy 155.518469 -284.26171) (xy 155.477966 -284.289666) (xy 155.433504 -284.310764)
			(xy 155.386233 -284.324456) (xy 155.337378 -284.330388) (xy 155.288203 -284.328407) (xy 155.239984 -284.318563)
			(xy 155.193968 -284.301111) (xy 155.151347 -284.276504) (xy 155.113226 -284.245379) (xy 155.080591 -284.208542)
			(xy 155.054288 -284.166946) (xy 155.034997 -284.12167) (xy 155.02322 -284.073886) (xy 155.01926 -284.024832)
			(xy 154.680412 -284.024832) (xy 154.679917 -284.049439) (xy 154.672022 -284.098016) (xy 154.656438 -284.144697)
			(xy 154.633567 -284.188274) (xy 154.604002 -284.227618) (xy 154.568509 -284.26171) (xy 154.528006 -284.289666)
			(xy 154.483544 -284.310764) (xy 154.436273 -284.324456) (xy 154.387418 -284.330388) (xy 154.338243 -284.328407)
			(xy 154.290024 -284.318563) (xy 154.244008 -284.301111) (xy 154.201387 -284.276504) (xy 154.163266 -284.245379)
			(xy 154.130631 -284.208542) (xy 154.104328 -284.166946) (xy 154.085037 -284.12167) (xy 154.07326 -284.073886)
			(xy 154.0693 -284.024832) (xy 149.574979 -284.024832) (xy 149.573429 -284.029983) (xy 149.549757 -284.08048)
			(xy 149.518984 -284.126993) (xy 149.481767 -284.16853) (xy 149.438899 -284.204205) (xy 149.391293 -284.233259)
			(xy 149.339964 -284.255071) (xy 149.286007 -284.269177) (xy 149.23057 -284.275277) (xy 149.174836 -284.27324)
			(xy 149.119993 -284.26311) (xy 149.067209 -284.245103) (xy 149.017609 -284.219602) (xy 148.972251 -284.187151)
			(xy 148.932102 -284.148442) (xy 148.898016 -284.104299) (xy 148.87072 -284.055664) (xy 148.850797 -284.003573)
			(xy 148.838671 -283.949136) (xy 148.8346 -283.893514) (xy 148.201126 -283.893514) (xy 148.20064 -283.920765)
			(xy 148.192884 -283.974713) (xy 148.177529 -284.027008) (xy 148.154887 -284.076585) (xy 148.125421 -284.122435)
			(xy 148.08973 -284.163626) (xy 148.048539 -284.199317) (xy 148.002689 -284.228783) (xy 147.953112 -284.251425)
			(xy 147.900817 -284.26678) (xy 147.846869 -284.274536) (xy 147.792367 -284.274536) (xy 147.738419 -284.26678)
			(xy 147.686124 -284.251425) (xy 147.636547 -284.228783) (xy 147.590697 -284.199317) (xy 147.549506 -284.163626)
			(xy 147.513815 -284.122435) (xy 147.484349 -284.076585) (xy 147.461707 -284.027008) (xy 147.446352 -283.974713)
			(xy 147.438596 -283.920765) (xy 147.43811 -283.893514) (xy 141.691421 -283.893514) (xy 141.706033 -283.924685)
			(xy 141.722101 -283.978092) (xy 141.730221 -284.033268) (xy 141.73073 -284.061154) (xy 141.730221 -284.08904)
			(xy 141.722101 -284.144216) (xy 141.706033 -284.197623) (xy 141.682361 -284.24812) (xy 141.651588 -284.294633)
			(xy 141.614371 -284.33617) (xy 141.571503 -284.371845) (xy 141.523897 -284.400899) (xy 141.472568 -284.422711)
			(xy 141.418611 -284.436817) (xy 141.363174 -284.442917) (xy 141.30744 -284.44088) (xy 141.252597 -284.43075)
			(xy 141.199813 -284.412743) (xy 141.150213 -284.387242) (xy 141.104855 -284.354791) (xy 141.064706 -284.316082)
			(xy 141.03062 -284.271939) (xy 141.003324 -284.223304) (xy 140.983401 -284.171213) (xy 140.971275 -284.116776)
			(xy 140.967204 -284.061154) (xy 136.317736 -284.061154) (xy 136.317736 -285.029656) (xy 141.911576 -285.029656)
			(xy 141.915647 -284.974034) (xy 141.927773 -284.919597) (xy 141.947696 -284.867506) (xy 141.974992 -284.818871)
			(xy 142.009078 -284.774728) (xy 142.049227 -284.736019) (xy 142.094585 -284.703568) (xy 142.144185 -284.678067)
			(xy 142.196969 -284.66006) (xy 142.251812 -284.64993) (xy 142.307546 -284.647893) (xy 142.362983 -284.653993)
			(xy 142.41694 -284.668099) (xy 142.468269 -284.689911) (xy 142.515875 -284.718965) (xy 142.558743 -284.75464)
			(xy 142.59596 -284.796177) (xy 142.626733 -284.84269) (xy 142.650405 -284.893187) (xy 142.666473 -284.946594)
			(xy 142.674593 -285.00177) (xy 142.675102 -285.029656) (xy 143.396714 -285.029656) (xy 143.400785 -284.974034)
			(xy 143.412911 -284.919597) (xy 143.432834 -284.867506) (xy 143.46013 -284.818871) (xy 143.494216 -284.774728)
			(xy 143.534365 -284.736019) (xy 143.579723 -284.703568) (xy 143.629323 -284.678067) (xy 143.682107 -284.66006)
			(xy 143.73695 -284.64993) (xy 143.792684 -284.647893) (xy 143.848121 -284.653993) (xy 143.902078 -284.668099)
			(xy 143.953407 -284.689911) (xy 144.001013 -284.718965) (xy 144.043881 -284.75464) (xy 144.081098 -284.796177)
			(xy 144.111871 -284.84269) (xy 144.135543 -284.893187) (xy 144.151611 -284.946594) (xy 144.155761 -284.974792)
			(xy 152.169126 -284.974792) (xy 152.173086 -284.925738) (xy 152.184863 -284.877954) (xy 152.204154 -284.832678)
			(xy 152.230457 -284.791082) (xy 152.263092 -284.754245) (xy 152.301213 -284.72312) (xy 152.343834 -284.698513)
			(xy 152.38985 -284.681061) (xy 152.438069 -284.671217) (xy 152.487244 -284.669236) (xy 152.536099 -284.675168)
			(xy 152.58337 -284.68886) (xy 152.627832 -284.709958) (xy 152.668335 -284.737914) (xy 152.703828 -284.772006)
			(xy 152.733393 -284.81135) (xy 152.756264 -284.854927) (xy 152.771848 -284.901608) (xy 152.779743 -284.950185)
			(xy 152.780238 -284.974792) (xy 153.119086 -284.974792) (xy 153.123046 -284.925738) (xy 153.134823 -284.877954)
			(xy 153.154114 -284.832678) (xy 153.180417 -284.791082) (xy 153.213052 -284.754245) (xy 153.251173 -284.72312)
			(xy 153.293794 -284.698513) (xy 153.33981 -284.681061) (xy 153.388029 -284.671217) (xy 153.437204 -284.669236)
			(xy 153.486059 -284.675168) (xy 153.53333 -284.68886) (xy 153.577792 -284.709958) (xy 153.618295 -284.737914)
			(xy 153.653788 -284.772006) (xy 153.683353 -284.81135) (xy 153.706224 -284.854927) (xy 153.721808 -284.901608)
			(xy 153.729703 -284.950185) (xy 153.730198 -284.974792) (xy 156.91918 -284.974792) (xy 156.92314 -284.925738)
			(xy 156.934917 -284.877954) (xy 156.954208 -284.832678) (xy 156.980511 -284.791082) (xy 157.013146 -284.754245)
			(xy 157.051267 -284.72312) (xy 157.093888 -284.698513) (xy 157.139904 -284.681061) (xy 157.188123 -284.671217)
			(xy 157.237298 -284.669236) (xy 157.286153 -284.675168) (xy 157.333424 -284.68886) (xy 157.377886 -284.709958)
			(xy 157.418389 -284.737914) (xy 157.453882 -284.772006) (xy 157.483447 -284.81135) (xy 157.506318 -284.854927)
			(xy 157.521902 -284.901608) (xy 157.529797 -284.950185) (xy 157.530292 -284.974792) (xy 157.529797 -284.999399)
			(xy 157.521902 -285.047976) (xy 157.506318 -285.094657) (xy 157.483447 -285.138234) (xy 157.453882 -285.177578)
			(xy 157.418389 -285.21167) (xy 157.377886 -285.239626) (xy 157.333424 -285.260724) (xy 157.286153 -285.274416)
			(xy 157.237298 -285.280348) (xy 157.188123 -285.278367) (xy 157.139904 -285.268523) (xy 157.093888 -285.251071)
			(xy 157.051267 -285.226464) (xy 157.013146 -285.195339) (xy 156.980511 -285.158502) (xy 156.954208 -285.116906)
			(xy 156.934917 -285.07163) (xy 156.92314 -285.023846) (xy 156.91918 -284.974792) (xy 153.730198 -284.974792)
			(xy 153.729703 -284.999399) (xy 153.721808 -285.047976) (xy 153.706224 -285.094657) (xy 153.683353 -285.138234)
			(xy 153.653788 -285.177578) (xy 153.618295 -285.21167) (xy 153.577792 -285.239626) (xy 153.53333 -285.260724)
			(xy 153.486059 -285.274416) (xy 153.437204 -285.280348) (xy 153.388029 -285.278367) (xy 153.33981 -285.268523)
			(xy 153.293794 -285.251071) (xy 153.251173 -285.226464) (xy 153.213052 -285.195339) (xy 153.180417 -285.158502)
			(xy 153.154114 -285.116906) (xy 153.134823 -285.07163) (xy 153.123046 -285.023846) (xy 153.119086 -284.974792)
			(xy 152.780238 -284.974792) (xy 152.779743 -284.999399) (xy 152.771848 -285.047976) (xy 152.756264 -285.094657)
			(xy 152.733393 -285.138234) (xy 152.703828 -285.177578) (xy 152.668335 -285.21167) (xy 152.627832 -285.239626)
			(xy 152.58337 -285.260724) (xy 152.536099 -285.274416) (xy 152.487244 -285.280348) (xy 152.438069 -285.278367)
			(xy 152.38985 -285.268523) (xy 152.343834 -285.251071) (xy 152.301213 -285.226464) (xy 152.263092 -285.195339)
			(xy 152.230457 -285.158502) (xy 152.204154 -285.116906) (xy 152.184863 -285.07163) (xy 152.173086 -285.023846)
			(xy 152.169126 -284.974792) (xy 144.155761 -284.974792) (xy 144.159731 -285.00177) (xy 144.16024 -285.029656)
			(xy 144.159731 -285.057542) (xy 144.151611 -285.112718) (xy 144.135543 -285.166125) (xy 144.111871 -285.216622)
			(xy 144.081098 -285.263135) (xy 144.043881 -285.304672) (xy 144.001013 -285.340347) (xy 143.953407 -285.369401)
			(xy 143.902078 -285.391213) (xy 143.848121 -285.405319) (xy 143.792684 -285.411419) (xy 143.73695 -285.409382)
			(xy 143.682107 -285.399252) (xy 143.629323 -285.381245) (xy 143.579723 -285.355744) (xy 143.534365 -285.323293)
			(xy 143.494216 -285.284584) (xy 143.46013 -285.240441) (xy 143.432834 -285.191806) (xy 143.412911 -285.139715)
			(xy 143.400785 -285.085278) (xy 143.396714 -285.029656) (xy 142.675102 -285.029656) (xy 142.674593 -285.057542)
			(xy 142.666473 -285.112718) (xy 142.650405 -285.166125) (xy 142.626733 -285.216622) (xy 142.59596 -285.263135)
			(xy 142.558743 -285.304672) (xy 142.515875 -285.340347) (xy 142.468269 -285.369401) (xy 142.41694 -285.391213)
			(xy 142.362983 -285.405319) (xy 142.307546 -285.411419) (xy 142.251812 -285.409382) (xy 142.196969 -285.399252)
			(xy 142.144185 -285.381245) (xy 142.094585 -285.355744) (xy 142.049227 -285.323293) (xy 142.009078 -285.284584)
			(xy 141.974992 -285.240441) (xy 141.947696 -285.191806) (xy 141.927773 -285.139715) (xy 141.915647 -285.085278)
			(xy 141.911576 -285.029656) (xy 136.317736 -285.029656) (xy 136.317736 -285.924752) (xy 154.0693 -285.924752)
			(xy 154.07326 -285.875698) (xy 154.085037 -285.827914) (xy 154.104328 -285.782638) (xy 154.130631 -285.741042)
			(xy 154.163266 -285.704205) (xy 154.201387 -285.67308) (xy 154.244008 -285.648473) (xy 154.290024 -285.631021)
			(xy 154.338243 -285.621177) (xy 154.387418 -285.619196) (xy 154.436273 -285.625128) (xy 154.483544 -285.63882)
			(xy 154.528006 -285.659918) (xy 154.568509 -285.687874) (xy 154.604002 -285.721966) (xy 154.633567 -285.76131)
			(xy 154.656438 -285.804887) (xy 154.672022 -285.851568) (xy 154.679917 -285.900145) (xy 154.680412 -285.924752)
			(xy 155.01926 -285.924752) (xy 155.02322 -285.875698) (xy 155.034997 -285.827914) (xy 155.054288 -285.782638)
			(xy 155.080591 -285.741042) (xy 155.113226 -285.704205) (xy 155.151347 -285.67308) (xy 155.193968 -285.648473)
			(xy 155.239984 -285.631021) (xy 155.288203 -285.621177) (xy 155.337378 -285.619196) (xy 155.386233 -285.625128)
			(xy 155.433504 -285.63882) (xy 155.477966 -285.659918) (xy 155.518469 -285.687874) (xy 155.553962 -285.721966)
			(xy 155.583527 -285.76131) (xy 155.606398 -285.804887) (xy 155.621982 -285.851568) (xy 155.629877 -285.900145)
			(xy 155.630372 -285.924752) (xy 155.629877 -285.949359) (xy 155.621982 -285.997936) (xy 155.606398 -286.044617)
			(xy 155.583527 -286.088194) (xy 155.553962 -286.127538) (xy 155.518469 -286.16163) (xy 155.477966 -286.189586)
			(xy 155.433504 -286.210684) (xy 155.386233 -286.224376) (xy 155.337378 -286.230308) (xy 155.288203 -286.228327)
			(xy 155.239984 -286.218483) (xy 155.193968 -286.201031) (xy 155.151347 -286.176424) (xy 155.113226 -286.145299)
			(xy 155.080591 -286.108462) (xy 155.054288 -286.066866) (xy 155.034997 -286.02159) (xy 155.02322 -285.973806)
			(xy 155.01926 -285.924752) (xy 154.680412 -285.924752) (xy 154.679917 -285.949359) (xy 154.672022 -285.997936)
			(xy 154.656438 -286.044617) (xy 154.633567 -286.088194) (xy 154.604002 -286.127538) (xy 154.568509 -286.16163)
			(xy 154.528006 -286.189586) (xy 154.483544 -286.210684) (xy 154.436273 -286.224376) (xy 154.387418 -286.230308)
			(xy 154.338243 -286.228327) (xy 154.290024 -286.218483) (xy 154.244008 -286.201031) (xy 154.201387 -286.176424)
			(xy 154.163266 -286.145299) (xy 154.130631 -286.108462) (xy 154.104328 -286.066866) (xy 154.085037 -286.02159)
			(xy 154.07326 -285.973806) (xy 154.0693 -285.924752) (xy 136.317736 -285.924752) (xy 136.317736 -286.689038)
			(xy 136.318167 -286.699104) (xy 136.325895 -286.717696) (xy 136.332722 -286.725106) (xy 136.661398 -287.053782)
			(xy 136.668796 -287.060631) (xy 136.687394 -287.068369) (xy 136.697466 -287.068768) (xy 147.41271 -287.068768)
		)
		(stroke
			(width 0)
			(type solid)
		)
		(fill yes)
		(layer "In13.Cu")
		(net "GND")
	)
	(gr_poly
		(pts
			(xy 136.570466 -165.460172) (xy 136.580339 -165.459703) (xy 136.598623 -165.452244) (xy 136.606026 -165.445694)
			(xy 136.60628 -165.44544) (xy 138.596624 -163.455096) (xy 138.597132 -163.454588) (xy 138.603723 -163.44721)
			(xy 138.611191 -163.428911) (xy 138.61161 -163.419028) (xy 138.61161 -154.245564) (xy 138.611038 -154.233651)
			(xy 138.600444 -154.212316) (xy 138.59129 -154.20467) (xy 138.516106 -154.14879) (xy 138.492484 -154.144472)
			(xy 138.4808 -154.148028) (xy 138.454112 -154.155487) (xy 138.399286 -154.163526) (xy 138.37158 -154.16403)
			(xy 138.344328 -154.163543) (xy 138.290379 -154.155784) (xy 138.238084 -154.140426) (xy 138.188507 -154.117782)
			(xy 138.142656 -154.088314) (xy 138.101466 -154.05262) (xy 138.065774 -154.011428) (xy 138.036308 -153.965576)
			(xy 138.013667 -153.915997) (xy 137.998312 -153.863701) (xy 137.990556 -153.809752) (xy 137.990556 -153.755248)
			(xy 137.998312 -153.701299) (xy 138.013667 -153.649003) (xy 138.036308 -153.599424) (xy 138.065774 -153.553572)
			(xy 138.101466 -153.51238) (xy 138.142656 -153.476686) (xy 138.188507 -153.447218) (xy 138.238084 -153.424574)
			(xy 138.290379 -153.409216) (xy 138.344328 -153.401457) (xy 138.37158 -153.401014) (xy 138.399287 -153.401507)
			(xy 138.454116 -153.409539) (xy 138.4808 -153.417016) (xy 138.492484 -153.420572) (xy 138.516106 -153.416254)
			(xy 138.59129 -153.360374) (xy 138.600441 -153.352723) (xy 138.611051 -153.331394) (xy 138.61161 -153.31948)
			(xy 138.61161 -148.201634) (xy 138.61097 -148.189652) (xy 138.600098 -148.168301) (xy 138.590782 -148.16074)
			(xy 138.514582 -148.105114) (xy 138.490706 -148.101304) (xy 138.479022 -148.10486) (xy 138.450871 -148.113264)
			(xy 138.392825 -148.122328) (xy 138.363452 -148.122894) (xy 138.336204 -148.122404) (xy 138.282264 -148.114643)
			(xy 138.229977 -148.099284) (xy 138.180407 -148.076641) (xy 138.134565 -148.047175) (xy 138.093382 -148.011484)
			(xy 138.057697 -147.970297) (xy 138.028236 -147.924451) (xy 138.005599 -147.874878) (xy 137.990247 -147.822589)
			(xy 137.982492 -147.768648) (xy 137.982492 -147.714152) (xy 137.990247 -147.66021) (xy 138.005599 -147.607922)
			(xy 138.028236 -147.558349) (xy 138.057697 -147.512503) (xy 138.093382 -147.471316) (xy 138.134565 -147.435625)
			(xy 138.180407 -147.406159) (xy 138.229977 -147.383516) (xy 138.282264 -147.368157) (xy 138.336204 -147.360396)
			(xy 138.363452 -147.359878) (xy 138.392827 -147.360436) (xy 138.450875 -147.369491) (xy 138.479022 -147.377912)
			(xy 138.490706 -147.381468) (xy 138.514582 -147.377658) (xy 138.590782 -147.322032) (xy 138.600042 -147.314426)
			(xy 138.610907 -147.2931) (xy 138.61161 -147.281138) (xy 138.61161 -114.670586) (xy 138.611185 -114.660517)
			(xy 138.603468 -114.641915) (xy 138.596624 -114.634518) (xy 135.699754 -111.737902) (xy 135.692353 -111.731063)
			(xy 135.673755 -111.723345) (xy 135.663686 -111.722916) (xy 128.358138 -111.722916) (xy 128.329182 -111.74984)
			(xy 128.327404 -111.769652) (xy 128.324782 -111.796631) (xy 128.31288 -111.849513) (xy 128.293612 -111.900178)
			(xy 128.267366 -111.947604) (xy 128.234669 -111.990837) (xy 128.196182 -112.029007) (xy 128.152679 -112.061343)
			(xy 128.105036 -112.087194) (xy 128.054213 -112.106041) (xy 128.001234 -112.117503) (xy 127.947166 -112.12135)
			(xy 127.893098 -112.117503) (xy 127.840119 -112.106041) (xy 127.789296 -112.087194) (xy 127.741653 -112.061343)
			(xy 127.69815 -112.029007) (xy 127.659663 -111.990837) (xy 127.626966 -111.947604) (xy 127.60072 -111.900178)
			(xy 127.581452 -111.849513) (xy 127.56955 -111.796631) (xy 127.566928 -111.769652) (xy 127.56515 -111.74984)
			(xy 127.536194 -111.722916) (xy 126.347982 -111.722916) (xy 126.337914 -111.723343) (xy 126.319315 -111.731064)
			(xy 126.311914 -111.737902) (xy 125.509782 -112.540034) (xy 129.905504 -112.540034) (xy 129.909575 -112.484412)
			(xy 129.921701 -112.429975) (xy 129.941624 -112.377884) (xy 129.96892 -112.329249) (xy 130.003006 -112.285106)
			(xy 130.043155 -112.246397) (xy 130.088513 -112.213946) (xy 130.138113 -112.188445) (xy 130.190897 -112.170438)
			(xy 130.24574 -112.160308) (xy 130.301474 -112.158271) (xy 130.356911 -112.164371) (xy 130.410868 -112.178477)
			(xy 130.462197 -112.200289) (xy 130.509803 -112.229343) (xy 130.552671 -112.265018) (xy 130.589888 -112.306555)
			(xy 130.620661 -112.353068) (xy 130.644333 -112.403565) (xy 130.649627 -112.421162) (xy 131.907024 -112.421162)
			(xy 131.911095 -112.36554) (xy 131.923221 -112.311103) (xy 131.943144 -112.259012) (xy 131.97044 -112.210377)
			(xy 132.004526 -112.166234) (xy 132.044675 -112.127525) (xy 132.090033 -112.095074) (xy 132.139633 -112.069573)
			(xy 132.192417 -112.051566) (xy 132.24726 -112.041436) (xy 132.302994 -112.039399) (xy 132.358431 -112.045499)
			(xy 132.412388 -112.059605) (xy 132.463717 -112.081417) (xy 132.511323 -112.110471) (xy 132.554191 -112.146146)
			(xy 132.591408 -112.187683) (xy 132.622181 -112.234196) (xy 132.645853 -112.284693) (xy 132.661921 -112.3381)
			(xy 132.670041 -112.393276) (xy 132.67055 -112.421162) (xy 132.670041 -112.449048) (xy 132.661921 -112.504224)
			(xy 132.645853 -112.557631) (xy 132.622181 -112.608128) (xy 132.591408 -112.654641) (xy 132.554191 -112.696178)
			(xy 132.511323 -112.731853) (xy 132.463717 -112.760907) (xy 132.412388 -112.782719) (xy 132.358431 -112.796825)
			(xy 132.302994 -112.802925) (xy 132.24726 -112.800888) (xy 132.192417 -112.790758) (xy 132.139633 -112.772751)
			(xy 132.090033 -112.74725) (xy 132.044675 -112.714799) (xy 132.004526 -112.67609) (xy 131.97044 -112.631947)
			(xy 131.943144 -112.583312) (xy 131.923221 -112.531221) (xy 131.911095 -112.476784) (xy 131.907024 -112.421162)
			(xy 130.649627 -112.421162) (xy 130.660401 -112.456972) (xy 130.668521 -112.512148) (xy 130.66903 -112.540034)
			(xy 130.668521 -112.56792) (xy 130.660401 -112.623096) (xy 130.644333 -112.676503) (xy 130.620661 -112.727)
			(xy 130.589888 -112.773513) (xy 130.552671 -112.81505) (xy 130.509803 -112.850725) (xy 130.462197 -112.879779)
			(xy 130.410868 -112.901591) (xy 130.356911 -112.915697) (xy 130.301474 -112.921797) (xy 130.24574 -112.91976)
			(xy 130.190897 -112.90963) (xy 130.138113 -112.891623) (xy 130.088513 -112.866122) (xy 130.043155 -112.833671)
			(xy 130.003006 -112.794962) (xy 129.96892 -112.750819) (xy 129.941624 -112.702184) (xy 129.921701 -112.650093)
			(xy 129.909575 -112.595656) (xy 129.905504 -112.540034) (xy 125.509782 -112.540034) (xy 124.15139 -113.898426)
			(xy 127.55321 -113.898426) (xy 127.557281 -113.842804) (xy 127.569407 -113.788367) (xy 127.58933 -113.736276)
			(xy 127.616626 -113.687641) (xy 127.650712 -113.643498) (xy 127.690861 -113.604789) (xy 127.736219 -113.572338)
			(xy 127.785819 -113.546837) (xy 127.838603 -113.52883) (xy 127.893446 -113.5187) (xy 127.94918 -113.516663)
			(xy 128.004617 -113.522763) (xy 128.058574 -113.536869) (xy 128.109903 -113.558681) (xy 128.157509 -113.587735)
			(xy 128.200377 -113.62341) (xy 128.237594 -113.664947) (xy 128.268367 -113.71146) (xy 128.292039 -113.761957)
			(xy 128.308107 -113.815364) (xy 128.316227 -113.87054) (xy 128.316736 -113.898426) (xy 128.316227 -113.926312)
			(xy 128.308107 -113.981488) (xy 128.292039 -114.034895) (xy 128.268367 -114.085392) (xy 128.237594 -114.131905)
			(xy 128.200377 -114.173442) (xy 128.157509 -114.209117) (xy 128.109903 -114.238171) (xy 128.058574 -114.259983)
			(xy 128.004617 -114.274089) (xy 127.94918 -114.280189) (xy 127.893446 -114.278152) (xy 127.838603 -114.268022)
			(xy 127.785819 -114.250015) (xy 127.736219 -114.224514) (xy 127.690861 -114.192063) (xy 127.650712 -114.153354)
			(xy 127.616626 -114.109211) (xy 127.58933 -114.060576) (xy 127.569407 -114.008485) (xy 127.557281 -113.954048)
			(xy 127.55321 -113.898426) (xy 124.15139 -113.898426) (xy 123.237244 -114.812572) (xy 123.230561 -114.819983)
			(xy 123.222978 -114.838418) (xy 123.222512 -114.848386) (xy 123.222512 -116.672106) (xy 128.968754 -116.672106)
			(xy 128.96921 -116.644735) (xy 128.977029 -116.590555) (xy 128.992519 -116.538052) (xy 129.015363 -116.488305)
			(xy 129.045091 -116.442339) (xy 129.062734 -116.421408) (xy 129.06883 -116.414296) (xy 129.07518 -116.397278)
			(xy 129.07518 -116.311934) (xy 129.06883 -116.294916) (xy 129.062734 -116.287804) (xy 129.045099 -116.266867)
			(xy 129.015373 -116.2209) (xy 128.992527 -116.171154) (xy 128.97703 -116.118653) (xy 128.969201 -116.064475)
			(xy 128.9692 -116.009734) (xy 128.977028 -115.955556) (xy 128.992524 -115.903054) (xy 129.015369 -115.853308)
			(xy 129.045093 -115.807341) (xy 129.062734 -115.786408) (xy 129.06883 -115.779296) (xy 129.07518 -115.762278)
			(xy 129.07518 -115.676934) (xy 129.06883 -115.659916) (xy 129.062734 -115.652804) (xy 129.045089 -115.631877)
			(xy 129.015377 -115.585903) (xy 128.992541 -115.536155) (xy 128.977052 -115.483653) (xy 128.969226 -115.429476)
			(xy 128.968754 -115.402106) (xy 128.969283 -115.374857) (xy 128.977038 -115.320912) (xy 128.99239 -115.268621)
			(xy 129.015028 -115.219046) (xy 129.04449 -115.173198) (xy 129.080177 -115.132008) (xy 129.121362 -115.096317)
			(xy 129.167207 -115.066849) (xy 129.21678 -115.044206) (xy 129.269069 -115.028847) (xy 129.323013 -115.021086)
			(xy 129.350262 -115.020598) (xy 129.377631 -115.021087) (xy 129.431809 -115.028899) (xy 129.484312 -115.044383)
			(xy 129.53406 -115.06722) (xy 129.580027 -115.096939) (xy 129.60096 -115.114578) (xy 129.608072 -115.120674)
			(xy 129.62509 -115.127024) (xy 129.710434 -115.127024) (xy 129.727452 -115.120674) (xy 129.734564 -115.114578)
			(xy 129.755496 -115.096939) (xy 129.801469 -115.067228) (xy 129.851217 -115.044392) (xy 129.903717 -115.028901)
			(xy 129.957893 -115.021072) (xy 129.985262 -115.020598) (xy 130.012514 -115.021091) (xy 130.066464 -115.028843)
			(xy 130.118762 -115.044194) (xy 130.168342 -115.066833) (xy 130.214196 -115.096297) (xy 130.255389 -115.131988)
			(xy 130.291084 -115.173178) (xy 130.320552 -115.219029) (xy 130.343195 -115.268608) (xy 130.358551 -115.320904)
			(xy 130.366307 -115.374854) (xy 130.36677 -115.402106) (xy 130.366315 -115.429477) (xy 130.358495 -115.483657)
			(xy 130.343004 -115.53616) (xy 130.32016 -115.585907) (xy 130.290433 -115.631873) (xy 130.27279 -115.652804)
			(xy 130.266694 -115.659916) (xy 130.260344 -115.676934) (xy 130.260344 -115.762278) (xy 130.266694 -115.779296)
			(xy 130.27279 -115.786408) (xy 130.290436 -115.807336) (xy 130.320159 -115.853305) (xy 130.343003 -115.903052)
			(xy 130.358498 -115.955555) (xy 130.366326 -116.009734) (xy 130.366325 -116.064475) (xy 130.358496 -116.118654)
			(xy 130.343 -116.171156) (xy 130.320155 -116.220903) (xy 130.29043 -116.266871) (xy 130.27279 -116.287804)
			(xy 130.266694 -116.294916) (xy 130.260344 -116.311934) (xy 130.260344 -116.397278) (xy 130.266694 -116.414296)
			(xy 130.27279 -116.421408) (xy 130.290445 -116.442327) (xy 130.320155 -116.488304) (xy 130.342988 -116.538054)
			(xy 130.358475 -116.590558) (xy 130.366299 -116.644736) (xy 130.36677 -116.672106) (xy 130.366631 -116.680234)
			(xy 131.250942 -116.680234) (xy 131.255013 -116.624612) (xy 131.267139 -116.570175) (xy 131.287062 -116.518084)
			(xy 131.314358 -116.469449) (xy 131.348444 -116.425306) (xy 131.388593 -116.386597) (xy 131.433951 -116.354146)
			(xy 131.483551 -116.328645) (xy 131.536335 -116.310638) (xy 131.591178 -116.300508) (xy 131.646912 -116.298471)
			(xy 131.702349 -116.304571) (xy 131.756306 -116.318677) (xy 131.807635 -116.340489) (xy 131.855241 -116.369543)
			(xy 131.898109 -116.405218) (xy 131.935326 -116.446755) (xy 131.966099 -116.493268) (xy 131.989771 -116.543765)
			(xy 132.005839 -116.597172) (xy 132.013959 -116.652348) (xy 132.014468 -116.680234) (xy 132.013959 -116.70812)
			(xy 132.005839 -116.763296) (xy 131.989771 -116.816703) (xy 131.966099 -116.8672) (xy 131.935326 -116.913713)
			(xy 131.898109 -116.95525) (xy 131.855241 -116.990925) (xy 131.807635 -117.019979) (xy 131.756306 -117.041791)
			(xy 131.702349 -117.055897) (xy 131.646912 -117.061997) (xy 131.591178 -117.05996) (xy 131.536335 -117.04983)
			(xy 131.483551 -117.031823) (xy 131.433951 -117.006322) (xy 131.388593 -116.973871) (xy 131.348444 -116.935162)
			(xy 131.314358 -116.891019) (xy 131.287062 -116.842384) (xy 131.267139 -116.790293) (xy 131.255013 -116.735856)
			(xy 131.250942 -116.680234) (xy 130.366631 -116.680234) (xy 130.366317 -116.698663) (xy 130.358948 -116.751262)
			(xy 130.344354 -116.802331) (xy 130.334004 -116.826792) (xy 130.328924 -116.838222) (xy 130.330448 -116.862606)
			(xy 130.384296 -116.954808) (xy 130.40487 -116.968016) (xy 130.417062 -116.969286) (xy 130.445045 -116.972458)
			(xy 130.499709 -116.985996) (xy 130.551788 -117.007424) (xy 130.600151 -117.036276) (xy 130.643746 -117.071926)
			(xy 130.681627 -117.113597) (xy 130.712968 -117.160385) (xy 130.73709 -117.211273) (xy 130.753467 -117.265155)
			(xy 130.758909 -117.301772) (xy 132.398006 -117.301772) (xy 132.402077 -117.24615) (xy 132.414203 -117.191713)
			(xy 132.434126 -117.139622) (xy 132.461422 -117.090987) (xy 132.495508 -117.046844) (xy 132.535657 -117.008135)
			(xy 132.581015 -116.975684) (xy 132.630615 -116.950183) (xy 132.683399 -116.932176) (xy 132.738242 -116.922046)
			(xy 132.793976 -116.920009) (xy 132.849413 -116.926109) (xy 132.90337 -116.940215) (xy 132.954699 -116.962027)
			(xy 133.002305 -116.991081) (xy 133.045173 -117.026756) (xy 133.08239 -117.068293) (xy 133.113163 -117.114806)
			(xy 133.136835 -117.165303) (xy 133.152903 -117.21871) (xy 133.158922 -117.259608) (xy 133.277356 -117.259608)
			(xy 133.277813 -117.232237) (xy 133.285631 -117.178057) (xy 133.301121 -117.125554) (xy 133.323966 -117.075807)
			(xy 133.353693 -117.029841) (xy 133.371336 -117.00891) (xy 133.377432 -117.001798) (xy 133.383782 -116.98478)
			(xy 133.383782 -116.899436) (xy 133.377432 -116.882418) (xy 133.371336 -116.875306) (xy 133.353703 -116.854367)
			(xy 133.323977 -116.808401) (xy 133.301131 -116.758655) (xy 133.285633 -116.706154) (xy 133.277804 -116.651976)
			(xy 133.277803 -116.597236) (xy 133.285631 -116.543058) (xy 133.301126 -116.490556) (xy 133.323971 -116.44081)
			(xy 133.353696 -116.394843) (xy 133.371336 -116.37391) (xy 133.377432 -116.366798) (xy 133.383782 -116.34978)
			(xy 133.383782 -116.264436) (xy 133.377432 -116.247418) (xy 133.371336 -116.240306) (xy 133.353692 -116.219378)
			(xy 133.32398 -116.173405) (xy 133.301144 -116.123656) (xy 133.285654 -116.071154) (xy 133.277828 -116.016978)
			(xy 133.277356 -115.989608) (xy 133.277885 -115.962359) (xy 133.28564 -115.908414) (xy 133.300992 -115.856123)
			(xy 133.323629 -115.806548) (xy 133.353092 -115.760699) (xy 133.388778 -115.71951) (xy 133.429964 -115.683818)
			(xy 133.475809 -115.654351) (xy 133.525381 -115.631707) (xy 133.577671 -115.616349) (xy 133.631615 -115.608588)
			(xy 133.658864 -115.6081) (xy 133.686233 -115.608587) (xy 133.740412 -115.6164) (xy 133.792915 -115.631884)
			(xy 133.842662 -115.654721) (xy 133.88863 -115.684441) (xy 133.909562 -115.70208) (xy 133.916674 -115.708176)
			(xy 133.933692 -115.714526) (xy 134.019036 -115.714526) (xy 134.036054 -115.708176) (xy 134.043166 -115.70208)
			(xy 134.064097 -115.68444) (xy 134.110071 -115.654729) (xy 134.159818 -115.631894) (xy 134.212319 -115.616403)
			(xy 134.266495 -115.608574) (xy 134.293864 -115.6081) (xy 134.321116 -115.608589) (xy 134.375067 -115.616341)
			(xy 134.427365 -115.631693) (xy 134.476945 -115.654332) (xy 134.522799 -115.683797) (xy 134.563992 -115.719488)
			(xy 134.599686 -115.760679) (xy 134.629155 -115.80653) (xy 134.651797 -115.856109) (xy 134.667153 -115.908406)
			(xy 134.674909 -115.962356) (xy 134.675372 -115.989608) (xy 134.674917 -116.016979) (xy 134.667098 -116.071159)
			(xy 134.651606 -116.123662) (xy 134.628762 -116.173409) (xy 134.599035 -116.219375) (xy 134.581392 -116.240306)
			(xy 134.575296 -116.247418) (xy 134.568946 -116.264436) (xy 134.568946 -116.34978) (xy 134.575296 -116.366798)
			(xy 134.581392 -116.37391) (xy 134.59904 -116.394837) (xy 134.628763 -116.440806) (xy 134.651606 -116.490553)
			(xy 134.667101 -116.543056) (xy 134.674929 -116.597235) (xy 134.674928 -116.651977) (xy 134.667099 -116.706156)
			(xy 134.651602 -116.758658) (xy 134.628757 -116.808405) (xy 134.599032 -116.854373) (xy 134.581392 -116.875306)
			(xy 134.575296 -116.882418) (xy 134.568946 -116.899436) (xy 134.568946 -116.98478) (xy 134.575296 -117.001798)
			(xy 134.581392 -117.00891) (xy 134.599048 -117.029828) (xy 134.628758 -117.075805) (xy 134.65159 -117.125556)
			(xy 134.667077 -117.17806) (xy 134.674901 -117.232238) (xy 134.675372 -117.259608) (xy 134.674952 -117.286863)
			(xy 134.667193 -117.340817) (xy 134.651834 -117.393118) (xy 134.629188 -117.4427) (xy 134.599716 -117.488555)
			(xy 134.564018 -117.529749) (xy 134.52282 -117.565442) (xy 134.476962 -117.594909) (xy 134.427377 -117.61755)
			(xy 134.375074 -117.632902) (xy 134.321119 -117.640655) (xy 134.293864 -117.641116) (xy 134.266492 -117.640692)
			(xy 134.21231 -117.632867) (xy 134.159806 -117.617369) (xy 134.11006 -117.594518) (xy 134.064095 -117.564783)
			(xy 134.043166 -117.547136) (xy 134.036054 -117.54104) (xy 134.019036 -117.53469) (xy 133.933692 -117.53469)
			(xy 133.916674 -117.54104) (xy 133.909562 -117.547136) (xy 133.888622 -117.564765) (xy 133.842651 -117.594477)
			(xy 133.792905 -117.617314) (xy 133.740407 -117.632808) (xy 133.686233 -117.64064) (xy 133.658864 -117.641116)
			(xy 133.631612 -117.640656) (xy 133.577664 -117.632894) (xy 133.525369 -117.617535) (xy 133.475792 -117.59489)
			(xy 133.429943 -117.565421) (xy 133.388753 -117.529727) (xy 133.353062 -117.488535) (xy 133.323596 -117.442683)
			(xy 133.300955 -117.393104) (xy 133.2856 -117.340809) (xy 133.277842 -117.28686) (xy 133.277356 -117.259608)
			(xy 133.158922 -117.259608) (xy 133.161023 -117.273886) (xy 133.161532 -117.301772) (xy 133.161023 -117.329658)
			(xy 133.152903 -117.384834) (xy 133.136835 -117.438241) (xy 133.113163 -117.488738) (xy 133.08239 -117.535251)
			(xy 133.045173 -117.576788) (xy 133.002305 -117.612463) (xy 132.954699 -117.641517) (xy 132.90337 -117.663329)
			(xy 132.849413 -117.677435) (xy 132.793976 -117.683535) (xy 132.738242 -117.681498) (xy 132.683399 -117.671368)
			(xy 132.630615 -117.653361) (xy 132.581015 -117.62786) (xy 132.535657 -117.595409) (xy 132.495508 -117.5567)
			(xy 132.461422 -117.512557) (xy 132.434126 -117.463922) (xy 132.414203 -117.411831) (xy 132.402077 -117.357394)
			(xy 132.398006 -117.301772) (xy 130.758909 -117.301772) (xy 130.761745 -117.320858) (xy 130.762248 -117.349016)
			(xy 130.761762 -117.376267) (xy 130.754006 -117.430215) (xy 130.738651 -117.48251) (xy 130.716009 -117.532087)
			(xy 130.686543 -117.577937) (xy 130.650852 -117.619128) (xy 130.609661 -117.654819) (xy 130.563811 -117.684285)
			(xy 130.514234 -117.706927) (xy 130.461939 -117.722282) (xy 130.407991 -117.730038) (xy 130.353489 -117.730038)
			(xy 130.299541 -117.722282) (xy 130.247246 -117.706927) (xy 130.197669 -117.684285) (xy 130.151819 -117.654819)
			(xy 130.110628 -117.619128) (xy 130.074937 -117.577937) (xy 130.045471 -117.532087) (xy 130.022829 -117.48251)
			(xy 130.007474 -117.430215) (xy 129.999718 -117.376267) (xy 129.999232 -117.349016) (xy 129.999692 -117.32246)
			(xy 130.007058 -117.26986) (xy 130.02165 -117.218791) (xy 130.031998 -117.19433) (xy 130.037078 -117.1829)
			(xy 130.035554 -117.158516) (xy 129.981706 -117.066314) (xy 129.961132 -117.053106) (xy 129.94894 -117.051836)
			(xy 129.919467 -117.048452) (xy 129.861998 -117.033735) (xy 129.807501 -117.010297) (xy 129.757291 -116.978703)
			(xy 129.734564 -116.959634) (xy 129.727452 -116.953538) (xy 129.710434 -116.947188) (xy 129.62509 -116.947188)
			(xy 129.608072 -116.953538) (xy 129.60096 -116.959634) (xy 129.58002 -116.977264) (xy 129.534049 -117.006976)
			(xy 129.484304 -117.029813) (xy 129.431805 -117.045306) (xy 129.377631 -117.053138) (xy 129.350262 -117.053614)
			(xy 129.32301 -117.053158) (xy 129.269062 -117.045396) (xy 129.216767 -117.030036) (xy 129.16719 -117.007391)
			(xy 129.12134 -116.977922) (xy 129.08015 -116.942227) (xy 129.044459 -116.901035) (xy 129.014993 -116.855182)
			(xy 128.992352 -116.805603) (xy 128.976997 -116.753307) (xy 128.96924 -116.699358) (xy 128.968754 -116.672106)
			(xy 123.222512 -116.672106) (xy 123.222512 -117.327426) (xy 125.787148 -117.327426) (xy 125.791219 -117.271804)
			(xy 125.803345 -117.217367) (xy 125.823268 -117.165276) (xy 125.850564 -117.116641) (xy 125.88465 -117.072498)
			(xy 125.924799 -117.033789) (xy 125.970157 -117.001338) (xy 126.019757 -116.975837) (xy 126.072541 -116.95783)
			(xy 126.127384 -116.9477) (xy 126.183118 -116.945663) (xy 126.238555 -116.951763) (xy 126.292512 -116.965869)
			(xy 126.343841 -116.987681) (xy 126.391447 -117.016735) (xy 126.434315 -117.05241) (xy 126.471532 -117.093947)
			(xy 126.502305 -117.14046) (xy 126.525977 -117.190957) (xy 126.528826 -117.200426) (xy 127.819148 -117.200426)
			(xy 127.823219 -117.144804) (xy 127.835345 -117.090367) (xy 127.855268 -117.038276) (xy 127.882564 -116.989641)
			(xy 127.91665 -116.945498) (xy 127.956799 -116.906789) (xy 128.002157 -116.874338) (xy 128.051757 -116.848837)
			(xy 128.104541 -116.83083) (xy 128.159384 -116.8207) (xy 128.215118 -116.818663) (xy 128.270555 -116.824763)
			(xy 128.324512 -116.838869) (xy 128.375841 -116.860681) (xy 128.423447 -116.889735) (xy 128.466315 -116.92541)
			(xy 128.503532 -116.966947) (xy 128.534305 -117.01346) (xy 128.557977 -117.063957) (xy 128.574045 -117.117364)
			(xy 128.582165 -117.17254) (xy 128.582674 -117.200426) (xy 128.582165 -117.228312) (xy 128.574045 -117.283488)
			(xy 128.557977 -117.336895) (xy 128.534305 -117.387392) (xy 128.503532 -117.433905) (xy 128.466315 -117.475442)
			(xy 128.423447 -117.511117) (xy 128.375841 -117.540171) (xy 128.324512 -117.561983) (xy 128.270555 -117.576089)
			(xy 128.215118 -117.582189) (xy 128.159384 -117.580152) (xy 128.104541 -117.570022) (xy 128.051757 -117.552015)
			(xy 128.002157 -117.526514) (xy 127.956799 -117.494063) (xy 127.91665 -117.455354) (xy 127.882564 -117.411211)
			(xy 127.855268 -117.362576) (xy 127.835345 -117.310485) (xy 127.823219 -117.256048) (xy 127.819148 -117.200426)
			(xy 126.528826 -117.200426) (xy 126.542045 -117.244364) (xy 126.550165 -117.29954) (xy 126.550674 -117.327426)
			(xy 126.550165 -117.355312) (xy 126.542045 -117.410488) (xy 126.525977 -117.463895) (xy 126.502305 -117.514392)
			(xy 126.471532 -117.560905) (xy 126.434315 -117.602442) (xy 126.391447 -117.638117) (xy 126.343841 -117.667171)
			(xy 126.292512 -117.688983) (xy 126.238555 -117.703089) (xy 126.183118 -117.709189) (xy 126.127384 -117.707152)
			(xy 126.072541 -117.697022) (xy 126.019757 -117.679015) (xy 125.970157 -117.653514) (xy 125.924799 -117.621063)
			(xy 125.88465 -117.582354) (xy 125.850564 -117.538211) (xy 125.823268 -117.489576) (xy 125.803345 -117.437485)
			(xy 125.791219 -117.383048) (xy 125.787148 -117.327426) (xy 123.222512 -117.327426) (xy 123.222512 -119.486426)
			(xy 125.787148 -119.486426) (xy 125.791219 -119.430804) (xy 125.803345 -119.376367) (xy 125.823268 -119.324276)
			(xy 125.850564 -119.275641) (xy 125.88465 -119.231498) (xy 125.924799 -119.192789) (xy 125.970157 -119.160338)
			(xy 126.019757 -119.134837) (xy 126.072541 -119.11683) (xy 126.127384 -119.1067) (xy 126.183118 -119.104663)
			(xy 126.238555 -119.110763) (xy 126.292512 -119.124869) (xy 126.343841 -119.146681) (xy 126.391447 -119.175735)
			(xy 126.434315 -119.21141) (xy 126.471532 -119.252947) (xy 126.502305 -119.29946) (xy 126.525977 -119.349957)
			(xy 126.527756 -119.35587) (xy 126.803148 -119.35587) (xy 126.807219 -119.300248) (xy 126.819345 -119.245811)
			(xy 126.839268 -119.19372) (xy 126.866564 -119.145085) (xy 126.90065 -119.100942) (xy 126.940799 -119.062233)
			(xy 126.986157 -119.029782) (xy 127.035757 -119.004281) (xy 127.088541 -118.986274) (xy 127.143384 -118.976144)
			(xy 127.199118 -118.974107) (xy 127.254555 -118.980207) (xy 127.308512 -118.994313) (xy 127.359841 -119.016125)
			(xy 127.407447 -119.045179) (xy 127.450315 -119.080854) (xy 127.487532 -119.122391) (xy 127.518305 -119.168904)
			(xy 127.541977 -119.219401) (xy 127.558045 -119.272808) (xy 127.566165 -119.327984) (xy 127.566674 -119.35587)
			(xy 127.819148 -119.35587) (xy 127.823219 -119.300248) (xy 127.835345 -119.245811) (xy 127.855268 -119.19372)
			(xy 127.882564 -119.145085) (xy 127.91665 -119.100942) (xy 127.956799 -119.062233) (xy 128.002157 -119.029782)
			(xy 128.051757 -119.004281) (xy 128.104541 -118.986274) (xy 128.159384 -118.976144) (xy 128.215118 -118.974107)
			(xy 128.270555 -118.980207) (xy 128.324512 -118.994313) (xy 128.375841 -119.016125) (xy 128.423447 -119.045179)
			(xy 128.466315 -119.080854) (xy 128.503532 -119.122391) (xy 128.534305 -119.168904) (xy 128.557977 -119.219401)
			(xy 128.574045 -119.272808) (xy 128.582165 -119.327984) (xy 128.582674 -119.35587) (xy 128.582165 -119.383756)
			(xy 128.581036 -119.39143) (xy 131.014722 -119.39143) (xy 131.018793 -119.335808) (xy 131.030919 -119.281371)
			(xy 131.050842 -119.22928) (xy 131.078138 -119.180645) (xy 131.112224 -119.136502) (xy 131.152373 -119.097793)
			(xy 131.197731 -119.065342) (xy 131.247331 -119.039841) (xy 131.300115 -119.021834) (xy 131.354958 -119.011704)
			(xy 131.410692 -119.009667) (xy 131.466129 -119.015767) (xy 131.520086 -119.029873) (xy 131.571415 -119.051685)
			(xy 131.619021 -119.080739) (xy 131.661889 -119.116414) (xy 131.699106 -119.157951) (xy 131.729879 -119.204464)
			(xy 131.753551 -119.254961) (xy 131.769619 -119.308368) (xy 131.777739 -119.363544) (xy 131.778248 -119.39143)
			(xy 131.777739 -119.419316) (xy 131.769619 -119.474492) (xy 131.753551 -119.527899) (xy 131.729879 -119.578396)
			(xy 131.699106 -119.624909) (xy 131.661889 -119.666446) (xy 131.619021 -119.702121) (xy 131.571415 -119.731175)
			(xy 131.520086 -119.752987) (xy 131.466129 -119.767093) (xy 131.410692 -119.773193) (xy 131.354958 -119.771156)
			(xy 131.300115 -119.761026) (xy 131.247331 -119.743019) (xy 131.197731 -119.717518) (xy 131.152373 -119.685067)
			(xy 131.112224 -119.646358) (xy 131.078138 -119.602215) (xy 131.050842 -119.55358) (xy 131.030919 -119.501489)
			(xy 131.018793 -119.447052) (xy 131.014722 -119.39143) (xy 128.581036 -119.39143) (xy 128.574045 -119.438932)
			(xy 128.557977 -119.492339) (xy 128.534305 -119.542836) (xy 128.503532 -119.589349) (xy 128.466315 -119.630886)
			(xy 128.423447 -119.666561) (xy 128.375841 -119.695615) (xy 128.324512 -119.717427) (xy 128.270555 -119.731533)
			(xy 128.215118 -119.737633) (xy 128.159384 -119.735596) (xy 128.104541 -119.725466) (xy 128.051757 -119.707459)
			(xy 128.002157 -119.681958) (xy 127.956799 -119.649507) (xy 127.91665 -119.610798) (xy 127.882564 -119.566655)
			(xy 127.855268 -119.51802) (xy 127.835345 -119.465929) (xy 127.823219 -119.411492) (xy 127.819148 -119.35587)
			(xy 127.566674 -119.35587) (xy 127.566165 -119.383756) (xy 127.558045 -119.438932) (xy 127.541977 -119.492339)
			(xy 127.518305 -119.542836) (xy 127.487532 -119.589349) (xy 127.450315 -119.630886) (xy 127.407447 -119.666561)
			(xy 127.359841 -119.695615) (xy 127.308512 -119.717427) (xy 127.254555 -119.731533) (xy 127.199118 -119.737633)
			(xy 127.143384 -119.735596) (xy 127.088541 -119.725466) (xy 127.035757 -119.707459) (xy 126.986157 -119.681958)
			(xy 126.940799 -119.649507) (xy 126.90065 -119.610798) (xy 126.866564 -119.566655) (xy 126.839268 -119.51802)
			(xy 126.819345 -119.465929) (xy 126.807219 -119.411492) (xy 126.803148 -119.35587) (xy 126.527756 -119.35587)
			(xy 126.542045 -119.403364) (xy 126.550165 -119.45854) (xy 126.550674 -119.486426) (xy 126.550165 -119.514312)
			(xy 126.542045 -119.569488) (xy 126.525977 -119.622895) (xy 126.502305 -119.673392) (xy 126.471532 -119.719905)
			(xy 126.434315 -119.761442) (xy 126.391447 -119.797117) (xy 126.343841 -119.826171) (xy 126.292512 -119.847983)
			(xy 126.238555 -119.862089) (xy 126.183118 -119.868189) (xy 126.127384 -119.866152) (xy 126.072541 -119.856022)
			(xy 126.019757 -119.838015) (xy 125.970157 -119.812514) (xy 125.924799 -119.780063) (xy 125.88465 -119.741354)
			(xy 125.850564 -119.697211) (xy 125.823268 -119.648576) (xy 125.803345 -119.596485) (xy 125.791219 -119.542048)
			(xy 125.787148 -119.486426) (xy 123.222512 -119.486426) (xy 123.222512 -121.57075) (xy 129.719832 -121.57075)
			(xy 129.720262 -121.544433) (xy 129.727485 -121.492298) (xy 129.741802 -121.441649) (xy 129.762941 -121.393446)
			(xy 129.790501 -121.348605) (xy 129.823959 -121.307975) (xy 129.843022 -121.289826) (xy 129.850417 -121.2823)
			(xy 129.858945 -121.263023) (xy 129.859532 -121.252488) (xy 129.859532 -121.177812) (xy 129.859001 -121.167263)
			(xy 129.850466 -121.147968) (xy 129.843022 -121.140474) (xy 129.823934 -121.122348) (xy 129.790456 -121.081726)
			(xy 129.762886 -121.036884) (xy 129.741749 -120.988675) (xy 129.727446 -120.938015) (xy 129.720251 -120.88587)
			(xy 129.719832 -120.85955) (xy 129.720318 -120.832299) (xy 129.728074 -120.778351) (xy 129.743429 -120.726056)
			(xy 129.766071 -120.676479) (xy 129.795537 -120.630629) (xy 129.831228 -120.589438) (xy 129.872419 -120.553747)
			(xy 129.918269 -120.524281) (xy 129.967846 -120.501639) (xy 130.020141 -120.486284) (xy 130.074089 -120.478528)
			(xy 130.128591 -120.478528) (xy 130.182539 -120.486284) (xy 130.234834 -120.501639) (xy 130.284411 -120.524281)
			(xy 130.330261 -120.553747) (xy 130.371452 -120.589438) (xy 130.407143 -120.630629) (xy 130.436609 -120.676479)
			(xy 130.459251 -120.726056) (xy 130.474606 -120.778351) (xy 130.482362 -120.832299) (xy 130.482848 -120.85955)
			(xy 130.482393 -120.885866) (xy 130.475171 -120.937999) (xy 130.460857 -120.988647) (xy 130.439723 -121.036848)
			(xy 130.412169 -121.08169) (xy 130.378717 -121.122323) (xy 130.359658 -121.140474) (xy 130.352274 -121.148011)
			(xy 130.343738 -121.167279) (xy 130.343148 -121.177812) (xy 130.343148 -121.252488) (xy 130.343656 -121.263041)
			(xy 130.352204 -121.282337) (xy 130.359658 -121.289826) (xy 130.378742 -121.307956) (xy 130.412221 -121.348577)
			(xy 130.439792 -121.393418) (xy 130.46093 -121.441626) (xy 130.475233 -121.492285) (xy 130.482429 -121.54443)
			(xy 130.482848 -121.57075) (xy 130.482362 -121.598001) (xy 130.474606 -121.651949) (xy 130.459251 -121.704244)
			(xy 130.436609 -121.753821) (xy 130.407143 -121.799671) (xy 130.371452 -121.840862) (xy 130.330261 -121.876553)
			(xy 130.284411 -121.906019) (xy 130.234834 -121.928661) (xy 130.182539 -121.944016) (xy 130.128591 -121.951772)
			(xy 130.074089 -121.951772) (xy 130.020141 -121.944016) (xy 129.967846 -121.928661) (xy 129.918269 -121.906019)
			(xy 129.872419 -121.876553) (xy 129.831228 -121.840862) (xy 129.795537 -121.799671) (xy 129.766071 -121.753821)
			(xy 129.743429 -121.704244) (xy 129.728074 -121.651949) (xy 129.720318 -121.598001) (xy 129.719832 -121.57075)
			(xy 123.222512 -121.57075) (xy 123.222512 -122.292618) (xy 125.880112 -122.292618) (xy 125.884183 -122.236996)
			(xy 125.896309 -122.182559) (xy 125.916232 -122.130468) (xy 125.943528 -122.081833) (xy 125.977614 -122.03769)
			(xy 126.017763 -121.998981) (xy 126.063121 -121.96653) (xy 126.112721 -121.941029) (xy 126.165505 -121.923022)
			(xy 126.220348 -121.912892) (xy 126.276082 -121.910855) (xy 126.331519 -121.916955) (xy 126.385476 -121.931061)
			(xy 126.436805 -121.952873) (xy 126.484411 -121.981927) (xy 126.527279 -122.017602) (xy 126.564496 -122.059139)
			(xy 126.595269 -122.105652) (xy 126.618941 -122.156149) (xy 126.635009 -122.209556) (xy 126.643129 -122.264732)
			(xy 126.643638 -122.292618) (xy 126.643129 -122.320504) (xy 126.635009 -122.37568) (xy 126.618941 -122.429087)
			(xy 126.599804 -122.46991) (xy 127.036828 -122.46991) (xy 127.040899 -122.414288) (xy 127.053025 -122.359851)
			(xy 127.072948 -122.30776) (xy 127.100244 -122.259125) (xy 127.13433 -122.214982) (xy 127.174479 -122.176273)
			(xy 127.219837 -122.143822) (xy 127.269437 -122.118321) (xy 127.322221 -122.100314) (xy 127.377064 -122.090184)
			(xy 127.432798 -122.088147) (xy 127.488235 -122.094247) (xy 127.542192 -122.108353) (xy 127.593521 -122.130165)
			(xy 127.641127 -122.159219) (xy 127.683995 -122.194894) (xy 127.721212 -122.236431) (xy 127.751985 -122.282944)
			(xy 127.775657 -122.333441) (xy 127.791725 -122.386848) (xy 127.799845 -122.442024) (xy 127.800354 -122.46991)
			(xy 127.799845 -122.497796) (xy 127.791725 -122.552972) (xy 127.775657 -122.606379) (xy 127.751985 -122.656876)
			(xy 127.721212 -122.703389) (xy 127.683995 -122.744926) (xy 127.641127 -122.780601) (xy 127.593521 -122.809655)
			(xy 127.542192 -122.831467) (xy 127.488235 -122.845573) (xy 127.432798 -122.851673) (xy 127.377064 -122.849636)
			(xy 127.322221 -122.839506) (xy 127.269437 -122.821499) (xy 127.219837 -122.795998) (xy 127.174479 -122.763547)
			(xy 127.13433 -122.724838) (xy 127.100244 -122.680695) (xy 127.072948 -122.63206) (xy 127.053025 -122.579969)
			(xy 127.040899 -122.525532) (xy 127.036828 -122.46991) (xy 126.599804 -122.46991) (xy 126.595269 -122.479584)
			(xy 126.564496 -122.526097) (xy 126.527279 -122.567634) (xy 126.484411 -122.603309) (xy 126.436805 -122.632363)
			(xy 126.385476 -122.654175) (xy 126.331519 -122.668281) (xy 126.276082 -122.674381) (xy 126.220348 -122.672344)
			(xy 126.165505 -122.662214) (xy 126.112721 -122.644207) (xy 126.063121 -122.618706) (xy 126.017763 -122.586255)
			(xy 125.977614 -122.547546) (xy 125.943528 -122.503403) (xy 125.916232 -122.454768) (xy 125.896309 -122.402677)
			(xy 125.884183 -122.34824) (xy 125.880112 -122.292618) (xy 123.222512 -122.292618) (xy 123.222512 -123.249752)
			(xy 128.009867 -123.249752) (xy 128.009867 -123.195248) (xy 128.017624 -123.141298) (xy 128.03298 -123.089002)
			(xy 128.055622 -123.039423) (xy 128.085089 -122.993571) (xy 128.120782 -122.95238) (xy 128.161974 -122.916687)
			(xy 128.207826 -122.88722) (xy 128.257405 -122.864579) (xy 128.309702 -122.849223) (xy 128.363652 -122.841467)
			(xy 128.390904 -122.841004) (xy 128.417934 -122.841497) (xy 128.471452 -122.849135) (xy 128.523353 -122.864259)
			(xy 128.572597 -122.886563) (xy 128.618196 -122.915602) (xy 128.659234 -122.950791) (xy 128.677416 -122.970798)
			(xy 128.684782 -122.978926) (xy 128.704594 -122.98807) (xy 128.802638 -122.988324) (xy 128.82245 -122.979434)
			(xy 128.829816 -122.971306) (xy 128.847975 -122.951581) (xy 128.888876 -122.916917) (xy 128.934232 -122.888329)
			(xy 128.983148 -122.86638) (xy 129.034657 -122.851505) (xy 129.087743 -122.843997) (xy 129.11455 -122.843544)
			(xy 129.14192 -122.844029) (xy 129.196098 -122.85184) (xy 129.248602 -122.867324) (xy 129.298349 -122.890162)
			(xy 129.344316 -122.919884) (xy 129.365248 -122.937524) (xy 129.37236 -122.94362) (xy 129.389378 -122.94997)
			(xy 129.474722 -122.94997) (xy 129.49174 -122.94362) (xy 129.498852 -122.937524) (xy 129.519785 -122.919883)
			(xy 129.565753 -122.890159) (xy 129.615499 -122.867313) (xy 129.668001 -122.851817) (xy 129.722179 -122.843988)
			(xy 129.776921 -122.843988) (xy 129.831099 -122.851817) (xy 129.883601 -122.867313) (xy 129.933347 -122.890159)
			(xy 129.979315 -122.919883) (xy 130.000248 -122.937524) (xy 130.00736 -122.94362) (xy 130.024378 -122.94997)
			(xy 130.109722 -122.94997) (xy 130.12674 -122.94362) (xy 130.133852 -122.937524) (xy 130.146653 -122.926579)
			(xy 130.173869 -122.906735) (xy 130.188208 -122.8979) (xy 130.197352 -122.892566) (xy 130.209544 -122.875548)
			(xy 130.22961 -122.78233) (xy 130.225546 -122.761756) (xy 130.21945 -122.75312) (xy 130.203451 -122.729056)
			(xy 130.178109 -122.677124) (xy 130.160884 -122.621966) (xy 130.152168 -122.564842) (xy 130.151632 -122.53595)
			(xy 130.152118 -122.508699) (xy 130.159874 -122.454751) (xy 130.175229 -122.402456) (xy 130.197871 -122.352879)
			(xy 130.227337 -122.307029) (xy 130.263028 -122.265838) (xy 130.304219 -122.230147) (xy 130.350069 -122.200681)
			(xy 130.399646 -122.178039) (xy 130.451941 -122.162684) (xy 130.505889 -122.154928) (xy 130.560391 -122.154928)
			(xy 130.614339 -122.162684) (xy 130.666634 -122.178039) (xy 130.716211 -122.200681) (xy 130.762061 -122.230147)
			(xy 130.803252 -122.265838) (xy 130.838943 -122.307029) (xy 130.868409 -122.352879) (xy 130.891051 -122.402456)
			(xy 130.906406 -122.454751) (xy 130.914162 -122.508699) (xy 130.914648 -122.53595) (xy 130.914099 -122.564039)
			(xy 130.90588 -122.619613) (xy 130.889597 -122.673381) (xy 130.865603 -122.724177) (xy 130.834417 -122.770905)
			(xy 130.796714 -122.812552) (xy 130.753308 -122.848217) (xy 130.729482 -122.863102) (xy 130.720338 -122.868436)
			(xy 130.708146 -122.885454) (xy 130.68808 -122.978672) (xy 130.692144 -122.999246) (xy 130.69824 -123.007882)
			(xy 130.714239 -123.031946) (xy 130.739581 -123.083878) (xy 130.756807 -123.139036) (xy 130.765523 -123.19616)
			(xy 130.766058 -123.225052) (xy 130.7656 -123.252306) (xy 130.757848 -123.30626) (xy 130.742496 -123.358561)
			(xy 130.719855 -123.408144) (xy 130.690387 -123.454) (xy 130.654693 -123.495194) (xy 130.613498 -123.530889)
			(xy 130.567642 -123.560356) (xy 130.518059 -123.582996) (xy 130.465758 -123.598349) (xy 130.411804 -123.6061)
			(xy 130.38455 -123.60656) (xy 130.35718 -123.606074) (xy 130.303002 -123.598263) (xy 130.250498 -123.582779)
			(xy 130.200751 -123.559941) (xy 130.154784 -123.53022) (xy 130.133852 -123.51258) (xy 130.12674 -123.506484)
			(xy 130.109722 -123.500134) (xy 130.024378 -123.500134) (xy 130.00736 -123.506484) (xy 130.000248 -123.51258)
			(xy 129.979315 -123.530221) (xy 129.933347 -123.559945) (xy 129.883601 -123.582791) (xy 129.831099 -123.598287)
			(xy 129.776921 -123.606116) (xy 129.722179 -123.606116) (xy 129.668001 -123.598287) (xy 129.615499 -123.582791)
			(xy 129.565753 -123.559945) (xy 129.519785 -123.530221) (xy 129.498852 -123.51258) (xy 129.49174 -123.506484)
			(xy 129.474722 -123.500134) (xy 129.389378 -123.500134) (xy 129.37236 -123.506484) (xy 129.365248 -123.51258)
			(xy 129.344306 -123.530207) (xy 129.298336 -123.559921) (xy 129.248591 -123.58276) (xy 129.196093 -123.598254)
			(xy 129.141919 -123.606085) (xy 129.11455 -123.60656) (xy 129.08752 -123.606077) (xy 129.034003 -123.598433)
			(xy 128.982102 -123.583307) (xy 128.932859 -123.561) (xy 128.88726 -123.531961) (xy 128.846221 -123.496772)
			(xy 128.828038 -123.476766) (xy 128.820672 -123.468638) (xy 128.80086 -123.459494) (xy 128.702816 -123.45924)
			(xy 128.683004 -123.46813) (xy 128.675638 -123.476258) (xy 128.657465 -123.495969) (xy 128.616566 -123.530632)
			(xy 128.571212 -123.559221) (xy 128.522299 -123.581171) (xy 128.470793 -123.59605) (xy 128.41771 -123.603564)
			(xy 128.390904 -123.60402) (xy 128.363652 -123.603533) (xy 128.309702 -123.595777) (xy 128.257405 -123.580421)
			(xy 128.207826 -123.55778) (xy 128.161974 -123.528313) (xy 128.120782 -123.49262) (xy 128.085089 -123.451429)
			(xy 128.055622 -123.405577) (xy 128.03298 -123.355998) (xy 128.017624 -123.303702) (xy 128.009867 -123.249752)
			(xy 123.222512 -123.249752) (xy 123.222512 -124.963428) (xy 124.772926 -124.963428) (xy 124.776997 -124.907806)
			(xy 124.789123 -124.853369) (xy 124.809046 -124.801278) (xy 124.836342 -124.752643) (xy 124.870428 -124.7085)
			(xy 124.910577 -124.669791) (xy 124.955935 -124.63734) (xy 125.005535 -124.611839) (xy 125.058319 -124.593832)
			(xy 125.113162 -124.583702) (xy 125.168896 -124.581665) (xy 125.224333 -124.587765) (xy 125.27829 -124.601871)
			(xy 125.329619 -124.623683) (xy 125.377225 -124.652737) (xy 125.420093 -124.688412) (xy 125.45731 -124.729949)
			(xy 125.488083 -124.776462) (xy 125.511755 -124.826959) (xy 125.527823 -124.880366) (xy 125.535943 -124.935542)
			(xy 125.536452 -124.963428) (xy 125.536137 -124.9807) (xy 126.928878 -124.9807) (xy 126.932949 -124.925078)
			(xy 126.945075 -124.870641) (xy 126.964998 -124.81855) (xy 126.992294 -124.769915) (xy 127.02638 -124.725772)
			(xy 127.066529 -124.687063) (xy 127.111887 -124.654612) (xy 127.161487 -124.629111) (xy 127.214271 -124.611104)
			(xy 127.269114 -124.600974) (xy 127.324848 -124.598937) (xy 127.380285 -124.605037) (xy 127.434242 -124.619143)
			(xy 127.485571 -124.640955) (xy 127.533177 -124.670009) (xy 127.576045 -124.705684) (xy 127.613262 -124.747221)
			(xy 127.644035 -124.793734) (xy 127.667707 -124.844231) (xy 127.683775 -124.897638) (xy 127.691895 -124.952814)
			(xy 127.692404 -124.9807) (xy 127.691895 -125.008586) (xy 127.683775 -125.063762) (xy 127.667707 -125.117169)
			(xy 127.644035 -125.167666) (xy 127.613262 -125.214179) (xy 127.576045 -125.255716) (xy 127.533177 -125.291391)
			(xy 127.485571 -125.320445) (xy 127.434242 -125.342257) (xy 127.380285 -125.356363) (xy 127.324848 -125.362463)
			(xy 127.269114 -125.360426) (xy 127.214271 -125.350296) (xy 127.161487 -125.332289) (xy 127.111887 -125.306788)
			(xy 127.066529 -125.274337) (xy 127.02638 -125.235628) (xy 126.992294 -125.191485) (xy 126.964998 -125.14285)
			(xy 126.945075 -125.090759) (xy 126.932949 -125.036322) (xy 126.928878 -124.9807) (xy 125.536137 -124.9807)
			(xy 125.535943 -124.991314) (xy 125.527823 -125.04649) (xy 125.511755 -125.099897) (xy 125.488083 -125.150394)
			(xy 125.45731 -125.196907) (xy 125.420093 -125.238444) (xy 125.377225 -125.274119) (xy 125.329619 -125.303173)
			(xy 125.27829 -125.324985) (xy 125.224333 -125.339091) (xy 125.168896 -125.345191) (xy 125.113162 -125.343154)
			(xy 125.058319 -125.333024) (xy 125.005535 -125.315017) (xy 124.955935 -125.289516) (xy 124.910577 -125.257065)
			(xy 124.870428 -125.218356) (xy 124.836342 -125.174213) (xy 124.809046 -125.125578) (xy 124.789123 -125.073487)
			(xy 124.776997 -125.01905) (xy 124.772926 -124.963428) (xy 123.222512 -124.963428) (xy 123.222512 -125.403356)
			(xy 131.644136 -125.403356) (xy 131.644626 -125.375987) (xy 131.652437 -125.321808) (xy 131.66792 -125.269305)
			(xy 131.690756 -125.219558) (xy 131.720477 -125.17359) (xy 131.738116 -125.152658) (xy 131.744212 -125.145546)
			(xy 131.750562 -125.128528) (xy 131.750562 -125.043184) (xy 131.744212 -125.026166) (xy 131.738116 -125.019054)
			(xy 131.720491 -124.99811) (xy 131.690777 -124.952141) (xy 131.667938 -124.902396) (xy 131.652443 -124.849898)
			(xy 131.644612 -124.795724) (xy 131.644136 -124.768356) (xy 131.644622 -124.741105) (xy 131.652378 -124.687157)
			(xy 131.667733 -124.634862) (xy 131.690375 -124.585285) (xy 131.719841 -124.539435) (xy 131.755532 -124.498244)
			(xy 131.796723 -124.462553) (xy 131.842573 -124.433087) (xy 131.89215 -124.410445) (xy 131.944445 -124.39509)
			(xy 131.998393 -124.387334) (xy 132.052895 -124.387334) (xy 132.106843 -124.39509) (xy 132.159138 -124.410445)
			(xy 132.208715 -124.433087) (xy 132.254565 -124.462553) (xy 132.295756 -124.498244) (xy 132.331447 -124.539435)
			(xy 132.360913 -124.585285) (xy 132.383555 -124.634862) (xy 132.39891 -124.687157) (xy 132.406666 -124.741105)
			(xy 132.407152 -124.768356) (xy 132.406672 -124.795726) (xy 132.398859 -124.849905) (xy 132.383374 -124.902408)
			(xy 132.360535 -124.952155) (xy 132.330813 -124.998122) (xy 132.313172 -125.019054) (xy 132.307076 -125.026166)
			(xy 132.300726 -125.043184) (xy 132.300726 -125.128528) (xy 132.307076 -125.145546) (xy 132.313172 -125.152658)
			(xy 132.330801 -125.173599) (xy 132.360515 -125.219569) (xy 132.383353 -125.269314) (xy 132.398847 -125.321813)
			(xy 132.406677 -125.375987) (xy 132.407152 -125.403356) (xy 132.406666 -125.430607) (xy 132.39891 -125.484555)
			(xy 132.383555 -125.53685) (xy 132.360913 -125.586427) (xy 132.331447 -125.632277) (xy 132.295756 -125.673468)
			(xy 132.254565 -125.709159) (xy 132.208715 -125.738625) (xy 132.159138 -125.761267) (xy 132.106843 -125.776622)
			(xy 132.052895 -125.784378) (xy 131.998393 -125.784378) (xy 131.944445 -125.776622) (xy 131.89215 -125.761267)
			(xy 131.842573 -125.738625) (xy 131.796723 -125.709159) (xy 131.755532 -125.673468) (xy 131.719841 -125.632277)
			(xy 131.690375 -125.586427) (xy 131.667733 -125.53685) (xy 131.652378 -125.484555) (xy 131.644622 -125.430607)
			(xy 131.644136 -125.403356) (xy 123.222512 -125.403356) (xy 123.222512 -125.979428) (xy 124.772926 -125.979428)
			(xy 124.776997 -125.923806) (xy 124.789123 -125.869369) (xy 124.809046 -125.817278) (xy 124.836342 -125.768643)
			(xy 124.870428 -125.7245) (xy 124.910577 -125.685791) (xy 124.955935 -125.65334) (xy 125.005535 -125.627839)
			(xy 125.058319 -125.609832) (xy 125.113162 -125.599702) (xy 125.168896 -125.597665) (xy 125.224333 -125.603765)
			(xy 125.27829 -125.617871) (xy 125.329619 -125.639683) (xy 125.377225 -125.668737) (xy 125.420093 -125.704412)
			(xy 125.45731 -125.745949) (xy 125.488083 -125.792462) (xy 125.511755 -125.842959) (xy 125.527823 -125.896366)
			(xy 125.535943 -125.951542) (xy 125.536151 -125.962918) (xy 127.251204 -125.962918) (xy 127.255275 -125.907296)
			(xy 127.267401 -125.852859) (xy 127.287324 -125.800768) (xy 127.31462 -125.752133) (xy 127.348706 -125.70799)
			(xy 127.388855 -125.669281) (xy 127.434213 -125.63683) (xy 127.483813 -125.611329) (xy 127.536597 -125.593322)
			(xy 127.59144 -125.583192) (xy 127.647174 -125.581155) (xy 127.702611 -125.587255) (xy 127.756568 -125.601361)
			(xy 127.807897 -125.623173) (xy 127.855503 -125.652227) (xy 127.898371 -125.687902) (xy 127.935588 -125.729439)
			(xy 127.966361 -125.775952) (xy 127.990033 -125.826449) (xy 127.998231 -125.853698) (xy 132.584698 -125.853698)
			(xy 132.585163 -125.826328) (xy 132.592981 -125.772149) (xy 132.608471 -125.719646) (xy 132.631313 -125.669899)
			(xy 132.661037 -125.623932) (xy 132.678678 -125.603) (xy 132.684774 -125.595888) (xy 132.691124 -125.57887)
			(xy 132.691124 -125.493526) (xy 132.684774 -125.476508) (xy 132.678678 -125.469396) (xy 132.66102 -125.448479)
			(xy 132.631312 -125.402502) (xy 132.60848 -125.35275) (xy 132.592993 -125.300246) (xy 132.58517 -125.246068)
			(xy 132.584698 -125.218698) (xy 132.585184 -125.191447) (xy 132.59294 -125.137499) (xy 132.608295 -125.085204)
			(xy 132.630937 -125.035627) (xy 132.660403 -124.989777) (xy 132.696094 -124.948586) (xy 132.737285 -124.912895)
			(xy 132.783135 -124.883429) (xy 132.832712 -124.860787) (xy 132.885007 -124.845432) (xy 132.938955 -124.837676)
			(xy 132.993457 -124.837676) (xy 133.047405 -124.845432) (xy 133.0997 -124.860787) (xy 133.149277 -124.883429)
			(xy 133.195127 -124.912895) (xy 133.236318 -124.948586) (xy 133.272009 -124.989777) (xy 133.301475 -125.035627)
			(xy 133.324117 -125.085204) (xy 133.339472 -125.137499) (xy 133.347228 -125.191447) (xy 133.347714 -125.218698)
			(xy 133.347243 -125.246068) (xy 133.339426 -125.300247) (xy 133.323938 -125.35275) (xy 133.301097 -125.402497)
			(xy 133.271374 -125.448464) (xy 133.253734 -125.469396) (xy 133.247638 -125.476508) (xy 133.241288 -125.493526)
			(xy 133.241288 -125.57887) (xy 133.247638 -125.595888) (xy 133.253734 -125.603) (xy 133.271392 -125.623917)
			(xy 133.3011 -125.669894) (xy 133.323931 -125.719646) (xy 133.339418 -125.77215) (xy 133.347242 -125.826328)
			(xy 133.347714 -125.853698) (xy 133.347228 -125.880949) (xy 133.339472 -125.934897) (xy 133.324117 -125.987192)
			(xy 133.301475 -126.036769) (xy 133.272009 -126.082619) (xy 133.236318 -126.12381) (xy 133.195127 -126.159501)
			(xy 133.149277 -126.188967) (xy 133.0997 -126.211609) (xy 133.047405 -126.226964) (xy 132.993457 -126.23472)
			(xy 132.938955 -126.23472) (xy 132.885007 -126.226964) (xy 132.832712 -126.211609) (xy 132.783135 -126.188967)
			(xy 132.737285 -126.159501) (xy 132.696094 -126.12381) (xy 132.660403 -126.082619) (xy 132.630937 -126.036769)
			(xy 132.608295 -125.987192) (xy 132.59294 -125.934897) (xy 132.585184 -125.880949) (xy 132.584698 -125.853698)
			(xy 127.998231 -125.853698) (xy 128.006101 -125.879856) (xy 128.014221 -125.935032) (xy 128.01473 -125.962918)
			(xy 128.014221 -125.990804) (xy 128.006101 -126.04598) (xy 127.990033 -126.099387) (xy 127.966361 -126.149884)
			(xy 127.935588 -126.196397) (xy 127.898371 -126.237934) (xy 127.855503 -126.273609) (xy 127.807897 -126.302663)
			(xy 127.756568 -126.324475) (xy 127.702611 -126.338581) (xy 127.647174 -126.344681) (xy 127.59144 -126.342644)
			(xy 127.536597 -126.332514) (xy 127.483813 -126.314507) (xy 127.434213 -126.289006) (xy 127.388855 -126.256555)
			(xy 127.348706 -126.217846) (xy 127.31462 -126.173703) (xy 127.287324 -126.125068) (xy 127.267401 -126.072977)
			(xy 127.255275 -126.01854) (xy 127.251204 -125.962918) (xy 125.536151 -125.962918) (xy 125.536452 -125.979428)
			(xy 125.535943 -126.007314) (xy 125.527823 -126.06249) (xy 125.511755 -126.115897) (xy 125.488083 -126.166394)
			(xy 125.45731 -126.212907) (xy 125.420093 -126.254444) (xy 125.377225 -126.290119) (xy 125.329619 -126.319173)
			(xy 125.27829 -126.340985) (xy 125.224333 -126.355091) (xy 125.168896 -126.361191) (xy 125.113162 -126.359154)
			(xy 125.058319 -126.349024) (xy 125.005535 -126.331017) (xy 124.955935 -126.305516) (xy 124.910577 -126.273065)
			(xy 124.870428 -126.234356) (xy 124.836342 -126.190213) (xy 124.809046 -126.141578) (xy 124.789123 -126.089487)
			(xy 124.776997 -126.03505) (xy 124.772926 -125.979428) (xy 123.222512 -125.979428) (xy 123.222512 -126.530354)
			(xy 133.79323 -126.530354) (xy 133.79377 -126.50269) (xy 133.801763 -126.447941) (xy 133.817574 -126.39492)
			(xy 133.840871 -126.344735) (xy 133.871169 -126.298439) (xy 133.907831 -126.257) (xy 133.95009 -126.221287)
			(xy 133.973316 -126.20625) (xy 133.983476 -126.1999) (xy 133.995922 -126.180342) (xy 134.006336 -126.076202)
			(xy 133.998208 -126.054358) (xy 133.989318 -126.045976) (xy 133.970746 -126.027885) (xy 133.938166 -125.987556)
			(xy 133.911352 -125.943184) (xy 133.890797 -125.895587) (xy 133.876882 -125.845644) (xy 133.869863 -125.794277)
			(xy 133.86943 -125.768354) (xy 133.869835 -125.7411) (xy 133.877599 -125.687147) (xy 133.892962 -125.634849)
			(xy 133.915611 -125.585269) (xy 133.945086 -125.539417) (xy 133.980786 -125.498226) (xy 134.021984 -125.462535)
			(xy 134.067843 -125.433071) (xy 134.117428 -125.410432) (xy 134.169729 -125.395081) (xy 134.223684 -125.387329)
			(xy 134.250938 -125.386846) (xy 134.278307 -125.387337) (xy 134.332486 -125.395147) (xy 134.384989 -125.41063)
			(xy 134.434737 -125.433466) (xy 134.480704 -125.463187) (xy 134.501636 -125.480826) (xy 134.508748 -125.486922)
			(xy 134.525766 -125.493272) (xy 134.61111 -125.493272) (xy 134.628128 -125.486922) (xy 134.63524 -125.480826)
			(xy 134.656187 -125.463206) (xy 134.702155 -125.43349) (xy 134.751899 -125.41065) (xy 134.804397 -125.395155)
			(xy 134.85857 -125.387322) (xy 134.885938 -125.386846) (xy 134.913188 -125.387342) (xy 134.967133 -125.395103)
			(xy 135.019425 -125.41046) (xy 135.068999 -125.433103) (xy 135.114847 -125.462569) (xy 135.156036 -125.498259)
			(xy 135.191727 -125.539447) (xy 135.221194 -125.585294) (xy 135.243837 -125.634868) (xy 135.259195 -125.687159)
			(xy 135.266957 -125.741104) (xy 135.267446 -125.768354) (xy 135.266915 -125.797271) (xy 135.258192 -125.854442)
			(xy 135.240938 -125.909642) (xy 135.215548 -125.961604) (xy 135.182606 -126.009138) (xy 135.142865 -126.051154)
			(xy 135.12038 -126.069344) (xy 135.111599 -126.076888) (xy 135.101427 -126.09766) (xy 135.100822 -126.109222)
			(xy 135.100822 -126.189486) (xy 135.101393 -126.201054) (xy 135.111586 -126.221825) (xy 135.12038 -126.229364)
			(xy 135.142842 -126.24758) (xy 135.18258 -126.289594) (xy 135.215522 -126.337124) (xy 135.240914 -126.38908)
			(xy 135.258175 -126.444273) (xy 135.266908 -126.501439) (xy 135.267446 -126.530354) (xy 135.266902 -126.557604)
			(xy 135.259152 -126.61155) (xy 135.247051 -126.652782) (xy 135.538718 -126.652782) (xy 135.539169 -126.625411)
			(xy 135.54699 -126.571231) (xy 135.562482 -126.518728) (xy 135.585327 -126.468981) (xy 135.615055 -126.423015)
			(xy 135.632698 -126.402084) (xy 135.638794 -126.394972) (xy 135.645144 -126.377954) (xy 135.645144 -126.29261)
			(xy 135.638794 -126.275592) (xy 135.632698 -126.26848) (xy 135.615041 -126.247561) (xy 135.585319 -126.20159)
			(xy 135.562476 -126.151841) (xy 135.546983 -126.099337) (xy 135.539157 -126.045158) (xy 135.539159 -125.990415)
			(xy 135.546989 -125.936236) (xy 135.562486 -125.883733) (xy 135.585332 -125.833986) (xy 135.615057 -125.788017)
			(xy 135.632698 -125.767084) (xy 135.638794 -125.759972) (xy 135.645144 -125.742954) (xy 135.645144 -125.65761)
			(xy 135.638794 -125.640592) (xy 135.632698 -125.63348) (xy 135.615041 -125.612561) (xy 135.585319 -125.56659)
			(xy 135.562476 -125.516841) (xy 135.546983 -125.464337) (xy 135.539157 -125.410158) (xy 135.539159 -125.355415)
			(xy 135.546989 -125.301236) (xy 135.562486 -125.248733) (xy 135.585332 -125.198986) (xy 135.615057 -125.153017)
			(xy 135.632698 -125.132084) (xy 135.638794 -125.124972) (xy 135.645144 -125.107954) (xy 135.645144 -125.02261)
			(xy 135.638794 -125.005592) (xy 135.632698 -124.99848) (xy 135.615083 -124.977529) (xy 135.585367 -124.931561)
			(xy 135.562527 -124.881819) (xy 135.54703 -124.829322) (xy 135.539196 -124.77515) (xy 135.538718 -124.747782)
			(xy 135.539204 -124.720531) (xy 135.54696 -124.666583) (xy 135.562315 -124.614288) (xy 135.584957 -124.564711)
			(xy 135.614423 -124.518861) (xy 135.650114 -124.47767) (xy 135.691305 -124.441979) (xy 135.737155 -124.412513)
			(xy 135.786732 -124.389871) (xy 135.839027 -124.374516) (xy 135.892975 -124.36676) (xy 135.947477 -124.36676)
			(xy 136.001425 -124.374516) (xy 136.05372 -124.389871) (xy 136.103297 -124.412513) (xy 136.149147 -124.441979)
			(xy 136.190338 -124.47767) (xy 136.226029 -124.518861) (xy 136.255495 -124.564711) (xy 136.278137 -124.614288)
			(xy 136.293492 -124.666583) (xy 136.301248 -124.720531) (xy 136.301734 -124.747782) (xy 136.301273 -124.775153)
			(xy 136.293457 -124.829333) (xy 136.277967 -124.881836) (xy 136.255124 -124.931583) (xy 136.225397 -124.977549)
			(xy 136.207754 -124.99848) (xy 136.201658 -125.005592) (xy 136.195308 -125.02261) (xy 136.195308 -125.107954)
			(xy 136.201658 -125.124972) (xy 136.207754 -125.132084) (xy 136.225378 -125.153031) (xy 136.255105 -125.198996)
			(xy 136.277952 -125.248739) (xy 136.293451 -125.30124) (xy 136.301282 -125.355416) (xy 136.301284 -125.410156)
			(xy 136.293457 -125.464334) (xy 136.277962 -125.516835) (xy 136.255118 -125.566581) (xy 136.225394 -125.612548)
			(xy 136.207754 -125.63348) (xy 136.201658 -125.640592) (xy 136.195308 -125.65761) (xy 136.195308 -125.742954)
			(xy 136.201658 -125.759972) (xy 136.207754 -125.767084) (xy 136.225378 -125.788031) (xy 136.255105 -125.833996)
			(xy 136.277952 -125.883739) (xy 136.293451 -125.93624) (xy 136.301282 -125.990416) (xy 136.301284 -126.045156)
			(xy 136.293457 -126.099334) (xy 136.277962 -126.151835) (xy 136.255118 -126.201581) (xy 136.225394 -126.247548)
			(xy 136.207754 -126.26848) (xy 136.201658 -126.275592) (xy 136.195308 -126.29261) (xy 136.195308 -126.377954)
			(xy 136.201658 -126.394972) (xy 136.207754 -126.402084) (xy 136.225392 -126.423017) (xy 136.255105 -126.468989)
			(xy 136.277942 -126.518736) (xy 136.293434 -126.571237) (xy 136.301261 -126.625413) (xy 136.301734 -126.652782)
			(xy 136.301248 -126.680033) (xy 136.293492 -126.733981) (xy 136.278137 -126.786276) (xy 136.255495 -126.835853)
			(xy 136.226029 -126.881703) (xy 136.190338 -126.922894) (xy 136.149147 -126.958585) (xy 136.103297 -126.988051)
			(xy 136.05372 -127.010693) (xy 136.001425 -127.026048) (xy 135.947477 -127.033804) (xy 135.892975 -127.033804)
			(xy 135.839027 -127.026048) (xy 135.786732 -127.010693) (xy 135.737155 -126.988051) (xy 135.691305 -126.958585)
			(xy 135.650114 -126.922894) (xy 135.614423 -126.881703) (xy 135.584957 -126.835853) (xy 135.562315 -126.786276)
			(xy 135.54696 -126.733981) (xy 135.539204 -126.680033) (xy 135.538718 -126.652782) (xy 135.247051 -126.652782)
			(xy 135.243804 -126.663844) (xy 135.22117 -126.713422) (xy 135.19171 -126.759273) (xy 135.156025 -126.800465)
			(xy 135.11484 -126.83616) (xy 135.068995 -126.865629) (xy 135.019423 -126.888275) (xy 134.967132 -126.903634)
			(xy 134.913188 -126.911396) (xy 134.885938 -126.911862) (xy 134.859621 -126.911442) (xy 134.807485 -126.904217)
			(xy 134.756835 -126.889898) (xy 134.708633 -126.868758) (xy 134.663792 -126.841196) (xy 134.623163 -126.807736)
			(xy 134.605014 -126.788672) (xy 134.59748 -126.781285) (xy 134.57821 -126.77275) (xy 134.567676 -126.772162)
			(xy 134.493 -126.772162) (xy 134.48245 -126.772689) (xy 134.463156 -126.781227) (xy 134.455662 -126.788672)
			(xy 134.43754 -126.807764) (xy 134.396918 -126.841242) (xy 134.352075 -126.868812) (xy 134.303865 -126.889948)
			(xy 134.253205 -126.90425) (xy 134.201058 -126.911444) (xy 134.174738 -126.911862) (xy 134.147484 -126.911409)
			(xy 134.09353 -126.903656) (xy 134.041229 -126.888303) (xy 133.991646 -126.865661) (xy 133.945791 -126.836193)
			(xy 133.904597 -126.800498) (xy 133.868902 -126.759303) (xy 133.839435 -126.713447) (xy 133.816795 -126.663863)
			(xy 133.801442 -126.611562) (xy 133.79369 -126.557608) (xy 133.79323 -126.530354) (xy 123.222512 -126.530354)
			(xy 123.222512 -127.051308) (xy 126.844042 -127.051308) (xy 126.848113 -126.995686) (xy 126.860239 -126.941249)
			(xy 126.880162 -126.889158) (xy 126.907458 -126.840523) (xy 126.941544 -126.79638) (xy 126.981693 -126.757671)
			(xy 127.027051 -126.72522) (xy 127.076651 -126.699719) (xy 127.129435 -126.681712) (xy 127.184278 -126.671582)
			(xy 127.240012 -126.669545) (xy 127.295449 -126.675645) (xy 127.349406 -126.689751) (xy 127.400735 -126.711563)
			(xy 127.448341 -126.740617) (xy 127.491209 -126.776292) (xy 127.528426 -126.817829) (xy 127.559199 -126.864342)
			(xy 127.582871 -126.914839) (xy 127.598939 -126.968246) (xy 127.607059 -127.023422) (xy 127.607568 -127.051308)
			(xy 127.607059 -127.079194) (xy 127.598939 -127.13437) (xy 127.582871 -127.187777) (xy 127.559199 -127.238274)
			(xy 127.528426 -127.284787) (xy 127.491209 -127.326324) (xy 127.448341 -127.361999) (xy 127.400735 -127.391053)
			(xy 127.349406 -127.412865) (xy 127.295449 -127.426971) (xy 127.240012 -127.433071) (xy 127.184278 -127.431034)
			(xy 127.129435 -127.420904) (xy 127.076651 -127.402897) (xy 127.027051 -127.377396) (xy 126.981693 -127.344945)
			(xy 126.941544 -127.306236) (xy 126.907458 -127.262093) (xy 126.880162 -127.213458) (xy 126.860239 -127.161367)
			(xy 126.848113 -127.10693) (xy 126.844042 -127.051308) (xy 123.222512 -127.051308) (xy 123.222512 -128.252748)
			(xy 125.828328 -128.252748) (xy 125.828328 -128.198252) (xy 125.836084 -128.144312) (xy 125.851437 -128.092024)
			(xy 125.874075 -128.042454) (xy 125.903537 -127.99661) (xy 125.939223 -127.955425) (xy 125.980408 -127.919738)
			(xy 126.026252 -127.890276) (xy 126.075822 -127.867637) (xy 126.12811 -127.852284) (xy 126.18205 -127.844528)
			(xy 126.209298 -127.844042) (xy 126.236669 -127.844499) (xy 126.290849 -127.852317) (xy 126.343352 -127.867808)
			(xy 126.393099 -127.890652) (xy 126.439065 -127.920379) (xy 126.459996 -127.938022) (xy 126.467108 -127.944118)
			(xy 126.484126 -127.950468) (xy 126.56947 -127.950468) (xy 126.586488 -127.944118) (xy 126.5936 -127.938022)
			(xy 126.614533 -127.920381) (xy 126.660501 -127.890657) (xy 126.710247 -127.867811) (xy 126.762749 -127.852315)
			(xy 126.816927 -127.844486) (xy 126.871669 -127.844486) (xy 126.925847 -127.852315) (xy 126.978349 -127.867811)
			(xy 127.028095 -127.890657) (xy 127.074063 -127.920381) (xy 127.094996 -127.938022) (xy 127.102108 -127.944118)
			(xy 127.119126 -127.950468) (xy 127.20447 -127.950468) (xy 127.221488 -127.944118) (xy 127.2286 -127.938022)
			(xy 127.249524 -127.920373) (xy 127.295499 -127.890662) (xy 127.345248 -127.867827) (xy 127.397751 -127.852339)
			(xy 127.451928 -127.844514) (xy 127.479298 -127.844042) (xy 127.506555 -127.844405) (xy 127.560513 -127.852163)
			(xy 127.612818 -127.86752) (xy 127.662405 -127.890166) (xy 127.708264 -127.919638) (xy 127.749463 -127.955336)
			(xy 127.785161 -127.996534) (xy 127.814633 -128.042393) (xy 127.837279 -128.09198) (xy 127.852637 -128.144285)
			(xy 127.860395 -128.198243) (xy 127.860395 -128.252757) (xy 127.852637 -128.306715) (xy 127.837279 -128.35902)
			(xy 127.814633 -128.408607) (xy 127.785161 -128.454466) (xy 127.749463 -128.495664) (xy 127.708264 -128.531362)
			(xy 127.662405 -128.560834) (xy 127.612818 -128.58348) (xy 127.560513 -128.598837) (xy 127.506555 -128.606595)
			(xy 127.479298 -128.607058) (xy 127.451927 -128.606603) (xy 127.397747 -128.598784) (xy 127.345244 -128.583293)
			(xy 127.295497 -128.560449) (xy 127.249531 -128.530721) (xy 127.2286 -128.513078) (xy 127.221488 -128.506982)
			(xy 127.20447 -128.500632) (xy 127.119126 -128.500632) (xy 127.102108 -128.506982) (xy 127.094996 -128.513078)
			(xy 127.074063 -128.530719) (xy 127.028095 -128.560443) (xy 126.978349 -128.583289) (xy 126.925847 -128.598785)
			(xy 126.871669 -128.606614) (xy 126.816927 -128.606614) (xy 126.762749 -128.598785) (xy 126.710247 -128.583289)
			(xy 126.660501 -128.560443) (xy 126.614533 -128.530719) (xy 126.5936 -128.513078) (xy 126.586488 -128.506982)
			(xy 126.56947 -128.500632) (xy 126.484126 -128.500632) (xy 126.467108 -128.506982) (xy 126.459996 -128.513078)
			(xy 126.439073 -128.530729) (xy 126.393098 -128.56044) (xy 126.343348 -128.583274) (xy 126.290846 -128.598762)
			(xy 126.236668 -128.606586) (xy 126.209298 -128.607058) (xy 126.18205 -128.606472) (xy 126.12811 -128.598716)
			(xy 126.075822 -128.583363) (xy 126.026252 -128.560724) (xy 125.980408 -128.531262) (xy 125.939223 -128.495575)
			(xy 125.903537 -128.45439) (xy 125.874075 -128.408546) (xy 125.851437 -128.358976) (xy 125.836084 -128.306688)
			(xy 125.828328 -128.252748) (xy 123.222512 -128.252748) (xy 123.222512 -131.447157) (xy 125.813209 -131.447157)
			(xy 125.813209 -131.392643) (xy 125.820967 -131.338685) (xy 125.836326 -131.28638) (xy 125.858972 -131.236793)
			(xy 125.888445 -131.190933) (xy 125.924144 -131.149735) (xy 125.965343 -131.114037) (xy 126.011203 -131.084566)
			(xy 126.060791 -131.061922) (xy 126.113096 -131.046565) (xy 126.167055 -131.038808) (xy 126.194312 -131.038346)
			(xy 126.221683 -131.038794) (xy 126.275863 -131.046614) (xy 126.328367 -131.062107) (xy 126.378114 -131.084953)
			(xy 126.424079 -131.114682) (xy 126.44501 -131.132326) (xy 126.452122 -131.138422) (xy 126.46914 -131.144772)
			(xy 126.554484 -131.144772) (xy 126.571502 -131.138422) (xy 126.578614 -131.132326) (xy 126.599547 -131.114685)
			(xy 126.645515 -131.084961) (xy 126.695261 -131.062115) (xy 126.747763 -131.046619) (xy 126.801941 -131.03879)
			(xy 126.856683 -131.03879) (xy 126.910861 -131.046619) (xy 126.963363 -131.062115) (xy 127.013109 -131.084961)
			(xy 127.059077 -131.114685) (xy 127.08001 -131.132326) (xy 127.087122 -131.138422) (xy 127.10414 -131.144772)
			(xy 127.189484 -131.144772) (xy 127.206502 -131.138422) (xy 127.213614 -131.132326) (xy 127.234571 -131.114718)
			(xy 127.280537 -131.085) (xy 127.330278 -131.062158) (xy 127.382773 -131.04666) (xy 127.436944 -131.038824)
			(xy 127.464312 -131.038346) (xy 127.491559 -131.038925) (xy 127.545499 -131.046682) (xy 127.597786 -131.062036)
			(xy 127.647356 -131.084675) (xy 127.693199 -131.114138) (xy 127.734383 -131.149826) (xy 127.770069 -131.19101)
			(xy 127.79953 -131.236855) (xy 127.822168 -131.286425) (xy 127.837521 -131.338712) (xy 127.845276 -131.392653)
			(xy 127.845276 -131.447147) (xy 127.837521 -131.501087) (xy 127.822168 -131.553375) (xy 127.79953 -131.602945)
			(xy 127.770069 -131.64879) (xy 127.734383 -131.689974) (xy 127.693199 -131.725662) (xy 127.647356 -131.755125)
			(xy 127.597786 -131.777764) (xy 127.545499 -131.793118) (xy 127.491559 -131.800875) (xy 127.464312 -131.801362)
			(xy 127.436942 -131.800898) (xy 127.382762 -131.793081) (xy 127.330259 -131.777592) (xy 127.280512 -131.75475)
			(xy 127.234545 -131.725024) (xy 127.213614 -131.707382) (xy 127.206502 -131.701286) (xy 127.189484 -131.694936)
			(xy 127.10414 -131.694936) (xy 127.087122 -131.701286) (xy 127.08001 -131.707382) (xy 127.059077 -131.725023)
			(xy 127.013109 -131.754747) (xy 126.963363 -131.777593) (xy 126.910861 -131.793089) (xy 126.856683 -131.800918)
			(xy 126.801941 -131.800918) (xy 126.747763 -131.793089) (xy 126.695261 -131.777593) (xy 126.645515 -131.754747)
			(xy 126.599547 -131.725023) (xy 126.578614 -131.707382) (xy 126.571502 -131.701286) (xy 126.554484 -131.694936)
			(xy 126.46914 -131.694936) (xy 126.452122 -131.701286) (xy 126.44501 -131.707382) (xy 126.424083 -131.725027)
			(xy 126.378109 -131.754739) (xy 126.32836 -131.777574) (xy 126.275858 -131.793063) (xy 126.221682 -131.800889)
			(xy 126.194312 -131.801362) (xy 126.167055 -131.800992) (xy 126.113096 -131.793235) (xy 126.060791 -131.777878)
			(xy 126.011203 -131.755234) (xy 125.965343 -131.725763) (xy 125.924144 -131.690065) (xy 125.888445 -131.648867)
			(xy 125.858972 -131.603007) (xy 125.836326 -131.55342) (xy 125.820967 -131.501115) (xy 125.813209 -131.447157)
			(xy 123.222512 -131.447157) (xy 123.222512 -133.443726) (xy 127.222758 -133.443726) (xy 127.223195 -133.41741)
			(xy 127.230421 -133.365275) (xy 127.244738 -133.314628) (xy 127.265875 -133.266426) (xy 127.293432 -133.221584)
			(xy 127.326887 -133.180952) (xy 127.345948 -133.162802) (xy 127.353343 -133.155275) (xy 127.361873 -133.135999)
			(xy 127.362458 -133.125464) (xy 127.362458 -133.050788) (xy 127.361961 -133.040234) (xy 127.353405 -133.020938)
			(xy 127.345948 -133.01345) (xy 127.326854 -132.99533) (xy 127.293375 -132.954708) (xy 127.265805 -132.909864)
			(xy 127.244669 -132.861654) (xy 127.230368 -132.810993) (xy 127.223175 -132.758847) (xy 127.222758 -132.732526)
			(xy 127.223244 -132.705275) (xy 127.231 -132.651327) (xy 127.246355 -132.599032) (xy 127.268997 -132.549455)
			(xy 127.298463 -132.503605) (xy 127.334154 -132.462414) (xy 127.375345 -132.426723) (xy 127.421195 -132.397257)
			(xy 127.470772 -132.374615) (xy 127.523067 -132.35926) (xy 127.577015 -132.351504) (xy 127.631517 -132.351504)
			(xy 127.685465 -132.35926) (xy 127.73776 -132.374615) (xy 127.787337 -132.397257) (xy 127.833187 -132.426723)
			(xy 127.874378 -132.462414) (xy 127.910069 -132.503605) (xy 127.939535 -132.549455) (xy 127.962177 -132.599032)
			(xy 127.977532 -132.651327) (xy 127.985288 -132.705275) (xy 127.985774 -132.732526) (xy 127.985326 -132.758842)
			(xy 127.978106 -132.810977) (xy 127.963793 -132.861625) (xy 127.942657 -132.909828) (xy 127.915101 -132.954669)
			(xy 127.881645 -132.995301) (xy 127.862584 -133.01345) (xy 127.855156 -133.020949) (xy 127.846647 -133.040246)
			(xy 127.846074 -133.050788) (xy 127.846074 -133.125464) (xy 127.846617 -133.136012) (xy 127.855143 -133.155307)
			(xy 127.862584 -133.162802) (xy 127.881661 -133.180939) (xy 127.91514 -133.221558) (xy 127.942711 -133.266398)
			(xy 127.96385 -133.314606) (xy 127.978155 -133.365263) (xy 127.985353 -133.417407) (xy 127.985774 -133.443726)
			(xy 127.985288 -133.470977) (xy 127.977532 -133.524925) (xy 127.962177 -133.57722) (xy 127.939535 -133.626797)
			(xy 127.910069 -133.672647) (xy 127.874378 -133.713838) (xy 127.833187 -133.749529) (xy 127.787337 -133.778995)
			(xy 127.73776 -133.801637) (xy 127.685465 -133.816992) (xy 127.631517 -133.824748) (xy 127.577015 -133.824748)
			(xy 127.523067 -133.816992) (xy 127.470772 -133.801637) (xy 127.421195 -133.778995) (xy 127.375345 -133.749529)
			(xy 127.334154 -133.713838) (xy 127.298463 -133.672647) (xy 127.268997 -133.626797) (xy 127.246355 -133.57722)
			(xy 127.231 -133.524925) (xy 127.223244 -133.470977) (xy 127.222758 -133.443726) (xy 123.222512 -133.443726)
			(xy 123.222512 -135.142051) (xy 125.46177 -135.142051) (xy 125.46177 -135.087549) (xy 125.469526 -135.033603)
			(xy 125.48488 -134.981309) (xy 125.50752 -134.931732) (xy 125.536985 -134.885882) (xy 125.572674 -134.844691)
			(xy 125.613862 -134.808999) (xy 125.659711 -134.779531) (xy 125.709286 -134.756888) (xy 125.761579 -134.741531)
			(xy 125.815525 -134.733771) (xy 125.842776 -134.733284) (xy 125.871694 -134.733788) (xy 125.928867 -134.742515)
			(xy 125.984068 -134.759774) (xy 126.03603 -134.785168) (xy 126.083563 -134.818116) (xy 126.125578 -134.857862)
			(xy 126.143766 -134.88035) (xy 126.151132 -134.889748) (xy 126.172976 -134.900162) (xy 126.278386 -134.897876)
			(xy 126.299722 -134.8867) (xy 126.30658 -134.876794) (xy 126.321977 -134.855883) (xy 126.357555 -134.818056)
			(xy 126.397935 -134.785404) (xy 126.442369 -134.75853) (xy 126.490038 -134.737929) (xy 126.54006 -134.723985)
			(xy 126.591511 -134.716952) (xy 126.617476 -134.71652) (xy 126.644846 -134.716995) (xy 126.699025 -134.72481)
			(xy 126.751528 -134.740297) (xy 126.801275 -134.763137) (xy 126.847242 -134.792859) (xy 126.868174 -134.8105)
			(xy 126.875286 -134.816596) (xy 126.892304 -134.822946) (xy 126.977648 -134.822946) (xy 126.994666 -134.816596)
			(xy 127.001778 -134.8105) (xy 127.022711 -134.792859) (xy 127.068679 -134.763135) (xy 127.118425 -134.740289)
			(xy 127.170927 -134.724793) (xy 127.225105 -134.716964) (xy 127.279847 -134.716964) (xy 127.334025 -134.724793)
			(xy 127.386527 -134.740289) (xy 127.436273 -134.763135) (xy 127.482241 -134.792859) (xy 127.503174 -134.8105)
			(xy 127.510286 -134.816596) (xy 127.527304 -134.822946) (xy 127.612648 -134.822946) (xy 127.629666 -134.816596)
			(xy 127.636778 -134.8105) (xy 127.649576 -134.799552) (xy 127.676794 -134.779709) (xy 127.691134 -134.770876)
			(xy 127.700278 -134.765542) (xy 127.71247 -134.748524) (xy 127.732536 -134.655306) (xy 127.728472 -134.634732)
			(xy 127.722376 -134.626096) (xy 127.706369 -134.602036) (xy 127.681029 -134.550103) (xy 127.663805 -134.494944)
			(xy 127.655092 -134.437819) (xy 127.654558 -134.408926) (xy 127.655044 -134.381675) (xy 127.6628 -134.327727)
			(xy 127.678155 -134.275432) (xy 127.700797 -134.225855) (xy 127.730263 -134.180005) (xy 127.765954 -134.138814)
			(xy 127.807145 -134.103123) (xy 127.852995 -134.073657) (xy 127.902572 -134.051015) (xy 127.954867 -134.03566)
			(xy 128.008815 -134.027904) (xy 128.063317 -134.027904) (xy 128.117265 -134.03566) (xy 128.16956 -134.051015)
			(xy 128.219137 -134.073657) (xy 128.264987 -134.103123) (xy 128.306178 -134.138814) (xy 128.341869 -134.180005)
			(xy 128.371335 -134.225855) (xy 128.393977 -134.275432) (xy 128.409332 -134.327727) (xy 128.417088 -134.381675)
			(xy 128.417574 -134.408926) (xy 128.417121 -134.437019) (xy 128.408889 -134.492599) (xy 128.392592 -134.54637)
			(xy 128.368583 -134.597169) (xy 128.337381 -134.643895) (xy 128.299662 -134.685539) (xy 128.256242 -134.721198)
			(xy 128.232408 -134.736078) (xy 128.223264 -134.741412) (xy 128.211072 -134.75843) (xy 128.191006 -134.851648)
			(xy 128.19507 -134.872222) (xy 128.201166 -134.880858) (xy 128.217146 -134.904934) (xy 128.242495 -134.956861)
			(xy 128.259726 -135.012015) (xy 128.268447 -135.069136) (xy 128.268984 -135.098028) (xy 128.268548 -135.125281)
			(xy 128.260787 -135.179232) (xy 128.245427 -135.231529) (xy 128.222781 -135.281108) (xy 128.19331 -135.326959)
			(xy 128.157613 -135.36815) (xy 128.116418 -135.403841) (xy 128.070562 -135.433306) (xy 128.02098 -135.455946)
			(xy 127.968681 -135.471298) (xy 127.914729 -135.479052) (xy 127.887476 -135.479536) (xy 127.860105 -135.4791)
			(xy 127.805924 -135.471277) (xy 127.753419 -135.455782) (xy 127.703673 -135.432933) (xy 127.657708 -135.403201)
			(xy 127.636778 -135.385556) (xy 127.629666 -135.37946) (xy 127.612648 -135.37311) (xy 127.527304 -135.37311)
			(xy 127.510286 -135.37946) (xy 127.503174 -135.385556) (xy 127.482241 -135.403197) (xy 127.436273 -135.432921)
			(xy 127.386527 -135.455767) (xy 127.334025 -135.471263) (xy 127.279847 -135.479092) (xy 127.225105 -135.479092)
			(xy 127.170927 -135.471263) (xy 127.118425 -135.455767) (xy 127.068679 -135.432921) (xy 127.022711 -135.403197)
			(xy 127.001778 -135.385556) (xy 126.994666 -135.37946) (xy 126.977648 -135.37311) (xy 126.892304 -135.37311)
			(xy 126.875286 -135.37946) (xy 126.868174 -135.385556) (xy 126.847219 -135.403167) (xy 126.801253 -135.432885)
			(xy 126.751512 -135.455727) (xy 126.699016 -135.471224) (xy 126.644844 -135.479059) (xy 126.617476 -135.479536)
			(xy 126.58856 -135.478987) (xy 126.531389 -135.470268) (xy 126.47619 -135.453018) (xy 126.424227 -135.427632)
			(xy 126.376693 -135.394692) (xy 126.334676 -135.354954) (xy 126.316486 -135.33247) (xy 126.30912 -135.323072)
			(xy 126.287276 -135.312658) (xy 126.181866 -135.314944) (xy 126.16053 -135.32612) (xy 126.153672 -135.336026)
			(xy 126.138249 -135.356917) (xy 126.102675 -135.394743) (xy 126.062299 -135.427397) (xy 126.017869 -135.454273)
			(xy 125.970205 -135.474877) (xy 125.920187 -135.488826) (xy 125.868739 -135.495864) (xy 125.842776 -135.4963)
			(xy 125.815525 -135.495829) (xy 125.761579 -135.488069) (xy 125.709286 -135.472712) (xy 125.659711 -135.450069)
			(xy 125.613862 -135.420601) (xy 125.572674 -135.384909) (xy 125.536985 -135.343718) (xy 125.50752 -135.297868)
			(xy 125.48488 -135.248291) (xy 125.469526 -135.195997) (xy 125.46177 -135.142051) (xy 123.222512 -135.142051)
			(xy 123.222512 -135.866886) (xy 124.539754 -135.866886) (xy 124.543825 -135.811264) (xy 124.555951 -135.756827)
			(xy 124.575874 -135.704736) (xy 124.60317 -135.656101) (xy 124.637256 -135.611958) (xy 124.677405 -135.573249)
			(xy 124.722763 -135.540798) (xy 124.772363 -135.515297) (xy 124.825147 -135.49729) (xy 124.87999 -135.48716)
			(xy 124.935724 -135.485123) (xy 124.991161 -135.491223) (xy 125.045118 -135.505329) (xy 125.096447 -135.527141)
			(xy 125.144053 -135.556195) (xy 125.186921 -135.59187) (xy 125.224138 -135.633407) (xy 125.254911 -135.67992)
			(xy 125.278583 -135.730417) (xy 125.294651 -135.783824) (xy 125.302771 -135.839) (xy 125.30328 -135.866886)
			(xy 125.302771 -135.894772) (xy 125.294651 -135.949948) (xy 125.278583 -136.003355) (xy 125.254911 -136.053852)
			(xy 125.224138 -136.100365) (xy 125.186921 -136.141902) (xy 125.144053 -136.177577) (xy 125.096447 -136.206631)
			(xy 125.045118 -136.228443) (xy 124.991161 -136.242549) (xy 124.935724 -136.248649) (xy 124.87999 -136.246612)
			(xy 124.825147 -136.236482) (xy 124.772363 -136.218475) (xy 124.722763 -136.192974) (xy 124.677405 -136.160523)
			(xy 124.637256 -136.121814) (xy 124.60317 -136.077671) (xy 124.575874 -136.029036) (xy 124.555951 -135.976945)
			(xy 124.543825 -135.922508) (xy 124.539754 -135.866886) (xy 123.222512 -135.866886) (xy 123.222512 -137.44829)
			(xy 124.445012 -137.44829) (xy 124.449083 -137.392668) (xy 124.461209 -137.338231) (xy 124.481132 -137.28614)
			(xy 124.508428 -137.237505) (xy 124.542514 -137.193362) (xy 124.582663 -137.154653) (xy 124.628021 -137.122202)
			(xy 124.677621 -137.096701) (xy 124.730405 -137.078694) (xy 124.785248 -137.068564) (xy 124.840982 -137.066527)
			(xy 124.896419 -137.072627) (xy 124.950376 -137.086733) (xy 125.001705 -137.108545) (xy 125.049311 -137.137599)
			(xy 125.092179 -137.173274) (xy 125.129396 -137.214811) (xy 125.160169 -137.261324) (xy 125.167204 -137.276332)
			(xy 129.147062 -137.276332) (xy 129.147532 -137.248962) (xy 129.155346 -137.194782) (xy 129.170834 -137.142279)
			(xy 129.193675 -137.092532) (xy 129.2234 -137.046565) (xy 129.241042 -137.025634) (xy 129.247138 -137.018522)
			(xy 129.253488 -137.001504) (xy 129.253488 -136.91616) (xy 129.247138 -136.899142) (xy 129.241042 -136.89203)
			(xy 129.22341 -136.871092) (xy 129.193696 -136.825122) (xy 129.170858 -136.775376) (xy 129.155365 -136.722876)
			(xy 129.147536 -136.668701) (xy 129.147062 -136.641332) (xy 129.147548 -136.614081) (xy 129.155304 -136.560133)
			(xy 129.170659 -136.507838) (xy 129.193301 -136.458261) (xy 129.222767 -136.412411) (xy 129.258458 -136.37122)
			(xy 129.299649 -136.335529) (xy 129.345499 -136.306063) (xy 129.395076 -136.283421) (xy 129.447371 -136.268066)
			(xy 129.501319 -136.26031) (xy 129.555821 -136.26031) (xy 129.609769 -136.268066) (xy 129.662064 -136.283421)
			(xy 129.711641 -136.306063) (xy 129.757491 -136.335529) (xy 129.798682 -136.37122) (xy 129.834373 -136.412411)
			(xy 129.863839 -136.458261) (xy 129.886481 -136.507838) (xy 129.901836 -136.560133) (xy 129.909592 -136.614081)
			(xy 129.910078 -136.641332) (xy 129.909636 -136.668703) (xy 129.901813 -136.722883) (xy 129.886319 -136.775387)
			(xy 129.863472 -136.825134) (xy 129.833742 -136.871099) (xy 129.816098 -136.89203) (xy 129.810002 -136.899142)
			(xy 129.803652 -136.91616) (xy 129.803652 -137.001504) (xy 129.810002 -137.018522) (xy 129.816098 -137.025634)
			(xy 129.833719 -137.04658) (xy 129.863434 -137.092549) (xy 129.886273 -137.142293) (xy 129.901769 -137.194791)
			(xy 129.909601 -137.248964) (xy 129.910078 -137.276332) (xy 129.909592 -137.303583) (xy 129.901836 -137.357531)
			(xy 129.886481 -137.409826) (xy 129.863839 -137.459403) (xy 129.834373 -137.505253) (xy 129.798682 -137.546444)
			(xy 129.757491 -137.582135) (xy 129.711641 -137.611601) (xy 129.662064 -137.634243) (xy 129.609769 -137.649598)
			(xy 129.555821 -137.657354) (xy 129.501319 -137.657354) (xy 129.447371 -137.649598) (xy 129.395076 -137.634243)
			(xy 129.345499 -137.611601) (xy 129.299649 -137.582135) (xy 129.258458 -137.546444) (xy 129.222767 -137.505253)
			(xy 129.193301 -137.459403) (xy 129.170659 -137.409826) (xy 129.155304 -137.357531) (xy 129.147548 -137.303583)
			(xy 129.147062 -137.276332) (xy 125.167204 -137.276332) (xy 125.183841 -137.311821) (xy 125.199909 -137.365228)
			(xy 125.208029 -137.420404) (xy 125.208538 -137.44829) (xy 125.208029 -137.476176) (xy 125.199909 -137.531352)
			(xy 125.183841 -137.584759) (xy 125.160169 -137.635256) (xy 125.129396 -137.681769) (xy 125.092179 -137.723306)
			(xy 125.088132 -137.726674) (xy 130.087624 -137.726674) (xy 130.088069 -137.699303) (xy 130.095891 -137.645123)
			(xy 130.111385 -137.592619) (xy 130.134231 -137.542873) (xy 130.16396 -137.496907) (xy 130.181604 -137.475976)
			(xy 130.1877 -137.468864) (xy 130.19405 -137.451846) (xy 130.19405 -137.366502) (xy 130.1877 -137.349484)
			(xy 130.181604 -137.342372) (xy 130.163986 -137.321423) (xy 130.134271 -137.275455) (xy 130.111431 -137.225712)
			(xy 130.095935 -137.173215) (xy 130.088101 -137.119042) (xy 130.087624 -137.091674) (xy 130.08811 -137.064423)
			(xy 130.095866 -137.010475) (xy 130.111221 -136.95818) (xy 130.133863 -136.908603) (xy 130.163329 -136.862753)
			(xy 130.19902 -136.821562) (xy 130.240211 -136.785871) (xy 130.286061 -136.756405) (xy 130.335638 -136.733763)
			(xy 130.387933 -136.718408) (xy 130.441881 -136.710652) (xy 130.496383 -136.710652) (xy 130.550331 -136.718408)
			(xy 130.602626 -136.733763) (xy 130.652203 -136.756405) (xy 130.698053 -136.785871) (xy 130.739244 -136.821562)
			(xy 130.774935 -136.862753) (xy 130.804401 -136.908603) (xy 130.827043 -136.95818) (xy 130.842398 -137.010475)
			(xy 130.850154 -137.064423) (xy 130.85064 -137.091674) (xy 130.850173 -137.119044) (xy 130.842358 -137.173224)
			(xy 130.82687 -137.225728) (xy 130.804028 -137.275475) (xy 130.774302 -137.321441) (xy 130.75666 -137.342372)
			(xy 130.750564 -137.349484) (xy 130.744214 -137.366502) (xy 130.744214 -137.451846) (xy 130.750564 -137.468864)
			(xy 130.75666 -137.475976) (xy 130.774295 -137.496911) (xy 130.804009 -137.542883) (xy 130.826846 -137.592629)
			(xy 130.842338 -137.645129) (xy 130.850166 -137.699305) (xy 130.85064 -137.726674) (xy 130.850154 -137.753925)
			(xy 130.842398 -137.807873) (xy 130.827043 -137.860168) (xy 130.804401 -137.909745) (xy 130.774935 -137.955595)
			(xy 130.739244 -137.996786) (xy 130.698053 -138.032477) (xy 130.652203 -138.061943) (xy 130.602626 -138.084585)
			(xy 130.550331 -138.09994) (xy 130.496383 -138.107696) (xy 130.441881 -138.107696) (xy 130.387933 -138.09994)
			(xy 130.335638 -138.084585) (xy 130.286061 -138.061943) (xy 130.240211 -138.032477) (xy 130.19902 -137.996786)
			(xy 130.163329 -137.955595) (xy 130.133863 -137.909745) (xy 130.111221 -137.860168) (xy 130.095866 -137.807873)
			(xy 130.08811 -137.753925) (xy 130.087624 -137.726674) (xy 125.088132 -137.726674) (xy 125.049311 -137.758981)
			(xy 125.001705 -137.788035) (xy 124.950376 -137.809847) (xy 124.896419 -137.823953) (xy 124.840982 -137.830053)
			(xy 124.785248 -137.828016) (xy 124.730405 -137.817886) (xy 124.677621 -137.799879) (xy 124.628021 -137.774378)
			(xy 124.582663 -137.741927) (xy 124.542514 -137.703218) (xy 124.508428 -137.659075) (xy 124.481132 -137.61044)
			(xy 124.461209 -137.558349) (xy 124.449083 -137.503912) (xy 124.445012 -137.44829) (xy 123.222512 -137.44829)
			(xy 123.222512 -138.40333) (xy 131.296156 -138.40333) (xy 131.296666 -138.375664) (xy 131.304662 -138.320914)
			(xy 131.320477 -138.267891) (xy 131.34378 -138.217706) (xy 131.374082 -138.17141) (xy 131.41075 -138.129973)
			(xy 131.453014 -138.094262) (xy 131.476242 -138.079226) (xy 131.486402 -138.072876) (xy 131.498848 -138.053318)
			(xy 131.509262 -137.949178) (xy 131.501134 -137.927334) (xy 131.492244 -137.918952) (xy 131.473666 -137.900868)
			(xy 131.441085 -137.860538) (xy 131.414271 -137.816164) (xy 131.393717 -137.768566) (xy 131.379804 -137.718622)
			(xy 131.372787 -137.667253) (xy 131.372356 -137.64133) (xy 131.372906 -137.614081) (xy 131.380658 -137.560138)
			(xy 131.396007 -137.507846) (xy 131.418642 -137.458272) (xy 131.448102 -137.412423) (xy 131.483787 -137.371233)
			(xy 131.52497 -137.335541) (xy 131.570814 -137.306074) (xy 131.620384 -137.28343) (xy 131.672673 -137.268072)
			(xy 131.726615 -137.260311) (xy 131.753864 -137.259822) (xy 131.781234 -137.260304) (xy 131.835412 -137.268117)
			(xy 131.887915 -137.283602) (xy 131.937663 -137.30644) (xy 131.98363 -137.336162) (xy 132.004562 -137.353802)
			(xy 132.011674 -137.359898) (xy 132.028692 -137.366248) (xy 132.114036 -137.366248) (xy 132.131054 -137.359898)
			(xy 132.138166 -137.353802) (xy 132.1591 -137.336166) (xy 132.205072 -137.306453) (xy 132.254819 -137.283617)
			(xy 132.30732 -137.268125) (xy 132.361495 -137.260296) (xy 132.388864 -137.259822) (xy 132.416117 -137.260289)
			(xy 132.47007 -137.268042) (xy 132.522369 -137.283395) (xy 132.571951 -137.306035) (xy 132.617806 -137.335502)
			(xy 132.659 -137.371196) (xy 132.694694 -137.412389) (xy 132.724162 -137.458243) (xy 132.746803 -137.507825)
			(xy 132.762157 -137.560124) (xy 132.769911 -137.614077) (xy 132.770372 -137.64133) (xy 132.769814 -137.670246)
			(xy 132.761095 -137.727415) (xy 132.743846 -137.782614) (xy 132.718461 -137.834576) (xy 132.685524 -137.882111)
			(xy 132.645789 -137.924129) (xy 132.623306 -137.94232) (xy 132.61454 -137.949879) (xy 132.604359 -137.97064)
			(xy 132.603748 -137.982198) (xy 132.603748 -138.062462) (xy 132.604324 -138.07403) (xy 132.614513 -138.094802)
			(xy 132.623306 -138.10234) (xy 132.64581 -138.120507) (xy 132.685544 -138.162532) (xy 132.71848 -138.210072)
			(xy 132.743865 -138.262038) (xy 132.761117 -138.31724) (xy 132.76984 -138.374413) (xy 132.770372 -138.40333)
			(xy 132.769973 -138.430585) (xy 132.762211 -138.48454) (xy 132.750105 -138.525758) (xy 133.041644 -138.525758)
			(xy 133.042133 -138.498388) (xy 133.049944 -138.44421) (xy 133.065427 -138.391707) (xy 133.088264 -138.341959)
			(xy 133.117984 -138.295992) (xy 133.135624 -138.27506) (xy 133.14172 -138.267948) (xy 133.14807 -138.25093)
			(xy 133.14807 -138.165586) (xy 133.14172 -138.148568) (xy 133.135624 -138.141456) (xy 133.117942 -138.120557)
			(xy 133.088219 -138.074583) (xy 133.065377 -138.024831) (xy 133.049884 -137.972324) (xy 133.042059 -137.918141)
			(xy 133.042064 -137.863396) (xy 133.049897 -137.809214) (xy 133.065399 -137.75671) (xy 133.08825 -137.706962)
			(xy 133.11798 -137.660993) (xy 133.135624 -137.64006) (xy 133.14172 -137.632948) (xy 133.14807 -137.61593)
			(xy 133.14807 -137.530586) (xy 133.14172 -137.513568) (xy 133.135624 -137.506456) (xy 133.117942 -137.485557)
			(xy 133.088219 -137.439583) (xy 133.065377 -137.389831) (xy 133.049884 -137.337324) (xy 133.042059 -137.283141)
			(xy 133.042064 -137.228396) (xy 133.049897 -137.174214) (xy 133.065399 -137.12171) (xy 133.08825 -137.071962)
			(xy 133.11798 -137.025993) (xy 133.135624 -137.00506) (xy 133.14172 -136.997948) (xy 133.14807 -136.98093)
			(xy 133.14807 -136.895586) (xy 133.14172 -136.878568) (xy 133.135624 -136.871456) (xy 133.118001 -136.850511)
			(xy 133.088286 -136.804542) (xy 133.065447 -136.754798) (xy 133.049952 -136.7023) (xy 133.04212 -136.648126)
			(xy 133.041644 -136.620758) (xy 133.04213 -136.593507) (xy 133.049886 -136.539559) (xy 133.065241 -136.487264)
			(xy 133.087883 -136.437687) (xy 133.117349 -136.391837) (xy 133.15304 -136.350646) (xy 133.194231 -136.314955)
			(xy 133.240081 -136.285489) (xy 133.289658 -136.262847) (xy 133.341953 -136.247492) (xy 133.395901 -136.239736)
			(xy 133.450403 -136.239736) (xy 133.504351 -136.247492) (xy 133.556646 -136.262847) (xy 133.606223 -136.285489)
			(xy 133.652073 -136.314955) (xy 133.693264 -136.350646) (xy 133.728955 -136.391837) (xy 133.758421 -136.437687)
			(xy 133.781063 -136.487264) (xy 133.796418 -136.539559) (xy 133.804174 -136.593507) (xy 133.80466 -136.620758)
			(xy 133.804179 -136.648128) (xy 133.796366 -136.702307) (xy 133.780881 -136.75481) (xy 133.758043 -136.804557)
			(xy 133.72832 -136.850524) (xy 133.71068 -136.871456) (xy 133.704584 -136.878568) (xy 133.698234 -136.895586)
			(xy 133.698234 -136.98093) (xy 133.704584 -136.997948) (xy 133.71068 -137.00506) (xy 133.728279 -137.026026)
			(xy 133.758005 -137.071988) (xy 133.780853 -137.121729) (xy 133.796352 -137.174226) (xy 133.804184 -137.2284)
			(xy 133.804189 -137.283137) (xy 133.796365 -137.337312) (xy 133.780875 -137.389812) (xy 133.758036 -137.439556)
			(xy 133.728317 -137.485523) (xy 133.71068 -137.506456) (xy 133.704584 -137.513568) (xy 133.698234 -137.530586)
			(xy 133.698234 -137.61593) (xy 133.704584 -137.632948) (xy 133.71068 -137.64006) (xy 133.728279 -137.661026)
			(xy 133.758005 -137.706988) (xy 133.780853 -137.756729) (xy 133.796352 -137.809226) (xy 133.804184 -137.8634)
			(xy 133.804189 -137.918137) (xy 133.796365 -137.972312) (xy 133.780875 -138.024812) (xy 133.758036 -138.074556)
			(xy 133.728317 -138.120523) (xy 133.71068 -138.141456) (xy 133.704584 -138.148568) (xy 133.698234 -138.165586)
			(xy 133.698234 -138.25093) (xy 133.704584 -138.267948) (xy 133.71068 -138.27506) (xy 133.728311 -138.295999)
			(xy 133.758024 -138.34197) (xy 133.780862 -138.391715) (xy 133.796355 -138.444215) (xy 133.804185 -138.498389)
			(xy 133.80466 -138.525758) (xy 133.804185 -138.552387) (xy 133.796782 -138.605129) (xy 133.782114 -138.656328)
			(xy 133.760466 -138.704988) (xy 133.732259 -138.750164) (xy 133.715506 -138.770868) (xy 133.707632 -138.780266)
			(xy 133.702044 -138.80338) (xy 133.726428 -138.906504) (xy 133.741668 -138.924538) (xy 133.752844 -138.929364)
			(xy 133.779561 -138.941549) (xy 133.829186 -138.972936) (xy 133.85165 -138.991848) (xy 133.858762 -138.997944)
			(xy 133.87578 -139.004294) (xy 133.961124 -139.004294) (xy 133.978142 -138.997944) (xy 133.985254 -138.991848)
			(xy 134.006187 -138.974207) (xy 134.052155 -138.944483) (xy 134.101901 -138.921637) (xy 134.154403 -138.906141)
			(xy 134.208581 -138.898312) (xy 134.263323 -138.898312) (xy 134.317501 -138.906141) (xy 134.370003 -138.921637)
			(xy 134.419749 -138.944483) (xy 134.465717 -138.974207) (xy 134.48665 -138.991848) (xy 134.493762 -138.997944)
			(xy 134.51078 -139.004294) (xy 134.596124 -139.004294) (xy 134.613142 -138.997944) (xy 134.620254 -138.991848)
			(xy 134.641187 -138.974207) (xy 134.687155 -138.944483) (xy 134.736901 -138.921637) (xy 134.789403 -138.906141)
			(xy 134.843581 -138.898312) (xy 134.898323 -138.898312) (xy 134.952501 -138.906141) (xy 135.005003 -138.921637)
			(xy 135.054749 -138.944483) (xy 135.100717 -138.974207) (xy 135.12165 -138.991848) (xy 135.128762 -138.997944)
			(xy 135.14578 -139.004294) (xy 135.231124 -139.004294) (xy 135.248142 -138.997944) (xy 135.255254 -138.991848)
			(xy 135.276199 -138.974224) (xy 135.322167 -138.944509) (xy 135.371912 -138.921669) (xy 135.42441 -138.906174)
			(xy 135.478584 -138.898343) (xy 135.505952 -138.897868) (xy 135.533205 -138.898376) (xy 135.587158 -138.906127)
			(xy 135.639458 -138.921478) (xy 135.689041 -138.944116) (xy 135.734898 -138.973581) (xy 135.776094 -139.009272)
			(xy 135.81179 -139.050464) (xy 135.841261 -139.096316) (xy 135.863905 -139.145897) (xy 135.879263 -139.198195)
			(xy 135.887021 -139.252147) (xy 135.887021 -139.306653) (xy 135.879263 -139.360605) (xy 135.863905 -139.412903)
			(xy 135.841261 -139.462484) (xy 135.81179 -139.508336) (xy 135.776094 -139.549528) (xy 135.734898 -139.585219)
			(xy 135.689041 -139.614684) (xy 135.639458 -139.637322) (xy 135.587158 -139.652673) (xy 135.533205 -139.660424)
			(xy 135.505952 -139.660884) (xy 135.478583 -139.660391) (xy 135.424405 -139.652581) (xy 135.371902 -139.637098)
			(xy 135.322154 -139.614262) (xy 135.276186 -139.584543) (xy 135.255254 -139.566904) (xy 135.248142 -139.560808)
			(xy 135.231124 -139.554458) (xy 135.14578 -139.554458) (xy 135.128762 -139.560808) (xy 135.12165 -139.566904)
			(xy 135.100717 -139.584545) (xy 135.054749 -139.614269) (xy 135.005003 -139.637115) (xy 134.952501 -139.652611)
			(xy 134.898323 -139.66044) (xy 134.843581 -139.66044) (xy 134.789403 -139.652611) (xy 134.736901 -139.637115)
			(xy 134.687155 -139.614269) (xy 134.641187 -139.584545) (xy 134.620254 -139.566904) (xy 134.613142 -139.560808)
			(xy 134.596124 -139.554458) (xy 134.51078 -139.554458) (xy 134.493762 -139.560808) (xy 134.48665 -139.566904)
			(xy 134.465717 -139.584545) (xy 134.419749 -139.614269) (xy 134.370003 -139.637115) (xy 134.317501 -139.652611)
			(xy 134.263323 -139.66044) (xy 134.208581 -139.66044) (xy 134.154403 -139.652611) (xy 134.101901 -139.637115)
			(xy 134.052155 -139.614269) (xy 134.006187 -139.584545) (xy 133.985254 -139.566904) (xy 133.978142 -139.560808)
			(xy 133.961124 -139.554458) (xy 133.87578 -139.554458) (xy 133.858762 -139.560808) (xy 133.85165 -139.566904)
			(xy 133.83071 -139.584534) (xy 133.78474 -139.614247) (xy 133.734994 -139.637085) (xy 133.682495 -139.652578)
			(xy 133.628321 -139.660409) (xy 133.600952 -139.660884) (xy 133.573698 -139.660467) (xy 133.519747 -139.652703)
			(xy 133.46745 -139.637341) (xy 133.417871 -139.614692) (xy 133.372019 -139.585219) (xy 133.330829 -139.54952)
			(xy 133.295138 -139.508323) (xy 133.265673 -139.462466) (xy 133.243034 -139.412883) (xy 133.227682 -139.360583)
			(xy 133.219928 -139.30663) (xy 133.219444 -139.279376) (xy 133.21988 -139.252745) (xy 133.227292 -139.200002)
			(xy 133.241969 -139.148803) (xy 133.263626 -139.100143) (xy 133.291841 -139.054969) (xy 133.308598 -139.034266)
			(xy 133.316472 -139.024868) (xy 133.32206 -139.001754) (xy 133.297676 -138.89863) (xy 133.282436 -138.880596)
			(xy 133.27126 -138.87577) (xy 133.246048 -138.864275) (xy 133.198951 -138.835085) (xy 133.156571 -138.799391)
			(xy 133.119797 -138.757944) (xy 133.089403 -138.711615) (xy 133.066029 -138.661377) (xy 133.050164 -138.608288)
			(xy 133.042143 -138.553462) (xy 133.041644 -138.525758) (xy 132.750105 -138.525758) (xy 132.746849 -138.536842)
			(xy 132.724201 -138.586424) (xy 132.694726 -138.632279) (xy 132.659026 -138.673472) (xy 132.617826 -138.709166)
			(xy 132.571966 -138.738632) (xy 132.52238 -138.761272) (xy 132.470076 -138.776625) (xy 132.416119 -138.784378)
			(xy 132.388864 -138.784838) (xy 132.362548 -138.784377) (xy 132.310415 -138.777156) (xy 132.259768 -138.762844)
			(xy 132.211566 -138.741711) (xy 132.166724 -138.714158) (xy 132.126091 -138.680707) (xy 132.10794 -138.661648)
			(xy 132.100399 -138.654269) (xy 132.081134 -138.64573) (xy 132.070602 -138.645138) (xy 131.995926 -138.645138)
			(xy 131.985375 -138.645657) (xy 131.966079 -138.654198) (xy 131.958588 -138.661648) (xy 131.940449 -138.680723)
			(xy 131.899831 -138.714204) (xy 131.854991 -138.741776) (xy 131.806785 -138.762916) (xy 131.756127 -138.77722)
			(xy 131.703983 -138.784418) (xy 131.677664 -138.784838) (xy 131.650413 -138.784356) (xy 131.596467 -138.776595)
			(xy 131.544174 -138.761237) (xy 131.494599 -138.738594) (xy 131.44875 -138.709127) (xy 131.407561 -138.673435)
			(xy 131.37187 -138.632245) (xy 131.342403 -138.586396) (xy 131.319761 -138.53682) (xy 131.304404 -138.484527)
			(xy 131.296644 -138.430581) (xy 131.296156 -138.40333) (xy 123.222512 -138.40333) (xy 123.222512 -138.824462)
			(xy 124.461776 -138.824462) (xy 124.465847 -138.76884) (xy 124.477973 -138.714403) (xy 124.497896 -138.662312)
			(xy 124.525192 -138.613677) (xy 124.559278 -138.569534) (xy 124.599427 -138.530825) (xy 124.644785 -138.498374)
			(xy 124.694385 -138.472873) (xy 124.747169 -138.454866) (xy 124.802012 -138.444736) (xy 124.857746 -138.442699)
			(xy 124.913183 -138.448799) (xy 124.96714 -138.462905) (xy 125.018469 -138.484717) (xy 125.066075 -138.513771)
			(xy 125.108943 -138.549446) (xy 125.14616 -138.590983) (xy 125.176933 -138.637496) (xy 125.200605 -138.687993)
			(xy 125.216673 -138.7414) (xy 125.224793 -138.796576) (xy 125.225302 -138.824462) (xy 125.224793 -138.852348)
			(xy 125.216673 -138.907524) (xy 125.200605 -138.960931) (xy 125.176933 -139.011428) (xy 125.14616 -139.057941)
			(xy 125.108943 -139.099478) (xy 125.066075 -139.135153) (xy 125.018469 -139.164207) (xy 124.96714 -139.186019)
			(xy 124.913183 -139.200125) (xy 124.857746 -139.206225) (xy 124.802012 -139.204188) (xy 124.747169 -139.194058)
			(xy 124.694385 -139.176051) (xy 124.644785 -139.15055) (xy 124.599427 -139.118099) (xy 124.559278 -139.07939)
			(xy 124.525192 -139.035247) (xy 124.497896 -138.986612) (xy 124.477973 -138.934521) (xy 124.465847 -138.880084)
			(xy 124.461776 -138.824462) (xy 123.222512 -138.824462) (xy 123.222512 -140.392404) (xy 124.467618 -140.392404)
			(xy 124.471689 -140.336782) (xy 124.483815 -140.282345) (xy 124.503738 -140.230254) (xy 124.531034 -140.181619)
			(xy 124.56512 -140.137476) (xy 124.605269 -140.098767) (xy 124.650627 -140.066316) (xy 124.700227 -140.040815)
			(xy 124.753011 -140.022808) (xy 124.807854 -140.012678) (xy 124.863588 -140.010641) (xy 124.919025 -140.016741)
			(xy 124.972982 -140.030847) (xy 125.024311 -140.052659) (xy 125.071917 -140.081713) (xy 125.114785 -140.117388)
			(xy 125.152002 -140.158925) (xy 125.182775 -140.205438) (xy 125.206447 -140.255935) (xy 125.222515 -140.309342)
			(xy 125.230635 -140.364518) (xy 125.231144 -140.392404) (xy 125.230635 -140.42029) (xy 125.222515 -140.475466)
			(xy 125.206447 -140.528873) (xy 125.182775 -140.57937) (xy 125.152002 -140.625883) (xy 125.114785 -140.66742)
			(xy 125.071917 -140.703095) (xy 125.024311 -140.732149) (xy 124.972982 -140.753961) (xy 124.919025 -140.768067)
			(xy 124.863588 -140.774167) (xy 124.807854 -140.77213) (xy 124.753011 -140.762) (xy 124.700227 -140.743993)
			(xy 124.650627 -140.718492) (xy 124.605269 -140.686041) (xy 124.56512 -140.647332) (xy 124.531034 -140.603189)
			(xy 124.503738 -140.554554) (xy 124.483815 -140.502463) (xy 124.471689 -140.448026) (xy 124.467618 -140.392404)
			(xy 123.222512 -140.392404) (xy 123.222512 -141.046551) (xy 126.854954 -141.046551) (xy 126.854954 -140.992049)
			(xy 126.86271 -140.9381) (xy 126.878064 -140.885805) (xy 126.900704 -140.836227) (xy 126.930169 -140.790375)
			(xy 126.965859 -140.749183) (xy 127.007048 -140.71349) (xy 127.052897 -140.684021) (xy 127.102473 -140.661376)
			(xy 127.154767 -140.646017) (xy 127.208715 -140.638256) (xy 127.235966 -140.637768) (xy 127.262282 -140.638208)
			(xy 127.314417 -140.645432) (xy 127.365065 -140.659748) (xy 127.413266 -140.680885) (xy 127.458108 -140.708442)
			(xy 127.49874 -140.741897) (xy 127.51689 -140.760958) (xy 127.524419 -140.768351) (xy 127.543693 -140.776882)
			(xy 127.554228 -140.777468) (xy 127.628904 -140.777468) (xy 127.639457 -140.776964) (xy 127.658752 -140.768412)
			(xy 127.666242 -140.760958) (xy 127.684368 -140.741869) (xy 127.724989 -140.70839) (xy 127.769831 -140.680819)
			(xy 127.81804 -140.659682) (xy 127.8687 -140.64538) (xy 127.920846 -140.638186) (xy 127.947166 -140.637768)
			(xy 127.974419 -140.638277) (xy 128.02837 -140.64603) (xy 128.080669 -140.661382) (xy 128.13025 -140.684021)
			(xy 128.176104 -140.713486) (xy 128.217299 -140.749177) (xy 128.252994 -140.790368) (xy 128.282463 -140.83622)
			(xy 128.305106 -140.8858) (xy 128.320463 -140.938097) (xy 128.328221 -140.992047) (xy 128.328221 -141.046553)
			(xy 128.320463 -141.100503) (xy 128.305106 -141.1528) (xy 128.282463 -141.20238) (xy 128.252994 -141.248232)
			(xy 128.217299 -141.289423) (xy 128.176104 -141.325114) (xy 128.13025 -141.354579) (xy 128.080669 -141.377218)
			(xy 128.02837 -141.39257) (xy 127.974419 -141.400323) (xy 127.947166 -141.400784) (xy 127.92085 -141.400338)
			(xy 127.868715 -141.393118) (xy 127.818067 -141.378803) (xy 127.769865 -141.357668) (xy 127.725023 -141.330111)
			(xy 127.684392 -141.296655) (xy 127.666242 -141.277594) (xy 127.658707 -141.270208) (xy 127.639437 -141.261675)
			(xy 127.628904 -141.261084) (xy 127.554228 -141.261084) (xy 127.543679 -141.26162) (xy 127.524384 -141.270151)
			(xy 127.51689 -141.277594) (xy 127.498759 -141.296677) (xy 127.458138 -141.330155) (xy 127.413297 -141.357725)
			(xy 127.365088 -141.378863) (xy 127.31443 -141.393167) (xy 127.262286 -141.400364) (xy 127.235966 -141.400784)
			(xy 127.208715 -141.400344) (xy 127.154767 -141.392583) (xy 127.102473 -141.377224) (xy 127.052897 -141.354579)
			(xy 127.007048 -141.32511) (xy 126.965859 -141.289417) (xy 126.930169 -141.248225) (xy 126.900704 -141.202373)
			(xy 126.878064 -141.152795) (xy 126.86271 -141.1005) (xy 126.854954 -141.046551) (xy 123.222512 -141.046551)
			(xy 123.222512 -143.078551) (xy 126.854954 -143.078551) (xy 126.854954 -143.024049) (xy 126.86271 -142.9701)
			(xy 126.878064 -142.917805) (xy 126.900704 -142.868227) (xy 126.930169 -142.822375) (xy 126.965859 -142.781183)
			(xy 127.007048 -142.74549) (xy 127.052897 -142.716021) (xy 127.102473 -142.693376) (xy 127.154767 -142.678017)
			(xy 127.208715 -142.670256) (xy 127.235966 -142.669768) (xy 127.262282 -142.670208) (xy 127.314417 -142.677432)
			(xy 127.365065 -142.691748) (xy 127.413266 -142.712885) (xy 127.458108 -142.740442) (xy 127.49874 -142.773897)
			(xy 127.51689 -142.792958) (xy 127.524419 -142.800351) (xy 127.543693 -142.808882) (xy 127.554228 -142.809468)
			(xy 127.628904 -142.809468) (xy 127.639457 -142.808964) (xy 127.658752 -142.800412) (xy 127.666242 -142.792958)
			(xy 127.684368 -142.773869) (xy 127.724989 -142.74039) (xy 127.769831 -142.712819) (xy 127.81804 -142.691682)
			(xy 127.8687 -142.67738) (xy 127.920846 -142.670186) (xy 127.947166 -142.669768) (xy 127.974419 -142.670277)
			(xy 128.02837 -142.67803) (xy 128.080669 -142.693382) (xy 128.13025 -142.716021) (xy 128.176104 -142.745486)
			(xy 128.217299 -142.781177) (xy 128.252994 -142.822368) (xy 128.282463 -142.86822) (xy 128.305106 -142.9178)
			(xy 128.320463 -142.970097) (xy 128.328221 -143.024047) (xy 128.328221 -143.078553) (xy 128.320463 -143.132503)
			(xy 128.305106 -143.1848) (xy 128.282463 -143.23438) (xy 128.252994 -143.280232) (xy 128.217299 -143.321423)
			(xy 128.176104 -143.357114) (xy 128.13025 -143.386579) (xy 128.080669 -143.409218) (xy 128.02837 -143.42457)
			(xy 127.974419 -143.432323) (xy 127.947166 -143.432784) (xy 127.92085 -143.432338) (xy 127.868715 -143.425118)
			(xy 127.818067 -143.410803) (xy 127.769865 -143.389668) (xy 127.725023 -143.362111) (xy 127.684392 -143.328655)
			(xy 127.666242 -143.309594) (xy 127.658707 -143.302208) (xy 127.639437 -143.293675) (xy 127.628904 -143.293084)
			(xy 127.554228 -143.293084) (xy 127.543679 -143.29362) (xy 127.524384 -143.302151) (xy 127.51689 -143.309594)
			(xy 127.498759 -143.328677) (xy 127.458138 -143.362155) (xy 127.413297 -143.389725) (xy 127.365088 -143.410863)
			(xy 127.31443 -143.425167) (xy 127.262286 -143.432364) (xy 127.235966 -143.432784) (xy 127.208715 -143.432344)
			(xy 127.154767 -143.424583) (xy 127.102473 -143.409224) (xy 127.052897 -143.386579) (xy 127.007048 -143.35711)
			(xy 126.965859 -143.321417) (xy 126.930169 -143.280225) (xy 126.900704 -143.234373) (xy 126.878064 -143.184795)
			(xy 126.86271 -143.1325) (xy 126.854954 -143.078551) (xy 123.222512 -143.078551) (xy 123.222512 -143.966438)
			(xy 135.564118 -143.966438) (xy 135.564527 -143.940462) (xy 135.571578 -143.88899) (xy 135.585553 -143.838952)
			(xy 135.606195 -143.791276) (xy 135.63312 -143.746845) (xy 135.66583 -143.706483) (xy 135.703718 -143.670936)
			(xy 135.724646 -143.655542) (xy 135.734137 -143.64791) (xy 135.745282 -143.626298) (xy 135.745982 -143.61414)
			(xy 135.745982 -143.531336) (xy 135.745289 -143.519174) (xy 135.73415 -143.497553) (xy 135.724646 -143.489934)
			(xy 135.703727 -143.474531) (xy 135.665851 -143.438978) (xy 135.633151 -143.398613) (xy 135.606232 -143.354184)
			(xy 135.585593 -143.306511) (xy 135.571616 -143.256479) (xy 135.56456 -143.205012) (xy 135.564118 -143.179038)
			(xy 135.564626 -143.150299) (xy 135.573256 -143.093472) (xy 135.590311 -143.038582) (xy 135.615405 -142.98687)
			(xy 135.647971 -142.939507) (xy 135.667242 -142.91818) (xy 135.673846 -142.911068) (xy 135.680958 -142.893542)
			(xy 135.680958 -142.804134) (xy 135.673846 -142.786608) (xy 135.667242 -142.779496) (xy 135.648008 -142.758137)
			(xy 135.61544 -142.710781) (xy 135.590345 -142.659074) (xy 135.573292 -142.604188) (xy 135.564665 -142.547365)
			(xy 135.564661 -142.489891) (xy 135.573279 -142.433066) (xy 135.590325 -142.378177) (xy 135.615412 -142.326467)
			(xy 135.647973 -142.279106) (xy 135.667242 -142.25778) (xy 135.673846 -142.250668) (xy 135.680958 -142.233142)
			(xy 135.680958 -142.143734) (xy 135.673846 -142.126208) (xy 135.667242 -142.119096) (xy 135.648008 -142.097737)
			(xy 135.61544 -142.050381) (xy 135.590345 -141.998674) (xy 135.573292 -141.943788) (xy 135.564665 -141.886965)
			(xy 135.564661 -141.829491) (xy 135.573279 -141.772666) (xy 135.590325 -141.717777) (xy 135.615412 -141.666067)
			(xy 135.647973 -141.618706) (xy 135.667242 -141.59738) (xy 135.673846 -141.590268) (xy 135.680958 -141.572742)
			(xy 135.680958 -141.483334) (xy 135.673846 -141.465808) (xy 135.667242 -141.458696) (xy 135.648008 -141.437337)
			(xy 135.61544 -141.389981) (xy 135.590345 -141.338274) (xy 135.573292 -141.283388) (xy 135.564665 -141.226565)
			(xy 135.564661 -141.169091) (xy 135.573279 -141.112266) (xy 135.590325 -141.057377) (xy 135.615412 -141.005667)
			(xy 135.647973 -140.958306) (xy 135.667242 -140.93698) (xy 135.673846 -140.929868) (xy 135.680958 -140.912342)
			(xy 135.680958 -140.822934) (xy 135.673846 -140.805408) (xy 135.667242 -140.798296) (xy 135.64799 -140.776953)
			(xy 135.615421 -140.729595) (xy 135.590325 -140.677888) (xy 135.57327 -140.623001) (xy 135.564642 -140.566176)
			(xy 135.564118 -140.537438) (xy 135.564604 -140.510187) (xy 135.57236 -140.456239) (xy 135.587715 -140.403944)
			(xy 135.610357 -140.354367) (xy 135.639823 -140.308517) (xy 135.675514 -140.267326) (xy 135.716705 -140.231635)
			(xy 135.762555 -140.202169) (xy 135.812132 -140.179527) (xy 135.864427 -140.164172) (xy 135.918375 -140.156416)
			(xy 135.972877 -140.156416) (xy 136.026825 -140.164172) (xy 136.07912 -140.179527) (xy 136.128697 -140.202169)
			(xy 136.174547 -140.231635) (xy 136.215738 -140.267326) (xy 136.251429 -140.308517) (xy 136.280895 -140.354367)
			(xy 136.303537 -140.403944) (xy 136.318892 -140.456239) (xy 136.326648 -140.510187) (xy 136.327134 -140.537438)
			(xy 136.326624 -140.566177) (xy 136.317997 -140.623005) (xy 136.300943 -140.677895) (xy 136.275849 -140.729607)
			(xy 136.243281 -140.776969) (xy 136.22401 -140.798296) (xy 136.217406 -140.805408) (xy 136.210294 -140.822934)
			(xy 136.210294 -140.912342) (xy 136.217406 -140.929868) (xy 136.22401 -140.93698) (xy 136.243317 -140.958275)
			(xy 136.275878 -141.005644) (xy 136.300965 -141.057361) (xy 136.318011 -141.112256) (xy 136.326629 -141.169087)
			(xy 136.326625 -141.226568) (xy 136.317999 -141.283398) (xy 136.300945 -141.338291) (xy 136.27585 -141.390004)
			(xy 136.243282 -141.437368) (xy 136.22401 -141.458696) (xy 136.217406 -141.465808) (xy 136.210294 -141.483334)
			(xy 136.210294 -141.572742) (xy 136.217406 -141.590268) (xy 136.22401 -141.59738) (xy 136.243317 -141.618675)
			(xy 136.275878 -141.666044) (xy 136.300965 -141.717761) (xy 136.318011 -141.772656) (xy 136.326629 -141.829487)
			(xy 136.326625 -141.886968) (xy 136.317999 -141.943798) (xy 136.300945 -141.998691) (xy 136.27585 -142.050404)
			(xy 136.243282 -142.097768) (xy 136.22401 -142.119096) (xy 136.217406 -142.126208) (xy 136.210294 -142.143734)
			(xy 136.210294 -142.233142) (xy 136.217406 -142.250668) (xy 136.22401 -142.25778) (xy 136.243317 -142.279075)
			(xy 136.275878 -142.326444) (xy 136.300965 -142.378161) (xy 136.318011 -142.433056) (xy 136.326629 -142.489887)
			(xy 136.326625 -142.547368) (xy 136.317999 -142.604198) (xy 136.300945 -142.659091) (xy 136.27585 -142.710804)
			(xy 136.243282 -142.758168) (xy 136.22401 -142.779496) (xy 136.217406 -142.786608) (xy 136.210294 -142.804134)
			(xy 136.210294 -142.893542) (xy 136.217406 -142.911068) (xy 136.22401 -142.91818) (xy 136.24329 -142.939499)
			(xy 136.275857 -142.986863) (xy 136.300948 -143.038576) (xy 136.317996 -143.093469) (xy 136.326615 -143.150298)
			(xy 136.327134 -143.179038) (xy 136.326727 -143.205015) (xy 136.319679 -143.256488) (xy 136.305704 -143.306526)
			(xy 136.285063 -143.354203) (xy 136.258137 -143.398634) (xy 136.225426 -143.438996) (xy 136.187535 -143.474541)
			(xy 136.166606 -143.489934) (xy 136.157135 -143.497587) (xy 136.145977 -143.519183) (xy 136.14527 -143.531336)
			(xy 136.14527 -143.61414) (xy 136.145957 -143.626303) (xy 136.157098 -143.647926) (xy 136.166606 -143.655542)
			(xy 136.187525 -143.670945) (xy 136.225399 -143.706499) (xy 136.258098 -143.746865) (xy 136.285015 -143.791294)
			(xy 136.305654 -143.838966) (xy 136.319632 -143.888998) (xy 136.326691 -143.940464) (xy 136.327134 -143.966438)
			(xy 136.326648 -143.993689) (xy 136.318892 -144.047637) (xy 136.303537 -144.099932) (xy 136.280895 -144.149509)
			(xy 136.251429 -144.195359) (xy 136.215738 -144.23655) (xy 136.174547 -144.272241) (xy 136.128697 -144.301707)
			(xy 136.07912 -144.324349) (xy 136.026825 -144.339704) (xy 135.972877 -144.34746) (xy 135.918375 -144.34746)
			(xy 135.864427 -144.339704) (xy 135.812132 -144.324349) (xy 135.762555 -144.301707) (xy 135.716705 -144.272241)
			(xy 135.675514 -144.23655) (xy 135.639823 -144.195359) (xy 135.610357 -144.149509) (xy 135.587715 -144.099932)
			(xy 135.57236 -144.047637) (xy 135.564604 -143.993689) (xy 135.564118 -143.966438) (xy 123.222512 -143.966438)
			(xy 123.222512 -145.110551) (xy 126.854954 -145.110551) (xy 126.854954 -145.056049) (xy 126.86271 -145.0021)
			(xy 126.878064 -144.949805) (xy 126.900704 -144.900227) (xy 126.930169 -144.854375) (xy 126.965859 -144.813183)
			(xy 127.007048 -144.77749) (xy 127.052897 -144.748021) (xy 127.102473 -144.725376) (xy 127.154767 -144.710017)
			(xy 127.208715 -144.702256) (xy 127.235966 -144.701768) (xy 127.262282 -144.702208) (xy 127.314417 -144.709432)
			(xy 127.365065 -144.723748) (xy 127.413266 -144.744885) (xy 127.458108 -144.772442) (xy 127.49874 -144.805897)
			(xy 127.51689 -144.824958) (xy 127.524419 -144.832351) (xy 127.543693 -144.840882) (xy 127.554228 -144.841468)
			(xy 127.628904 -144.841468) (xy 127.639457 -144.840964) (xy 127.658752 -144.832412) (xy 127.666242 -144.824958)
			(xy 127.684368 -144.805869) (xy 127.724989 -144.77239) (xy 127.769831 -144.744819) (xy 127.81804 -144.723682)
			(xy 127.8687 -144.70938) (xy 127.920846 -144.702186) (xy 127.947166 -144.701768) (xy 127.974419 -144.702277)
			(xy 128.02837 -144.71003) (xy 128.080669 -144.725382) (xy 128.13025 -144.748021) (xy 128.176104 -144.777486)
			(xy 128.217299 -144.813177) (xy 128.252994 -144.854368) (xy 128.282463 -144.90022) (xy 128.305106 -144.9498)
			(xy 128.306411 -144.954244) (xy 134.038848 -144.954244) (xy 134.039419 -144.926996) (xy 134.047168 -144.873054)
			(xy 134.062516 -144.820763) (xy 134.085149 -144.771189) (xy 134.114606 -144.725341) (xy 134.150289 -144.684151)
			(xy 134.19147 -144.648459) (xy 134.237312 -144.618991) (xy 134.286881 -144.596347) (xy 134.339167 -144.580987)
			(xy 134.393108 -144.573225) (xy 134.420356 -144.572736) (xy 134.44913 -144.573257) (xy 134.506025 -144.581907)
			(xy 134.560976 -144.599004) (xy 134.612736 -144.624159) (xy 134.660132 -144.656801) (xy 134.681468 -144.676114)
			(xy 134.689596 -144.683734) (xy 134.709154 -144.690592) (xy 134.805674 -144.68348) (xy 134.823962 -144.673574)
			(xy 134.83082 -144.664938) (xy 134.849055 -144.642762) (xy 134.890987 -144.603551) (xy 134.938321 -144.571063)
			(xy 134.989987 -144.546033) (xy 135.04482 -144.529025) (xy 135.101581 -144.520423) (xy 135.130286 -144.519904)
			(xy 135.157539 -144.520368) (xy 135.211491 -144.528124) (xy 135.263789 -144.543479) (xy 135.31337 -144.56612)
			(xy 135.359224 -144.595588) (xy 135.400417 -144.631282) (xy 135.436111 -144.672475) (xy 135.465579 -144.718328)
			(xy 135.488221 -144.767909) (xy 135.503576 -144.820207) (xy 135.511331 -144.874159) (xy 135.511794 -144.901412)
			(xy 135.511345 -144.928315) (xy 135.503772 -144.981586) (xy 135.48879 -145.033265) (xy 135.466698 -145.082327)
			(xy 135.437933 -145.127799) (xy 135.403067 -145.16878) (xy 135.362789 -145.204457) (xy 135.340598 -145.219674)
			(xy 135.329676 -145.226786) (xy 135.317738 -145.249646) (xy 135.31977 -145.361914) (xy 135.332724 -145.384266)
			(xy 135.3439 -145.391124) (xy 135.367501 -145.406046) (xy 135.410453 -145.441725) (xy 135.447747 -145.483283)
			(xy 135.478584 -145.529833) (xy 135.502308 -145.58038) (xy 135.51841 -145.633846) (xy 135.526548 -145.689087)
			(xy 135.527034 -145.717006) (xy 135.526579 -145.744) (xy 135.518972 -145.797448) (xy 135.50391 -145.849292)
			(xy 135.481695 -145.898496) (xy 135.452769 -145.94408) (xy 135.435594 -145.96491) (xy 135.428482 -145.973038)
			(xy 135.422386 -145.993612) (xy 135.434578 -146.089624) (xy 135.445754 -146.107912) (xy 135.454644 -146.114262)
			(xy 135.47585 -146.129648) (xy 135.514304 -146.16523) (xy 135.547524 -146.205741) (xy 135.574886 -146.250418)
			(xy 135.595874 -146.298421) (xy 135.610092 -146.348845) (xy 135.617273 -146.400741) (xy 135.617712 -146.426936)
			(xy 135.617226 -146.454187) (xy 135.60947 -146.508135) (xy 135.594115 -146.56043) (xy 135.571473 -146.610007)
			(xy 135.542007 -146.655857) (xy 135.506316 -146.697048) (xy 135.465125 -146.732739) (xy 135.419275 -146.762205)
			(xy 135.369698 -146.784847) (xy 135.317403 -146.800202) (xy 135.263455 -146.807958) (xy 135.208953 -146.807958)
			(xy 135.155005 -146.800202) (xy 135.10271 -146.784847) (xy 135.053133 -146.762205) (xy 135.007283 -146.732739)
			(xy 134.966092 -146.697048) (xy 134.930401 -146.655857) (xy 134.900935 -146.610007) (xy 134.878293 -146.56043)
			(xy 134.862938 -146.508135) (xy 134.855182 -146.454187) (xy 134.854696 -146.426936) (xy 134.855192 -146.399944)
			(xy 134.862792 -146.346498) (xy 134.877845 -146.294656) (xy 134.90005 -146.24545) (xy 134.928966 -146.199864)
			(xy 134.946136 -146.179032) (xy 134.953248 -146.170904) (xy 134.959344 -146.15033) (xy 134.947152 -146.054318)
			(xy 134.935976 -146.03603) (xy 134.927086 -146.02968) (xy 134.902785 -146.012068) (xy 134.859526 -145.970472)
			(xy 134.84098 -145.946876) (xy 134.834884 -145.938748) (xy 134.817866 -145.928588) (xy 134.726934 -145.91538)
			(xy 134.707884 -145.920206) (xy 134.699756 -145.926048) (xy 134.675012 -145.943552) (xy 134.62116 -145.971355)
			(xy 134.563588 -145.990291) (xy 134.503745 -145.999883) (xy 134.473442 -146.00047) (xy 134.446188 -146.000006)
			(xy 134.392236 -145.992253) (xy 134.339935 -145.976901) (xy 134.290353 -145.95426) (xy 134.244498 -145.924793)
			(xy 134.203304 -145.889099) (xy 134.167609 -145.847905) (xy 134.138142 -145.802051) (xy 134.115501 -145.752468)
			(xy 134.100148 -145.700168) (xy 134.092395 -145.646216) (xy 134.091934 -145.618962) (xy 134.092369 -145.592928)
			(xy 134.09946 -145.541345) (xy 134.113493 -145.491203) (xy 134.134206 -145.443432) (xy 134.161217 -145.398918)
			(xy 134.177278 -145.378424) (xy 134.183628 -145.370804) (xy 134.189216 -145.352262) (xy 134.182104 -145.2626)
			(xy 134.173468 -145.245328) (xy 134.166102 -145.238724) (xy 134.146463 -145.220535) (xy 134.111937 -145.179632)
			(xy 134.083465 -145.134305) (xy 134.061605 -145.085444) (xy 134.046787 -145.034009) (xy 134.039302 -144.981008)
			(xy 134.038848 -144.954244) (xy 128.306411 -144.954244) (xy 128.320463 -145.002097) (xy 128.328221 -145.056047)
			(xy 128.328221 -145.110553) (xy 128.320463 -145.164503) (xy 128.305106 -145.2168) (xy 128.282463 -145.26638)
			(xy 128.252994 -145.312232) (xy 128.217299 -145.353423) (xy 128.176104 -145.389114) (xy 128.13025 -145.418579)
			(xy 128.080669 -145.441218) (xy 128.02837 -145.45657) (xy 127.974419 -145.464323) (xy 127.947166 -145.464784)
			(xy 127.92085 -145.464338) (xy 127.868715 -145.457118) (xy 127.818067 -145.442803) (xy 127.769865 -145.421668)
			(xy 127.725023 -145.394111) (xy 127.684392 -145.360655) (xy 127.666242 -145.341594) (xy 127.658707 -145.334208)
			(xy 127.639437 -145.325675) (xy 127.628904 -145.325084) (xy 127.554228 -145.325084) (xy 127.543679 -145.32562)
			(xy 127.524384 -145.334151) (xy 127.51689 -145.341594) (xy 127.498759 -145.360677) (xy 127.458138 -145.394155)
			(xy 127.413297 -145.421725) (xy 127.365088 -145.442863) (xy 127.31443 -145.457167) (xy 127.262286 -145.464364)
			(xy 127.235966 -145.464784) (xy 127.208715 -145.464344) (xy 127.154767 -145.456583) (xy 127.102473 -145.441224)
			(xy 127.052897 -145.418579) (xy 127.007048 -145.38911) (xy 126.965859 -145.353417) (xy 126.930169 -145.312225)
			(xy 126.900704 -145.266373) (xy 126.878064 -145.216795) (xy 126.86271 -145.1645) (xy 126.854954 -145.110551)
			(xy 123.222512 -145.110551) (xy 123.222512 -146.91487) (xy 135.716008 -146.91487) (xy 135.720079 -146.859248)
			(xy 135.732205 -146.804811) (xy 135.752128 -146.75272) (xy 135.779424 -146.704085) (xy 135.81351 -146.659942)
			(xy 135.853659 -146.621233) (xy 135.899017 -146.588782) (xy 135.948617 -146.563281) (xy 136.001401 -146.545274)
			(xy 136.056244 -146.535144) (xy 136.111978 -146.533107) (xy 136.167415 -146.539207) (xy 136.221372 -146.553313)
			(xy 136.272701 -146.575125) (xy 136.320307 -146.604179) (xy 136.363175 -146.639854) (xy 136.400392 -146.681391)
			(xy 136.431165 -146.727904) (xy 136.454837 -146.778401) (xy 136.470905 -146.831808) (xy 136.479025 -146.886984)
			(xy 136.479534 -146.91487) (xy 136.479025 -146.942756) (xy 136.470905 -146.997932) (xy 136.454837 -147.051339)
			(xy 136.449631 -147.062444) (xy 137.094212 -147.062444) (xy 137.098283 -147.006822) (xy 137.110409 -146.952385)
			(xy 137.130332 -146.900294) (xy 137.157628 -146.851659) (xy 137.191714 -146.807516) (xy 137.231863 -146.768807)
			(xy 137.277221 -146.736356) (xy 137.326821 -146.710855) (xy 137.379605 -146.692848) (xy 137.434448 -146.682718)
			(xy 137.490182 -146.680681) (xy 137.545619 -146.686781) (xy 137.599576 -146.700887) (xy 137.650905 -146.722699)
			(xy 137.698511 -146.751753) (xy 137.741379 -146.787428) (xy 137.778596 -146.828965) (xy 137.809369 -146.875478)
			(xy 137.833041 -146.925975) (xy 137.849109 -146.979382) (xy 137.857229 -147.034558) (xy 137.857738 -147.062444)
			(xy 137.857229 -147.09033) (xy 137.849109 -147.145506) (xy 137.833041 -147.198913) (xy 137.809369 -147.24941)
			(xy 137.778596 -147.295923) (xy 137.741379 -147.33746) (xy 137.698511 -147.373135) (xy 137.650905 -147.402189)
			(xy 137.599576 -147.424001) (xy 137.545619 -147.438107) (xy 137.490182 -147.444207) (xy 137.434448 -147.44217)
			(xy 137.379605 -147.43204) (xy 137.326821 -147.414033) (xy 137.277221 -147.388532) (xy 137.231863 -147.356081)
			(xy 137.191714 -147.317372) (xy 137.157628 -147.273229) (xy 137.130332 -147.224594) (xy 137.110409 -147.172503)
			(xy 137.098283 -147.118066) (xy 137.094212 -147.062444) (xy 136.449631 -147.062444) (xy 136.431165 -147.101836)
			(xy 136.400392 -147.148349) (xy 136.363175 -147.189886) (xy 136.320307 -147.225561) (xy 136.272701 -147.254615)
			(xy 136.221372 -147.276427) (xy 136.167415 -147.290533) (xy 136.111978 -147.296633) (xy 136.056244 -147.294596)
			(xy 136.001401 -147.284466) (xy 135.948617 -147.266459) (xy 135.899017 -147.240958) (xy 135.853659 -147.208507)
			(xy 135.81351 -147.169798) (xy 135.779424 -147.125655) (xy 135.752128 -147.07702) (xy 135.732205 -147.024929)
			(xy 135.720079 -146.970492) (xy 135.716008 -146.91487) (xy 123.222512 -146.91487) (xy 123.222512 -147.657656)
			(xy 127.250343 -147.657656) (xy 127.250343 -147.603144) (xy 127.258101 -147.549188) (xy 127.27346 -147.496885)
			(xy 127.296107 -147.4473) (xy 127.32558 -147.401443) (xy 127.361279 -147.360248) (xy 127.402478 -147.324553)
			(xy 127.448339 -147.295085) (xy 127.497926 -147.272445) (xy 127.550231 -147.257092) (xy 127.604188 -147.24934)
			(xy 127.631444 -147.24888) (xy 127.65776 -147.24933) (xy 127.709894 -147.256552) (xy 127.760542 -147.270866)
			(xy 127.808744 -147.292001) (xy 127.853586 -147.319556) (xy 127.894218 -147.35301) (xy 127.912368 -147.37207)
			(xy 127.919904 -147.379455) (xy 127.939173 -147.38799) (xy 127.949706 -147.38858) (xy 128.024382 -147.38858)
			(xy 128.034933 -147.388061) (xy 128.054229 -147.379519) (xy 128.06172 -147.37207) (xy 128.079859 -147.352994)
			(xy 128.120477 -147.319513) (xy 128.165316 -147.291941) (xy 128.213523 -147.270801) (xy 128.26418 -147.256496)
			(xy 128.316324 -147.249299) (xy 128.342644 -147.24888) (xy 128.36896 -147.24933) (xy 128.421094 -147.256552)
			(xy 128.471742 -147.270866) (xy 128.519944 -147.292001) (xy 128.564786 -147.319556) (xy 128.605418 -147.35301)
			(xy 128.623568 -147.37207) (xy 128.631104 -147.379455) (xy 128.650373 -147.38799) (xy 128.660906 -147.38858)
			(xy 128.735582 -147.38858) (xy 128.746133 -147.388061) (xy 128.765429 -147.379519) (xy 128.77292 -147.37207)
			(xy 128.791059 -147.352994) (xy 128.831677 -147.319513) (xy 128.876516 -147.291941) (xy 128.924723 -147.270801)
			(xy 128.97538 -147.256496) (xy 129.027524 -147.249299) (xy 129.053844 -147.24888) (xy 129.081092 -147.249393)
			(xy 129.135034 -147.257155) (xy 129.187321 -147.272513) (xy 129.236891 -147.295156) (xy 129.282735 -147.324622)
			(xy 129.323918 -147.360313) (xy 129.359604 -147.401501) (xy 129.389065 -147.447347) (xy 129.411702 -147.49692)
			(xy 129.427055 -147.54921) (xy 129.43481 -147.603152) (xy 129.43481 -147.657648) (xy 129.427055 -147.71159)
			(xy 129.411702 -147.76388) (xy 129.389065 -147.813453) (xy 129.359604 -147.859299) (xy 129.323918 -147.900487)
			(xy 129.282735 -147.936178) (xy 129.236891 -147.965644) (xy 129.187321 -147.988287) (xy 129.135034 -148.003645)
			(xy 129.081092 -148.011407) (xy 129.053844 -148.011896) (xy 129.027527 -148.011461) (xy 128.975392 -148.004238)
			(xy 128.924744 -147.989921) (xy 128.876542 -147.968783) (xy 128.8317 -147.941225) (xy 128.791069 -147.907768)
			(xy 128.77292 -147.888706) (xy 128.765392 -147.881312) (xy 128.746117 -147.872783) (xy 128.735582 -147.872196)
			(xy 128.660906 -147.872196) (xy 128.650355 -147.872716) (xy 128.63106 -147.881258) (xy 128.623568 -147.888706)
			(xy 128.60545 -147.907802) (xy 128.564826 -147.941278) (xy 128.519982 -147.968846) (xy 128.471771 -147.989982)
			(xy 128.421111 -148.004283) (xy 128.368965 -148.011477) (xy 128.342644 -148.011896) (xy 128.316327 -148.011461)
			(xy 128.264192 -148.004238) (xy 128.213544 -147.989921) (xy 128.165342 -147.968783) (xy 128.1205 -147.941225)
			(xy 128.079869 -147.907768) (xy 128.06172 -147.888706) (xy 128.054192 -147.881312) (xy 128.034917 -147.872783)
			(xy 128.024382 -147.872196) (xy 127.949706 -147.872196) (xy 127.939155 -147.872716) (xy 127.91986 -147.881258)
			(xy 127.912368 -147.888706) (xy 127.89425 -147.907802) (xy 127.853626 -147.941278) (xy 127.808782 -147.968846)
			(xy 127.760571 -147.989982) (xy 127.709911 -148.004283) (xy 127.657765 -148.011477) (xy 127.631444 -148.011896)
			(xy 127.604188 -148.01146) (xy 127.550231 -148.003708) (xy 127.497926 -147.988355) (xy 127.448339 -147.965715)
			(xy 127.402478 -147.936247) (xy 127.361279 -147.900552) (xy 127.32558 -147.859357) (xy 127.296107 -147.8135)
			(xy 127.27346 -147.763915) (xy 127.258101 -147.711612) (xy 127.250343 -147.657656) (xy 123.222512 -147.657656)
			(xy 123.222512 -148.017738) (xy 132.077458 -148.017738) (xy 132.081529 -147.962116) (xy 132.093655 -147.907679)
			(xy 132.113578 -147.855588) (xy 132.140874 -147.806953) (xy 132.17496 -147.76281) (xy 132.215109 -147.724101)
			(xy 132.260467 -147.69165) (xy 132.310067 -147.666149) (xy 132.362851 -147.648142) (xy 132.417694 -147.638012)
			(xy 132.473428 -147.635975) (xy 132.528865 -147.642075) (xy 132.582822 -147.656181) (xy 132.634151 -147.677993)
			(xy 132.681757 -147.707047) (xy 132.724625 -147.742722) (xy 132.761842 -147.784259) (xy 132.792615 -147.830772)
			(xy 132.816287 -147.881269) (xy 132.832355 -147.934676) (xy 132.840475 -147.989852) (xy 132.840984 -148.017738)
			(xy 132.840475 -148.045624) (xy 132.832355 -148.1008) (xy 132.816287 -148.154207) (xy 132.792615 -148.204704)
			(xy 132.761842 -148.251217) (xy 132.724625 -148.292754) (xy 132.681757 -148.328429) (xy 132.634151 -148.357483)
			(xy 132.582822 -148.379295) (xy 132.528865 -148.393401) (xy 132.473428 -148.399501) (xy 132.417694 -148.397464)
			(xy 132.362851 -148.387334) (xy 132.310067 -148.369327) (xy 132.260467 -148.343826) (xy 132.215109 -148.311375)
			(xy 132.17496 -148.272666) (xy 132.140874 -148.228523) (xy 132.113578 -148.179888) (xy 132.093655 -148.127797)
			(xy 132.081529 -148.07336) (xy 132.077458 -148.017738) (xy 123.222512 -148.017738) (xy 123.222512 -150.195854)
			(xy 127.250365 -150.195854) (xy 127.250365 -150.141346) (xy 127.258123 -150.087392) (xy 127.273481 -150.035093)
			(xy 127.296126 -149.985511) (xy 127.325598 -149.939657) (xy 127.361295 -149.898464) (xy 127.402492 -149.862771)
			(xy 127.448349 -149.833305) (xy 127.497934 -149.810666) (xy 127.550236 -149.795314) (xy 127.60419 -149.787562)
			(xy 127.631444 -149.787102) (xy 127.65776 -149.787545) (xy 127.709895 -149.794767) (xy 127.760543 -149.809082)
			(xy 127.808745 -149.830219) (xy 127.853587 -149.857776) (xy 127.894218 -149.891231) (xy 127.912368 -149.910292)
			(xy 127.919901 -149.91768) (xy 127.939172 -149.926212) (xy 127.949706 -149.926802) (xy 128.024382 -149.926802)
			(xy 128.034932 -149.926276) (xy 128.054227 -149.917738) (xy 128.06172 -149.910292) (xy 128.079843 -149.891201)
			(xy 128.120466 -149.857725) (xy 128.165309 -149.830156) (xy 128.213519 -149.809019) (xy 128.264178 -149.794717)
			(xy 128.316324 -149.787521) (xy 128.342644 -149.787102) (xy 128.36896 -149.787545) (xy 128.421095 -149.794767)
			(xy 128.471743 -149.809082) (xy 128.519945 -149.830219) (xy 128.564787 -149.857776) (xy 128.605418 -149.891231)
			(xy 128.623568 -149.910292) (xy 128.631101 -149.91768) (xy 128.650372 -149.926212) (xy 128.660906 -149.926802)
			(xy 128.735582 -149.926802) (xy 128.746132 -149.926276) (xy 128.765427 -149.917738) (xy 128.77292 -149.910292)
			(xy 128.791043 -149.891201) (xy 128.831666 -149.857725) (xy 128.876509 -149.830156) (xy 128.924719 -149.809019)
			(xy 128.975378 -149.794717) (xy 129.027524 -149.787521) (xy 129.053844 -149.787102) (xy 129.081094 -149.787571)
			(xy 129.135038 -149.795333) (xy 129.187329 -149.810692) (xy 129.236902 -149.833336) (xy 129.282748 -149.862804)
			(xy 129.323934 -149.898497) (xy 129.359622 -149.939687) (xy 129.389085 -149.985537) (xy 129.411723 -150.035112)
			(xy 129.420045 -150.063454) (xy 131.938012 -150.063454) (xy 131.942083 -150.007832) (xy 131.954209 -149.953395)
			(xy 131.974132 -149.901304) (xy 132.001428 -149.852669) (xy 132.035514 -149.808526) (xy 132.075663 -149.769817)
			(xy 132.121021 -149.737366) (xy 132.170621 -149.711865) (xy 132.223405 -149.693858) (xy 132.278248 -149.683728)
			(xy 132.333982 -149.681691) (xy 132.389419 -149.687791) (xy 132.443376 -149.701897) (xy 132.494705 -149.723709)
			(xy 132.542311 -149.752763) (xy 132.585179 -149.788438) (xy 132.622396 -149.829975) (xy 132.653169 -149.876488)
			(xy 132.676841 -149.926985) (xy 132.692909 -149.980392) (xy 132.701029 -150.035568) (xy 132.701538 -150.063454)
			(xy 132.701029 -150.09134) (xy 132.692909 -150.146516) (xy 132.676841 -150.199923) (xy 132.653169 -150.25042)
			(xy 132.622396 -150.296933) (xy 132.585179 -150.33847) (xy 132.542311 -150.374145) (xy 132.494705 -150.403199)
			(xy 132.443376 -150.425011) (xy 132.389419 -150.439117) (xy 132.333982 -150.445217) (xy 132.278248 -150.44318)
			(xy 132.223405 -150.43305) (xy 132.170621 -150.415043) (xy 132.121021 -150.389542) (xy 132.075663 -150.357091)
			(xy 132.035514 -150.318382) (xy 132.001428 -150.274239) (xy 131.974132 -150.225604) (xy 131.954209 -150.173513)
			(xy 131.942083 -150.119076) (xy 131.938012 -150.063454) (xy 129.420045 -150.063454) (xy 129.427077 -150.087405)
			(xy 129.434832 -150.14135) (xy 129.434832 -150.19585) (xy 129.427077 -150.249795) (xy 129.411723 -150.302088)
			(xy 129.389085 -150.351663) (xy 129.359622 -150.397513) (xy 129.323934 -150.438703) (xy 129.282748 -150.474396)
			(xy 129.236902 -150.503864) (xy 129.187329 -150.526508) (xy 129.135038 -150.541867) (xy 129.081094 -150.549629)
			(xy 129.053844 -150.550118) (xy 129.027528 -150.549676) (xy 128.975393 -150.542453) (xy 128.924745 -150.528137)
			(xy 128.876543 -150.507001) (xy 128.831702 -150.479444) (xy 128.79107 -150.445989) (xy 128.77292 -150.426928)
			(xy 128.765389 -150.419537) (xy 128.746116 -150.411006) (xy 128.735582 -150.410418) (xy 128.660906 -150.410418)
			(xy 128.650354 -150.410932) (xy 128.631059 -150.419477) (xy 128.623568 -150.426928) (xy 128.605435 -150.446009)
			(xy 128.564816 -150.47949) (xy 128.519975 -150.507062) (xy 128.471767 -150.528201) (xy 128.421109 -150.542504)
			(xy 128.368964 -150.549699) (xy 128.342644 -150.550118) (xy 128.316328 -150.549676) (xy 128.264193 -150.542453)
			(xy 128.213545 -150.528137) (xy 128.165343 -150.507001) (xy 128.120502 -150.479444) (xy 128.07987 -150.445989)
			(xy 128.06172 -150.426928) (xy 128.054189 -150.419537) (xy 128.034916 -150.411006) (xy 128.024382 -150.410418)
			(xy 127.949706 -150.410418) (xy 127.939154 -150.410932) (xy 127.919859 -150.419477) (xy 127.912368 -150.426928)
			(xy 127.894235 -150.446009) (xy 127.853616 -150.47949) (xy 127.808775 -150.507062) (xy 127.760567 -150.528201)
			(xy 127.709909 -150.542504) (xy 127.657764 -150.549699) (xy 127.631444 -150.550118) (xy 127.60419 -150.549638)
			(xy 127.550236 -150.541886) (xy 127.497934 -150.526534) (xy 127.448349 -150.503895) (xy 127.402492 -150.474429)
			(xy 127.361295 -150.438736) (xy 127.325598 -150.397543) (xy 127.296126 -150.351689) (xy 127.273481 -150.302107)
			(xy 127.258123 -150.249808) (xy 127.250365 -150.195854) (xy 123.222512 -150.195854) (xy 123.222512 -151.67102)
			(xy 131.893562 -151.67102) (xy 131.897633 -151.615398) (xy 131.909759 -151.560961) (xy 131.929682 -151.50887)
			(xy 131.956978 -151.460235) (xy 131.991064 -151.416092) (xy 132.031213 -151.377383) (xy 132.076571 -151.344932)
			(xy 132.126171 -151.319431) (xy 132.178955 -151.301424) (xy 132.233798 -151.291294) (xy 132.289532 -151.289257)
			(xy 132.344969 -151.295357) (xy 132.398926 -151.309463) (xy 132.450255 -151.331275) (xy 132.497861 -151.360329)
			(xy 132.540729 -151.396004) (xy 132.577946 -151.437541) (xy 132.608719 -151.484054) (xy 132.632391 -151.534551)
			(xy 132.648459 -151.587958) (xy 132.656579 -151.643134) (xy 132.657088 -151.67102) (xy 132.656615 -151.696928)
			(xy 132.909562 -151.696928) (xy 132.913633 -151.641306) (xy 132.925759 -151.586869) (xy 132.945682 -151.534778)
			(xy 132.972978 -151.486143) (xy 133.007064 -151.442) (xy 133.047213 -151.403291) (xy 133.092571 -151.37084)
			(xy 133.142171 -151.345339) (xy 133.194955 -151.327332) (xy 133.249798 -151.317202) (xy 133.305532 -151.315165)
			(xy 133.360969 -151.321265) (xy 133.414926 -151.335371) (xy 133.466255 -151.357183) (xy 133.513861 -151.386237)
			(xy 133.538337 -151.406606) (xy 134.136636 -151.406606) (xy 134.140707 -151.350984) (xy 134.152833 -151.296547)
			(xy 134.172756 -151.244456) (xy 134.200052 -151.195821) (xy 134.234138 -151.151678) (xy 134.274287 -151.112969)
			(xy 134.319645 -151.080518) (xy 134.369245 -151.055017) (xy 134.422029 -151.03701) (xy 134.476872 -151.02688)
			(xy 134.532606 -151.024843) (xy 134.588043 -151.030943) (xy 134.642 -151.045049) (xy 134.693329 -151.066861)
			(xy 134.740935 -151.095915) (xy 134.783803 -151.13159) (xy 134.82102 -151.173127) (xy 134.851793 -151.21964)
			(xy 134.875465 -151.270137) (xy 134.891533 -151.323544) (xy 134.899653 -151.37872) (xy 134.900162 -151.406606)
			(xy 134.899653 -151.434492) (xy 134.891533 -151.489668) (xy 134.875465 -151.543075) (xy 134.856923 -151.582628)
			(xy 135.462262 -151.582628) (xy 135.466333 -151.527006) (xy 135.478459 -151.472569) (xy 135.498382 -151.420478)
			(xy 135.525678 -151.371843) (xy 135.559764 -151.3277) (xy 135.599913 -151.288991) (xy 135.645271 -151.25654)
			(xy 135.694871 -151.231039) (xy 135.747655 -151.213032) (xy 135.802498 -151.202902) (xy 135.858232 -151.200865)
			(xy 135.913669 -151.206965) (xy 135.967626 -151.221071) (xy 136.018955 -151.242883) (xy 136.066561 -151.271937)
			(xy 136.109429 -151.307612) (xy 136.146646 -151.349149) (xy 136.177419 -151.395662) (xy 136.201091 -151.446159)
			(xy 136.217159 -151.499566) (xy 136.225279 -151.554742) (xy 136.225542 -151.569166) (xy 136.973562 -151.569166)
			(xy 136.977633 -151.513544) (xy 136.989759 -151.459107) (xy 137.009682 -151.407016) (xy 137.036978 -151.358381)
			(xy 137.071064 -151.314238) (xy 137.111213 -151.275529) (xy 137.156571 -151.243078) (xy 137.206171 -151.217577)
			(xy 137.258955 -151.19957) (xy 137.313798 -151.18944) (xy 137.369532 -151.187403) (xy 137.424969 -151.193503)
			(xy 137.478926 -151.207609) (xy 137.530255 -151.229421) (xy 137.577861 -151.258475) (xy 137.620729 -151.29415)
			(xy 137.657946 -151.335687) (xy 137.688719 -151.3822) (xy 137.712391 -151.432697) (xy 137.728459 -151.486104)
			(xy 137.736579 -151.54128) (xy 137.737088 -151.569166) (xy 137.736579 -151.597052) (xy 137.728459 -151.652228)
			(xy 137.712391 -151.705635) (xy 137.688719 -151.756132) (xy 137.657946 -151.802645) (xy 137.620729 -151.844182)
			(xy 137.577861 -151.879857) (xy 137.530255 -151.908911) (xy 137.478926 -151.930723) (xy 137.424969 -151.944829)
			(xy 137.369532 -151.950929) (xy 137.313798 -151.948892) (xy 137.258955 -151.938762) (xy 137.206171 -151.920755)
			(xy 137.156571 -151.895254) (xy 137.111213 -151.862803) (xy 137.071064 -151.824094) (xy 137.036978 -151.779951)
			(xy 137.009682 -151.731316) (xy 136.989759 -151.679225) (xy 136.977633 -151.624788) (xy 136.973562 -151.569166)
			(xy 136.225542 -151.569166) (xy 136.225788 -151.582628) (xy 136.225279 -151.610514) (xy 136.217159 -151.66569)
			(xy 136.201091 -151.719097) (xy 136.177419 -151.769594) (xy 136.146646 -151.816107) (xy 136.109429 -151.857644)
			(xy 136.066561 -151.893319) (xy 136.018955 -151.922373) (xy 135.967626 -151.944185) (xy 135.913669 -151.958291)
			(xy 135.858232 -151.964391) (xy 135.802498 -151.962354) (xy 135.747655 -151.952224) (xy 135.694871 -151.934217)
			(xy 135.645271 -151.908716) (xy 135.599913 -151.876265) (xy 135.559764 -151.837556) (xy 135.525678 -151.793413)
			(xy 135.498382 -151.744778) (xy 135.478459 -151.692687) (xy 135.466333 -151.63825) (xy 135.462262 -151.582628)
			(xy 134.856923 -151.582628) (xy 134.851793 -151.593572) (xy 134.82102 -151.640085) (xy 134.783803 -151.681622)
			(xy 134.740935 -151.717297) (xy 134.693329 -151.746351) (xy 134.642 -151.768163) (xy 134.588043 -151.782269)
			(xy 134.532606 -151.788369) (xy 134.476872 -151.786332) (xy 134.422029 -151.776202) (xy 134.369245 -151.758195)
			(xy 134.319645 -151.732694) (xy 134.274287 -151.700243) (xy 134.234138 -151.661534) (xy 134.200052 -151.617391)
			(xy 134.172756 -151.568756) (xy 134.152833 -151.516665) (xy 134.140707 -151.462228) (xy 134.136636 -151.406606)
			(xy 133.538337 -151.406606) (xy 133.556729 -151.421912) (xy 133.593946 -151.463449) (xy 133.624719 -151.509962)
			(xy 133.648391 -151.560459) (xy 133.664459 -151.613866) (xy 133.672579 -151.669042) (xy 133.673088 -151.696928)
			(xy 133.672579 -151.724814) (xy 133.664459 -151.77999) (xy 133.648391 -151.833397) (xy 133.624719 -151.883894)
			(xy 133.593946 -151.930407) (xy 133.556729 -151.971944) (xy 133.513861 -152.007619) (xy 133.466255 -152.036673)
			(xy 133.414926 -152.058485) (xy 133.360969 -152.072591) (xy 133.305532 -152.078691) (xy 133.249798 -152.076654)
			(xy 133.194955 -152.066524) (xy 133.142171 -152.048517) (xy 133.092571 -152.023016) (xy 133.047213 -151.990565)
			(xy 133.007064 -151.951856) (xy 132.972978 -151.907713) (xy 132.945682 -151.859078) (xy 132.925759 -151.806987)
			(xy 132.913633 -151.75255) (xy 132.909562 -151.696928) (xy 132.656615 -151.696928) (xy 132.656579 -151.698906)
			(xy 132.648459 -151.754082) (xy 132.632391 -151.807489) (xy 132.608719 -151.857986) (xy 132.577946 -151.904499)
			(xy 132.540729 -151.946036) (xy 132.497861 -151.981711) (xy 132.450255 -152.010765) (xy 132.398926 -152.032577)
			(xy 132.344969 -152.046683) (xy 132.289532 -152.052783) (xy 132.233798 -152.050746) (xy 132.178955 -152.040616)
			(xy 132.126171 -152.022609) (xy 132.076571 -151.997108) (xy 132.031213 -151.964657) (xy 131.991064 -151.925948)
			(xy 131.956978 -151.881805) (xy 131.929682 -151.83317) (xy 131.909759 -151.781079) (xy 131.897633 -151.726642)
			(xy 131.893562 -151.67102) (xy 123.222512 -151.67102) (xy 123.222512 -153.782522) (xy 130.877562 -153.782522)
			(xy 130.881633 -153.7269) (xy 130.893759 -153.672463) (xy 130.913682 -153.620372) (xy 130.940978 -153.571737)
			(xy 130.975064 -153.527594) (xy 131.015213 -153.488885) (xy 131.060571 -153.456434) (xy 131.110171 -153.430933)
			(xy 131.162955 -153.412926) (xy 131.217798 -153.402796) (xy 131.273532 -153.400759) (xy 131.328969 -153.406859)
			(xy 131.382926 -153.420965) (xy 131.434255 -153.442777) (xy 131.481861 -153.471831) (xy 131.524729 -153.507506)
			(xy 131.561946 -153.549043) (xy 131.592719 -153.595556) (xy 131.616391 -153.646053) (xy 131.632459 -153.69946)
			(xy 131.640579 -153.754636) (xy 131.641088 -153.782522) (xy 131.893562 -153.782522) (xy 131.897633 -153.7269)
			(xy 131.909759 -153.672463) (xy 131.929682 -153.620372) (xy 131.956978 -153.571737) (xy 131.991064 -153.527594)
			(xy 132.031213 -153.488885) (xy 132.076571 -153.456434) (xy 132.126171 -153.430933) (xy 132.178955 -153.412926)
			(xy 132.233798 -153.402796) (xy 132.289532 -153.400759) (xy 132.344969 -153.406859) (xy 132.398926 -153.420965)
			(xy 132.450255 -153.442777) (xy 132.497861 -153.471831) (xy 132.540729 -153.507506) (xy 132.577946 -153.549043)
			(xy 132.608719 -153.595556) (xy 132.632391 -153.646053) (xy 132.648459 -153.69946) (xy 132.656579 -153.754636)
			(xy 132.657088 -153.782522) (xy 132.656579 -153.810408) (xy 132.653431 -153.831798) (xy 132.909562 -153.831798)
			(xy 132.913633 -153.776176) (xy 132.925759 -153.721739) (xy 132.945682 -153.669648) (xy 132.972978 -153.621013)
			(xy 133.007064 -153.57687) (xy 133.047213 -153.538161) (xy 133.092571 -153.50571) (xy 133.142171 -153.480209)
			(xy 133.194955 -153.462202) (xy 133.249798 -153.452072) (xy 133.305532 -153.450035) (xy 133.360969 -153.456135)
			(xy 133.414926 -153.470241) (xy 133.466255 -153.492053) (xy 133.513861 -153.521107) (xy 133.556729 -153.556782)
			(xy 133.593946 -153.598319) (xy 133.624719 -153.644832) (xy 133.648391 -153.695329) (xy 133.664459 -153.748736)
			(xy 133.669431 -153.782522) (xy 135.957562 -153.782522) (xy 135.961633 -153.7269) (xy 135.973759 -153.672463)
			(xy 135.993682 -153.620372) (xy 136.020978 -153.571737) (xy 136.055064 -153.527594) (xy 136.095213 -153.488885)
			(xy 136.140571 -153.456434) (xy 136.190171 -153.430933) (xy 136.242955 -153.412926) (xy 136.297798 -153.402796)
			(xy 136.353532 -153.400759) (xy 136.408969 -153.406859) (xy 136.462926 -153.420965) (xy 136.514255 -153.442777)
			(xy 136.561861 -153.471831) (xy 136.604729 -153.507506) (xy 136.641946 -153.549043) (xy 136.672719 -153.595556)
			(xy 136.696391 -153.646053) (xy 136.712459 -153.69946) (xy 136.720579 -153.754636) (xy 136.721088 -153.782522)
			(xy 136.720579 -153.810408) (xy 136.712459 -153.865584) (xy 136.696391 -153.918991) (xy 136.672719 -153.969488)
			(xy 136.641946 -154.016001) (xy 136.604729 -154.057538) (xy 136.561861 -154.093213) (xy 136.514255 -154.122267)
			(xy 136.462926 -154.144079) (xy 136.408969 -154.158185) (xy 136.353532 -154.164285) (xy 136.297798 -154.162248)
			(xy 136.242955 -154.152118) (xy 136.190171 -154.134111) (xy 136.140571 -154.10861) (xy 136.095213 -154.076159)
			(xy 136.055064 -154.03745) (xy 136.020978 -153.993307) (xy 135.993682 -153.944672) (xy 135.973759 -153.892581)
			(xy 135.961633 -153.838144) (xy 135.957562 -153.782522) (xy 133.669431 -153.782522) (xy 133.672579 -153.803912)
			(xy 133.673088 -153.831798) (xy 133.672579 -153.859684) (xy 133.664459 -153.91486) (xy 133.648391 -153.968267)
			(xy 133.624719 -154.018764) (xy 133.593946 -154.065277) (xy 133.556729 -154.106814) (xy 133.513861 -154.142489)
			(xy 133.466255 -154.171543) (xy 133.414926 -154.193355) (xy 133.360969 -154.207461) (xy 133.305532 -154.213561)
			(xy 133.249798 -154.211524) (xy 133.194955 -154.201394) (xy 133.142171 -154.183387) (xy 133.092571 -154.157886)
			(xy 133.047213 -154.125435) (xy 133.007064 -154.086726) (xy 132.972978 -154.042583) (xy 132.945682 -153.993948)
			(xy 132.925759 -153.941857) (xy 132.913633 -153.88742) (xy 132.909562 -153.831798) (xy 132.653431 -153.831798)
			(xy 132.648459 -153.865584) (xy 132.632391 -153.918991) (xy 132.608719 -153.969488) (xy 132.577946 -154.016001)
			(xy 132.540729 -154.057538) (xy 132.497861 -154.093213) (xy 132.450255 -154.122267) (xy 132.398926 -154.144079)
			(xy 132.344969 -154.158185) (xy 132.289532 -154.164285) (xy 132.233798 -154.162248) (xy 132.178955 -154.152118)
			(xy 132.126171 -154.134111) (xy 132.076571 -154.10861) (xy 132.031213 -154.076159) (xy 131.991064 -154.03745)
			(xy 131.956978 -153.993307) (xy 131.929682 -153.944672) (xy 131.909759 -153.892581) (xy 131.897633 -153.838144)
			(xy 131.893562 -153.782522) (xy 131.641088 -153.782522) (xy 131.640579 -153.810408) (xy 131.632459 -153.865584)
			(xy 131.616391 -153.918991) (xy 131.592719 -153.969488) (xy 131.561946 -154.016001) (xy 131.524729 -154.057538)
			(xy 131.481861 -154.093213) (xy 131.434255 -154.122267) (xy 131.382926 -154.144079) (xy 131.328969 -154.158185)
			(xy 131.273532 -154.164285) (xy 131.217798 -154.162248) (xy 131.162955 -154.152118) (xy 131.110171 -154.134111)
			(xy 131.060571 -154.10861) (xy 131.015213 -154.076159) (xy 130.975064 -154.03745) (xy 130.940978 -153.993307)
			(xy 130.913682 -153.944672) (xy 130.893759 -153.892581) (xy 130.881633 -153.838144) (xy 130.877562 -153.782522)
			(xy 123.222512 -153.782522) (xy 123.222512 -155.212034) (xy 123.369068 -155.212034) (xy 123.373139 -155.156412)
			(xy 123.385265 -155.101975) (xy 123.405188 -155.049884) (xy 123.432484 -155.001249) (xy 123.46657 -154.957106)
			(xy 123.506719 -154.918397) (xy 123.552077 -154.885946) (xy 123.601677 -154.860445) (xy 123.654461 -154.842438)
			(xy 123.709304 -154.832308) (xy 123.765038 -154.830271) (xy 123.820475 -154.836371) (xy 123.874432 -154.850477)
			(xy 123.925761 -154.872289) (xy 123.973367 -154.901343) (xy 124.016235 -154.937018) (xy 124.053452 -154.978555)
			(xy 124.084225 -155.025068) (xy 124.107897 -155.075565) (xy 124.108988 -155.079192) (xy 125.969774 -155.079192)
			(xy 125.973845 -155.02357) (xy 125.985971 -154.969133) (xy 126.005894 -154.917042) (xy 126.03319 -154.868407)
			(xy 126.067276 -154.824264) (xy 126.107425 -154.785555) (xy 126.152783 -154.753104) (xy 126.202383 -154.727603)
			(xy 126.255167 -154.709596) (xy 126.31001 -154.699466) (xy 126.365744 -154.697429) (xy 126.421181 -154.703529)
			(xy 126.475138 -154.717635) (xy 126.526467 -154.739447) (xy 126.574073 -154.768501) (xy 126.616941 -154.804176)
			(xy 126.654158 -154.845713) (xy 126.684931 -154.892226) (xy 126.708603 -154.942723) (xy 126.724671 -154.99613)
			(xy 126.732791 -155.051306) (xy 126.7333 -155.079192) (xy 126.733235 -155.082748) (xy 127.293624 -155.082748)
			(xy 127.294055 -155.056431) (xy 127.301279 -155.004296) (xy 127.315595 -154.953647) (xy 127.336734 -154.905445)
			(xy 127.364294 -154.860604) (xy 127.397752 -154.819973) (xy 127.416814 -154.801824) (xy 127.424209 -154.794297)
			(xy 127.432737 -154.775021) (xy 127.433324 -154.764486) (xy 127.433324 -154.68981) (xy 127.432796 -154.67926)
			(xy 127.424259 -154.659965) (xy 127.416814 -154.652472) (xy 127.397724 -154.634348) (xy 127.364246 -154.593726)
			(xy 127.336677 -154.548883) (xy 127.31554 -154.500673) (xy 127.301238 -154.450014) (xy 127.294043 -154.397868)
			(xy 127.293624 -154.371548) (xy 127.2941 -154.344295) (xy 127.301851 -154.290343) (xy 127.317203 -154.238043)
			(xy 127.339842 -154.188461) (xy 127.369308 -154.142606) (xy 127.405001 -154.101412) (xy 127.446193 -154.065718)
			(xy 127.492047 -154.03625) (xy 127.541628 -154.013608) (xy 127.593927 -153.998255) (xy 127.647879 -153.990501)
			(xy 127.675132 -153.99004) (xy 127.701449 -153.990479) (xy 127.753584 -153.9977) (xy 127.804233 -154.012015)
			(xy 127.852435 -154.033152) (xy 127.897276 -154.060711) (xy 127.937907 -154.094168) (xy 127.956056 -154.11323)
			(xy 127.963601 -154.120604) (xy 127.982863 -154.129147) (xy 127.993394 -154.12974) (xy 128.06807 -154.12974)
			(xy 128.078618 -154.129197) (xy 128.097913 -154.12067) (xy 128.105408 -154.11323) (xy 128.123545 -154.094152)
			(xy 128.164164 -154.060673) (xy 128.209004 -154.033102) (xy 128.257211 -154.011963) (xy 128.307869 -153.997658)
			(xy 128.360012 -153.99046) (xy 128.386332 -153.99004) (xy 128.412649 -153.990479) (xy 128.464784 -153.9977)
			(xy 128.515433 -154.012015) (xy 128.563635 -154.033152) (xy 128.608476 -154.060711) (xy 128.649107 -154.094168)
			(xy 128.667256 -154.11323) (xy 128.674801 -154.120604) (xy 128.694063 -154.129147) (xy 128.704594 -154.12974)
			(xy 128.77927 -154.12974) (xy 128.789818 -154.129197) (xy 128.809113 -154.12067) (xy 128.816608 -154.11323)
			(xy 128.834745 -154.094152) (xy 128.875364 -154.060673) (xy 128.920204 -154.033102) (xy 128.968411 -154.011963)
			(xy 129.019069 -153.997658) (xy 129.071212 -153.99046) (xy 129.097532 -153.99004) (xy 129.123849 -153.990479)
			(xy 129.175984 -153.9977) (xy 129.226633 -154.012015) (xy 129.274835 -154.033152) (xy 129.319676 -154.060711)
			(xy 129.360307 -154.094168) (xy 129.378456 -154.11323) (xy 129.386001 -154.120604) (xy 129.405263 -154.129147)
			(xy 129.415794 -154.12974) (xy 129.49047 -154.12974) (xy 129.501018 -154.129197) (xy 129.520313 -154.12067)
			(xy 129.527808 -154.11323) (xy 129.545945 -154.094152) (xy 129.586564 -154.060673) (xy 129.631404 -154.033102)
			(xy 129.679611 -154.011963) (xy 129.730269 -153.997658) (xy 129.782412 -153.99046) (xy 129.808732 -153.99004)
			(xy 129.835988 -153.990425) (xy 129.889944 -153.998188) (xy 129.942246 -154.01355) (xy 129.99183 -154.0362)
			(xy 130.037685 -154.065676) (xy 130.078879 -154.101378) (xy 130.114572 -154.142579) (xy 130.144038 -154.18844)
			(xy 130.166678 -154.238029) (xy 130.182029 -154.290334) (xy 130.18978 -154.344292) (xy 130.19024 -154.371548)
			(xy 130.189786 -154.397864) (xy 130.182564 -154.449997) (xy 130.168251 -154.500645) (xy 130.147116 -154.548847)
			(xy 130.119562 -154.593689) (xy 130.086109 -154.634321) (xy 130.06705 -154.652472) (xy 130.059666 -154.660009)
			(xy 130.05113 -154.679277) (xy 130.05054 -154.68981) (xy 130.05054 -154.764486) (xy 130.051051 -154.775038)
			(xy 130.059598 -154.794334) (xy 130.06705 -154.801824) (xy 130.086132 -154.819957) (xy 130.119611 -154.860577)
			(xy 130.147183 -154.905417) (xy 130.168321 -154.953625) (xy 130.182625 -155.004283) (xy 130.189821 -155.056428)
			(xy 130.19024 -155.082748) (xy 130.189767 -155.109999) (xy 130.182005 -155.163945) (xy 130.166645 -155.216238)
			(xy 130.144001 -155.265814) (xy 130.114532 -155.311662) (xy 130.07884 -155.352851) (xy 130.03765 -155.388542)
			(xy 129.9918 -155.418008) (xy 129.942223 -155.440651) (xy 129.88993 -155.456008) (xy 129.835983 -155.463768)
			(xy 129.808732 -155.464256) (xy 129.782415 -155.463842) (xy 129.730278 -155.456616) (xy 129.679629 -155.442296)
			(xy 129.631427 -155.421154) (xy 129.586586 -155.393592) (xy 129.545956 -155.36013) (xy 129.527808 -155.341066)
			(xy 129.520277 -155.333676) (xy 129.501004 -155.325143) (xy 129.49047 -155.324556) (xy 129.415794 -155.324556)
			(xy 129.405244 -155.325082) (xy 129.38595 -155.333621) (xy 129.378456 -155.341066) (xy 129.360336 -155.36016)
			(xy 129.319713 -155.393638) (xy 129.27487 -155.421208) (xy 129.226659 -155.442344) (xy 129.175999 -155.456645)
			(xy 129.123853 -155.463838) (xy 129.097532 -155.464256) (xy 129.071215 -155.463842) (xy 129.019078 -155.456616)
			(xy 128.968429 -155.442296) (xy 128.920227 -155.421154) (xy 128.875386 -155.393592) (xy 128.834756 -155.36013)
			(xy 128.816608 -155.341066) (xy 128.809077 -155.333676) (xy 128.789804 -155.325143) (xy 128.77927 -155.324556)
			(xy 128.704594 -155.324556) (xy 128.694044 -155.325082) (xy 128.67475 -155.333621) (xy 128.667256 -155.341066)
			(xy 128.649136 -155.36016) (xy 128.608513 -155.393638) (xy 128.56367 -155.421208) (xy 128.515459 -155.442344)
			(xy 128.464799 -155.456645) (xy 128.412653 -155.463838) (xy 128.386332 -155.464256) (xy 128.360015 -155.463842)
			(xy 128.307878 -155.456616) (xy 128.257229 -155.442296) (xy 128.209027 -155.421154) (xy 128.164186 -155.393592)
			(xy 128.123556 -155.36013) (xy 128.105408 -155.341066) (xy 128.097877 -155.333676) (xy 128.078604 -155.325143)
			(xy 128.06807 -155.324556) (xy 127.993394 -155.324556) (xy 127.982844 -155.325082) (xy 127.96355 -155.333621)
			(xy 127.956056 -155.341066) (xy 127.937936 -155.36016) (xy 127.897313 -155.393638) (xy 127.85247 -155.421208)
			(xy 127.804259 -155.442344) (xy 127.753599 -155.456645) (xy 127.701453 -155.463838) (xy 127.675132 -155.464256)
			(xy 127.647884 -155.463692) (xy 127.593941 -155.455941) (xy 127.541651 -155.440593) (xy 127.492077 -155.417959)
			(xy 127.446229 -155.3885) (xy 127.40504 -155.352817) (xy 127.369348 -155.311635) (xy 127.33988 -155.265793)
			(xy 127.317235 -155.216224) (xy 127.301876 -155.163937) (xy 127.294114 -155.109996) (xy 127.293624 -155.082748)
			(xy 126.733235 -155.082748) (xy 126.732791 -155.107078) (xy 126.724671 -155.162254) (xy 126.708603 -155.215661)
			(xy 126.684931 -155.266158) (xy 126.654158 -155.312671) (xy 126.616941 -155.354208) (xy 126.574073 -155.389883)
			(xy 126.526467 -155.418937) (xy 126.475138 -155.440749) (xy 126.421181 -155.454855) (xy 126.365744 -155.460955)
			(xy 126.31001 -155.458918) (xy 126.255167 -155.448788) (xy 126.202383 -155.430781) (xy 126.152783 -155.40528)
			(xy 126.107425 -155.372829) (xy 126.067276 -155.33412) (xy 126.03319 -155.289977) (xy 126.005894 -155.241342)
			(xy 125.985971 -155.189251) (xy 125.973845 -155.134814) (xy 125.969774 -155.079192) (xy 124.108988 -155.079192)
			(xy 124.123965 -155.128972) (xy 124.132085 -155.184148) (xy 124.132594 -155.212034) (xy 124.132085 -155.23992)
			(xy 124.123965 -155.295096) (xy 124.107897 -155.348503) (xy 124.084225 -155.399) (xy 124.053452 -155.445513)
			(xy 124.016235 -155.48705) (xy 123.973367 -155.522725) (xy 123.925761 -155.551779) (xy 123.874432 -155.573591)
			(xy 123.820475 -155.587697) (xy 123.765038 -155.593797) (xy 123.709304 -155.59176) (xy 123.654461 -155.58163)
			(xy 123.601677 -155.563623) (xy 123.552077 -155.538122) (xy 123.506719 -155.505671) (xy 123.46657 -155.466962)
			(xy 123.432484 -155.422819) (xy 123.405188 -155.374184) (xy 123.385265 -155.322093) (xy 123.373139 -155.267656)
			(xy 123.369068 -155.212034) (xy 123.222512 -155.212034) (xy 123.222512 -156.69387) (xy 124.987302 -156.69387)
			(xy 124.991373 -156.638248) (xy 125.003499 -156.583811) (xy 125.023422 -156.53172) (xy 125.050718 -156.483085)
			(xy 125.084804 -156.438942) (xy 125.124953 -156.400233) (xy 125.170311 -156.367782) (xy 125.219911 -156.342281)
			(xy 125.272695 -156.324274) (xy 125.327538 -156.314144) (xy 125.383272 -156.312107) (xy 125.438709 -156.318207)
			(xy 125.492666 -156.332313) (xy 125.543995 -156.354125) (xy 125.591601 -156.383179) (xy 125.634469 -156.418854)
			(xy 125.671686 -156.460391) (xy 125.702459 -156.506904) (xy 125.726131 -156.557401) (xy 125.742199 -156.610808)
			(xy 125.750319 -156.665984) (xy 125.750828 -156.69387) (xy 125.750319 -156.721756) (xy 125.742199 -156.776932)
			(xy 125.726131 -156.830339) (xy 125.702459 -156.880836) (xy 125.671686 -156.927349) (xy 125.634469 -156.968886)
			(xy 125.591601 -157.004561) (xy 125.543995 -157.033615) (xy 125.492666 -157.055427) (xy 125.438709 -157.069533)
			(xy 125.383272 -157.075633) (xy 125.327538 -157.073596) (xy 125.272695 -157.063466) (xy 125.219911 -157.045459)
			(xy 125.170311 -157.019958) (xy 125.124953 -156.987507) (xy 125.084804 -156.948798) (xy 125.050718 -156.904655)
			(xy 125.023422 -156.85602) (xy 125.003499 -156.803929) (xy 124.991373 -156.749492) (xy 124.987302 -156.69387)
			(xy 123.222512 -156.69387) (xy 123.222512 -157.420818) (xy 123.241308 -157.44698) (xy 123.256802 -157.452314)
			(xy 123.282899 -157.461889) (xy 123.332225 -157.487516) (xy 123.377313 -157.520027) (xy 123.417209 -157.558733)
			(xy 123.451069 -157.602817) (xy 123.47625 -157.647894) (xy 127.113792 -157.647894) (xy 127.114327 -157.621251)
			(xy 127.12285 -157.568653) (xy 127.139707 -157.518105) (xy 127.164461 -157.470918) (xy 127.196468 -157.428318)
			(xy 127.2349 -157.391409) (xy 127.25654 -157.37586) (xy 127.267829 -157.367502) (xy 127.28568 -157.345826)
			(xy 127.296959 -157.320111) (xy 127.300815 -157.292297) (xy 127.296957 -157.264483) (xy 127.285677 -157.238768)
			(xy 127.267824 -157.217094) (xy 127.25654 -157.208728) (xy 127.234939 -157.193131) (xy 127.196524 -157.156217)
			(xy 127.164523 -157.113623) (xy 127.139765 -157.066449) (xy 127.12289 -157.015916) (xy 127.114334 -156.963332)
			(xy 127.113792 -156.936694) (xy 127.114302 -156.910707) (xy 127.122432 -156.859372) (xy 127.138493 -156.809942)
			(xy 127.162089 -156.763632) (xy 127.192639 -156.721584) (xy 127.22939 -156.684833) (xy 127.271438 -156.654283)
			(xy 127.317748 -156.630687) (xy 127.367178 -156.614626) (xy 127.418513 -156.606496) (xy 127.470487 -156.606496)
			(xy 127.521822 -156.614626) (xy 127.571252 -156.630687) (xy 127.617562 -156.654283) (xy 127.65961 -156.684833)
			(xy 127.696361 -156.721584) (xy 127.726911 -156.763632) (xy 127.750507 -156.809942) (xy 127.766568 -156.859372)
			(xy 127.774698 -156.910707) (xy 127.775208 -156.936694) (xy 127.774664 -156.963336) (xy 127.766143 -157.015935)
			(xy 127.749288 -157.066482) (xy 127.724536 -157.113669) (xy 127.69253 -157.156269) (xy 127.6541 -157.193179)
			(xy 127.63246 -157.208728) (xy 127.621182 -157.217101) (xy 127.603332 -157.238773) (xy 127.592052 -157.264485)
			(xy 127.588195 -157.292297) (xy 127.59205 -157.320108) (xy 127.603328 -157.345821) (xy 127.621177 -157.367494)
			(xy 127.63246 -157.37586) (xy 127.654056 -157.391465) (xy 127.692471 -157.428377) (xy 127.724472 -157.47097)
			(xy 127.749231 -157.518142) (xy 127.766107 -157.568673) (xy 127.774665 -157.621257) (xy 127.775208 -157.647894)
			(xy 128.013714 -157.647894) (xy 128.014239 -157.621251) (xy 128.022763 -157.568651) (xy 128.039622 -157.518103)
			(xy 128.064377 -157.470916) (xy 128.096387 -157.428316) (xy 128.13482 -157.391408) (xy 128.156462 -157.37586)
			(xy 128.167749 -157.3675) (xy 128.185596 -157.345824) (xy 128.196873 -157.320109) (xy 128.200728 -157.292297)
			(xy 128.196871 -157.264484) (xy 128.185593 -157.238771) (xy 128.167744 -157.217095) (xy 128.156462 -157.208728)
			(xy 128.134866 -157.193124) (xy 128.096449 -157.156213) (xy 128.064448 -157.11362) (xy 128.039689 -157.066447)
			(xy 128.022813 -157.015915) (xy 128.014256 -156.963332) (xy 128.013714 -156.936694) (xy 128.014224 -156.910707)
			(xy 128.022354 -156.859372) (xy 128.038415 -156.809942) (xy 128.062011 -156.763632) (xy 128.092561 -156.721584)
			(xy 128.129312 -156.684833) (xy 128.17136 -156.654283) (xy 128.21767 -156.630687) (xy 128.2671 -156.614626)
			(xy 128.318435 -156.606496) (xy 128.370409 -156.606496) (xy 128.421744 -156.614626) (xy 128.471174 -156.630687)
			(xy 128.517484 -156.654283) (xy 128.559532 -156.684833) (xy 128.596283 -156.721584) (xy 128.626833 -156.763632)
			(xy 128.650429 -156.809942) (xy 128.66649 -156.859372) (xy 128.67462 -156.910707) (xy 128.67513 -156.936694)
			(xy 128.67462 -156.963338) (xy 128.666096 -157.01594) (xy 128.649236 -157.06649) (xy 128.624478 -157.113677)
			(xy 128.592465 -157.156276) (xy 128.554026 -157.193182) (xy 128.532382 -157.208728) (xy 128.521103 -157.2171)
			(xy 128.503248 -157.238771) (xy 128.491966 -157.264484) (xy 128.488108 -157.292297) (xy 128.491964 -157.320109)
			(xy 128.503245 -157.345823) (xy 128.521098 -157.367495) (xy 128.532382 -157.37586) (xy 128.553982 -157.391458)
			(xy 128.592396 -157.428372) (xy 128.624396 -157.470967) (xy 128.649154 -157.51814) (xy 128.66603 -157.568673)
			(xy 128.674587 -157.621256) (xy 128.67513 -157.647894) (xy 128.913636 -157.647894) (xy 128.914152 -157.62125)
			(xy 128.922677 -157.56865) (xy 128.939536 -157.5181) (xy 128.964293 -157.470914) (xy 128.996305 -157.428314)
			(xy 129.034741 -157.391407) (xy 129.056384 -157.37586) (xy 129.067678 -157.367505) (xy 129.085539 -157.345831)
			(xy 129.096824 -157.320115) (xy 129.100683 -157.292297) (xy 129.096823 -157.264479) (xy 129.085535 -157.238763)
			(xy 129.067673 -157.217091) (xy 129.056384 -157.208728) (xy 129.034792 -157.193118) (xy 128.996375 -157.156208)
			(xy 128.964372 -157.113617) (xy 128.939612 -157.066446) (xy 128.922735 -157.015914) (xy 128.914178 -156.963331)
			(xy 128.913636 -156.936694) (xy 128.914146 -156.910707) (xy 128.922276 -156.859372) (xy 128.938337 -156.809942)
			(xy 128.961933 -156.763632) (xy 128.992483 -156.721584) (xy 129.029234 -156.684833) (xy 129.071282 -156.654283)
			(xy 129.117592 -156.630687) (xy 129.167022 -156.614626) (xy 129.218357 -156.606496) (xy 129.270331 -156.606496)
			(xy 129.321666 -156.614626) (xy 129.371096 -156.630687) (xy 129.417406 -156.654283) (xy 129.459454 -156.684833)
			(xy 129.496205 -156.721584) (xy 129.526755 -156.763632) (xy 129.550351 -156.809942) (xy 129.566412 -156.859372)
			(xy 129.574542 -156.910707) (xy 129.575052 -156.936694) (xy 129.574532 -156.963338) (xy 129.566009 -157.015938)
			(xy 129.549151 -157.066488) (xy 129.524395 -157.113674) (xy 129.492383 -157.156274) (xy 129.453947 -157.193181)
			(xy 129.432304 -157.208728) (xy 129.421023 -157.217099) (xy 129.403164 -157.238769) (xy 129.39188 -157.264482)
			(xy 129.38802 -157.292297) (xy 129.391878 -157.320111) (xy 129.403161 -157.345825) (xy 129.421018 -157.367497)
			(xy 129.432304 -157.37586) (xy 129.453887 -157.391481) (xy 129.492306 -157.428388) (xy 129.52431 -157.470977)
			(xy 129.549072 -157.518146) (xy 129.56595 -157.568676) (xy 129.574509 -157.621257) (xy 129.575052 -157.647894)
			(xy 129.813812 -157.647894) (xy 129.814338 -157.621251) (xy 129.822862 -157.568651) (xy 129.83972 -157.518103)
			(xy 129.864475 -157.470916) (xy 129.896485 -157.428316) (xy 129.934919 -157.391408) (xy 129.95656 -157.37586)
			(xy 129.967847 -157.3675) (xy 129.985695 -157.345824) (xy 129.996971 -157.320109) (xy 130.000827 -157.292297)
			(xy 129.99697 -157.264484) (xy 129.985691 -157.23877) (xy 129.967842 -157.217095) (xy 129.95656 -157.208728)
			(xy 129.934963 -157.193125) (xy 129.896547 -157.156213) (xy 129.864545 -157.11362) (xy 129.839786 -157.066447)
			(xy 129.822911 -157.015915) (xy 129.814354 -156.963332) (xy 129.813812 -156.936694) (xy 129.814322 -156.910707)
			(xy 129.822452 -156.859372) (xy 129.838513 -156.809942) (xy 129.862109 -156.763632) (xy 129.892659 -156.721584)
			(xy 129.92941 -156.684833) (xy 129.971458 -156.654283) (xy 130.017768 -156.630687) (xy 130.067198 -156.614626)
			(xy 130.118533 -156.606496) (xy 130.170507 -156.606496) (xy 130.221842 -156.614626) (xy 130.271272 -156.630687)
			(xy 130.317582 -156.654283) (xy 130.35963 -156.684833) (xy 130.396381 -156.721584) (xy 130.426931 -156.763632)
			(xy 130.450527 -156.809942) (xy 130.466588 -156.859372) (xy 130.474718 -156.910707) (xy 130.475228 -156.936694)
			(xy 130.474719 -156.963338) (xy 130.466195 -157.01594) (xy 130.449335 -157.06649) (xy 130.424577 -157.113677)
			(xy 130.392563 -157.156276) (xy 130.354124 -157.193182) (xy 130.33248 -157.208728) (xy 130.321201 -157.2171)
			(xy 130.303346 -157.238771) (xy 130.292064 -157.264484) (xy 130.288206 -157.292297) (xy 130.292063 -157.320109)
			(xy 130.303343 -157.345823) (xy 130.321196 -157.367495) (xy 130.33248 -157.37586) (xy 130.35408 -157.391459)
			(xy 130.392494 -157.428373) (xy 130.424494 -157.470967) (xy 130.449252 -157.518141) (xy 130.466128 -157.568673)
			(xy 130.474685 -157.621256) (xy 130.475187 -157.645862) (xy 131.429252 -157.645862) (xy 131.429715 -157.619547)
			(xy 131.436936 -157.567414) (xy 131.451248 -157.516766) (xy 131.47238 -157.468565) (xy 131.499933 -157.423722)
			(xy 131.533383 -157.383089) (xy 131.552442 -157.364938) (xy 131.55982 -157.357396) (xy 131.56836 -157.338132)
			(xy 131.568952 -157.3276) (xy 131.568952 -157.252924) (xy 131.568437 -157.242372) (xy 131.559893 -157.223076)
			(xy 131.552442 -157.215586) (xy 131.533364 -157.19745) (xy 131.499884 -157.156831) (xy 131.472312 -157.111991)
			(xy 131.451173 -157.063783) (xy 131.436869 -157.013126) (xy 131.429672 -156.960982) (xy 131.429252 -156.934662)
			(xy 131.429738 -156.907411) (xy 131.437494 -156.853463) (xy 131.452849 -156.801168) (xy 131.475491 -156.751591)
			(xy 131.504957 -156.705741) (xy 131.540648 -156.66455) (xy 131.581839 -156.628859) (xy 131.627689 -156.599393)
			(xy 131.677266 -156.576751) (xy 131.729561 -156.561396) (xy 131.783509 -156.55364) (xy 131.838011 -156.55364)
			(xy 131.891959 -156.561396) (xy 131.944254 -156.576751) (xy 131.993831 -156.599393) (xy 132.039681 -156.628859)
			(xy 132.080872 -156.66455) (xy 132.116563 -156.705741) (xy 132.146029 -156.751591) (xy 132.168671 -156.801168)
			(xy 132.184026 -156.853463) (xy 132.191782 -156.907411) (xy 132.192268 -156.934662) (xy 132.191846 -156.960979)
			(xy 132.184621 -157.013115) (xy 132.170303 -157.063764) (xy 132.149162 -157.111966) (xy 132.121601 -157.156807)
			(xy 132.088141 -157.197437) (xy 132.069078 -157.215586) (xy 132.061677 -157.223108) (xy 132.053153 -157.242388)
			(xy 132.052568 -157.252924) (xy 132.052568 -157.3276) (xy 132.053093 -157.33815) (xy 132.061126 -157.356302)
			(xy 133.414516 -157.356302) (xy 133.414919 -157.329984) (xy 133.422148 -157.277848) (xy 133.436471 -157.227198)
			(xy 133.457615 -157.178997) (xy 133.485179 -157.134156) (xy 133.518642 -157.093526) (xy 133.537706 -157.075378)
			(xy 133.54512 -157.067867) (xy 133.553637 -157.048579) (xy 133.554216 -157.03804) (xy 133.554216 -156.963364)
			(xy 133.553661 -156.952817) (xy 133.545144 -156.933522) (xy 133.537706 -156.926026) (xy 133.51864 -156.907877)
			(xy 133.485161 -156.86726) (xy 133.457588 -156.822423) (xy 133.436447 -156.774218) (xy 133.42214 -156.723563)
			(xy 133.414938 -156.671421) (xy 133.414516 -156.645102) (xy 133.414919 -156.618784) (xy 133.422148 -156.566648)
			(xy 133.436471 -156.515998) (xy 133.457615 -156.467797) (xy 133.485179 -156.422956) (xy 133.518642 -156.382326)
			(xy 133.537706 -156.364178) (xy 133.54512 -156.356667) (xy 133.553637 -156.337379) (xy 133.554216 -156.32684)
			(xy 133.554216 -156.252164) (xy 133.553661 -156.241617) (xy 133.545144 -156.222322) (xy 133.537706 -156.214826)
			(xy 133.51864 -156.196677) (xy 133.485161 -156.15606) (xy 133.457588 -156.111223) (xy 133.436447 -156.063018)
			(xy 133.42214 -156.012363) (xy 133.414938 -155.960221) (xy 133.414516 -155.933902) (xy 133.415002 -155.906651)
			(xy 133.422758 -155.852703) (xy 133.438113 -155.800408) (xy 133.460755 -155.750831) (xy 133.490221 -155.704981)
			(xy 133.525912 -155.66379) (xy 133.567103 -155.628099) (xy 133.612953 -155.598633) (xy 133.66253 -155.575991)
			(xy 133.714825 -155.560636) (xy 133.768773 -155.55288) (xy 133.823275 -155.55288) (xy 133.877223 -155.560636)
			(xy 133.929518 -155.575991) (xy 133.979095 -155.598633) (xy 134.024945 -155.628099) (xy 134.066136 -155.66379)
			(xy 134.101827 -155.704981) (xy 134.131293 -155.750831) (xy 134.153935 -155.800408) (xy 134.16929 -155.852703)
			(xy 134.177046 -155.906651) (xy 134.177532 -155.933902) (xy 134.177116 -155.960219) (xy 134.169887 -156.012354)
			(xy 134.155566 -156.063003) (xy 134.134425 -156.111204) (xy 134.106863 -156.156046) (xy 134.073404 -156.196676)
			(xy 134.054342 -156.214826) (xy 134.046933 -156.222342) (xy 134.038412 -156.241626) (xy 134.037832 -156.252164)
			(xy 134.037832 -156.32684) (xy 134.038371 -156.337389) (xy 134.046898 -156.356685) (xy 134.054342 -156.364178)
			(xy 134.0734 -156.382335) (xy 134.106882 -156.422949) (xy 134.134457 -156.467785) (xy 134.155599 -156.515988)
			(xy 134.169908 -156.566642) (xy 134.17711 -156.618784) (xy 134.177532 -156.645102) (xy 134.177116 -156.671419)
			(xy 134.169887 -156.723554) (xy 134.155566 -156.774203) (xy 134.134425 -156.822404) (xy 134.106863 -156.867246)
			(xy 134.073404 -156.907876) (xy 134.054342 -156.926026) (xy 134.046933 -156.933542) (xy 134.038412 -156.952826)
			(xy 134.037832 -156.963364) (xy 134.037832 -157.03804) (xy 134.038371 -157.048589) (xy 134.046898 -157.067885)
			(xy 134.054342 -157.075378) (xy 134.0734 -157.093535) (xy 134.106882 -157.134149) (xy 134.134457 -157.178985)
			(xy 134.155599 -157.227188) (xy 134.169908 -157.277842) (xy 134.17711 -157.329984) (xy 134.177532 -157.356302)
			(xy 134.177046 -157.383553) (xy 134.172017 -157.418532) (xy 136.480296 -157.418532) (xy 136.480725 -157.392215)
			(xy 136.48795 -157.34008) (xy 136.502268 -157.289432) (xy 136.523407 -157.24123) (xy 136.550967 -157.196388)
			(xy 136.584424 -157.155757) (xy 136.603486 -157.137608) (xy 136.610884 -157.130083) (xy 136.619411 -157.110806)
			(xy 136.619996 -157.10027) (xy 136.619996 -157.025594) (xy 136.619485 -157.015042) (xy 136.610937 -156.995747)
			(xy 136.603486 -156.988256) (xy 136.584383 -156.970146) (xy 136.550907 -156.92952) (xy 136.52334 -156.884674)
			(xy 136.502206 -156.836462) (xy 136.487906 -156.7858) (xy 136.480714 -156.733653) (xy 136.480296 -156.707332)
			(xy 136.480725 -156.681015) (xy 136.48795 -156.62888) (xy 136.502268 -156.578232) (xy 136.523407 -156.53003)
			(xy 136.550967 -156.485188) (xy 136.584424 -156.444557) (xy 136.603486 -156.426408) (xy 136.610884 -156.418883)
			(xy 136.619411 -156.399606) (xy 136.619996 -156.38907) (xy 136.619996 -156.314394) (xy 136.619485 -156.303842)
			(xy 136.610937 -156.284547) (xy 136.603486 -156.277056) (xy 136.584383 -156.258946) (xy 136.550907 -156.21832)
			(xy 136.52334 -156.173474) (xy 136.502206 -156.125262) (xy 136.487906 -156.0746) (xy 136.480714 -156.022453)
			(xy 136.480296 -155.996132) (xy 136.480782 -155.968881) (xy 136.488538 -155.914933) (xy 136.503893 -155.862638)
			(xy 136.526535 -155.813061) (xy 136.556001 -155.767211) (xy 136.591692 -155.72602) (xy 136.632883 -155.690329)
			(xy 136.678733 -155.660863) (xy 136.72831 -155.638221) (xy 136.780605 -155.622866) (xy 136.834553 -155.61511)
			(xy 136.889055 -155.61511) (xy 136.943003 -155.622866) (xy 136.995298 -155.638221) (xy 137.044875 -155.660863)
			(xy 137.090725 -155.690329) (xy 137.131916 -155.72602) (xy 137.167607 -155.767211) (xy 137.197073 -155.813061)
			(xy 137.219715 -155.862638) (xy 137.23507 -155.914933) (xy 137.242826 -155.968881) (xy 137.243312 -155.996132)
			(xy 137.242856 -156.022448) (xy 137.235636 -156.074582) (xy 137.221323 -156.12523) (xy 137.200189 -156.173431)
			(xy 137.172635 -156.218274) (xy 137.139182 -156.258906) (xy 137.120122 -156.277056) (xy 137.112741 -156.284595)
			(xy 137.104204 -156.303862) (xy 137.103612 -156.314394) (xy 137.103612 -156.38907) (xy 137.10414 -156.39962)
			(xy 137.112676 -156.418915) (xy 137.120122 -156.426408) (xy 137.13919 -156.444554) (xy 137.172672 -156.48517)
			(xy 137.200246 -156.530008) (xy 137.221387 -156.578213) (xy 137.235693 -156.62887) (xy 137.242892 -156.681013)
			(xy 137.243312 -156.707332) (xy 137.242856 -156.733648) (xy 137.235636 -156.785782) (xy 137.221323 -156.83643)
			(xy 137.200189 -156.884631) (xy 137.172635 -156.929474) (xy 137.139182 -156.970106) (xy 137.120122 -156.988256)
			(xy 137.112741 -156.995795) (xy 137.104204 -157.015062) (xy 137.103612 -157.025594) (xy 137.103612 -157.10027)
			(xy 137.10414 -157.11082) (xy 137.112676 -157.130115) (xy 137.120122 -157.137608) (xy 137.13919 -157.155754)
			(xy 137.172672 -157.19637) (xy 137.200246 -157.241208) (xy 137.221387 -157.289413) (xy 137.235693 -157.34007)
			(xy 137.242892 -157.392213) (xy 137.243312 -157.418532) (xy 137.242826 -157.445783) (xy 137.23507 -157.499731)
			(xy 137.219715 -157.552026) (xy 137.197073 -157.601603) (xy 137.167607 -157.647453) (xy 137.131916 -157.688644)
			(xy 137.090725 -157.724335) (xy 137.044875 -157.753801) (xy 136.995298 -157.776443) (xy 136.943003 -157.791798)
			(xy 136.889055 -157.799554) (xy 136.834553 -157.799554) (xy 136.780605 -157.791798) (xy 136.72831 -157.776443)
			(xy 136.678733 -157.753801) (xy 136.632883 -157.724335) (xy 136.591692 -157.688644) (xy 136.556001 -157.647453)
			(xy 136.526535 -157.601603) (xy 136.503893 -157.552026) (xy 136.488538 -157.499731) (xy 136.480782 -157.445783)
			(xy 136.480296 -157.418532) (xy 134.172017 -157.418532) (xy 134.16929 -157.437501) (xy 134.153935 -157.489796)
			(xy 134.131293 -157.539373) (xy 134.101827 -157.585223) (xy 134.066136 -157.626414) (xy 134.024945 -157.662105)
			(xy 133.979095 -157.691571) (xy 133.929518 -157.714213) (xy 133.877223 -157.729568) (xy 133.823275 -157.737324)
			(xy 133.768773 -157.737324) (xy 133.714825 -157.729568) (xy 133.66253 -157.714213) (xy 133.612953 -157.691571)
			(xy 133.567103 -157.662105) (xy 133.525912 -157.626414) (xy 133.490221 -157.585223) (xy 133.460755 -157.539373)
			(xy 133.438113 -157.489796) (xy 133.422758 -157.437501) (xy 133.415002 -157.383553) (xy 133.414516 -157.356302)
			(xy 132.061126 -157.356302) (xy 132.061632 -157.357445) (xy 132.069078 -157.364938) (xy 132.088172 -157.383058)
			(xy 132.121649 -157.423681) (xy 132.149218 -157.468525) (xy 132.170355 -157.516735) (xy 132.184656 -157.567395)
			(xy 132.19185 -157.619542) (xy 132.192268 -157.645862) (xy 132.191782 -157.673113) (xy 132.184026 -157.727061)
			(xy 132.168671 -157.779356) (xy 132.146029 -157.828933) (xy 132.116563 -157.874783) (xy 132.080872 -157.915974)
			(xy 132.039681 -157.951665) (xy 131.993831 -157.981131) (xy 131.944254 -158.003773) (xy 131.891959 -158.019128)
			(xy 131.838011 -158.026884) (xy 131.783509 -158.026884) (xy 131.729561 -158.019128) (xy 131.677266 -158.003773)
			(xy 131.627689 -157.981131) (xy 131.581839 -157.951665) (xy 131.540648 -157.915974) (xy 131.504957 -157.874783)
			(xy 131.475491 -157.828933) (xy 131.452849 -157.779356) (xy 131.437494 -157.727061) (xy 131.429738 -157.673113)
			(xy 131.429252 -157.645862) (xy 130.475187 -157.645862) (xy 130.475228 -157.647894) (xy 130.474718 -157.673881)
			(xy 130.466588 -157.725216) (xy 130.450527 -157.774646) (xy 130.426931 -157.820956) (xy 130.396381 -157.863004)
			(xy 130.35963 -157.899755) (xy 130.317582 -157.930305) (xy 130.271272 -157.953901) (xy 130.221842 -157.969962)
			(xy 130.170507 -157.978092) (xy 130.118533 -157.978092) (xy 130.067198 -157.969962) (xy 130.017768 -157.953901)
			(xy 129.971458 -157.930305) (xy 129.92941 -157.899755) (xy 129.892659 -157.863004) (xy 129.862109 -157.820956)
			(xy 129.838513 -157.774646) (xy 129.822452 -157.725216) (xy 129.814322 -157.673881) (xy 129.813812 -157.647894)
			(xy 129.575052 -157.647894) (xy 129.574542 -157.673881) (xy 129.566412 -157.725216) (xy 129.550351 -157.774646)
			(xy 129.526755 -157.820956) (xy 129.496205 -157.863004) (xy 129.459454 -157.899755) (xy 129.417406 -157.930305)
			(xy 129.371096 -157.953901) (xy 129.321666 -157.969962) (xy 129.270331 -157.978092) (xy 129.218357 -157.978092)
			(xy 129.167022 -157.969962) (xy 129.117592 -157.953901) (xy 129.071282 -157.930305) (xy 129.029234 -157.899755)
			(xy 128.992483 -157.863004) (xy 128.961933 -157.820956) (xy 128.938337 -157.774646) (xy 128.922276 -157.725216)
			(xy 128.914146 -157.673881) (xy 128.913636 -157.647894) (xy 128.67513 -157.647894) (xy 128.67462 -157.673881)
			(xy 128.66649 -157.725216) (xy 128.650429 -157.774646) (xy 128.626833 -157.820956) (xy 128.596283 -157.863004)
			(xy 128.559532 -157.899755) (xy 128.517484 -157.930305) (xy 128.471174 -157.953901) (xy 128.421744 -157.969962)
			(xy 128.370409 -157.978092) (xy 128.318435 -157.978092) (xy 128.2671 -157.969962) (xy 128.21767 -157.953901)
			(xy 128.17136 -157.930305) (xy 128.129312 -157.899755) (xy 128.092561 -157.863004) (xy 128.062011 -157.820956)
			(xy 128.038415 -157.774646) (xy 128.022354 -157.725216) (xy 128.014224 -157.673881) (xy 128.013714 -157.647894)
			(xy 127.775208 -157.647894) (xy 127.774698 -157.673881) (xy 127.766568 -157.725216) (xy 127.750507 -157.774646)
			(xy 127.726911 -157.820956) (xy 127.696361 -157.863004) (xy 127.65961 -157.899755) (xy 127.617562 -157.930305)
			(xy 127.571252 -157.953901) (xy 127.521822 -157.969962) (xy 127.470487 -157.978092) (xy 127.418513 -157.978092)
			(xy 127.367178 -157.969962) (xy 127.317748 -157.953901) (xy 127.271438 -157.930305) (xy 127.22939 -157.899755)
			(xy 127.192639 -157.863004) (xy 127.162089 -157.820956) (xy 127.138493 -157.774646) (xy 127.122432 -157.725216)
			(xy 127.114302 -157.673881) (xy 127.113792 -157.647894) (xy 123.47625 -157.647894) (xy 123.478178 -157.651345)
			(xy 123.497961 -157.703292) (xy 123.510001 -157.757559) (xy 123.514043 -157.812998) (xy 123.510002 -157.868437)
			(xy 123.497962 -157.922704) (xy 123.478179 -157.974652) (xy 123.451071 -158.02318) (xy 123.422492 -158.06039)
			(xy 124.93955 -158.06039) (xy 124.943621 -158.004768) (xy 124.955747 -157.950331) (xy 124.97567 -157.89824)
			(xy 125.002966 -157.849605) (xy 125.037052 -157.805462) (xy 125.077201 -157.766753) (xy 125.122559 -157.734302)
			(xy 125.172159 -157.708801) (xy 125.224943 -157.690794) (xy 125.279786 -157.680664) (xy 125.33552 -157.678627)
			(xy 125.390957 -157.684727) (xy 125.444914 -157.698833) (xy 125.496243 -157.720645) (xy 125.543849 -157.749699)
			(xy 125.586717 -157.785374) (xy 125.623934 -157.826911) (xy 125.654707 -157.873424) (xy 125.678379 -157.923921)
			(xy 125.694447 -157.977328) (xy 125.702567 -158.032504) (xy 125.703076 -158.06039) (xy 125.702567 -158.088276)
			(xy 125.694447 -158.143452) (xy 125.678379 -158.196859) (xy 125.654707 -158.247356) (xy 125.623934 -158.293869)
			(xy 125.586717 -158.335406) (xy 125.543849 -158.371081) (xy 125.496243 -158.400135) (xy 125.444914 -158.421947)
			(xy 125.390957 -158.436053) (xy 125.33552 -158.442153) (xy 125.279786 -158.440116) (xy 125.224943 -158.429986)
			(xy 125.172159 -158.411979) (xy 125.122559 -158.386478) (xy 125.077201 -158.354027) (xy 125.037052 -158.315318)
			(xy 125.002966 -158.271175) (xy 124.97567 -158.22254) (xy 124.955747 -158.170449) (xy 124.943621 -158.116012)
			(xy 124.93955 -158.06039) (xy 123.422492 -158.06039) (xy 123.417212 -158.067264) (xy 123.377316 -158.105971)
			(xy 123.332229 -158.138482) (xy 123.282902 -158.16411) (xy 123.256802 -158.173674) (xy 123.241308 -158.179008)
			(xy 123.222512 -158.20517) (xy 123.222512 -158.436818) (xy 123.241308 -158.46298) (xy 123.256802 -158.468314)
			(xy 123.282899 -158.477889) (xy 123.332225 -158.503516) (xy 123.377313 -158.536027) (xy 123.417209 -158.574733)
			(xy 123.451069 -158.618817) (xy 123.478178 -158.667345) (xy 123.497961 -158.719292) (xy 123.505507 -158.753302)
			(xy 132.616446 -158.753302) (xy 132.620517 -158.69768) (xy 132.632643 -158.643243) (xy 132.652566 -158.591152)
			(xy 132.679862 -158.542517) (xy 132.713948 -158.498374) (xy 132.754097 -158.459665) (xy 132.799455 -158.427214)
			(xy 132.849055 -158.401713) (xy 132.901839 -158.383706) (xy 132.956682 -158.373576) (xy 133.012416 -158.371539)
			(xy 133.067853 -158.377639) (xy 133.12181 -158.391745) (xy 133.173139 -158.413557) (xy 133.220745 -158.442611)
			(xy 133.263613 -158.478286) (xy 133.30083 -158.519823) (xy 133.331603 -158.566336) (xy 133.355275 -158.616833)
			(xy 133.371343 -158.67024) (xy 133.379463 -158.725416) (xy 133.379972 -158.753302) (xy 133.379463 -158.781188)
			(xy 133.371343 -158.836364) (xy 133.355275 -158.889771) (xy 133.331603 -158.940268) (xy 133.30083 -158.986781)
			(xy 133.263613 -159.028318) (xy 133.220745 -159.063993) (xy 133.173139 -159.093047) (xy 133.12181 -159.114859)
			(xy 133.067853 -159.128965) (xy 133.012416 -159.135065) (xy 132.956682 -159.133028) (xy 132.901839 -159.122898)
			(xy 132.849055 -159.104891) (xy 132.799455 -159.07939) (xy 132.754097 -159.046939) (xy 132.713948 -159.00823)
			(xy 132.679862 -158.964087) (xy 132.652566 -158.915452) (xy 132.632643 -158.863361) (xy 132.620517 -158.808924)
			(xy 132.616446 -158.753302) (xy 123.505507 -158.753302) (xy 123.510001 -158.773559) (xy 123.514043 -158.828998)
			(xy 123.510002 -158.884437) (xy 123.497962 -158.938704) (xy 123.478179 -158.990652) (xy 123.451071 -159.03918)
			(xy 123.417212 -159.083264) (xy 123.377316 -159.121971) (xy 123.332229 -159.154482) (xy 123.282902 -159.18011)
			(xy 123.256802 -159.189674) (xy 123.241308 -159.195008) (xy 123.222512 -159.22117) (xy 123.222512 -159.439102)
			(xy 125.007876 -159.439102) (xy 125.011947 -159.38348) (xy 125.024073 -159.329043) (xy 125.043996 -159.276952)
			(xy 125.071292 -159.228317) (xy 125.105378 -159.184174) (xy 125.145527 -159.145465) (xy 125.190885 -159.113014)
			(xy 125.240485 -159.087513) (xy 125.293269 -159.069506) (xy 125.348112 -159.059376) (xy 125.403846 -159.057339)
			(xy 125.459283 -159.063439) (xy 125.51324 -159.077545) (xy 125.564569 -159.099357) (xy 125.612175 -159.128411)
			(xy 125.655043 -159.164086) (xy 125.69226 -159.205623) (xy 125.723033 -159.252136) (xy 125.746705 -159.302633)
			(xy 125.762773 -159.35604) (xy 125.770893 -159.411216) (xy 125.771402 -159.439102) (xy 125.770893 -159.466988)
			(xy 125.762773 -159.522164) (xy 125.75987 -159.531812) (xy 128.212594 -159.531812) (xy 128.216665 -159.47619)
			(xy 128.228791 -159.421753) (xy 128.248714 -159.369662) (xy 128.27601 -159.321027) (xy 128.310096 -159.276884)
			(xy 128.350245 -159.238175) (xy 128.395603 -159.205724) (xy 128.445203 -159.180223) (xy 128.497987 -159.162216)
			(xy 128.55283 -159.152086) (xy 128.608564 -159.150049) (xy 128.664001 -159.156149) (xy 128.717958 -159.170255)
			(xy 128.769287 -159.192067) (xy 128.816893 -159.221121) (xy 128.859761 -159.256796) (xy 128.896978 -159.298333)
			(xy 128.927751 -159.344846) (xy 128.951423 -159.395343) (xy 128.967491 -159.44875) (xy 128.97336 -159.488632)
			(xy 130.4958 -159.488632) (xy 130.499871 -159.43301) (xy 130.511997 -159.378573) (xy 130.53192 -159.326482)
			(xy 130.559216 -159.277847) (xy 130.593302 -159.233704) (xy 130.633451 -159.194995) (xy 130.678809 -159.162544)
			(xy 130.728409 -159.137043) (xy 130.781193 -159.119036) (xy 130.836036 -159.108906) (xy 130.89177 -159.106869)
			(xy 130.947207 -159.112969) (xy 131.001164 -159.127075) (xy 131.052493 -159.148887) (xy 131.100099 -159.177941)
			(xy 131.142967 -159.213616) (xy 131.180184 -159.255153) (xy 131.210957 -159.301666) (xy 131.234629 -159.352163)
			(xy 131.250697 -159.40557) (xy 131.258817 -159.460746) (xy 131.259326 -159.488632) (xy 131.258817 -159.516518)
			(xy 131.250697 -159.571694) (xy 131.234629 -159.625101) (xy 131.210957 -159.675598) (xy 131.180184 -159.722111)
			(xy 131.142967 -159.763648) (xy 131.100099 -159.799323) (xy 131.052493 -159.828377) (xy 131.001164 -159.850189)
			(xy 130.947207 -159.864295) (xy 130.89177 -159.870395) (xy 130.836036 -159.868358) (xy 130.781193 -159.858228)
			(xy 130.728409 -159.840221) (xy 130.678809 -159.81472) (xy 130.633451 -159.782269) (xy 130.593302 -159.74356)
			(xy 130.559216 -159.699417) (xy 130.53192 -159.650782) (xy 130.511997 -159.598691) (xy 130.499871 -159.544254)
			(xy 130.4958 -159.488632) (xy 128.97336 -159.488632) (xy 128.975611 -159.503926) (xy 128.97612 -159.531812)
			(xy 128.975611 -159.559698) (xy 128.967491 -159.614874) (xy 128.951423 -159.668281) (xy 128.927751 -159.718778)
			(xy 128.896978 -159.765291) (xy 128.859761 -159.806828) (xy 128.816893 -159.842503) (xy 128.769287 -159.871557)
			(xy 128.717958 -159.893369) (xy 128.664001 -159.907475) (xy 128.608564 -159.913575) (xy 128.55283 -159.911538)
			(xy 128.497987 -159.901408) (xy 128.445203 -159.883401) (xy 128.395603 -159.8579) (xy 128.350245 -159.825449)
			(xy 128.310096 -159.78674) (xy 128.27601 -159.742597) (xy 128.248714 -159.693962) (xy 128.228791 -159.641871)
			(xy 128.216665 -159.587434) (xy 128.212594 -159.531812) (xy 125.75987 -159.531812) (xy 125.746705 -159.575571)
			(xy 125.723033 -159.626068) (xy 125.69226 -159.672581) (xy 125.655043 -159.714118) (xy 125.612175 -159.749793)
			(xy 125.564569 -159.778847) (xy 125.51324 -159.800659) (xy 125.459283 -159.814765) (xy 125.403846 -159.820865)
			(xy 125.348112 -159.818828) (xy 125.293269 -159.808698) (xy 125.240485 -159.790691) (xy 125.190885 -159.76519)
			(xy 125.145527 -159.732739) (xy 125.105378 -159.69403) (xy 125.071292 -159.649887) (xy 125.043996 -159.601252)
			(xy 125.024073 -159.549161) (xy 125.011947 -159.494724) (xy 125.007876 -159.439102) (xy 123.222512 -159.439102)
			(xy 123.222512 -159.452818) (xy 123.241308 -159.47898) (xy 123.256802 -159.484314) (xy 123.282899 -159.493889)
			(xy 123.332225 -159.519516) (xy 123.377313 -159.552027) (xy 123.417209 -159.590733) (xy 123.451069 -159.634817)
			(xy 123.478178 -159.683345) (xy 123.497961 -159.735292) (xy 123.510001 -159.789559) (xy 123.514043 -159.844998)
			(xy 123.510002 -159.900437) (xy 123.497962 -159.954704) (xy 123.478179 -160.006652) (xy 123.451071 -160.05518)
			(xy 123.417212 -160.099264) (xy 123.377316 -160.137971) (xy 123.332229 -160.170482) (xy 123.282902 -160.19611)
			(xy 123.256802 -160.205674) (xy 123.241308 -160.211008) (xy 123.222512 -160.23717) (xy 123.222512 -160.965896)
			(xy 125.037594 -160.965896) (xy 125.041665 -160.910274) (xy 125.053791 -160.855837) (xy 125.073714 -160.803746)
			(xy 125.10101 -160.755111) (xy 125.135096 -160.710968) (xy 125.175245 -160.672259) (xy 125.220603 -160.639808)
			(xy 125.270203 -160.614307) (xy 125.322987 -160.5963) (xy 125.37783 -160.58617) (xy 125.433564 -160.584133)
			(xy 125.489001 -160.590233) (xy 125.542958 -160.604339) (xy 125.594287 -160.626151) (xy 125.641893 -160.655205)
			(xy 125.684761 -160.69088) (xy 125.721978 -160.732417) (xy 125.752751 -160.77893) (xy 125.776423 -160.829427)
			(xy 125.792491 -160.882834) (xy 125.800611 -160.93801) (xy 125.801083 -160.963864) (xy 126.429514 -160.963864)
			(xy 126.433585 -160.908242) (xy 126.445711 -160.853805) (xy 126.465634 -160.801714) (xy 126.49293 -160.753079)
			(xy 126.527016 -160.708936) (xy 126.567165 -160.670227) (xy 126.612523 -160.637776) (xy 126.662123 -160.612275)
			(xy 126.714907 -160.594268) (xy 126.76975 -160.584138) (xy 126.825484 -160.582101) (xy 126.880921 -160.588201)
			(xy 126.934878 -160.602307) (xy 126.986207 -160.624119) (xy 127.033813 -160.653173) (xy 127.076681 -160.688848)
			(xy 127.113898 -160.730385) (xy 127.144671 -160.776898) (xy 127.168343 -160.827395) (xy 127.184411 -160.880802)
			(xy 127.192531 -160.935978) (xy 127.19304 -160.963864) (xy 127.192947 -160.968944) (xy 127.701292 -160.968944)
			(xy 127.705363 -160.913322) (xy 127.717489 -160.858885) (xy 127.737412 -160.806794) (xy 127.764708 -160.758159)
			(xy 127.798794 -160.714016) (xy 127.838943 -160.675307) (xy 127.884301 -160.642856) (xy 127.933901 -160.617355)
			(xy 127.986685 -160.599348) (xy 128.041528 -160.589218) (xy 128.097262 -160.587181) (xy 128.152699 -160.593281)
			(xy 128.206656 -160.607387) (xy 128.257985 -160.629199) (xy 128.305591 -160.658253) (xy 128.348459 -160.693928)
			(xy 128.385676 -160.735465) (xy 128.416449 -160.781978) (xy 128.440121 -160.832475) (xy 128.456189 -160.885882)
			(xy 128.458582 -160.902142) (xy 129.482594 -160.902142) (xy 129.486665 -160.84652) (xy 129.498791 -160.792083)
			(xy 129.518714 -160.739992) (xy 129.54601 -160.691357) (xy 129.580096 -160.647214) (xy 129.620245 -160.608505)
			(xy 129.665603 -160.576054) (xy 129.715203 -160.550553) (xy 129.767987 -160.532546) (xy 129.82283 -160.522416)
			(xy 129.878564 -160.520379) (xy 129.934001 -160.526479) (xy 129.987958 -160.540585) (xy 130.039287 -160.562397)
			(xy 130.086893 -160.591451) (xy 130.129761 -160.627126) (xy 130.166978 -160.668663) (xy 130.197751 -160.715176)
			(xy 130.221423 -160.765673) (xy 130.237491 -160.81908) (xy 130.245611 -160.874256) (xy 130.24612 -160.902142)
			(xy 130.245611 -160.930028) (xy 130.237491 -160.985204) (xy 130.221423 -161.038611) (xy 130.197751 -161.089108)
			(xy 130.166978 -161.135621) (xy 130.129761 -161.177158) (xy 130.086893 -161.212833) (xy 130.039287 -161.241887)
			(xy 129.987958 -161.263699) (xy 129.934001 -161.277805) (xy 129.878564 -161.283905) (xy 129.82283 -161.281868)
			(xy 129.767987 -161.271738) (xy 129.715203 -161.253731) (xy 129.665603 -161.22823) (xy 129.620245 -161.195779)
			(xy 129.580096 -161.15707) (xy 129.54601 -161.112927) (xy 129.518714 -161.064292) (xy 129.498791 -161.012201)
			(xy 129.486665 -160.957764) (xy 129.482594 -160.902142) (xy 128.458582 -160.902142) (xy 128.464309 -160.941058)
			(xy 128.464818 -160.968944) (xy 128.464309 -160.99683) (xy 128.456189 -161.052006) (xy 128.440121 -161.105413)
			(xy 128.416449 -161.15591) (xy 128.385676 -161.202423) (xy 128.348459 -161.24396) (xy 128.305591 -161.279635)
			(xy 128.257985 -161.308689) (xy 128.206656 -161.330501) (xy 128.152699 -161.344607) (xy 128.097262 -161.350707)
			(xy 128.041528 -161.34867) (xy 127.986685 -161.33854) (xy 127.933901 -161.320533) (xy 127.884301 -161.295032)
			(xy 127.838943 -161.262581) (xy 127.798794 -161.223872) (xy 127.764708 -161.179729) (xy 127.737412 -161.131094)
			(xy 127.717489 -161.079003) (xy 127.705363 -161.024566) (xy 127.701292 -160.968944) (xy 127.192947 -160.968944)
			(xy 127.192531 -160.99175) (xy 127.184411 -161.046926) (xy 127.168343 -161.100333) (xy 127.144671 -161.15083)
			(xy 127.113898 -161.197343) (xy 127.076681 -161.23888) (xy 127.033813 -161.274555) (xy 126.986207 -161.303609)
			(xy 126.934878 -161.325421) (xy 126.880921 -161.339527) (xy 126.825484 -161.345627) (xy 126.76975 -161.34359)
			(xy 126.714907 -161.33346) (xy 126.662123 -161.315453) (xy 126.612523 -161.289952) (xy 126.567165 -161.257501)
			(xy 126.527016 -161.218792) (xy 126.49293 -161.174649) (xy 126.465634 -161.126014) (xy 126.445711 -161.073923)
			(xy 126.433585 -161.019486) (xy 126.429514 -160.963864) (xy 125.801083 -160.963864) (xy 125.80112 -160.965896)
			(xy 125.800611 -160.993782) (xy 125.792491 -161.048958) (xy 125.776423 -161.102365) (xy 125.752751 -161.152862)
			(xy 125.721978 -161.199375) (xy 125.684761 -161.240912) (xy 125.641893 -161.276587) (xy 125.594287 -161.305641)
			(xy 125.542958 -161.327453) (xy 125.489001 -161.341559) (xy 125.433564 -161.347659) (xy 125.37783 -161.345622)
			(xy 125.322987 -161.335492) (xy 125.270203 -161.317485) (xy 125.220603 -161.291984) (xy 125.175245 -161.259533)
			(xy 125.135096 -161.220824) (xy 125.10101 -161.176681) (xy 125.073714 -161.128046) (xy 125.053791 -161.075955)
			(xy 125.041665 -161.021518) (xy 125.037594 -160.965896) (xy 123.222512 -160.965896) (xy 123.222512 -163.114736)
			(xy 132.149594 -163.114736) (xy 132.153665 -163.059114) (xy 132.165791 -163.004677) (xy 132.185714 -162.952586)
			(xy 132.21301 -162.903951) (xy 132.247096 -162.859808) (xy 132.287245 -162.821099) (xy 132.332603 -162.788648)
			(xy 132.382203 -162.763147) (xy 132.434987 -162.74514) (xy 132.48983 -162.73501) (xy 132.545564 -162.732973)
			(xy 132.601001 -162.739073) (xy 132.654958 -162.753179) (xy 132.706287 -162.774991) (xy 132.753893 -162.804045)
			(xy 132.796761 -162.83972) (xy 132.833978 -162.881257) (xy 132.864751 -162.92777) (xy 132.888423 -162.978267)
			(xy 132.904491 -163.031674) (xy 132.912611 -163.08685) (xy 132.91312 -163.114736) (xy 132.912611 -163.142622)
			(xy 132.904491 -163.197798) (xy 132.888423 -163.251205) (xy 132.864751 -163.301702) (xy 132.833978 -163.348215)
			(xy 132.796761 -163.389752) (xy 132.753893 -163.425427) (xy 132.706287 -163.454481) (xy 132.654958 -163.476293)
			(xy 132.601001 -163.490399) (xy 132.545564 -163.496499) (xy 132.48983 -163.494462) (xy 132.434987 -163.484332)
			(xy 132.382203 -163.466325) (xy 132.332603 -163.440824) (xy 132.287245 -163.408373) (xy 132.247096 -163.369664)
			(xy 132.21301 -163.325521) (xy 132.185714 -163.276886) (xy 132.165791 -163.224795) (xy 132.153665 -163.170358)
			(xy 132.149594 -163.114736) (xy 123.222512 -163.114736) (xy 123.222512 -163.599368) (xy 123.222948 -163.609432)
			(xy 123.230681 -163.628018) (xy 123.237498 -163.635436) (xy 125.047248 -165.445186) (xy 125.047756 -165.445694)
			(xy 125.055139 -165.452271) (xy 125.073438 -165.459714) (xy 125.083316 -165.460172)
		)
		(stroke
			(width 0)
			(type solid)
		)
		(fill yes)
		(layer "In13.Cu")
		(net "GND")
	)
	(gr_poly
		(pts
			(xy 185.353706 -126.866142) (xy 185.35943 -126.865988) (xy 185.370583 -126.863415) (xy 185.375804 -126.861062)
			(xy 185.399172 -126.849886) (xy 185.4073 -126.843282) (xy 185.410856 -126.839218) (xy 185.41111 -126.838964)
			(xy 185.440799 -126.804553) (xy 185.505801 -126.741023) (xy 185.576631 -126.684065) (xy 185.652628 -126.63421)
			(xy 185.733084 -126.591924) (xy 185.817245 -126.557601) (xy 185.904326 -126.531563) (xy 185.993515 -126.514052)
			(xy 186.083977 -126.505233) (xy 186.129422 -126.5047) (xy 187.985146 -126.5047) (xy 188.030587 -126.505288)
			(xy 188.121039 -126.514134) (xy 188.210216 -126.531661) (xy 188.297288 -126.557705) (xy 188.381442 -126.592025)
			(xy 188.461894 -126.634301) (xy 188.537895 -126.684137) (xy 188.608735 -126.74107) (xy 188.673755 -126.80457)
			(xy 188.703458 -126.838964) (xy 188.703712 -126.839218) (xy 188.707268 -126.843282) (xy 188.715396 -126.849886)
			(xy 188.739018 -126.861062) (xy 188.744179 -126.863391) (xy 188.755203 -126.865967) (xy 188.760862 -126.866142)
			(xy 208.015586 -126.866142) (xy 208.025648 -126.865702) (xy 208.044224 -126.857959) (xy 208.051654 -126.851156)
			(xy 208.139538 -126.763272) (xy 208.140046 -126.762764) (xy 208.146632 -126.755384) (xy 208.154089 -126.737085)
			(xy 208.154524 -126.727204) (xy 208.154524 -125.317504) (xy 208.154102 -125.307433) (xy 208.146392 -125.288825)
			(xy 208.139538 -125.281436) (xy 208.033874 -125.175772) (xy 208.02854 -125.169676) (xy 208.009744 -125.16104)
			(xy 207.999838 -125.160532) (xy 207.970893 -125.158519) (xy 207.914063 -125.146835) (xy 207.859657 -125.126682)
			(xy 207.80893 -125.098523) (xy 207.763051 -125.063008) (xy 207.723078 -125.020956) (xy 207.689934 -124.973337)
			(xy 207.664381 -124.921248) (xy 207.64701 -124.865891) (xy 207.63822 -124.808541) (xy 207.637634 -124.779532)
			(xy 207.638111 -124.752164) (xy 207.645944 -124.697991) (xy 207.661439 -124.645494) (xy 207.684279 -124.59575)
			(xy 207.713995 -124.549782) (xy 207.731614 -124.528834) (xy 207.73771 -124.521722) (xy 207.74406 -124.504958)
			(xy 207.74406 -124.419106) (xy 207.73771 -124.402342) (xy 207.731614 -124.39523) (xy 207.71397 -124.374299)
			(xy 207.684239 -124.328334) (xy 207.661391 -124.278588) (xy 207.645896 -124.226084) (xy 207.638073 -124.171903)
			(xy 207.637634 -124.144532) (xy 207.637634 -124.144278) (xy 207.638142 -124.126498) (xy 207.638142 -124.124974)
			(xy 207.638396 -124.119386) (xy 207.636364 -124.107194) (xy 207.634295 -124.097573) (xy 207.623974 -124.080839)
			(xy 207.616298 -124.074682) (xy 207.56753 -124.038868) (xy 207.567276 -124.038614) (xy 207.53705 -124.017024)
			(xy 207.523842 -124.0155) (xy 207.51038 -124.013976) (xy 207.497426 -124.019056) (xy 207.497172 -124.019056)
			(xy 207.47472 -124.027672) (xy 207.42819 -124.03983) (xy 207.380501 -124.046044) (xy 207.356456 -124.046488)
			(xy 207.329087 -124.046013) (xy 207.274912 -124.038183) (xy 207.222412 -124.022691) (xy 207.172666 -123.999854)
			(xy 207.126694 -123.970142) (xy 207.105758 -123.952508) (xy 207.098646 -123.946412) (xy 207.081882 -123.940062)
			(xy 206.99603 -123.940062) (xy 206.979266 -123.946412) (xy 206.972154 -123.952508) (xy 206.951222 -123.970147)
			(xy 206.905254 -123.999867) (xy 206.855507 -124.022704) (xy 206.803004 -124.038187) (xy 206.748825 -124.045999)
			(xy 206.721456 -124.046488) (xy 206.693634 -124.04598) (xy 206.638581 -124.03789) (xy 206.585287 -124.021887)
			(xy 206.534884 -123.998312) (xy 206.48844 -123.967664) (xy 206.446942 -123.930594) (xy 206.411269 -123.887889)
			(xy 206.38218 -123.840454) (xy 206.36029 -123.789296) (xy 206.346064 -123.735501) (xy 206.342488 -123.707906)
			(xy 206.340851 -123.697613) (xy 206.330551 -123.679518) (xy 206.313924 -123.666986) (xy 206.293692 -123.662066)
			(xy 206.273167 -123.665566) (xy 206.255708 -123.67691) (xy 206.249524 -123.6853) (xy 206.242597 -123.695561)
			(xy 206.2276 -123.715262) (xy 206.219552 -123.72467) (xy 206.213456 -123.731782) (xy 206.207106 -123.748546)
			(xy 206.207106 -123.834398) (xy 206.213456 -123.851162) (xy 206.219552 -123.858274) (xy 206.237196 -123.879206)
			(xy 206.266926 -123.925174) (xy 206.289776 -123.974922) (xy 206.305277 -124.027426) (xy 206.31311 -124.081607)
			(xy 206.313113 -124.136351) (xy 206.305286 -124.190533) (xy 206.289791 -124.243039) (xy 206.266946 -124.292789)
			(xy 206.237221 -124.33876) (xy 206.219552 -124.35967) (xy 206.213456 -124.366782) (xy 206.207106 -124.383546)
			(xy 206.207106 -124.469398) (xy 206.213456 -124.486162) (xy 206.219552 -124.493274) (xy 206.237197 -124.514204)
			(xy 206.26693 -124.560169) (xy 206.28978 -124.609915) (xy 206.305276 -124.662419) (xy 206.313099 -124.7166)
			(xy 206.313532 -124.743972) (xy 206.313046 -124.771223) (xy 206.30529 -124.825171) (xy 206.289935 -124.877466)
			(xy 206.267293 -124.927043) (xy 206.237827 -124.972893) (xy 206.202136 -125.014084) (xy 206.160945 -125.049775)
			(xy 206.115095 -125.079241) (xy 206.065518 -125.101883) (xy 206.013223 -125.117238) (xy 205.959275 -125.124994)
			(xy 205.904773 -125.124994) (xy 205.850825 -125.117238) (xy 205.79853 -125.101883) (xy 205.748953 -125.079241)
			(xy 205.703103 -125.049775) (xy 205.661912 -125.014084) (xy 205.626221 -124.972893) (xy 205.596755 -124.927043)
			(xy 205.574113 -124.877466) (xy 205.558758 -124.825171) (xy 205.551002 -124.771223) (xy 205.550516 -124.743972)
			(xy 205.55099 -124.716603) (xy 205.558817 -124.662427) (xy 205.574308 -124.609926) (xy 205.597144 -124.560178)
			(xy 205.626855 -124.514205) (xy 205.644496 -124.493274) (xy 205.650592 -124.486162) (xy 205.656942 -124.469398)
			(xy 205.656942 -124.383546) (xy 205.650592 -124.366782) (xy 205.644496 -124.35967) (xy 205.626859 -124.338737)
			(xy 205.59714 -124.292769) (xy 205.574301 -124.243024) (xy 205.558809 -124.190524) (xy 205.550985 -124.136348)
			(xy 205.550988 -124.08161) (xy 205.558818 -124.027435) (xy 205.574315 -123.974937) (xy 205.59716 -123.925194)
			(xy 205.626884 -123.87923) (xy 205.644496 -123.858274) (xy 205.650592 -123.851162) (xy 205.656942 -123.834398)
			(xy 205.656942 -123.748546) (xy 205.650592 -123.731782) (xy 205.644496 -123.72467) (xy 205.626859 -123.703737)
			(xy 205.59714 -123.657769) (xy 205.574301 -123.608024) (xy 205.558809 -123.555524) (xy 205.550985 -123.501348)
			(xy 205.550988 -123.44661) (xy 205.558818 -123.392435) (xy 205.574315 -123.339937) (xy 205.59716 -123.290194)
			(xy 205.626884 -123.24423) (xy 205.644496 -123.223274) (xy 205.650592 -123.216162) (xy 205.656942 -123.199398)
			(xy 205.656942 -123.113546) (xy 205.650592 -123.096782) (xy 205.644496 -123.08967) (xy 205.626856 -123.068738)
			(xy 205.597134 -123.022771) (xy 205.574295 -122.973024) (xy 205.558809 -122.920521) (xy 205.550995 -122.866342)
			(xy 205.550516 -122.838972) (xy 205.551002 -122.811721) (xy 205.558758 -122.757773) (xy 205.574113 -122.705478)
			(xy 205.596755 -122.655901) (xy 205.626221 -122.610051) (xy 205.661912 -122.56886) (xy 205.703103 -122.533169)
			(xy 205.748953 -122.503703) (xy 205.79853 -122.481061) (xy 205.850825 -122.465706) (xy 205.904773 -122.45795)
			(xy 205.959275 -122.45795) (xy 206.013223 -122.465706) (xy 206.065518 -122.481061) (xy 206.115095 -122.503703)
			(xy 206.160945 -122.533169) (xy 206.202136 -122.56886) (xy 206.237827 -122.610051) (xy 206.267293 -122.655901)
			(xy 206.289935 -122.705478) (xy 206.30529 -122.757773) (xy 206.313046 -122.811721) (xy 206.313532 -122.838972)
			(xy 206.313055 -122.86634) (xy 206.305221 -122.920512) (xy 206.289724 -122.973008) (xy 206.266882 -123.02275)
			(xy 206.237164 -123.068716) (xy 206.219552 -123.08967) (xy 206.213456 -123.096782) (xy 206.207106 -123.113546)
			(xy 206.207106 -123.180602) (xy 206.207193 -123.185277) (xy 206.208861 -123.194477) (xy 206.210408 -123.19889)
			(xy 206.22006 -123.223782) (xy 206.225648 -123.230386) (xy 206.23911 -123.247404) (xy 206.24165 -123.25096)
			(xy 206.25308 -123.267724) (xy 206.265077 -123.286891) (xy 206.284941 -123.327513) (xy 206.292704 -123.34875)
			(xy 206.297022 -123.360942) (xy 206.316072 -123.378214) (xy 206.410814 -123.40082) (xy 206.434944 -123.40082)
			(xy 206.453232 -123.393454) (xy 206.460344 -123.38685) (xy 206.481675 -123.367528) (xy 206.529065 -123.334872)
			(xy 206.580826 -123.30971) (xy 206.63578 -123.292614) (xy 206.69268 -123.283972) (xy 206.721456 -123.283472)
			(xy 206.748824 -123.283948) (xy 206.802997 -123.29178) (xy 206.855495 -123.307276) (xy 206.905238 -123.330116)
			(xy 206.951206 -123.359833) (xy 206.972154 -123.377452) (xy 206.979266 -123.383548) (xy 206.99603 -123.389898)
			(xy 207.081882 -123.389898) (xy 207.098646 -123.383548) (xy 207.105758 -123.377452) (xy 207.126689 -123.359811)
			(xy 207.172656 -123.330088) (xy 207.222403 -123.307249) (xy 207.274907 -123.291765) (xy 207.329086 -123.283953)
			(xy 207.356456 -123.283472) (xy 207.383711 -123.283932) (xy 207.437668 -123.291684) (xy 207.489973 -123.307036)
			(xy 207.53956 -123.329675) (xy 207.58542 -123.359142) (xy 207.626619 -123.394835) (xy 207.66232 -123.436029)
			(xy 207.691794 -123.481884) (xy 207.714442 -123.531467) (xy 207.729803 -123.583769) (xy 207.737564 -123.637725)
			(xy 207.737964 -123.66498) (xy 207.737964 -123.665234) (xy 207.737456 -123.683014) (xy 207.737456 -123.684538)
			(xy 207.737202 -123.690126) (xy 207.739234 -123.702318) (xy 207.74084 -123.710618) (xy 207.748753 -123.725547)
			(xy 207.754728 -123.731528) (xy 207.757014 -123.73356) (xy 207.798416 -123.763532) (xy 207.827372 -123.784614)
			(xy 207.82788 -123.784614) (xy 207.836516 -123.790964) (xy 207.857852 -123.795536) (xy 207.8736 -123.79198)
			(xy 207.877664 -123.790456) (xy 207.90024 -123.78181) (xy 207.947024 -123.769633) (xy 207.994971 -123.763454)
			(xy 208.019142 -123.763024) (xy 208.021682 -123.763024) (xy 208.033112 -123.763278) (xy 208.057976 -123.764597)
			(xy 208.107073 -123.772877) (xy 208.15468 -123.78746) (xy 208.199992 -123.808099) (xy 208.221326 -123.820936)
			(xy 208.24825 -123.82881) (xy 208.254766 -123.828575) (xy 208.267366 -123.825231) (xy 208.273142 -123.822206)
			(xy 208.350612 -123.778772) (xy 208.354422 -123.77547) (xy 208.356454 -123.773946) (xy 208.365598 -123.767088)
			(xy 208.366614 -123.765818) (xy 208.374996 -123.748546) (xy 208.37652 -123.74118) (xy 208.37652 -122.712226)
			(xy 208.376084 -122.702161) (xy 208.368353 -122.683574) (xy 208.361534 -122.676158) (xy 208.044542 -122.359166)
			(xy 208.03743 -122.3518) (xy 208.018634 -122.34418) (xy 205.507336 -122.34418) (xy 205.497271 -122.343745)
			(xy 205.478686 -122.336012) (xy 205.471268 -122.329194) (xy 204.94879 -121.806716) (xy 204.941947 -121.799317)
			(xy 204.934229 -121.780718) (xy 204.933804 -121.770648) (xy 204.933804 -118.845076) (xy 204.934232 -118.835008)
			(xy 204.941953 -118.81641) (xy 204.94879 -118.809008) (xy 205.965552 -117.792246) (xy 205.972951 -117.785403)
			(xy 205.99155 -117.77768) (xy 206.00162 -117.77726) (xy 209.453734 -117.77726) (xy 209.46536 -117.776695)
			(xy 209.486264 -117.766515) (xy 209.493866 -117.757702) (xy 209.497676 -117.752622) (xy 209.548222 -117.66423)
			(xy 209.548476 -117.650514) (xy 209.548476 -117.636036) (xy 209.540094 -117.621304) (xy 209.539078 -117.620034)
			(xy 209.538824 -117.619526) (xy 209.53349 -117.609112) (xy 209.529426 -117.600984) (xy 209.516752 -117.574421)
			(xy 209.498809 -117.518368) (xy 209.48966 -117.46023) (xy 209.48904 -117.430804) (xy 209.489574 -117.401888)
			(xy 209.498301 -117.344717) (xy 209.515556 -117.289518) (xy 209.540943 -117.237556) (xy 209.573882 -117.19002)
			(xy 209.613617 -117.147999) (xy 209.636106 -117.129814) (xy 209.644893 -117.122273) (xy 209.65507 -117.101501)
			(xy 209.655664 -117.089936) (xy 209.655664 -117.009672) (xy 209.655048 -116.998116) (xy 209.644862 -116.977362)
			(xy 209.636106 -116.969794) (xy 209.613619 -116.951605) (xy 209.573874 -116.90959) (xy 209.540926 -116.862056)
			(xy 209.515532 -116.810094) (xy 209.498271 -116.754894) (xy 209.48954 -116.697722) (xy 209.48904 -116.668804)
			(xy 209.489526 -116.641553) (xy 209.497282 -116.587605) (xy 209.512637 -116.53531) (xy 209.535279 -116.485733)
			(xy 209.564745 -116.439883) (xy 209.600436 -116.398692) (xy 209.641627 -116.363001) (xy 209.687477 -116.333535)
			(xy 209.737054 -116.310893) (xy 209.789349 -116.295538) (xy 209.843297 -116.287782) (xy 209.897799 -116.287782)
			(xy 209.951747 -116.295538) (xy 210.004042 -116.310893) (xy 210.053619 -116.333535) (xy 210.099469 -116.363001)
			(xy 210.14066 -116.398692) (xy 210.176351 -116.439883) (xy 210.205817 -116.485733) (xy 210.228459 -116.53531)
			(xy 210.243814 -116.587605) (xy 210.25157 -116.641553) (xy 210.252056 -116.668804) (xy 210.251522 -116.69772)
			(xy 210.242793 -116.75489) (xy 210.225537 -116.810088) (xy 210.200149 -116.862049) (xy 210.16721 -116.909584)
			(xy 210.127474 -116.951604) (xy 210.10499 -116.969794) (xy 210.096205 -116.977336) (xy 210.086033 -116.998108)
			(xy 210.085432 -117.009672) (xy 210.085432 -117.089936) (xy 210.086049 -117.101491) (xy 210.096237 -117.122243)
			(xy 210.10499 -117.129814) (xy 210.126742 -117.147385) (xy 210.165366 -117.187819) (xy 210.197684 -117.23345)
			(xy 210.223007 -117.283304) (xy 210.240793 -117.336316) (xy 210.246214 -117.363748) (xy 210.248884 -117.379809)
			(xy 210.251805 -117.412239) (xy 210.252056 -117.428518) (xy 210.252056 -117.431058) (xy 210.251629 -117.456001)
			(xy 210.245093 -117.505459) (xy 210.232178 -117.553646) (xy 210.213104 -117.599743) (xy 210.201002 -117.621558)
			(xy 210.199986 -117.623336) (xy 210.197954 -117.6274) (xy 210.192874 -117.637814) (xy 210.19262 -117.649244)
			(xy 210.192366 -117.663468) (xy 210.243166 -117.75186) (xy 210.247951 -117.759344) (xy 210.261558 -117.77074)
			(xy 210.278234 -117.776818) (xy 210.287108 -117.77726) (xy 211.907374 -117.77726) (xy 211.915756 -117.776498)
			(xy 211.923364 -117.774989) (xy 211.937206 -117.768011) (xy 211.942934 -117.762782) (xy 212.073998 -117.631718)
			(xy 212.074506 -117.63121) (xy 212.081088 -117.623829) (xy 212.088532 -117.605529) (xy 212.088984 -117.59565)
			(xy 212.088984 -116.226844) (xy 212.088612 -116.217413) (xy 212.081796 -116.199827) (xy 212.069072 -116.185904)
			(xy 212.06079 -116.181378) (xy 212.056472 -116.179092) (xy 211.963254 -116.143024) (xy 211.948014 -116.143024)
			(xy 211.942779 -116.143177) (xy 211.932534 -116.145343) (xy 211.927694 -116.147342) (xy 211.918042 -116.15166)
			(xy 211.910676 -116.159534) (xy 211.910422 -116.159788) (xy 211.892296 -116.178986) (xy 211.851664 -116.212702)
			(xy 211.806767 -116.240486) (xy 211.758464 -116.261807) (xy 211.707681 -116.276256) (xy 211.655389 -116.283557)
			(xy 211.62899 -116.283994) (xy 211.601738 -116.28353) (xy 211.547789 -116.275772) (xy 211.495493 -116.260415)
			(xy 211.445915 -116.237771) (xy 211.400064 -116.208303) (xy 211.358874 -116.172609) (xy 211.323183 -116.131417)
			(xy 211.293717 -116.085564) (xy 211.271077 -116.035984) (xy 211.255723 -115.983688) (xy 211.247968 -115.929738)
			(xy 211.247482 -115.902486) (xy 211.247941 -115.875621) (xy 211.25548 -115.822422) (xy 211.270406 -115.770807)
			(xy 211.292424 -115.721796) (xy 211.321099 -115.676358) (xy 211.355865 -115.635391) (xy 211.396033 -115.599706)
			(xy 211.41817 -115.584478) (xy 211.42325 -115.580922) (xy 211.431378 -115.572286) (xy 211.445856 -115.546124)
			(xy 211.448815 -115.5404) (xy 211.452031 -115.527927) (xy 211.452206 -115.521486) (xy 211.452206 -115.267486)
			(xy 211.452019 -115.261046) (xy 211.448809 -115.248573) (xy 211.445856 -115.242848) (xy 211.431378 -115.216686)
			(xy 211.42325 -115.20805) (xy 211.417916 -115.204494) (xy 211.395814 -115.189263) (xy 211.355707 -115.15359)
			(xy 211.320994 -115.11265) (xy 211.29236 -115.067249) (xy 211.270371 -115.018284) (xy 211.255458 -114.966721)
			(xy 211.247918 -114.913578) (xy 211.247482 -114.88674) (xy 211.247482 -114.886486) (xy 211.248047 -114.856435)
			(xy 211.257477 -114.797077) (xy 211.276103 -114.739933) (xy 211.303463 -114.686419) (xy 211.338878 -114.637859)
			(xy 211.35975 -114.61623) (xy 211.366591 -114.60883) (xy 211.374308 -114.590231) (xy 211.374736 -114.580162)
			(xy 211.374736 -114.531394) (xy 211.37431 -114.521326) (xy 211.366587 -114.502729) (xy 211.35975 -114.495326)
			(xy 211.284566 -114.420142) (xy 211.277454 -114.412776) (xy 211.258658 -114.405156) (xy 209.86877 -114.405156)
			(xy 209.858402 -114.405647) (xy 209.839349 -114.413836) (xy 209.82507 -114.428874) (xy 209.821018 -114.43843)
			(xy 209.821018 -114.438684) (xy 209.810555 -114.466055) (xy 209.782505 -114.517501) (xy 209.746935 -114.564065)
			(xy 209.704677 -114.604657) (xy 209.656721 -114.638327) (xy 209.604189 -114.664286) (xy 209.548312 -114.681927)
			(xy 209.490398 -114.690836) (xy 209.4611 -114.691414) (xy 209.431792 -114.690856) (xy 209.37386 -114.681925)
			(xy 209.317965 -114.664271) (xy 209.265413 -114.638306) (xy 209.217431 -114.604638) (xy 209.175138 -114.564052)
			(xy 209.139524 -114.517495) (xy 209.11142 -114.466056) (xy 209.100928 -114.438684) (xy 209.09534 -114.423444)
			(xy 209.069178 -114.405156) (xy 203.51369 -114.405156) (xy 203.503622 -114.405582) (xy 203.485025 -114.413306)
			(xy 203.477622 -114.420142) (xy 203.476352 -114.421412) (xy 203.468955 -114.428261) (xy 203.450356 -114.435992)
			(xy 203.440284 -114.436398) (xy 202.138026 -114.436398) (xy 202.137772 -114.436652) (xy 202.128882 -114.436652)
			(xy 202.100688 -114.461544) (xy 202.098148 -114.480594) (xy 202.094011 -114.507715) (xy 202.078968 -114.560474)
			(xy 202.056524 -114.610535) (xy 202.027142 -114.656866) (xy 201.991428 -114.698511) (xy 201.950118 -114.734612)
			(xy 201.904063 -114.764424) (xy 201.854213 -114.787333) (xy 201.801596 -114.802867) (xy 201.747297 -114.810705)
			(xy 201.692436 -114.810686) (xy 201.638142 -114.80281) (xy 201.585536 -114.787239) (xy 201.535703 -114.764295)
			(xy 201.489669 -114.73445) (xy 201.448384 -114.698321) (xy 201.412699 -114.656651) (xy 201.383349 -114.6103)
			(xy 201.36094 -114.560223) (xy 201.345935 -114.507453) (xy 201.341736 -114.48034) (xy 201.339196 -114.46129)
			(xy 201.311256 -114.436652) (xy 201.302112 -114.436652) (xy 201.301604 -114.436398) (xy 198.29145 -114.436398)
			(xy 198.291196 -114.436652) (xy 198.282306 -114.436652) (xy 198.254112 -114.461544) (xy 198.251572 -114.480594)
			(xy 198.247435 -114.507717) (xy 198.232391 -114.56048) (xy 198.209947 -114.610544) (xy 198.180563 -114.656877)
			(xy 198.144847 -114.698525) (xy 198.103534 -114.734629) (xy 198.057477 -114.764443) (xy 198.007625 -114.787354)
			(xy 197.955005 -114.802889) (xy 197.900702 -114.810728) (xy 197.845837 -114.81071) (xy 197.79154 -114.802834)
			(xy 197.738931 -114.787262) (xy 197.689094 -114.764317) (xy 197.643057 -114.734471) (xy 197.601769 -114.69834)
			(xy 197.566081 -114.656667) (xy 197.53673 -114.610314) (xy 197.514319 -114.560234) (xy 197.499312 -114.507461)
			(xy 197.49516 -114.48034) (xy 197.49262 -114.46129) (xy 197.46468 -114.436652) (xy 197.455536 -114.436652)
			(xy 197.455028 -114.436398) (xy 192.550542 -114.436398) (xy 192.540477 -114.435964) (xy 192.521888 -114.428235)
			(xy 192.514474 -114.421412) (xy 191.523112 -113.43005) (xy 191.516 -113.422684) (xy 191.497204 -113.415064)
			(xy 187.341002 -113.415064) (xy 187.330932 -113.414641) (xy 187.312331 -113.406923) (xy 187.304934 -113.400078)
			(xy 186.814714 -112.909604) (xy 186.807866 -112.902206) (xy 186.800128 -112.883608) (xy 186.799728 -112.873536)
			(xy 186.799728 -108.065824) (xy 186.799245 -108.055811) (xy 186.79159 -108.037306) (xy 186.777437 -108.023139)
			(xy 186.75894 -108.015466) (xy 186.748928 -108.015024) (xy 186.130184 -108.015024) (xy 186.086748 -108.014522)
			(xy 186.000246 -108.006505) (xy 185.914853 -107.990541) (xy 185.831297 -107.966766) (xy 185.750291 -107.935383)
			(xy 185.672526 -107.896659) (xy 185.598666 -107.850926) (xy 185.529341 -107.798573) (xy 185.465142 -107.740047)
			(xy 185.406617 -107.675847) (xy 185.354265 -107.60652) (xy 185.308533 -107.53266) (xy 185.269811 -107.454894)
			(xy 185.238429 -107.373888) (xy 185.214656 -107.290332) (xy 185.198693 -107.204938) (xy 185.190678 -107.118436)
			(xy 185.190678 -107.031564) (xy 185.198693 -106.945062) (xy 185.214656 -106.859668) (xy 185.238429 -106.776112)
			(xy 185.269811 -106.695106) (xy 185.308533 -106.61734) (xy 185.354265 -106.54348) (xy 185.406617 -106.474153)
			(xy 185.465142 -106.409953) (xy 185.529341 -106.351427) (xy 185.598666 -106.299074) (xy 185.672526 -106.253341)
			(xy 185.750291 -106.214617) (xy 185.831297 -106.183234) (xy 185.914853 -106.159459) (xy 186.000246 -106.143495)
			(xy 186.086748 -106.135478) (xy 186.130184 -106.134916) (xy 187.582556 -106.134916) (xy 187.591271 -106.133623)
			(xy 187.607121 -106.12596) (xy 187.613544 -106.11993) (xy 190.689992 -103.043482) (xy 190.697386 -103.036626)
			(xy 190.715985 -103.028875) (xy 190.72606 -103.028496) (xy 190.926212 -103.028496) (xy 190.935356 -103.027734)
			(xy 190.944754 -103.025956) (xy 190.951612 -103.023924) (xy 190.953136 -103.023416) (xy 190.953644 -103.023162)
			(xy 190.985902 -103.013256) (xy 191.012577 -103.006555) (xy 191.067113 -102.999419) (xy 191.094614 -102.999032)
			(xy 191.123037 -102.999483) (xy 191.179366 -103.007132) (xy 191.206882 -103.014272) (xy 191.24041 -103.025194)
			(xy 191.249046 -103.028496) (xy 191.85001 -103.028496) (xy 191.859856 -103.028052) (xy 191.878097 -103.020638)
			(xy 191.89218 -103.006877) (xy 191.896492 -102.998016) (xy 191.92748 -102.926896) (xy 191.92748 -102.926388)
			(xy 191.932814 -102.91445) (xy 191.934816 -102.90961) (xy 191.936992 -102.899366) (xy 191.937132 -102.89413)
			(xy 191.937132 -102.88143) (xy 191.930274 -102.86365) (xy 191.923416 -102.856538) (xy 191.902349 -102.833245)
			(xy 191.866745 -102.781508) (xy 191.839309 -102.725014) (xy 191.820664 -102.665043) (xy 191.81123 -102.602952)
			(xy 191.81064 -102.57155) (xy 191.81064 -102.571296) (xy 191.811126 -102.542836) (xy 191.818876 -102.486445)
			(xy 191.834233 -102.431636) (xy 191.856911 -102.379427) (xy 191.886486 -102.330793) (xy 191.922407 -102.28664)
			(xy 191.964007 -102.247788) (xy 192.010509 -102.214963) (xy 192.061048 -102.188776) (xy 192.114682 -102.169715)
			(xy 192.170412 -102.158134) (xy 192.2272 -102.15425) (xy 192.283988 -102.158134) (xy 192.339718 -102.169715)
			(xy 192.393352 -102.188776) (xy 192.443891 -102.214963) (xy 192.490393 -102.247788) (xy 192.531993 -102.28664)
			(xy 192.567914 -102.330793) (xy 192.597489 -102.379427) (xy 192.620167 -102.431636) (xy 192.635524 -102.486445)
			(xy 192.643274 -102.542836) (xy 192.64376 -102.571296) (xy 192.64376 -102.57155) (xy 192.643183 -102.60306)
			(xy 192.633689 -102.66536) (xy 192.61491 -102.725516) (xy 192.587276 -102.782154) (xy 192.551417 -102.833977)
			(xy 192.530222 -102.8573) (xy 192.523574 -102.864886) (xy 192.516364 -102.883705) (xy 192.516999 -102.903849)
			(xy 192.520824 -102.91318) (xy 192.52692 -102.926388) (xy 192.52692 -102.926896) (xy 192.557654 -102.997762)
			(xy 192.560225 -103.003293) (xy 192.567543 -103.013048) (xy 192.572132 -103.017066) (xy 192.572386 -103.017066)
			(xy 192.579348 -103.022273) (xy 192.595705 -103.028125) (xy 192.60439 -103.028496) (xy 194.178174 -103.028496)
			(xy 194.186556 -103.027734) (xy 194.194165 -103.026227) (xy 194.20801 -103.019252) (xy 194.213734 -103.014018)
			(xy 194.331844 -102.895908) (xy 194.334638 -102.891844) (xy 194.3485 -102.871867) (xy 194.380496 -102.835253)
			(xy 194.416878 -102.802993) (xy 194.436746 -102.788974) (xy 194.438524 -102.787704) (xy 194.44589 -102.781862)
			(xy 194.591432 -102.63632) (xy 194.59194 -102.635812) (xy 194.598518 -102.62843) (xy 194.605958 -102.61013)
			(xy 194.606418 -102.600252) (xy 194.606418 -102.56012) (xy 194.60464 -102.546912) (xy 194.590162 -102.493318)
			(xy 194.587493 -102.484856) (xy 194.577328 -102.470329) (xy 194.562818 -102.460141) (xy 194.554348 -102.457504)
			(xy 194.554094 -102.457504) (xy 194.52731 -102.449912) (xy 194.476121 -102.428035) (xy 194.428652 -102.398952)
			(xy 194.385913 -102.363282) (xy 194.348809 -102.321781) (xy 194.318129 -102.27533) (xy 194.294523 -102.224914)
			(xy 194.278491 -102.171604) (xy 194.270375 -102.11653) (xy 194.269868 -102.088696) (xy 194.270354 -102.061444)
			(xy 194.278111 -102.007496) (xy 194.293466 -101.9552) (xy 194.316107 -101.905622) (xy 194.345573 -101.85977)
			(xy 194.381264 -101.818579) (xy 194.422454 -101.782885) (xy 194.468304 -101.753417) (xy 194.517881 -101.730773)
			(xy 194.570176 -101.715415) (xy 194.624124 -101.707655) (xy 194.651376 -101.707188) (xy 194.679201 -101.707691)
			(xy 194.73426 -101.715775) (xy 194.78756 -101.731774) (xy 194.837969 -101.755349) (xy 194.884417 -101.785999)
			(xy 194.925918 -101.823074) (xy 194.961591 -101.865786) (xy 194.990678 -101.913228) (xy 195.012561 -101.964395)
			(xy 195.020184 -101.99116) (xy 195.021962 -101.998018) (xy 195.028566 -102.009448) (xy 195.033646 -102.014528)
			(xy 195.038429 -102.018992) (xy 195.049747 -102.025548) (xy 195.055998 -102.027482) (xy 195.12026 -102.045008)
			(xy 195.120768 -102.045516) (xy 195.140834 -102.05085) (xy 195.150971 -102.052958) (xy 195.171414 -102.049799)
			(xy 195.180458 -102.044754) (xy 195.186808 -102.040944) (xy 200.09358 -97.134172) (xy 200.094088 -97.133664)
			(xy 200.100669 -97.126282) (xy 200.108121 -97.107984) (xy 200.108566 -97.098104) (xy 200.108566 -77.51064)
			(xy 200.108131 -77.500575) (xy 200.100398 -77.48199) (xy 200.09358 -77.474572) (xy 199.404224 -76.785216)
			(xy 199.397112 -76.77785) (xy 199.378316 -76.77023) (xy 198.730616 -76.77023) (xy 198.72706 -76.770484)
			(xy 198.708772 -76.78166) (xy 198.702422 -76.786232) (xy 198.696326 -76.798932) (xy 198.657464 -76.878942)
			(xy 198.653152 -76.889143) (xy 198.65276 -76.911264) (xy 198.656702 -76.921614) (xy 198.662798 -76.935076)
			(xy 198.666608 -76.940156) (xy 198.681826 -76.960327) (xy 198.707381 -77.003917) (xy 198.726962 -77.050497)
			(xy 198.740228 -77.099254) (xy 198.746946 -77.149334) (xy 198.74738 -77.174598) (xy 198.74738 -77.175106)
			(xy 198.746894 -77.202357) (xy 198.739138 -77.256305) (xy 198.723783 -77.3086) (xy 198.701141 -77.358177)
			(xy 198.671675 -77.404027) (xy 198.635984 -77.445218) (xy 198.594793 -77.480909) (xy 198.548943 -77.510375)
			(xy 198.499366 -77.533017) (xy 198.447071 -77.548372) (xy 198.393123 -77.556128) (xy 198.338621 -77.556128)
			(xy 198.284673 -77.548372) (xy 198.232378 -77.533017) (xy 198.182801 -77.510375) (xy 198.136951 -77.480909)
			(xy 198.09576 -77.445218) (xy 198.060069 -77.404027) (xy 198.030603 -77.358177) (xy 198.007961 -77.3086)
			(xy 197.992606 -77.256305) (xy 197.98485 -77.202357) (xy 197.984364 -77.175106) (xy 197.984364 -77.174598)
			(xy 197.984788 -77.149332) (xy 197.99149 -77.099247) (xy 198.004751 -77.050486) (xy 198.024336 -77.003904)
			(xy 198.049904 -76.960318) (xy 198.065136 -76.940156) (xy 198.068946 -76.935076) (xy 198.075042 -76.921614)
			(xy 198.079019 -76.91127) (xy 198.078623 -76.889138) (xy 198.07428 -76.878942) (xy 198.035418 -76.798932)
			(xy 198.030918 -76.790529) (xy 198.016947 -76.777582) (xy 197.999221 -76.770611) (xy 197.989698 -76.77023)
			(xy 197.449186 -76.77023) (xy 197.439118 -76.770656) (xy 197.42052 -76.778378) (xy 197.413118 -76.785216)
			(xy 195.54952 -78.648814) (xy 195.543424 -78.654656) (xy 195.5419 -78.65618) (xy 195.534534 -78.674722)
			(xy 195.534534 -79.98206) (xy 195.747892 -79.98206) (xy 195.751963 -79.926438) (xy 195.764089 -79.872001)
			(xy 195.784012 -79.81991) (xy 195.811308 -79.771275) (xy 195.845394 -79.727132) (xy 195.885543 -79.688423)
			(xy 195.930901 -79.655972) (xy 195.980501 -79.630471) (xy 196.033285 -79.612464) (xy 196.088128 -79.602334)
			(xy 196.143862 -79.600297) (xy 196.199299 -79.606397) (xy 196.253256 -79.620503) (xy 196.304585 -79.642315)
			(xy 196.352191 -79.671369) (xy 196.395059 -79.707044) (xy 196.432276 -79.748581) (xy 196.463049 -79.795094)
			(xy 196.486721 -79.845591) (xy 196.502789 -79.898998) (xy 196.510909 -79.954174) (xy 196.511418 -79.98206)
			(xy 196.510909 -80.009946) (xy 196.502789 -80.065122) (xy 196.486721 -80.118529) (xy 196.463049 -80.169026)
			(xy 196.432276 -80.215539) (xy 196.395059 -80.257076) (xy 196.352191 -80.292751) (xy 196.304585 -80.321805)
			(xy 196.253256 -80.343617) (xy 196.199299 -80.357723) (xy 196.143862 -80.363823) (xy 196.088128 -80.361786)
			(xy 196.033285 -80.351656) (xy 195.980501 -80.333649) (xy 195.930901 -80.308148) (xy 195.885543 -80.275697)
			(xy 195.845394 -80.236988) (xy 195.811308 -80.192845) (xy 195.784012 -80.14421) (xy 195.764089 -80.092119)
			(xy 195.751963 -80.037682) (xy 195.747892 -79.98206) (xy 195.534534 -79.98206) (xy 195.534534 -81.698846)
			(xy 196.961504 -81.698846) (xy 196.965575 -81.643224) (xy 196.977701 -81.588787) (xy 196.997624 -81.536696)
			(xy 197.02492 -81.488061) (xy 197.059006 -81.443918) (xy 197.099155 -81.405209) (xy 197.144513 -81.372758)
			(xy 197.194113 -81.347257) (xy 197.246897 -81.32925) (xy 197.30174 -81.31912) (xy 197.357474 -81.317083)
			(xy 197.412911 -81.323183) (xy 197.466868 -81.337289) (xy 197.518197 -81.359101) (xy 197.565803 -81.388155)
			(xy 197.608671 -81.42383) (xy 197.645888 -81.465367) (xy 197.676661 -81.51188) (xy 197.700333 -81.562377)
			(xy 197.716401 -81.615784) (xy 197.724521 -81.67096) (xy 197.72503 -81.698846) (xy 197.724521 -81.726732)
			(xy 197.716401 -81.781908) (xy 197.700333 -81.835315) (xy 197.676661 -81.885812) (xy 197.645888 -81.932325)
			(xy 197.608671 -81.973862) (xy 197.565803 -82.009537) (xy 197.518197 -82.038591) (xy 197.466868 -82.060403)
			(xy 197.412911 -82.074509) (xy 197.357474 -82.080609) (xy 197.30174 -82.078572) (xy 197.246897 -82.068442)
			(xy 197.194113 -82.050435) (xy 197.144513 -82.024934) (xy 197.099155 -81.992483) (xy 197.059006 -81.953774)
			(xy 197.02492 -81.909631) (xy 196.997624 -81.860996) (xy 196.977701 -81.808905) (xy 196.965575 -81.754468)
			(xy 196.961504 -81.698846) (xy 195.534534 -81.698846) (xy 195.534534 -82.04581) (xy 195.551044 -82.070956)
			(xy 195.565268 -82.077052) (xy 195.590602 -82.088487) (xy 195.637942 -82.117611) (xy 195.680555 -82.153296)
			(xy 195.717539 -82.194786) (xy 195.748113 -82.241203) (xy 195.771628 -82.291565) (xy 195.787587 -82.344805)
			(xy 195.795653 -82.399798) (xy 195.795655 -82.45538) (xy 195.787592 -82.510373) (xy 195.771636 -82.563615)
			(xy 195.748124 -82.613978) (xy 195.717553 -82.660396) (xy 195.680571 -82.701889) (xy 195.63796 -82.737576)
			(xy 195.590622 -82.766703) (xy 195.565268 -82.778092) (xy 195.551044 -82.784188) (xy 195.534534 -82.809334)
			(xy 195.534534 -84.476336) (xy 195.74713 -84.476336) (xy 195.751201 -84.420714) (xy 195.763327 -84.366277)
			(xy 195.78325 -84.314186) (xy 195.810546 -84.265551) (xy 195.844632 -84.221408) (xy 195.884781 -84.182699)
			(xy 195.930139 -84.150248) (xy 195.979739 -84.124747) (xy 196.032523 -84.10674) (xy 196.087366 -84.09661)
			(xy 196.1431 -84.094573) (xy 196.198537 -84.100673) (xy 196.252494 -84.114779) (xy 196.303823 -84.136591)
			(xy 196.351429 -84.165645) (xy 196.394297 -84.20132) (xy 196.431514 -84.242857) (xy 196.462287 -84.28937)
			(xy 196.485959 -84.339867) (xy 196.502027 -84.393274) (xy 196.510147 -84.44845) (xy 196.510656 -84.476336)
			(xy 196.510147 -84.504222) (xy 196.502027 -84.559398) (xy 196.485959 -84.612805) (xy 196.462287 -84.663302)
			(xy 196.431514 -84.709815) (xy 196.394297 -84.751352) (xy 196.351429 -84.787027) (xy 196.303823 -84.816081)
			(xy 196.252494 -84.837893) (xy 196.198537 -84.851999) (xy 196.1431 -84.858099) (xy 196.087366 -84.856062)
			(xy 196.032523 -84.845932) (xy 195.979739 -84.827925) (xy 195.930139 -84.802424) (xy 195.884781 -84.769973)
			(xy 195.844632 -84.731264) (xy 195.810546 -84.687121) (xy 195.78325 -84.638486) (xy 195.763327 -84.586395)
			(xy 195.751201 -84.531958) (xy 195.74713 -84.476336) (xy 195.534534 -84.476336) (xy 195.534534 -85.426296)
			(xy 195.957442 -85.426296) (xy 195.961513 -85.370674) (xy 195.973639 -85.316237) (xy 195.993562 -85.264146)
			(xy 196.020858 -85.215511) (xy 196.054944 -85.171368) (xy 196.095093 -85.132659) (xy 196.140451 -85.100208)
			(xy 196.190051 -85.074707) (xy 196.242835 -85.0567) (xy 196.297678 -85.04657) (xy 196.353412 -85.044533)
			(xy 196.408849 -85.050633) (xy 196.462806 -85.064739) (xy 196.514135 -85.086551) (xy 196.561741 -85.115605)
			(xy 196.604609 -85.15128) (xy 196.641826 -85.192817) (xy 196.672599 -85.23933) (xy 196.696271 -85.289827)
			(xy 196.712339 -85.343234) (xy 196.720459 -85.39841) (xy 196.720968 -85.426296) (xy 196.720459 -85.454182)
			(xy 196.712339 -85.509358) (xy 196.696271 -85.562765) (xy 196.672599 -85.613262) (xy 196.641826 -85.659775)
			(xy 196.604609 -85.701312) (xy 196.561741 -85.736987) (xy 196.514135 -85.766041) (xy 196.462806 -85.787853)
			(xy 196.408849 -85.801959) (xy 196.353412 -85.808059) (xy 196.297678 -85.806022) (xy 196.242835 -85.795892)
			(xy 196.190051 -85.777885) (xy 196.140451 -85.752384) (xy 196.095093 -85.719933) (xy 196.054944 -85.681224)
			(xy 196.020858 -85.637081) (xy 195.993562 -85.588446) (xy 195.973639 -85.536355) (xy 195.961513 -85.481918)
			(xy 195.957442 -85.426296) (xy 195.534534 -85.426296) (xy 195.534534 -88.375998) (xy 195.924168 -88.375998)
			(xy 195.928239 -88.320376) (xy 195.940365 -88.265939) (xy 195.960288 -88.213848) (xy 195.987584 -88.165213)
			(xy 196.02167 -88.12107) (xy 196.061819 -88.082361) (xy 196.107177 -88.04991) (xy 196.156777 -88.024409)
			(xy 196.209561 -88.006402) (xy 196.264404 -87.996272) (xy 196.320138 -87.994235) (xy 196.375575 -88.000335)
			(xy 196.429532 -88.014441) (xy 196.480861 -88.036253) (xy 196.528467 -88.065307) (xy 196.571335 -88.100982)
			(xy 196.608552 -88.142519) (xy 196.639325 -88.189032) (xy 196.662997 -88.239529) (xy 196.679065 -88.292936)
			(xy 196.687185 -88.348112) (xy 196.687694 -88.375998) (xy 196.687332 -88.39581) (xy 197.35749 -88.39581)
			(xy 197.361561 -88.340188) (xy 197.373687 -88.285751) (xy 197.39361 -88.23366) (xy 197.420906 -88.185025)
			(xy 197.454992 -88.140882) (xy 197.495141 -88.102173) (xy 197.540499 -88.069722) (xy 197.590099 -88.044221)
			(xy 197.642883 -88.026214) (xy 197.697726 -88.016084) (xy 197.75346 -88.014047) (xy 197.808897 -88.020147)
			(xy 197.862854 -88.034253) (xy 197.914183 -88.056065) (xy 197.961789 -88.085119) (xy 198.004657 -88.120794)
			(xy 198.041874 -88.162331) (xy 198.072647 -88.208844) (xy 198.096319 -88.259341) (xy 198.112387 -88.312748)
			(xy 198.120507 -88.367924) (xy 198.121016 -88.39581) (xy 198.120507 -88.423696) (xy 198.112387 -88.478872)
			(xy 198.096319 -88.532279) (xy 198.072647 -88.582776) (xy 198.041874 -88.629289) (xy 198.004657 -88.670826)
			(xy 197.961789 -88.706501) (xy 197.914183 -88.735555) (xy 197.862854 -88.757367) (xy 197.808897 -88.771473)
			(xy 197.75346 -88.777573) (xy 197.697726 -88.775536) (xy 197.642883 -88.765406) (xy 197.590099 -88.747399)
			(xy 197.540499 -88.721898) (xy 197.495141 -88.689447) (xy 197.454992 -88.650738) (xy 197.420906 -88.606595)
			(xy 197.39361 -88.55796) (xy 197.373687 -88.505869) (xy 197.361561 -88.451432) (xy 197.35749 -88.39581)
			(xy 196.687332 -88.39581) (xy 196.687185 -88.403884) (xy 196.679065 -88.45906) (xy 196.662997 -88.512467)
			(xy 196.639325 -88.562964) (xy 196.608552 -88.609477) (xy 196.571335 -88.651014) (xy 196.528467 -88.686689)
			(xy 196.480861 -88.715743) (xy 196.429532 -88.737555) (xy 196.375575 -88.751661) (xy 196.320138 -88.757761)
			(xy 196.264404 -88.755724) (xy 196.209561 -88.745594) (xy 196.156777 -88.727587) (xy 196.107177 -88.702086)
			(xy 196.061819 -88.669635) (xy 196.02167 -88.630926) (xy 195.987584 -88.586783) (xy 195.960288 -88.538148)
			(xy 195.940365 -88.486057) (xy 195.928239 -88.43162) (xy 195.924168 -88.375998) (xy 195.534534 -88.375998)
			(xy 195.534534 -89.808655) (xy 196.321335 -89.808655) (xy 196.321335 -89.754145) (xy 196.329093 -89.700188)
			(xy 196.344451 -89.647886) (xy 196.367097 -89.598301) (xy 196.396569 -89.552444) (xy 196.432267 -89.511249)
			(xy 196.473465 -89.475553) (xy 196.519324 -89.446084) (xy 196.56891 -89.423442) (xy 196.621214 -89.408087)
			(xy 196.67517 -89.400333) (xy 196.702426 -89.399872) (xy 196.729329 -89.400325) (xy 196.782599 -89.4079)
			(xy 196.834277 -89.422882) (xy 196.883338 -89.444973) (xy 196.92881 -89.473737) (xy 196.969792 -89.508602)
			(xy 197.00547 -89.548878) (xy 197.020688 -89.571068) (xy 197.028917 -89.58266) (xy 197.050456 -89.601189)
			(xy 197.076269 -89.613062) (xy 197.104354 -89.61736) (xy 197.132536 -89.613749) (xy 197.158631 -89.602509)
			(xy 197.180616 -89.584512) (xy 197.18909 -89.5731) (xy 197.204452 -89.551762) (xy 197.240053 -89.513074)
			(xy 197.280633 -89.479643) (xy 197.325421 -89.452105) (xy 197.373567 -89.430983) (xy 197.42416 -89.416675)
			(xy 197.476238 -89.409455) (xy 197.502526 -89.409016) (xy 197.529778 -89.409456) (xy 197.583726 -89.417216)
			(xy 197.636021 -89.432574) (xy 197.685598 -89.455218) (xy 197.731448 -89.484687) (xy 197.772638 -89.520381)
			(xy 197.808329 -89.561573) (xy 197.837794 -89.607425) (xy 197.860435 -89.657003) (xy 197.87579 -89.709299)
			(xy 197.883546 -89.763248) (xy 197.883546 -89.817752) (xy 197.87579 -89.871701) (xy 197.860435 -89.923997)
			(xy 197.837794 -89.973575) (xy 197.808329 -90.019427) (xy 197.772638 -90.060619) (xy 197.731448 -90.096313)
			(xy 197.685598 -90.125782) (xy 197.636021 -90.148426) (xy 197.583726 -90.163784) (xy 197.529778 -90.171544)
			(xy 197.502526 -90.172032) (xy 197.475625 -90.171537) (xy 197.422357 -90.16397) (xy 197.37068 -90.148995)
			(xy 197.321618 -90.12691) (xy 197.276146 -90.098153) (xy 197.235163 -90.063294) (xy 197.199483 -90.023023)
			(xy 197.184264 -90.000836) (xy 197.176096 -89.989197) (xy 197.154544 -89.970666) (xy 197.128717 -89.958795)
			(xy 197.10062 -89.954502) (xy 197.072427 -89.958122) (xy 197.046325 -89.969374) (xy 197.024336 -89.987385)
			(xy 197.015862 -89.998804) (xy 197.000531 -90.020165) (xy 196.964924 -90.058853) (xy 196.924339 -90.092282)
			(xy 196.879546 -90.119816) (xy 196.831395 -90.140935) (xy 196.780798 -90.155238) (xy 196.728716 -90.162452)
			(xy 196.702426 -90.162888) (xy 196.67517 -90.162467) (xy 196.621214 -90.154713) (xy 196.56891 -90.139358)
			(xy 196.519324 -90.116716) (xy 196.473465 -90.087247) (xy 196.432267 -90.051551) (xy 196.396569 -90.010356)
			(xy 196.367097 -89.964499) (xy 196.344451 -89.914914) (xy 196.329093 -89.862612) (xy 196.321335 -89.808655)
			(xy 195.534534 -89.808655) (xy 195.534534 -92.628212) (xy 195.534107 -92.63828) (xy 195.526382 -92.656875)
			(xy 195.519548 -92.66428) (xy 192.409572 -95.774256) (xy 192.402206 -95.781368) (xy 192.394586 -95.800164)
			(xy 192.394586 -95.834962) (xy 192.398396 -95.844106) (xy 192.40754 -95.86727) (xy 192.420423 -95.915375)
			(xy 192.426937 -95.964748) (xy 192.427352 -95.989648) (xy 192.426863 -96.016898) (xy 192.419101 -96.070843)
			(xy 192.403742 -96.123135) (xy 192.381099 -96.172709) (xy 192.351632 -96.218556) (xy 192.315941 -96.259744)
			(xy 192.274753 -96.295435) (xy 192.228905 -96.324901) (xy 192.179331 -96.347544) (xy 192.127039 -96.362902)
			(xy 192.073094 -96.370663) (xy 192.045844 -96.371156) (xy 192.01933 -96.370683) (xy 191.966818 -96.363305)
			(xy 191.915833 -96.348726) (xy 191.891412 -96.33839) (xy 191.881264 -96.334382) (xy 191.859468 -96.334484)
			(xy 191.839687 -96.343636) (xy 191.83223 -96.351598) (xy 191.493394 -96.690434) (xy 191.490505 -96.693361)
			(xy 191.485652 -96.7) (xy 191.483742 -96.703642) (xy 191.468502 -96.734376) (xy 191.473328 -96.766126)
			(xy 191.48425 -96.77781) (xy 191.503758 -96.799175) (xy 191.5115 -96.810322) (xy 192.124329 -96.810322)
			(xy 192.12839 -96.752242) (xy 192.140495 -96.695292) (xy 192.160408 -96.640581) (xy 192.187742 -96.589175)
			(xy 192.221964 -96.542072) (xy 192.262408 -96.500191) (xy 192.308288 -96.464346) (xy 192.35871 -96.435235)
			(xy 192.412692 -96.413424) (xy 192.469185 -96.399339) (xy 192.527088 -96.393253) (xy 192.585274 -96.395285)
			(xy 192.642612 -96.405395) (xy 192.697984 -96.423387) (xy 192.750314 -96.44891) (xy 192.798582 -96.481467)
			(xy 192.841849 -96.520425) (xy 192.879273 -96.565026) (xy 192.910126 -96.614401) (xy 192.933807 -96.667589)
			(xy 192.949855 -96.723556) (xy 192.957958 -96.781211) (xy 192.958466 -96.810322) (xy 192.957958 -96.839433)
			(xy 192.949855 -96.897088) (xy 192.933807 -96.953055) (xy 192.910126 -97.006243) (xy 192.879273 -97.055618)
			(xy 192.841849 -97.100219) (xy 192.798582 -97.139177) (xy 192.750314 -97.171734) (xy 192.697984 -97.197257)
			(xy 192.642612 -97.215249) (xy 192.585274 -97.225359) (xy 192.527088 -97.227391) (xy 192.469185 -97.221305)
			(xy 192.412692 -97.20722) (xy 192.35871 -97.185409) (xy 192.308288 -97.156298) (xy 192.262408 -97.120453)
			(xy 192.221964 -97.078572) (xy 192.187742 -97.031469) (xy 192.160408 -96.980063) (xy 192.140495 -96.925352)
			(xy 192.12839 -96.868402) (xy 192.124329 -96.810322) (xy 191.5115 -96.810322) (xy 191.536759 -96.846691)
			(xy 191.562217 -96.89864) (xy 191.579549 -96.953835) (xy 191.588358 -97.011013) (xy 191.588898 -97.039938)
			(xy 191.588409 -97.067187) (xy 191.580648 -97.12113) (xy 191.56529 -97.17342) (xy 191.542646 -97.222991)
			(xy 191.513179 -97.268836) (xy 191.477487 -97.310021) (xy 191.436298 -97.345708) (xy 191.390449 -97.375169)
			(xy 191.340875 -97.397806) (xy 191.288583 -97.413158) (xy 191.234639 -97.420913) (xy 191.20739 -97.421446)
			(xy 191.178856 -97.420892) (xy 191.12243 -97.412356) (xy 191.067902 -97.395518) (xy 191.016487 -97.370755)
			(xy 190.969328 -97.338617) (xy 190.948056 -97.319592) (xy 190.941198 -97.313242) (xy 190.922656 -97.305622)
			(xy 190.913643 -97.302309) (xy 190.894457 -97.301913) (xy 190.885318 -97.30486) (xy 190.874904 -97.308924)
			(xy 190.758064 -97.425764) (xy 190.754762 -97.429574) (xy 190.754508 -97.429574) (xy 190.749338 -97.436403)
			(xy 190.743471 -97.452485) (xy 190.743248 -97.469601) (xy 190.745618 -97.477834) (xy 190.746888 -97.481644)
			(xy 190.747904 -97.484184) (xy 190.748412 -97.484946) (xy 190.758826 -97.50948) (xy 190.773521 -97.560713)
			(xy 190.780952 -97.613491) (xy 190.781432 -97.64014) (xy 190.780944 -97.66739) (xy 190.773183 -97.721335)
			(xy 190.757824 -97.773626) (xy 190.735181 -97.8232) (xy 190.705714 -97.869047) (xy 190.670023 -97.910234)
			(xy 190.628834 -97.945924) (xy 190.582986 -97.975389) (xy 190.533411 -97.99803) (xy 190.481119 -98.013386)
			(xy 190.427174 -98.021145) (xy 190.399924 -98.021648) (xy 190.372897 -98.021164) (xy 190.319389 -98.013503)
			(xy 190.267501 -97.998359) (xy 190.242698 -97.987612) (xy 190.242444 -97.987612) (xy 190.232899 -97.983816)
			(xy 190.212383 -97.98339) (xy 190.19335 -97.991062) (xy 190.185802 -97.998026) (xy 190.012828 -98.171)
			(xy 191.663826 -98.171) (xy 191.667897 -98.115378) (xy 191.680023 -98.060941) (xy 191.699946 -98.00885)
			(xy 191.727242 -97.960215) (xy 191.761328 -97.916072) (xy 191.801477 -97.877363) (xy 191.846835 -97.844912)
			(xy 191.896435 -97.819411) (xy 191.949219 -97.801404) (xy 192.004062 -97.791274) (xy 192.059796 -97.789237)
			(xy 192.115233 -97.795337) (xy 192.16919 -97.809443) (xy 192.220519 -97.831255) (xy 192.268125 -97.860309)
			(xy 192.310993 -97.895984) (xy 192.34821 -97.937521) (xy 192.378983 -97.984034) (xy 192.396616 -98.021648)
			(xy 194.269358 -98.021648) (xy 194.273429 -97.966026) (xy 194.285555 -97.911589) (xy 194.305478 -97.859498)
			(xy 194.332774 -97.810863) (xy 194.36686 -97.76672) (xy 194.407009 -97.728011) (xy 194.452367 -97.69556)
			(xy 194.501967 -97.670059) (xy 194.554751 -97.652052) (xy 194.609594 -97.641922) (xy 194.665328 -97.639885)
			(xy 194.720765 -97.645985) (xy 194.774722 -97.660091) (xy 194.826051 -97.681903) (xy 194.873657 -97.710957)
			(xy 194.916525 -97.746632) (xy 194.953742 -97.788169) (xy 194.984515 -97.834682) (xy 195.008187 -97.885179)
			(xy 195.024255 -97.938586) (xy 195.032375 -97.993762) (xy 195.032884 -98.021648) (xy 195.032375 -98.049534)
			(xy 195.024255 -98.10471) (xy 195.008187 -98.158117) (xy 194.984515 -98.208614) (xy 194.953742 -98.255127)
			(xy 194.916525 -98.296664) (xy 194.873657 -98.332339) (xy 194.826051 -98.361393) (xy 194.774722 -98.383205)
			(xy 194.720765 -98.397311) (xy 194.665328 -98.403411) (xy 194.609594 -98.401374) (xy 194.554751 -98.391244)
			(xy 194.501967 -98.373237) (xy 194.452367 -98.347736) (xy 194.407009 -98.315285) (xy 194.36686 -98.276576)
			(xy 194.332774 -98.232433) (xy 194.305478 -98.183798) (xy 194.285555 -98.131707) (xy 194.273429 -98.07727)
			(xy 194.269358 -98.021648) (xy 192.396616 -98.021648) (xy 192.402655 -98.034531) (xy 192.418723 -98.087938)
			(xy 192.426843 -98.143114) (xy 192.427352 -98.171) (xy 192.426843 -98.198886) (xy 192.418723 -98.254062)
			(xy 192.402655 -98.307469) (xy 192.378983 -98.357966) (xy 192.34821 -98.404479) (xy 192.310993 -98.446016)
			(xy 192.268125 -98.481691) (xy 192.220519 -98.510745) (xy 192.16919 -98.532557) (xy 192.115233 -98.546663)
			(xy 192.059796 -98.552763) (xy 192.004062 -98.550726) (xy 191.949219 -98.540596) (xy 191.896435 -98.522589)
			(xy 191.846835 -98.497088) (xy 191.801477 -98.464637) (xy 191.761328 -98.425928) (xy 191.727242 -98.381785)
			(xy 191.699946 -98.33315) (xy 191.680023 -98.281059) (xy 191.667897 -98.226622) (xy 191.663826 -98.171)
			(xy 190.012828 -98.171) (xy 189.14618 -99.037648) (xy 194.269358 -99.037648) (xy 194.273429 -98.982026)
			(xy 194.285555 -98.927589) (xy 194.305478 -98.875498) (xy 194.332774 -98.826863) (xy 194.36686 -98.78272)
			(xy 194.407009 -98.744011) (xy 194.452367 -98.71156) (xy 194.501967 -98.686059) (xy 194.554751 -98.668052)
			(xy 194.609594 -98.657922) (xy 194.665328 -98.655885) (xy 194.720765 -98.661985) (xy 194.774722 -98.676091)
			(xy 194.826051 -98.697903) (xy 194.873657 -98.726957) (xy 194.916525 -98.762632) (xy 194.953742 -98.804169)
			(xy 194.984515 -98.850682) (xy 195.008187 -98.901179) (xy 195.024255 -98.954586) (xy 195.032375 -99.009762)
			(xy 195.032884 -99.037648) (xy 195.032375 -99.065534) (xy 195.024255 -99.12071) (xy 195.008187 -99.174117)
			(xy 194.984515 -99.224614) (xy 194.953742 -99.271127) (xy 194.916525 -99.312664) (xy 194.873657 -99.348339)
			(xy 194.826051 -99.377393) (xy 194.774722 -99.399205) (xy 194.720765 -99.413311) (xy 194.665328 -99.419411)
			(xy 194.609594 -99.417374) (xy 194.554751 -99.407244) (xy 194.501967 -99.389237) (xy 194.452367 -99.363736)
			(xy 194.407009 -99.331285) (xy 194.36686 -99.292576) (xy 194.332774 -99.248433) (xy 194.305478 -99.199798)
			(xy 194.285555 -99.147707) (xy 194.273429 -99.09327) (xy 194.269358 -99.037648) (xy 189.14618 -99.037648)
			(xy 188.743844 -99.439984) (xy 191.409826 -99.439984) (xy 191.413897 -99.384362) (xy 191.426023 -99.329925)
			(xy 191.445946 -99.277834) (xy 191.473242 -99.229199) (xy 191.507328 -99.185056) (xy 191.547477 -99.146347)
			(xy 191.592835 -99.113896) (xy 191.642435 -99.088395) (xy 191.695219 -99.070388) (xy 191.750062 -99.060258)
			(xy 191.805796 -99.058221) (xy 191.861233 -99.064321) (xy 191.91519 -99.078427) (xy 191.966519 -99.100239)
			(xy 192.014125 -99.129293) (xy 192.056993 -99.164968) (xy 192.09421 -99.206505) (xy 192.124983 -99.253018)
			(xy 192.148655 -99.303515) (xy 192.164723 -99.356922) (xy 192.172843 -99.412098) (xy 192.173352 -99.439984)
			(xy 192.172843 -99.46787) (xy 192.164723 -99.523046) (xy 192.148655 -99.576453) (xy 192.124983 -99.62695)
			(xy 192.09421 -99.673463) (xy 192.056993 -99.715) (xy 192.014125 -99.750675) (xy 191.966519 -99.779729)
			(xy 191.91519 -99.801541) (xy 191.861233 -99.815647) (xy 191.805796 -99.821747) (xy 191.750062 -99.81971)
			(xy 191.695219 -99.80958) (xy 191.642435 -99.791573) (xy 191.592835 -99.766072) (xy 191.547477 -99.733621)
			(xy 191.507328 -99.694912) (xy 191.473242 -99.650769) (xy 191.445946 -99.602134) (xy 191.426023 -99.550043)
			(xy 191.413897 -99.495606) (xy 191.409826 -99.439984) (xy 188.743844 -99.439984) (xy 188.202062 -99.981766)
			(xy 188.194663 -99.98861) (xy 188.176065 -99.996336) (xy 188.165994 -99.996752) (xy 187.012326 -99.996752)
			(xy 186.983878 -100.021136) (xy 186.981084 -100.039932) (xy 189.976758 -100.039932) (xy 189.980829 -99.98431)
			(xy 189.992955 -99.929873) (xy 190.012878 -99.877782) (xy 190.040174 -99.829147) (xy 190.07426 -99.785004)
			(xy 190.114409 -99.746295) (xy 190.159767 -99.713844) (xy 190.209367 -99.688343) (xy 190.262151 -99.670336)
			(xy 190.316994 -99.660206) (xy 190.372728 -99.658169) (xy 190.428165 -99.664269) (xy 190.482122 -99.678375)
			(xy 190.533451 -99.700187) (xy 190.581057 -99.729241) (xy 190.623925 -99.764916) (xy 190.661142 -99.806453)
			(xy 190.691915 -99.852966) (xy 190.715587 -99.903463) (xy 190.731655 -99.95687) (xy 190.739775 -100.012046)
			(xy 190.740284 -100.039932) (xy 190.739775 -100.067818) (xy 190.731655 -100.122994) (xy 190.715587 -100.176401)
			(xy 190.691915 -100.226898) (xy 190.661142 -100.273411) (xy 190.623925 -100.314948) (xy 190.581057 -100.350623)
			(xy 190.533451 -100.379677) (xy 190.482122 -100.401489) (xy 190.428165 -100.415595) (xy 190.372728 -100.421695)
			(xy 190.316994 -100.419658) (xy 190.262151 -100.409528) (xy 190.209367 -100.391521) (xy 190.159767 -100.36602)
			(xy 190.114409 -100.333569) (xy 190.07426 -100.29486) (xy 190.040174 -100.250717) (xy 190.012878 -100.202082)
			(xy 189.992955 -100.149991) (xy 189.980829 -100.095554) (xy 189.976758 -100.039932) (xy 186.981084 -100.039932)
			(xy 186.976553 -100.066661) (xy 186.960925 -100.118572) (xy 186.938107 -100.167747) (xy 186.908556 -100.213197)
			(xy 186.872869 -100.254007) (xy 186.831764 -100.289353) (xy 186.786069 -100.318524) (xy 186.736705 -100.340932)
			(xy 186.684666 -100.356126) (xy 186.631 -100.363801) (xy 186.576788 -100.363801) (xy 186.523122 -100.356126)
			(xy 186.471083 -100.340932) (xy 186.421719 -100.318524) (xy 186.376024 -100.289353) (xy 186.334919 -100.254007)
			(xy 186.299232 -100.213197) (xy 186.269681 -100.167747) (xy 186.246863 -100.118572) (xy 186.231235 -100.066661)
			(xy 186.226704 -100.039932) (xy 186.22391 -100.021136) (xy 186.195462 -99.996752) (xy 174.394368 -99.996752)
			(xy 174.384462 -100.00107) (xy 174.369222 -100.007674) (xy 174.361348 -100.011992) (xy 174.35068 -100.019104)
			(xy 174.347124 -100.02266) (xy 174.327885 -100.040902) (xy 174.285264 -100.072432) (xy 174.238683 -100.097747)
			(xy 174.214028 -100.107496) (xy 174.181662 -100.118831) (xy 174.1142 -100.131105) (xy 174.079916 -100.13188)
			(xy 174.074582 -100.13188) (xy 174.040292 -100.129848) (xy 174.017664 -100.127168) (xy 173.97322 -100.117112)
			(xy 173.951646 -100.109782) (xy 173.937676 -100.104702) (xy 173.908974 -100.111306) (xy 173.197266 -100.823014)
			(xy 173.190415 -100.83041) (xy 173.182675 -100.849009) (xy 173.18228 -100.859082) (xy 173.18228 -101.240082)
			(xy 183.371742 -101.240082) (xy 183.375813 -101.18446) (xy 183.387939 -101.130023) (xy 183.407862 -101.077932)
			(xy 183.435158 -101.029297) (xy 183.469244 -100.985154) (xy 183.509393 -100.946445) (xy 183.554751 -100.913994)
			(xy 183.604351 -100.888493) (xy 183.657135 -100.870486) (xy 183.711978 -100.860356) (xy 183.767712 -100.858319)
			(xy 183.823149 -100.864419) (xy 183.877106 -100.878525) (xy 183.928435 -100.900337) (xy 183.976041 -100.929391)
			(xy 184.018909 -100.965066) (xy 184.056126 -101.006603) (xy 184.086899 -101.053116) (xy 184.110571 -101.103613)
			(xy 184.126639 -101.15702) (xy 184.134759 -101.212196) (xy 184.135268 -101.240082) (xy 190.393826 -101.240082)
			(xy 190.397897 -101.18446) (xy 190.410023 -101.130023) (xy 190.429946 -101.077932) (xy 190.457242 -101.029297)
			(xy 190.491328 -100.985154) (xy 190.531477 -100.946445) (xy 190.576835 -100.913994) (xy 190.626435 -100.888493)
			(xy 190.679219 -100.870486) (xy 190.734062 -100.860356) (xy 190.789796 -100.858319) (xy 190.845233 -100.864419)
			(xy 190.89919 -100.878525) (xy 190.950519 -100.900337) (xy 190.998125 -100.929391) (xy 191.040993 -100.965066)
			(xy 191.07821 -101.006603) (xy 191.108983 -101.053116) (xy 191.129477 -101.096834) (xy 191.687225 -101.096834)
			(xy 191.687227 -101.04234) (xy 191.694984 -100.988401) (xy 191.710338 -100.936114) (xy 191.732977 -100.886545)
			(xy 191.762439 -100.840703) (xy 191.798126 -100.799519) (xy 191.83931 -100.763834) (xy 191.885154 -100.734372)
			(xy 191.934723 -100.711735) (xy 191.98701 -100.696382) (xy 192.040949 -100.688626) (xy 192.068196 -100.68814)
			(xy 192.06845 -100.68814) (xy 192.081895 -100.688261) (xy 192.108717 -100.690167) (xy 192.122044 -100.69195)
			(xy 192.136738 -100.693613) (xy 192.165979 -100.68927) (xy 192.192754 -100.676741) (xy 192.214824 -100.657073)
			(xy 192.230342 -100.631912) (xy 192.238011 -100.603362) (xy 192.237189 -100.573812) (xy 192.233042 -100.559616)
			(xy 192.223226 -100.527938) (xy 192.212638 -100.462472) (xy 192.21196 -100.429314) (xy 192.212464 -100.400415)
			(xy 192.220447 -100.343172) (xy 192.236263 -100.28758) (xy 192.259607 -100.234706) (xy 192.290032 -100.185565)
			(xy 192.326955 -100.141099) (xy 192.369668 -100.10216) (xy 192.41735 -100.069496) (xy 192.469088 -100.043732)
			(xy 192.52389 -100.025364) (xy 192.580703 -100.014744) (xy 192.638439 -100.012074) (xy 192.69599 -100.017407)
			(xy 192.752253 -100.03064) (xy 192.806147 -100.051519) (xy 192.815441 -100.056696) (xy 194.269358 -100.056696)
			(xy 194.273429 -100.001074) (xy 194.285555 -99.946637) (xy 194.305478 -99.894546) (xy 194.332774 -99.845911)
			(xy 194.36686 -99.801768) (xy 194.407009 -99.763059) (xy 194.452367 -99.730608) (xy 194.501967 -99.705107)
			(xy 194.554751 -99.6871) (xy 194.609594 -99.67697) (xy 194.665328 -99.674933) (xy 194.720765 -99.681033)
			(xy 194.774722 -99.695139) (xy 194.826051 -99.716951) (xy 194.873657 -99.746005) (xy 194.916525 -99.78168)
			(xy 194.953742 -99.823217) (xy 194.984515 -99.86973) (xy 195.008187 -99.920227) (xy 195.024255 -99.973634)
			(xy 195.032375 -100.02881) (xy 195.032884 -100.056696) (xy 195.032375 -100.084582) (xy 195.024255 -100.139758)
			(xy 195.008187 -100.193165) (xy 194.984515 -100.243662) (xy 194.953742 -100.290175) (xy 194.916525 -100.331712)
			(xy 194.873657 -100.367387) (xy 194.826051 -100.396441) (xy 194.774722 -100.418253) (xy 194.720765 -100.432359)
			(xy 194.665328 -100.438459) (xy 194.609594 -100.436422) (xy 194.554751 -100.426292) (xy 194.501967 -100.408285)
			(xy 194.452367 -100.382784) (xy 194.407009 -100.350333) (xy 194.36686 -100.311624) (xy 194.332774 -100.267481)
			(xy 194.305478 -100.218846) (xy 194.285555 -100.166755) (xy 194.273429 -100.112318) (xy 194.269358 -100.056696)
			(xy 192.815441 -100.056696) (xy 192.85664 -100.079645) (xy 192.902763 -100.114476) (xy 192.943632 -100.155346)
			(xy 192.978462 -100.20147) (xy 193.006586 -100.251964) (xy 193.027463 -100.305859) (xy 193.040695 -100.362122)
			(xy 193.046026 -100.419673) (xy 193.043355 -100.477409) (xy 193.032733 -100.534222) (xy 193.014363 -100.589023)
			(xy 192.988598 -100.64076) (xy 192.955933 -100.688442) (xy 192.916993 -100.731153) (xy 192.872525 -100.768075)
			(xy 192.823383 -100.798499) (xy 192.770509 -100.821841) (xy 192.714917 -100.837655) (xy 192.657673 -100.845637)
			(xy 192.628774 -100.846128) (xy 192.609479 -100.845842) (xy 192.571063 -100.842152) (xy 192.552066 -100.838762)
			(xy 192.537439 -100.836553) (xy 192.508032 -100.839614) (xy 192.480734 -100.85097) (xy 192.457832 -100.86967)
			(xy 192.441246 -100.894146) (xy 192.432366 -100.922347) (xy 192.431935 -100.951909) (xy 192.43548 -100.96627)
			(xy 192.442144 -100.991528) (xy 192.449278 -101.043275) (xy 192.449704 -101.069394) (xy 192.449704 -101.069648)
			(xy 192.44917 -101.096895) (xy 192.441409 -101.150833) (xy 192.42605 -101.203118) (xy 192.403406 -101.252685)
			(xy 192.37394 -101.298525) (xy 192.338249 -101.339705) (xy 192.297062 -101.375387) (xy 192.251216 -101.404844)
			(xy 192.201644 -101.427477) (xy 192.149356 -101.442825) (xy 192.095416 -101.450576) (xy 192.040922 -101.450572)
			(xy 191.986984 -101.442812) (xy 191.934698 -101.427456) (xy 191.88513 -101.404815) (xy 191.839289 -101.37535)
			(xy 191.798107 -101.339662) (xy 191.762423 -101.298476) (xy 191.732964 -101.252631) (xy 191.710329 -101.203061)
			(xy 191.694978 -101.150773) (xy 191.687225 -101.096834) (xy 191.129477 -101.096834) (xy 191.132655 -101.103613)
			(xy 191.148723 -101.15702) (xy 191.156843 -101.212196) (xy 191.157352 -101.240082) (xy 191.156843 -101.267968)
			(xy 191.148723 -101.323144) (xy 191.132655 -101.376551) (xy 191.108983 -101.427048) (xy 191.07821 -101.473561)
			(xy 191.040993 -101.515098) (xy 190.998125 -101.550773) (xy 190.950519 -101.579827) (xy 190.89919 -101.601639)
			(xy 190.845233 -101.615745) (xy 190.789796 -101.621845) (xy 190.734062 -101.619808) (xy 190.679219 -101.609678)
			(xy 190.626435 -101.591671) (xy 190.576835 -101.56617) (xy 190.531477 -101.533719) (xy 190.491328 -101.49501)
			(xy 190.457242 -101.450867) (xy 190.429946 -101.402232) (xy 190.410023 -101.350141) (xy 190.397897 -101.295704)
			(xy 190.393826 -101.240082) (xy 184.135268 -101.240082) (xy 184.134759 -101.267968) (xy 184.126639 -101.323144)
			(xy 184.110571 -101.376551) (xy 184.086899 -101.427048) (xy 184.056126 -101.473561) (xy 184.018909 -101.515098)
			(xy 183.976041 -101.550773) (xy 183.928435 -101.579827) (xy 183.877106 -101.601639) (xy 183.823149 -101.615745)
			(xy 183.767712 -101.621845) (xy 183.711978 -101.619808) (xy 183.657135 -101.609678) (xy 183.604351 -101.591671)
			(xy 183.554751 -101.56617) (xy 183.509393 -101.533719) (xy 183.469244 -101.49501) (xy 183.435158 -101.450867)
			(xy 183.407862 -101.402232) (xy 183.387939 -101.350141) (xy 183.375813 -101.295704) (xy 183.371742 -101.240082)
			(xy 173.18228 -101.240082) (xy 173.18228 -101.782372) (xy 173.697644 -101.782372) (xy 173.701715 -101.72675)
			(xy 173.713841 -101.672313) (xy 173.733764 -101.620222) (xy 173.76106 -101.571587) (xy 173.795146 -101.527444)
			(xy 173.835295 -101.488735) (xy 173.880653 -101.456284) (xy 173.930253 -101.430783) (xy 173.983037 -101.412776)
			(xy 174.03788 -101.402646) (xy 174.093614 -101.400609) (xy 174.149051 -101.406709) (xy 174.203008 -101.420815)
			(xy 174.254337 -101.442627) (xy 174.301943 -101.471681) (xy 174.344811 -101.507356) (xy 174.382028 -101.548893)
			(xy 174.412801 -101.595406) (xy 174.436473 -101.645903) (xy 174.452541 -101.69931) (xy 174.460661 -101.754486)
			(xy 174.46117 -101.782372) (xy 174.460661 -101.810258) (xy 174.452541 -101.865434) (xy 174.436473 -101.918841)
			(xy 174.412801 -101.969338) (xy 174.382028 -102.015851) (xy 174.344811 -102.057388) (xy 174.301943 -102.093063)
			(xy 174.254337 -102.122117) (xy 174.203008 -102.143929) (xy 174.149051 -102.158035) (xy 174.093614 -102.164135)
			(xy 174.03788 -102.162098) (xy 173.983037 -102.151968) (xy 173.930253 -102.133961) (xy 173.880653 -102.10846)
			(xy 173.835295 -102.076009) (xy 173.795146 -102.0373) (xy 173.76106 -101.993157) (xy 173.733764 -101.944522)
			(xy 173.713841 -101.892431) (xy 173.701715 -101.837994) (xy 173.697644 -101.782372) (xy 173.18228 -101.782372)
			(xy 173.18228 -102.798372) (xy 173.697644 -102.798372) (xy 173.701715 -102.74275) (xy 173.713841 -102.688313)
			(xy 173.733764 -102.636222) (xy 173.76106 -102.587587) (xy 173.795146 -102.543444) (xy 173.835295 -102.504735)
			(xy 173.880653 -102.472284) (xy 173.930253 -102.446783) (xy 173.983037 -102.428776) (xy 174.03788 -102.418646)
			(xy 174.093614 -102.416609) (xy 174.149051 -102.422709) (xy 174.203008 -102.436815) (xy 174.254337 -102.458627)
			(xy 174.301943 -102.487681) (xy 174.344811 -102.523356) (xy 174.382028 -102.564893) (xy 174.412801 -102.611406)
			(xy 174.436473 -102.661903) (xy 174.448186 -102.700836) (xy 181.842662 -102.700836) (xy 181.846733 -102.645214)
			(xy 181.858859 -102.590777) (xy 181.878782 -102.538686) (xy 181.906078 -102.490051) (xy 181.940164 -102.445908)
			(xy 181.980313 -102.407199) (xy 182.025671 -102.374748) (xy 182.075271 -102.349247) (xy 182.128055 -102.33124)
			(xy 182.182898 -102.32111) (xy 182.238632 -102.319073) (xy 182.294069 -102.325173) (xy 182.348026 -102.339279)
			(xy 182.399355 -102.361091) (xy 182.446961 -102.390145) (xy 182.489829 -102.42582) (xy 182.502515 -102.439978)
			(xy 183.03062 -102.439978) (xy 183.034691 -102.384356) (xy 183.046817 -102.329919) (xy 183.06674 -102.277828)
			(xy 183.094036 -102.229193) (xy 183.128122 -102.18505) (xy 183.168271 -102.146341) (xy 183.213629 -102.11389)
			(xy 183.263229 -102.088389) (xy 183.316013 -102.070382) (xy 183.370856 -102.060252) (xy 183.42659 -102.058215)
			(xy 183.482027 -102.064315) (xy 183.535984 -102.078421) (xy 183.587313 -102.100233) (xy 183.634919 -102.129287)
			(xy 183.677787 -102.164962) (xy 183.715004 -102.206499) (xy 183.745777 -102.253012) (xy 183.769449 -102.303509)
			(xy 183.785517 -102.356916) (xy 183.793637 -102.412092) (xy 183.794146 -102.439978) (xy 190.012826 -102.439978)
			(xy 190.016897 -102.384356) (xy 190.029023 -102.329919) (xy 190.048946 -102.277828) (xy 190.076242 -102.229193)
			(xy 190.110328 -102.18505) (xy 190.150477 -102.146341) (xy 190.195835 -102.11389) (xy 190.245435 -102.088389)
			(xy 190.298219 -102.070382) (xy 190.353062 -102.060252) (xy 190.408796 -102.058215) (xy 190.464233 -102.064315)
			(xy 190.51819 -102.078421) (xy 190.569519 -102.100233) (xy 190.617125 -102.129287) (xy 190.659993 -102.164962)
			(xy 190.69721 -102.206499) (xy 190.727983 -102.253012) (xy 190.751655 -102.303509) (xy 190.767723 -102.356916)
			(xy 190.775843 -102.412092) (xy 190.776352 -102.439978) (xy 190.775843 -102.467864) (xy 190.772733 -102.489)
			(xy 190.901826 -102.489) (xy 190.905897 -102.433378) (xy 190.918023 -102.378941) (xy 190.937946 -102.32685)
			(xy 190.965242 -102.278215) (xy 190.999328 -102.234072) (xy 191.039477 -102.195363) (xy 191.084835 -102.162912)
			(xy 191.134435 -102.137411) (xy 191.187219 -102.119404) (xy 191.242062 -102.109274) (xy 191.297796 -102.107237)
			(xy 191.353233 -102.113337) (xy 191.40719 -102.127443) (xy 191.458519 -102.149255) (xy 191.506125 -102.178309)
			(xy 191.548993 -102.213984) (xy 191.58621 -102.255521) (xy 191.616983 -102.302034) (xy 191.640655 -102.352531)
			(xy 191.656723 -102.405938) (xy 191.664843 -102.461114) (xy 191.665352 -102.489) (xy 191.664843 -102.516886)
			(xy 191.656723 -102.572062) (xy 191.640655 -102.625469) (xy 191.616983 -102.675966) (xy 191.58621 -102.722479)
			(xy 191.548993 -102.764016) (xy 191.506125 -102.799691) (xy 191.458519 -102.828745) (xy 191.40719 -102.850557)
			(xy 191.353233 -102.864663) (xy 191.297796 -102.870763) (xy 191.242062 -102.868726) (xy 191.187219 -102.858596)
			(xy 191.134435 -102.840589) (xy 191.084835 -102.815088) (xy 191.039477 -102.782637) (xy 190.999328 -102.743928)
			(xy 190.965242 -102.699785) (xy 190.937946 -102.65115) (xy 190.918023 -102.599059) (xy 190.905897 -102.544622)
			(xy 190.901826 -102.489) (xy 190.772733 -102.489) (xy 190.767723 -102.52304) (xy 190.751655 -102.576447)
			(xy 190.727983 -102.626944) (xy 190.69721 -102.673457) (xy 190.659993 -102.714994) (xy 190.617125 -102.750669)
			(xy 190.569519 -102.779723) (xy 190.51819 -102.801535) (xy 190.464233 -102.815641) (xy 190.408796 -102.821741)
			(xy 190.353062 -102.819704) (xy 190.298219 -102.809574) (xy 190.245435 -102.791567) (xy 190.195835 -102.766066)
			(xy 190.150477 -102.733615) (xy 190.110328 -102.694906) (xy 190.076242 -102.650763) (xy 190.048946 -102.602128)
			(xy 190.029023 -102.550037) (xy 190.016897 -102.4956) (xy 190.012826 -102.439978) (xy 183.794146 -102.439978)
			(xy 183.793637 -102.467864) (xy 183.785517 -102.52304) (xy 183.769449 -102.576447) (xy 183.745777 -102.626944)
			(xy 183.715004 -102.673457) (xy 183.677787 -102.714994) (xy 183.634919 -102.750669) (xy 183.587313 -102.779723)
			(xy 183.535984 -102.801535) (xy 183.482027 -102.815641) (xy 183.42659 -102.821741) (xy 183.370856 -102.819704)
			(xy 183.316013 -102.809574) (xy 183.263229 -102.791567) (xy 183.213629 -102.766066) (xy 183.168271 -102.733615)
			(xy 183.128122 -102.694906) (xy 183.094036 -102.650763) (xy 183.06674 -102.602128) (xy 183.046817 -102.550037)
			(xy 183.034691 -102.4956) (xy 183.03062 -102.439978) (xy 182.502515 -102.439978) (xy 182.527046 -102.467357)
			(xy 182.557819 -102.51387) (xy 182.581491 -102.564367) (xy 182.597559 -102.617774) (xy 182.605679 -102.67295)
			(xy 182.606188 -102.700836) (xy 182.605679 -102.728722) (xy 182.597559 -102.783898) (xy 182.581491 -102.837305)
			(xy 182.557819 -102.887802) (xy 182.527046 -102.934315) (xy 182.489829 -102.975852) (xy 182.446961 -103.011527)
			(xy 182.399355 -103.040581) (xy 182.348026 -103.062393) (xy 182.294069 -103.076499) (xy 182.238632 -103.082599)
			(xy 182.182898 -103.080562) (xy 182.128055 -103.070432) (xy 182.075271 -103.052425) (xy 182.025671 -103.026924)
			(xy 181.980313 -102.994473) (xy 181.940164 -102.955764) (xy 181.906078 -102.911621) (xy 181.878782 -102.862986)
			(xy 181.858859 -102.810895) (xy 181.846733 -102.756458) (xy 181.842662 -102.700836) (xy 174.448186 -102.700836)
			(xy 174.452541 -102.71531) (xy 174.460661 -102.770486) (xy 174.46117 -102.798372) (xy 174.460661 -102.826258)
			(xy 174.452541 -102.881434) (xy 174.436473 -102.934841) (xy 174.412801 -102.985338) (xy 174.382028 -103.031851)
			(xy 174.344811 -103.073388) (xy 174.301943 -103.109063) (xy 174.254337 -103.138117) (xy 174.203008 -103.159929)
			(xy 174.149051 -103.174035) (xy 174.093614 -103.180135) (xy 174.03788 -103.178098) (xy 173.983037 -103.167968)
			(xy 173.930253 -103.149961) (xy 173.880653 -103.12446) (xy 173.835295 -103.092009) (xy 173.795146 -103.0533)
			(xy 173.76106 -103.009157) (xy 173.733764 -102.960522) (xy 173.713841 -102.908431) (xy 173.701715 -102.853994)
			(xy 173.697644 -102.798372) (xy 173.18228 -102.798372) (xy 173.18228 -103.814372) (xy 173.697644 -103.814372)
			(xy 173.701715 -103.75875) (xy 173.713841 -103.704313) (xy 173.733764 -103.652222) (xy 173.76106 -103.603587)
			(xy 173.795146 -103.559444) (xy 173.835295 -103.520735) (xy 173.880653 -103.488284) (xy 173.930253 -103.462783)
			(xy 173.983037 -103.444776) (xy 174.03788 -103.434646) (xy 174.093614 -103.432609) (xy 174.149051 -103.438709)
			(xy 174.203008 -103.452815) (xy 174.254337 -103.474627) (xy 174.301943 -103.503681) (xy 174.344811 -103.539356)
			(xy 174.382028 -103.580893) (xy 174.412801 -103.627406) (xy 174.436473 -103.677903) (xy 174.452541 -103.73131)
			(xy 174.460661 -103.786486) (xy 174.46117 -103.814372) (xy 174.460661 -103.842258) (xy 174.452541 -103.897434)
			(xy 174.436473 -103.950841) (xy 174.412801 -104.001338) (xy 174.382028 -104.047851) (xy 174.344811 -104.089388)
			(xy 174.301943 -104.125063) (xy 174.254337 -104.154117) (xy 174.203008 -104.175929) (xy 174.149051 -104.190035)
			(xy 174.093614 -104.196135) (xy 174.03788 -104.194098) (xy 173.983037 -104.183968) (xy 173.930253 -104.165961)
			(xy 173.880653 -104.14046) (xy 173.835295 -104.108009) (xy 173.795146 -104.0693) (xy 173.76106 -104.025157)
			(xy 173.733764 -103.976522) (xy 173.713841 -103.924431) (xy 173.701715 -103.869994) (xy 173.697644 -103.814372)
			(xy 173.18228 -103.814372) (xy 173.18228 -104.384856) (xy 181.762652 -104.384856) (xy 181.766723 -104.329234)
			(xy 181.778849 -104.274797) (xy 181.798772 -104.222706) (xy 181.826068 -104.174071) (xy 181.860154 -104.129928)
			(xy 181.900303 -104.091219) (xy 181.945661 -104.058768) (xy 181.995261 -104.033267) (xy 182.048045 -104.01526)
			(xy 182.102888 -104.00513) (xy 182.158622 -104.003093) (xy 182.214059 -104.009193) (xy 182.268016 -104.023299)
			(xy 182.319345 -104.045111) (xy 182.366951 -104.074165) (xy 182.409819 -104.10984) (xy 182.447036 -104.151377)
			(xy 182.477809 -104.19789) (xy 182.497585 -104.240076) (xy 183.03062 -104.240076) (xy 183.034691 -104.184454)
			(xy 183.046817 -104.130017) (xy 183.06674 -104.077926) (xy 183.094036 -104.029291) (xy 183.128122 -103.985148)
			(xy 183.168271 -103.946439) (xy 183.213629 -103.913988) (xy 183.263229 -103.888487) (xy 183.316013 -103.87048)
			(xy 183.370856 -103.86035) (xy 183.42659 -103.858313) (xy 183.482027 -103.864413) (xy 183.535984 -103.878519)
			(xy 183.587313 -103.900331) (xy 183.634919 -103.929385) (xy 183.677787 -103.96506) (xy 183.715004 -104.006597)
			(xy 183.745777 -104.05311) (xy 183.769449 -104.103607) (xy 183.785517 -104.157014) (xy 183.793637 -104.21219)
			(xy 183.794146 -104.240076) (xy 183.793637 -104.267962) (xy 183.785517 -104.323138) (xy 183.769449 -104.376545)
			(xy 183.745777 -104.427042) (xy 183.715004 -104.473555) (xy 183.677787 -104.515092) (xy 183.634919 -104.550767)
			(xy 183.587313 -104.579821) (xy 183.535984 -104.601633) (xy 183.482027 -104.615739) (xy 183.42659 -104.621839)
			(xy 183.370856 -104.619802) (xy 183.316013 -104.609672) (xy 183.263229 -104.591665) (xy 183.213629 -104.566164)
			(xy 183.168271 -104.533713) (xy 183.128122 -104.495004) (xy 183.094036 -104.450861) (xy 183.06674 -104.402226)
			(xy 183.046817 -104.350135) (xy 183.034691 -104.295698) (xy 183.03062 -104.240076) (xy 182.497585 -104.240076)
			(xy 182.501481 -104.248387) (xy 182.517549 -104.301794) (xy 182.525669 -104.35697) (xy 182.526178 -104.384856)
			(xy 182.525669 -104.412742) (xy 182.517549 -104.467918) (xy 182.501481 -104.521325) (xy 182.477809 -104.571822)
			(xy 182.447036 -104.618335) (xy 182.409819 -104.659872) (xy 182.366951 -104.695547) (xy 182.319345 -104.724601)
			(xy 182.268016 -104.746413) (xy 182.214059 -104.760519) (xy 182.158622 -104.766619) (xy 182.102888 -104.764582)
			(xy 182.048045 -104.754452) (xy 181.995261 -104.736445) (xy 181.945661 -104.710944) (xy 181.900303 -104.678493)
			(xy 181.860154 -104.639784) (xy 181.826068 -104.595641) (xy 181.798772 -104.547006) (xy 181.778849 -104.494915)
			(xy 181.766723 -104.440478) (xy 181.762652 -104.384856) (xy 173.18228 -104.384856) (xy 173.18228 -104.830372)
			(xy 173.697644 -104.830372) (xy 173.701715 -104.77475) (xy 173.713841 -104.720313) (xy 173.733764 -104.668222)
			(xy 173.76106 -104.619587) (xy 173.795146 -104.575444) (xy 173.835295 -104.536735) (xy 173.880653 -104.504284)
			(xy 173.930253 -104.478783) (xy 173.983037 -104.460776) (xy 174.03788 -104.450646) (xy 174.093614 -104.448609)
			(xy 174.149051 -104.454709) (xy 174.203008 -104.468815) (xy 174.254337 -104.490627) (xy 174.301943 -104.519681)
			(xy 174.344811 -104.555356) (xy 174.382028 -104.596893) (xy 174.412801 -104.643406) (xy 174.436473 -104.693903)
			(xy 174.452541 -104.74731) (xy 174.460661 -104.802486) (xy 174.46117 -104.830372) (xy 174.460661 -104.858258)
			(xy 174.452541 -104.913434) (xy 174.436473 -104.966841) (xy 174.412801 -105.017338) (xy 174.382028 -105.063851)
			(xy 174.344811 -105.105388) (xy 174.301943 -105.141063) (xy 174.254337 -105.170117) (xy 174.203008 -105.191929)
			(xy 174.149051 -105.206035) (xy 174.093614 -105.212135) (xy 174.03788 -105.210098) (xy 173.983037 -105.199968)
			(xy 173.930253 -105.181961) (xy 173.880653 -105.15646) (xy 173.835295 -105.124009) (xy 173.795146 -105.0853)
			(xy 173.76106 -105.041157) (xy 173.733764 -104.992522) (xy 173.713841 -104.940431) (xy 173.701715 -104.885994)
			(xy 173.697644 -104.830372) (xy 173.18228 -104.830372) (xy 173.18228 -107.11842) (xy 182.937652 -107.11842)
			(xy 182.937652 -107.03152) (xy 182.94567 -106.944991) (xy 182.961638 -106.859571) (xy 182.985419 -106.775989)
			(xy 183.016811 -106.694957) (xy 183.055545 -106.617168) (xy 183.101292 -106.543284) (xy 183.153661 -106.473937)
			(xy 183.212205 -106.409717) (xy 183.276425 -106.351173) (xy 183.345772 -106.298804) (xy 183.419656 -106.253057)
			(xy 183.497445 -106.214323) (xy 183.578477 -106.182931) (xy 183.662059 -106.15915) (xy 183.747479 -106.143182)
			(xy 183.834008 -106.135164) (xy 183.920908 -106.135164) (xy 184.007437 -106.143182) (xy 184.092857 -106.15915)
			(xy 184.176439 -106.182931) (xy 184.257471 -106.214323) (xy 184.33526 -106.253057) (xy 184.409144 -106.298804)
			(xy 184.478491 -106.351173) (xy 184.542711 -106.409717) (xy 184.601255 -106.473937) (xy 184.653624 -106.543284)
			(xy 184.699371 -106.617168) (xy 184.738105 -106.694957) (xy 184.769497 -106.775989) (xy 184.793278 -106.859571)
			(xy 184.809246 -106.944991) (xy 184.817264 -107.03152) (xy 184.817766 -107.07497) (xy 184.817264 -107.11842)
			(xy 184.809246 -107.204949) (xy 184.793278 -107.290369) (xy 184.769497 -107.373951) (xy 184.738105 -107.454983)
			(xy 184.699371 -107.532772) (xy 184.653624 -107.606656) (xy 184.601255 -107.676003) (xy 184.542711 -107.740223)
			(xy 184.478491 -107.798767) (xy 184.409144 -107.851136) (xy 184.33526 -107.896883) (xy 184.257471 -107.935617)
			(xy 184.176439 -107.967009) (xy 184.092857 -107.99079) (xy 184.007437 -108.006758) (xy 183.920908 -108.014776)
			(xy 183.834008 -108.014776) (xy 183.747479 -108.006758) (xy 183.662059 -107.99079) (xy 183.578477 -107.967009)
			(xy 183.497445 -107.935617) (xy 183.419656 -107.896883) (xy 183.345772 -107.851136) (xy 183.276425 -107.798767)
			(xy 183.212205 -107.740223) (xy 183.153661 -107.676003) (xy 183.101292 -107.606656) (xy 183.055545 -107.532772)
			(xy 183.016811 -107.454983) (xy 182.985419 -107.373951) (xy 182.961638 -107.290369) (xy 182.94567 -107.204949)
			(xy 182.937652 -107.11842) (xy 173.18228 -107.11842) (xy 173.18228 -110.361222) (xy 180.725825 -110.361222)
			(xy 180.729886 -110.303142) (xy 180.741991 -110.246192) (xy 180.761904 -110.191481) (xy 180.789238 -110.140075)
			(xy 180.82346 -110.092972) (xy 180.863904 -110.051091) (xy 180.909784 -110.015246) (xy 180.960206 -109.986135)
			(xy 181.014188 -109.964324) (xy 181.070681 -109.950239) (xy 181.128584 -109.944153) (xy 181.18677 -109.946185)
			(xy 181.244108 -109.956295) (xy 181.29948 -109.974287) (xy 181.35181 -109.99981) (xy 181.400078 -110.032367)
			(xy 181.443345 -110.071325) (xy 181.480769 -110.115926) (xy 181.511622 -110.165301) (xy 181.535303 -110.218489)
			(xy 181.551351 -110.274456) (xy 181.559454 -110.332111) (xy 181.559962 -110.361222) (xy 181.559454 -110.390333)
			(xy 181.551351 -110.447988) (xy 181.535303 -110.503955) (xy 181.511622 -110.557143) (xy 181.480769 -110.606518)
			(xy 181.443345 -110.651119) (xy 181.400078 -110.690077) (xy 181.35181 -110.722634) (xy 181.29948 -110.748157)
			(xy 181.244108 -110.766149) (xy 181.18677 -110.776259) (xy 181.128584 -110.778291) (xy 181.070681 -110.772205)
			(xy 181.014188 -110.75812) (xy 180.960206 -110.736309) (xy 180.909784 -110.707198) (xy 180.863904 -110.671353)
			(xy 180.82346 -110.629472) (xy 180.789238 -110.582369) (xy 180.761904 -110.530963) (xy 180.741991 -110.476252)
			(xy 180.729886 -110.419302) (xy 180.725825 -110.361222) (xy 173.18228 -110.361222) (xy 173.18228 -111.334042)
			(xy 180.363874 -111.334042) (xy 180.367945 -111.27842) (xy 180.380071 -111.223983) (xy 180.399994 -111.171892)
			(xy 180.42729 -111.123257) (xy 180.461376 -111.079114) (xy 180.501525 -111.040405) (xy 180.546883 -111.007954)
			(xy 180.596483 -110.982453) (xy 180.649267 -110.964446) (xy 180.70411 -110.954316) (xy 180.759844 -110.952279)
			(xy 180.815281 -110.958379) (xy 180.869238 -110.972485) (xy 180.920567 -110.994297) (xy 180.968173 -111.023351)
			(xy 181.011041 -111.059026) (xy 181.048258 -111.100563) (xy 181.079031 -111.147076) (xy 181.102703 -111.197573)
			(xy 181.118771 -111.25098) (xy 181.126891 -111.306156) (xy 181.1274 -111.334042) (xy 181.126891 -111.361928)
			(xy 181.118771 -111.417104) (xy 181.102703 -111.470511) (xy 181.079031 -111.521008) (xy 181.048258 -111.567521)
			(xy 181.011041 -111.609058) (xy 180.968173 -111.644733) (xy 180.920567 -111.673787) (xy 180.869238 -111.695599)
			(xy 180.815281 -111.709705) (xy 180.759844 -111.715805) (xy 180.70411 -111.713768) (xy 180.649267 -111.703638)
			(xy 180.596483 -111.685631) (xy 180.546883 -111.66013) (xy 180.501525 -111.627679) (xy 180.461376 -111.58897)
			(xy 180.42729 -111.544827) (xy 180.399994 -111.496192) (xy 180.380071 -111.444101) (xy 180.367945 -111.389664)
			(xy 180.363874 -111.334042) (xy 173.18228 -111.334042) (xy 173.18228 -111.784892) (xy 183.268366 -111.784892)
			(xy 183.268811 -111.757521) (xy 183.276632 -111.70334) (xy 183.292125 -111.650836) (xy 183.314971 -111.60109)
			(xy 183.344702 -111.555124) (xy 183.362346 -111.534194) (xy 183.3626 -111.53394) (xy 183.368176 -111.526846)
			(xy 183.374429 -111.509935) (xy 183.374792 -111.50092) (xy 183.374792 -111.433864) (xy 183.374454 -111.424845)
			(xy 183.368193 -111.407928) (xy 183.3626 -111.400844) (xy 183.362346 -111.400844) (xy 183.362346 -111.40059)
			(xy 183.344697 -111.379664) (xy 183.314971 -111.333696) (xy 183.292125 -111.283948) (xy 183.276628 -111.231445)
			(xy 183.2688 -111.177265) (xy 183.268801 -111.122523) (xy 183.276631 -111.068343) (xy 183.292129 -111.01584)
			(xy 183.314977 -110.966094) (xy 183.344704 -110.920126) (xy 183.362346 -110.899194) (xy 183.3626 -110.89894)
			(xy 183.368176 -110.891846) (xy 183.374429 -110.874935) (xy 183.374792 -110.86592) (xy 183.374792 -110.798864)
			(xy 183.374454 -110.789845) (xy 183.368193 -110.772928) (xy 183.3626 -110.765844) (xy 183.362346 -110.765844)
			(xy 183.362346 -110.76559) (xy 183.344697 -110.744664) (xy 183.314971 -110.698696) (xy 183.292125 -110.648948)
			(xy 183.276628 -110.596445) (xy 183.2688 -110.542265) (xy 183.268801 -110.487523) (xy 183.276631 -110.433343)
			(xy 183.292129 -110.38084) (xy 183.314977 -110.331094) (xy 183.344704 -110.285126) (xy 183.362346 -110.264194)
			(xy 183.3626 -110.26394) (xy 183.368176 -110.256846) (xy 183.374429 -110.239935) (xy 183.374792 -110.23092)
			(xy 183.374792 -110.163864) (xy 183.374454 -110.154845) (xy 183.368193 -110.137928) (xy 183.3626 -110.130844)
			(xy 183.362346 -110.130844) (xy 183.362346 -110.13059) (xy 183.344697 -110.109664) (xy 183.314971 -110.063696)
			(xy 183.292125 -110.013948) (xy 183.276628 -109.961445) (xy 183.2688 -109.907265) (xy 183.268801 -109.852523)
			(xy 183.276631 -109.798343) (xy 183.292129 -109.74584) (xy 183.314977 -109.696094) (xy 183.344704 -109.650126)
			(xy 183.362346 -109.629194) (xy 183.3626 -109.62894) (xy 183.368176 -109.621846) (xy 183.374429 -109.604935)
			(xy 183.374792 -109.59592) (xy 183.374792 -109.528864) (xy 183.374454 -109.519845) (xy 183.368193 -109.502928)
			(xy 183.3626 -109.495844) (xy 183.362346 -109.495844) (xy 183.362346 -109.49559) (xy 183.344696 -109.474667)
			(xy 183.314984 -109.428692) (xy 183.29215 -109.378943) (xy 183.276661 -109.32644) (xy 183.268837 -109.272262)
			(xy 183.268366 -109.244892) (xy 183.268852 -109.217641) (xy 183.276608 -109.163693) (xy 183.291963 -109.111398)
			(xy 183.314605 -109.061821) (xy 183.344071 -109.015971) (xy 183.379762 -108.97478) (xy 183.420953 -108.939089)
			(xy 183.466803 -108.909623) (xy 183.51638 -108.886981) (xy 183.568675 -108.871626) (xy 183.622623 -108.86387)
			(xy 183.677125 -108.86387) (xy 183.731073 -108.871626) (xy 183.783368 -108.886981) (xy 183.832945 -108.909623)
			(xy 183.878795 -108.939089) (xy 183.919986 -108.97478) (xy 183.955677 -109.015971) (xy 183.985143 -109.061821)
			(xy 184.007785 -109.111398) (xy 184.02314 -109.163693) (xy 184.030896 -109.217641) (xy 184.031382 -109.244892)
			(xy 184.030916 -109.272262) (xy 184.023099 -109.326442) (xy 184.00761 -109.378945) (xy 183.984768 -109.428692)
			(xy 183.955043 -109.474658) (xy 183.937402 -109.49559) (xy 183.937148 -109.495844) (xy 183.931573 -109.502938)
			(xy 183.92532 -109.519849) (xy 183.924956 -109.528864) (xy 183.924956 -109.59592) (xy 183.925292 -109.604939)
			(xy 183.931553 -109.621857) (xy 183.937148 -109.62894) (xy 183.937402 -109.62894) (xy 183.937402 -109.629194)
			(xy 183.955034 -109.650134) (xy 183.984757 -109.696101) (xy 184.007601 -109.745846) (xy 184.023096 -109.798347)
			(xy 184.030925 -109.852524) (xy 184.030926 -109.907264) (xy 184.023099 -109.961441) (xy 184.007605 -110.013942)
			(xy 183.984762 -110.063688) (xy 183.955041 -110.109657) (xy 183.937402 -110.13059) (xy 183.937148 -110.130844)
			(xy 183.931573 -110.137938) (xy 183.92532 -110.154849) (xy 183.924956 -110.163864) (xy 183.924956 -110.23092)
			(xy 183.925292 -110.239939) (xy 183.931553 -110.256857) (xy 183.937148 -110.26394) (xy 183.937402 -110.26394)
			(xy 183.937402 -110.264194) (xy 183.955034 -110.285134) (xy 183.984757 -110.331101) (xy 184.007601 -110.380846)
			(xy 184.023096 -110.433347) (xy 184.030925 -110.487524) (xy 184.030926 -110.542264) (xy 184.023099 -110.596441)
			(xy 184.007605 -110.648942) (xy 183.984762 -110.698688) (xy 183.955041 -110.744657) (xy 183.937402 -110.76559)
			(xy 183.937148 -110.765844) (xy 183.931573 -110.772938) (xy 183.92532 -110.789849) (xy 183.924956 -110.798864)
			(xy 183.924956 -110.86592) (xy 183.925292 -110.874939) (xy 183.931553 -110.891857) (xy 183.937148 -110.89894)
			(xy 183.937402 -110.89894) (xy 183.937402 -110.899194) (xy 183.955034 -110.920134) (xy 183.984757 -110.966101)
			(xy 184.007601 -111.015846) (xy 184.023096 -111.068347) (xy 184.030925 -111.122524) (xy 184.030926 -111.177264)
			(xy 184.023099 -111.231441) (xy 184.007605 -111.283942) (xy 183.984762 -111.333688) (xy 183.955041 -111.379657)
			(xy 183.937402 -111.40059) (xy 183.937148 -111.400844) (xy 183.931573 -111.407938) (xy 183.92532 -111.424849)
			(xy 183.924956 -111.433864) (xy 183.924956 -111.50092) (xy 183.925292 -111.509939) (xy 183.931553 -111.526857)
			(xy 183.937148 -111.53394) (xy 183.937402 -111.53394) (xy 183.937402 -111.534194) (xy 183.955052 -111.555117)
			(xy 183.984762 -111.601093) (xy 184.007596 -111.650842) (xy 184.023084 -111.703345) (xy 184.03091 -111.757522)
			(xy 184.031382 -111.784892) (xy 184.030896 -111.812143) (xy 184.02314 -111.866091) (xy 184.007785 -111.918386)
			(xy 183.985143 -111.967963) (xy 183.955677 -112.013813) (xy 183.919986 -112.055004) (xy 183.878795 -112.090695)
			(xy 183.832945 -112.120161) (xy 183.783368 -112.142803) (xy 183.731073 -112.158158) (xy 183.677125 -112.165914)
			(xy 183.622623 -112.165914) (xy 183.568675 -112.158158) (xy 183.51638 -112.142803) (xy 183.466803 -112.120161)
			(xy 183.420953 -112.090695) (xy 183.379762 -112.055004) (xy 183.344071 -112.013813) (xy 183.314605 -111.967963)
			(xy 183.291963 -111.918386) (xy 183.276608 -111.866091) (xy 183.268852 -111.812143) (xy 183.268366 -111.784892)
			(xy 173.18228 -111.784892) (xy 173.18228 -112.510824) (xy 179.902356 -112.510824) (xy 179.906427 -112.455202)
			(xy 179.918553 -112.400765) (xy 179.938476 -112.348674) (xy 179.965772 -112.300039) (xy 179.999858 -112.255896)
			(xy 180.040007 -112.217187) (xy 180.085365 -112.184736) (xy 180.134965 -112.159235) (xy 180.187749 -112.141228)
			(xy 180.242592 -112.131098) (xy 180.298326 -112.129061) (xy 180.353763 -112.135161) (xy 180.40772 -112.149267)
			(xy 180.459049 -112.171079) (xy 180.506655 -112.200133) (xy 180.549523 -112.235808) (xy 180.58674 -112.277345)
			(xy 180.617513 -112.323858) (xy 180.641185 -112.374355) (xy 180.657253 -112.427762) (xy 180.665373 -112.482938)
			(xy 180.665418 -112.485424) (xy 182.750966 -112.485424) (xy 182.755037 -112.429802) (xy 182.767163 -112.375365)
			(xy 182.787086 -112.323274) (xy 182.814382 -112.274639) (xy 182.848468 -112.230496) (xy 182.888617 -112.191787)
			(xy 182.933975 -112.159336) (xy 182.983575 -112.133835) (xy 183.036359 -112.115828) (xy 183.091202 -112.105698)
			(xy 183.146936 -112.103661) (xy 183.202373 -112.109761) (xy 183.25633 -112.123867) (xy 183.307659 -112.145679)
			(xy 183.355265 -112.174733) (xy 183.398133 -112.210408) (xy 183.43535 -112.251945) (xy 183.466123 -112.298458)
			(xy 183.489795 -112.348955) (xy 183.505863 -112.402362) (xy 183.513983 -112.457538) (xy 183.514492 -112.485424)
			(xy 183.513983 -112.51331) (xy 183.505863 -112.568486) (xy 183.489795 -112.621893) (xy 183.466123 -112.67239)
			(xy 183.43535 -112.718903) (xy 183.398133 -112.76044) (xy 183.355265 -112.796115) (xy 183.307659 -112.825169)
			(xy 183.25633 -112.846981) (xy 183.202373 -112.861087) (xy 183.146936 -112.867187) (xy 183.091202 -112.86515)
			(xy 183.036359 -112.85502) (xy 182.983575 -112.837013) (xy 182.933975 -112.811512) (xy 182.888617 -112.779061)
			(xy 182.848468 -112.740352) (xy 182.814382 -112.696209) (xy 182.787086 -112.647574) (xy 182.767163 -112.595483)
			(xy 182.755037 -112.541046) (xy 182.750966 -112.485424) (xy 180.665418 -112.485424) (xy 180.665882 -112.510824)
			(xy 180.665373 -112.53871) (xy 180.657253 -112.593886) (xy 180.641185 -112.647293) (xy 180.617513 -112.69779)
			(xy 180.58674 -112.744303) (xy 180.549523 -112.78584) (xy 180.506655 -112.821515) (xy 180.459049 -112.850569)
			(xy 180.40772 -112.872381) (xy 180.353763 -112.886487) (xy 180.298326 -112.892587) (xy 180.242592 -112.89055)
			(xy 180.187749 -112.88042) (xy 180.134965 -112.862413) (xy 180.085365 -112.836912) (xy 180.040007 -112.804461)
			(xy 179.999858 -112.765752) (xy 179.965772 -112.721609) (xy 179.938476 -112.672974) (xy 179.918553 -112.620883)
			(xy 179.906427 -112.566446) (xy 179.902356 -112.510824) (xy 173.18228 -112.510824) (xy 173.18228 -113.43513)
			(xy 183.03062 -113.43513) (xy 183.034691 -113.379508) (xy 183.046817 -113.325071) (xy 183.06674 -113.27298)
			(xy 183.094036 -113.224345) (xy 183.128122 -113.180202) (xy 183.168271 -113.141493) (xy 183.213629 -113.109042)
			(xy 183.263229 -113.083541) (xy 183.316013 -113.065534) (xy 183.370856 -113.055404) (xy 183.42659 -113.053367)
			(xy 183.482027 -113.059467) (xy 183.535984 -113.073573) (xy 183.587313 -113.095385) (xy 183.634919 -113.124439)
			(xy 183.677787 -113.160114) (xy 183.715004 -113.201651) (xy 183.745777 -113.248164) (xy 183.769449 -113.298661)
			(xy 183.785517 -113.352068) (xy 183.793637 -113.407244) (xy 183.794146 -113.43513) (xy 183.793637 -113.463016)
			(xy 183.785517 -113.518192) (xy 183.769449 -113.571599) (xy 183.745777 -113.622096) (xy 183.715004 -113.668609)
			(xy 183.677787 -113.710146) (xy 183.634919 -113.745821) (xy 183.587313 -113.774875) (xy 183.535984 -113.796687)
			(xy 183.482027 -113.810793) (xy 183.42659 -113.816893) (xy 183.370856 -113.814856) (xy 183.316013 -113.804726)
			(xy 183.263229 -113.786719) (xy 183.213629 -113.761218) (xy 183.168271 -113.728767) (xy 183.128122 -113.690058)
			(xy 183.094036 -113.645915) (xy 183.06674 -113.59728) (xy 183.046817 -113.545189) (xy 183.034691 -113.490752)
			(xy 183.03062 -113.43513) (xy 173.18228 -113.43513) (xy 173.18228 -114.267742) (xy 180.406038 -114.267742)
			(xy 180.410109 -114.21212) (xy 180.422235 -114.157683) (xy 180.442158 -114.105592) (xy 180.469454 -114.056957)
			(xy 180.50354 -114.012814) (xy 180.543689 -113.974105) (xy 180.589047 -113.941654) (xy 180.638647 -113.916153)
			(xy 180.691431 -113.898146) (xy 180.746274 -113.888016) (xy 180.802008 -113.885979) (xy 180.857445 -113.892079)
			(xy 180.911402 -113.906185) (xy 180.962731 -113.927997) (xy 181.010337 -113.957051) (xy 181.053205 -113.992726)
			(xy 181.090422 -114.034263) (xy 181.121195 -114.080776) (xy 181.144867 -114.131273) (xy 181.160935 -114.18468)
			(xy 181.169055 -114.239856) (xy 181.169564 -114.267742) (xy 181.169055 -114.295628) (xy 181.160935 -114.350804)
			(xy 181.144867 -114.404211) (xy 181.121195 -114.454708) (xy 181.090422 -114.501221) (xy 181.053205 -114.542758)
			(xy 181.010337 -114.578433) (xy 181.005423 -114.581432) (xy 182.39943 -114.581432) (xy 182.403501 -114.52581)
			(xy 182.415627 -114.471373) (xy 182.43555 -114.419282) (xy 182.462846 -114.370647) (xy 182.496932 -114.326504)
			(xy 182.537081 -114.287795) (xy 182.582439 -114.255344) (xy 182.632039 -114.229843) (xy 182.684823 -114.211836)
			(xy 182.739666 -114.201706) (xy 182.7954 -114.199669) (xy 182.850837 -114.205769) (xy 182.904794 -114.219875)
			(xy 182.956123 -114.241687) (xy 183.003729 -114.270741) (xy 183.046597 -114.306416) (xy 183.083814 -114.347953)
			(xy 183.114587 -114.394466) (xy 183.138259 -114.444963) (xy 183.154327 -114.49837) (xy 183.162447 -114.553546)
			(xy 183.162956 -114.581432) (xy 183.162447 -114.609318) (xy 183.154327 -114.664494) (xy 183.138259 -114.717901)
			(xy 183.114587 -114.768398) (xy 183.083814 -114.814911) (xy 183.046597 -114.856448) (xy 183.003729 -114.892123)
			(xy 182.956123 -114.921177) (xy 182.904794 -114.942989) (xy 182.850837 -114.957095) (xy 182.7954 -114.963195)
			(xy 182.739666 -114.961158) (xy 182.684823 -114.951028) (xy 182.632039 -114.933021) (xy 182.582439 -114.90752)
			(xy 182.537081 -114.875069) (xy 182.496932 -114.83636) (xy 182.462846 -114.792217) (xy 182.43555 -114.743582)
			(xy 182.415627 -114.691491) (xy 182.403501 -114.637054) (xy 182.39943 -114.581432) (xy 181.005423 -114.581432)
			(xy 180.962731 -114.607487) (xy 180.911402 -114.629299) (xy 180.857445 -114.643405) (xy 180.802008 -114.649505)
			(xy 180.746274 -114.647468) (xy 180.691431 -114.637338) (xy 180.638647 -114.619331) (xy 180.589047 -114.59383)
			(xy 180.543689 -114.561379) (xy 180.50354 -114.52267) (xy 180.469454 -114.478527) (xy 180.442158 -114.429892)
			(xy 180.422235 -114.377801) (xy 180.410109 -114.323364) (xy 180.406038 -114.267742) (xy 173.18228 -114.267742)
			(xy 173.18228 -115.285774) (xy 183.03113 -115.285774) (xy 183.031698 -115.256692) (xy 183.040545 -115.199203)
			(xy 183.058015 -115.143724) (xy 183.083703 -115.091538) (xy 183.117014 -115.043856) (xy 183.157176 -115.001782)
			(xy 183.203258 -114.966292) (xy 183.254193 -114.938206) (xy 183.308801 -114.918177) (xy 183.3372 -114.911886)
			(xy 183.337454 -114.911886) (xy 183.348178 -114.909104) (xy 183.365965 -114.895938) (xy 183.371744 -114.886486)
			(xy 183.41467 -114.807746) (xy 183.416194 -114.785648) (xy 183.411876 -114.77498) (xy 183.403449 -114.752619)
			(xy 183.391591 -114.706327) (xy 183.385595 -114.658919) (xy 183.385206 -114.635026) (xy 183.385692 -114.607775)
			(xy 183.393448 -114.553827) (xy 183.408803 -114.501532) (xy 183.431445 -114.451955) (xy 183.460911 -114.406105)
			(xy 183.496602 -114.364914) (xy 183.537793 -114.329223) (xy 183.583643 -114.299757) (xy 183.63322 -114.277115)
			(xy 183.685515 -114.26176) (xy 183.739463 -114.254004) (xy 183.793965 -114.254004) (xy 183.847913 -114.26176)
			(xy 183.900208 -114.277115) (xy 183.928627 -114.290094) (xy 186.460128 -114.290094) (xy 186.464199 -114.234472)
			(xy 186.476325 -114.180035) (xy 186.496248 -114.127944) (xy 186.523544 -114.079309) (xy 186.55763 -114.035166)
			(xy 186.597779 -113.996457) (xy 186.643137 -113.964006) (xy 186.692737 -113.938505) (xy 186.745521 -113.920498)
			(xy 186.800364 -113.910368) (xy 186.856098 -113.908331) (xy 186.911535 -113.914431) (xy 186.965492 -113.928537)
			(xy 187.016821 -113.950349) (xy 187.064427 -113.979403) (xy 187.107295 -114.015078) (xy 187.144512 -114.056615)
			(xy 187.175285 -114.103128) (xy 187.198957 -114.153625) (xy 187.215025 -114.207032) (xy 187.223145 -114.262208)
			(xy 187.223654 -114.290094) (xy 187.223145 -114.31798) (xy 187.215025 -114.373156) (xy 187.198957 -114.426563)
			(xy 187.175285 -114.47706) (xy 187.144512 -114.523573) (xy 187.107295 -114.56511) (xy 187.064427 -114.600785)
			(xy 187.016821 -114.629839) (xy 186.965492 -114.651651) (xy 186.911535 -114.665757) (xy 186.856098 -114.671857)
			(xy 186.800364 -114.66982) (xy 186.745521 -114.65969) (xy 186.692737 -114.641683) (xy 186.643137 -114.616182)
			(xy 186.597779 -114.583731) (xy 186.55763 -114.545022) (xy 186.523544 -114.500879) (xy 186.496248 -114.452244)
			(xy 186.476325 -114.400153) (xy 186.464199 -114.345716) (xy 186.460128 -114.290094) (xy 183.928627 -114.290094)
			(xy 183.949785 -114.299757) (xy 183.995635 -114.329223) (xy 184.036826 -114.364914) (xy 184.072517 -114.406105)
			(xy 184.101983 -114.451955) (xy 184.124625 -114.501532) (xy 184.13998 -114.553827) (xy 184.147736 -114.607775)
			(xy 184.148222 -114.635026) (xy 184.147612 -114.664106) (xy 184.138767 -114.721591) (xy 184.1213 -114.777067)
			(xy 184.103825 -114.812572) (xy 187.950602 -114.812572) (xy 187.951088 -114.785321) (xy 187.958844 -114.731373)
			(xy 187.974199 -114.679078) (xy 187.996841 -114.629501) (xy 188.026307 -114.583651) (xy 188.061998 -114.54246)
			(xy 188.103189 -114.506769) (xy 188.149039 -114.477303) (xy 188.198616 -114.454661) (xy 188.250911 -114.439306)
			(xy 188.304859 -114.43155) (xy 188.359361 -114.43155) (xy 188.413309 -114.439306) (xy 188.465604 -114.454661)
			(xy 188.515181 -114.477303) (xy 188.561031 -114.506769) (xy 188.602222 -114.54246) (xy 188.637913 -114.583651)
			(xy 188.667379 -114.629501) (xy 188.690021 -114.679078) (xy 188.705376 -114.731373) (xy 188.713132 -114.785321)
			(xy 188.713618 -114.812572) (xy 188.71305 -114.842263) (xy 188.705111 -114.892836) (xy 203.360526 -114.892836)
			(xy 203.364597 -114.837214) (xy 203.376723 -114.782777) (xy 203.396646 -114.730686) (xy 203.423942 -114.682051)
			(xy 203.458028 -114.637908) (xy 203.498177 -114.599199) (xy 203.543535 -114.566748) (xy 203.593135 -114.541247)
			(xy 203.645919 -114.52324) (xy 203.700762 -114.51311) (xy 203.756496 -114.511073) (xy 203.811933 -114.517173)
			(xy 203.86589 -114.531279) (xy 203.917219 -114.553091) (xy 203.964825 -114.582145) (xy 204.007693 -114.61782)
			(xy 204.04491 -114.659357) (xy 204.075683 -114.70587) (xy 204.099355 -114.756367) (xy 204.115423 -114.809774)
			(xy 204.123543 -114.86495) (xy 204.124052 -114.892836) (xy 204.123543 -114.920722) (xy 204.115423 -114.975898)
			(xy 204.099355 -115.029305) (xy 204.075683 -115.079802) (xy 204.04491 -115.126315) (xy 204.027434 -115.14582)
			(xy 205.473044 -115.14582) (xy 205.477115 -115.090198) (xy 205.489241 -115.035761) (xy 205.509164 -114.98367)
			(xy 205.53646 -114.935035) (xy 205.570546 -114.890892) (xy 205.610695 -114.852183) (xy 205.656053 -114.819732)
			(xy 205.705653 -114.794231) (xy 205.758437 -114.776224) (xy 205.81328 -114.766094) (xy 205.869014 -114.764057)
			(xy 205.924451 -114.770157) (xy 205.978408 -114.784263) (xy 206.029737 -114.806075) (xy 206.077343 -114.835129)
			(xy 206.120211 -114.870804) (xy 206.157428 -114.912341) (xy 206.188201 -114.958854) (xy 206.211873 -115.009351)
			(xy 206.227941 -115.062758) (xy 206.236061 -115.117934) (xy 206.23657 -115.14582) (xy 206.236061 -115.173706)
			(xy 206.227941 -115.228882) (xy 206.211873 -115.282289) (xy 206.188201 -115.332786) (xy 206.157428 -115.379299)
			(xy 206.120211 -115.420836) (xy 206.077343 -115.456511) (xy 206.029737 -115.485565) (xy 205.978408 -115.507377)
			(xy 205.924451 -115.521483) (xy 205.869014 -115.527583) (xy 205.81328 -115.525546) (xy 205.758437 -115.515416)
			(xy 205.705653 -115.497409) (xy 205.656053 -115.471908) (xy 205.610695 -115.439457) (xy 205.570546 -115.400748)
			(xy 205.53646 -115.356605) (xy 205.509164 -115.30797) (xy 205.489241 -115.255879) (xy 205.477115 -115.201442)
			(xy 205.473044 -115.14582) (xy 204.027434 -115.14582) (xy 204.007693 -115.167852) (xy 203.964825 -115.203527)
			(xy 203.917219 -115.232581) (xy 203.86589 -115.254393) (xy 203.811933 -115.268499) (xy 203.756496 -115.274599)
			(xy 203.700762 -115.272562) (xy 203.645919 -115.262432) (xy 203.593135 -115.244425) (xy 203.543535 -115.218924)
			(xy 203.498177 -115.186473) (xy 203.458028 -115.147764) (xy 203.423942 -115.103621) (xy 203.396646 -115.054986)
			(xy 203.376723 -115.002895) (xy 203.364597 -114.948458) (xy 203.360526 -114.892836) (xy 188.705111 -114.892836)
			(xy 188.703841 -114.900927) (xy 188.685657 -114.957456) (xy 188.658935 -115.010487) (xy 188.624322 -115.058738)
			(xy 188.60389 -115.080288) (xy 188.596524 -115.087654) (xy 188.589158 -115.10645) (xy 188.590936 -115.200176)
			(xy 188.599318 -115.218972) (xy 188.606938 -115.22583) (xy 188.625739 -115.243945) (xy 188.658719 -115.284417)
			(xy 188.685875 -115.329008) (xy 188.706698 -115.376884) (xy 188.720802 -115.427151) (xy 188.727922 -115.478872)
			(xy 188.72835 -115.504976) (xy 188.727864 -115.532227) (xy 188.721192 -115.578636) (xy 209.079082 -115.578636)
			(xy 209.083153 -115.523014) (xy 209.095279 -115.468577) (xy 209.115202 -115.416486) (xy 209.142498 -115.367851)
			(xy 209.176584 -115.323708) (xy 209.216733 -115.284999) (xy 209.262091 -115.252548) (xy 209.311691 -115.227047)
			(xy 209.364475 -115.20904) (xy 209.419318 -115.19891) (xy 209.475052 -115.196873) (xy 209.530489 -115.202973)
			(xy 209.584446 -115.217079) (xy 209.635775 -115.238891) (xy 209.683381 -115.267945) (xy 209.726249 -115.30362)
			(xy 209.763466 -115.345157) (xy 209.794239 -115.39167) (xy 209.817911 -115.442167) (xy 209.833979 -115.495574)
			(xy 209.842099 -115.55075) (xy 209.842608 -115.578636) (xy 209.842099 -115.606522) (xy 209.833979 -115.661698)
			(xy 209.817911 -115.715105) (xy 209.794239 -115.765602) (xy 209.763466 -115.812115) (xy 209.726249 -115.853652)
			(xy 209.683381 -115.889327) (xy 209.635775 -115.918381) (xy 209.584446 -115.940193) (xy 209.530489 -115.954299)
			(xy 209.475052 -115.960399) (xy 209.419318 -115.958362) (xy 209.364475 -115.948232) (xy 209.311691 -115.930225)
			(xy 209.262091 -115.904724) (xy 209.216733 -115.872273) (xy 209.176584 -115.833564) (xy 209.142498 -115.789421)
			(xy 209.115202 -115.740786) (xy 209.095279 -115.688695) (xy 209.083153 -115.634258) (xy 209.079082 -115.578636)
			(xy 188.721192 -115.578636) (xy 188.720108 -115.586175) (xy 188.704753 -115.63847) (xy 188.682111 -115.688047)
			(xy 188.652645 -115.733897) (xy 188.616954 -115.775088) (xy 188.575763 -115.810779) (xy 188.529913 -115.840245)
			(xy 188.480336 -115.862887) (xy 188.428041 -115.878242) (xy 188.374093 -115.885998) (xy 188.319591 -115.885998)
			(xy 188.265643 -115.878242) (xy 188.213348 -115.862887) (xy 188.163771 -115.840245) (xy 188.117921 -115.810779)
			(xy 188.07673 -115.775088) (xy 188.041039 -115.733897) (xy 188.011573 -115.688047) (xy 187.988931 -115.63847)
			(xy 187.973576 -115.586175) (xy 187.96582 -115.532227) (xy 187.965334 -115.504976) (xy 187.965917 -115.475285)
			(xy 187.97512 -115.416622) (xy 187.9933 -115.360092) (xy 188.020019 -115.307061) (xy 188.05463 -115.25881)
			(xy 188.075062 -115.23726) (xy 188.082428 -115.229894) (xy 188.089794 -115.211098) (xy 188.088016 -115.117372)
			(xy 188.079634 -115.098576) (xy 188.072014 -115.091718) (xy 188.053227 -115.073589) (xy 188.020248 -115.033119)
			(xy 187.993091 -114.988531) (xy 187.972265 -114.940658) (xy 187.958158 -114.890393) (xy 187.951033 -114.838675)
			(xy 187.950602 -114.812572) (xy 184.103825 -114.812572) (xy 184.095616 -114.82925) (xy 184.06231 -114.87693)
			(xy 184.022155 -114.919004) (xy 183.976079 -114.954497) (xy 183.92515 -114.982586) (xy 183.870549 -115.00262)
			(xy 183.842152 -115.008914) (xy 183.841898 -115.008914) (xy 183.831166 -115.011674) (xy 183.813384 -115.024856)
			(xy 183.807608 -115.034314) (xy 183.764682 -115.113054) (xy 183.763158 -115.135152) (xy 183.767476 -115.14582)
			(xy 183.775901 -115.168182) (xy 183.78776 -115.214473) (xy 183.793757 -115.261881) (xy 183.794146 -115.285774)
			(xy 183.79366 -115.313025) (xy 183.785904 -115.366973) (xy 183.770549 -115.419268) (xy 183.747907 -115.468845)
			(xy 183.718441 -115.514695) (xy 183.68275 -115.555886) (xy 183.641559 -115.591577) (xy 183.595709 -115.621043)
			(xy 183.546132 -115.643685) (xy 183.493837 -115.65904) (xy 183.439889 -115.666796) (xy 183.385387 -115.666796)
			(xy 183.331439 -115.65904) (xy 183.279144 -115.643685) (xy 183.229567 -115.621043) (xy 183.183717 -115.591577)
			(xy 183.142526 -115.555886) (xy 183.106835 -115.514695) (xy 183.077369 -115.468845) (xy 183.054727 -115.419268)
			(xy 183.039372 -115.366973) (xy 183.031616 -115.313025) (xy 183.03113 -115.285774) (xy 173.18228 -115.285774)
			(xy 173.18228 -115.90909) (xy 180.121304 -115.90909) (xy 180.125375 -115.853468) (xy 180.137501 -115.799031)
			(xy 180.157424 -115.74694) (xy 180.18472 -115.698305) (xy 180.218806 -115.654162) (xy 180.258955 -115.615453)
			(xy 180.304313 -115.583002) (xy 180.353913 -115.557501) (xy 180.406697 -115.539494) (xy 180.46154 -115.529364)
			(xy 180.517274 -115.527327) (xy 180.572711 -115.533427) (xy 180.626668 -115.547533) (xy 180.677997 -115.569345)
			(xy 180.725603 -115.598399) (xy 180.768471 -115.634074) (xy 180.805688 -115.675611) (xy 180.836461 -115.722124)
			(xy 180.860133 -115.772621) (xy 180.876201 -115.826028) (xy 180.884321 -115.881204) (xy 180.88483 -115.90909)
			(xy 180.884321 -115.936976) (xy 180.876201 -115.992152) (xy 180.860133 -116.045559) (xy 180.836461 -116.096056)
			(xy 180.805688 -116.142569) (xy 180.768471 -116.184106) (xy 180.725603 -116.219781) (xy 180.677997 -116.248835)
			(xy 180.626668 -116.270647) (xy 180.572711 -116.284753) (xy 180.517274 -116.290853) (xy 180.46154 -116.288816)
			(xy 180.406697 -116.278686) (xy 180.353913 -116.260679) (xy 180.304313 -116.235178) (xy 180.258955 -116.202727)
			(xy 180.218806 -116.164018) (xy 180.18472 -116.119875) (xy 180.157424 -116.07124) (xy 180.137501 -116.019149)
			(xy 180.125375 -115.964712) (xy 180.121304 -115.90909) (xy 173.18228 -115.90909) (xy 173.18228 -116.44757)
			(xy 182.256936 -116.44757) (xy 182.261007 -116.391948) (xy 182.273133 -116.337511) (xy 182.293056 -116.28542)
			(xy 182.320352 -116.236785) (xy 182.354438 -116.192642) (xy 182.394587 -116.153933) (xy 182.439945 -116.121482)
			(xy 182.489545 -116.095981) (xy 182.542329 -116.077974) (xy 182.597172 -116.067844) (xy 182.652906 -116.065807)
			(xy 182.708343 -116.071907) (xy 182.7623 -116.086013) (xy 182.813629 -116.107825) (xy 182.861235 -116.136879)
			(xy 182.904103 -116.172554) (xy 182.94132 -116.214091) (xy 182.972093 -116.260604) (xy 182.995765 -116.311101)
			(xy 183.011833 -116.364508) (xy 183.019953 -116.419684) (xy 183.020235 -116.435124) (xy 183.384696 -116.435124)
			(xy 183.388767 -116.379502) (xy 183.400893 -116.325065) (xy 183.420816 -116.272974) (xy 183.448112 -116.224339)
			(xy 183.482198 -116.180196) (xy 183.522347 -116.141487) (xy 183.567705 -116.109036) (xy 183.617305 -116.083535)
			(xy 183.670089 -116.065528) (xy 183.724932 -116.055398) (xy 183.780666 -116.053361) (xy 183.836103 -116.059461)
			(xy 183.89006 -116.073567) (xy 183.941389 -116.095379) (xy 183.988995 -116.124433) (xy 184.031863 -116.160108)
			(xy 184.06908 -116.201645) (xy 184.099853 -116.248158) (xy 184.123525 -116.298655) (xy 184.139593 -116.352062)
			(xy 184.147713 -116.407238) (xy 184.148222 -116.435124) (xy 184.147713 -116.46301) (xy 184.1416 -116.50455)
			(xy 187.405266 -116.50455) (xy 187.405266 -116.45005) (xy 187.413022 -116.396103) (xy 187.428375 -116.34381)
			(xy 187.451015 -116.294233) (xy 187.480478 -116.248383) (xy 187.516167 -116.207193) (xy 187.557354 -116.1715)
			(xy 187.603202 -116.142032) (xy 187.652776 -116.119388) (xy 187.705068 -116.104029) (xy 187.759014 -116.096268)
			(xy 187.786264 -116.09578) (xy 187.814335 -116.096277) (xy 187.869868 -116.104522) (xy 187.923595 -116.12081)
			(xy 187.974358 -116.144789) (xy 188.021063 -116.175944) (xy 188.062702 -116.213601) (xy 188.098378 -116.25695)
			(xy 188.127322 -116.305056) (xy 188.14891 -116.356881) (xy 188.162676 -116.411309) (xy 188.165994 -116.439188)
			(xy 188.1679 -116.453142) (xy 188.178239 -116.479323) (xy 188.195335 -116.501685) (xy 188.21789 -116.518526)
			(xy 188.244187 -116.528567) (xy 188.272226 -116.531043) (xy 188.286136 -116.52885) (xy 188.303935 -116.525653)
			(xy 188.339936 -116.522218) (xy 188.358018 -116.521992) (xy 188.358272 -116.521992) (xy 188.385526 -116.522453)
			(xy 188.43948 -116.530207) (xy 188.491781 -116.545561) (xy 188.541365 -116.568202) (xy 188.587222 -116.597669)
			(xy 188.628418 -116.633363) (xy 188.664114 -116.674556) (xy 188.693585 -116.72041) (xy 188.716229 -116.769992)
			(xy 188.731587 -116.822292) (xy 188.739345 -116.876246) (xy 188.739345 -116.930754) (xy 188.731587 -116.984708)
			(xy 188.716229 -117.037008) (xy 188.693585 -117.08659) (xy 188.664114 -117.132444) (xy 188.628418 -117.173637)
			(xy 188.587222 -117.209331) (xy 188.541365 -117.238798) (xy 188.491781 -117.261439) (xy 188.43948 -117.276793)
			(xy 188.385526 -117.284547) (xy 188.358272 -117.285008) (xy 188.330199 -117.28458) (xy 188.274662 -117.276326)
			(xy 188.220933 -117.260029) (xy 188.170169 -117.236041) (xy 188.123464 -117.204879) (xy 188.081826 -117.167214)
			(xy 188.046151 -117.123858) (xy 188.017208 -117.075746) (xy 187.995623 -117.023914) (xy 187.981859 -116.969481)
			(xy 187.978542 -116.9416) (xy 187.976718 -116.927631) (xy 187.966368 -116.90144) (xy 187.949256 -116.879073)
			(xy 187.926684 -116.862232) (xy 187.90037 -116.852198) (xy 187.872315 -116.849736) (xy 187.8584 -116.851938)
			(xy 187.840601 -116.85513) (xy 187.8046 -116.858569) (xy 187.786518 -116.858796) (xy 187.786264 -116.858796)
			(xy 187.759014 -116.858332) (xy 187.705068 -116.850571) (xy 187.652776 -116.835212) (xy 187.603202 -116.812568)
			(xy 187.557354 -116.7831) (xy 187.516167 -116.747407) (xy 187.480478 -116.706217) (xy 187.451015 -116.660367)
			(xy 187.428375 -116.61079) (xy 187.413022 -116.558497) (xy 187.405266 -116.50455) (xy 184.1416 -116.50455)
			(xy 184.139593 -116.518186) (xy 184.123525 -116.571593) (xy 184.099853 -116.62209) (xy 184.06908 -116.668603)
			(xy 184.031863 -116.71014) (xy 183.988995 -116.745815) (xy 183.941389 -116.774869) (xy 183.89006 -116.796681)
			(xy 183.836103 -116.810787) (xy 183.780666 -116.816887) (xy 183.724932 -116.81485) (xy 183.670089 -116.80472)
			(xy 183.617305 -116.786713) (xy 183.567705 -116.761212) (xy 183.522347 -116.728761) (xy 183.482198 -116.690052)
			(xy 183.448112 -116.645909) (xy 183.420816 -116.597274) (xy 183.400893 -116.545183) (xy 183.388767 -116.490746)
			(xy 183.384696 -116.435124) (xy 183.020235 -116.435124) (xy 183.020462 -116.44757) (xy 183.019953 -116.475456)
			(xy 183.011833 -116.530632) (xy 182.995765 -116.584039) (xy 182.972093 -116.634536) (xy 182.94132 -116.681049)
			(xy 182.904103 -116.722586) (xy 182.861235 -116.758261) (xy 182.813629 -116.787315) (xy 182.7623 -116.809127)
			(xy 182.708343 -116.823233) (xy 182.652906 -116.829333) (xy 182.597172 -116.827296) (xy 182.542329 -116.817166)
			(xy 182.489545 -116.799159) (xy 182.439945 -116.773658) (xy 182.394587 -116.741207) (xy 182.354438 -116.702498)
			(xy 182.320352 -116.658355) (xy 182.293056 -116.60972) (xy 182.273133 -116.557629) (xy 182.261007 -116.503192)
			(xy 182.256936 -116.44757) (xy 173.18228 -116.44757) (xy 173.18228 -118.331996) (xy 178.995576 -118.331996)
			(xy 178.999647 -118.276374) (xy 179.011773 -118.221937) (xy 179.031696 -118.169846) (xy 179.058992 -118.121211)
			(xy 179.093078 -118.077068) (xy 179.133227 -118.038359) (xy 179.178585 -118.005908) (xy 179.228185 -117.980407)
			(xy 179.280969 -117.9624) (xy 179.335812 -117.95227) (xy 179.391546 -117.950233) (xy 179.446983 -117.956333)
			(xy 179.50094 -117.970439) (xy 179.552269 -117.992251) (xy 179.599875 -118.021305) (xy 179.642743 -118.05698)
			(xy 179.67996 -118.098517) (xy 179.710733 -118.14503) (xy 179.734405 -118.195527) (xy 179.750473 -118.248934)
			(xy 179.758593 -118.30411) (xy 179.759102 -118.331996) (xy 179.758593 -118.359882) (xy 179.750473 -118.415058)
			(xy 179.734405 -118.468465) (xy 179.710733 -118.518962) (xy 179.67996 -118.565475) (xy 179.642743 -118.607012)
			(xy 179.599875 -118.642687) (xy 179.552269 -118.671741) (xy 179.50094 -118.693553) (xy 179.446983 -118.707659)
			(xy 179.391546 -118.713759) (xy 179.335812 -118.711722) (xy 179.280969 -118.701592) (xy 179.228185 -118.683585)
			(xy 179.178585 -118.658084) (xy 179.133227 -118.625633) (xy 179.093078 -118.586924) (xy 179.058992 -118.542781)
			(xy 179.031696 -118.494146) (xy 179.011773 -118.442055) (xy 178.999647 -118.387618) (xy 178.995576 -118.331996)
			(xy 173.18228 -118.331996) (xy 173.18228 -123.547124) (xy 173.18274 -123.557001) (xy 173.190183 -123.5753)
			(xy 173.196758 -123.582684) (xy 173.277524 -123.66345) (xy 180.292999 -123.66345) (xy 180.292999 -123.60615)
			(xy 180.301153 -123.549433) (xy 180.317295 -123.494453) (xy 180.341098 -123.442331) (xy 180.372075 -123.394126)
			(xy 180.409597 -123.35082) (xy 180.4529 -123.313294) (xy 180.501103 -123.282313) (xy 180.553223 -123.258507)
			(xy 180.608202 -123.24236) (xy 180.664918 -123.234201) (xy 180.693568 -123.233688) (xy 180.721908 -123.234247)
			(xy 180.778022 -123.242249) (xy 180.832451 -123.25807) (xy 180.88411 -123.281395) (xy 180.931972 -123.31176)
			(xy 180.975083 -123.34856) (xy 181.012585 -123.391062) (xy 181.04373 -123.438419) (xy 181.067899 -123.48969)
			(xy 181.084611 -123.543851) (xy 181.089554 -123.571762) (xy 181.091078 -123.582176) (xy 181.102254 -123.599702)
			(xy 181.179978 -123.653296) (xy 181.200044 -123.65736) (xy 181.210458 -123.655328) (xy 181.233374 -123.650845)
			(xy 181.27982 -123.646007) (xy 181.303168 -123.645676) (xy 181.326516 -123.646009) (xy 181.372962 -123.650847)
			(xy 181.395878 -123.655328) (xy 181.406292 -123.65736) (xy 181.426358 -123.653296) (xy 181.504082 -123.599702)
			(xy 181.515258 -123.582176) (xy 181.516782 -123.571762) (xy 181.521748 -123.543849) (xy 181.538423 -123.489664)
			(xy 181.562566 -123.43837) (xy 181.593696 -123.390989) (xy 181.631192 -123.348468) (xy 181.674306 -123.311654)
			(xy 181.722177 -123.281283) (xy 181.77385 -123.257961) (xy 181.828294 -123.242153) (xy 181.884422 -123.234174)
			(xy 181.912768 -123.233688) (xy 181.942136 -123.234244) (xy 182.000241 -123.242837) (xy 182.056471 -123.259815)
			(xy 182.109623 -123.284815) (xy 182.158558 -123.317301) (xy 182.180738 -123.336558) (xy 182.187922 -123.342562)
			(xy 182.205415 -123.349206) (xy 182.214774 -123.349512) (xy 182.245762 -123.349512) (xy 182.255099 -123.349107)
			(xy 182.272551 -123.342459) (xy 182.279798 -123.336558) (xy 182.301957 -123.317275) (xy 182.3509 -123.284794)
			(xy 182.404057 -123.259796) (xy 182.46029 -123.242816) (xy 182.518398 -123.234217) (xy 182.547768 -123.233688)
			(xy 182.564809 -123.233874) (xy 182.598764 -123.236799) (xy 182.615586 -123.23953) (xy 182.626579 -123.240885)
			(xy 182.647929 -123.235076) (xy 182.656734 -123.228354) (xy 182.681372 -123.20778) (xy 182.689599 -123.200159)
			(xy 182.699079 -123.179864) (xy 182.69966 -123.168664) (xy 182.69966 -123.16714) (xy 182.69966 -122.301)
			(xy 182.699109 -122.289793) (xy 182.68962 -122.269491) (xy 182.681372 -122.261884) (xy 182.656734 -122.241056)
			(xy 182.647891 -122.234413) (xy 182.626572 -122.228611) (xy 182.615586 -122.22988) (xy 182.598758 -122.232531)
			(xy 182.564803 -122.235329) (xy 182.547768 -122.235468) (xy 182.518417 -122.234975) (xy 182.460334 -122.226479)
			(xy 182.404112 -122.209602) (xy 182.350953 -122.184703) (xy 182.301995 -122.152316) (xy 182.279798 -122.133106)
			(xy 182.272685 -122.127079) (xy 182.255331 -122.120294) (xy 182.246016 -122.119898) (xy 182.214774 -122.119898)
			(xy 182.20547 -122.120343) (xy 182.188139 -122.12713) (xy 182.180992 -122.133106) (xy 182.158812 -122.152403)
			(xy 182.109823 -122.184908) (xy 182.056615 -122.209915) (xy 182.000327 -122.226888) (xy 181.942164 -122.235464)
			(xy 181.912768 -122.235976) (xy 181.884476 -122.23548) (xy 181.828452 -122.22753) (xy 181.774104 -122.211779)
			(xy 181.722512 -122.18854) (xy 181.674701 -122.158275) (xy 181.631623 -122.121585) (xy 181.594135 -122.079201)
			(xy 181.56298 -122.031965) (xy 181.53878 -121.980817) (xy 181.522015 -121.926773) (xy 181.517036 -121.898918)
			(xy 181.515258 -121.888504) (xy 181.504336 -121.871232) (xy 181.426612 -121.817638) (xy 181.406292 -121.813574)
			(xy 181.396132 -121.815606) (xy 181.373148 -121.82004) (xy 181.326574 -121.824749) (xy 181.303168 -121.825004)
			(xy 181.279762 -121.824737) (xy 181.233189 -121.820031) (xy 181.210204 -121.815606) (xy 181.200044 -121.813574)
			(xy 181.179724 -121.817638) (xy 181.102 -121.871232) (xy 181.091078 -121.888504) (xy 181.0893 -121.898918)
			(xy 181.084377 -121.926784) (xy 181.0676 -121.980827) (xy 181.04339 -122.031975) (xy 181.012227 -122.079209)
			(xy 180.974732 -122.121591) (xy 180.931649 -122.15828) (xy 180.883834 -122.188545) (xy 180.832239 -122.211785)
			(xy 180.777888 -122.227538) (xy 180.721862 -122.235492) (xy 180.693568 -122.235976) (xy 180.664922 -122.235443)
			(xy 180.608214 -122.227285) (xy 180.553243 -122.21114) (xy 180.50113 -122.187337) (xy 180.452934 -122.15636)
			(xy 180.409637 -122.11884) (xy 180.37212 -122.07554) (xy 180.341147 -122.027342) (xy 180.317348 -121.975227)
			(xy 180.301208 -121.920255) (xy 180.293055 -121.863546) (xy 180.293055 -121.806254) (xy 180.301208 -121.749545)
			(xy 180.317348 -121.694573) (xy 180.341147 -121.642458) (xy 180.37212 -121.59426) (xy 180.409637 -121.55096)
			(xy 180.452934 -121.51344) (xy 180.50113 -121.482463) (xy 180.553243 -121.45866) (xy 180.608214 -121.442515)
			(xy 180.664922 -121.434357) (xy 180.693568 -121.433844) (xy 180.710609 -121.43403) (xy 180.744564 -121.436956)
			(xy 180.761386 -121.439686) (xy 180.77238 -121.441028) (xy 180.793727 -121.435226) (xy 180.802534 -121.42851)
			(xy 180.827172 -121.407936) (xy 180.835374 -121.400292) (xy 180.844868 -121.380014) (xy 180.84546 -121.36882)
			(xy 180.84546 -121.367296) (xy 180.84546 -120.501156) (xy 180.844878 -120.489953) (xy 180.835411 -120.469651)
			(xy 180.827172 -120.46204) (xy 180.802534 -120.441212) (xy 180.793687 -120.434574) (xy 180.772372 -120.428767)
			(xy 180.761386 -120.430036) (xy 180.744558 -120.432687) (xy 180.710603 -120.435485) (xy 180.693568 -120.435624)
			(xy 180.66494 -120.435087) (xy 180.608268 -120.426935) (xy 180.553333 -120.410801) (xy 180.501252 -120.387013)
			(xy 180.453088 -120.356055) (xy 180.409818 -120.318559) (xy 180.372325 -120.275287) (xy 180.341372 -120.227119)
			(xy 180.317588 -120.175037) (xy 180.301458 -120.120101) (xy 180.29331 -120.063428) (xy 180.29331 -120.006172)
			(xy 180.301458 -119.949499) (xy 180.317588 -119.894563) (xy 180.341372 -119.842481) (xy 180.372325 -119.794313)
			(xy 180.409818 -119.751041) (xy 180.453088 -119.713545) (xy 180.501252 -119.682587) (xy 180.553333 -119.658799)
			(xy 180.608268 -119.642665) (xy 180.66494 -119.634513) (xy 180.693568 -119.634) (xy 180.7219 -119.634516)
			(xy 180.778 -119.642501) (xy 180.832417 -119.658302) (xy 180.884069 -119.681606) (xy 180.931926 -119.711947)
			(xy 180.975036 -119.748723) (xy 181.012541 -119.7912) (xy 181.043694 -119.838533) (xy 181.067875 -119.889779)
			(xy 181.084602 -119.943919) (xy 181.089554 -119.97182) (xy 181.091078 -119.982234) (xy 181.102254 -119.99976)
			(xy 181.179978 -120.053354) (xy 181.200044 -120.057418) (xy 181.210458 -120.055386) (xy 181.233379 -120.050963)
			(xy 181.279825 -120.046253) (xy 181.303168 -120.045988) (xy 181.32651 -120.046268) (xy 181.372956 -120.050972)
			(xy 181.395878 -120.055386) (xy 181.406292 -120.057418) (xy 181.426358 -120.053354) (xy 181.504082 -119.99976)
			(xy 181.515258 -119.982234) (xy 181.516782 -119.97182) (xy 181.521735 -119.943916) (xy 181.538444 -119.889765)
			(xy 181.562613 -119.838506) (xy 181.59376 -119.791161) (xy 181.631263 -119.748675) (xy 181.674376 -119.711893)
			(xy 181.722239 -119.68155) (xy 181.773899 -119.658249) (xy 181.828325 -119.642456) (xy 181.884432 -119.634485)
			(xy 181.912768 -119.634) (xy 181.942127 -119.634498) (xy 182.000218 -119.643064) (xy 182.056441 -119.660004)
			(xy 182.109595 -119.684956) (xy 182.158545 -119.717388) (xy 182.180738 -119.736616) (xy 182.187926 -119.742614)
			(xy 182.205416 -119.749263) (xy 182.214774 -119.74957) (xy 182.245762 -119.74957) (xy 182.2551 -119.749174)
			(xy 182.272552 -119.742521) (xy 182.279798 -119.736616) (xy 182.301968 -119.717357) (xy 182.350909 -119.684899)
			(xy 182.404067 -119.65994) (xy 182.460301 -119.643016) (xy 182.518405 -119.634489) (xy 182.547768 -119.634)
			(xy 182.564804 -119.634129) (xy 182.598759 -119.636924) (xy 182.615586 -119.639588) (xy 182.62658 -119.64093)
			(xy 182.647927 -119.635128) (xy 182.656734 -119.628412) (xy 182.681372 -119.607838) (xy 182.689573 -119.600194)
			(xy 182.699067 -119.579916) (xy 182.69966 -119.568722) (xy 182.69966 -119.567198) (xy 182.69966 -118.701058)
			(xy 182.699077 -118.689855) (xy 182.68961 -118.669553) (xy 182.681372 -118.661942) (xy 182.656734 -118.641114)
			(xy 182.647887 -118.634476) (xy 182.626572 -118.628669) (xy 182.615586 -118.629938) (xy 182.598762 -118.632647)
			(xy 182.564808 -118.635574) (xy 182.547768 -118.63578) (xy 182.519122 -118.635239) (xy 182.462414 -118.627081)
			(xy 182.407445 -118.610937) (xy 182.355332 -118.587134) (xy 182.307137 -118.556157) (xy 182.26384 -118.518637)
			(xy 182.226324 -118.475338) (xy 182.195351 -118.42714) (xy 182.171552 -118.375025) (xy 182.155412 -118.320054)
			(xy 182.147259 -118.263346) (xy 182.147259 -118.206054) (xy 182.155412 -118.149346) (xy 182.171552 -118.094375)
			(xy 182.195351 -118.04226) (xy 182.226324 -117.994062) (xy 182.26384 -117.950763) (xy 182.307137 -117.913243)
			(xy 182.355332 -117.882266) (xy 182.407445 -117.858463) (xy 182.462414 -117.842319) (xy 182.519122 -117.834161)
			(xy 182.547768 -117.833648) (xy 182.576111 -117.834156) (xy 182.632229 -117.84216) (xy 182.686661 -117.857984)
			(xy 182.738324 -117.881314) (xy 182.786188 -117.911684) (xy 182.8293 -117.94849) (xy 182.866801 -117.990998)
			(xy 182.897944 -118.038363) (xy 182.922109 -118.08964) (xy 182.938815 -118.143808) (xy 182.943754 -118.171722)
			(xy 182.945278 -118.182136) (xy 182.956454 -118.199662) (xy 183.034178 -118.253256) (xy 183.054244 -118.25732)
			(xy 183.064658 -118.255288) (xy 183.087574 -118.250806) (xy 183.13402 -118.245967) (xy 183.157368 -118.245636)
			(xy 183.184686 -118.246023) (xy 183.238934 -118.252519) (xy 183.265572 -118.25859) (xy 183.275986 -118.261384)
			(xy 183.29656 -118.257574) (xy 183.376824 -118.204234) (xy 183.388254 -118.186454) (xy 183.389778 -118.175786)
			(xy 183.394168 -118.150551) (xy 183.408832 -118.101474) (xy 183.429931 -118.054801) (xy 183.457086 -118.01137)
			(xy 183.489809 -117.971964) (xy 183.52751 -117.937292) (xy 183.548274 -117.922294) (xy 183.559196 -117.914674)
			(xy 183.570626 -117.891052) (xy 183.56453 -117.778276) (xy 183.55056 -117.756178) (xy 183.538876 -117.749828)
			(xy 183.513542 -117.735334) (xy 183.467211 -117.699841) (xy 183.426825 -117.657708) (xy 183.393326 -117.609916)
			(xy 183.367494 -117.55758) (xy 183.349933 -117.501922) (xy 183.341053 -117.444238) (xy 183.340502 -117.415056)
			(xy 183.340988 -117.387805) (xy 183.348744 -117.333857) (xy 183.364099 -117.281562) (xy 183.386741 -117.231985)
			(xy 183.416207 -117.186135) (xy 183.451898 -117.144944) (xy 183.493089 -117.109253) (xy 183.538939 -117.079787)
			(xy 183.588516 -117.057145) (xy 183.640811 -117.04179) (xy 183.694759 -117.034034) (xy 183.749261 -117.034034)
			(xy 183.803209 -117.04179) (xy 183.855504 -117.057145) (xy 183.905081 -117.079787) (xy 183.950931 -117.109253)
			(xy 183.992122 -117.144944) (xy 184.027813 -117.186135) (xy 184.057279 -117.231985) (xy 184.079921 -117.281562)
			(xy 184.095276 -117.333857) (xy 184.103032 -117.387805) (xy 184.103518 -117.415056) (xy 184.103086 -117.441254)
			(xy 184.095917 -117.493156) (xy 184.081707 -117.543587) (xy 184.060724 -117.591597) (xy 184.033364 -117.636281)
			(xy 184.000143 -117.676797) (xy 183.961685 -117.712382) (xy 183.94045 -117.72773) (xy 183.929528 -117.73535)
			(xy 183.918098 -117.758972) (xy 183.924194 -117.871748) (xy 183.938164 -117.893846) (xy 183.949848 -117.900196)
			(xy 183.975197 -117.914664) (xy 184.021528 -117.950161) (xy 184.061912 -117.9923) (xy 184.09541 -118.040096)
			(xy 184.121238 -118.092436) (xy 184.138796 -118.148098) (xy 184.147673 -118.205785) (xy 184.148222 -118.234968)
			(xy 184.147715 -118.262219) (xy 184.139963 -118.316168) (xy 184.124611 -118.368464) (xy 184.123518 -118.370858)
			(xy 185.366406 -118.370858) (xy 185.366893 -118.342073) (xy 185.375548 -118.285158) (xy 185.392656 -118.230189)
			(xy 185.417828 -118.178415) (xy 185.450494 -118.13101) (xy 185.48991 -118.089051) (xy 185.535183 -118.05349)
			(xy 185.585285 -118.025134) (xy 185.639079 -118.004627) (xy 185.695342 -117.992436) (xy 185.724038 -117.990112)
			(xy 185.735976 -117.98935) (xy 185.756804 -117.977412) (xy 185.814462 -117.88902) (xy 185.817256 -117.865144)
			(xy 185.812938 -117.853968) (xy 185.802316 -117.822573) (xy 185.790814 -117.757309) (xy 185.790078 -117.724174)
			(xy 185.790078 -117.723666) (xy 185.790564 -117.696415) (xy 185.79832 -117.642467) (xy 185.813675 -117.590172)
			(xy 185.836317 -117.540595) (xy 185.865783 -117.494745) (xy 185.901474 -117.453554) (xy 185.942665 -117.417863)
			(xy 185.988515 -117.388397) (xy 186.038092 -117.365755) (xy 186.090387 -117.3504) (xy 186.144335 -117.342644)
			(xy 186.198837 -117.342644) (xy 186.252785 -117.3504) (xy 186.30508 -117.365755) (xy 186.354657 -117.388397)
			(xy 186.400507 -117.417863) (xy 186.441698 -117.453554) (xy 186.477389 -117.494745) (xy 186.506855 -117.540595)
			(xy 186.529497 -117.590172) (xy 186.544852 -117.642467) (xy 186.552608 -117.696415) (xy 186.553094 -117.723666)
			(xy 186.55263 -117.752451) (xy 186.543971 -117.809367) (xy 186.526859 -117.864336) (xy 186.501684 -117.916111)
			(xy 186.469016 -117.963516) (xy 186.429597 -118.005475) (xy 186.384322 -118.041035) (xy 186.334218 -118.069391)
			(xy 186.280423 -118.089897) (xy 186.224158 -118.102089) (xy 186.195462 -118.104412) (xy 186.183524 -118.105174)
			(xy 186.162696 -118.117112) (xy 186.105038 -118.205504) (xy 186.102244 -118.22938) (xy 186.104403 -118.234968)
			(xy 187.98489 -118.234968) (xy 187.988961 -118.179346) (xy 188.001087 -118.124909) (xy 188.02101 -118.072818)
			(xy 188.048306 -118.024183) (xy 188.082392 -117.98004) (xy 188.122541 -117.941331) (xy 188.167899 -117.90888)
			(xy 188.217499 -117.883379) (xy 188.270283 -117.865372) (xy 188.325126 -117.855242) (xy 188.38086 -117.853205)
			(xy 188.436297 -117.859305) (xy 188.490254 -117.873411) (xy 188.541583 -117.895223) (xy 188.589189 -117.924277)
			(xy 188.632057 -117.959952) (xy 188.669274 -118.001489) (xy 188.700047 -118.048002) (xy 188.723719 -118.098499)
			(xy 188.739787 -118.151906) (xy 188.747907 -118.207082) (xy 188.748416 -118.234968) (xy 188.747918 -118.262256)
			(xy 189.967023 -118.262256) (xy 189.967023 -118.207744) (xy 189.974781 -118.153788) (xy 189.990139 -118.101485)
			(xy 190.012784 -118.0519) (xy 190.042255 -118.006043) (xy 190.077952 -117.964847) (xy 190.119149 -117.92915)
			(xy 190.165007 -117.89968) (xy 190.214593 -117.877036) (xy 190.266896 -117.861679) (xy 190.320852 -117.853922)
			(xy 190.348108 -117.85346) (xy 190.348616 -117.85346) (xy 190.373482 -117.853881) (xy 190.422788 -117.860379)
			(xy 190.446914 -117.866414) (xy 190.447168 -117.866414) (xy 190.458736 -117.86892) (xy 190.481916 -117.864301)
			(xy 190.491618 -117.857524) (xy 190.555372 -117.807486) (xy 190.564253 -117.799771) (xy 190.574448 -117.7786)
			(xy 190.57493 -117.766846) (xy 190.57493 -117.766592) (xy 190.574676 -117.758718) (xy 190.574676 -116.895118)
			(xy 190.575946 -116.862098) (xy 190.576277 -116.853508) (xy 190.571813 -116.836917) (xy 190.562103 -116.822743)
			(xy 190.555372 -116.817394) (xy 190.53048 -116.798852) (xy 190.523521 -116.794043) (xy 190.507384 -116.788994)
			(xy 190.490483 -116.789523) (xy 190.482474 -116.792248) (xy 190.450045 -116.803592) (xy 190.382455 -116.815856)
			(xy 190.348108 -116.816632) (xy 190.320856 -116.816121) (xy 190.266908 -116.808366) (xy 190.214613 -116.793011)
			(xy 190.165035 -116.770371) (xy 190.119183 -116.740905) (xy 190.077992 -116.705213) (xy 190.0423 -116.664023)
			(xy 190.012833 -116.618172) (xy 189.990191 -116.568595) (xy 189.974836 -116.5163) (xy 189.967079 -116.462352)
			(xy 189.967079 -116.407848) (xy 189.974836 -116.3539) (xy 189.990191 -116.301605) (xy 190.012833 -116.252028)
			(xy 190.0423 -116.206177) (xy 190.077992 -116.164987) (xy 190.119183 -116.129295) (xy 190.165035 -116.099829)
			(xy 190.214613 -116.077189) (xy 190.266908 -116.061834) (xy 190.320856 -116.054079) (xy 190.348108 -116.053616)
			(xy 190.375687 -116.054117) (xy 190.430267 -116.062074) (xy 190.483133 -116.077807) (xy 190.533184 -116.100987)
			(xy 190.579375 -116.131133) (xy 190.620744 -116.167615) (xy 190.656429 -116.209673) (xy 190.685687 -116.256431)
			(xy 190.707908 -116.306915) (xy 190.722629 -116.360072) (xy 190.726568 -116.387372) (xy 190.728092 -116.399056)
			(xy 190.740792 -116.418614) (xy 190.830454 -116.4717) (xy 190.853568 -116.473478) (xy 190.864744 -116.46916)
			(xy 190.891563 -116.459031) (xy 190.947096 -116.444796) (xy 191.003974 -116.437612) (xy 191.032638 -116.437156)
			(xy 191.062624 -116.437593) (xy 191.122082 -116.445425) (xy 191.180009 -116.460951) (xy 191.235414 -116.483906)
			(xy 191.28735 -116.513895) (xy 191.334926 -116.550407) (xy 191.37733 -116.592816) (xy 191.413836 -116.640397)
			(xy 191.443819 -116.692336) (xy 191.466767 -116.747744) (xy 191.482286 -116.805673) (xy 191.490111 -116.865132)
			(xy 191.4906 -116.895118) (xy 191.4906 -117.758718) (xy 191.490089 -117.788701) (xy 191.48226 -117.848154)
			(xy 191.466738 -117.906077) (xy 191.44379 -117.961478) (xy 191.413807 -118.013411) (xy 191.377302 -118.060985)
			(xy 191.334901 -118.103389) (xy 191.287327 -118.139896) (xy 191.235396 -118.169881) (xy 191.179996 -118.192832)
			(xy 191.122074 -118.208356) (xy 191.062621 -118.216188) (xy 191.032638 -118.21668) (xy 191.004202 -118.216244)
			(xy 190.947771 -118.209161) (xy 190.892651 -118.195148) (xy 190.866014 -118.185184) (xy 190.854776 -118.181414)
			(xy 190.831195 -118.183546) (xy 190.820802 -118.189248) (xy 190.741554 -118.23827) (xy 190.729108 -118.258336)
			(xy 190.728092 -118.270274) (xy 190.724898 -118.298308) (xy 190.711443 -118.353098) (xy 190.690069 -118.405311)
			(xy 190.661241 -118.453809) (xy 190.625589 -118.497535) (xy 190.583888 -118.535536) (xy 190.537047 -118.566984)
			(xy 190.486087 -118.591195) (xy 190.432119 -118.60764) (xy 190.376317 -118.615961) (xy 190.348108 -118.616476)
			(xy 190.320852 -118.616078) (xy 190.266896 -118.608321) (xy 190.214593 -118.592964) (xy 190.165007 -118.57032)
			(xy 190.119149 -118.54085) (xy 190.077952 -118.505153) (xy 190.042255 -118.463957) (xy 190.012784 -118.4181)
			(xy 189.990139 -118.368515) (xy 189.974781 -118.316212) (xy 189.967023 -118.262256) (xy 188.747918 -118.262256)
			(xy 188.747907 -118.262854) (xy 188.739787 -118.31803) (xy 188.723719 -118.371437) (xy 188.700047 -118.421934)
			(xy 188.669274 -118.468447) (xy 188.632057 -118.509984) (xy 188.589189 -118.545659) (xy 188.541583 -118.574713)
			(xy 188.490254 -118.596525) (xy 188.436297 -118.610631) (xy 188.38086 -118.616731) (xy 188.325126 -118.614694)
			(xy 188.270283 -118.604564) (xy 188.217499 -118.586557) (xy 188.167899 -118.561056) (xy 188.122541 -118.528605)
			(xy 188.082392 -118.489896) (xy 188.048306 -118.445753) (xy 188.02101 -118.397118) (xy 188.001087 -118.345027)
			(xy 187.988961 -118.29059) (xy 187.98489 -118.234968) (xy 186.104403 -118.234968) (xy 186.106562 -118.240556)
			(xy 186.113928 -118.263416) (xy 186.113928 -118.26367) (xy 186.116946 -118.272366) (xy 186.128152 -118.286953)
			(xy 186.135772 -118.292118) (xy 186.192922 -118.327932) (xy 186.200881 -118.332504) (xy 186.21886 -118.336139)
			(xy 186.227974 -118.335044) (xy 186.228482 -118.335044) (xy 186.244049 -118.33257) (xy 186.275459 -118.329899)
			(xy 186.29122 -118.32971) (xy 186.318472 -118.330161) (xy 186.37242 -118.33792) (xy 186.424715 -118.353278)
			(xy 186.474292 -118.375921) (xy 186.520142 -118.40539) (xy 186.561331 -118.441083) (xy 186.597022 -118.482274)
			(xy 186.626488 -118.528126) (xy 186.649129 -118.577704) (xy 186.664484 -118.63) (xy 186.67224 -118.683948)
			(xy 186.67224 -118.738452) (xy 186.664484 -118.7924) (xy 186.649129 -118.844696) (xy 186.626488 -118.894274)
			(xy 186.597022 -118.940126) (xy 186.561331 -118.981317) (xy 186.520142 -119.01701) (xy 186.474292 -119.046479)
			(xy 186.424715 -119.069122) (xy 186.37242 -119.08448) (xy 186.318472 -119.092239) (xy 186.29122 -119.092726)
			(xy 186.263973 -119.092177) (xy 186.210033 -119.084412) (xy 186.157747 -119.069052) (xy 186.108179 -119.04641)
			(xy 186.062336 -119.016946) (xy 186.021151 -118.981259) (xy 185.985463 -118.940076) (xy 185.955997 -118.894234)
			(xy 185.933353 -118.844666) (xy 185.925206 -118.81866) (xy 185.925206 -118.818406) (xy 185.922181 -118.809712)
			(xy 185.910982 -118.795122) (xy 185.903362 -118.789958) (xy 185.846212 -118.754144) (xy 185.838246 -118.749587)
			(xy 185.820273 -118.745944) (xy 185.81116 -118.747032) (xy 185.810652 -118.747032) (xy 185.795084 -118.749502)
			(xy 185.763675 -118.752176) (xy 185.747914 -118.752366) (xy 185.72066 -118.751932) (xy 185.666705 -118.744175)
			(xy 185.614404 -118.728819) (xy 185.564822 -118.706175) (xy 185.518966 -118.676705) (xy 185.477772 -118.641008)
			(xy 185.442079 -118.599811) (xy 185.412612 -118.553954) (xy 185.389971 -118.504369) (xy 185.374619 -118.452067)
			(xy 185.366866 -118.398112) (xy 185.366406 -118.370858) (xy 184.123518 -118.370858) (xy 184.101974 -118.418043)
			(xy 184.07251 -118.463896) (xy 184.036821 -118.505089) (xy 183.995633 -118.540783) (xy 183.949784 -118.570252)
			(xy 183.900207 -118.592895) (xy 183.847913 -118.608253) (xy 183.793965 -118.616012) (xy 183.766714 -118.616476)
			(xy 183.749666 -118.616282) (xy 183.715706 -118.613225) (xy 183.698896 -118.61038) (xy 183.687604 -118.60903)
			(xy 183.665715 -118.615091) (xy 183.656732 -118.622064) (xy 183.632348 -118.643146) (xy 183.623961 -118.651074)
			(xy 183.614836 -118.672245) (xy 183.614822 -118.683786) (xy 183.615076 -118.703598) (xy 183.615076 -119.441725)
			(xy 187.409571 -119.441725) (xy 187.409575 -119.387221) (xy 187.417336 -119.333273) (xy 187.432695 -119.280978)
			(xy 187.455341 -119.231401) (xy 187.484811 -119.185552) (xy 187.520507 -119.144363) (xy 187.561701 -119.108674)
			(xy 187.607556 -119.079211) (xy 187.657136 -119.056574) (xy 187.709433 -119.041223) (xy 187.763383 -119.033471)
			(xy 187.817887 -119.033476) (xy 187.871836 -119.041238) (xy 187.92413 -119.056598) (xy 187.973707 -119.079245)
			(xy 188.019555 -119.108717) (xy 188.060743 -119.144413) (xy 188.096431 -119.185608) (xy 188.125893 -119.231463)
			(xy 188.14853 -119.281044) (xy 188.163879 -119.333342) (xy 188.17163 -119.387292) (xy 188.17209 -119.414544)
			(xy 188.17209 -119.415052) (xy 188.171487 -119.445494) (xy 188.161789 -119.5056) (xy 188.152786 -119.534686)
			(xy 188.148927 -119.547704) (xy 188.147548 -119.574814) (xy 188.153361 -119.601328) (xy 188.165956 -119.625374)
			(xy 188.184441 -119.645251) (xy 188.207511 -119.659555) (xy 188.233535 -119.667274) (xy 188.260673 -119.667864)
			(xy 188.273944 -119.664988) (xy 188.296687 -119.659662) (xy 188.343045 -119.653928) (xy 188.3664 -119.653558)
			(xy 188.366908 -119.653558) (xy 188.394161 -119.654064) (xy 188.448111 -119.661822) (xy 188.500408 -119.677179)
			(xy 188.549987 -119.699823) (xy 188.595839 -119.729292) (xy 188.637031 -119.764987) (xy 188.672723 -119.80618)
			(xy 188.702189 -119.852034) (xy 188.724829 -119.901615) (xy 188.740183 -119.953913) (xy 188.747938 -120.007864)
			(xy 188.747937 -120.035066) (xy 189.96609 -120.035066) (xy 189.970161 -119.979444) (xy 189.982287 -119.925007)
			(xy 190.00221 -119.872916) (xy 190.029506 -119.824281) (xy 190.063592 -119.780138) (xy 190.103741 -119.741429)
			(xy 190.149099 -119.708978) (xy 190.198699 -119.683477) (xy 190.251483 -119.66547) (xy 190.306326 -119.65534)
			(xy 190.36206 -119.653303) (xy 190.417497 -119.659403) (xy 190.471454 -119.673509) (xy 190.522783 -119.695321)
			(xy 190.570389 -119.724375) (xy 190.613257 -119.76005) (xy 190.636088 -119.785531) (xy 196.598011 -119.785531)
			(xy 196.598011 -119.728269) (xy 196.60616 -119.67159) (xy 196.622294 -119.616648) (xy 196.646082 -119.564562)
			(xy 196.677042 -119.516391) (xy 196.714542 -119.473117) (xy 196.75782 -119.43562) (xy 196.805993 -119.404665)
			(xy 196.858082 -119.380881) (xy 196.913025 -119.364753) (xy 196.969705 -119.356608) (xy 196.998336 -119.356124)
			(xy 197.01325 -119.356234) (xy 197.042999 -119.358395) (xy 197.057772 -119.360442) (xy 197.068694 -119.361966)
			(xy 197.09003 -119.35587) (xy 197.156832 -119.298466) (xy 197.164874 -119.290911) (xy 197.17408 -119.270881)
			(xy 197.174612 -119.259858) (xy 197.174612 -118.99519) (xy 197.174076 -118.984171) (xy 197.164855 -118.964155)
			(xy 197.156832 -118.956582) (xy 197.09003 -118.899178) (xy 197.068948 -118.893082) (xy 197.057772 -118.894606)
			(xy 197.043062 -118.896646) (xy 197.01344 -118.898808) (xy 196.99859 -118.898924) (xy 196.969961 -118.898389)
			(xy 196.913287 -118.890239) (xy 196.858349 -118.874106) (xy 196.806266 -118.85032) (xy 196.758098 -118.819363)
			(xy 196.714826 -118.781867) (xy 196.677331 -118.738594) (xy 196.646375 -118.690426) (xy 196.62259 -118.638342)
			(xy 196.606459 -118.583404) (xy 196.59831 -118.526729) (xy 196.59831 -118.469471) (xy 196.606459 -118.412796)
			(xy 196.62259 -118.357858) (xy 196.646375 -118.305774) (xy 196.677331 -118.257606) (xy 196.714826 -118.214333)
			(xy 196.758098 -118.176837) (xy 196.806266 -118.14588) (xy 196.858349 -118.122094) (xy 196.913287 -118.105961)
			(xy 196.969961 -118.097811) (xy 196.99859 -118.0973) (xy 197.025959 -118.097785) (xy 197.08019 -118.105229)
			(xy 197.132904 -118.119978) (xy 197.183123 -118.14176) (xy 197.229912 -118.170169) (xy 197.272403 -118.204678)
			(xy 197.309806 -118.244645) (xy 197.325996 -118.266718) (xy 197.331596 -118.273939) (xy 197.34669 -118.284217)
			(xy 197.35546 -118.286784) (xy 197.385178 -118.293896) (xy 197.394189 -118.295726) (xy 197.412426 -118.293509)
			(xy 197.420738 -118.289578) (xy 197.445318 -118.277252) (xy 197.4968 -118.257931) (xy 197.550225 -118.244915)
			(xy 197.604825 -118.238392) (xy 197.63232 -118.238016) (xy 197.659821 -118.238437) (xy 197.714426 -118.245026)
			(xy 197.76785 -118.258106) (xy 197.819323 -118.277489) (xy 197.843902 -118.289832) (xy 197.852278 -118.293771)
			(xy 197.870642 -118.295981) (xy 197.879716 -118.29415) (xy 197.909434 -118.286784) (xy 197.918216 -118.284242)
			(xy 197.933316 -118.273958) (xy 197.938898 -118.266718) (xy 197.955075 -118.244635) (xy 197.99248 -118.204666)
			(xy 198.034972 -118.170155) (xy 198.081764 -118.141744) (xy 198.131984 -118.11996) (xy 198.1847 -118.105209)
			(xy 198.238933 -118.097765) (xy 198.266304 -118.0973) (xy 198.294935 -118.097787) (xy 198.351613 -118.105937)
			(xy 198.406555 -118.122069) (xy 198.458642 -118.145857) (xy 198.506814 -118.176815) (xy 198.550089 -118.214314)
			(xy 198.587587 -118.25759) (xy 198.618545 -118.305761) (xy 198.642332 -118.357848) (xy 198.658464 -118.41279)
			(xy 198.666613 -118.469469) (xy 198.666613 -118.526731) (xy 198.658464 -118.58341) (xy 198.642332 -118.638352)
			(xy 198.618545 -118.690439) (xy 198.587587 -118.73861) (xy 198.550089 -118.781886) (xy 198.506814 -118.819385)
			(xy 198.458642 -118.850343) (xy 198.406555 -118.874131) (xy 198.351613 -118.890263) (xy 198.294935 -118.898413)
			(xy 198.266304 -118.898924) (xy 198.25139 -118.89882) (xy 198.221641 -118.896655) (xy 198.206868 -118.894606)
			(xy 198.195946 -118.893082) (xy 198.17461 -118.899178) (xy 198.107808 -118.956582) (xy 198.099796 -118.964164)
			(xy 198.090571 -118.984173) (xy 198.090028 -118.99519) (xy 198.090028 -119.259858) (xy 198.09058 -119.270875)
			(xy 198.099789 -119.290893) (xy 198.107808 -119.298466) (xy 198.17461 -119.35587) (xy 198.195946 -119.361966)
			(xy 198.206868 -119.360442) (xy 198.221641 -119.358391) (xy 198.25139 -119.356232) (xy 198.266304 -119.356124)
			(xy 198.294937 -119.356563) (xy 198.351619 -119.364713) (xy 198.406564 -119.380847) (xy 198.458654 -119.404636)
			(xy 198.506828 -119.435596) (xy 198.550106 -119.473097) (xy 198.587606 -119.516375) (xy 198.618566 -119.56455)
			(xy 198.642354 -119.61664) (xy 198.658488 -119.671585) (xy 198.666637 -119.728267) (xy 198.666637 -119.785533)
			(xy 198.658488 -119.842215) (xy 198.642354 -119.89716) (xy 198.618566 -119.94925) (xy 198.587606 -119.997425)
			(xy 198.550106 -120.040703) (xy 198.506828 -120.078204) (xy 198.458654 -120.109164) (xy 198.406564 -120.132953)
			(xy 198.351619 -120.149087) (xy 198.294937 -120.157237) (xy 198.266304 -120.157748) (xy 198.238933 -120.157289)
			(xy 198.184701 -120.149844) (xy 198.131985 -120.135091) (xy 198.081766 -120.113306) (xy 198.034976 -120.084892)
			(xy 197.992486 -120.050378) (xy 197.955086 -120.010405) (xy 197.938898 -119.98833) (xy 197.933329 -119.981075)
			(xy 197.918225 -119.970787) (xy 197.909434 -119.968264) (xy 197.879716 -119.960898) (xy 197.870645 -119.959038)
			(xy 197.852276 -119.961263) (xy 197.843902 -119.965216) (xy 197.815784 -119.979278) (xy 197.75658 -120.000424)
			(xy 197.69504 -120.013273) (xy 197.63232 -120.017583) (xy 197.5696 -120.013273) (xy 197.50806 -120.000424)
			(xy 197.448856 -119.979278) (xy 197.420738 -119.965216) (xy 197.412354 -119.961296) (xy 197.393997 -119.959075)
			(xy 197.384924 -119.960898) (xy 197.355206 -119.968264) (xy 197.346424 -119.970808) (xy 197.331323 -119.981089)
			(xy 197.325742 -119.98833) (xy 197.309525 -120.010382) (xy 197.272129 -120.050355) (xy 197.229644 -120.08487)
			(xy 197.18286 -120.113286) (xy 197.132645 -120.135074) (xy 197.079934 -120.14983) (xy 197.025705 -120.15728)
			(xy 196.998336 -120.157748) (xy 196.969705 -120.157192) (xy 196.913025 -120.149047) (xy 196.858082 -120.132919)
			(xy 196.805993 -120.109135) (xy 196.75782 -120.07818) (xy 196.714542 -120.040683) (xy 196.677042 -119.997409)
			(xy 196.646082 -119.949238) (xy 196.622294 -119.897152) (xy 196.60616 -119.84221) (xy 196.598011 -119.785531)
			(xy 190.636088 -119.785531) (xy 190.650474 -119.801587) (xy 190.681247 -119.8481) (xy 190.704919 -119.898597)
			(xy 190.720987 -119.952004) (xy 190.729107 -120.00718) (xy 190.729616 -120.035066) (xy 190.729107 -120.062952)
			(xy 190.720987 -120.118128) (xy 190.704919 -120.171535) (xy 190.681247 -120.222032) (xy 190.650474 -120.268545)
			(xy 190.613257 -120.310082) (xy 190.585433 -120.333237) (xy 199.240035 -120.333237) (xy 199.240035 -120.275963)
			(xy 199.248186 -120.219273) (xy 199.264323 -120.16432) (xy 199.288117 -120.112223) (xy 199.319083 -120.064043)
			(xy 199.356591 -120.02076) (xy 199.399878 -119.983257) (xy 199.448062 -119.952296) (xy 199.500161 -119.928508)
			(xy 199.555116 -119.912377) (xy 199.611807 -119.904232) (xy 199.640444 -119.903748) (xy 199.667813 -119.904248)
			(xy 199.722044 -119.911686) (xy 199.774759 -119.926431) (xy 199.824978 -119.94821) (xy 199.871768 -119.976618)
			(xy 199.914259 -120.011126) (xy 199.951661 -120.051093) (xy 199.96785 -120.073166) (xy 199.973403 -120.080435)
			(xy 199.988518 -120.090716) (xy 199.997314 -120.093232) (xy 200.027032 -120.100598) (xy 200.036107 -120.102431)
			(xy 200.054471 -120.100224) (xy 200.062846 -120.09628) (xy 200.090964 -120.082218) (xy 200.150168 -120.061072)
			(xy 200.211708 -120.048223) (xy 200.274428 -120.043913) (xy 200.337148 -120.048223) (xy 200.398688 -120.061072)
			(xy 200.457892 -120.082218) (xy 200.48601 -120.09628) (xy 200.494384 -120.100224) (xy 200.51275 -120.10243)
			(xy 200.521824 -120.100598) (xy 200.551542 -120.093232) (xy 200.560331 -120.090709) (xy 200.575428 -120.080413)
			(xy 200.581006 -120.073166) (xy 200.597193 -120.05109) (xy 200.634594 -120.011118) (xy 200.677084 -119.976606)
			(xy 200.723874 -119.948193) (xy 200.774093 -119.926408) (xy 200.826809 -119.911657) (xy 200.881042 -119.904213)
			(xy 200.908412 -119.903748) (xy 200.937039 -119.904339) (xy 200.993709 -119.912489) (xy 201.048643 -119.92862)
			(xy 201.100722 -119.952405) (xy 201.148886 -119.98336) (xy 201.192155 -120.020854) (xy 201.229647 -120.064123)
			(xy 201.2606 -120.112288) (xy 201.284384 -120.164368) (xy 201.300514 -120.219303) (xy 201.308662 -120.275973)
			(xy 201.308662 -120.333227) (xy 201.300514 -120.389897) (xy 201.284384 -120.444832) (xy 201.2606 -120.496912)
			(xy 201.229647 -120.545077) (xy 201.192155 -120.588346) (xy 201.148886 -120.62584) (xy 201.100722 -120.656795)
			(xy 201.048643 -120.68058) (xy 200.993709 -120.696711) (xy 200.937039 -120.704861) (xy 200.908412 -120.705372)
			(xy 200.893498 -120.705267) (xy 200.863749 -120.703103) (xy 200.848976 -120.701054) (xy 200.838054 -120.69953)
			(xy 200.816718 -120.705626) (xy 200.749916 -120.76303) (xy 200.741884 -120.770594) (xy 200.73267 -120.790617)
			(xy 200.732136 -120.801638) (xy 200.732136 -121.066306) (xy 200.732659 -121.077327) (xy 200.741888 -121.097344)
			(xy 200.749916 -121.104914) (xy 200.816718 -121.162318) (xy 200.838054 -121.168414) (xy 200.848976 -121.16689)
			(xy 200.863749 -121.164838) (xy 200.893498 -121.162679) (xy 200.908412 -121.162572) (xy 200.93704 -121.163115)
			(xy 200.993714 -121.171265) (xy 201.048651 -121.187398) (xy 201.100734 -121.211184) (xy 201.148901 -121.242141)
			(xy 201.192172 -121.279637) (xy 201.229667 -121.322909) (xy 201.260621 -121.371077) (xy 201.284406 -121.42316)
			(xy 201.300537 -121.478097) (xy 201.308686 -121.534772) (xy 201.308686 -121.592028) (xy 201.300537 -121.648703)
			(xy 201.284406 -121.70364) (xy 201.260621 -121.755723) (xy 201.229667 -121.803891) (xy 201.192172 -121.847163)
			(xy 201.148901 -121.884659) (xy 201.100734 -121.915616) (xy 201.048651 -121.939402) (xy 200.993714 -121.955535)
			(xy 200.93704 -121.963685) (xy 200.908412 -121.964196) (xy 200.881042 -121.963711) (xy 200.826812 -121.956268)
			(xy 200.774098 -121.941518) (xy 200.723879 -121.919736) (xy 200.677089 -121.891327) (xy 200.634598 -121.856818)
			(xy 200.597196 -121.816851) (xy 200.581006 -121.794778) (xy 200.575425 -121.787534) (xy 200.56033 -121.777239)
			(xy 200.551542 -121.774712) (xy 200.521824 -121.767346) (xy 200.512753 -121.765485) (xy 200.494384 -121.76771)
			(xy 200.48601 -121.771664) (xy 200.457892 -121.785726) (xy 200.398688 -121.806872) (xy 200.337148 -121.819721)
			(xy 200.274428 -121.824031) (xy 200.211708 -121.819721) (xy 200.150168 -121.806872) (xy 200.090964 -121.785726)
			(xy 200.062846 -121.771664) (xy 200.05446 -121.767749) (xy 200.036104 -121.765523) (xy 200.027032 -121.767346)
			(xy 199.997314 -121.774712) (xy 199.988539 -121.777275) (xy 199.973435 -121.787543) (xy 199.96785 -121.794778)
			(xy 199.951642 -121.816837) (xy 199.914243 -121.856807) (xy 199.871756 -121.89132) (xy 199.82497 -121.919734)
			(xy 199.774754 -121.941522) (xy 199.722042 -121.956278) (xy 199.667813 -121.963728) (xy 199.640444 -121.964196)
			(xy 199.611809 -121.963744) (xy 199.555121 -121.9556) (xy 199.50017 -121.93947) (xy 199.448073 -121.915683)
			(xy 199.399892 -121.884724) (xy 199.356608 -121.847223) (xy 199.319102 -121.803943) (xy 199.288138 -121.755766)
			(xy 199.264346 -121.703672) (xy 199.24821 -121.648722) (xy 199.240059 -121.592035) (xy 199.240059 -121.534765)
			(xy 199.24821 -121.478078) (xy 199.264346 -121.423128) (xy 199.288138 -121.371034) (xy 199.319102 -121.322857)
			(xy 199.356608 -121.279577) (xy 199.399892 -121.242076) (xy 199.448073 -121.211117) (xy 199.50017 -121.18733)
			(xy 199.555121 -121.1712) (xy 199.611809 -121.163056) (xy 199.640444 -121.162572) (xy 199.655358 -121.162681)
			(xy 199.685107 -121.164843) (xy 199.69988 -121.16689) (xy 199.710802 -121.168414) (xy 199.732138 -121.162318)
			(xy 199.79894 -121.104914) (xy 199.806961 -121.09734) (xy 199.816179 -121.077324) (xy 199.81672 -121.066306)
			(xy 199.81672 -120.801638) (xy 199.816155 -120.790623) (xy 199.806954 -120.770606) (xy 199.79894 -120.76303)
			(xy 199.732138 -120.705626) (xy 199.710802 -120.69953) (xy 199.69988 -120.701054) (xy 199.685107 -120.703099)
			(xy 199.655358 -120.705262) (xy 199.640444 -120.705372) (xy 199.611807 -120.704968) (xy 199.555116 -120.696823)
			(xy 199.500161 -120.680692) (xy 199.448062 -120.656904) (xy 199.399878 -120.625943) (xy 199.356591 -120.58844)
			(xy 199.319083 -120.545157) (xy 199.288117 -120.496977) (xy 199.264323 -120.44488) (xy 199.248186 -120.389927)
			(xy 199.240035 -120.333237) (xy 190.585433 -120.333237) (xy 190.570389 -120.345757) (xy 190.522783 -120.374811)
			(xy 190.471454 -120.396623) (xy 190.417497 -120.410729) (xy 190.36206 -120.416829) (xy 190.306326 -120.414792)
			(xy 190.251483 -120.404662) (xy 190.198699 -120.386655) (xy 190.149099 -120.361154) (xy 190.103741 -120.328703)
			(xy 190.063592 -120.289994) (xy 190.029506 -120.245851) (xy 190.00221 -120.197216) (xy 189.982287 -120.145125)
			(xy 189.970161 -120.090688) (xy 189.96609 -120.035066) (xy 188.747937 -120.035066) (xy 188.747935 -120.062369)
			(xy 188.740176 -120.11632) (xy 188.724818 -120.168616) (xy 188.702173 -120.218195) (xy 188.672703 -120.264046)
			(xy 188.637007 -120.305237) (xy 188.595813 -120.340928) (xy 188.549958 -120.370393) (xy 188.500377 -120.393032)
			(xy 188.448078 -120.408385) (xy 188.394127 -120.416138) (xy 188.339622 -120.416135) (xy 188.285672 -120.408374)
			(xy 188.233376 -120.393015) (xy 188.183797 -120.370369) (xy 188.137947 -120.340897) (xy 188.096757 -120.305201)
			(xy 188.061067 -120.264006) (xy 188.031603 -120.21815) (xy 188.008965 -120.168569) (xy 187.993613 -120.11627)
			(xy 187.985861 -120.062319) (xy 187.9854 -120.035066) (xy 187.9854 -120.034558) (xy 187.986005 -120.004116)
			(xy 187.995702 -119.94401) (xy 188.004704 -119.914924) (xy 188.008563 -119.901905) (xy 188.009945 -119.874795)
			(xy 188.004133 -119.848279) (xy 187.991539 -119.824232) (xy 187.973053 -119.804353) (xy 187.949982 -119.79005)
			(xy 187.923957 -119.782332) (xy 187.896817 -119.781745) (xy 187.883546 -119.784622) (xy 187.860803 -119.78995)
			(xy 187.814445 -119.795683) (xy 187.79109 -119.796052) (xy 187.790582 -119.796052) (xy 187.76333 -119.795525)
			(xy 187.709381 -119.787766) (xy 187.657086 -119.772408) (xy 187.607509 -119.749763) (xy 187.561659 -119.720294)
			(xy 187.520469 -119.684599) (xy 187.484779 -119.643406) (xy 187.455315 -119.597552) (xy 187.432677 -119.547972)
			(xy 187.417324 -119.495675) (xy 187.409571 -119.441725) (xy 183.615076 -119.441725) (xy 183.615076 -119.567198)
			(xy 183.614822 -119.586502) (xy 183.615014 -119.597948) (xy 183.624128 -119.618919) (xy 183.632348 -119.626888)
			(xy 183.656732 -119.64797) (xy 183.665708 -119.654963) (xy 183.687603 -119.661037) (xy 183.698896 -119.659654)
			(xy 183.715704 -119.656792) (xy 183.749665 -119.65374) (xy 183.766714 -119.653558) (xy 183.793962 -119.654113)
			(xy 183.847903 -119.661871) (xy 183.900192 -119.677226) (xy 183.949763 -119.699865) (xy 183.995607 -119.729329)
			(xy 184.036792 -119.765018) (xy 184.072479 -119.806204) (xy 184.101941 -119.852049) (xy 184.124579 -119.901621)
			(xy 184.139932 -119.95391) (xy 184.147688 -120.007852) (xy 184.147688 -120.062348) (xy 184.139932 -120.11629)
			(xy 184.124579 -120.168579) (xy 184.101941 -120.218151) (xy 184.072479 -120.263996) (xy 184.036792 -120.305182)
			(xy 183.995607 -120.340871) (xy 183.949763 -120.370335) (xy 183.900192 -120.392974) (xy 183.847903 -120.408329)
			(xy 183.793962 -120.416087) (xy 183.766714 -120.416574) (xy 183.739738 -120.416066) (xy 183.686322 -120.408487)
			(xy 183.634508 -120.393451) (xy 183.585332 -120.371259) (xy 183.539778 -120.342353) (xy 183.498756 -120.307311)
			(xy 183.463085 -120.266835) (xy 183.433479 -120.221732) (xy 183.410529 -120.172905) (xy 183.394695 -120.12133)
			(xy 183.390032 -120.094756) (xy 183.388254 -120.084088) (xy 183.376824 -120.066562) (xy 183.296814 -120.013222)
			(xy 183.275986 -120.009412) (xy 183.265572 -120.011952) (xy 183.238939 -120.018076) (xy 183.184692 -120.024701)
			(xy 183.157368 -120.02516) (xy 183.133957 -120.024826) (xy 183.087383 -120.019995) (xy 183.064404 -120.015508)
			(xy 183.054244 -120.013476) (xy 183.033924 -120.01754) (xy 182.9562 -120.071134) (xy 182.945278 -120.088406)
			(xy 182.9435 -120.09882) (xy 182.938463 -120.126651) (xy 182.921663 -120.180654) (xy 182.89744 -120.231761)
			(xy 182.866275 -120.278956) (xy 182.828787 -120.321303) (xy 182.785719 -120.357961) (xy 182.737927 -120.388203)
			(xy 182.68636 -120.411428) (xy 182.63204 -120.427176) (xy 182.576046 -120.435134) (xy 182.547768 -120.435624)
			(xy 182.51841 -120.435099) (xy 182.46032 -120.426538) (xy 182.404098 -120.409604) (xy 182.350944 -120.384658)
			(xy 182.301992 -120.352233) (xy 182.279798 -120.333008) (xy 182.272596 -120.327029) (xy 182.255117 -120.320368)
			(xy 182.245762 -120.320054) (xy 182.214774 -120.320054) (xy 182.205437 -120.320462) (xy 182.187985 -120.327106)
			(xy 182.180738 -120.333008) (xy 182.158543 -120.352238) (xy 182.10961 -120.384703) (xy 182.056459 -120.409669)
			(xy 182.00023 -120.4266) (xy 181.94213 -120.435132) (xy 181.912768 -120.435624) (xy 181.895732 -120.435504)
			(xy 181.861776 -120.432704) (xy 181.84495 -120.430036) (xy 181.833955 -120.428711) (xy 181.812609 -120.4345)
			(xy 181.803802 -120.441212) (xy 181.779164 -120.46204) (xy 181.770934 -120.469658) (xy 181.761454 -120.489955)
			(xy 181.760876 -120.501156) (xy 181.760876 -120.503696) (xy 181.760876 -120.716548) (xy 185.401964 -120.716548)
			(xy 185.406035 -120.660926) (xy 185.418161 -120.606489) (xy 185.438084 -120.554398) (xy 185.46538 -120.505763)
			(xy 185.499466 -120.46162) (xy 185.539615 -120.422911) (xy 185.584973 -120.39046) (xy 185.634573 -120.364959)
			(xy 185.687357 -120.346952) (xy 185.7422 -120.336822) (xy 185.797934 -120.334785) (xy 185.853371 -120.340885)
			(xy 185.907328 -120.354991) (xy 185.958657 -120.376803) (xy 186.006263 -120.405857) (xy 186.049131 -120.441532)
			(xy 186.086348 -120.483069) (xy 186.117121 -120.529582) (xy 186.140793 -120.580079) (xy 186.156861 -120.633486)
			(xy 186.164981 -120.688662) (xy 186.16549 -120.716548) (xy 186.164981 -120.744434) (xy 186.156861 -120.79961)
			(xy 186.140793 -120.853017) (xy 186.117121 -120.903514) (xy 186.086348 -120.950027) (xy 186.049131 -120.991564)
			(xy 186.006263 -121.027239) (xy 185.958657 -121.056293) (xy 185.907328 -121.078105) (xy 185.853371 -121.092211)
			(xy 185.797934 -121.098311) (xy 185.7422 -121.096274) (xy 185.687357 -121.086144) (xy 185.634573 -121.068137)
			(xy 185.584973 -121.042636) (xy 185.539615 -121.010185) (xy 185.499466 -120.971476) (xy 185.46538 -120.927333)
			(xy 185.438084 -120.878698) (xy 185.418161 -120.826607) (xy 185.406035 -120.77217) (xy 185.401964 -120.716548)
			(xy 181.760876 -120.716548) (xy 181.760876 -121.36882) (xy 181.761404 -121.38003) (xy 181.770908 -121.400332)
			(xy 181.779164 -121.407936) (xy 181.803802 -121.42851) (xy 181.812635 -121.43517) (xy 181.833962 -121.440963)
			(xy 181.84495 -121.439686) (xy 181.861774 -121.436973) (xy 181.895728 -121.434048) (xy 181.912768 -121.433844)
			(xy 181.942127 -121.434347) (xy 182.000215 -121.442922) (xy 182.056435 -121.459864) (xy 182.109588 -121.484813)
			(xy 182.158542 -121.517236) (xy 182.180738 -121.53646) (xy 182.187834 -121.542511) (xy 182.205201 -121.54928)
			(xy 182.21452 -121.549668) (xy 182.245762 -121.549668) (xy 182.255064 -121.5492) (xy 182.272396 -121.54243)
			(xy 182.279544 -121.53646) (xy 182.301767 -121.51723) (xy 182.350763 -121.484781) (xy 182.403967 -121.459823)
			(xy 182.460242 -121.44289) (xy 182.518384 -121.434345) (xy 182.547768 -121.433844) (xy 182.576098 -121.434407)
			(xy 182.632194 -121.44239) (xy 182.686607 -121.458189) (xy 182.738256 -121.481489) (xy 182.786111 -121.511825)
			(xy 182.829221 -121.548595) (xy 182.866726 -121.591066) (xy 182.897881 -121.638392) (xy 182.922066 -121.689632)
			(xy 182.938798 -121.743766) (xy 182.943754 -121.771664) (xy 182.945278 -121.782078) (xy 182.956454 -121.799604)
			(xy 183.034178 -121.853198) (xy 183.054244 -121.857262) (xy 183.064658 -121.85523) (xy 183.087579 -121.850806)
			(xy 183.134025 -121.846097) (xy 183.157368 -121.845832) (xy 183.184679 -121.846154) (xy 183.238928 -121.852523)
			(xy 183.265572 -121.858532) (xy 183.275986 -121.861326) (xy 183.29656 -121.857516) (xy 183.376824 -121.804176)
			(xy 183.388254 -121.786396) (xy 183.389778 -121.775728) (xy 183.394392 -121.749114) (xy 183.410224 -121.697472)
			(xy 183.433179 -121.648578) (xy 183.4628 -121.60341) (xy 183.498494 -121.56287) (xy 183.539548 -121.527768)
			(xy 183.585142 -121.498806) (xy 183.634365 -121.476564) (xy 183.686232 -121.461484) (xy 183.739707 -121.453869)
			(xy 183.766714 -121.453402) (xy 183.793965 -121.453869) (xy 183.847913 -121.461627) (xy 183.900207 -121.476984)
			(xy 183.949784 -121.499626) (xy 183.995634 -121.529094) (xy 184.036824 -121.564786) (xy 184.072515 -121.605977)
			(xy 184.10198 -121.651828) (xy 184.10358 -121.655332) (xy 187.85027 -121.655332) (xy 187.854341 -121.59971)
			(xy 187.866467 -121.545273) (xy 187.88639 -121.493182) (xy 187.913686 -121.444547) (xy 187.947772 -121.400404)
			(xy 187.987921 -121.361695) (xy 188.033279 -121.329244) (xy 188.082879 -121.303743) (xy 188.135663 -121.285736)
			(xy 188.190506 -121.275606) (xy 188.24624 -121.273569) (xy 188.301677 -121.279669) (xy 188.355634 -121.293775)
			(xy 188.406963 -121.315587) (xy 188.454569 -121.344641) (xy 188.497437 -121.380316) (xy 188.534654 -121.421853)
			(xy 188.565427 -121.468366) (xy 188.589099 -121.518863) (xy 188.605167 -121.57227) (xy 188.613287 -121.627446)
			(xy 188.613796 -121.655332) (xy 188.613287 -121.683218) (xy 188.605167 -121.738394) (xy 188.589099 -121.791801)
			(xy 188.56889 -121.83491) (xy 189.96609 -121.83491) (xy 189.970161 -121.779288) (xy 189.982287 -121.724851)
			(xy 190.00221 -121.67276) (xy 190.029506 -121.624125) (xy 190.063592 -121.579982) (xy 190.103741 -121.541273)
			(xy 190.149099 -121.508822) (xy 190.198699 -121.483321) (xy 190.251483 -121.465314) (xy 190.306326 -121.455184)
			(xy 190.36206 -121.453147) (xy 190.417497 -121.459247) (xy 190.471454 -121.473353) (xy 190.522783 -121.495165)
			(xy 190.570389 -121.524219) (xy 190.613257 -121.559894) (xy 190.650474 -121.601431) (xy 190.681247 -121.647944)
			(xy 190.704919 -121.698441) (xy 190.720987 -121.751848) (xy 190.729107 -121.807024) (xy 190.729616 -121.83491)
			(xy 190.729107 -121.862796) (xy 190.720987 -121.917972) (xy 190.704919 -121.971379) (xy 190.681247 -122.021876)
			(xy 190.650474 -122.068389) (xy 190.613257 -122.109926) (xy 190.593035 -122.126755) (xy 196.597675 -122.126755)
			(xy 196.597675 -122.069445) (xy 196.605831 -122.012719) (xy 196.621978 -121.957731) (xy 196.645787 -121.9056)
			(xy 196.676773 -121.857389) (xy 196.714304 -121.814079) (xy 196.757618 -121.776551) (xy 196.805832 -121.74557)
			(xy 196.857964 -121.721766) (xy 196.912954 -121.705624) (xy 196.969681 -121.697472) (xy 196.998336 -121.696988)
			(xy 197.025717 -121.697432) (xy 197.079968 -121.704904) (xy 197.132697 -121.719691) (xy 197.182923 -121.741517)
			(xy 197.229711 -121.769976) (xy 197.27219 -121.804538) (xy 197.309569 -121.84456) (xy 197.325742 -121.86666)
			(xy 197.331299 -121.873926) (xy 197.346412 -121.884208) (xy 197.355206 -121.886726) (xy 197.384924 -121.894092)
			(xy 197.393999 -121.895922) (xy 197.412363 -121.893717) (xy 197.420738 -121.889774) (xy 197.445302 -121.877383)
			(xy 197.496769 -121.857933) (xy 197.550195 -121.844789) (xy 197.604811 -121.838141) (xy 197.63232 -121.837704)
			(xy 197.659829 -121.83814) (xy 197.714443 -121.844793) (xy 197.767868 -121.857942) (xy 197.819332 -121.877396)
			(xy 197.843902 -121.889774) (xy 197.852278 -121.893714) (xy 197.870642 -121.895923) (xy 197.879716 -121.894092)
			(xy 197.909434 -121.886726) (xy 197.918222 -121.884202) (xy 197.93332 -121.873907) (xy 197.938898 -121.86666)
			(xy 197.955082 -121.844567) (xy 197.99245 -121.804533) (xy 198.034923 -121.769962) (xy 198.081709 -121.741499)
			(xy 198.131936 -121.719674) (xy 198.184668 -121.704894) (xy 198.238922 -121.697434) (xy 198.266304 -121.696988)
			(xy 198.294949 -121.697591) (xy 198.351655 -121.705745) (xy 198.406624 -121.721886) (xy 198.458736 -121.745685)
			(xy 198.506931 -121.776658) (xy 198.550227 -121.814175) (xy 198.587744 -121.857472) (xy 198.618717 -121.905667)
			(xy 198.642516 -121.95778) (xy 198.658656 -122.012749) (xy 198.666809 -122.069455) (xy 198.666809 -122.126745)
			(xy 198.658656 -122.183451) (xy 198.642516 -122.23842) (xy 198.618717 -122.290533) (xy 198.587744 -122.338728)
			(xy 198.550227 -122.382025) (xy 198.506931 -122.419542) (xy 198.458736 -122.450515) (xy 198.406624 -122.474314)
			(xy 198.351655 -122.490455) (xy 198.294949 -122.498609) (xy 198.266304 -122.49912) (xy 198.251386 -122.498945)
			(xy 198.221637 -122.49666) (xy 198.206868 -122.494548) (xy 198.195946 -122.493024) (xy 198.17461 -122.49912)
			(xy 198.107808 -122.556524) (xy 198.099777 -122.564089) (xy 198.090563 -122.584111) (xy 198.090028 -122.595132)
			(xy 198.090028 -122.8598) (xy 198.090557 -122.87082) (xy 198.099782 -122.890837) (xy 198.107808 -122.898408)
			(xy 198.17461 -122.955812) (xy 198.195946 -122.961908) (xy 198.206868 -122.960384) (xy 198.221637 -122.958277)
			(xy 198.251386 -122.955988) (xy 198.266304 -122.955812) (xy 198.29495 -122.956367) (xy 198.35166 -122.964522)
			(xy 198.406632 -122.980663) (xy 198.458748 -123.004464) (xy 198.506945 -123.035439) (xy 198.550244 -123.072958)
			(xy 198.587763 -123.116258) (xy 198.618738 -123.164456) (xy 198.642538 -123.216571) (xy 198.658679 -123.271544)
			(xy 198.666833 -123.328254) (xy 198.666833 -123.385546) (xy 198.658679 -123.442256) (xy 198.642538 -123.497229)
			(xy 198.618738 -123.549344) (xy 198.587763 -123.597542) (xy 198.550244 -123.640842) (xy 198.506945 -123.678361)
			(xy 198.458748 -123.709336) (xy 198.406632 -123.733137) (xy 198.35166 -123.749278) (xy 198.29495 -123.757433)
			(xy 198.266304 -123.757944) (xy 198.238924 -123.757456) (xy 198.184676 -123.74999) (xy 198.131948 -123.73521)
			(xy 198.081723 -123.713391) (xy 198.034935 -123.684939) (xy 197.992455 -123.650384) (xy 197.955073 -123.610368)
			(xy 197.938898 -123.588272) (xy 197.933321 -123.581024) (xy 197.918223 -123.570731) (xy 197.909434 -123.568206)
			(xy 197.879716 -123.56084) (xy 197.870646 -123.558975) (xy 197.852276 -123.561203) (xy 197.843902 -123.565158)
			(xy 197.819332 -123.577536) (xy 197.767867 -123.596989) (xy 197.714443 -123.610136) (xy 197.659829 -123.616789)
			(xy 197.63232 -123.617228) (xy 197.604811 -123.616783) (xy 197.550197 -123.610134) (xy 197.496773 -123.596988)
			(xy 197.445308 -123.577536) (xy 197.420738 -123.565158) (xy 197.412354 -123.561239) (xy 197.393997 -123.559016)
			(xy 197.384924 -123.56084) (xy 197.355206 -123.568206) (xy 197.346431 -123.570767) (xy 197.331327 -123.581037)
			(xy 197.325742 -123.588272) (xy 197.309604 -123.6104) (xy 197.272227 -123.650432) (xy 197.229746 -123.684999)
			(xy 197.182952 -123.713458) (xy 197.132718 -123.735277) (xy 197.079979 -123.75005) (xy 197.02572 -123.757502)
			(xy 196.998336 -123.757944) (xy 196.969683 -123.757504) (xy 196.912959 -123.749353) (xy 196.857973 -123.733212)
			(xy 196.805843 -123.709409) (xy 196.757632 -123.67843) (xy 196.714321 -123.640904) (xy 196.676792 -123.597596)
			(xy 196.645808 -123.549388) (xy 196.622001 -123.497261) (xy 196.605855 -123.442276) (xy 196.597699 -123.385553)
			(xy 196.597699 -123.328247) (xy 196.605855 -123.271524) (xy 196.622001 -123.216539) (xy 196.645808 -123.164412)
			(xy 196.676792 -123.116204) (xy 196.714321 -123.072896) (xy 196.757632 -123.03537) (xy 196.805843 -123.004391)
			(xy 196.857973 -122.980588) (xy 196.912959 -122.964447) (xy 196.969683 -122.956296) (xy 196.998336 -122.955812)
			(xy 197.013254 -122.955983) (xy 197.043003 -122.958271) (xy 197.057772 -122.960384) (xy 197.068694 -122.961908)
			(xy 197.09003 -122.955812) (xy 197.156832 -122.898408) (xy 197.164855 -122.890836) (xy 197.174072 -122.870819)
			(xy 197.174612 -122.8598) (xy 197.174612 -122.595132) (xy 197.174053 -122.584116) (xy 197.164848 -122.564099)
			(xy 197.156832 -122.556524) (xy 197.09003 -122.49912) (xy 197.068694 -122.493024) (xy 197.057772 -122.494548)
			(xy 197.043002 -122.496651) (xy 197.013254 -122.498943) (xy 196.998336 -122.49912) (xy 196.969681 -122.498728)
			(xy 196.912954 -122.490576) (xy 196.857964 -122.474434) (xy 196.805832 -122.45063) (xy 196.757618 -122.419649)
			(xy 196.714304 -122.382121) (xy 196.676773 -122.338811) (xy 196.645787 -122.2906) (xy 196.621978 -122.238469)
			(xy 196.605831 -122.183481) (xy 196.597675 -122.126755) (xy 190.593035 -122.126755) (xy 190.570389 -122.145601)
			(xy 190.522783 -122.174655) (xy 190.471454 -122.196467) (xy 190.417497 -122.210573) (xy 190.36206 -122.216673)
			(xy 190.306326 -122.214636) (xy 190.251483 -122.204506) (xy 190.198699 -122.186499) (xy 190.149099 -122.160998)
			(xy 190.103741 -122.128547) (xy 190.063592 -122.089838) (xy 190.029506 -122.045695) (xy 190.00221 -121.99706)
			(xy 189.982287 -121.944969) (xy 189.970161 -121.890532) (xy 189.96609 -121.83491) (xy 188.56889 -121.83491)
			(xy 188.565427 -121.842298) (xy 188.534654 -121.888811) (xy 188.497437 -121.930348) (xy 188.454569 -121.966023)
			(xy 188.406963 -121.995077) (xy 188.355634 -122.016889) (xy 188.301677 -122.030995) (xy 188.24624 -122.037095)
			(xy 188.190506 -122.035058) (xy 188.135663 -122.024928) (xy 188.082879 -122.006921) (xy 188.033279 -121.98142)
			(xy 187.987921 -121.948969) (xy 187.947772 -121.91026) (xy 187.913686 -121.866117) (xy 187.88639 -121.817482)
			(xy 187.866467 -121.765391) (xy 187.854341 -121.710954) (xy 187.85027 -121.655332) (xy 184.10358 -121.655332)
			(xy 184.124621 -121.701406) (xy 184.139976 -121.753701) (xy 184.147732 -121.807649) (xy 184.147732 -121.862151)
			(xy 184.139976 -121.916099) (xy 184.124621 -121.968394) (xy 184.10198 -122.017972) (xy 184.072515 -122.063823)
			(xy 184.036824 -122.105014) (xy 183.995634 -122.140706) (xy 183.949784 -122.170174) (xy 183.900207 -122.192816)
			(xy 183.847913 -122.208173) (xy 183.793965 -122.215931) (xy 183.766714 -122.216418) (xy 183.749666 -122.216225)
			(xy 183.715706 -122.213168) (xy 183.698896 -122.210322) (xy 183.687604 -122.208986) (xy 183.665718 -122.215039)
			(xy 183.656732 -122.222006) (xy 183.632348 -122.243088) (xy 183.623989 -122.25104) (xy 183.614849 -122.272193)
			(xy 183.614822 -122.283728) (xy 183.615076 -122.30354) (xy 183.615076 -122.597164) (xy 185.401964 -122.597164)
			(xy 185.406035 -122.541542) (xy 185.418161 -122.487105) (xy 185.438084 -122.435014) (xy 185.46538 -122.386379)
			(xy 185.499466 -122.342236) (xy 185.539615 -122.303527) (xy 185.584973 -122.271076) (xy 185.634573 -122.245575)
			(xy 185.687357 -122.227568) (xy 185.7422 -122.217438) (xy 185.797934 -122.215401) (xy 185.853371 -122.221501)
			(xy 185.907328 -122.235607) (xy 185.958657 -122.257419) (xy 186.006263 -122.286473) (xy 186.049131 -122.322148)
			(xy 186.086348 -122.363685) (xy 186.117121 -122.410198) (xy 186.140793 -122.460695) (xy 186.156861 -122.514102)
			(xy 186.164981 -122.569278) (xy 186.16549 -122.597164) (xy 186.164981 -122.62505) (xy 186.156861 -122.680226)
			(xy 186.140793 -122.733633) (xy 186.117121 -122.78413) (xy 186.086348 -122.830643) (xy 186.049131 -122.87218)
			(xy 186.006263 -122.907855) (xy 185.958657 -122.936909) (xy 185.907328 -122.958721) (xy 185.853371 -122.972827)
			(xy 185.797934 -122.978927) (xy 185.7422 -122.97689) (xy 185.687357 -122.96676) (xy 185.634573 -122.948753)
			(xy 185.584973 -122.923252) (xy 185.539615 -122.890801) (xy 185.499466 -122.852092) (xy 185.46538 -122.807949)
			(xy 185.438084 -122.759314) (xy 185.418161 -122.707223) (xy 185.406035 -122.652786) (xy 185.401964 -122.597164)
			(xy 183.615076 -122.597164) (xy 183.615076 -123.16714) (xy 183.614822 -123.186444) (xy 183.615048 -123.197887)
			(xy 183.624137 -123.218857) (xy 183.632348 -123.22683) (xy 183.656732 -123.247912) (xy 183.665705 -123.254909)
			(xy 183.687602 -123.260979) (xy 183.698896 -123.259596) (xy 183.715704 -123.256735) (xy 183.749665 -123.253682)
			(xy 183.766714 -123.2535) (xy 183.793965 -123.253971) (xy 183.847913 -123.261729) (xy 183.900207 -123.277086)
			(xy 183.949783 -123.299728) (xy 183.995633 -123.329195) (xy 184.036822 -123.364888) (xy 184.072513 -123.406078)
			(xy 184.101979 -123.451929) (xy 184.124619 -123.501506) (xy 184.139974 -123.553801) (xy 184.14773 -123.607749)
			(xy 184.14773 -123.635008) (xy 187.98489 -123.635008) (xy 187.988961 -123.579386) (xy 188.001087 -123.524949)
			(xy 188.02101 -123.472858) (xy 188.048306 -123.424223) (xy 188.082392 -123.38008) (xy 188.122541 -123.341371)
			(xy 188.167899 -123.30892) (xy 188.217499 -123.283419) (xy 188.270283 -123.265412) (xy 188.325126 -123.255282)
			(xy 188.38086 -123.253245) (xy 188.436297 -123.259345) (xy 188.490254 -123.273451) (xy 188.541583 -123.295263)
			(xy 188.589189 -123.324317) (xy 188.632057 -123.359992) (xy 188.669274 -123.401529) (xy 188.700047 -123.448042)
			(xy 188.723719 -123.498539) (xy 188.739787 -123.551946) (xy 188.747907 -123.607122) (xy 188.748416 -123.635008)
			(xy 189.96609 -123.635008) (xy 189.970161 -123.579386) (xy 189.982287 -123.524949) (xy 190.00221 -123.472858)
			(xy 190.029506 -123.424223) (xy 190.063592 -123.38008) (xy 190.103741 -123.341371) (xy 190.149099 -123.30892)
			(xy 190.198699 -123.283419) (xy 190.251483 -123.265412) (xy 190.306326 -123.255282) (xy 190.36206 -123.253245)
			(xy 190.417497 -123.259345) (xy 190.471454 -123.273451) (xy 190.522783 -123.295263) (xy 190.570389 -123.324317)
			(xy 190.613257 -123.359992) (xy 190.650474 -123.401529) (xy 190.681247 -123.448042) (xy 190.704919 -123.498539)
			(xy 190.720987 -123.551946) (xy 190.729107 -123.607122) (xy 190.729616 -123.635008) (xy 190.729107 -123.662894)
			(xy 190.720987 -123.71807) (xy 190.704919 -123.771477) (xy 190.681247 -123.821974) (xy 190.650474 -123.868487)
			(xy 190.613257 -123.910024) (xy 190.585466 -123.933152) (xy 199.239823 -123.933152) (xy 199.239823 -123.875848)
			(xy 199.247979 -123.819128) (xy 199.264124 -123.764146) (xy 199.28793 -123.712021) (xy 199.318913 -123.663815)
			(xy 199.356441 -123.62051) (xy 199.399751 -123.582987) (xy 199.44796 -123.552009) (xy 199.500087 -123.528209)
			(xy 199.555071 -123.512069) (xy 199.611792 -123.50392) (xy 199.640444 -123.503436) (xy 199.667825 -123.503896)
			(xy 199.722074 -123.511368) (xy 199.774802 -123.526154) (xy 199.825027 -123.547978) (xy 199.871814 -123.576433)
			(xy 199.914294 -123.610992) (xy 199.951675 -123.65101) (xy 199.96785 -123.673108) (xy 199.973394 -123.680385)
			(xy 199.988517 -123.69066) (xy 199.997314 -123.693174) (xy 200.027032 -123.70054) (xy 200.036107 -123.702369)
			(xy 200.05447 -123.700163) (xy 200.062846 -123.696222) (xy 200.087411 -123.683832) (xy 200.138877 -123.664381)
			(xy 200.192303 -123.651237) (xy 200.246919 -123.644588) (xy 200.274428 -123.644152) (xy 200.301937 -123.644579)
			(xy 200.356552 -123.651234) (xy 200.409976 -123.664385) (xy 200.46144 -123.683842) (xy 200.48601 -123.696222)
			(xy 200.494385 -123.700165) (xy 200.51275 -123.702373) (xy 200.521824 -123.70054) (xy 200.551542 -123.693174)
			(xy 200.560326 -123.690638) (xy 200.575425 -123.68035) (xy 200.581006 -123.673108) (xy 200.59717 -123.651)
			(xy 200.634543 -123.610969) (xy 200.67702 -123.5764) (xy 200.72381 -123.54794) (xy 200.77404 -123.526117)
			(xy 200.826774 -123.511339) (xy 200.881029 -123.503882) (xy 200.908412 -123.503436) (xy 200.93706 -123.503944)
			(xy 200.993772 -123.5121) (xy 201.048747 -123.528243) (xy 201.100864 -123.552046) (xy 201.149064 -123.583023)
			(xy 201.192364 -123.620544) (xy 201.229884 -123.663846) (xy 201.26086 -123.712047) (xy 201.284661 -123.764165)
			(xy 201.300803 -123.81914) (xy 201.308957 -123.875852) (xy 201.308957 -123.933148) (xy 201.300803 -123.98986)
			(xy 201.284661 -124.044835) (xy 201.26086 -124.096953) (xy 201.229884 -124.145154) (xy 201.192364 -124.188456)
			(xy 201.149064 -124.225977) (xy 201.100864 -124.256954) (xy 201.048747 -124.280757) (xy 200.993772 -124.2969)
			(xy 200.93706 -124.305056) (xy 200.908412 -124.305568) (xy 200.893494 -124.305403) (xy 200.863745 -124.303111)
			(xy 200.848976 -124.300996) (xy 200.838054 -124.299472) (xy 200.816718 -124.305568) (xy 200.749916 -124.362972)
			(xy 200.74191 -124.37056) (xy 200.732682 -124.390565) (xy 200.732136 -124.40158) (xy 200.732136 -124.666248)
			(xy 200.732691 -124.677265) (xy 200.741897 -124.697283) (xy 200.749916 -124.704856) (xy 200.816718 -124.76226)
			(xy 200.838054 -124.768356) (xy 200.848976 -124.766832) (xy 200.863745 -124.764723) (xy 200.893494 -124.762436)
			(xy 200.908412 -124.76226) (xy 200.937062 -124.76272) (xy 200.993777 -124.770876) (xy 201.048755 -124.78702)
			(xy 201.100876 -124.810824) (xy 201.149078 -124.841803) (xy 201.192382 -124.879327) (xy 201.229904 -124.922631)
			(xy 201.260882 -124.970835) (xy 201.284684 -125.022956) (xy 201.300827 -125.077934) (xy 201.308981 -125.13465)
			(xy 201.308981 -125.19195) (xy 201.300827 -125.248666) (xy 201.284684 -125.303644) (xy 201.260882 -125.355765)
			(xy 201.229904 -125.403969) (xy 201.192382 -125.447273) (xy 201.149078 -125.484797) (xy 201.100876 -125.515776)
			(xy 201.048755 -125.53958) (xy 200.993777 -125.555724) (xy 200.937062 -125.56388) (xy 200.908412 -125.564392)
			(xy 200.881031 -125.56392) (xy 200.826781 -125.556454) (xy 200.774053 -125.541673) (xy 200.723827 -125.519852)
			(xy 200.677038 -125.491397) (xy 200.634559 -125.456838) (xy 200.597179 -125.416819) (xy 200.581006 -125.39472)
			(xy 200.575437 -125.387466) (xy 200.560333 -125.377178) (xy 200.551542 -125.374654) (xy 200.521824 -125.367288)
			(xy 200.512753 -125.365433) (xy 200.494385 -125.367655) (xy 200.48601 -125.371606) (xy 200.461436 -125.383977)
			(xy 200.409973 -125.403433) (xy 200.35655 -125.416582) (xy 200.301936 -125.423237) (xy 200.274428 -125.423676)
			(xy 200.24692 -125.423223) (xy 200.192306 -125.416575) (xy 200.138881 -125.403432) (xy 200.087417 -125.383982)
			(xy 200.062846 -125.371606) (xy 200.054461 -125.36769) (xy 200.036105 -125.365466) (xy 200.027032 -125.367288)
			(xy 199.997314 -125.374654) (xy 199.988535 -125.377204) (xy 199.973432 -125.387481) (xy 199.96785 -125.39472)
			(xy 199.951722 -125.416855) (xy 199.914342 -125.456884) (xy 199.871858 -125.49145) (xy 199.825062 -125.519906)
			(xy 199.774827 -125.541724) (xy 199.722088 -125.556497) (xy 199.667828 -125.563949) (xy 199.640444 -125.564392)
			(xy 199.611794 -125.563856) (xy 199.555076 -125.555707) (xy 199.500095 -125.539569) (xy 199.447971 -125.51577)
			(xy 199.399765 -125.484794) (xy 199.356458 -125.447273) (xy 199.318932 -125.40397) (xy 199.287951 -125.355767)
			(xy 199.264147 -125.303646) (xy 199.248002 -125.248667) (xy 199.239847 -125.19195) (xy 199.239847 -125.13465)
			(xy 199.248002 -125.077933) (xy 199.264147 -125.022954) (xy 199.287951 -124.970833) (xy 199.318932 -124.92263)
			(xy 199.356458 -124.879327) (xy 199.399765 -124.841806) (xy 199.447971 -124.81083) (xy 199.500095 -124.787031)
			(xy 199.555076 -124.770893) (xy 199.611794 -124.762744) (xy 199.640444 -124.76226) (xy 199.655362 -124.762429)
			(xy 199.685111 -124.764718) (xy 199.69988 -124.766832) (xy 199.710802 -124.768356) (xy 199.732138 -124.76226)
			(xy 199.79894 -124.704856) (xy 199.806942 -124.697265) (xy 199.816171 -124.677262) (xy 199.81672 -124.666248)
			(xy 199.81672 -124.40158) (xy 199.816187 -124.390561) (xy 199.806963 -124.370545) (xy 199.79894 -124.362972)
			(xy 199.732138 -124.305568) (xy 199.710802 -124.299472) (xy 199.69988 -124.300996) (xy 199.685111 -124.303109)
			(xy 199.655362 -124.305394) (xy 199.640444 -124.305568) (xy 199.611792 -124.30508) (xy 199.555071 -124.296931)
			(xy 199.500087 -124.280791) (xy 199.44796 -124.256991) (xy 199.399751 -124.226013) (xy 199.356441 -124.18849)
			(xy 199.318913 -124.145185) (xy 199.28793 -124.096979) (xy 199.264124 -124.044854) (xy 199.247979 -123.989872)
			(xy 199.239823 -123.933152) (xy 190.585466 -123.933152) (xy 190.570389 -123.945699) (xy 190.522783 -123.974753)
			(xy 190.471454 -123.996565) (xy 190.417497 -124.010671) (xy 190.36206 -124.016771) (xy 190.306326 -124.014734)
			(xy 190.251483 -124.004604) (xy 190.198699 -123.986597) (xy 190.149099 -123.961096) (xy 190.103741 -123.928645)
			(xy 190.063592 -123.889936) (xy 190.029506 -123.845793) (xy 190.00221 -123.797158) (xy 189.982287 -123.745067)
			(xy 189.970161 -123.69063) (xy 189.96609 -123.635008) (xy 188.748416 -123.635008) (xy 188.747907 -123.662894)
			(xy 188.739787 -123.71807) (xy 188.723719 -123.771477) (xy 188.700047 -123.821974) (xy 188.669274 -123.868487)
			(xy 188.632057 -123.910024) (xy 188.589189 -123.945699) (xy 188.541583 -123.974753) (xy 188.490254 -123.996565)
			(xy 188.436297 -124.010671) (xy 188.38086 -124.016771) (xy 188.325126 -124.014734) (xy 188.270283 -124.004604)
			(xy 188.217499 -123.986597) (xy 188.167899 -123.961096) (xy 188.122541 -123.928645) (xy 188.082392 -123.889936)
			(xy 188.048306 -123.845793) (xy 188.02101 -123.797158) (xy 188.001087 -123.745067) (xy 187.988961 -123.69063)
			(xy 187.98489 -123.635008) (xy 184.14773 -123.635008) (xy 184.14773 -123.662251) (xy 184.139974 -123.716199)
			(xy 184.124619 -123.768494) (xy 184.101979 -123.818071) (xy 184.072513 -123.863922) (xy 184.036822 -123.905112)
			(xy 183.995633 -123.940805) (xy 183.949783 -123.970272) (xy 183.900207 -123.992914) (xy 183.847913 -124.008271)
			(xy 183.793965 -124.016029) (xy 183.766714 -124.016516) (xy 183.739736 -124.016057) (xy 183.686315 -124.008477)
			(xy 183.634497 -123.993438) (xy 183.585319 -123.971241) (xy 183.539763 -123.94233) (xy 183.498739 -123.907283)
			(xy 183.463069 -123.866799) (xy 183.433466 -123.82169) (xy 183.41052 -123.772856) (xy 183.394692 -123.721275)
			(xy 183.390032 -123.694698) (xy 183.388254 -123.68403) (xy 183.376824 -123.666504) (xy 183.296814 -123.613164)
			(xy 183.275986 -123.609354) (xy 183.265572 -123.611894) (xy 183.238933 -123.617959) (xy 183.184685 -123.624451)
			(xy 183.157368 -123.624848) (xy 183.133962 -123.62458) (xy 183.087389 -123.619874) (xy 183.064404 -123.61545)
			(xy 183.054244 -123.613418) (xy 183.033924 -123.617482) (xy 182.9562 -123.671076) (xy 182.945278 -123.688348)
			(xy 182.9435 -123.698762) (xy 182.938534 -123.72662) (xy 182.921765 -123.780663) (xy 182.897561 -123.831811)
			(xy 182.866404 -123.879046) (xy 182.828914 -123.92143) (xy 182.785835 -123.95812) (xy 182.738025 -123.988386)
			(xy 182.686433 -124.011628) (xy 182.632084 -124.027382) (xy 182.576061 -124.035336) (xy 182.547768 -124.03582)
			(xy 182.518398 -124.035301) (xy 182.460292 -124.026699) (xy 182.404061 -124.009712) (xy 182.350911 -123.984704)
			(xy 182.301976 -123.952211) (xy 182.279798 -123.93295) (xy 182.272602 -123.926963) (xy 182.255118 -123.920309)
			(xy 182.245762 -123.919996) (xy 182.214774 -123.919996) (xy 182.205439 -123.920417) (xy 182.187987 -123.927054)
			(xy 182.180738 -123.93295) (xy 182.158566 -123.952217) (xy 182.109626 -123.984701) (xy 182.056473 -124.009701)
			(xy 182.000243 -124.026685) (xy 181.942137 -124.035288) (xy 181.912768 -124.03582) (xy 181.895727 -124.03563)
			(xy 181.861772 -124.032707) (xy 181.84495 -124.029978) (xy 181.833956 -124.028643) (xy 181.812608 -124.034438)
			(xy 181.803802 -124.041154) (xy 181.779164 -124.061982) (xy 181.77096 -124.069624) (xy 181.761466 -124.089903)
			(xy 181.760876 -124.101098) (xy 181.760876 -124.103638) (xy 181.760876 -124.31649) (xy 185.401964 -124.31649)
			(xy 185.406035 -124.260868) (xy 185.418161 -124.206431) (xy 185.438084 -124.15434) (xy 185.46538 -124.105705)
			(xy 185.499466 -124.061562) (xy 185.539615 -124.022853) (xy 185.584973 -123.990402) (xy 185.634573 -123.964901)
			(xy 185.687357 -123.946894) (xy 185.7422 -123.936764) (xy 185.797934 -123.934727) (xy 185.853371 -123.940827)
			(xy 185.907328 -123.954933) (xy 185.958657 -123.976745) (xy 186.006263 -124.005799) (xy 186.049131 -124.041474)
			(xy 186.086348 -124.083011) (xy 186.117121 -124.129524) (xy 186.140793 -124.180021) (xy 186.156861 -124.233428)
			(xy 186.164981 -124.288604) (xy 186.16549 -124.31649) (xy 186.164981 -124.344376) (xy 186.156861 -124.399552)
			(xy 186.140793 -124.452959) (xy 186.117121 -124.503456) (xy 186.086348 -124.549969) (xy 186.049131 -124.591506)
			(xy 186.006263 -124.627181) (xy 185.958657 -124.656235) (xy 185.907328 -124.678047) (xy 185.853371 -124.692153)
			(xy 185.797934 -124.698253) (xy 185.7422 -124.696216) (xy 185.687357 -124.686086) (xy 185.634573 -124.668079)
			(xy 185.584973 -124.642578) (xy 185.539615 -124.610127) (xy 185.499466 -124.571418) (xy 185.46538 -124.527275)
			(xy 185.438084 -124.47864) (xy 185.418161 -124.426549) (xy 185.406035 -124.372112) (xy 185.401964 -124.31649)
			(xy 181.760876 -124.31649) (xy 181.760876 -124.968762) (xy 181.761436 -124.979968) (xy 181.770918 -125.000271)
			(xy 181.779164 -125.007878) (xy 181.803802 -125.028452) (xy 181.812639 -125.035106) (xy 181.833962 -125.040905)
			(xy 181.84495 -125.039628) (xy 181.861778 -125.036973) (xy 181.895733 -125.034178) (xy 181.912768 -125.03404)
			(xy 181.941398 -125.03462) (xy 181.998075 -125.042765) (xy 182.053017 -125.058893) (xy 182.105103 -125.082677)
			(xy 182.153275 -125.113631) (xy 182.196551 -125.151127) (xy 182.234049 -125.194399) (xy 182.265008 -125.242568)
			(xy 182.288795 -125.294653) (xy 182.304928 -125.349593) (xy 182.313077 -125.40627) (xy 182.313077 -125.435106)
			(xy 183.384696 -125.435106) (xy 183.388767 -125.379484) (xy 183.400893 -125.325047) (xy 183.420816 -125.272956)
			(xy 183.448112 -125.224321) (xy 183.482198 -125.180178) (xy 183.522347 -125.141469) (xy 183.567705 -125.109018)
			(xy 183.617305 -125.083517) (xy 183.670089 -125.06551) (xy 183.724932 -125.05538) (xy 183.780666 -125.053343)
			(xy 183.836103 -125.059443) (xy 183.89006 -125.073549) (xy 183.941389 -125.095361) (xy 183.988995 -125.124415)
			(xy 184.031863 -125.16009) (xy 184.06908 -125.201627) (xy 184.099853 -125.24814) (xy 184.123525 -125.298637)
			(xy 184.139593 -125.352044) (xy 184.147713 -125.40722) (xy 184.148222 -125.435106) (xy 184.147713 -125.462992)
			(xy 184.139593 -125.518168) (xy 184.123525 -125.571575) (xy 184.099853 -125.622072) (xy 184.06908 -125.668585)
			(xy 184.031863 -125.710122) (xy 183.988995 -125.745797) (xy 183.978254 -125.752352) (xy 185.355228 -125.752352)
			(xy 185.359299 -125.69673) (xy 185.371425 -125.642293) (xy 185.391348 -125.590202) (xy 185.418644 -125.541567)
			(xy 185.45273 -125.497424) (xy 185.492879 -125.458715) (xy 185.538237 -125.426264) (xy 185.587837 -125.400763)
			(xy 185.640621 -125.382756) (xy 185.695464 -125.372626) (xy 185.751198 -125.370589) (xy 185.806635 -125.376689)
			(xy 185.860592 -125.390795) (xy 185.911921 -125.412607) (xy 185.948786 -125.435106) (xy 187.98489 -125.435106)
			(xy 187.988961 -125.379484) (xy 188.001087 -125.325047) (xy 188.02101 -125.272956) (xy 188.048306 -125.224321)
			(xy 188.082392 -125.180178) (xy 188.122541 -125.141469) (xy 188.167899 -125.109018) (xy 188.217499 -125.083517)
			(xy 188.270283 -125.06551) (xy 188.325126 -125.05538) (xy 188.38086 -125.053343) (xy 188.436297 -125.059443)
			(xy 188.490254 -125.073549) (xy 188.541583 -125.095361) (xy 188.589189 -125.124415) (xy 188.632057 -125.16009)
			(xy 188.669274 -125.201627) (xy 188.700047 -125.24814) (xy 188.723719 -125.298637) (xy 188.739787 -125.352044)
			(xy 188.747907 -125.40722) (xy 188.748416 -125.435106) (xy 189.96609 -125.435106) (xy 189.970161 -125.379484)
			(xy 189.982287 -125.325047) (xy 190.00221 -125.272956) (xy 190.029506 -125.224321) (xy 190.063592 -125.180178)
			(xy 190.103741 -125.141469) (xy 190.149099 -125.109018) (xy 190.198699 -125.083517) (xy 190.251483 -125.06551)
			(xy 190.306326 -125.05538) (xy 190.36206 -125.053343) (xy 190.417497 -125.059443) (xy 190.471454 -125.073549)
			(xy 190.522783 -125.095361) (xy 190.570389 -125.124415) (xy 190.613257 -125.16009) (xy 190.650474 -125.201627)
			(xy 190.681247 -125.24814) (xy 190.704919 -125.298637) (xy 190.720987 -125.352044) (xy 190.729107 -125.40722)
			(xy 190.729616 -125.435106) (xy 190.729107 -125.462992) (xy 190.720987 -125.518168) (xy 190.704919 -125.571575)
			(xy 190.681247 -125.622072) (xy 190.650474 -125.668585) (xy 190.613257 -125.710122) (xy 190.570389 -125.745797)
			(xy 190.522783 -125.774851) (xy 190.471454 -125.796663) (xy 190.417497 -125.810769) (xy 190.36206 -125.816869)
			(xy 190.306326 -125.814832) (xy 190.251483 -125.804702) (xy 190.198699 -125.786695) (xy 190.149099 -125.761194)
			(xy 190.103741 -125.728743) (xy 190.063592 -125.690034) (xy 190.029506 -125.645891) (xy 190.00221 -125.597256)
			(xy 189.982287 -125.545165) (xy 189.970161 -125.490728) (xy 189.96609 -125.435106) (xy 188.748416 -125.435106)
			(xy 188.747907 -125.462992) (xy 188.739787 -125.518168) (xy 188.723719 -125.571575) (xy 188.700047 -125.622072)
			(xy 188.669274 -125.668585) (xy 188.632057 -125.710122) (xy 188.589189 -125.745797) (xy 188.541583 -125.774851)
			(xy 188.490254 -125.796663) (xy 188.436297 -125.810769) (xy 188.38086 -125.816869) (xy 188.325126 -125.814832)
			(xy 188.270283 -125.804702) (xy 188.217499 -125.786695) (xy 188.167899 -125.761194) (xy 188.122541 -125.728743)
			(xy 188.082392 -125.690034) (xy 188.048306 -125.645891) (xy 188.02101 -125.597256) (xy 188.001087 -125.545165)
			(xy 187.988961 -125.490728) (xy 187.98489 -125.435106) (xy 185.948786 -125.435106) (xy 185.959527 -125.441661)
			(xy 186.002395 -125.477336) (xy 186.039612 -125.518873) (xy 186.070385 -125.565386) (xy 186.094057 -125.615883)
			(xy 186.110125 -125.66929) (xy 186.118245 -125.724466) (xy 186.118754 -125.752352) (xy 186.118245 -125.780238)
			(xy 186.110125 -125.835414) (xy 186.094057 -125.888821) (xy 186.070385 -125.939318) (xy 186.039612 -125.985831)
			(xy 186.002395 -126.027368) (xy 185.959527 -126.063043) (xy 185.911921 -126.092097) (xy 185.860592 -126.113909)
			(xy 185.806635 -126.128015) (xy 185.751198 -126.134115) (xy 185.695464 -126.132078) (xy 185.640621 -126.121948)
			(xy 185.587837 -126.103941) (xy 185.538237 -126.07844) (xy 185.492879 -126.045989) (xy 185.45273 -126.00728)
			(xy 185.418644 -125.963137) (xy 185.391348 -125.914502) (xy 185.371425 -125.862411) (xy 185.359299 -125.807974)
			(xy 185.355228 -125.752352) (xy 183.978254 -125.752352) (xy 183.941389 -125.774851) (xy 183.89006 -125.796663)
			(xy 183.836103 -125.810769) (xy 183.780666 -125.816869) (xy 183.724932 -125.814832) (xy 183.670089 -125.804702)
			(xy 183.617305 -125.786695) (xy 183.567705 -125.761194) (xy 183.522347 -125.728743) (xy 183.482198 -125.690034)
			(xy 183.448112 -125.645891) (xy 183.420816 -125.597256) (xy 183.400893 -125.545165) (xy 183.388767 -125.490728)
			(xy 183.384696 -125.435106) (xy 182.313077 -125.435106) (xy 182.313077 -125.46353) (xy 182.304928 -125.520207)
			(xy 182.288795 -125.575147) (xy 182.265008 -125.627232) (xy 182.234049 -125.675401) (xy 182.196551 -125.718673)
			(xy 182.153275 -125.756169) (xy 182.105103 -125.787123) (xy 182.053017 -125.810907) (xy 181.998075 -125.827035)
			(xy 181.941398 -125.83518) (xy 181.912768 -125.835664) (xy 181.884487 -125.835127) (xy 181.828485 -125.827197)
			(xy 181.774155 -125.811471) (xy 181.722576 -125.78826) (xy 181.674774 -125.758027) (xy 181.631698 -125.721372)
			(xy 181.594204 -125.679024) (xy 181.563039 -125.631825) (xy 181.53882 -125.580711) (xy 181.52203 -125.5267)
			(xy 181.517036 -125.49886) (xy 181.515258 -125.488446) (xy 181.504336 -125.471174) (xy 181.426612 -125.41758)
			(xy 181.406292 -125.413516) (xy 181.396132 -125.415548) (xy 181.373153 -125.420041) (xy 181.32658 -125.424879)
			(xy 181.303168 -125.4252) (xy 181.279757 -125.424865) (xy 181.233183 -125.420035) (xy 181.210204 -125.415548)
			(xy 181.200044 -125.413516) (xy 181.179724 -125.41758) (xy 181.102 -125.471174) (xy 181.091078 -125.488446)
			(xy 181.0893 -125.49886) (xy 181.084294 -125.526697) (xy 181.067488 -125.5807) (xy 181.04326 -125.631806)
			(xy 181.012091 -125.679001) (xy 180.974599 -125.721347) (xy 180.931528 -125.758004) (xy 180.883734 -125.788245)
			(xy 180.832164 -125.811469) (xy 180.777843 -125.827217) (xy 180.721847 -125.835174) (xy 180.693568 -125.835664)
			(xy 180.664936 -125.835247) (xy 180.608255 -125.827094) (xy 180.553312 -125.810957) (xy 180.501224 -125.787165)
			(xy 180.453052 -125.756203) (xy 180.409776 -125.718702) (xy 180.372277 -125.675423) (xy 180.341319 -125.627248)
			(xy 180.317532 -125.575158) (xy 180.3014 -125.520213) (xy 180.293251 -125.463532) (xy 180.293251 -125.406268)
			(xy 180.3014 -125.349587) (xy 180.317532 -125.294642) (xy 180.341319 -125.242552) (xy 180.372277 -125.194377)
			(xy 180.409776 -125.151098) (xy 180.453052 -125.113597) (xy 180.501224 -125.082635) (xy 180.553312 -125.058843)
			(xy 180.608255 -125.042706) (xy 180.664936 -125.034553) (xy 180.693568 -125.03404) (xy 180.710604 -125.034168)
			(xy 180.744559 -125.036963) (xy 180.761386 -125.039628) (xy 180.772379 -125.040983) (xy 180.793729 -125.035174)
			(xy 180.802534 -125.028452) (xy 180.827172 -125.007878) (xy 180.8354 -125.000258) (xy 180.844879 -124.979962)
			(xy 180.84546 -124.968762) (xy 180.84546 -124.967238) (xy 180.84546 -124.101098) (xy 180.84491 -124.089891)
			(xy 180.83542 -124.069589) (xy 180.827172 -124.061982) (xy 180.802534 -124.041154) (xy 180.793691 -124.03451)
			(xy 180.772372 -124.028709) (xy 180.761386 -124.029978) (xy 180.744562 -124.032687) (xy 180.710608 -124.035614)
			(xy 180.693568 -124.03582) (xy 180.664918 -124.035399) (xy 180.608202 -124.02724) (xy 180.553223 -124.011093)
			(xy 180.501103 -123.987287) (xy 180.4529 -123.956306) (xy 180.409597 -123.91878) (xy 180.372075 -123.875474)
			(xy 180.341098 -123.827269) (xy 180.317295 -123.775147) (xy 180.301153 -123.720167) (xy 180.292999 -123.66345)
			(xy 173.277524 -123.66345) (xy 176.46523 -126.851156) (xy 176.465738 -126.851664) (xy 176.473119 -126.858247)
			(xy 176.491418 -126.865701) (xy 176.501298 -126.866142)
		)
		(stroke
			(width 0)
			(type solid)
		)
		(fill yes)
		(layer "In13.Cu")
		(net "P3V3_NIC3")
	)
	(gr_poly
		(pts
			(xy 306.077112 -125.840236) (xy 306.085733 -125.839138) (xy 306.101542 -125.831949) (xy 306.114049 -125.819899)
			(xy 306.11826 -125.812296) (xy 306.118514 -125.811534) (xy 306.164234 -125.715522) (xy 306.160678 -125.686566)
			(xy 306.151534 -125.675136) (xy 306.135554 -125.654665) (xy 306.10869 -125.610222) (xy 306.088096 -125.562548)
			(xy 306.074151 -125.512524) (xy 306.067114 -125.461072) (xy 306.066698 -125.435106) (xy 306.066698 -125.427232)
			(xy 306.067785 -125.399067) (xy 306.077225 -125.343499) (xy 306.094735 -125.289925) (xy 306.119936 -125.239509)
			(xy 306.152279 -125.193349) (xy 306.191061 -125.152449) (xy 306.235436 -125.117698) (xy 306.284441 -125.089852)
			(xy 306.337009 -125.069519) (xy 306.391996 -125.057139) (xy 306.448206 -125.052982) (xy 306.504416 -125.057139)
			(xy 306.559403 -125.069519) (xy 306.611971 -125.089852) (xy 306.660976 -125.117698) (xy 306.705351 -125.152449)
			(xy 306.744133 -125.193349) (xy 306.776476 -125.239509) (xy 306.801677 -125.289925) (xy 306.819187 -125.343499)
			(xy 306.828627 -125.399067) (xy 306.829714 -125.427232) (xy 306.829714 -125.433582) (xy 306.829714 -125.435106)
			(xy 306.829294 -125.461073) (xy 306.82228 -125.512529) (xy 306.808342 -125.562557) (xy 306.787738 -125.610227)
			(xy 306.76085 -125.654657) (xy 306.744878 -125.675136) (xy 306.735734 -125.686566) (xy 306.732178 -125.715522)
			(xy 306.777898 -125.811534) (xy 306.778152 -125.812296) (xy 306.782332 -125.819924) (xy 306.794836 -125.831997)
			(xy 306.810668 -125.839171) (xy 306.8193 -125.840236) (xy 306.823872 -125.84049) (xy 321.709796 -125.84049)
			(xy 321.720031 -125.840017) (xy 321.738881 -125.83203) (xy 321.753148 -125.817348) (xy 321.757294 -125.807978)
			(xy 321.791076 -125.719332) (xy 321.794342 -125.709574) (xy 321.793649 -125.689028) (xy 321.784969 -125.670392)
			(xy 321.777614 -125.663198) (xy 321.757997 -125.645029) (xy 321.723535 -125.604147) (xy 321.695119 -125.558854)
			(xy 321.673307 -125.510037) (xy 321.658524 -125.458652) (xy 321.651062 -125.405706) (xy 321.650614 -125.378972)
			(xy 321.651088 -125.351603) (xy 321.658915 -125.297427) (xy 321.674406 -125.244926) (xy 321.697241 -125.195178)
			(xy 321.726953 -125.149204) (xy 321.744594 -125.128274) (xy 321.75069 -125.121162) (xy 321.75704 -125.104398)
			(xy 321.75704 -125.018546) (xy 321.75069 -125.001782) (xy 321.744594 -124.99467) (xy 321.726957 -124.973737)
			(xy 321.697238 -124.927769) (xy 321.674399 -124.878024) (xy 321.658908 -124.825524) (xy 321.651083 -124.771348)
			(xy 321.651086 -124.71661) (xy 321.658917 -124.662435) (xy 321.674414 -124.609937) (xy 321.697259 -124.560194)
			(xy 321.726982 -124.51423) (xy 321.744594 -124.493274) (xy 321.75069 -124.486162) (xy 321.75704 -124.469398)
			(xy 321.75704 -124.383546) (xy 321.75069 -124.366782) (xy 321.744594 -124.35967) (xy 321.726954 -124.338738)
			(xy 321.697232 -124.292771) (xy 321.674393 -124.243024) (xy 321.658907 -124.19052) (xy 321.651093 -124.136342)
			(xy 321.650614 -124.108972) (xy 321.6511 -124.081721) (xy 321.658856 -124.027773) (xy 321.674211 -123.975478)
			(xy 321.696853 -123.925901) (xy 321.726319 -123.880051) (xy 321.76201 -123.83886) (xy 321.803201 -123.803169)
			(xy 321.849051 -123.773703) (xy 321.898628 -123.751061) (xy 321.950923 -123.735706) (xy 322.004871 -123.72795)
			(xy 322.059373 -123.72795) (xy 322.113321 -123.735706) (xy 322.165616 -123.751061) (xy 322.215193 -123.773703)
			(xy 322.261043 -123.803169) (xy 322.302234 -123.83886) (xy 322.337925 -123.880051) (xy 322.367391 -123.925901)
			(xy 322.390033 -123.975478) (xy 322.405388 -124.027773) (xy 322.413144 -124.081721) (xy 322.41363 -124.108972)
			(xy 322.413153 -124.13634) (xy 322.405319 -124.190512) (xy 322.389822 -124.243008) (xy 322.36698 -124.29275)
			(xy 322.337262 -124.338716) (xy 322.31965 -124.35967) (xy 322.313554 -124.366782) (xy 322.307204 -124.383546)
			(xy 322.307204 -124.469398) (xy 322.310379 -124.47778) (xy 324.612762 -124.47778) (xy 324.613201 -124.450409)
			(xy 324.621023 -124.396228) (xy 324.636518 -124.343724) (xy 324.659366 -124.293977) (xy 324.689097 -124.248012)
			(xy 324.706742 -124.227082) (xy 324.712838 -124.21997) (xy 324.719188 -124.202952) (xy 324.719188 -124.117608)
			(xy 324.712838 -124.10059) (xy 324.706742 -124.093478) (xy 324.689133 -124.072522) (xy 324.659415 -124.026556)
			(xy 324.636572 -123.976815) (xy 324.621075 -123.924319) (xy 324.613239 -123.870148) (xy 324.612762 -123.84278)
			(xy 324.613248 -123.815529) (xy 324.621004 -123.761581) (xy 324.636359 -123.709286) (xy 324.659001 -123.659709)
			(xy 324.688467 -123.613859) (xy 324.724158 -123.572668) (xy 324.765349 -123.536977) (xy 324.811199 -123.507511)
			(xy 324.860776 -123.484869) (xy 324.913071 -123.469514) (xy 324.967019 -123.461758) (xy 325.021521 -123.461758)
			(xy 325.075469 -123.469514) (xy 325.127764 -123.484869) (xy 325.177341 -123.507511) (xy 325.223191 -123.536977)
			(xy 325.264382 -123.572668) (xy 325.300073 -123.613859) (xy 325.329539 -123.659709) (xy 325.352181 -123.709286)
			(xy 325.367536 -123.761581) (xy 325.375292 -123.815529) (xy 325.375411 -123.822229) (xy 329.642205 -123.822229)
			(xy 329.642208 -123.767731) (xy 329.649966 -123.713788) (xy 329.665323 -123.661498) (xy 329.687965 -123.611926)
			(xy 329.717431 -123.566081) (xy 329.753121 -123.524896) (xy 329.79431 -123.489209) (xy 329.840158 -123.459747)
			(xy 329.889732 -123.43711) (xy 329.942023 -123.421759) (xy 329.995967 -123.414005) (xy 330.023216 -123.41352)
			(xy 330.033715 -123.413586) (xy 330.054682 -123.414731) (xy 330.065126 -123.415806) (xy 330.079675 -123.416857)
			(xy 330.108365 -123.411664) (xy 330.134422 -123.398584) (xy 330.155726 -123.378679) (xy 330.170544 -123.35357)
			(xy 330.177672 -123.325299) (xy 330.176529 -123.296165) (xy 330.172314 -123.282202) (xy 330.162959 -123.252528)
			(xy 330.152868 -123.191136) (xy 330.152248 -123.160028) (xy 330.152725 -123.132772) (xy 330.160479 -123.078814)
			(xy 330.175834 -123.02651) (xy 330.198476 -122.976922) (xy 330.227945 -122.931063) (xy 330.263641 -122.889864)
			(xy 330.304837 -122.854164) (xy 330.350694 -122.824691) (xy 330.40028 -122.802045) (xy 330.452583 -122.786686)
			(xy 330.50654 -122.778927) (xy 330.561052 -122.778927) (xy 330.615009 -122.786684) (xy 330.667313 -122.802042)
			(xy 330.716899 -122.824688) (xy 330.762757 -122.85416) (xy 330.803953 -122.889858) (xy 330.83965 -122.931056)
			(xy 330.86912 -122.976915) (xy 330.891763 -123.026502) (xy 330.907119 -123.078807) (xy 330.914874 -123.132764)
			(xy 330.914872 -123.187276) (xy 330.907111 -123.241233) (xy 330.891749 -123.293535) (xy 330.869101 -123.34312)
			(xy 330.839626 -123.388976) (xy 330.803925 -123.43017) (xy 330.762725 -123.465864) (xy 330.716863 -123.495332)
			(xy 330.667275 -123.517972) (xy 330.61497 -123.533324) (xy 330.561012 -123.541076) (xy 330.533756 -123.541536)
			(xy 330.523257 -123.541464) (xy 330.50229 -123.540323) (xy 330.491846 -123.53925) (xy 330.477298 -123.538232)
			(xy 330.448617 -123.543429) (xy 330.422569 -123.556508) (xy 330.40127 -123.576406) (xy 330.386452 -123.601506)
			(xy 330.379319 -123.629767) (xy 330.380451 -123.658893) (xy 330.384658 -123.672854) (xy 330.394025 -123.702525)
			(xy 330.404108 -123.76392) (xy 330.404724 -123.795028) (xy 331.848966 -123.795028) (xy 331.853037 -123.739406)
			(xy 331.865163 -123.684969) (xy 331.885086 -123.632878) (xy 331.912382 -123.584243) (xy 331.946468 -123.5401)
			(xy 331.986617 -123.501391) (xy 332.031975 -123.46894) (xy 332.081575 -123.443439) (xy 332.134359 -123.425432)
			(xy 332.189202 -123.415302) (xy 332.244936 -123.413265) (xy 332.300373 -123.419365) (xy 332.35433 -123.433471)
			(xy 332.405659 -123.455283) (xy 332.453265 -123.484337) (xy 332.496133 -123.520012) (xy 332.53335 -123.561549)
			(xy 332.564123 -123.608062) (xy 332.587795 -123.658559) (xy 332.603863 -123.711966) (xy 332.611983 -123.767142)
			(xy 332.612492 -123.795028) (xy 332.611983 -123.822914) (xy 332.603863 -123.87809) (xy 332.587795 -123.931497)
			(xy 332.564123 -123.981994) (xy 332.53335 -124.028507) (xy 332.496133 -124.070044) (xy 332.453265 -124.105719)
			(xy 332.405659 -124.134773) (xy 332.35433 -124.156585) (xy 332.300373 -124.170691) (xy 332.244936 -124.176791)
			(xy 332.189202 -124.174754) (xy 332.134359 -124.164624) (xy 332.081575 -124.146617) (xy 332.031975 -124.121116)
			(xy 331.986617 -124.088665) (xy 331.946468 -124.049956) (xy 331.912382 -124.005813) (xy 331.885086 -123.957178)
			(xy 331.865163 -123.905087) (xy 331.853037 -123.85065) (xy 331.848966 -123.795028) (xy 330.404724 -123.795028)
			(xy 330.404192 -123.822277) (xy 330.396432 -123.87622) (xy 330.381074 -123.928509) (xy 330.358432 -123.978081)
			(xy 330.328965 -124.023925) (xy 330.293273 -124.06511) (xy 330.252084 -124.100796) (xy 330.206235 -124.130257)
			(xy 330.15666 -124.152893) (xy 330.104369 -124.168243) (xy 330.050425 -124.175996) (xy 329.995927 -124.175992)
			(xy 329.941984 -124.168233) (xy 329.889695 -124.152876) (xy 329.840123 -124.130234) (xy 329.794278 -124.100767)
			(xy 329.753093 -124.065076) (xy 329.717407 -124.023887) (xy 329.687945 -123.978039) (xy 329.665309 -123.928464)
			(xy 329.649958 -123.876173) (xy 329.642205 -123.822229) (xy 325.375411 -123.822229) (xy 325.375778 -123.84278)
			(xy 325.375306 -123.87015) (xy 325.36749 -123.924329) (xy 325.352003 -123.976832) (xy 325.329162 -124.026579)
			(xy 325.299439 -124.072546) (xy 325.281798 -124.093478) (xy 325.275702 -124.10059) (xy 325.269352 -124.117608)
			(xy 325.269352 -124.202952) (xy 325.273901 -124.215144) (xy 326.806558 -124.215144) (xy 326.810629 -124.159522)
			(xy 326.822755 -124.105085) (xy 326.842678 -124.052994) (xy 326.869974 -124.004359) (xy 326.90406 -123.960216)
			(xy 326.944209 -123.921507) (xy 326.989567 -123.889056) (xy 327.039167 -123.863555) (xy 327.091951 -123.845548)
			(xy 327.146794 -123.835418) (xy 327.202528 -123.833381) (xy 327.257965 -123.839481) (xy 327.311922 -123.853587)
			(xy 327.363251 -123.875399) (xy 327.410857 -123.904453) (xy 327.453725 -123.940128) (xy 327.490942 -123.981665)
			(xy 327.521715 -124.028178) (xy 327.545387 -124.078675) (xy 327.561455 -124.132082) (xy 327.569575 -124.187258)
			(xy 327.570084 -124.215144) (xy 327.569575 -124.24303) (xy 327.561455 -124.298206) (xy 327.545387 -124.351613)
			(xy 327.521715 -124.40211) (xy 327.490942 -124.448623) (xy 327.453725 -124.49016) (xy 327.410857 -124.525835)
			(xy 327.363251 -124.554889) (xy 327.311922 -124.576701) (xy 327.257965 -124.590807) (xy 327.202528 -124.596907)
			(xy 327.146794 -124.59487) (xy 327.091951 -124.58474) (xy 327.039167 -124.566733) (xy 326.989567 -124.541232)
			(xy 326.944209 -124.508781) (xy 326.90406 -124.470072) (xy 326.869974 -124.425929) (xy 326.842678 -124.377294)
			(xy 326.822755 -124.325203) (xy 326.810629 -124.270766) (xy 326.806558 -124.215144) (xy 325.273901 -124.215144)
			(xy 325.275702 -124.21997) (xy 325.281798 -124.227082) (xy 325.299442 -124.24801) (xy 325.329153 -124.293984)
			(xy 325.351988 -124.343733) (xy 325.367478 -124.396234) (xy 325.375305 -124.450411) (xy 325.375778 -124.47778)
			(xy 325.375292 -124.505031) (xy 325.367536 -124.558979) (xy 325.352181 -124.611274) (xy 325.329539 -124.660851)
			(xy 325.300073 -124.706701) (xy 325.264382 -124.747892) (xy 325.223191 -124.783583) (xy 325.177341 -124.813049)
			(xy 325.127764 -124.835691) (xy 325.075469 -124.851046) (xy 325.021521 -124.858802) (xy 324.967019 -124.858802)
			(xy 324.913071 -124.851046) (xy 324.860776 -124.835691) (xy 324.811199 -124.813049) (xy 324.765349 -124.783583)
			(xy 324.724158 -124.747892) (xy 324.688467 -124.706701) (xy 324.659001 -124.660851) (xy 324.636359 -124.611274)
			(xy 324.621004 -124.558979) (xy 324.613248 -124.505031) (xy 324.612762 -124.47778) (xy 322.310379 -124.47778)
			(xy 322.313554 -124.486162) (xy 322.31965 -124.493274) (xy 322.338446 -124.516642) (xy 322.355325 -124.540249)
			(xy 322.382497 -124.591526) (xy 322.392548 -124.61875) (xy 322.396866 -124.630942) (xy 322.415916 -124.648214)
			(xy 322.523866 -124.674376) (xy 322.549012 -124.667518) (xy 322.55841 -124.658628) (xy 322.579828 -124.638998)
			(xy 322.627498 -124.60579) (xy 322.67965 -124.580191) (xy 322.73508 -124.562792) (xy 322.792506 -124.553995)
			(xy 322.821554 -124.553472) (xy 322.848922 -124.553948) (xy 322.903096 -124.56178) (xy 322.955593 -124.577275)
			(xy 323.005337 -124.600115) (xy 323.051304 -124.629832) (xy 323.072252 -124.647452) (xy 323.079364 -124.653548)
			(xy 323.096128 -124.659898) (xy 323.18198 -124.659898) (xy 323.198744 -124.653548) (xy 323.205856 -124.647452)
			(xy 323.226787 -124.629811) (xy 323.272754 -124.600088) (xy 323.322501 -124.577249) (xy 323.375005 -124.561764)
			(xy 323.429184 -124.553952) (xy 323.456554 -124.553472) (xy 323.48381 -124.553932) (xy 323.537767 -124.561683)
			(xy 323.590071 -124.577035) (xy 323.639658 -124.599675) (xy 323.685519 -124.629141) (xy 323.726719 -124.664835)
			(xy 323.762419 -124.706028) (xy 323.791894 -124.751884) (xy 323.814542 -124.801467) (xy 323.829903 -124.853769)
			(xy 323.837664 -124.907725) (xy 323.838062 -124.93498) (xy 323.8373 -124.959872) (xy 323.836538 -124.97308)
			(xy 323.84746 -124.996448) (xy 323.938646 -125.062488) (xy 323.9643 -125.065536) (xy 323.976746 -125.06071)
			(xy 323.999473 -125.051963) (xy 324.04659 -125.039651) (xy 324.094891 -125.033434) (xy 324.11924 -125.033024)
			(xy 324.146489 -125.033513) (xy 324.20043 -125.041274) (xy 324.252718 -125.056633) (xy 324.302288 -125.079277)
			(xy 324.348131 -125.108745) (xy 324.389314 -125.144437) (xy 324.424998 -125.185626) (xy 324.454457 -125.231475)
			(xy 324.477092 -125.281049) (xy 324.492441 -125.33334) (xy 324.500192 -125.387283) (xy 324.500748 -125.414532)
			(xy 324.500274 -125.441901) (xy 324.492445 -125.496076) (xy 324.476953 -125.548576) (xy 324.454115 -125.598322)
			(xy 324.424402 -125.644293) (xy 324.406768 -125.66523) (xy 324.400672 -125.672342) (xy 324.394322 -125.689106)
			(xy 324.394322 -125.774958) (xy 324.400672 -125.791722) (xy 324.406768 -125.798834) (xy 324.42404 -125.82017)
			(xy 324.431641 -125.82928) (xy 324.452832 -125.839886) (xy 324.46468 -125.84049) (xy 327.336404 -125.84049)
			(xy 327.347742 -125.839892) (xy 327.368215 -125.830146) (xy 327.382478 -125.812519) (xy 327.38568 -125.801628)
			(xy 327.392454 -125.775572) (xy 327.412335 -125.72554) (xy 327.43905 -125.678799) (xy 327.472069 -125.636277)
			(xy 327.49109 -125.617224) (xy 327.498456 -125.610366) (xy 327.510394 -125.583188) (xy 327.512429 -125.578291)
			(xy 327.514614 -125.567916) (xy 327.514712 -125.562614) (xy 327.514712 -125.509274) (xy 327.514569 -125.503977)
			(xy 327.512382 -125.493612) (xy 327.510394 -125.4887) (xy 327.498202 -125.461522) (xy 327.49109 -125.45441)
			(xy 327.473073 -125.436374) (xy 327.441499 -125.396349) (xy 327.415538 -125.352474) (xy 327.395653 -125.305533)
			(xy 327.382198 -125.25636) (xy 327.375415 -125.205834) (xy 327.375012 -125.180344) (xy 327.375012 -125.170692)
			(xy 327.376222 -125.142613) (xy 327.385868 -125.087247) (xy 327.403529 -125.033894) (xy 327.428824 -124.983708)
			(xy 327.461206 -124.937774) (xy 327.499975 -124.897087) (xy 327.544291 -124.862525) (xy 327.593197 -124.834836)
			(xy 327.645636 -124.814619) (xy 327.700472 -124.802311) (xy 327.75652 -124.798179) (xy 327.812568 -124.802311)
			(xy 327.867404 -124.814619) (xy 327.919843 -124.834836) (xy 327.968749 -124.862525) (xy 328.013065 -124.897087)
			(xy 328.051834 -124.937774) (xy 328.084216 -124.983708) (xy 328.109511 -125.033894) (xy 328.127172 -125.087247)
			(xy 328.136818 -125.142613) (xy 328.138028 -125.170692) (xy 328.138028 -125.17755) (xy 328.138028 -125.180344)
			(xy 328.137601 -125.205832) (xy 328.130809 -125.256353) (xy 328.117351 -125.30552) (xy 328.097468 -125.352458)
			(xy 328.071514 -125.396331) (xy 328.039949 -125.436359) (xy 328.02195 -125.45441) (xy 328.014838 -125.461522)
			(xy 328.002646 -125.4887) (xy 328.000612 -125.493597) (xy 327.998427 -125.503972) (xy 327.998328 -125.509274)
			(xy 327.998328 -125.562614) (xy 327.99847 -125.567911) (xy 328.000652 -125.578278) (xy 328.002646 -125.583188)
			(xy 328.014584 -125.610366) (xy 328.02195 -125.617224) (xy 328.040968 -125.636281) (xy 328.073999 -125.678796)
			(xy 328.100724 -125.725534) (xy 328.120613 -125.775564) (xy 328.12736 -125.801628) (xy 328.130624 -125.812486)
			(xy 328.14489 -125.830069) (xy 328.165316 -125.839841) (xy 328.176636 -125.84049) (xy 333.194406 -125.84049)
			(xy 333.204284 -125.840032) (xy 333.222585 -125.832591) (xy 333.229966 -125.826012) (xy 333.23022 -125.825758)
			(xy 333.540862 -125.515116) (xy 333.54137 -125.514608) (xy 333.547945 -125.507224) (xy 333.555378 -125.488925)
			(xy 333.555848 -125.479048) (xy 333.555848 -122.15495) (xy 333.555848 -122.15241) (xy 333.554973 -122.14332)
			(xy 333.547665 -122.126597) (xy 333.534972 -122.113486) (xy 333.526892 -122.10923) (xy 333.52486 -122.108214)
			(xy 333.42453 -122.065796) (xy 333.394558 -122.071384) (xy 333.383636 -122.082052) (xy 333.362154 -122.10214)
			(xy 333.31416 -122.136133) (xy 333.261518 -122.162356) (xy 333.205475 -122.180189) (xy 333.147358 -122.189208)
			(xy 333.117952 -122.189748) (xy 333.0907 -122.189259) (xy 333.036752 -122.181496) (xy 332.984457 -122.166135)
			(xy 332.934881 -122.143489) (xy 332.889032 -122.114018) (xy 332.847843 -122.078323) (xy 332.812153 -122.03713)
			(xy 332.782688 -121.991277) (xy 332.760048 -121.941697) (xy 332.744694 -121.889401) (xy 332.736938 -121.835452)
			(xy 332.736938 -121.780948) (xy 332.744694 -121.726999) (xy 332.760048 -121.674703) (xy 332.782688 -121.625123)
			(xy 332.812153 -121.57927) (xy 332.847843 -121.538077) (xy 332.889032 -121.502382) (xy 332.934881 -121.472911)
			(xy 332.984457 -121.450265) (xy 333.036752 -121.434904) (xy 333.0907 -121.427141) (xy 333.117952 -121.426732)
			(xy 333.147357 -121.427279) (xy 333.205469 -121.436308) (xy 333.261509 -121.454144) (xy 333.31415 -121.480365)
			(xy 333.362146 -121.51435) (xy 333.383636 -121.534428) (xy 333.394558 -121.545096) (xy 333.42453 -121.550684)
			(xy 333.52486 -121.508266) (xy 333.526892 -121.50725) (xy 333.534978 -121.502997) (xy 333.547689 -121.489892)
			(xy 333.555005 -121.473166) (xy 333.555848 -121.46407) (xy 333.555848 -120.927876) (xy 333.555419 -120.917809)
			(xy 333.547693 -120.899216) (xy 333.540862 -120.891808) (xy 333.264764 -120.61571) (xy 333.257417 -120.608904)
			(xy 333.238955 -120.601183) (xy 333.22895 -120.600724) (xy 332.572614 -120.600724) (xy 332.54696 -120.61825)
			(xy 332.541118 -120.632982) (xy 332.530152 -120.659317) (xy 332.501545 -120.70867) (xy 332.465914 -120.753218)
			(xy 332.42405 -120.791967) (xy 332.376887 -120.824057) (xy 332.325475 -120.848772) (xy 332.270957 -120.865562)
			(xy 332.214548 -120.874053) (xy 332.186026 -120.874536) (xy 332.158773 -120.874052) (xy 332.104821 -120.866299)
			(xy 332.052521 -120.850946) (xy 332.002939 -120.828307) (xy 331.957083 -120.798842) (xy 331.915888 -120.763151)
			(xy 331.880191 -120.72196) (xy 331.850719 -120.676108) (xy 331.828073 -120.626529) (xy 331.812713 -120.574232)
			(xy 331.804952 -120.520281) (xy 331.804518 -120.493028) (xy 331.804979 -120.466115) (xy 331.812543 -120.412824)
			(xy 331.827525 -120.361125) (xy 331.849626 -120.312047) (xy 331.878409 -120.266563) (xy 331.913302 -120.225579)
			(xy 331.95361 -120.189907) (xy 331.998533 -120.160258) (xy 332.047178 -120.137219) (xy 332.072742 -120.128792)
			(xy 332.078584 -120.12676) (xy 332.089252 -120.12041) (xy 332.175358 -120.034304) (xy 332.191841 -120.018393)
			(xy 332.228411 -119.9908) (xy 332.268435 -119.96851) (xy 332.289658 -119.959882) (xy 332.292706 -119.958358)
			(xy 332.314166 -119.948819) (xy 332.359156 -119.935352) (xy 332.405623 -119.928547) (xy 332.429104 -119.928132)
			(xy 332.637638 -119.928132) (xy 332.648294 -119.927666) (xy 332.667754 -119.918978) (xy 332.67523 -119.911368)
			(xy 332.732888 -119.847614) (xy 332.739746 -119.827294) (xy 332.738476 -119.816372) (xy 332.737502 -119.806368)
			(xy 332.736484 -119.786291) (xy 332.736444 -119.77624) (xy 332.736927 -119.748986) (xy 332.744679 -119.695031)
			(xy 332.76003 -119.642729) (xy 332.782668 -119.593143) (xy 332.812132 -119.547285) (xy 332.847823 -119.506086)
			(xy 332.889014 -119.470385) (xy 332.934866 -119.44091) (xy 332.984446 -119.418261) (xy 333.036745 -119.402897)
			(xy 333.090698 -119.395133) (xy 333.117952 -119.394732) (xy 333.13069 -119.394809) (xy 333.156112 -119.396459)
			(xy 333.168752 -119.398034) (xy 333.198797 -119.402656) (xy 333.256999 -119.420193) (xy 333.311676 -119.446752)
			(xy 333.361439 -119.481658) (xy 333.383636 -119.502428) (xy 333.394558 -119.513096) (xy 333.42453 -119.518684)
			(xy 333.52486 -119.476266) (xy 333.526892 -119.47525) (xy 333.534978 -119.470997) (xy 333.547689 -119.457892)
			(xy 333.555005 -119.441166) (xy 333.555848 -119.43207) (xy 333.555848 -115.752118) (xy 333.555408 -115.742056)
			(xy 333.547667 -115.723478) (xy 333.540862 -115.71605) (xy 333.09941 -115.274598) (xy 333.092298 -115.267232)
			(xy 333.073502 -115.259612) (xy 332.998318 -115.259612) (xy 332.987597 -115.260038) (xy 332.968004 -115.268733)
			(xy 332.960472 -115.276376) (xy 332.959456 -115.277646) (xy 332.959202 -115.277646) (xy 332.941676 -115.295934)
			(xy 332.934564 -115.302792) (xy 332.922626 -115.32997) (xy 332.920596 -115.334868) (xy 332.918422 -115.345243)
			(xy 332.918308 -115.350544) (xy 332.918308 -115.403884) (xy 332.918447 -115.409182) (xy 332.920622 -115.419552)
			(xy 332.922626 -115.424458) (xy 332.934818 -115.451636) (xy 332.94193 -115.458748) (xy 332.959943 -115.476786)
			(xy 332.99151 -115.516813) (xy 333.017463 -115.560688) (xy 333.03734 -115.60763) (xy 333.050786 -115.656801)
			(xy 333.057562 -115.707326) (xy 333.058008 -115.732814) (xy 333.058008 -115.742466) (xy 333.056798 -115.770545)
			(xy 333.047152 -115.825911) (xy 333.029491 -115.879264) (xy 333.004196 -115.92945) (xy 332.971814 -115.975384)
			(xy 332.933045 -116.016071) (xy 332.888729 -116.050633) (xy 332.839823 -116.078322) (xy 332.787384 -116.098539)
			(xy 332.732548 -116.110847) (xy 332.6765 -116.114979) (xy 332.620452 -116.110847) (xy 332.565616 -116.098539)
			(xy 332.513177 -116.078322) (xy 332.464271 -116.050633) (xy 332.419955 -116.016071) (xy 332.381186 -115.975384)
			(xy 332.348804 -115.92945) (xy 332.323509 -115.879264) (xy 332.305848 -115.825911) (xy 332.296202 -115.770545)
			(xy 332.294992 -115.742466) (xy 332.294992 -115.735608) (xy 332.294992 -115.732814) (xy 332.295415 -115.707325)
			(xy 332.302201 -115.6568) (xy 332.315653 -115.607629) (xy 332.335532 -115.560686) (xy 332.361484 -115.516808)
			(xy 332.393047 -115.476776) (xy 332.41107 -115.458748) (xy 332.418182 -115.451636) (xy 332.430374 -115.424458)
			(xy 332.432407 -115.419561) (xy 332.434586 -115.409185) (xy 332.434692 -115.403884) (xy 332.434692 -115.350544)
			(xy 332.434556 -115.345246) (xy 332.432386 -115.334873) (xy 332.430374 -115.32997) (xy 332.418436 -115.302792)
			(xy 332.411324 -115.295934) (xy 332.393798 -115.277646) (xy 332.393544 -115.277646) (xy 332.392528 -115.276376)
			(xy 332.384935 -115.268821) (xy 332.365379 -115.260141) (xy 332.354682 -115.259612) (xy 330.460096 -115.259612)
			(xy 330.449368 -115.260023) (xy 330.429752 -115.268698) (xy 330.42225 -115.276376) (xy 330.421234 -115.277646)
			(xy 330.42098 -115.277646) (xy 330.403454 -115.295934) (xy 330.396342 -115.302792) (xy 330.384404 -115.32997)
			(xy 330.382375 -115.334868) (xy 330.380202 -115.345243) (xy 330.380086 -115.350544) (xy 330.380086 -115.403884)
			(xy 330.380225 -115.409182) (xy 330.382404 -115.419551) (xy 330.384404 -115.424458) (xy 330.396596 -115.451636)
			(xy 330.403708 -115.458748) (xy 330.421722 -115.476785) (xy 330.453291 -115.516812) (xy 330.479245 -115.560687)
			(xy 330.499123 -115.607629) (xy 330.51257 -115.6568) (xy 330.519346 -115.707325) (xy 330.519786 -115.732814)
			(xy 330.519786 -115.742466) (xy 330.518576 -115.770545) (xy 330.50893 -115.825911) (xy 330.491269 -115.879264)
			(xy 330.465974 -115.92945) (xy 330.433592 -115.975384) (xy 330.394823 -116.016071) (xy 330.350507 -116.050633)
			(xy 330.301601 -116.078322) (xy 330.249162 -116.098539) (xy 330.194326 -116.110847) (xy 330.138278 -116.114979)
			(xy 330.08223 -116.110847) (xy 330.027394 -116.098539) (xy 329.974955 -116.078322) (xy 329.926049 -116.050633)
			(xy 329.881733 -116.016071) (xy 329.842964 -115.975384) (xy 329.810582 -115.92945) (xy 329.785287 -115.879264)
			(xy 329.767626 -115.825911) (xy 329.75798 -115.770545) (xy 329.75677 -115.742466) (xy 329.75677 -115.735608)
			(xy 329.75677 -115.732814) (xy 329.757193 -115.707325) (xy 329.763978 -115.6568) (xy 329.77743 -115.607628)
			(xy 329.797308 -115.560685) (xy 329.823259 -115.516806) (xy 329.854821 -115.476772) (xy 329.872848 -115.458748)
			(xy 329.87996 -115.451636) (xy 329.892152 -115.424458) (xy 329.894182 -115.41956) (xy 329.896359 -115.409185)
			(xy 329.89647 -115.403884) (xy 329.89647 -115.350544) (xy 329.896334 -115.345246) (xy 329.894163 -115.334874)
			(xy 329.892152 -115.32997) (xy 329.880214 -115.302792) (xy 329.873102 -115.295934) (xy 329.855576 -115.277646)
			(xy 329.855322 -115.277646) (xy 329.854306 -115.276376) (xy 329.846712 -115.268824) (xy 329.827156 -115.260153)
			(xy 329.81646 -115.259612) (xy 328.210926 -115.259612) (xy 328.200482 -115.260182) (xy 328.18135 -115.268584)
			(xy 328.173842 -115.275868) (xy 328.123296 -115.32997) (xy 328.11976 -115.33394) (xy 328.114255 -115.343032)
			(xy 328.112374 -115.348004) (xy 328.109072 -115.35791) (xy 328.10958 -115.368324) (xy 328.110596 -115.394486)
			(xy 328.11011 -115.421737) (xy 328.102354 -115.475685) (xy 328.086999 -115.52798) (xy 328.064357 -115.577557)
			(xy 328.034891 -115.623407) (xy 327.9992 -115.664598) (xy 327.958009 -115.700289) (xy 327.912159 -115.729755)
			(xy 327.862582 -115.752397) (xy 327.810287 -115.767752) (xy 327.756339 -115.775508) (xy 327.701837 -115.775508)
			(xy 327.647889 -115.767752) (xy 327.595594 -115.752397) (xy 327.546017 -115.729755) (xy 327.500167 -115.700289)
			(xy 327.458976 -115.664598) (xy 327.423285 -115.623407) (xy 327.393819 -115.577557) (xy 327.371177 -115.52798)
			(xy 327.355822 -115.475685) (xy 327.348066 -115.421737) (xy 327.34758 -115.394486) (xy 327.34885 -115.364006)
			(xy 327.349104 -115.357656) (xy 327.345802 -115.348004) (xy 327.343921 -115.343032) (xy 327.338417 -115.333939)
			(xy 327.33488 -115.32997) (xy 327.28408 -115.275614) (xy 327.276581 -115.268346) (xy 327.257428 -115.260079)
			(xy 327.246996 -115.259612) (xy 325.867776 -115.259612) (xy 325.862898 -115.259706) (xy 325.853308 -115.261492)
			(xy 325.848726 -115.263168) (xy 325.823326 -115.273582) (xy 325.816722 -115.279424) (xy 325.801649 -115.292644)
			(xy 325.769197 -115.31619) (xy 325.751952 -115.326414) (xy 325.744461 -115.331195) (xy 325.733048 -115.3448)
			(xy 325.726952 -115.361478) (xy 325.726552 -115.370356) (xy 325.726552 -115.45824) (xy 325.726883 -115.467134)
			(xy 325.732962 -115.48385) (xy 325.744403 -115.497469) (xy 325.751952 -115.502182) (xy 325.776431 -115.516897)
			(xy 325.821085 -115.552504) (xy 325.859932 -115.594371) (xy 325.892101 -115.641562) (xy 325.916873 -115.693023)
			(xy 325.933696 -115.747602) (xy 325.942192 -115.804079) (xy 325.942706 -115.832636) (xy 325.94222 -115.859887)
			(xy 325.934464 -115.913835) (xy 325.919109 -115.96613) (xy 325.896467 -116.015707) (xy 325.867001 -116.061557)
			(xy 325.83131 -116.102748) (xy 325.790119 -116.138439) (xy 325.744269 -116.167905) (xy 325.694692 -116.190547)
			(xy 325.642397 -116.205902) (xy 325.588449 -116.213658) (xy 325.533947 -116.213658) (xy 325.479999 -116.205902)
			(xy 325.427704 -116.190547) (xy 325.378127 -116.167905) (xy 325.332277 -116.138439) (xy 325.291086 -116.102748)
			(xy 325.255395 -116.061557) (xy 325.225929 -116.015707) (xy 325.203287 -115.96613) (xy 325.187932 -115.913835)
			(xy 325.180176 -115.859887) (xy 325.17969 -115.832636) (xy 325.180228 -115.804084) (xy 325.188744 -115.747617)
			(xy 325.205578 -115.69305) (xy 325.230354 -115.641599) (xy 325.262517 -115.594413) (xy 325.301352 -115.552546)
			(xy 325.34599 -115.516931) (xy 325.370444 -115.502182) (xy 325.377935 -115.497401) (xy 325.389348 -115.483796)
			(xy 325.395443 -115.467118) (xy 325.395844 -115.45824) (xy 325.395844 -115.370356) (xy 325.395512 -115.361463)
			(xy 325.389432 -115.344748) (xy 325.37799 -115.331131) (xy 325.370444 -115.326414) (xy 325.353202 -115.316184)
			(xy 325.320752 -115.292637) (xy 325.305674 -115.279424) (xy 325.29907 -115.273582) (xy 325.27367 -115.263168)
			(xy 325.269095 -115.261465) (xy 325.259501 -115.259674) (xy 325.25462 -115.259612) (xy 323.755512 -115.259612)
			(xy 323.745441 -115.259192) (xy 323.726832 -115.251482) (xy 323.719444 -115.244626) (xy 323.1261 -114.651282)
			(xy 323.117464 -114.644424) (xy 323.09465 -114.629234) (xy 323.053218 -114.593355) (xy 323.017343 -114.551919)
			(xy 323.002148 -114.529108) (xy 322.999354 -114.524536) (xy 322.700142 -114.225324) (xy 322.693303 -114.217923)
			(xy 322.685589 -114.199325) (xy 322.685156 -114.189256) (xy 322.685156 -113.968784) (xy 322.659502 -113.940082)
			(xy 322.639944 -113.937796) (xy 322.616097 -113.934875) (xy 322.569346 -113.923794) (xy 322.546726 -113.915698)
			(xy 322.534534 -113.911126) (xy 322.508626 -113.914936) (xy 322.419218 -113.983516) (xy 322.408804 -114.007646)
			(xy 322.410074 -114.0206) (xy 322.411852 -114.056668) (xy 322.411852 -114.057938) (xy 322.41133 -114.085165)
			(xy 322.403511 -114.139057) (xy 322.38811 -114.19129) (xy 322.365439 -114.240802) (xy 322.335959 -114.286588)
			(xy 322.300268 -114.327718) (xy 322.259092 -114.363355) (xy 322.213268 -114.392776) (xy 322.163726 -114.415383)
			(xy 322.111474 -114.430717) (xy 322.057572 -114.438465) (xy 322.030344 -114.438938) (xy 322.003087 -114.438478)
			(xy 321.949127 -114.430726) (xy 321.89682 -114.415372) (xy 321.84723 -114.39273) (xy 321.801368 -114.363261)
			(xy 321.760166 -114.327565) (xy 321.724465 -114.286368) (xy 321.694991 -114.240509) (xy 321.672343 -114.190922)
			(xy 321.656984 -114.138616) (xy 321.649225 -114.084657) (xy 321.649225 -114.030143) (xy 321.656984 -113.976184)
			(xy 321.672343 -113.923878) (xy 321.694991 -113.874291) (xy 321.724465 -113.828432) (xy 321.760166 -113.787235)
			(xy 321.801368 -113.751539) (xy 321.84723 -113.72207) (xy 321.89682 -113.699428) (xy 321.949127 -113.684074)
			(xy 322.003087 -113.676322) (xy 322.030344 -113.675922) (xy 322.064633 -113.676647) (xy 322.132104 -113.688921)
			(xy 322.164456 -113.700306) (xy 322.176648 -113.704878) (xy 322.202556 -113.701068) (xy 322.291964 -113.632488)
			(xy 322.302378 -113.608358) (xy 322.301108 -113.595404) (xy 322.29933 -113.559336) (xy 322.29933 -113.558066)
			(xy 322.299848 -113.530163) (xy 322.308044 -113.474962) (xy 322.324197 -113.421544) (xy 322.347963 -113.371051)
			(xy 322.378834 -113.32456) (xy 322.41615 -113.283065) (xy 322.459116 -113.247451) (xy 322.506813 -113.218479)
			(xy 322.558223 -113.196767) (xy 322.612248 -113.18278) (xy 322.639944 -113.179352) (xy 322.659502 -113.177066)
			(xy 322.685156 -113.148364) (xy 322.685156 -108.508038) (xy 322.682616 -108.500164) (xy 322.673365 -108.470733)
			(xy 322.663417 -108.409851) (xy 322.662804 -108.379006) (xy 322.663417 -108.348162) (xy 322.673369 -108.28728)
			(xy 322.682616 -108.257848) (xy 322.685156 -108.249974) (xy 322.685156 -107.847638) (xy 322.682616 -107.839764)
			(xy 322.673365 -107.810333) (xy 322.663417 -107.749451) (xy 322.662804 -107.718606) (xy 322.663417 -107.687762)
			(xy 322.673369 -107.62688) (xy 322.682616 -107.597448) (xy 322.685156 -107.589574) (xy 322.685156 -107.317286)
			(xy 322.684729 -107.307218) (xy 322.677006 -107.288621) (xy 322.67017 -107.281218) (xy 322.63461 -107.245658)
			(xy 322.626094 -107.238068) (xy 322.604595 -107.230534) (xy 322.593208 -107.23118) (xy 322.502784 -107.241086)
			(xy 322.48348 -107.253278) (xy 322.47713 -107.26293) (xy 322.462049 -107.285782) (xy 322.426375 -107.327318)
			(xy 322.385126 -107.363322) (xy 322.33915 -107.393055) (xy 322.289393 -107.415903) (xy 322.236879 -107.431397)
			(xy 322.182688 -107.439218) (xy 322.155312 -107.439714) (xy 322.128058 -107.439251) (xy 322.074106 -107.431496)
			(xy 322.021806 -107.416141) (xy 321.972224 -107.393499) (xy 321.926369 -107.364032) (xy 321.885175 -107.328338)
			(xy 321.849479 -107.287145) (xy 321.820009 -107.241292) (xy 321.797365 -107.191711) (xy 321.782008 -107.139412)
			(xy 321.77425 -107.08546) (xy 321.773804 -107.058206) (xy 321.774324 -107.029467) (xy 321.782946 -106.972639)
			(xy 321.799996 -106.917747) (xy 321.825087 -106.866034) (xy 321.857653 -106.818671) (xy 321.876928 -106.797348)
			(xy 321.883786 -106.790236) (xy 321.890644 -106.772456) (xy 321.890644 -106.683556) (xy 321.883786 -106.66603)
			(xy 321.876928 -106.658664) (xy 321.858129 -106.63787) (xy 321.826202 -106.591796) (xy 321.80135 -106.541551)
			(xy 321.784106 -106.488215) (xy 321.77484 -106.432931) (xy 321.773804 -106.404918) (xy 321.77355 -106.395012)
			(xy 321.766184 -106.377232) (xy 316.831218 -101.442266) (xy 316.823818 -101.435425) (xy 316.805219 -101.42771)
			(xy 316.79515 -101.42728) (xy 316.53734 -101.42728) (xy 316.512051 -101.42678) (xy 316.462096 -101.418865)
			(xy 316.413993 -101.403239) (xy 316.368923 -101.380286) (xy 316.327996 -101.35057) (xy 316.309756 -101.333046)
			(xy 310.829706 -95.852742) (xy 310.82231 -95.84589) (xy 310.803711 -95.838147) (xy 310.793638 -95.837756)
			(xy 308.626256 -95.837756) (xy 308.615593 -95.838206) (xy 308.596116 -95.846881) (xy 308.588664 -95.85452)
			(xy 308.531006 -95.918274) (xy 308.524148 -95.938594) (xy 308.525418 -95.949516) (xy 308.526392 -95.95952)
			(xy 308.527411 -95.979597) (xy 308.52745 -95.989648) (xy 308.526964 -96.016899) (xy 308.519208 -96.070847)
			(xy 308.503853 -96.123142) (xy 308.481211 -96.172719) (xy 308.451745 -96.218569) (xy 308.416054 -96.25976)
			(xy 308.374863 -96.295451) (xy 308.329013 -96.324917) (xy 308.279436 -96.347559) (xy 308.227141 -96.362914)
			(xy 308.173193 -96.37067) (xy 308.118691 -96.37067) (xy 308.064743 -96.362914) (xy 308.012448 -96.347559)
			(xy 307.962871 -96.324917) (xy 307.917021 -96.295451) (xy 307.87583 -96.25976) (xy 307.840139 -96.218569)
			(xy 307.810673 -96.172719) (xy 307.788031 -96.123142) (xy 307.772676 -96.070847) (xy 307.76492 -96.016899)
			(xy 307.764434 -95.989648) (xy 307.76473 -95.967149) (xy 307.769945 -95.922454) (xy 307.774848 -95.900494)
			(xy 307.776372 -95.894652) (xy 307.776372 -95.888556) (xy 307.775876 -95.878556) (xy 307.768208 -95.860084)
			(xy 307.754055 -95.845952) (xy 307.735573 -95.83831) (xy 307.725572 -95.837756) (xy 307.710586 -95.837756)
			(xy 307.700619 -95.838232) (xy 307.682177 -95.845801) (xy 307.674772 -95.852488) (xy 306.487322 -97.039938)
			(xy 306.92547 -97.039938) (xy 306.929541 -96.984316) (xy 306.941667 -96.929879) (xy 306.96159 -96.877788)
			(xy 306.988886 -96.829153) (xy 307.022972 -96.78501) (xy 307.063121 -96.746301) (xy 307.108479 -96.71385)
			(xy 307.158079 -96.688349) (xy 307.210863 -96.670342) (xy 307.265706 -96.660212) (xy 307.32144 -96.658175)
			(xy 307.376877 -96.664275) (xy 307.430834 -96.678381) (xy 307.482163 -96.700193) (xy 307.529769 -96.729247)
			(xy 307.572637 -96.764922) (xy 307.609854 -96.806459) (xy 307.640627 -96.852972) (xy 307.664299 -96.903469)
			(xy 307.680367 -96.956876) (xy 307.688487 -97.012052) (xy 307.688996 -97.039938) (xy 307.688487 -97.067824)
			(xy 307.680367 -97.123) (xy 307.664299 -97.176407) (xy 307.640627 -97.226904) (xy 307.609854 -97.273417)
			(xy 307.572637 -97.314954) (xy 307.529769 -97.350629) (xy 307.482163 -97.379683) (xy 307.430834 -97.401495)
			(xy 307.376877 -97.415601) (xy 307.32144 -97.421701) (xy 307.265706 -97.419664) (xy 307.210863 -97.409534)
			(xy 307.158079 -97.391527) (xy 307.108479 -97.366026) (xy 307.063121 -97.333575) (xy 307.022972 -97.294866)
			(xy 306.988886 -97.250723) (xy 306.96159 -97.202088) (xy 306.941667 -97.149997) (xy 306.929541 -97.09556)
			(xy 306.92547 -97.039938) (xy 306.487322 -97.039938) (xy 306.441856 -97.085404) (xy 306.435242 -97.092732)
			(xy 306.427667 -97.110941) (xy 306.427511 -97.130662) (xy 306.43068 -97.140014) (xy 306.470812 -97.241106)
			(xy 306.49545 -97.258378) (xy 306.510944 -97.258886) (xy 306.537667 -97.26011) (xy 306.590399 -97.269112)
			(xy 306.641356 -97.28539) (xy 306.68954 -97.308626) (xy 306.734007 -97.338365) (xy 306.773884 -97.374023)
			(xy 306.80839 -97.414901) (xy 306.836848 -97.460197) (xy 306.8587 -97.509025) (xy 306.873519 -97.560426)
			(xy 306.881013 -97.613393) (xy 306.88153 -97.64014) (xy 306.881042 -97.66739) (xy 306.87328 -97.721335)
			(xy 306.857922 -97.773626) (xy 306.835279 -97.823199) (xy 306.805812 -97.869046) (xy 306.770121 -97.910234)
			(xy 306.728932 -97.945923) (xy 306.683083 -97.975388) (xy 306.633509 -97.998028) (xy 306.581217 -98.013384)
			(xy 306.527272 -98.021143) (xy 306.500022 -98.021648) (xy 306.47327 -98.021198) (xy 306.42029 -98.013722)
			(xy 306.368876 -97.998915) (xy 306.320036 -97.977065) (xy 306.27473 -97.948604) (xy 306.233846 -97.914089)
			(xy 306.198189 -97.874198) (xy 306.168458 -97.829714) (xy 306.145236 -97.781512) (xy 306.128981 -97.730537)
			(xy 306.12001 -97.67779) (xy 306.118768 -97.651062) (xy 306.11826 -97.635568) (xy 306.100988 -97.61093)
			(xy 305.999896 -97.570798) (xy 305.990557 -97.567575) (xy 305.97082 -97.567736) (xy 305.952604 -97.575337)
			(xy 305.945286 -97.581974) (xy 305.35626 -98.171) (xy 307.763924 -98.171) (xy 307.767995 -98.115378)
			(xy 307.780121 -98.060941) (xy 307.800044 -98.00885) (xy 307.82734 -97.960215) (xy 307.861426 -97.916072)
			(xy 307.901575 -97.877363) (xy 307.946933 -97.844912) (xy 307.996533 -97.819411) (xy 308.049317 -97.801404)
			(xy 308.10416 -97.791274) (xy 308.159894 -97.789237) (xy 308.215331 -97.795337) (xy 308.269288 -97.809443)
			(xy 308.320617 -97.831255) (xy 308.368223 -97.860309) (xy 308.411091 -97.895984) (xy 308.448308 -97.937521)
			(xy 308.479081 -97.984034) (xy 308.496714 -98.021648) (xy 310.369456 -98.021648) (xy 310.373527 -97.966026)
			(xy 310.385653 -97.911589) (xy 310.405576 -97.859498) (xy 310.432872 -97.810863) (xy 310.466958 -97.76672)
			(xy 310.507107 -97.728011) (xy 310.552465 -97.69556) (xy 310.602065 -97.670059) (xy 310.654849 -97.652052)
			(xy 310.709692 -97.641922) (xy 310.765426 -97.639885) (xy 310.820863 -97.645985) (xy 310.87482 -97.660091)
			(xy 310.926149 -97.681903) (xy 310.973755 -97.710957) (xy 311.016623 -97.746632) (xy 311.05384 -97.788169)
			(xy 311.084613 -97.834682) (xy 311.108285 -97.885179) (xy 311.124353 -97.938586) (xy 311.132473 -97.993762)
			(xy 311.132982 -98.021648) (xy 311.132473 -98.049534) (xy 311.124353 -98.10471) (xy 311.108285 -98.158117)
			(xy 311.084613 -98.208614) (xy 311.05384 -98.255127) (xy 311.016623 -98.296664) (xy 310.973755 -98.332339)
			(xy 310.926149 -98.361393) (xy 310.87482 -98.383205) (xy 310.820863 -98.397311) (xy 310.765426 -98.403411)
			(xy 310.709692 -98.401374) (xy 310.654849 -98.391244) (xy 310.602065 -98.373237) (xy 310.552465 -98.347736)
			(xy 310.507107 -98.315285) (xy 310.466958 -98.276576) (xy 310.432872 -98.232433) (xy 310.405576 -98.183798)
			(xy 310.385653 -98.131707) (xy 310.373527 -98.07727) (xy 310.369456 -98.021648) (xy 308.496714 -98.021648)
			(xy 308.502753 -98.034531) (xy 308.518821 -98.087938) (xy 308.526941 -98.143114) (xy 308.52745 -98.171)
			(xy 308.526941 -98.198886) (xy 308.518821 -98.254062) (xy 308.502753 -98.307469) (xy 308.479081 -98.357966)
			(xy 308.448308 -98.404479) (xy 308.411091 -98.446016) (xy 308.368223 -98.481691) (xy 308.320617 -98.510745)
			(xy 308.269288 -98.532557) (xy 308.215331 -98.546663) (xy 308.159894 -98.552763) (xy 308.10416 -98.550726)
			(xy 308.049317 -98.540596) (xy 307.996533 -98.522589) (xy 307.946933 -98.497088) (xy 307.901575 -98.464637)
			(xy 307.861426 -98.425928) (xy 307.82734 -98.381785) (xy 307.800044 -98.33315) (xy 307.780121 -98.281059)
			(xy 307.767995 -98.226622) (xy 307.763924 -98.171) (xy 305.35626 -98.171) (xy 304.489612 -99.037648)
			(xy 310.369456 -99.037648) (xy 310.373527 -98.982026) (xy 310.385653 -98.927589) (xy 310.405576 -98.875498)
			(xy 310.432872 -98.826863) (xy 310.466958 -98.78272) (xy 310.507107 -98.744011) (xy 310.552465 -98.71156)
			(xy 310.602065 -98.686059) (xy 310.654849 -98.668052) (xy 310.709692 -98.657922) (xy 310.765426 -98.655885)
			(xy 310.820863 -98.661985) (xy 310.87482 -98.676091) (xy 310.926149 -98.697903) (xy 310.973755 -98.726957)
			(xy 311.016623 -98.762632) (xy 311.05384 -98.804169) (xy 311.084613 -98.850682) (xy 311.108285 -98.901179)
			(xy 311.124353 -98.954586) (xy 311.132473 -99.009762) (xy 311.132982 -99.037648) (xy 311.132473 -99.065534)
			(xy 311.124353 -99.12071) (xy 311.108285 -99.174117) (xy 311.084613 -99.224614) (xy 311.05384 -99.271127)
			(xy 311.016623 -99.312664) (xy 310.973755 -99.348339) (xy 310.926149 -99.377393) (xy 310.87482 -99.399205)
			(xy 310.820863 -99.413311) (xy 310.765426 -99.419411) (xy 310.709692 -99.417374) (xy 310.654849 -99.407244)
			(xy 310.602065 -99.389237) (xy 310.552465 -99.363736) (xy 310.507107 -99.331285) (xy 310.466958 -99.292576)
			(xy 310.432872 -99.248433) (xy 310.405576 -99.199798) (xy 310.385653 -99.147707) (xy 310.373527 -99.09327)
			(xy 310.369456 -99.037648) (xy 304.489612 -99.037648) (xy 304.087276 -99.439984) (xy 307.509924 -99.439984)
			(xy 307.513995 -99.384362) (xy 307.526121 -99.329925) (xy 307.546044 -99.277834) (xy 307.57334 -99.229199)
			(xy 307.607426 -99.185056) (xy 307.647575 -99.146347) (xy 307.692933 -99.113896) (xy 307.742533 -99.088395)
			(xy 307.795317 -99.070388) (xy 307.85016 -99.060258) (xy 307.905894 -99.058221) (xy 307.961331 -99.064321)
			(xy 308.015288 -99.078427) (xy 308.066617 -99.100239) (xy 308.114223 -99.129293) (xy 308.157091 -99.164968)
			(xy 308.194308 -99.206505) (xy 308.225081 -99.253018) (xy 308.248753 -99.303515) (xy 308.264821 -99.356922)
			(xy 308.272941 -99.412098) (xy 308.27345 -99.439984) (xy 308.272941 -99.46787) (xy 308.264821 -99.523046)
			(xy 308.248753 -99.576453) (xy 308.225081 -99.62695) (xy 308.194308 -99.673463) (xy 308.157091 -99.715)
			(xy 308.114223 -99.750675) (xy 308.066617 -99.779729) (xy 308.015288 -99.801541) (xy 307.961331 -99.815647)
			(xy 307.905894 -99.821747) (xy 307.85016 -99.81971) (xy 307.795317 -99.80958) (xy 307.742533 -99.791573)
			(xy 307.692933 -99.766072) (xy 307.647575 -99.733621) (xy 307.607426 -99.694912) (xy 307.57334 -99.650769)
			(xy 307.546044 -99.602134) (xy 307.526121 -99.550043) (xy 307.513995 -99.495606) (xy 307.509924 -99.439984)
			(xy 304.087276 -99.439984) (xy 303.842166 -99.685094) (xy 303.834766 -99.691936) (xy 303.816168 -99.699659)
			(xy 303.806098 -99.70008) (xy 303.219612 -99.70008) (xy 303.209623 -99.700615) (xy 303.191186 -99.708323)
			(xy 303.183798 -99.715066) (xy 303.08169 -99.81692) (xy 303.075086 -99.82835) (xy 303.073308 -99.835208)
			(xy 303.065835 -99.862134) (xy 303.044094 -99.91361) (xy 303.015078 -99.961365) (xy 302.979408 -100.004377)
			(xy 302.939844 -100.039932) (xy 306.076856 -100.039932) (xy 306.080927 -99.98431) (xy 306.093053 -99.929873)
			(xy 306.112976 -99.877782) (xy 306.140272 -99.829147) (xy 306.174358 -99.785004) (xy 306.214507 -99.746295)
			(xy 306.259865 -99.713844) (xy 306.309465 -99.688343) (xy 306.362249 -99.670336) (xy 306.417092 -99.660206)
			(xy 306.472826 -99.658169) (xy 306.528263 -99.664269) (xy 306.58222 -99.678375) (xy 306.633549 -99.700187)
			(xy 306.681155 -99.729241) (xy 306.724023 -99.764916) (xy 306.76124 -99.806453) (xy 306.792013 -99.852966)
			(xy 306.815685 -99.903463) (xy 306.831753 -99.95687) (xy 306.839873 -100.012046) (xy 306.840382 -100.039932)
			(xy 306.840076 -100.056696) (xy 310.369456 -100.056696) (xy 310.373527 -100.001074) (xy 310.385653 -99.946637)
			(xy 310.405576 -99.894546) (xy 310.432872 -99.845911) (xy 310.466958 -99.801768) (xy 310.507107 -99.763059)
			(xy 310.552465 -99.730608) (xy 310.602065 -99.705107) (xy 310.654849 -99.6871) (xy 310.709692 -99.67697)
			(xy 310.765426 -99.674933) (xy 310.820863 -99.681033) (xy 310.87482 -99.695139) (xy 310.926149 -99.716951)
			(xy 310.973755 -99.746005) (xy 311.016623 -99.78168) (xy 311.05384 -99.823217) (xy 311.084613 -99.86973)
			(xy 311.108285 -99.920227) (xy 311.124353 -99.973634) (xy 311.132473 -100.02881) (xy 311.132982 -100.056696)
			(xy 311.132473 -100.084582) (xy 311.124353 -100.139758) (xy 311.108285 -100.193165) (xy 311.084613 -100.243662)
			(xy 311.05384 -100.290175) (xy 311.016623 -100.331712) (xy 310.973755 -100.367387) (xy 310.926149 -100.396441)
			(xy 310.87482 -100.418253) (xy 310.820863 -100.432359) (xy 310.765426 -100.438459) (xy 310.709692 -100.436422)
			(xy 310.654849 -100.426292) (xy 310.602065 -100.408285) (xy 310.552465 -100.382784) (xy 310.507107 -100.350333)
			(xy 310.466958 -100.311624) (xy 310.432872 -100.267481) (xy 310.405576 -100.218846) (xy 310.385653 -100.166755)
			(xy 310.373527 -100.112318) (xy 310.369456 -100.056696) (xy 306.840076 -100.056696) (xy 306.839873 -100.067818)
			(xy 306.831753 -100.122994) (xy 306.815685 -100.176401) (xy 306.792013 -100.226898) (xy 306.76124 -100.273411)
			(xy 306.724023 -100.314948) (xy 306.681155 -100.350623) (xy 306.633549 -100.379677) (xy 306.58222 -100.401489)
			(xy 306.528263 -100.415595) (xy 306.472826 -100.421695) (xy 306.417092 -100.419658) (xy 306.362249 -100.409528)
			(xy 306.309465 -100.391521) (xy 306.259865 -100.36602) (xy 306.214507 -100.333569) (xy 306.174358 -100.29486)
			(xy 306.140272 -100.250717) (xy 306.112976 -100.202082) (xy 306.093053 -100.149991) (xy 306.080927 -100.095554)
			(xy 306.076856 -100.039932) (xy 302.939844 -100.039932) (xy 302.937846 -100.041728) (xy 302.891281 -100.072617)
			(xy 302.840709 -100.096384) (xy 302.787211 -100.112522) (xy 302.731931 -100.120685) (xy 302.703992 -100.121212)
			(xy 302.677195 -100.120751) (xy 302.624132 -100.113235) (xy 302.572642 -100.098368) (xy 302.52374 -100.07644)
			(xy 302.478388 -100.047884) (xy 302.437478 -100.013263) (xy 302.401817 -99.973256) (xy 302.372105 -99.928653)
			(xy 302.348929 -99.88033) (xy 302.332743 -99.82924) (xy 302.323866 -99.776386) (xy 302.322738 -99.74961)
			(xy 302.321976 -99.728782) (xy 302.292512 -99.70008) (xy 290.611814 -99.70008) (xy 290.601764 -99.700587)
			(xy 290.583206 -99.70831) (xy 290.575746 -99.715066) (xy 290.568888 -99.721924) (xy 290.561268 -99.740466)
			(xy 290.561268 -99.75088) (xy 290.560748 -99.778108) (xy 290.552932 -99.832) (xy 290.537533 -99.884234)
			(xy 290.514863 -99.933747) (xy 290.485383 -99.979534) (xy 290.449692 -100.020664) (xy 290.408515 -100.0563)
			(xy 290.362689 -100.085719) (xy 290.313146 -100.108323) (xy 290.260891 -100.123653) (xy 290.206988 -100.131396)
			(xy 290.152532 -100.131396) (xy 290.098629 -100.123653) (xy 290.046374 -100.108323) (xy 289.996831 -100.085719)
			(xy 289.951005 -100.0563) (xy 289.909828 -100.020664) (xy 289.874137 -99.979534) (xy 289.844657 -99.933747)
			(xy 289.821987 -99.884234) (xy 289.806588 -99.832) (xy 289.798772 -99.778108) (xy 289.798252 -99.75088)
			(xy 289.798252 -99.750626) (xy 289.797814 -99.740563) (xy 289.790075 -99.721983) (xy 289.783266 -99.714558)
			(xy 289.776408 -99.7077) (xy 289.757866 -99.70008) (xy 288.71037 -99.70008) (xy 288.700302 -99.700508)
			(xy 288.681703 -99.708228) (xy 288.674302 -99.715066) (xy 287.342326 -101.047042) (xy 287.33496 -101.054154)
			(xy 287.32734 -101.07295) (xy 287.32734 -101.240082) (xy 306.493924 -101.240082) (xy 306.497995 -101.18446)
			(xy 306.510121 -101.130023) (xy 306.530044 -101.077932) (xy 306.55734 -101.029297) (xy 306.591426 -100.985154)
			(xy 306.631575 -100.946445) (xy 306.676933 -100.913994) (xy 306.726533 -100.888493) (xy 306.779317 -100.870486)
			(xy 306.83416 -100.860356) (xy 306.889894 -100.858319) (xy 306.945331 -100.864419) (xy 306.999288 -100.878525)
			(xy 307.050617 -100.900337) (xy 307.098223 -100.929391) (xy 307.141091 -100.965066) (xy 307.178308 -101.006603)
			(xy 307.209081 -101.053116) (xy 307.216831 -101.069648) (xy 307.786276 -101.069648) (xy 307.790347 -101.014026)
			(xy 307.802473 -100.959589) (xy 307.822396 -100.907498) (xy 307.849692 -100.858863) (xy 307.883778 -100.81472)
			(xy 307.923927 -100.776011) (xy 307.969285 -100.74356) (xy 308.018885 -100.718059) (xy 308.071669 -100.700052)
			(xy 308.126512 -100.689922) (xy 308.182246 -100.687885) (xy 308.237683 -100.693985) (xy 308.29164 -100.708091)
			(xy 308.342969 -100.729903) (xy 308.390575 -100.758957) (xy 308.433443 -100.794632) (xy 308.47066 -100.836169)
			(xy 308.501433 -100.882682) (xy 308.525105 -100.933179) (xy 308.541173 -100.986586) (xy 308.549293 -101.041762)
			(xy 308.549802 -101.069648) (xy 308.549293 -101.097534) (xy 308.541173 -101.15271) (xy 308.525105 -101.206117)
			(xy 308.501433 -101.256614) (xy 308.47066 -101.303127) (xy 308.433443 -101.344664) (xy 308.390575 -101.380339)
			(xy 308.342969 -101.409393) (xy 308.29164 -101.431205) (xy 308.237683 -101.445311) (xy 308.182246 -101.451411)
			(xy 308.126512 -101.449374) (xy 308.071669 -101.439244) (xy 308.018885 -101.421237) (xy 307.969285 -101.395736)
			(xy 307.923927 -101.363285) (xy 307.883778 -101.324576) (xy 307.849692 -101.280433) (xy 307.822396 -101.231798)
			(xy 307.802473 -101.179707) (xy 307.790347 -101.12527) (xy 307.786276 -101.069648) (xy 307.216831 -101.069648)
			(xy 307.232753 -101.103613) (xy 307.248821 -101.15702) (xy 307.256941 -101.212196) (xy 307.25745 -101.240082)
			(xy 307.256941 -101.267968) (xy 307.248821 -101.323144) (xy 307.232753 -101.376551) (xy 307.209081 -101.427048)
			(xy 307.178308 -101.473561) (xy 307.141091 -101.515098) (xy 307.098223 -101.550773) (xy 307.050617 -101.579827)
			(xy 306.999288 -101.601639) (xy 306.945331 -101.615745) (xy 306.889894 -101.621845) (xy 306.83416 -101.619808)
			(xy 306.779317 -101.609678) (xy 306.726533 -101.591671) (xy 306.676933 -101.56617) (xy 306.631575 -101.533719)
			(xy 306.591426 -101.49501) (xy 306.55734 -101.450867) (xy 306.530044 -101.402232) (xy 306.510121 -101.350141)
			(xy 306.497995 -101.295704) (xy 306.493924 -101.240082) (xy 287.32734 -101.240082) (xy 287.32734 -101.782372)
			(xy 289.797742 -101.782372) (xy 289.801813 -101.72675) (xy 289.813939 -101.672313) (xy 289.833862 -101.620222)
			(xy 289.861158 -101.571587) (xy 289.895244 -101.527444) (xy 289.935393 -101.488735) (xy 289.980751 -101.456284)
			(xy 290.030351 -101.430783) (xy 290.083135 -101.412776) (xy 290.137978 -101.402646) (xy 290.193712 -101.400609)
			(xy 290.249149 -101.406709) (xy 290.303106 -101.420815) (xy 290.354435 -101.442627) (xy 290.402041 -101.471681)
			(xy 290.444909 -101.507356) (xy 290.482126 -101.548893) (xy 290.512899 -101.595406) (xy 290.536571 -101.645903)
			(xy 290.552639 -101.69931) (xy 290.560759 -101.754486) (xy 290.561268 -101.782372) (xy 290.560759 -101.810258)
			(xy 290.552639 -101.865434) (xy 290.536571 -101.918841) (xy 290.512899 -101.969338) (xy 290.482126 -102.015851)
			(xy 290.444909 -102.057388) (xy 290.402041 -102.093063) (xy 290.354435 -102.122117) (xy 290.303106 -102.143929)
			(xy 290.249149 -102.158035) (xy 290.193712 -102.164135) (xy 290.137978 -102.162098) (xy 290.083135 -102.151968)
			(xy 290.030351 -102.133961) (xy 289.980751 -102.10846) (xy 289.935393 -102.076009) (xy 289.895244 -102.0373)
			(xy 289.861158 -101.993157) (xy 289.833862 -101.944522) (xy 289.813939 -101.892431) (xy 289.801813 -101.837994)
			(xy 289.797742 -101.782372) (xy 287.32734 -101.782372) (xy 287.32734 -102.798372) (xy 289.797742 -102.798372)
			(xy 289.801813 -102.74275) (xy 289.813939 -102.688313) (xy 289.833862 -102.636222) (xy 289.861158 -102.587587)
			(xy 289.895244 -102.543444) (xy 289.935393 -102.504735) (xy 289.980751 -102.472284) (xy 290.030351 -102.446783)
			(xy 290.083135 -102.428776) (xy 290.137978 -102.418646) (xy 290.193712 -102.416609) (xy 290.249149 -102.422709)
			(xy 290.303106 -102.436815) (xy 290.310549 -102.439978) (xy 299.130718 -102.439978) (xy 299.134789 -102.384356)
			(xy 299.146915 -102.329919) (xy 299.166838 -102.277828) (xy 299.194134 -102.229193) (xy 299.22822 -102.18505)
			(xy 299.268369 -102.146341) (xy 299.313727 -102.11389) (xy 299.363327 -102.088389) (xy 299.416111 -102.070382)
			(xy 299.470954 -102.060252) (xy 299.526688 -102.058215) (xy 299.582125 -102.064315) (xy 299.636082 -102.078421)
			(xy 299.687411 -102.100233) (xy 299.735017 -102.129287) (xy 299.777885 -102.164962) (xy 299.815102 -102.206499)
			(xy 299.845875 -102.253012) (xy 299.869547 -102.303509) (xy 299.885615 -102.356916) (xy 299.893735 -102.412092)
			(xy 299.894244 -102.439978) (xy 306.112924 -102.439978) (xy 306.116995 -102.384356) (xy 306.129121 -102.329919)
			(xy 306.149044 -102.277828) (xy 306.17634 -102.229193) (xy 306.210426 -102.18505) (xy 306.250575 -102.146341)
			(xy 306.295933 -102.11389) (xy 306.345533 -102.088389) (xy 306.398317 -102.070382) (xy 306.45316 -102.060252)
			(xy 306.508894 -102.058215) (xy 306.564331 -102.064315) (xy 306.618288 -102.078421) (xy 306.642468 -102.088696)
			(xy 310.369456 -102.088696) (xy 310.373527 -102.033074) (xy 310.385653 -101.978637) (xy 310.405576 -101.926546)
			(xy 310.432872 -101.877911) (xy 310.466958 -101.833768) (xy 310.507107 -101.795059) (xy 310.552465 -101.762608)
			(xy 310.602065 -101.737107) (xy 310.654849 -101.7191) (xy 310.709692 -101.70897) (xy 310.765426 -101.706933)
			(xy 310.820863 -101.713033) (xy 310.87482 -101.727139) (xy 310.926149 -101.748951) (xy 310.973755 -101.778005)
			(xy 311.016623 -101.81368) (xy 311.05384 -101.855217) (xy 311.084613 -101.90173) (xy 311.108285 -101.952227)
			(xy 311.124353 -102.005634) (xy 311.132473 -102.06081) (xy 311.132982 -102.088696) (xy 311.132473 -102.116582)
			(xy 311.124353 -102.171758) (xy 311.108285 -102.225165) (xy 311.084613 -102.275662) (xy 311.05384 -102.322175)
			(xy 311.016623 -102.363712) (xy 310.973755 -102.399387) (xy 310.926149 -102.428441) (xy 310.87482 -102.450253)
			(xy 310.820863 -102.464359) (xy 310.765426 -102.470459) (xy 310.709692 -102.468422) (xy 310.654849 -102.458292)
			(xy 310.602065 -102.440285) (xy 310.552465 -102.414784) (xy 310.507107 -102.382333) (xy 310.466958 -102.343624)
			(xy 310.432872 -102.299481) (xy 310.405576 -102.250846) (xy 310.385653 -102.198755) (xy 310.373527 -102.144318)
			(xy 310.369456 -102.088696) (xy 306.642468 -102.088696) (xy 306.669617 -102.100233) (xy 306.717223 -102.129287)
			(xy 306.760091 -102.164962) (xy 306.797308 -102.206499) (xy 306.828081 -102.253012) (xy 306.851753 -102.303509)
			(xy 306.867821 -102.356916) (xy 306.875941 -102.412092) (xy 306.87645 -102.439978) (xy 306.875941 -102.467864)
			(xy 306.872831 -102.489) (xy 307.001924 -102.489) (xy 307.005995 -102.433378) (xy 307.018121 -102.378941)
			(xy 307.038044 -102.32685) (xy 307.06534 -102.278215) (xy 307.099426 -102.234072) (xy 307.139575 -102.195363)
			(xy 307.184933 -102.162912) (xy 307.234533 -102.137411) (xy 307.287317 -102.119404) (xy 307.34216 -102.109274)
			(xy 307.397894 -102.107237) (xy 307.453331 -102.113337) (xy 307.507288 -102.127443) (xy 307.558617 -102.149255)
			(xy 307.606223 -102.178309) (xy 307.649091 -102.213984) (xy 307.686308 -102.255521) (xy 307.717081 -102.302034)
			(xy 307.740753 -102.352531) (xy 307.756821 -102.405938) (xy 307.764941 -102.461114) (xy 307.76545 -102.489)
			(xy 307.764941 -102.516886) (xy 307.756821 -102.572062) (xy 307.740753 -102.625469) (xy 307.717081 -102.675966)
			(xy 307.686308 -102.722479) (xy 307.649091 -102.764016) (xy 307.606223 -102.799691) (xy 307.558617 -102.828745)
			(xy 307.507288 -102.850557) (xy 307.453331 -102.864663) (xy 307.397894 -102.870763) (xy 307.34216 -102.868726)
			(xy 307.287317 -102.858596) (xy 307.234533 -102.840589) (xy 307.184933 -102.815088) (xy 307.139575 -102.782637)
			(xy 307.099426 -102.743928) (xy 307.06534 -102.699785) (xy 307.038044 -102.65115) (xy 307.018121 -102.599059)
			(xy 307.005995 -102.544622) (xy 307.001924 -102.489) (xy 306.872831 -102.489) (xy 306.867821 -102.52304)
			(xy 306.851753 -102.576447) (xy 306.828081 -102.626944) (xy 306.797308 -102.673457) (xy 306.760091 -102.714994)
			(xy 306.717223 -102.750669) (xy 306.669617 -102.779723) (xy 306.618288 -102.801535) (xy 306.564331 -102.815641)
			(xy 306.508894 -102.821741) (xy 306.45316 -102.819704) (xy 306.398317 -102.809574) (xy 306.345533 -102.791567)
			(xy 306.295933 -102.766066) (xy 306.250575 -102.733615) (xy 306.210426 -102.694906) (xy 306.17634 -102.650763)
			(xy 306.149044 -102.602128) (xy 306.129121 -102.550037) (xy 306.116995 -102.4956) (xy 306.112924 -102.439978)
			(xy 299.894244 -102.439978) (xy 299.893735 -102.467864) (xy 299.885615 -102.52304) (xy 299.869547 -102.576447)
			(xy 299.845875 -102.626944) (xy 299.815102 -102.673457) (xy 299.777885 -102.714994) (xy 299.735017 -102.750669)
			(xy 299.687411 -102.779723) (xy 299.636082 -102.801535) (xy 299.582125 -102.815641) (xy 299.526688 -102.821741)
			(xy 299.470954 -102.819704) (xy 299.416111 -102.809574) (xy 299.363327 -102.791567) (xy 299.313727 -102.766066)
			(xy 299.268369 -102.733615) (xy 299.22822 -102.694906) (xy 299.194134 -102.650763) (xy 299.166838 -102.602128)
			(xy 299.146915 -102.550037) (xy 299.134789 -102.4956) (xy 299.130718 -102.439978) (xy 290.310549 -102.439978)
			(xy 290.354435 -102.458627) (xy 290.402041 -102.487681) (xy 290.444909 -102.523356) (xy 290.482126 -102.564893)
			(xy 290.512899 -102.611406) (xy 290.536571 -102.661903) (xy 290.552639 -102.71531) (xy 290.560759 -102.770486)
			(xy 290.561268 -102.798372) (xy 290.560759 -102.826258) (xy 290.552639 -102.881434) (xy 290.536571 -102.934841)
			(xy 290.512899 -102.985338) (xy 290.482126 -103.031851) (xy 290.444909 -103.073388) (xy 290.407288 -103.104696)
			(xy 310.369456 -103.104696) (xy 310.373527 -103.049074) (xy 310.385653 -102.994637) (xy 310.405576 -102.942546)
			(xy 310.432872 -102.893911) (xy 310.466958 -102.849768) (xy 310.507107 -102.811059) (xy 310.552465 -102.778608)
			(xy 310.602065 -102.753107) (xy 310.654849 -102.7351) (xy 310.709692 -102.72497) (xy 310.765426 -102.722933)
			(xy 310.820863 -102.729033) (xy 310.87482 -102.743139) (xy 310.926149 -102.764951) (xy 310.973755 -102.794005)
			(xy 311.016623 -102.82968) (xy 311.05384 -102.871217) (xy 311.084613 -102.91773) (xy 311.108285 -102.968227)
			(xy 311.124353 -103.021634) (xy 311.132473 -103.07681) (xy 311.132982 -103.104696) (xy 311.132473 -103.132582)
			(xy 311.124353 -103.187758) (xy 311.108285 -103.241165) (xy 311.084613 -103.291662) (xy 311.05384 -103.338175)
			(xy 311.016623 -103.379712) (xy 310.973755 -103.415387) (xy 310.926149 -103.444441) (xy 310.87482 -103.466253)
			(xy 310.820863 -103.480359) (xy 310.765426 -103.486459) (xy 310.709692 -103.484422) (xy 310.654849 -103.474292)
			(xy 310.602065 -103.456285) (xy 310.552465 -103.430784) (xy 310.507107 -103.398333) (xy 310.466958 -103.359624)
			(xy 310.432872 -103.315481) (xy 310.405576 -103.266846) (xy 310.385653 -103.214755) (xy 310.373527 -103.160318)
			(xy 310.369456 -103.104696) (xy 290.407288 -103.104696) (xy 290.402041 -103.109063) (xy 290.354435 -103.138117)
			(xy 290.303106 -103.159929) (xy 290.249149 -103.174035) (xy 290.193712 -103.180135) (xy 290.137978 -103.178098)
			(xy 290.083135 -103.167968) (xy 290.030351 -103.149961) (xy 289.980751 -103.12446) (xy 289.935393 -103.092009)
			(xy 289.895244 -103.0533) (xy 289.861158 -103.009157) (xy 289.833862 -102.960522) (xy 289.813939 -102.908431)
			(xy 289.801813 -102.853994) (xy 289.797742 -102.798372) (xy 287.32734 -102.798372) (xy 287.32734 -103.814372)
			(xy 289.797742 -103.814372) (xy 289.801813 -103.75875) (xy 289.813939 -103.704313) (xy 289.833862 -103.652222)
			(xy 289.861158 -103.603587) (xy 289.895244 -103.559444) (xy 289.935393 -103.520735) (xy 289.980751 -103.488284)
			(xy 290.030351 -103.462783) (xy 290.083135 -103.444776) (xy 290.137978 -103.434646) (xy 290.193712 -103.432609)
			(xy 290.249149 -103.438709) (xy 290.303106 -103.452815) (xy 290.354435 -103.474627) (xy 290.402041 -103.503681)
			(xy 290.444909 -103.539356) (xy 290.482126 -103.580893) (xy 290.512899 -103.627406) (xy 290.536571 -103.677903)
			(xy 290.552639 -103.73131) (xy 290.560759 -103.786486) (xy 290.561268 -103.814372) (xy 290.560759 -103.842258)
			(xy 290.552639 -103.897434) (xy 290.536571 -103.950841) (xy 290.512899 -104.001338) (xy 290.482126 -104.047851)
			(xy 290.444909 -104.089388) (xy 290.402041 -104.125063) (xy 290.354435 -104.154117) (xy 290.303106 -104.175929)
			(xy 290.249149 -104.190035) (xy 290.193712 -104.196135) (xy 290.137978 -104.194098) (xy 290.083135 -104.183968)
			(xy 290.030351 -104.165961) (xy 289.980751 -104.14046) (xy 289.935393 -104.108009) (xy 289.895244 -104.0693)
			(xy 289.861158 -104.025157) (xy 289.833862 -103.976522) (xy 289.813939 -103.924431) (xy 289.801813 -103.869994)
			(xy 289.797742 -103.814372) (xy 287.32734 -103.814372) (xy 287.32734 -104.240076) (xy 299.130718 -104.240076)
			(xy 299.134789 -104.184454) (xy 299.146915 -104.130017) (xy 299.166838 -104.077926) (xy 299.194134 -104.029291)
			(xy 299.22822 -103.985148) (xy 299.268369 -103.946439) (xy 299.313727 -103.913988) (xy 299.363327 -103.888487)
			(xy 299.416111 -103.87048) (xy 299.470954 -103.86035) (xy 299.526688 -103.858313) (xy 299.582125 -103.864413)
			(xy 299.636082 -103.878519) (xy 299.687411 -103.900331) (xy 299.735017 -103.929385) (xy 299.777885 -103.96506)
			(xy 299.815102 -104.006597) (xy 299.845875 -104.05311) (xy 299.869547 -104.103607) (xy 299.885615 -104.157014)
			(xy 299.893735 -104.21219) (xy 299.894244 -104.240076) (xy 306.112924 -104.240076) (xy 306.116995 -104.184454)
			(xy 306.129121 -104.130017) (xy 306.149044 -104.077926) (xy 306.17634 -104.029291) (xy 306.210426 -103.985148)
			(xy 306.250575 -103.946439) (xy 306.295933 -103.913988) (xy 306.345533 -103.888487) (xy 306.398317 -103.87048)
			(xy 306.45316 -103.86035) (xy 306.508894 -103.858313) (xy 306.564331 -103.864413) (xy 306.618288 -103.878519)
			(xy 306.635893 -103.886) (xy 307.509924 -103.886) (xy 307.513995 -103.830378) (xy 307.526121 -103.775941)
			(xy 307.546044 -103.72385) (xy 307.57334 -103.675215) (xy 307.607426 -103.631072) (xy 307.647575 -103.592363)
			(xy 307.692933 -103.559912) (xy 307.742533 -103.534411) (xy 307.795317 -103.516404) (xy 307.85016 -103.506274)
			(xy 307.905894 -103.504237) (xy 307.961331 -103.510337) (xy 308.015288 -103.524443) (xy 308.066617 -103.546255)
			(xy 308.114223 -103.575309) (xy 308.157091 -103.610984) (xy 308.194308 -103.652521) (xy 308.225081 -103.699034)
			(xy 308.248753 -103.749531) (xy 308.264821 -103.802938) (xy 308.272941 -103.858114) (xy 308.27345 -103.886)
			(xy 308.272941 -103.913886) (xy 308.264821 -103.969062) (xy 308.248753 -104.022469) (xy 308.225081 -104.072966)
			(xy 308.194308 -104.119479) (xy 308.193218 -104.120696) (xy 310.369456 -104.120696) (xy 310.373527 -104.065074)
			(xy 310.385653 -104.010637) (xy 310.405576 -103.958546) (xy 310.432872 -103.909911) (xy 310.466958 -103.865768)
			(xy 310.507107 -103.827059) (xy 310.552465 -103.794608) (xy 310.602065 -103.769107) (xy 310.654849 -103.7511)
			(xy 310.709692 -103.74097) (xy 310.765426 -103.738933) (xy 310.820863 -103.745033) (xy 310.87482 -103.759139)
			(xy 310.926149 -103.780951) (xy 310.973755 -103.810005) (xy 311.016623 -103.84568) (xy 311.05384 -103.887217)
			(xy 311.084613 -103.93373) (xy 311.108285 -103.984227) (xy 311.124353 -104.037634) (xy 311.132473 -104.09281)
			(xy 311.132982 -104.120696) (xy 311.132473 -104.148582) (xy 311.124353 -104.203758) (xy 311.108285 -104.257165)
			(xy 311.084613 -104.307662) (xy 311.05384 -104.354175) (xy 311.016623 -104.395712) (xy 310.973755 -104.431387)
			(xy 310.926149 -104.460441) (xy 310.87482 -104.482253) (xy 310.820863 -104.496359) (xy 310.765426 -104.502459)
			(xy 310.709692 -104.500422) (xy 310.654849 -104.490292) (xy 310.602065 -104.472285) (xy 310.552465 -104.446784)
			(xy 310.507107 -104.414333) (xy 310.466958 -104.375624) (xy 310.432872 -104.331481) (xy 310.405576 -104.282846)
			(xy 310.385653 -104.230755) (xy 310.373527 -104.176318) (xy 310.369456 -104.120696) (xy 308.193218 -104.120696)
			(xy 308.157091 -104.161016) (xy 308.114223 -104.196691) (xy 308.066617 -104.225745) (xy 308.015288 -104.247557)
			(xy 307.961331 -104.261663) (xy 307.905894 -104.267763) (xy 307.85016 -104.265726) (xy 307.795317 -104.255596)
			(xy 307.742533 -104.237589) (xy 307.692933 -104.212088) (xy 307.647575 -104.179637) (xy 307.607426 -104.140928)
			(xy 307.57334 -104.096785) (xy 307.546044 -104.04815) (xy 307.526121 -103.996059) (xy 307.513995 -103.941622)
			(xy 307.509924 -103.886) (xy 306.635893 -103.886) (xy 306.669617 -103.900331) (xy 306.717223 -103.929385)
			(xy 306.760091 -103.96506) (xy 306.797308 -104.006597) (xy 306.828081 -104.05311) (xy 306.851753 -104.103607)
			(xy 306.867821 -104.157014) (xy 306.875941 -104.21219) (xy 306.87645 -104.240076) (xy 306.875941 -104.267962)
			(xy 306.867821 -104.323138) (xy 306.851753 -104.376545) (xy 306.828081 -104.427042) (xy 306.797308 -104.473555)
			(xy 306.760091 -104.515092) (xy 306.717223 -104.550767) (xy 306.669617 -104.579821) (xy 306.618288 -104.601633)
			(xy 306.564331 -104.615739) (xy 306.508894 -104.621839) (xy 306.45316 -104.619802) (xy 306.398317 -104.609672)
			(xy 306.345533 -104.591665) (xy 306.295933 -104.566164) (xy 306.250575 -104.533713) (xy 306.210426 -104.495004)
			(xy 306.17634 -104.450861) (xy 306.149044 -104.402226) (xy 306.129121 -104.350135) (xy 306.116995 -104.295698)
			(xy 306.112924 -104.240076) (xy 299.894244 -104.240076) (xy 299.893735 -104.267962) (xy 299.885615 -104.323138)
			(xy 299.869547 -104.376545) (xy 299.845875 -104.427042) (xy 299.815102 -104.473555) (xy 299.777885 -104.515092)
			(xy 299.735017 -104.550767) (xy 299.687411 -104.579821) (xy 299.636082 -104.601633) (xy 299.582125 -104.615739)
			(xy 299.526688 -104.621839) (xy 299.470954 -104.619802) (xy 299.416111 -104.609672) (xy 299.363327 -104.591665)
			(xy 299.313727 -104.566164) (xy 299.268369 -104.533713) (xy 299.22822 -104.495004) (xy 299.194134 -104.450861)
			(xy 299.166838 -104.402226) (xy 299.146915 -104.350135) (xy 299.134789 -104.295698) (xy 299.130718 -104.240076)
			(xy 287.32734 -104.240076) (xy 287.32734 -104.830372) (xy 289.797742 -104.830372) (xy 289.801813 -104.77475)
			(xy 289.813939 -104.720313) (xy 289.833862 -104.668222) (xy 289.861158 -104.619587) (xy 289.895244 -104.575444)
			(xy 289.935393 -104.536735) (xy 289.980751 -104.504284) (xy 290.030351 -104.478783) (xy 290.083135 -104.460776)
			(xy 290.137978 -104.450646) (xy 290.193712 -104.448609) (xy 290.249149 -104.454709) (xy 290.303106 -104.468815)
			(xy 290.354435 -104.490627) (xy 290.402041 -104.519681) (xy 290.444909 -104.555356) (xy 290.482126 -104.596893)
			(xy 290.512899 -104.643406) (xy 290.536571 -104.693903) (xy 290.552639 -104.74731) (xy 290.560759 -104.802486)
			(xy 290.561268 -104.830372) (xy 290.560759 -104.858258) (xy 290.552639 -104.913434) (xy 290.536571 -104.966841)
			(xy 290.512899 -105.017338) (xy 290.482126 -105.063851) (xy 290.444909 -105.105388) (xy 290.402041 -105.141063)
			(xy 290.354435 -105.170117) (xy 290.303106 -105.191929) (xy 290.249149 -105.206035) (xy 290.193712 -105.212135)
			(xy 290.137978 -105.210098) (xy 290.083135 -105.199968) (xy 290.030351 -105.181961) (xy 289.980751 -105.15646)
			(xy 289.935393 -105.124009) (xy 289.895244 -105.0853) (xy 289.861158 -105.041157) (xy 289.833862 -104.992522)
			(xy 289.813939 -104.940431) (xy 289.801813 -104.885994) (xy 289.797742 -104.830372) (xy 287.32734 -104.830372)
			(xy 287.32734 -107.210352) (xy 297.165012 -107.210352) (xy 297.169083 -107.15473) (xy 297.181209 -107.100293)
			(xy 297.201132 -107.048202) (xy 297.228428 -106.999567) (xy 297.262514 -106.955424) (xy 297.302663 -106.916715)
			(xy 297.348021 -106.884264) (xy 297.397621 -106.858763) (xy 297.450405 -106.840756) (xy 297.505248 -106.830626)
			(xy 297.560982 -106.828589) (xy 297.616419 -106.834689) (xy 297.670376 -106.848795) (xy 297.721705 -106.870607)
			(xy 297.769311 -106.899661) (xy 297.812179 -106.935336) (xy 297.849396 -106.976873) (xy 297.880169 -107.023386)
			(xy 297.903841 -107.073883) (xy 297.91724 -107.11842) (xy 299.03775 -107.11842) (xy 299.03775 -107.03152)
			(xy 299.045768 -106.944991) (xy 299.061736 -106.859571) (xy 299.085517 -106.775989) (xy 299.116909 -106.694957)
			(xy 299.155643 -106.617168) (xy 299.20139 -106.543284) (xy 299.253759 -106.473937) (xy 299.312303 -106.409717)
			(xy 299.376523 -106.351173) (xy 299.44587 -106.298804) (xy 299.519754 -106.253057) (xy 299.597543 -106.214323)
			(xy 299.678575 -106.182931) (xy 299.762157 -106.15915) (xy 299.847577 -106.143182) (xy 299.934106 -106.135164)
			(xy 300.021006 -106.135164) (xy 300.107535 -106.143182) (xy 300.192955 -106.15915) (xy 300.276537 -106.182931)
			(xy 300.357569 -106.214323) (xy 300.435358 -106.253057) (xy 300.509242 -106.298804) (xy 300.578589 -106.351173)
			(xy 300.642809 -106.409717) (xy 300.701353 -106.473937) (xy 300.753722 -106.543284) (xy 300.799469 -106.617168)
			(xy 300.838203 -106.694957) (xy 300.869595 -106.775989) (xy 300.893376 -106.859571) (xy 300.909344 -106.944991)
			(xy 300.917362 -107.03152) (xy 300.917864 -107.07497) (xy 300.917362 -107.11842) (xy 300.91736 -107.118439)
			(xy 301.290718 -107.118439) (xy 301.290718 -107.031561) (xy 301.298734 -106.945054) (xy 301.314697 -106.859655)
			(xy 301.338472 -106.776093) (xy 301.369856 -106.695082) (xy 301.40858 -106.617312) (xy 301.454315 -106.543446)
			(xy 301.50667 -106.474116) (xy 301.565199 -106.409912) (xy 301.629402 -106.351382) (xy 301.698731 -106.299025)
			(xy 301.772596 -106.253289) (xy 301.850365 -106.214563) (xy 301.931376 -106.183178) (xy 302.014937 -106.159401)
			(xy 302.100336 -106.143436) (xy 302.186843 -106.135418) (xy 302.230282 -106.134916) (xy 304.084482 -106.134916)
			(xy 304.12792 -106.135462) (xy 304.214425 -106.143476) (xy 304.299822 -106.159438) (xy 304.383382 -106.183211)
			(xy 304.464392 -106.214594) (xy 304.542161 -106.253316) (xy 304.616025 -106.29905) (xy 304.685354 -106.351403)
			(xy 304.749557 -106.409931) (xy 304.808085 -106.474132) (xy 304.86044 -106.54346) (xy 304.906175 -106.617323)
			(xy 304.944899 -106.695091) (xy 304.976283 -106.776101) (xy 305.000058 -106.85966) (xy 305.016021 -106.945057)
			(xy 305.024037 -107.031562) (xy 305.024037 -107.11842) (xy 306.40756 -107.11842) (xy 306.40756 -107.03152)
			(xy 306.415578 -106.944991) (xy 306.431546 -106.859571) (xy 306.455327 -106.775989) (xy 306.486719 -106.694957)
			(xy 306.525453 -106.617168) (xy 306.5712 -106.543284) (xy 306.623569 -106.473937) (xy 306.682113 -106.409717)
			(xy 306.746333 -106.351173) (xy 306.81568 -106.298804) (xy 306.889564 -106.253057) (xy 306.967353 -106.214323)
			(xy 307.048385 -106.182931) (xy 307.131967 -106.15915) (xy 307.217387 -106.143182) (xy 307.303916 -106.135164)
			(xy 307.390816 -106.135164) (xy 307.477345 -106.143182) (xy 307.562765 -106.15915) (xy 307.646347 -106.182931)
			(xy 307.727379 -106.214323) (xy 307.805168 -106.253057) (xy 307.879052 -106.298804) (xy 307.948399 -106.351173)
			(xy 308.012619 -106.409717) (xy 308.071163 -106.473937) (xy 308.123532 -106.543284) (xy 308.169279 -106.617168)
			(xy 308.208013 -106.694957) (xy 308.239405 -106.775989) (xy 308.263186 -106.859571) (xy 308.279154 -106.944991)
			(xy 308.287172 -107.03152) (xy 308.287674 -107.07497) (xy 308.287172 -107.11842) (xy 308.279154 -107.204949)
			(xy 308.278144 -107.210352) (xy 317.942722 -107.210352) (xy 317.943237 -107.181613) (xy 317.951865 -107.124786)
			(xy 317.968918 -107.069896) (xy 317.994011 -107.018185) (xy 318.026576 -106.970822) (xy 318.045846 -106.949494)
			(xy 318.05245 -106.942382) (xy 318.059562 -106.924856) (xy 318.059562 -106.835448) (xy 318.05245 -106.817922)
			(xy 318.045846 -106.81081) (xy 318.026527 -106.789525) (xy 317.993961 -106.742156) (xy 317.968871 -106.690438)
			(xy 317.951823 -106.63554) (xy 317.943204 -106.578707) (xy 317.94321 -106.521223) (xy 317.951839 -106.464391)
			(xy 317.968896 -106.409497) (xy 317.993996 -106.357783) (xy 318.026571 -106.31042) (xy 318.045846 -106.289094)
			(xy 318.05245 -106.281982) (xy 318.059562 -106.264456) (xy 318.059562 -106.175048) (xy 318.05245 -106.157522)
			(xy 318.045846 -106.15041) (xy 318.026554 -106.129101) (xy 317.99399 -106.081735) (xy 317.968902 -106.030018)
			(xy 317.951856 -105.975123) (xy 317.943239 -105.918292) (xy 317.942722 -105.889552) (xy 317.943208 -105.862301)
			(xy 317.950964 -105.808353) (xy 317.966319 -105.756058) (xy 317.988961 -105.706481) (xy 318.018427 -105.660631)
			(xy 318.054118 -105.61944) (xy 318.095309 -105.583749) (xy 318.141159 -105.554283) (xy 318.190736 -105.531641)
			(xy 318.243031 -105.516286) (xy 318.296979 -105.50853) (xy 318.351481 -105.50853) (xy 318.405429 -105.516286)
			(xy 318.457724 -105.531641) (xy 318.507301 -105.554283) (xy 318.553151 -105.583749) (xy 318.594342 -105.61944)
			(xy 318.630033 -105.660631) (xy 318.659499 -105.706481) (xy 318.682141 -105.756058) (xy 318.697496 -105.808353)
			(xy 318.705252 -105.862301) (xy 318.705738 -105.889552) (xy 318.705236 -105.918292) (xy 318.696606 -105.975119)
			(xy 318.679551 -106.03001) (xy 318.654455 -106.081721) (xy 318.621886 -106.129083) (xy 318.602614 -106.15041)
			(xy 318.59601 -106.157522) (xy 318.588898 -106.175048) (xy 318.588898 -106.264456) (xy 318.59601 -106.281982)
			(xy 318.602614 -106.289094) (xy 318.621836 -106.310463) (xy 318.654399 -106.357819) (xy 318.679491 -106.409524)
			(xy 318.696543 -106.464408) (xy 318.705169 -106.521229) (xy 318.705174 -106.578701) (xy 318.696558 -106.635523)
			(xy 318.679517 -106.69041) (xy 318.654434 -106.74212) (xy 318.62188 -106.789482) (xy 318.602614 -106.81081)
			(xy 318.59601 -106.817922) (xy 318.588898 -106.835448) (xy 318.588898 -106.924856) (xy 318.59601 -106.942382)
			(xy 318.602614 -106.949494) (xy 318.621901 -106.970807) (xy 318.654467 -107.018172) (xy 318.679557 -107.069887)
			(xy 318.696604 -107.124781) (xy 318.705221 -107.181612) (xy 318.705738 -107.210352) (xy 318.705252 -107.237603)
			(xy 318.697496 -107.291551) (xy 318.682141 -107.343846) (xy 318.659499 -107.393423) (xy 318.630033 -107.439273)
			(xy 318.594342 -107.480464) (xy 318.553151 -107.516155) (xy 318.507301 -107.545621) (xy 318.457724 -107.568263)
			(xy 318.405429 -107.583618) (xy 318.351481 -107.591374) (xy 318.296979 -107.591374) (xy 318.243031 -107.583618)
			(xy 318.190736 -107.568263) (xy 318.141159 -107.545621) (xy 318.095309 -107.516155) (xy 318.054118 -107.480464)
			(xy 318.018427 -107.439273) (xy 317.988961 -107.393423) (xy 317.966319 -107.343846) (xy 317.950964 -107.291551)
			(xy 317.943208 -107.237603) (xy 317.942722 -107.210352) (xy 308.278144 -107.210352) (xy 308.263186 -107.290369)
			(xy 308.239405 -107.373951) (xy 308.208013 -107.454983) (xy 308.169279 -107.532772) (xy 308.123532 -107.606656)
			(xy 308.071163 -107.676003) (xy 308.012619 -107.740223) (xy 307.948399 -107.798767) (xy 307.879052 -107.851136)
			(xy 307.805168 -107.896883) (xy 307.727379 -107.935617) (xy 307.646347 -107.967009) (xy 307.562765 -107.99079)
			(xy 307.477345 -108.006758) (xy 307.390816 -108.014776) (xy 307.303916 -108.014776) (xy 307.217387 -108.006758)
			(xy 307.131967 -107.99079) (xy 307.048385 -107.967009) (xy 306.967353 -107.935617) (xy 306.889564 -107.896883)
			(xy 306.81568 -107.851136) (xy 306.746333 -107.798767) (xy 306.682113 -107.740223) (xy 306.623569 -107.676003)
			(xy 306.5712 -107.606656) (xy 306.525453 -107.532772) (xy 306.486719 -107.454983) (xy 306.455327 -107.373951)
			(xy 306.431546 -107.290369) (xy 306.415578 -107.204949) (xy 306.40756 -107.11842) (xy 305.024037 -107.11842)
			(xy 305.024037 -107.118438) (xy 305.016021 -107.204943) (xy 305.000058 -107.29034) (xy 304.976283 -107.373899)
			(xy 304.944899 -107.454909) (xy 304.906175 -107.532677) (xy 304.86044 -107.60654) (xy 304.808085 -107.675868)
			(xy 304.749557 -107.740069) (xy 304.685354 -107.798597) (xy 304.616025 -107.85095) (xy 304.542161 -107.896684)
			(xy 304.464392 -107.935406) (xy 304.383382 -107.966789) (xy 304.299822 -107.990562) (xy 304.214425 -108.006524)
			(xy 304.12792 -108.014538) (xy 304.084482 -108.015024) (xy 302.230282 -108.015024) (xy 302.186843 -108.014582)
			(xy 302.100336 -108.006564) (xy 302.014937 -107.990599) (xy 301.931376 -107.966822) (xy 301.850365 -107.935437)
			(xy 301.772596 -107.896711) (xy 301.698731 -107.850975) (xy 301.629402 -107.798618) (xy 301.565199 -107.740088)
			(xy 301.50667 -107.675884) (xy 301.454315 -107.606554) (xy 301.40858 -107.532688) (xy 301.369856 -107.454918)
			(xy 301.338472 -107.373907) (xy 301.314697 -107.290345) (xy 301.298734 -107.204946) (xy 301.290718 -107.118439)
			(xy 300.91736 -107.118439) (xy 300.909344 -107.204949) (xy 300.893376 -107.290369) (xy 300.869595 -107.373951)
			(xy 300.838203 -107.454983) (xy 300.799469 -107.532772) (xy 300.753722 -107.606656) (xy 300.701353 -107.676003)
			(xy 300.642809 -107.740223) (xy 300.578589 -107.798767) (xy 300.509242 -107.851136) (xy 300.435358 -107.896883)
			(xy 300.357569 -107.935617) (xy 300.276537 -107.967009) (xy 300.192955 -107.99079) (xy 300.107535 -108.006758)
			(xy 300.021006 -108.014776) (xy 299.934106 -108.014776) (xy 299.847577 -108.006758) (xy 299.762157 -107.99079)
			(xy 299.678575 -107.967009) (xy 299.597543 -107.935617) (xy 299.519754 -107.896883) (xy 299.44587 -107.851136)
			(xy 299.376523 -107.798767) (xy 299.312303 -107.740223) (xy 299.253759 -107.676003) (xy 299.20139 -107.606656)
			(xy 299.155643 -107.532772) (xy 299.116909 -107.454983) (xy 299.085517 -107.373951) (xy 299.061736 -107.290369)
			(xy 299.045768 -107.204949) (xy 299.03775 -107.11842) (xy 297.91724 -107.11842) (xy 297.919909 -107.12729)
			(xy 297.928029 -107.182466) (xy 297.928538 -107.210352) (xy 297.928029 -107.238238) (xy 297.919909 -107.293414)
			(xy 297.903841 -107.346821) (xy 297.880169 -107.397318) (xy 297.849396 -107.443831) (xy 297.812179 -107.485368)
			(xy 297.769311 -107.521043) (xy 297.721705 -107.550097) (xy 297.670376 -107.571909) (xy 297.616419 -107.586015)
			(xy 297.560982 -107.592115) (xy 297.505248 -107.590078) (xy 297.450405 -107.579948) (xy 297.397621 -107.561941)
			(xy 297.348021 -107.53644) (xy 297.302663 -107.503989) (xy 297.262514 -107.46528) (xy 297.228428 -107.421137)
			(xy 297.201132 -107.372502) (xy 297.181209 -107.320411) (xy 297.169083 -107.265974) (xy 297.165012 -107.210352)
			(xy 287.32734 -107.210352) (xy 287.32734 -108.462318) (xy 296.587924 -108.462318) (xy 296.591995 -108.406696)
			(xy 296.604121 -108.352259) (xy 296.624044 -108.300168) (xy 296.65134 -108.251533) (xy 296.685426 -108.20739)
			(xy 296.725575 -108.168681) (xy 296.770933 -108.13623) (xy 296.820533 -108.110729) (xy 296.873317 -108.092722)
			(xy 296.92816 -108.082592) (xy 296.983894 -108.080555) (xy 297.039331 -108.086655) (xy 297.093288 -108.100761)
			(xy 297.144617 -108.122573) (xy 297.192223 -108.151627) (xy 297.235091 -108.187302) (xy 297.272308 -108.228839)
			(xy 297.303081 -108.275352) (xy 297.326753 -108.325849) (xy 297.342821 -108.379256) (xy 297.350941 -108.434432)
			(xy 297.35145 -108.462318) (xy 297.350941 -108.490204) (xy 297.342821 -108.54538) (xy 297.326753 -108.598787)
			(xy 297.303081 -108.649284) (xy 297.272308 -108.695797) (xy 297.235091 -108.737334) (xy 297.192223 -108.773009)
			(xy 297.144617 -108.802063) (xy 297.093288 -108.823875) (xy 297.039331 -108.837981) (xy 296.983894 -108.844081)
			(xy 296.92816 -108.842044) (xy 296.873317 -108.831914) (xy 296.820533 -108.813907) (xy 296.770933 -108.788406)
			(xy 296.725575 -108.755955) (xy 296.685426 -108.717246) (xy 296.65134 -108.673103) (xy 296.624044 -108.624468)
			(xy 296.604121 -108.572377) (xy 296.591995 -108.51794) (xy 296.587924 -108.462318) (xy 287.32734 -108.462318)
			(xy 287.32734 -109.481366) (xy 296.51909 -109.481366) (xy 296.523161 -109.425744) (xy 296.535287 -109.371307)
			(xy 296.55521 -109.319216) (xy 296.582506 -109.270581) (xy 296.616592 -109.226438) (xy 296.656741 -109.187729)
			(xy 296.702099 -109.155278) (xy 296.751699 -109.129777) (xy 296.804483 -109.11177) (xy 296.859326 -109.10164)
			(xy 296.91506 -109.099603) (xy 296.970497 -109.105703) (xy 297.024454 -109.119809) (xy 297.075783 -109.141621)
			(xy 297.123389 -109.170675) (xy 297.166257 -109.20635) (xy 297.203474 -109.247887) (xy 297.234247 -109.2944)
			(xy 297.257919 -109.344897) (xy 297.273987 -109.398304) (xy 297.282107 -109.45348) (xy 297.282616 -109.481366)
			(xy 297.282107 -109.509252) (xy 297.273987 -109.564428) (xy 297.257919 -109.617835) (xy 297.234247 -109.668332)
			(xy 297.203474 -109.714845) (xy 297.166257 -109.756382) (xy 297.123389 -109.792057) (xy 297.075783 -109.821111)
			(xy 297.024454 -109.842923) (xy 296.970497 -109.857029) (xy 296.91506 -109.863129) (xy 296.859326 -109.861092)
			(xy 296.804483 -109.850962) (xy 296.751699 -109.832955) (xy 296.702099 -109.807454) (xy 296.656741 -109.775003)
			(xy 296.616592 -109.736294) (xy 296.582506 -109.692151) (xy 296.55521 -109.643516) (xy 296.535287 -109.591425)
			(xy 296.523161 -109.536988) (xy 296.51909 -109.481366) (xy 287.32734 -109.481366) (xy 287.32734 -110.497366)
			(xy 296.272966 -110.497366) (xy 296.273452 -110.470115) (xy 296.281208 -110.416167) (xy 296.296563 -110.363872)
			(xy 296.319205 -110.314295) (xy 296.348671 -110.268445) (xy 296.384362 -110.227254) (xy 296.425553 -110.191563)
			(xy 296.471403 -110.162097) (xy 296.52098 -110.139455) (xy 296.573275 -110.1241) (xy 296.627223 -110.116344)
			(xy 296.681725 -110.116344) (xy 296.735673 -110.1241) (xy 296.787968 -110.139455) (xy 296.837545 -110.162097)
			(xy 296.883395 -110.191563) (xy 296.924586 -110.227254) (xy 296.960277 -110.268445) (xy 296.989743 -110.314295)
			(xy 297.012385 -110.363872) (xy 297.02774 -110.416167) (xy 297.035496 -110.470115) (xy 297.035982 -110.497366)
			(xy 297.035521 -110.525004) (xy 297.027558 -110.579703) (xy 297.011782 -110.632679) (xy 296.988521 -110.682822)
			(xy 296.958264 -110.729081) (xy 296.921644 -110.770487) (xy 296.900854 -110.788704) (xy 296.890583 -110.798065)
			(xy 296.875062 -110.8211) (xy 296.866324 -110.847467) (xy 296.865017 -110.875213) (xy 296.871237 -110.902284)
			(xy 296.884523 -110.926677) (xy 296.903893 -110.946585) (xy 296.927913 -110.960536) (xy 296.94124 -110.964472)
			(xy 296.968188 -110.971962) (xy 297.019723 -110.99369) (xy 297.067535 -111.022707) (xy 297.1106 -111.058392)
			(xy 297.147994 -111.099981) (xy 297.178918 -111.146583) (xy 297.202707 -111.1972) (xy 297.218854 -111.250747)
			(xy 297.227011 -111.306078) (xy 297.227498 -111.334042) (xy 297.227012 -111.361293) (xy 297.219256 -111.415241)
			(xy 297.203901 -111.467536) (xy 297.181259 -111.517113) (xy 297.151793 -111.562963) (xy 297.116102 -111.604154)
			(xy 297.074911 -111.639845) (xy 297.029061 -111.669311) (xy 296.979484 -111.691953) (xy 296.927189 -111.707308)
			(xy 296.873241 -111.715064) (xy 296.818739 -111.715064) (xy 296.764791 -111.707308) (xy 296.712496 -111.691953)
			(xy 296.662919 -111.669311) (xy 296.617069 -111.639845) (xy 296.575878 -111.604154) (xy 296.540187 -111.562963)
			(xy 296.510721 -111.517113) (xy 296.488079 -111.467536) (xy 296.472724 -111.415241) (xy 296.464968 -111.361293)
			(xy 296.464482 -111.334042) (xy 296.464962 -111.306405) (xy 296.472922 -111.251707) (xy 296.488696 -111.198732)
			(xy 296.511953 -111.148589) (xy 296.542207 -111.102329) (xy 296.578822 -111.060923) (xy 296.59961 -111.042704)
			(xy 296.609848 -111.033313) (xy 296.625356 -111.010282) (xy 296.634086 -110.983925) (xy 296.635392 -110.95619)
			(xy 296.629177 -110.929129) (xy 296.615901 -110.904743) (xy 296.596546 -110.884835) (xy 296.572544 -110.870879)
			(xy 296.559224 -110.866936) (xy 296.532272 -110.859462) (xy 296.480737 -110.837731) (xy 296.432926 -110.80871)
			(xy 296.389863 -110.773022) (xy 296.35247 -110.731431) (xy 296.321547 -110.684827) (xy 296.297758 -110.63421)
			(xy 296.281611 -110.580662) (xy 296.273453 -110.525331) (xy 296.272966 -110.497366) (xy 287.32734 -110.497366)
			(xy 287.32734 -111.784892) (xy 299.368464 -111.784892) (xy 299.36891 -111.757521) (xy 299.37673 -111.70334)
			(xy 299.392223 -111.650836) (xy 299.41507 -111.60109) (xy 299.4448 -111.555124) (xy 299.462444 -111.534194)
			(xy 299.46854 -111.527082) (xy 299.47489 -111.510064) (xy 299.47489 -111.42472) (xy 299.46854 -111.407702)
			(xy 299.462444 -111.40059) (xy 299.444795 -111.379664) (xy 299.415069 -111.333695) (xy 299.392223 -111.283948)
			(xy 299.376727 -111.231445) (xy 299.368898 -111.177265) (xy 299.368899 -111.122523) (xy 299.376729 -111.068343)
			(xy 299.392227 -111.015841) (xy 299.415075 -110.966094) (xy 299.444802 -110.920126) (xy 299.462444 -110.899194)
			(xy 299.46854 -110.892082) (xy 299.47489 -110.875064) (xy 299.47489 -110.78972) (xy 299.46854 -110.772702)
			(xy 299.462444 -110.76559) (xy 299.444795 -110.744664) (xy 299.415069 -110.698695) (xy 299.392223 -110.648948)
			(xy 299.376727 -110.596445) (xy 299.368898 -110.542265) (xy 299.368899 -110.487523) (xy 299.376729 -110.433343)
			(xy 299.392227 -110.380841) (xy 299.415075 -110.331094) (xy 299.444802 -110.285126) (xy 299.462444 -110.264194)
			(xy 299.46854 -110.257082) (xy 299.47489 -110.240064) (xy 299.47489 -110.15472) (xy 299.46854 -110.137702)
			(xy 299.462444 -110.13059) (xy 299.444795 -110.109664) (xy 299.415069 -110.063695) (xy 299.392223 -110.013948)
			(xy 299.376727 -109.961445) (xy 299.368898 -109.907265) (xy 299.368899 -109.852523) (xy 299.376729 -109.798343)
			(xy 299.392227 -109.745841) (xy 299.415075 -109.696094) (xy 299.444802 -109.650126) (xy 299.462444 -109.629194)
			(xy 299.46854 -109.622082) (xy 299.47489 -109.605064) (xy 299.47489 -109.51972) (xy 299.46854 -109.502702)
			(xy 299.462444 -109.49559) (xy 299.444794 -109.474667) (xy 299.415082 -109.428692) (xy 299.392247 -109.378943)
			(xy 299.376759 -109.32644) (xy 299.368935 -109.272262) (xy 299.368464 -109.244892) (xy 299.36895 -109.217641)
			(xy 299.376706 -109.163693) (xy 299.392061 -109.111398) (xy 299.414703 -109.061821) (xy 299.444169 -109.015971)
			(xy 299.47986 -108.97478) (xy 299.521051 -108.939089) (xy 299.566901 -108.909623) (xy 299.616478 -108.886981)
			(xy 299.668773 -108.871626) (xy 299.722721 -108.86387) (xy 299.777223 -108.86387) (xy 299.831171 -108.871626)
			(xy 299.883466 -108.886981) (xy 299.933043 -108.909623) (xy 299.978893 -108.939089) (xy 300.020084 -108.97478)
			(xy 300.055775 -109.015971) (xy 300.085241 -109.061821) (xy 300.107883 -109.111398) (xy 300.123238 -109.163693)
			(xy 300.130994 -109.217641) (xy 300.13148 -109.244892) (xy 300.131014 -109.272262) (xy 300.123197 -109.326442)
			(xy 300.107708 -109.378945) (xy 300.092053 -109.41304) (xy 304.029364 -109.41304) (xy 304.02985 -109.385789)
			(xy 304.037606 -109.331841) (xy 304.052961 -109.279546) (xy 304.075603 -109.229969) (xy 304.105069 -109.184119)
			(xy 304.14076 -109.142928) (xy 304.181951 -109.107237) (xy 304.227801 -109.077771) (xy 304.277378 -109.055129)
			(xy 304.329673 -109.039774) (xy 304.383621 -109.032018) (xy 304.438123 -109.032018) (xy 304.492071 -109.039774)
			(xy 304.544366 -109.055129) (xy 304.593943 -109.077771) (xy 304.639793 -109.107237) (xy 304.680984 -109.142928)
			(xy 304.716675 -109.184119) (xy 304.746141 -109.229969) (xy 304.768783 -109.279546) (xy 304.784138 -109.331841)
			(xy 304.791894 -109.385789) (xy 304.79238 -109.41304) (xy 304.791958 -109.439235) (xy 304.784789 -109.491133)
			(xy 304.770591 -109.541563) (xy 304.749631 -109.589579) (xy 304.722303 -109.634277) (xy 304.689119 -109.674819)
			(xy 304.670206 -109.692948) (xy 304.662332 -109.700314) (xy 304.653696 -109.719872) (xy 304.654458 -109.816392)
			(xy 304.663348 -109.83595) (xy 304.671222 -109.843062) (xy 304.690781 -109.861206) (xy 304.725109 -109.902043)
			(xy 304.75341 -109.947268) (xy 304.775131 -109.995995) (xy 304.789848 -110.047275) (xy 304.797274 -110.100105)
			(xy 304.797714 -110.12678) (xy 304.797228 -110.154031) (xy 304.789472 -110.207979) (xy 304.774117 -110.260274)
			(xy 304.751475 -110.309851) (xy 304.722009 -110.355701) (xy 304.686318 -110.396892) (xy 304.645127 -110.432583)
			(xy 304.599277 -110.462049) (xy 304.5497 -110.484691) (xy 304.497405 -110.500046) (xy 304.443457 -110.507802)
			(xy 304.388955 -110.507802) (xy 304.335007 -110.500046) (xy 304.282712 -110.484691) (xy 304.233135 -110.462049)
			(xy 304.187285 -110.432583) (xy 304.146094 -110.396892) (xy 304.110403 -110.355701) (xy 304.080937 -110.309851)
			(xy 304.058295 -110.260274) (xy 304.04294 -110.207979) (xy 304.035184 -110.154031) (xy 304.034698 -110.12678)
			(xy 304.03514 -110.100585) (xy 304.042306 -110.048689) (xy 304.0565 -109.998259) (xy 304.077457 -109.950244)
			(xy 304.104781 -109.905545) (xy 304.137961 -109.865002) (xy 304.156872 -109.846872) (xy 304.164746 -109.839506)
			(xy 304.173382 -109.819948) (xy 304.17262 -109.723428) (xy 304.16373 -109.70387) (xy 304.155856 -109.696758)
			(xy 304.136303 -109.678609) (xy 304.101975 -109.637772) (xy 304.073673 -109.592549) (xy 304.051951 -109.543822)
			(xy 304.037233 -109.492544) (xy 304.029806 -109.439715) (xy 304.029364 -109.41304) (xy 300.092053 -109.41304)
			(xy 300.084866 -109.428692) (xy 300.055141 -109.474658) (xy 300.0375 -109.49559) (xy 300.031404 -109.502702)
			(xy 300.025054 -109.51972) (xy 300.025054 -109.605064) (xy 300.031404 -109.622082) (xy 300.0375 -109.629194)
			(xy 300.055132 -109.650134) (xy 300.084855 -109.696101) (xy 300.107699 -109.745846) (xy 300.123195 -109.798347)
			(xy 300.131023 -109.852524) (xy 300.131024 -109.907264) (xy 300.123197 -109.961441) (xy 300.107703 -110.013943)
			(xy 300.084861 -110.063689) (xy 300.055139 -110.109657) (xy 300.0375 -110.13059) (xy 300.031404 -110.137702)
			(xy 300.025054 -110.15472) (xy 300.025054 -110.240064) (xy 300.031404 -110.257082) (xy 300.0375 -110.264194)
			(xy 300.055132 -110.285134) (xy 300.084855 -110.331101) (xy 300.107699 -110.380846) (xy 300.123195 -110.433347)
			(xy 300.131023 -110.487524) (xy 300.131024 -110.530132) (xy 302.62906 -110.530132) (xy 302.633131 -110.47451)
			(xy 302.645257 -110.420073) (xy 302.66518 -110.367982) (xy 302.692476 -110.319347) (xy 302.726562 -110.275204)
			(xy 302.766711 -110.236495) (xy 302.812069 -110.204044) (xy 302.861669 -110.178543) (xy 302.914453 -110.160536)
			(xy 302.969296 -110.150406) (xy 303.02503 -110.148369) (xy 303.080467 -110.154469) (xy 303.134424 -110.168575)
			(xy 303.185753 -110.190387) (xy 303.233359 -110.219441) (xy 303.276227 -110.255116) (xy 303.313444 -110.296653)
			(xy 303.344217 -110.343166) (xy 303.367889 -110.393663) (xy 303.383957 -110.44707) (xy 303.392077 -110.502246)
			(xy 303.392586 -110.530132) (xy 303.392077 -110.558018) (xy 303.383957 -110.613194) (xy 303.367889 -110.666601)
			(xy 303.344217 -110.717098) (xy 303.313444 -110.763611) (xy 303.276227 -110.805148) (xy 303.233359 -110.840823)
			(xy 303.185753 -110.869877) (xy 303.134424 -110.891689) (xy 303.080467 -110.905795) (xy 303.02503 -110.911895)
			(xy 302.969296 -110.909858) (xy 302.914453 -110.899728) (xy 302.861669 -110.881721) (xy 302.812069 -110.85622)
			(xy 302.766711 -110.823769) (xy 302.726562 -110.78506) (xy 302.692476 -110.740917) (xy 302.66518 -110.692282)
			(xy 302.645257 -110.640191) (xy 302.633131 -110.585754) (xy 302.62906 -110.530132) (xy 300.131024 -110.530132)
			(xy 300.131024 -110.542264) (xy 300.123197 -110.596441) (xy 300.107703 -110.648943) (xy 300.084861 -110.698689)
			(xy 300.055139 -110.744657) (xy 300.0375 -110.76559) (xy 300.031404 -110.772702) (xy 300.025054 -110.78972)
			(xy 300.025054 -110.875064) (xy 300.031404 -110.892082) (xy 300.0375 -110.899194) (xy 300.055132 -110.920134)
			(xy 300.084855 -110.966101) (xy 300.107699 -111.015846) (xy 300.107829 -111.016288) (xy 303.987962 -111.016288)
			(xy 303.988448 -110.989037) (xy 303.996204 -110.935089) (xy 304.011559 -110.882794) (xy 304.034201 -110.833217)
			(xy 304.063667 -110.787367) (xy 304.099358 -110.746176) (xy 304.140549 -110.710485) (xy 304.186399 -110.681019)
			(xy 304.235976 -110.658377) (xy 304.288271 -110.643022) (xy 304.342219 -110.635266) (xy 304.396721 -110.635266)
			(xy 304.450669 -110.643022) (xy 304.502964 -110.658377) (xy 304.552541 -110.681019) (xy 304.598391 -110.710485)
			(xy 304.639582 -110.746176) (xy 304.675273 -110.787367) (xy 304.704739 -110.833217) (xy 304.727381 -110.882794)
			(xy 304.742736 -110.935089) (xy 304.750492 -110.989037) (xy 304.750978 -111.016288) (xy 304.750513 -111.043308)
			(xy 304.742901 -111.09681) (xy 304.727812 -111.148701) (xy 304.705549 -111.197942) (xy 304.676557 -111.243548)
			(xy 304.641419 -111.284604) (xy 304.621438 -111.3028) (xy 304.613056 -111.310166) (xy 304.604166 -111.330486)
			(xy 304.605436 -111.430054) (xy 304.615088 -111.449866) (xy 304.623724 -111.457232) (xy 304.644852 -111.475468)
			(xy 304.682132 -111.517001) (xy 304.712958 -111.563525) (xy 304.736673 -111.614046) (xy 304.75277 -111.667483)
			(xy 304.760906 -111.722697) (xy 304.761392 -111.750602) (xy 304.76077 -111.780394) (xy 304.75152 -111.839255)
			(xy 304.733231 -111.895962) (xy 304.706346 -111.949135) (xy 304.68359 -111.980726) (xy 306.101496 -111.980726)
			(xy 306.102037 -111.951988) (xy 306.110655 -111.895161) (xy 306.127701 -111.840271) (xy 306.152789 -111.788559)
			(xy 306.185351 -111.741195) (xy 306.20462 -111.719868) (xy 306.211224 -111.712756) (xy 306.218336 -111.69523)
			(xy 306.218336 -111.605822) (xy 306.211224 -111.588296) (xy 306.20462 -111.581184) (xy 306.185375 -111.559835)
			(xy 306.152809 -111.512476) (xy 306.127717 -111.460768) (xy 306.110665 -111.405881) (xy 306.10204 -111.349056)
			(xy 306.102037 -111.291581) (xy 306.110656 -111.234756) (xy 306.127703 -111.179867) (xy 306.15279 -111.128157)
			(xy 306.185351 -111.080795) (xy 306.20462 -111.059468) (xy 306.211224 -111.052356) (xy 306.218336 -111.03483)
			(xy 306.218336 -110.945422) (xy 306.211224 -110.927896) (xy 306.20462 -110.920784) (xy 306.185375 -110.899435)
			(xy 306.152809 -110.852076) (xy 306.127717 -110.800368) (xy 306.110665 -110.745481) (xy 306.10204 -110.688656)
			(xy 306.102037 -110.631181) (xy 306.110656 -110.574356) (xy 306.127703 -110.519467) (xy 306.15279 -110.467757)
			(xy 306.185351 -110.420395) (xy 306.20462 -110.399068) (xy 306.211224 -110.391956) (xy 306.218336 -110.37443)
			(xy 306.218336 -110.285022) (xy 306.211224 -110.267496) (xy 306.20462 -110.260384) (xy 306.185375 -110.239035)
			(xy 306.152809 -110.191676) (xy 306.127717 -110.139968) (xy 306.110665 -110.085081) (xy 306.10204 -110.028256)
			(xy 306.102037 -109.970781) (xy 306.110656 -109.913956) (xy 306.127703 -109.859067) (xy 306.15279 -109.807357)
			(xy 306.185351 -109.759995) (xy 306.20462 -109.738668) (xy 306.211224 -109.731556) (xy 306.218336 -109.71403)
			(xy 306.218336 -109.624622) (xy 306.211224 -109.607096) (xy 306.20462 -109.599984) (xy 306.185359 -109.578649)
			(xy 306.152792 -109.531289) (xy 306.127698 -109.479579) (xy 306.110645 -109.42469) (xy 306.102019 -109.367864)
			(xy 306.101496 -109.339126) (xy 306.10198 -109.311874) (xy 306.109733 -109.257923) (xy 306.125086 -109.205625)
			(xy 306.147726 -109.156045) (xy 306.177191 -109.110192) (xy 306.212883 -109.068999) (xy 306.254074 -109.033305)
			(xy 306.299926 -109.003836) (xy 306.349505 -108.981194) (xy 306.401802 -108.965838) (xy 306.455752 -108.958081)
			(xy 306.483004 -108.957618) (xy 306.50932 -108.958083) (xy 306.561453 -108.9653) (xy 306.612102 -108.97961)
			(xy 306.660304 -109.000742) (xy 306.705146 -109.028296) (xy 306.745778 -109.061748) (xy 306.763928 -109.080808)
			(xy 306.771436 -109.088225) (xy 306.790727 -109.09674) (xy 306.801266 -109.097318) (xy 306.875942 -109.097318)
			(xy 306.886489 -109.096766) (xy 306.905784 -109.088246) (xy 306.91328 -109.080808) (xy 306.931426 -109.06174)
			(xy 306.972044 -109.028261) (xy 307.016882 -109.000688) (xy 307.065087 -108.979548) (xy 307.115743 -108.965241)
			(xy 307.167885 -108.95804) (xy 307.194204 -108.957618) (xy 307.221458 -108.958052) (xy 307.275411 -108.96581)
			(xy 307.327711 -108.981168) (xy 307.377293 -109.003813) (xy 307.423148 -109.033283) (xy 307.464341 -109.06898)
			(xy 307.500035 -109.110176) (xy 307.529502 -109.156033) (xy 307.552143 -109.205617) (xy 307.567496 -109.257918)
			(xy 307.57525 -109.311872) (xy 307.575712 -109.339126) (xy 307.575201 -109.367865) (xy 307.566575 -109.424693)
			(xy 307.549522 -109.479584) (xy 307.524427 -109.531295) (xy 307.49186 -109.578657) (xy 307.472588 -109.599984)
			(xy 307.465984 -109.607096) (xy 307.458872 -109.624622) (xy 307.458872 -109.71403) (xy 307.465984 -109.731556)
			(xy 307.472588 -109.738668) (xy 307.491884 -109.759973) (xy 307.524447 -109.807339) (xy 307.549537 -109.859055)
			(xy 307.566584 -109.913949) (xy 307.575204 -109.970779) (xy 307.575201 -110.028259) (xy 307.566576 -110.085088)
			(xy 307.549523 -110.139981) (xy 307.524428 -110.191694) (xy 307.49186 -110.239057) (xy 307.472588 -110.260384)
			(xy 307.465984 -110.267496) (xy 307.458872 -110.285022) (xy 307.458872 -110.37443) (xy 307.465984 -110.391956)
			(xy 307.472588 -110.399068) (xy 307.491884 -110.420373) (xy 307.524447 -110.467739) (xy 307.549537 -110.519455)
			(xy 307.566584 -110.574349) (xy 307.575204 -110.631179) (xy 307.575201 -110.688659) (xy 307.566576 -110.745488)
			(xy 307.549523 -110.800381) (xy 307.524428 -110.852094) (xy 307.49186 -110.899457) (xy 307.472588 -110.920784)
			(xy 307.465984 -110.927896) (xy 307.458872 -110.945422) (xy 307.458872 -111.03483) (xy 307.465984 -111.052356)
			(xy 307.472588 -111.059468) (xy 307.491884 -111.080773) (xy 307.524447 -111.128139) (xy 307.549537 -111.179855)
			(xy 307.566584 -111.234749) (xy 307.575204 -111.291579) (xy 307.575201 -111.349059) (xy 307.566576 -111.405888)
			(xy 307.549523 -111.460781) (xy 307.524428 -111.512494) (xy 307.49186 -111.559857) (xy 307.472588 -111.581184)
			(xy 307.465984 -111.588296) (xy 307.458872 -111.605822) (xy 307.458872 -111.69523) (xy 307.465984 -111.712756)
			(xy 307.472588 -111.719868) (xy 307.491875 -111.741181) (xy 307.524438 -111.788547) (xy 307.549527 -111.840262)
			(xy 307.566574 -111.895156) (xy 307.575193 -111.951986) (xy 307.575712 -111.980726) (xy 307.575246 -112.007978)
			(xy 307.567486 -112.061926) (xy 307.552128 -112.114221) (xy 307.529484 -112.163798) (xy 307.500016 -112.209648)
			(xy 307.464322 -112.250838) (xy 307.42313 -112.286529) (xy 307.377279 -112.315995) (xy 307.3277 -112.338636)
			(xy 307.275404 -112.353991) (xy 307.221456 -112.361748) (xy 307.194204 -112.362234) (xy 307.167887 -112.361814)
			(xy 307.115752 -112.354585) (xy 307.065104 -112.340265) (xy 307.016902 -112.319125) (xy 306.972061 -112.291564)
			(xy 306.93143 -112.258106) (xy 306.91328 -112.239044) (xy 306.905762 -112.231638) (xy 306.886479 -112.223115)
			(xy 306.875942 -112.222534) (xy 306.801266 -112.222534) (xy 306.790717 -112.223075) (xy 306.771421 -112.231601)
			(xy 306.763928 -112.239044) (xy 306.745769 -112.258099) (xy 306.705155 -112.291581) (xy 306.66032 -112.319157)
			(xy 306.612117 -112.3403) (xy 306.561463 -112.354609) (xy 306.509322 -112.361811) (xy 306.483004 -112.362234)
			(xy 306.455754 -112.361719) (xy 306.401809 -112.353963) (xy 306.349516 -112.33861) (xy 306.299941 -112.315971)
			(xy 306.254091 -112.286508) (xy 306.212902 -112.250819) (xy 306.17721 -112.209633) (xy 306.147743 -112.163786)
			(xy 306.125101 -112.114212) (xy 306.109743 -112.061921) (xy 306.101984 -112.007976) (xy 306.101496 -111.980726)
			(xy 304.68359 -111.980726) (xy 304.67152 -111.997482) (xy 304.629601 -112.039825) (xy 304.605944 -112.057942)
			(xy 304.595276 -112.065816) (xy 304.584354 -112.089692) (xy 304.592736 -112.201706) (xy 304.607214 -112.22355)
			(xy 304.618898 -112.2299) (xy 304.641711 -112.242282) (xy 304.684004 -112.272377) (xy 304.721824 -112.30793)
			(xy 304.754472 -112.348285) (xy 304.781345 -112.392695) (xy 304.801946 -112.44034) (xy 304.815894 -112.490338)
			(xy 304.822932 -112.541766) (xy 304.823368 -112.56772) (xy 304.822882 -112.594971) (xy 304.815126 -112.648919)
			(xy 304.799771 -112.701214) (xy 304.777129 -112.750791) (xy 304.747663 -112.796641) (xy 304.711972 -112.837832)
			(xy 304.670781 -112.873523) (xy 304.624931 -112.902989) (xy 304.575354 -112.925631) (xy 304.523059 -112.940986)
			(xy 304.469111 -112.948742) (xy 304.414609 -112.948742) (xy 304.360661 -112.940986) (xy 304.308366 -112.925631)
			(xy 304.258789 -112.902989) (xy 304.212939 -112.873523) (xy 304.171748 -112.837832) (xy 304.136057 -112.796641)
			(xy 304.106591 -112.750791) (xy 304.083949 -112.701214) (xy 304.068594 -112.648919) (xy 304.060838 -112.594971)
			(xy 304.060352 -112.56772) (xy 304.060899 -112.537925) (xy 304.070162 -112.479059) (xy 304.088465 -112.42235)
			(xy 304.115364 -112.369177) (xy 304.150203 -112.320833) (xy 304.192137 -112.278494) (xy 304.2158 -112.26038)
			(xy 304.226468 -112.252506) (xy 304.23739 -112.22863) (xy 304.229008 -112.116616) (xy 304.21453 -112.094772)
			(xy 304.202846 -112.088422) (xy 304.180052 -112.076006) (xy 304.137758 -112.045917) (xy 304.099936 -112.010369)
			(xy 304.067286 -111.97002) (xy 304.04041 -111.925615) (xy 304.019806 -111.877975) (xy 304.005855 -111.82798)
			(xy 303.998814 -111.776554) (xy 303.998376 -111.750602) (xy 303.998816 -111.723581) (xy 304.006431 -111.670077)
			(xy 304.021524 -111.618185) (xy 304.043791 -111.568943) (xy 304.072788 -111.523338) (xy 304.107932 -111.482284)
			(xy 304.127916 -111.46409) (xy 304.136298 -111.456724) (xy 304.145188 -111.436404) (xy 304.143918 -111.336836)
			(xy 304.134266 -111.317024) (xy 304.12563 -111.309658) (xy 304.104487 -111.291438) (xy 304.067211 -111.2499)
			(xy 304.036388 -111.203373) (xy 304.012676 -111.152849) (xy 303.996581 -111.099409) (xy 303.988448 -111.044194)
			(xy 303.987962 -111.016288) (xy 300.107829 -111.016288) (xy 300.123195 -111.068347) (xy 300.131023 -111.122524)
			(xy 300.131024 -111.177264) (xy 300.123197 -111.231441) (xy 300.107703 -111.283943) (xy 300.084861 -111.333689)
			(xy 300.055139 -111.379657) (xy 300.0375 -111.40059) (xy 300.031404 -111.407702) (xy 300.025054 -111.42472)
			(xy 300.025054 -111.510064) (xy 300.031404 -111.527082) (xy 300.0375 -111.534194) (xy 300.05515 -111.555117)
			(xy 300.08486 -111.601093) (xy 300.107694 -111.650842) (xy 300.123182 -111.703345) (xy 300.131008 -111.757522)
			(xy 300.13148 -111.784892) (xy 300.130994 -111.812143) (xy 300.123238 -111.866091) (xy 300.117919 -111.884206)
			(xy 302.56429 -111.884206) (xy 302.568361 -111.828584) (xy 302.580487 -111.774147) (xy 302.60041 -111.722056)
			(xy 302.627706 -111.673421) (xy 302.661792 -111.629278) (xy 302.701941 -111.590569) (xy 302.747299 -111.558118)
			(xy 302.796899 -111.532617) (xy 302.849683 -111.51461) (xy 302.904526 -111.50448) (xy 302.96026 -111.502443)
			(xy 303.015697 -111.508543) (xy 303.069654 -111.522649) (xy 303.120983 -111.544461) (xy 303.168589 -111.573515)
			(xy 303.211457 -111.60919) (xy 303.248674 -111.650727) (xy 303.279447 -111.69724) (xy 303.303119 -111.747737)
			(xy 303.319187 -111.801144) (xy 303.327307 -111.85632) (xy 303.327816 -111.884206) (xy 303.327307 -111.912092)
			(xy 303.319187 -111.967268) (xy 303.303119 -112.020675) (xy 303.279447 -112.071172) (xy 303.248674 -112.117685)
			(xy 303.211457 -112.159222) (xy 303.168589 -112.194897) (xy 303.120983 -112.223951) (xy 303.069654 -112.245763)
			(xy 303.015697 -112.259869) (xy 302.96026 -112.265969) (xy 302.904526 -112.263932) (xy 302.849683 -112.253802)
			(xy 302.796899 -112.235795) (xy 302.747299 -112.210294) (xy 302.701941 -112.177843) (xy 302.661792 -112.139134)
			(xy 302.627706 -112.094991) (xy 302.60041 -112.046356) (xy 302.580487 -111.994265) (xy 302.568361 -111.939828)
			(xy 302.56429 -111.884206) (xy 300.117919 -111.884206) (xy 300.107883 -111.918386) (xy 300.085241 -111.967963)
			(xy 300.055775 -112.013813) (xy 300.020084 -112.055004) (xy 299.978893 -112.090695) (xy 299.933043 -112.120161)
			(xy 299.883466 -112.142803) (xy 299.831171 -112.158158) (xy 299.777223 -112.165914) (xy 299.722721 -112.165914)
			(xy 299.668773 -112.158158) (xy 299.616478 -112.142803) (xy 299.566901 -112.120161) (xy 299.521051 -112.090695)
			(xy 299.47986 -112.055004) (xy 299.444169 -112.013813) (xy 299.414703 -111.967963) (xy 299.392061 -111.918386)
			(xy 299.376706 -111.866091) (xy 299.36895 -111.812143) (xy 299.368464 -111.784892) (xy 287.32734 -111.784892)
			(xy 287.32734 -112.302544) (xy 287.327803 -112.31242) (xy 287.335247 -112.330717) (xy 287.341818 -112.338104)
			(xy 287.342072 -112.338358) (xy 287.514538 -112.510824) (xy 296.002454 -112.510824) (xy 296.006525 -112.455202)
			(xy 296.018651 -112.400765) (xy 296.038574 -112.348674) (xy 296.06587 -112.300039) (xy 296.099956 -112.255896)
			(xy 296.140105 -112.217187) (xy 296.185463 -112.184736) (xy 296.235063 -112.159235) (xy 296.287847 -112.141228)
			(xy 296.34269 -112.131098) (xy 296.398424 -112.129061) (xy 296.453861 -112.135161) (xy 296.507818 -112.149267)
			(xy 296.559147 -112.171079) (xy 296.606753 -112.200133) (xy 296.649621 -112.235808) (xy 296.686838 -112.277345)
			(xy 296.717611 -112.323858) (xy 296.741283 -112.374355) (xy 296.757351 -112.427762) (xy 296.765471 -112.482938)
			(xy 296.765516 -112.485424) (xy 298.851064 -112.485424) (xy 298.855135 -112.429802) (xy 298.867261 -112.375365)
			(xy 298.887184 -112.323274) (xy 298.91448 -112.274639) (xy 298.948566 -112.230496) (xy 298.988715 -112.191787)
			(xy 299.034073 -112.159336) (xy 299.083673 -112.133835) (xy 299.136457 -112.115828) (xy 299.1913 -112.105698)
			(xy 299.247034 -112.103661) (xy 299.302471 -112.109761) (xy 299.356428 -112.123867) (xy 299.407757 -112.145679)
			(xy 299.455363 -112.174733) (xy 299.498231 -112.210408) (xy 299.535448 -112.251945) (xy 299.566221 -112.298458)
			(xy 299.589893 -112.348955) (xy 299.605961 -112.402362) (xy 299.614081 -112.457538) (xy 299.61459 -112.485424)
			(xy 299.614081 -112.51331) (xy 299.605961 -112.568486) (xy 299.589893 -112.621893) (xy 299.566221 -112.67239)
			(xy 299.535448 -112.718903) (xy 299.498231 -112.76044) (xy 299.455363 -112.796115) (xy 299.407757 -112.825169)
			(xy 299.356428 -112.846981) (xy 299.302471 -112.861087) (xy 299.247034 -112.867187) (xy 299.1913 -112.86515)
			(xy 299.136457 -112.85502) (xy 299.083673 -112.837013) (xy 299.034073 -112.811512) (xy 298.988715 -112.779061)
			(xy 298.948566 -112.740352) (xy 298.91448 -112.696209) (xy 298.887184 -112.647574) (xy 298.867261 -112.595483)
			(xy 298.855135 -112.541046) (xy 298.851064 -112.485424) (xy 296.765516 -112.485424) (xy 296.76598 -112.510824)
			(xy 296.765471 -112.53871) (xy 296.757351 -112.593886) (xy 296.741283 -112.647293) (xy 296.717611 -112.69779)
			(xy 296.686838 -112.744303) (xy 296.649621 -112.78584) (xy 296.606753 -112.821515) (xy 296.559147 -112.850569)
			(xy 296.507818 -112.872381) (xy 296.453861 -112.886487) (xy 296.398424 -112.892587) (xy 296.34269 -112.89055)
			(xy 296.287847 -112.88042) (xy 296.235063 -112.862413) (xy 296.185463 -112.836912) (xy 296.140105 -112.804461)
			(xy 296.099956 -112.765752) (xy 296.06587 -112.721609) (xy 296.038574 -112.672974) (xy 296.018651 -112.620883)
			(xy 296.006525 -112.566446) (xy 296.002454 -112.510824) (xy 287.514538 -112.510824) (xy 287.993328 -112.989614)
			(xy 302.639982 -112.989614) (xy 302.644053 -112.933992) (xy 302.656179 -112.879555) (xy 302.676102 -112.827464)
			(xy 302.703398 -112.778829) (xy 302.737484 -112.734686) (xy 302.777633 -112.695977) (xy 302.822991 -112.663526)
			(xy 302.872591 -112.638025) (xy 302.925375 -112.620018) (xy 302.980218 -112.609888) (xy 303.035952 -112.607851)
			(xy 303.091389 -112.613951) (xy 303.145346 -112.628057) (xy 303.196675 -112.649869) (xy 303.244281 -112.678923)
			(xy 303.287149 -112.714598) (xy 303.324366 -112.756135) (xy 303.355139 -112.802648) (xy 303.378811 -112.853145)
			(xy 303.394879 -112.906552) (xy 303.402999 -112.961728) (xy 303.403508 -112.989614) (xy 303.402999 -113.0175)
			(xy 303.394879 -113.072676) (xy 303.378811 -113.126083) (xy 303.355139 -113.17658) (xy 303.324366 -113.223093)
			(xy 303.290731 -113.260632) (xy 307.638702 -113.260632) (xy 307.642773 -113.20501) (xy 307.654899 -113.150573)
			(xy 307.674822 -113.098482) (xy 307.702118 -113.049847) (xy 307.736204 -113.005704) (xy 307.776353 -112.966995)
			(xy 307.821711 -112.934544) (xy 307.871311 -112.909043) (xy 307.924095 -112.891036) (xy 307.978938 -112.880906)
			(xy 308.034672 -112.878869) (xy 308.090109 -112.884969) (xy 308.144066 -112.899075) (xy 308.195395 -112.920887)
			(xy 308.243001 -112.949941) (xy 308.285869 -112.985616) (xy 308.323086 -113.027153) (xy 308.353859 -113.073666)
			(xy 308.377531 -113.124163) (xy 308.393599 -113.17757) (xy 308.4013 -113.229898) (xy 308.642002 -113.229898)
			(xy 308.646073 -113.174276) (xy 308.658199 -113.119839) (xy 308.678122 -113.067748) (xy 308.705418 -113.019113)
			(xy 308.739504 -112.97497) (xy 308.779653 -112.936261) (xy 308.825011 -112.90381) (xy 308.874611 -112.878309)
			(xy 308.927395 -112.860302) (xy 308.982238 -112.850172) (xy 309.037972 -112.848135) (xy 309.093409 -112.854235)
			(xy 309.147366 -112.868341) (xy 309.198695 -112.890153) (xy 309.246301 -112.919207) (xy 309.289169 -112.954882)
			(xy 309.326386 -112.996419) (xy 309.357159 -113.042932) (xy 309.380831 -113.093429) (xy 309.396899 -113.146836)
			(xy 309.405019 -113.202012) (xy 309.405528 -113.229898) (xy 309.405019 -113.257784) (xy 309.396899 -113.31296)
			(xy 309.380831 -113.366367) (xy 309.357159 -113.416864) (xy 309.326386 -113.463377) (xy 309.289169 -113.504914)
			(xy 309.246301 -113.540589) (xy 309.198695 -113.569643) (xy 309.147366 -113.591455) (xy 309.093409 -113.605561)
			(xy 309.037972 -113.611661) (xy 308.982238 -113.609624) (xy 308.927395 -113.599494) (xy 308.874611 -113.581487)
			(xy 308.825011 -113.555986) (xy 308.779653 -113.523535) (xy 308.739504 -113.484826) (xy 308.705418 -113.440683)
			(xy 308.678122 -113.392048) (xy 308.658199 -113.339957) (xy 308.646073 -113.28552) (xy 308.642002 -113.229898)
			(xy 308.4013 -113.229898) (xy 308.401719 -113.232746) (xy 308.402228 -113.260632) (xy 308.401719 -113.288518)
			(xy 308.393599 -113.343694) (xy 308.377531 -113.397101) (xy 308.353859 -113.447598) (xy 308.323086 -113.494111)
			(xy 308.285869 -113.535648) (xy 308.243001 -113.571323) (xy 308.195395 -113.600377) (xy 308.144066 -113.622189)
			(xy 308.090109 -113.636295) (xy 308.034672 -113.642395) (xy 307.978938 -113.640358) (xy 307.924095 -113.630228)
			(xy 307.871311 -113.612221) (xy 307.821711 -113.58672) (xy 307.776353 -113.554269) (xy 307.736204 -113.51556)
			(xy 307.702118 -113.471417) (xy 307.674822 -113.422782) (xy 307.654899 -113.370691) (xy 307.642773 -113.316254)
			(xy 307.638702 -113.260632) (xy 303.290731 -113.260632) (xy 303.287149 -113.26463) (xy 303.244281 -113.300305)
			(xy 303.196675 -113.329359) (xy 303.145346 -113.351171) (xy 303.091389 -113.365277) (xy 303.035952 -113.371377)
			(xy 302.980218 -113.36934) (xy 302.925375 -113.35921) (xy 302.872591 -113.341203) (xy 302.822991 -113.315702)
			(xy 302.777633 -113.283251) (xy 302.737484 -113.244542) (xy 302.703398 -113.200399) (xy 302.676102 -113.151764)
			(xy 302.656179 -113.099673) (xy 302.644053 -113.045236) (xy 302.639982 -112.989614) (xy 287.993328 -112.989614)
			(xy 288.438844 -113.43513) (xy 299.130718 -113.43513) (xy 299.134789 -113.379508) (xy 299.146915 -113.325071)
			(xy 299.166838 -113.27298) (xy 299.194134 -113.224345) (xy 299.22822 -113.180202) (xy 299.268369 -113.141493)
			(xy 299.313727 -113.109042) (xy 299.363327 -113.083541) (xy 299.416111 -113.065534) (xy 299.470954 -113.055404)
			(xy 299.526688 -113.053367) (xy 299.582125 -113.059467) (xy 299.636082 -113.073573) (xy 299.687411 -113.095385)
			(xy 299.735017 -113.124439) (xy 299.777885 -113.160114) (xy 299.815102 -113.201651) (xy 299.845875 -113.248164)
			(xy 299.869547 -113.298661) (xy 299.885615 -113.352068) (xy 299.893735 -113.407244) (xy 299.894244 -113.43513)
			(xy 299.893735 -113.463016) (xy 299.885615 -113.518192) (xy 299.869547 -113.571599) (xy 299.845875 -113.622096)
			(xy 299.819842 -113.661444) (xy 320.070224 -113.661444) (xy 320.074295 -113.605822) (xy 320.086421 -113.551385)
			(xy 320.106344 -113.499294) (xy 320.13364 -113.450659) (xy 320.167726 -113.406516) (xy 320.207875 -113.367807)
			(xy 320.253233 -113.335356) (xy 320.302833 -113.309855) (xy 320.355617 -113.291848) (xy 320.41046 -113.281718)
			(xy 320.466194 -113.279681) (xy 320.521631 -113.285781) (xy 320.575588 -113.299887) (xy 320.626917 -113.321699)
			(xy 320.674523 -113.350753) (xy 320.717391 -113.386428) (xy 320.754608 -113.427965) (xy 320.785381 -113.474478)
			(xy 320.809053 -113.524975) (xy 320.825121 -113.578382) (xy 320.833241 -113.633558) (xy 320.83375 -113.661444)
			(xy 320.833241 -113.68933) (xy 320.825121 -113.744506) (xy 320.809053 -113.797913) (xy 320.785381 -113.84841)
			(xy 320.754608 -113.894923) (xy 320.717391 -113.93646) (xy 320.674523 -113.972135) (xy 320.626917 -114.001189)
			(xy 320.575588 -114.023001) (xy 320.521631 -114.037107) (xy 320.466194 -114.043207) (xy 320.41046 -114.04117)
			(xy 320.355617 -114.03104) (xy 320.302833 -114.013033) (xy 320.253233 -113.987532) (xy 320.207875 -113.955081)
			(xy 320.167726 -113.916372) (xy 320.13364 -113.872229) (xy 320.106344 -113.823594) (xy 320.086421 -113.771503)
			(xy 320.074295 -113.717066) (xy 320.070224 -113.661444) (xy 299.819842 -113.661444) (xy 299.815102 -113.668609)
			(xy 299.777885 -113.710146) (xy 299.735017 -113.745821) (xy 299.687411 -113.774875) (xy 299.636082 -113.796687)
			(xy 299.582125 -113.810793) (xy 299.526688 -113.816893) (xy 299.470954 -113.814856) (xy 299.416111 -113.804726)
			(xy 299.363327 -113.786719) (xy 299.313727 -113.761218) (xy 299.268369 -113.728767) (xy 299.22822 -113.690058)
			(xy 299.194134 -113.645915) (xy 299.166838 -113.59728) (xy 299.146915 -113.545189) (xy 299.134789 -113.490752)
			(xy 299.130718 -113.43513) (xy 288.438844 -113.43513) (xy 289.271456 -114.267742) (xy 296.506136 -114.267742)
			(xy 296.510207 -114.21212) (xy 296.522333 -114.157683) (xy 296.542256 -114.105592) (xy 296.569552 -114.056957)
			(xy 296.603638 -114.012814) (xy 296.643787 -113.974105) (xy 296.689145 -113.941654) (xy 296.738745 -113.916153)
			(xy 296.791529 -113.898146) (xy 296.846372 -113.888016) (xy 296.902106 -113.885979) (xy 296.957543 -113.892079)
			(xy 297.0115 -113.906185) (xy 297.062829 -113.927997) (xy 297.110435 -113.957051) (xy 297.153303 -113.992726)
			(xy 297.19052 -114.034263) (xy 297.221293 -114.080776) (xy 297.244965 -114.131273) (xy 297.261033 -114.18468)
			(xy 297.269153 -114.239856) (xy 297.269662 -114.267742) (xy 297.269153 -114.295628) (xy 297.261033 -114.350804)
			(xy 297.244965 -114.404211) (xy 297.221293 -114.454708) (xy 297.19052 -114.501221) (xy 297.153303 -114.542758)
			(xy 297.110435 -114.578433) (xy 297.062829 -114.607487) (xy 297.0115 -114.629299) (xy 296.957543 -114.643405)
			(xy 296.902106 -114.649505) (xy 296.846372 -114.647468) (xy 296.791529 -114.637338) (xy 296.738745 -114.619331)
			(xy 296.689145 -114.59383) (xy 296.643787 -114.561379) (xy 296.603638 -114.52267) (xy 296.569552 -114.478527)
			(xy 296.542256 -114.429892) (xy 296.522333 -114.377801) (xy 296.510207 -114.323364) (xy 296.506136 -114.267742)
			(xy 289.271456 -114.267742) (xy 289.774376 -114.770662) (xy 289.774884 -114.77117) (xy 289.782267 -114.777746)
			(xy 289.800566 -114.785182) (xy 289.810444 -114.785648) (xy 298.409614 -114.785648) (xy 298.421028 -114.78501)
			(xy 298.441593 -114.775101) (xy 298.449238 -114.766598) (xy 298.498768 -114.704876) (xy 298.505391 -114.695608)
			(xy 298.510515 -114.673447) (xy 298.508674 -114.662204) (xy 298.504741 -114.642882) (xy 298.500415 -114.603687)
			(xy 298.500038 -114.583972) (xy 298.500038 -114.578892) (xy 298.500696 -114.551759) (xy 298.508745 -114.498086)
			(xy 298.524319 -114.446096) (xy 298.547104 -114.396837) (xy 298.576639 -114.351304) (xy 298.612329 -114.310417)
			(xy 298.653453 -114.275) (xy 298.699182 -114.245768) (xy 298.748591 -114.223312) (xy 298.800684 -114.208084)
			(xy 298.854409 -114.200393) (xy 298.908683 -114.200393) (xy 298.962408 -114.208084) (xy 299.014501 -114.223312)
			(xy 299.06391 -114.245768) (xy 299.109639 -114.275) (xy 299.150763 -114.310417) (xy 299.186453 -114.351304)
			(xy 299.215988 -114.396837) (xy 299.238773 -114.446096) (xy 299.254347 -114.498086) (xy 299.262396 -114.551759)
			(xy 299.263054 -114.578892) (xy 299.263054 -114.581686) (xy 299.262773 -114.601974) (xy 299.258449 -114.642319)
			(xy 299.254418 -114.662204) (xy 299.252585 -114.673441) (xy 299.257739 -114.695586) (xy 299.264324 -114.704876)
			(xy 299.313854 -114.766598) (xy 299.321536 -114.775152) (xy 299.342251 -114.785055) (xy 299.353732 -114.785648)
			(xy 299.386244 -114.785648) (xy 299.396907 -114.785198) (xy 299.416385 -114.776523) (xy 299.423836 -114.768884)
			(xy 299.481748 -114.704876) (xy 299.488352 -114.684556) (xy 299.487336 -114.673634) (xy 299.485304 -114.635026)
			(xy 299.48579 -114.607775) (xy 299.493546 -114.553827) (xy 299.508901 -114.501532) (xy 299.531543 -114.451955)
			(xy 299.561009 -114.406105) (xy 299.5967 -114.364914) (xy 299.637891 -114.329223) (xy 299.683741 -114.299757)
			(xy 299.733318 -114.277115) (xy 299.785613 -114.26176) (xy 299.839561 -114.254004) (xy 299.894063 -114.254004)
			(xy 299.948011 -114.26176) (xy 300.000306 -114.277115) (xy 300.028725 -114.290094) (xy 302.560226 -114.290094)
			(xy 302.564297 -114.234472) (xy 302.576423 -114.180035) (xy 302.596346 -114.127944) (xy 302.623642 -114.079309)
			(xy 302.657728 -114.035166) (xy 302.697877 -113.996457) (xy 302.743235 -113.964006) (xy 302.792835 -113.938505)
			(xy 302.845619 -113.920498) (xy 302.900462 -113.910368) (xy 302.956196 -113.908331) (xy 303.011633 -113.914431)
			(xy 303.06559 -113.928537) (xy 303.116919 -113.950349) (xy 303.164525 -113.979403) (xy 303.207393 -114.015078)
			(xy 303.24461 -114.056615) (xy 303.275383 -114.103128) (xy 303.299055 -114.153625) (xy 303.315123 -114.207032)
			(xy 303.323243 -114.262208) (xy 303.323752 -114.290094) (xy 303.323243 -114.31798) (xy 303.315123 -114.373156)
			(xy 303.299055 -114.426563) (xy 303.275383 -114.47706) (xy 303.24461 -114.523573) (xy 303.207393 -114.56511)
			(xy 303.164525 -114.600785) (xy 303.116919 -114.629839) (xy 303.06559 -114.651651) (xy 303.011633 -114.665757)
			(xy 302.956196 -114.671857) (xy 302.900462 -114.66982) (xy 302.845619 -114.65969) (xy 302.792835 -114.641683)
			(xy 302.743235 -114.616182) (xy 302.697877 -114.583731) (xy 302.657728 -114.545022) (xy 302.623642 -114.500879)
			(xy 302.596346 -114.452244) (xy 302.576423 -114.400153) (xy 302.564297 -114.345716) (xy 302.560226 -114.290094)
			(xy 300.028725 -114.290094) (xy 300.049883 -114.299757) (xy 300.095733 -114.329223) (xy 300.136924 -114.364914)
			(xy 300.172615 -114.406105) (xy 300.202081 -114.451955) (xy 300.224723 -114.501532) (xy 300.240078 -114.553827)
			(xy 300.247834 -114.607775) (xy 300.24832 -114.635026) (xy 300.246288 -114.673634) (xy 300.245272 -114.684556)
			(xy 300.251876 -114.704876) (xy 300.309788 -114.768884) (xy 300.317333 -114.776392) (xy 300.336752 -114.785052)
			(xy 300.34738 -114.785648) (xy 300.820582 -114.785648) (xy 300.830644 -114.786088) (xy 300.849223 -114.793828)
			(xy 300.85665 -114.800634) (xy 300.868588 -114.812572) (xy 304.0507 -114.812572) (xy 304.051186 -114.785321)
			(xy 304.058942 -114.731373) (xy 304.074297 -114.679078) (xy 304.096939 -114.629501) (xy 304.126405 -114.583651)
			(xy 304.162096 -114.54246) (xy 304.203287 -114.506769) (xy 304.249137 -114.477303) (xy 304.298714 -114.454661)
			(xy 304.351009 -114.439306) (xy 304.404957 -114.43155) (xy 304.459459 -114.43155) (xy 304.513407 -114.439306)
			(xy 304.565702 -114.454661) (xy 304.615279 -114.477303) (xy 304.661129 -114.506769) (xy 304.70232 -114.54246)
			(xy 304.738011 -114.583651) (xy 304.767477 -114.629501) (xy 304.790119 -114.679078) (xy 304.805474 -114.731373)
			(xy 304.81323 -114.785321) (xy 304.813716 -114.812572) (xy 304.813149 -114.842263) (xy 304.80394 -114.900927)
			(xy 304.785755 -114.957456) (xy 304.759033 -115.010487) (xy 304.72442 -115.058738) (xy 304.703988 -115.080288)
			(xy 304.696622 -115.087908) (xy 304.689256 -115.10645) (xy 304.691288 -115.20043) (xy 304.699416 -115.218718)
			(xy 304.707036 -115.22583) (xy 304.725837 -115.243945) (xy 304.758817 -115.284418) (xy 304.785972 -115.329008)
			(xy 304.806796 -115.376884) (xy 304.813516 -115.400836) (xy 319.460624 -115.400836) (xy 319.464695 -115.345214)
			(xy 319.476821 -115.290777) (xy 319.496744 -115.238686) (xy 319.52404 -115.190051) (xy 319.558126 -115.145908)
			(xy 319.598275 -115.107199) (xy 319.643633 -115.074748) (xy 319.693233 -115.049247) (xy 319.746017 -115.03124)
			(xy 319.80086 -115.02111) (xy 319.856594 -115.019073) (xy 319.912031 -115.025173) (xy 319.965988 -115.039279)
			(xy 320.017317 -115.061091) (xy 320.064923 -115.090145) (xy 320.107791 -115.12582) (xy 320.145008 -115.167357)
			(xy 320.175781 -115.21387) (xy 320.199453 -115.264367) (xy 320.215521 -115.317774) (xy 320.223259 -115.370356)
			(xy 321.561204 -115.370356) (xy 321.565275 -115.314734) (xy 321.577401 -115.260297) (xy 321.597324 -115.208206)
			(xy 321.62462 -115.159571) (xy 321.658706 -115.115428) (xy 321.698855 -115.076719) (xy 321.744213 -115.044268)
			(xy 321.793813 -115.018767) (xy 321.846597 -115.00076) (xy 321.90144 -114.99063) (xy 321.957174 -114.988593)
			(xy 322.012611 -114.994693) (xy 322.066568 -115.008799) (xy 322.117897 -115.030611) (xy 322.165503 -115.059665)
			(xy 322.208371 -115.09534) (xy 322.245588 -115.136877) (xy 322.276361 -115.18339) (xy 322.300033 -115.233887)
			(xy 322.316101 -115.287294) (xy 322.324221 -115.34247) (xy 322.32473 -115.370356) (xy 322.324221 -115.398242)
			(xy 322.316101 -115.453418) (xy 322.300033 -115.506825) (xy 322.276361 -115.557322) (xy 322.245588 -115.603835)
			(xy 322.208371 -115.645372) (xy 322.165503 -115.681047) (xy 322.117897 -115.710101) (xy 322.066568 -115.731913)
			(xy 322.012611 -115.746019) (xy 321.957174 -115.752119) (xy 321.90144 -115.750082) (xy 321.846597 -115.739952)
			(xy 321.793813 -115.721945) (xy 321.744213 -115.696444) (xy 321.698855 -115.663993) (xy 321.658706 -115.625284)
			(xy 321.62462 -115.581141) (xy 321.597324 -115.532506) (xy 321.577401 -115.480415) (xy 321.565275 -115.425978)
			(xy 321.561204 -115.370356) (xy 320.223259 -115.370356) (xy 320.223641 -115.37295) (xy 320.22415 -115.400836)
			(xy 320.223641 -115.428722) (xy 320.215521 -115.483898) (xy 320.199453 -115.537305) (xy 320.175781 -115.587802)
			(xy 320.145008 -115.634315) (xy 320.107791 -115.675852) (xy 320.064923 -115.711527) (xy 320.017317 -115.740581)
			(xy 319.965988 -115.762393) (xy 319.912031 -115.776499) (xy 319.856594 -115.782599) (xy 319.80086 -115.780562)
			(xy 319.746017 -115.770432) (xy 319.693233 -115.752425) (xy 319.643633 -115.726924) (xy 319.598275 -115.694473)
			(xy 319.558126 -115.655764) (xy 319.52404 -115.611621) (xy 319.496744 -115.562986) (xy 319.476821 -115.510895)
			(xy 319.464695 -115.456458) (xy 319.460624 -115.400836) (xy 304.813516 -115.400836) (xy 304.8209 -115.427151)
			(xy 304.82802 -115.478872) (xy 304.828448 -115.504976) (xy 304.827962 -115.532227) (xy 304.820206 -115.586175)
			(xy 304.804851 -115.63847) (xy 304.782209 -115.688047) (xy 304.752743 -115.733897) (xy 304.717052 -115.775088)
			(xy 304.675861 -115.810779) (xy 304.630011 -115.840245) (xy 304.580434 -115.862887) (xy 304.528139 -115.878242)
			(xy 304.474191 -115.885998) (xy 304.419689 -115.885998) (xy 304.365741 -115.878242) (xy 304.313446 -115.862887)
			(xy 304.263869 -115.840245) (xy 304.218019 -115.810779) (xy 304.176828 -115.775088) (xy 304.141137 -115.733897)
			(xy 304.111671 -115.688047) (xy 304.089029 -115.63847) (xy 304.073674 -115.586175) (xy 304.065918 -115.532227)
			(xy 304.065432 -115.504976) (xy 304.066015 -115.475285) (xy 304.075218 -115.416622) (xy 304.093399 -115.360092)
			(xy 304.120117 -115.307061) (xy 304.154728 -115.25881) (xy 304.17516 -115.23726) (xy 304.182526 -115.22964)
			(xy 304.189892 -115.211098) (xy 304.18786 -115.117118) (xy 304.179732 -115.09883) (xy 304.172112 -115.091718)
			(xy 304.153325 -115.07359) (xy 304.120345 -115.033119) (xy 304.093189 -114.988531) (xy 304.072363 -114.940658)
			(xy 304.058256 -114.890393) (xy 304.051131 -114.838675) (xy 304.0507 -114.812572) (xy 300.868588 -114.812572)
			(xy 302.560566 -116.50455) (xy 303.505366 -116.50455) (xy 303.505366 -116.45005) (xy 303.513121 -116.396104)
			(xy 303.528475 -116.34381) (xy 303.551114 -116.294234) (xy 303.580578 -116.248384) (xy 303.616266 -116.207193)
			(xy 303.657453 -116.171501) (xy 303.703301 -116.142032) (xy 303.752875 -116.119388) (xy 303.805166 -116.10403)
			(xy 303.859112 -116.096268) (xy 303.886362 -116.09578) (xy 303.914433 -116.096279) (xy 303.969966 -116.104524)
			(xy 304.023693 -116.120811) (xy 304.074456 -116.14479) (xy 304.121161 -116.175945) (xy 304.1628 -116.213602)
			(xy 304.198476 -116.256951) (xy 304.22742 -116.305056) (xy 304.249008 -116.356882) (xy 304.262774 -116.411309)
			(xy 304.266092 -116.439188) (xy 304.268 -116.453142) (xy 304.278339 -116.479322) (xy 304.295435 -116.501684)
			(xy 304.317989 -116.518525) (xy 304.344285 -116.528566) (xy 304.372324 -116.531043) (xy 304.386234 -116.52885)
			(xy 304.404096 -116.525644) (xy 304.440224 -116.522209) (xy 304.45837 -116.521992) (xy 304.485624 -116.522453)
			(xy 304.539578 -116.530207) (xy 304.59188 -116.54556) (xy 304.641464 -116.568201) (xy 304.687321 -116.597668)
			(xy 304.728517 -116.633362) (xy 304.764214 -116.674555) (xy 304.793685 -116.72041) (xy 304.816329 -116.769992)
			(xy 304.831687 -116.822292) (xy 304.839445 -116.876246) (xy 304.839445 -116.930754) (xy 304.831687 -116.984708)
			(xy 304.816329 -117.037008) (xy 304.793685 -117.08659) (xy 304.764214 -117.132445) (xy 304.728517 -117.173638)
			(xy 304.687321 -117.209332) (xy 304.641464 -117.238799) (xy 304.59188 -117.26144) (xy 304.539578 -117.276793)
			(xy 304.485624 -117.284547) (xy 304.45837 -117.285008) (xy 304.430297 -117.284582) (xy 304.37476 -117.276328)
			(xy 304.321031 -117.260031) (xy 304.270267 -117.236042) (xy 304.223562 -117.20488) (xy 304.181924 -117.167214)
			(xy 304.146249 -117.123858) (xy 304.117306 -117.075746) (xy 304.095721 -117.023915) (xy 304.081957 -116.969481)
			(xy 304.07864 -116.9416) (xy 304.076819 -116.92763) (xy 304.066468 -116.901439) (xy 304.049356 -116.879072)
			(xy 304.026783 -116.862231) (xy 304.000468 -116.852197) (xy 303.972413 -116.849735) (xy 303.958498 -116.851938)
			(xy 303.940636 -116.855139) (xy 303.904508 -116.858578) (xy 303.886362 -116.858796) (xy 303.859112 -116.858332)
			(xy 303.805166 -116.85057) (xy 303.752875 -116.835212) (xy 303.703301 -116.812568) (xy 303.657453 -116.783099)
			(xy 303.616266 -116.747407) (xy 303.580578 -116.706216) (xy 303.551114 -116.660366) (xy 303.528475 -116.61079)
			(xy 303.513121 -116.558496) (xy 303.505366 -116.50455) (xy 302.560566 -116.50455) (xy 303.131474 -117.075458)
			(xy 303.138314 -117.082859) (xy 303.146031 -117.101457) (xy 303.14646 -117.111526) (xy 303.14646 -118.234968)
			(xy 304.084988 -118.234968) (xy 304.089059 -118.179346) (xy 304.101185 -118.124909) (xy 304.121108 -118.072818)
			(xy 304.148404 -118.024183) (xy 304.18249 -117.98004) (xy 304.222639 -117.941331) (xy 304.267997 -117.90888)
			(xy 304.317597 -117.883379) (xy 304.370381 -117.865372) (xy 304.425224 -117.855242) (xy 304.480958 -117.853205)
			(xy 304.536395 -117.859305) (xy 304.590352 -117.873411) (xy 304.641681 -117.895223) (xy 304.689287 -117.924277)
			(xy 304.732155 -117.959952) (xy 304.769372 -118.001489) (xy 304.800145 -118.048002) (xy 304.823817 -118.098499)
			(xy 304.839885 -118.151906) (xy 304.848005 -118.207082) (xy 304.848514 -118.234968) (xy 304.848016 -118.262255)
			(xy 306.067123 -118.262255) (xy 306.067123 -118.207745) (xy 306.074881 -118.153789) (xy 306.090238 -118.101486)
			(xy 306.112883 -118.051901) (xy 306.142354 -118.006044) (xy 306.178052 -117.964847) (xy 306.219249 -117.929151)
			(xy 306.265106 -117.89968) (xy 306.314691 -117.877036) (xy 306.366994 -117.861679) (xy 306.420951 -117.853923)
			(xy 306.448206 -117.85346) (xy 306.473199 -117.853857) (xy 306.522761 -117.860354) (xy 306.547012 -117.866414)
			(xy 306.558696 -117.869716) (xy 306.582064 -117.86489) (xy 306.665122 -117.80012) (xy 306.675282 -117.778784)
			(xy 306.675028 -117.766592) (xy 306.675028 -117.758718) (xy 306.675028 -116.895118) (xy 306.676044 -116.862098)
			(xy 306.676347 -116.853531) (xy 306.671982 -116.836969) (xy 306.662394 -116.822775) (xy 306.655724 -116.817394)
			(xy 306.630578 -116.798852) (xy 306.623562 -116.794059) (xy 306.607345 -116.789011) (xy 306.590369 -116.789529)
			(xy 306.582318 -116.792248) (xy 306.549969 -116.803644) (xy 306.482496 -116.815911) (xy 306.448206 -116.816632)
			(xy 306.420955 -116.816121) (xy 306.367006 -116.808365) (xy 306.314711 -116.793011) (xy 306.265133 -116.77037)
			(xy 306.219282 -116.740904) (xy 306.178092 -116.705213) (xy 306.1424 -116.664022) (xy 306.112933 -116.618172)
			(xy 306.090291 -116.568594) (xy 306.074936 -116.516299) (xy 306.067179 -116.462351) (xy 306.067179 -116.407849)
			(xy 306.074936 -116.353901) (xy 306.090291 -116.301606) (xy 306.112933 -116.252028) (xy 306.1424 -116.206178)
			(xy 306.178092 -116.164987) (xy 306.219282 -116.129296) (xy 306.265133 -116.09983) (xy 306.314711 -116.077189)
			(xy 306.367006 -116.061835) (xy 306.420955 -116.054079) (xy 306.448206 -116.053616) (xy 306.475785 -116.054118)
			(xy 306.530365 -116.062075) (xy 306.583231 -116.077808) (xy 306.633281 -116.100988) (xy 306.679472 -116.131134)
			(xy 306.720842 -116.167615) (xy 306.756527 -116.209673) (xy 306.785785 -116.256431) (xy 306.808006 -116.306915)
			(xy 306.822727 -116.360072) (xy 306.826666 -116.387372) (xy 306.82819 -116.39931) (xy 306.83972 -116.416836)
			(xy 319.460624 -116.416836) (xy 319.464695 -116.361214) (xy 319.476821 -116.306777) (xy 319.496744 -116.254686)
			(xy 319.52404 -116.206051) (xy 319.558126 -116.161908) (xy 319.598275 -116.123199) (xy 319.643633 -116.090748)
			(xy 319.693233 -116.065247) (xy 319.746017 -116.04724) (xy 319.80086 -116.03711) (xy 319.856594 -116.035073)
			(xy 319.912031 -116.041173) (xy 319.965988 -116.055279) (xy 320.017317 -116.077091) (xy 320.064923 -116.106145)
			(xy 320.107791 -116.14182) (xy 320.145008 -116.183357) (xy 320.175781 -116.22987) (xy 320.199453 -116.280367)
			(xy 320.215521 -116.333774) (xy 320.223641 -116.38895) (xy 320.22415 -116.416836) (xy 320.223641 -116.444722)
			(xy 320.215521 -116.499898) (xy 320.199453 -116.553305) (xy 320.175781 -116.603802) (xy 320.145008 -116.650315)
			(xy 320.127532 -116.66982) (xy 321.573142 -116.66982) (xy 321.577213 -116.614198) (xy 321.589339 -116.559761)
			(xy 321.609262 -116.50767) (xy 321.636558 -116.459035) (xy 321.670644 -116.414892) (xy 321.710793 -116.376183)
			(xy 321.756151 -116.343732) (xy 321.805751 -116.318231) (xy 321.858535 -116.300224) (xy 321.913378 -116.290094)
			(xy 321.969112 -116.288057) (xy 322.024549 -116.294157) (xy 322.078506 -116.308263) (xy 322.129835 -116.330075)
			(xy 322.177441 -116.359129) (xy 322.220309 -116.394804) (xy 322.23436 -116.410486) (xy 327.34707 -116.410486)
			(xy 327.351141 -116.354864) (xy 327.363267 -116.300427) (xy 327.38319 -116.248336) (xy 327.410486 -116.199701)
			(xy 327.444572 -116.155558) (xy 327.484721 -116.116849) (xy 327.530079 -116.084398) (xy 327.579679 -116.058897)
			(xy 327.632463 -116.04089) (xy 327.687306 -116.03076) (xy 327.74304 -116.028723) (xy 327.798477 -116.034823)
			(xy 327.852434 -116.048929) (xy 327.903763 -116.070741) (xy 327.951369 -116.099795) (xy 327.994237 -116.13547)
			(xy 328.031454 -116.177007) (xy 328.062227 -116.22352) (xy 328.085899 -116.274017) (xy 328.101967 -116.327424)
			(xy 328.110087 -116.3826) (xy 328.110596 -116.410486) (xy 328.110087 -116.438372) (xy 328.101967 -116.493548)
			(xy 328.085899 -116.546955) (xy 328.062227 -116.597452) (xy 328.031454 -116.643965) (xy 327.994237 -116.685502)
			(xy 327.951369 -116.721177) (xy 327.903763 -116.750231) (xy 327.852434 -116.772043) (xy 327.798477 -116.786149)
			(xy 327.74304 -116.792249) (xy 327.687306 -116.790212) (xy 327.632463 -116.780082) (xy 327.579679 -116.762075)
			(xy 327.530079 -116.736574) (xy 327.484721 -116.704123) (xy 327.444572 -116.665414) (xy 327.410486 -116.621271)
			(xy 327.38319 -116.572636) (xy 327.363267 -116.520545) (xy 327.351141 -116.466108) (xy 327.34707 -116.410486)
			(xy 322.23436 -116.410486) (xy 322.257526 -116.436341) (xy 322.288299 -116.482854) (xy 322.311971 -116.533351)
			(xy 322.328039 -116.586758) (xy 322.336159 -116.641934) (xy 322.336668 -116.66982) (xy 322.336159 -116.697706)
			(xy 322.328039 -116.752882) (xy 322.311971 -116.806289) (xy 322.288299 -116.856786) (xy 322.257526 -116.903299)
			(xy 322.220309 -116.944836) (xy 322.177441 -116.980511) (xy 322.129835 -117.009565) (xy 322.078506 -117.031377)
			(xy 322.024549 -117.045483) (xy 321.969112 -117.051583) (xy 321.913378 -117.049546) (xy 321.858535 -117.039416)
			(xy 321.805751 -117.021409) (xy 321.756151 -116.995908) (xy 321.710793 -116.963457) (xy 321.670644 -116.924748)
			(xy 321.636558 -116.880605) (xy 321.609262 -116.83197) (xy 321.589339 -116.779879) (xy 321.577213 -116.725442)
			(xy 321.573142 -116.66982) (xy 320.127532 -116.66982) (xy 320.107791 -116.691852) (xy 320.064923 -116.727527)
			(xy 320.017317 -116.756581) (xy 319.965988 -116.778393) (xy 319.912031 -116.792499) (xy 319.856594 -116.798599)
			(xy 319.80086 -116.796562) (xy 319.746017 -116.786432) (xy 319.693233 -116.768425) (xy 319.643633 -116.742924)
			(xy 319.598275 -116.710473) (xy 319.558126 -116.671764) (xy 319.52404 -116.627621) (xy 319.496744 -116.578986)
			(xy 319.476821 -116.526895) (xy 319.464695 -116.472458) (xy 319.460624 -116.416836) (xy 306.83972 -116.416836)
			(xy 306.84089 -116.418614) (xy 306.930552 -116.4717) (xy 306.953666 -116.473478) (xy 306.964842 -116.46916)
			(xy 306.991661 -116.459031) (xy 307.047194 -116.444796) (xy 307.104072 -116.437612) (xy 307.132736 -116.437156)
			(xy 307.162715 -116.437628) (xy 307.222159 -116.445461) (xy 307.280072 -116.460987) (xy 307.335461 -116.483942)
			(xy 307.38738 -116.513932) (xy 307.434939 -116.550444) (xy 307.477324 -116.592852) (xy 307.513809 -116.640431)
			(xy 307.54377 -116.692367) (xy 307.566694 -116.747769) (xy 307.582189 -116.80569) (xy 307.589989 -116.865139)
			(xy 307.590444 -116.895118) (xy 307.590444 -117.102636) (xy 325.17918 -117.102636) (xy 325.183251 -117.047014)
			(xy 325.195377 -116.992577) (xy 325.2153 -116.940486) (xy 325.242596 -116.891851) (xy 325.276682 -116.847708)
			(xy 325.316831 -116.808999) (xy 325.362189 -116.776548) (xy 325.411789 -116.751047) (xy 325.464573 -116.73304)
			(xy 325.519416 -116.72291) (xy 325.57515 -116.720873) (xy 325.630587 -116.726973) (xy 325.684544 -116.741079)
			(xy 325.735873 -116.762891) (xy 325.783479 -116.791945) (xy 325.826347 -116.82762) (xy 325.863564 -116.869157)
			(xy 325.894337 -116.91567) (xy 325.918009 -116.966167) (xy 325.934077 -117.019574) (xy 325.942197 -117.07475)
			(xy 325.942706 -117.102636) (xy 325.942197 -117.130522) (xy 325.934077 -117.185698) (xy 325.918009 -117.239105)
			(xy 325.894337 -117.289602) (xy 325.863564 -117.336115) (xy 325.826347 -117.377652) (xy 325.783479 -117.413327)
			(xy 325.761918 -117.426486) (xy 327.34707 -117.426486) (xy 327.351141 -117.370864) (xy 327.363267 -117.316427)
			(xy 327.38319 -117.264336) (xy 327.410486 -117.215701) (xy 327.444572 -117.171558) (xy 327.484721 -117.132849)
			(xy 327.530079 -117.100398) (xy 327.579679 -117.074897) (xy 327.632463 -117.05689) (xy 327.687306 -117.04676)
			(xy 327.74304 -117.044723) (xy 327.798477 -117.050823) (xy 327.852434 -117.064929) (xy 327.903763 -117.086741)
			(xy 327.951369 -117.115795) (xy 327.994237 -117.15147) (xy 328.031454 -117.193007) (xy 328.062227 -117.23952)
			(xy 328.085899 -117.290017) (xy 328.101967 -117.343424) (xy 328.110087 -117.3986) (xy 328.110596 -117.426486)
			(xy 328.110087 -117.454372) (xy 328.101967 -117.509548) (xy 328.085899 -117.562955) (xy 328.062227 -117.613452)
			(xy 328.031454 -117.659965) (xy 327.994237 -117.701502) (xy 327.951369 -117.737177) (xy 327.903763 -117.766231)
			(xy 327.852434 -117.788043) (xy 327.798477 -117.802149) (xy 327.74304 -117.808249) (xy 327.687306 -117.806212)
			(xy 327.632463 -117.796082) (xy 327.579679 -117.778075) (xy 327.530079 -117.752574) (xy 327.484721 -117.720123)
			(xy 327.444572 -117.681414) (xy 327.410486 -117.637271) (xy 327.38319 -117.588636) (xy 327.363267 -117.536545)
			(xy 327.351141 -117.482108) (xy 327.34707 -117.426486) (xy 325.761918 -117.426486) (xy 325.735873 -117.442381)
			(xy 325.684544 -117.464193) (xy 325.630587 -117.478299) (xy 325.57515 -117.484399) (xy 325.519416 -117.482362)
			(xy 325.464573 -117.472232) (xy 325.411789 -117.454225) (xy 325.362189 -117.428724) (xy 325.316831 -117.396273)
			(xy 325.276682 -117.357564) (xy 325.242596 -117.313421) (xy 325.2153 -117.264786) (xy 325.195377 -117.212695)
			(xy 325.183251 -117.158258) (xy 325.17918 -117.102636) (xy 307.590444 -117.102636) (xy 307.590444 -117.758718)
			(xy 307.589989 -117.788693) (xy 307.582165 -117.84813) (xy 307.566652 -117.906038) (xy 307.543715 -117.961426)
			(xy 307.513748 -118.013349) (xy 307.477262 -118.060917) (xy 307.434881 -118.103318) (xy 307.38733 -118.139827)
			(xy 307.335422 -118.169819) (xy 307.280044 -118.192782) (xy 307.222144 -118.208322) (xy 307.162711 -118.216175)
			(xy 307.132736 -118.21668) (xy 307.1043 -118.216245) (xy 307.047869 -118.209161) (xy 306.992749 -118.195148)
			(xy 306.966112 -118.185184) (xy 306.954936 -118.180866) (xy 306.931314 -118.182898) (xy 306.841652 -118.23827)
			(xy 306.829206 -118.258336) (xy 306.82819 -118.270274) (xy 306.824998 -118.298308) (xy 306.811543 -118.353099)
			(xy 306.790169 -118.405312) (xy 306.761341 -118.45381) (xy 306.725688 -118.497536) (xy 306.693654 -118.526728)
			(xy 312.69791 -118.526728) (xy 312.69791 -118.469472) (xy 312.706059 -118.412798) (xy 312.722189 -118.35786)
			(xy 312.745974 -118.305777) (xy 312.776928 -118.257609) (xy 312.814422 -118.214337) (xy 312.857693 -118.17684)
			(xy 312.90586 -118.145883) (xy 312.957941 -118.122096) (xy 313.012878 -118.105963) (xy 313.069552 -118.097812)
			(xy 313.09818 -118.0973) (xy 313.125549 -118.097793) (xy 313.179779 -118.105235) (xy 313.232494 -118.119983)
			(xy 313.282712 -118.141764) (xy 313.329502 -118.170172) (xy 313.371993 -118.20468) (xy 313.409396 -118.244646)
			(xy 313.425586 -118.266718) (xy 313.43115 -118.273977) (xy 313.446258 -118.284261) (xy 313.45505 -118.286784)
			(xy 313.484768 -118.29415) (xy 313.493839 -118.296007) (xy 313.512208 -118.293785) (xy 313.520582 -118.289832)
			(xy 313.5487 -118.27577) (xy 313.607904 -118.254624) (xy 313.669444 -118.241775) (xy 313.732164 -118.237465)
			(xy 313.794884 -118.241775) (xy 313.856424 -118.254624) (xy 313.915628 -118.27577) (xy 313.943746 -118.289832)
			(xy 313.952134 -118.293743) (xy 313.970488 -118.295971) (xy 313.97956 -118.29415) (xy 314.009278 -118.286784)
			(xy 314.018052 -118.28422) (xy 314.033156 -118.273952) (xy 314.038742 -118.266718) (xy 314.054892 -118.244615)
			(xy 314.092301 -118.204646) (xy 314.134798 -118.170137) (xy 314.181594 -118.141728) (xy 314.231819 -118.119948)
			(xy 314.28454 -118.105201) (xy 314.338776 -118.097762) (xy 314.366148 -118.0973) (xy 314.394777 -118.09779)
			(xy 314.451451 -118.105945) (xy 314.506387 -118.122081) (xy 314.558469 -118.145872) (xy 314.606634 -118.176831)
			(xy 314.649904 -118.21433) (xy 314.687398 -118.257604) (xy 314.718352 -118.305774) (xy 314.742135 -118.357858)
			(xy 314.758266 -118.412796) (xy 314.766414 -118.469471) (xy 314.766414 -118.526729) (xy 314.758266 -118.583404)
			(xy 314.742135 -118.638342) (xy 314.718352 -118.690426) (xy 314.687398 -118.738596) (xy 314.649904 -118.78187)
			(xy 314.606634 -118.819369) (xy 314.558469 -118.850328) (xy 314.506387 -118.874119) (xy 314.451451 -118.890255)
			(xy 314.422978 -118.894352) (xy 325.616062 -118.894352) (xy 325.616515 -118.868036) (xy 325.623737 -118.815903)
			(xy 325.638051 -118.765255) (xy 325.659185 -118.717053) (xy 325.68674 -118.672211) (xy 325.720193 -118.631579)
			(xy 325.739252 -118.613428) (xy 325.746636 -118.605891) (xy 325.755172 -118.586623) (xy 325.755762 -118.57609)
			(xy 325.755762 -118.501414) (xy 325.75525 -118.490862) (xy 325.746704 -118.471566) (xy 325.739252 -118.464076)
			(xy 325.720171 -118.445943) (xy 325.686691 -118.405323) (xy 325.659119 -118.360483) (xy 325.637981 -118.312275)
			(xy 325.623677 -118.261617) (xy 325.616481 -118.209472) (xy 325.616062 -118.183152) (xy 325.616548 -118.155901)
			(xy 325.624304 -118.101953) (xy 325.639659 -118.049658) (xy 325.662301 -118.000081) (xy 325.691767 -117.954231)
			(xy 325.727458 -117.91304) (xy 325.768649 -117.877349) (xy 325.814499 -117.847883) (xy 325.864076 -117.825241)
			(xy 325.916371 -117.809886) (xy 325.970319 -117.80213) (xy 326.024821 -117.80213) (xy 326.078769 -117.809886)
			(xy 326.131064 -117.825241) (xy 326.180641 -117.847883) (xy 326.226491 -117.877349) (xy 326.267682 -117.91304)
			(xy 326.303373 -117.954231) (xy 326.332839 -118.000081) (xy 326.355481 -118.049658) (xy 326.370836 -118.101953)
			(xy 326.378592 -118.155901) (xy 326.379078 -118.183152) (xy 326.378646 -118.209469) (xy 326.371423 -118.261604)
			(xy 326.357106 -118.312253) (xy 326.335968 -118.360455) (xy 326.308408 -118.405296) (xy 326.27495 -118.445927)
			(xy 326.255888 -118.464076) (xy 326.252145 -118.467886) (xy 329.682346 -118.467886) (xy 329.686417 -118.412264)
			(xy 329.698543 -118.357827) (xy 329.718466 -118.305736) (xy 329.745762 -118.257101) (xy 329.779848 -118.212958)
			(xy 329.819997 -118.174249) (xy 329.865355 -118.141798) (xy 329.914955 -118.116297) (xy 329.967739 -118.09829)
			(xy 330.022582 -118.08816) (xy 330.078316 -118.086123) (xy 330.133753 -118.092223) (xy 330.18771 -118.106329)
			(xy 330.239039 -118.128141) (xy 330.286645 -118.157195) (xy 330.329513 -118.19287) (xy 330.36673 -118.234407)
			(xy 330.397503 -118.28092) (xy 330.421175 -118.331417) (xy 330.437243 -118.384824) (xy 330.445363 -118.44)
			(xy 330.445872 -118.467886) (xy 331.852522 -118.467886) (xy 331.856593 -118.412264) (xy 331.868719 -118.357827)
			(xy 331.888642 -118.305736) (xy 331.915938 -118.257101) (xy 331.950024 -118.212958) (xy 331.990173 -118.174249)
			(xy 332.035531 -118.141798) (xy 332.085131 -118.116297) (xy 332.137915 -118.09829) (xy 332.192758 -118.08816)
			(xy 332.248492 -118.086123) (xy 332.303929 -118.092223) (xy 332.357886 -118.106329) (xy 332.409215 -118.128141)
			(xy 332.456821 -118.157195) (xy 332.499689 -118.19287) (xy 332.536906 -118.234407) (xy 332.567679 -118.28092)
			(xy 332.591351 -118.331417) (xy 332.607419 -118.384824) (xy 332.615539 -118.44) (xy 332.616048 -118.467886)
			(xy 332.615539 -118.495772) (xy 332.607419 -118.550948) (xy 332.591351 -118.604355) (xy 332.567679 -118.654852)
			(xy 332.536906 -118.701365) (xy 332.499689 -118.742902) (xy 332.456821 -118.778577) (xy 332.409215 -118.807631)
			(xy 332.357886 -118.829443) (xy 332.303929 -118.843549) (xy 332.248492 -118.849649) (xy 332.192758 -118.847612)
			(xy 332.137915 -118.837482) (xy 332.085131 -118.819475) (xy 332.035531 -118.793974) (xy 331.990173 -118.761523)
			(xy 331.950024 -118.722814) (xy 331.915938 -118.678671) (xy 331.888642 -118.630036) (xy 331.868719 -118.577945)
			(xy 331.856593 -118.523508) (xy 331.852522 -118.467886) (xy 330.445872 -118.467886) (xy 330.445363 -118.495772)
			(xy 330.437243 -118.550948) (xy 330.421175 -118.604355) (xy 330.397503 -118.654852) (xy 330.36673 -118.701365)
			(xy 330.329513 -118.742902) (xy 330.286645 -118.778577) (xy 330.239039 -118.807631) (xy 330.18771 -118.829443)
			(xy 330.133753 -118.843549) (xy 330.078316 -118.849649) (xy 330.022582 -118.847612) (xy 329.967739 -118.837482)
			(xy 329.914955 -118.819475) (xy 329.865355 -118.793974) (xy 329.819997 -118.761523) (xy 329.779848 -118.722814)
			(xy 329.745762 -118.678671) (xy 329.718466 -118.630036) (xy 329.698543 -118.577945) (xy 329.686417 -118.523508)
			(xy 329.682346 -118.467886) (xy 326.252145 -118.467886) (xy 326.248493 -118.471603) (xy 326.239965 -118.490879)
			(xy 326.239378 -118.501414) (xy 326.239378 -118.57609) (xy 326.239905 -118.58664) (xy 326.248442 -118.605935)
			(xy 326.255888 -118.613428) (xy 326.274979 -118.631551) (xy 326.308456 -118.672174) (xy 326.336025 -118.717017)
			(xy 326.357162 -118.765227) (xy 326.371464 -118.815886) (xy 326.378659 -118.868032) (xy 326.379078 -118.894352)
			(xy 326.378592 -118.921603) (xy 326.370836 -118.975551) (xy 326.355481 -119.027846) (xy 326.332839 -119.077423)
			(xy 326.303373 -119.123273) (xy 326.267682 -119.164464) (xy 326.226491 -119.200155) (xy 326.180641 -119.229621)
			(xy 326.131064 -119.252263) (xy 326.078769 -119.267618) (xy 326.024821 -119.275374) (xy 325.970319 -119.275374)
			(xy 325.916371 -119.267618) (xy 325.864076 -119.252263) (xy 325.814499 -119.229621) (xy 325.768649 -119.200155)
			(xy 325.727458 -119.164464) (xy 325.691767 -119.123273) (xy 325.662301 -119.077423) (xy 325.639659 -119.027846)
			(xy 325.624304 -118.975551) (xy 325.616548 -118.921603) (xy 325.616062 -118.894352) (xy 314.422978 -118.894352)
			(xy 314.394777 -118.89841) (xy 314.366148 -118.898924) (xy 314.351234 -118.898815) (xy 314.321485 -118.896654)
			(xy 314.306712 -118.894606) (xy 314.29579 -118.893082) (xy 314.274454 -118.899178) (xy 314.207652 -118.956582)
			(xy 314.199632 -118.964156) (xy 314.190414 -118.984172) (xy 314.189872 -118.99519) (xy 314.189872 -119.259858)
			(xy 314.190442 -119.270873) (xy 314.19964 -119.290889) (xy 314.207652 -119.298466) (xy 314.274454 -119.35587)
			(xy 314.29579 -119.361966) (xy 314.306712 -119.360442) (xy 314.321485 -119.358397) (xy 314.351234 -119.356234)
			(xy 314.366148 -119.356124) (xy 314.394778 -119.356566) (xy 314.451456 -119.364721) (xy 314.506396 -119.380859)
			(xy 314.55848 -119.40465) (xy 314.563003 -119.407557) (xy 326.699509 -119.407557) (xy 326.699509 -119.353043)
			(xy 326.707268 -119.299083) (xy 326.722627 -119.246777) (xy 326.745274 -119.197189) (xy 326.774748 -119.151329)
			(xy 326.810449 -119.11013) (xy 326.85165 -119.074432) (xy 326.897512 -119.044962) (xy 326.947101 -119.022318)
			(xy 326.999408 -119.006962) (xy 327.053369 -118.999207) (xy 327.080626 -118.998746) (xy 327.107997 -118.999186)
			(xy 327.162178 -119.007008) (xy 327.214682 -119.022503) (xy 327.264428 -119.045351) (xy 327.310394 -119.075082)
			(xy 327.331324 -119.092726) (xy 327.338436 -119.098822) (xy 327.355454 -119.105172) (xy 327.440798 -119.105172)
			(xy 327.457816 -119.098822) (xy 327.464928 -119.092726) (xy 327.48588 -119.075111) (xy 327.531847 -119.045395)
			(xy 327.581589 -119.022554) (xy 327.634086 -119.007057) (xy 327.688258 -118.999223) (xy 327.715626 -118.998746)
			(xy 327.742873 -118.999326) (xy 327.796811 -119.007085) (xy 327.849096 -119.02244) (xy 327.898664 -119.04508)
			(xy 327.944506 -119.074543) (xy 327.985688 -119.11023) (xy 328.021372 -119.151415) (xy 328.050833 -119.197259)
			(xy 328.073469 -119.246828) (xy 328.088821 -119.299114) (xy 328.096576 -119.353053) (xy 328.096576 -119.407547)
			(xy 328.088821 -119.461486) (xy 328.073469 -119.513772) (xy 328.050833 -119.563341) (xy 328.021372 -119.609185)
			(xy 327.985688 -119.65037) (xy 327.944506 -119.686057) (xy 327.898664 -119.71552) (xy 327.849096 -119.73816)
			(xy 327.796811 -119.753515) (xy 327.742873 -119.761274) (xy 327.715626 -119.761762) (xy 327.688256 -119.76129)
			(xy 327.634077 -119.753475) (xy 327.581573 -119.737988) (xy 327.531826 -119.715147) (xy 327.48586 -119.685423)
			(xy 327.464928 -119.667782) (xy 327.457816 -119.661686) (xy 327.440798 -119.655336) (xy 327.355454 -119.655336)
			(xy 327.338436 -119.661686) (xy 327.331324 -119.667782) (xy 327.310391 -119.685421) (xy 327.264419 -119.715133)
			(xy 327.214672 -119.737969) (xy 327.162171 -119.753461) (xy 327.107995 -119.761288) (xy 327.080626 -119.761762)
			(xy 327.053369 -119.761393) (xy 326.999408 -119.753638) (xy 326.947101 -119.738282) (xy 326.897512 -119.715638)
			(xy 326.85165 -119.686168) (xy 326.810449 -119.65047) (xy 326.774748 -119.609271) (xy 326.745274 -119.563411)
			(xy 326.722627 -119.513823) (xy 326.707268 -119.461517) (xy 326.699509 -119.407557) (xy 314.563003 -119.407557)
			(xy 314.606649 -119.435612) (xy 314.649921 -119.473113) (xy 314.687417 -119.51639) (xy 314.718373 -119.564562)
			(xy 314.742158 -119.616649) (xy 314.758289 -119.671591) (xy 314.766438 -119.728269) (xy 314.766438 -119.785531)
			(xy 314.758289 -119.842209) (xy 314.742158 -119.897151) (xy 314.718373 -119.949238) (xy 314.687417 -119.99741)
			(xy 314.649921 -120.040687) (xy 314.606649 -120.078188) (xy 314.55848 -120.10915) (xy 314.506396 -120.132941)
			(xy 314.451456 -120.149079) (xy 314.394778 -120.157234) (xy 314.366148 -120.157748) (xy 314.338778 -120.157256)
			(xy 314.284547 -120.149817) (xy 314.231832 -120.13507) (xy 314.181613 -120.11329) (xy 314.134823 -120.084881)
			(xy 314.092332 -120.050372) (xy 314.054931 -120.010403) (xy 314.038742 -119.98833) (xy 314.033158 -119.981088)
			(xy 314.018065 -119.970793) (xy 314.009278 -119.968264) (xy 313.97956 -119.960898) (xy 313.970486 -119.959061)
			(xy 313.952121 -119.961271) (xy 313.943746 -119.965216) (xy 313.915628 -119.979278) (xy 313.856424 -120.000424)
			(xy 313.794884 -120.013273) (xy 313.732164 -120.017583) (xy 313.669444 -120.013273) (xy 313.607904 -120.000424)
			(xy 313.5487 -119.979278) (xy 313.520582 -119.965216) (xy 313.512209 -119.961268) (xy 313.493842 -119.959065)
			(xy 313.484768 -119.960898) (xy 313.45505 -119.968264) (xy 313.446261 -119.970785) (xy 313.431164 -119.981083)
			(xy 313.425586 -119.98833) (xy 313.409403 -120.010409) (xy 313.372001 -120.050381) (xy 313.329511 -120.084893)
			(xy 313.28272 -120.113306) (xy 313.2325 -120.13509) (xy 313.179784 -120.149841) (xy 313.125551 -120.157284)
			(xy 313.09818 -120.157748) (xy 313.069553 -120.157164) (xy 313.012883 -120.149014) (xy 312.95795 -120.132881)
			(xy 312.905871 -120.109096) (xy 312.857708 -120.078141) (xy 312.814439 -120.040646) (xy 312.776947 -119.997376)
			(xy 312.745995 -119.949211) (xy 312.722212 -119.897132) (xy 312.706082 -119.842197) (xy 312.697934 -119.785527)
			(xy 312.697934 -119.728273) (xy 312.706082 -119.671603) (xy 312.722212 -119.616668) (xy 312.745995 -119.564589)
			(xy 312.776947 -119.516424) (xy 312.814439 -119.473154) (xy 312.857708 -119.435659) (xy 312.905871 -119.404704)
			(xy 312.95795 -119.380919) (xy 313.012883 -119.364786) (xy 313.069553 -119.356636) (xy 313.09818 -119.356124)
			(xy 313.113094 -119.356229) (xy 313.142843 -119.358393) (xy 313.157616 -119.360442) (xy 313.168538 -119.361966)
			(xy 313.189874 -119.35587) (xy 313.256676 -119.298466) (xy 313.264724 -119.290917) (xy 313.273926 -119.270882)
			(xy 313.274456 -119.259858) (xy 313.274456 -118.99519) (xy 313.273938 -118.984168) (xy 313.264706 -118.964151)
			(xy 313.256676 -118.956582) (xy 313.189874 -118.899178) (xy 313.168538 -118.893082) (xy 313.157616 -118.894606)
			(xy 313.142844 -118.896659) (xy 313.113094 -118.898817) (xy 313.09818 -118.898924) (xy 313.069552 -118.898388)
			(xy 313.012878 -118.890237) (xy 312.957941 -118.874104) (xy 312.90586 -118.850317) (xy 312.857693 -118.81936)
			(xy 312.814422 -118.781863) (xy 312.776928 -118.738591) (xy 312.745974 -118.690423) (xy 312.722189 -118.63834)
			(xy 312.706059 -118.583402) (xy 312.69791 -118.526728) (xy 306.693654 -118.526728) (xy 306.683987 -118.535537)
			(xy 306.637146 -118.566985) (xy 306.586186 -118.591195) (xy 306.532217 -118.60764) (xy 306.476415 -118.615961)
			(xy 306.448206 -118.616476) (xy 306.420951 -118.616077) (xy 306.366994 -118.608321) (xy 306.314691 -118.592964)
			(xy 306.265106 -118.57032) (xy 306.219249 -118.540849) (xy 306.178052 -118.505153) (xy 306.142354 -118.463956)
			(xy 306.112883 -118.418099) (xy 306.090238 -118.368514) (xy 306.074881 -118.316211) (xy 306.067123 -118.262255)
			(xy 304.848016 -118.262255) (xy 304.848005 -118.262854) (xy 304.839885 -118.31803) (xy 304.823817 -118.371437)
			(xy 304.800145 -118.421934) (xy 304.769372 -118.468447) (xy 304.732155 -118.509984) (xy 304.689287 -118.545659)
			(xy 304.641681 -118.574713) (xy 304.590352 -118.596525) (xy 304.536395 -118.610631) (xy 304.480958 -118.616731)
			(xy 304.425224 -118.614694) (xy 304.370381 -118.604564) (xy 304.317597 -118.586557) (xy 304.267997 -118.561056)
			(xy 304.222639 -118.528605) (xy 304.18249 -118.489896) (xy 304.148404 -118.445753) (xy 304.121108 -118.397118)
			(xy 304.101185 -118.345027) (xy 304.089059 -118.29059) (xy 304.084988 -118.234968) (xy 303.14646 -118.234968)
			(xy 303.14646 -119.441724) (xy 303.509673 -119.441724) (xy 303.509677 -119.38722) (xy 303.517438 -119.333272)
			(xy 303.532798 -119.280977) (xy 303.555443 -119.231401) (xy 303.584914 -119.185552) (xy 303.620609 -119.144364)
			(xy 303.661803 -119.108675) (xy 303.707657 -119.079212) (xy 303.757237 -119.056575) (xy 303.809535 -119.041224)
			(xy 303.863484 -119.033473) (xy 303.917988 -119.033478) (xy 303.971936 -119.04124) (xy 304.02423 -119.0566)
			(xy 304.073806 -119.079247) (xy 304.119654 -119.108718) (xy 304.160842 -119.144415) (xy 304.19653 -119.18561)
			(xy 304.225992 -119.231464) (xy 304.248628 -119.281045) (xy 304.263977 -119.333342) (xy 304.271728 -119.387292)
			(xy 304.272188 -119.414544) (xy 304.271616 -119.445113) (xy 304.261917 -119.505476) (xy 304.252884 -119.534686)
			(xy 304.249028 -119.547705) (xy 304.247649 -119.574814) (xy 304.253462 -119.601328) (xy 304.266056 -119.625373)
			(xy 304.284541 -119.645251) (xy 304.30761 -119.659554) (xy 304.333634 -119.667274) (xy 304.360771 -119.667863)
			(xy 304.374042 -119.664988) (xy 304.39691 -119.659639) (xy 304.443523 -119.653904) (xy 304.467006 -119.653558)
			(xy 304.494259 -119.654062) (xy 304.54821 -119.66182) (xy 304.600507 -119.677177) (xy 304.650087 -119.69982)
			(xy 304.695939 -119.72929) (xy 304.737131 -119.764984) (xy 304.772823 -119.806178) (xy 304.80229 -119.852032)
			(xy 304.824931 -119.901613) (xy 304.840285 -119.953911) (xy 304.84804 -120.007862) (xy 304.848039 -120.035066)
			(xy 306.066188 -120.035066) (xy 306.070259 -119.979444) (xy 306.082385 -119.925007) (xy 306.102308 -119.872916)
			(xy 306.129604 -119.824281) (xy 306.16369 -119.780138) (xy 306.203839 -119.741429) (xy 306.249197 -119.708978)
			(xy 306.298797 -119.683477) (xy 306.351581 -119.66547) (xy 306.406424 -119.65534) (xy 306.462158 -119.653303)
			(xy 306.517595 -119.659403) (xy 306.571552 -119.673509) (xy 306.622881 -119.695321) (xy 306.670487 -119.724375)
			(xy 306.713355 -119.76005) (xy 306.750572 -119.801587) (xy 306.781345 -119.8481) (xy 306.805017 -119.898597)
			(xy 306.821085 -119.952004) (xy 306.829205 -120.00718) (xy 306.829714 -120.035066) (xy 306.829205 -120.062952)
			(xy 306.821085 -120.118128) (xy 306.805017 -120.171535) (xy 306.781345 -120.222032) (xy 306.750572 -120.268545)
			(xy 306.713355 -120.310082) (xy 306.685537 -120.333232) (xy 315.339959 -120.333232) (xy 315.339959 -120.275968)
			(xy 315.348108 -120.219286) (xy 315.364241 -120.16434) (xy 315.388029 -120.11225) (xy 315.418989 -120.064075)
			(xy 315.456489 -120.020797) (xy 315.499766 -119.983296) (xy 315.54794 -119.952335) (xy 315.600029 -119.928545)
			(xy 315.654974 -119.912411) (xy 315.711656 -119.904259) (xy 315.740288 -119.903748) (xy 315.767658 -119.904215)
			(xy 315.82189 -119.911659) (xy 315.874606 -119.92641) (xy 315.924825 -119.948194) (xy 315.971615 -119.976607)
			(xy 316.014105 -120.01112) (xy 316.051506 -120.051091) (xy 316.067694 -120.073166) (xy 316.073266 -120.080418)
			(xy 316.088368 -120.090708) (xy 316.097158 -120.093232) (xy 316.126876 -120.100598) (xy 316.135947 -120.102455)
			(xy 316.154316 -120.100232) (xy 316.16269 -120.09628) (xy 316.190808 -120.082218) (xy 316.250012 -120.061072)
			(xy 316.311552 -120.048223) (xy 316.374272 -120.043913) (xy 316.436992 -120.048223) (xy 316.498532 -120.061072)
			(xy 316.557736 -120.082218) (xy 316.585854 -120.09628) (xy 316.594239 -120.100196) (xy 316.612595 -120.10242)
			(xy 316.621668 -120.100598) (xy 316.651386 -120.093232) (xy 316.660167 -120.090687) (xy 316.675269 -120.080407)
			(xy 316.68085 -120.073166) (xy 316.697071 -120.051116) (xy 316.734466 -120.011144) (xy 316.776951 -119.976629)
			(xy 316.823734 -119.948213) (xy 316.873948 -119.926424) (xy 316.926659 -119.911667) (xy 316.980887 -119.904216)
			(xy 317.008256 -119.903748) (xy 317.036887 -119.904311) (xy 317.093567 -119.912455) (xy 317.148511 -119.928583)
			(xy 317.164769 -119.936006) (xy 324.894446 -119.936006) (xy 324.898517 -119.880384) (xy 324.910643 -119.825947)
			(xy 324.930566 -119.773856) (xy 324.957862 -119.725221) (xy 324.991948 -119.681078) (xy 325.032097 -119.642369)
			(xy 325.077455 -119.609918) (xy 325.127055 -119.584417) (xy 325.179839 -119.56641) (xy 325.234682 -119.55628)
			(xy 325.290416 -119.554243) (xy 325.345853 -119.560343) (xy 325.39981 -119.574449) (xy 325.451139 -119.596261)
			(xy 325.498745 -119.625315) (xy 325.541613 -119.66099) (xy 325.57883 -119.702527) (xy 325.609603 -119.74904)
			(xy 325.633275 -119.799537) (xy 325.649343 -119.852944) (xy 325.65525 -119.89308) (xy 329.76896 -119.89308)
			(xy 329.773031 -119.837458) (xy 329.785157 -119.783021) (xy 329.80508 -119.73093) (xy 329.832376 -119.682295)
			(xy 329.866462 -119.638152) (xy 329.906611 -119.599443) (xy 329.951969 -119.566992) (xy 330.001569 -119.541491)
			(xy 330.054353 -119.523484) (xy 330.109196 -119.513354) (xy 330.16493 -119.511317) (xy 330.220367 -119.517417)
			(xy 330.274324 -119.531523) (xy 330.325653 -119.553335) (xy 330.373259 -119.582389) (xy 330.416127 -119.618064)
			(xy 330.453344 -119.659601) (xy 330.484117 -119.706114) (xy 330.507789 -119.756611) (xy 330.523857 -119.810018)
			(xy 330.531977 -119.865194) (xy 330.532486 -119.89308) (xy 330.531977 -119.920966) (xy 330.523857 -119.976142)
			(xy 330.507789 -120.029549) (xy 330.484117 -120.080046) (xy 330.453344 -120.126559) (xy 330.416127 -120.168096)
			(xy 330.373259 -120.203771) (xy 330.325653 -120.232825) (xy 330.274324 -120.254637) (xy 330.220367 -120.268743)
			(xy 330.16493 -120.274843) (xy 330.109196 -120.272806) (xy 330.054353 -120.262676) (xy 330.001569 -120.244669)
			(xy 329.951969 -120.219168) (xy 329.906611 -120.186717) (xy 329.866462 -120.148008) (xy 329.832376 -120.103865)
			(xy 329.80508 -120.05523) (xy 329.785157 -120.003139) (xy 329.773031 -119.948702) (xy 329.76896 -119.89308)
			(xy 325.65525 -119.89308) (xy 325.657463 -119.90812) (xy 325.657972 -119.936006) (xy 325.657463 -119.963892)
			(xy 325.649343 -120.019068) (xy 325.633275 -120.072475) (xy 325.609603 -120.122972) (xy 325.57883 -120.169485)
			(xy 325.541613 -120.211022) (xy 325.498745 -120.246697) (xy 325.451139 -120.275751) (xy 325.39981 -120.297563)
			(xy 325.345853 -120.311669) (xy 325.290416 -120.317769) (xy 325.234682 -120.315732) (xy 325.179839 -120.305602)
			(xy 325.127055 -120.287595) (xy 325.077455 -120.262094) (xy 325.032097 -120.229643) (xy 324.991948 -120.190934)
			(xy 324.957862 -120.146791) (xy 324.930566 -120.098156) (xy 324.910643 -120.046065) (xy 324.898517 -119.991628)
			(xy 324.894446 -119.936006) (xy 317.164769 -119.936006) (xy 317.2006 -119.952366) (xy 317.248774 -119.983321)
			(xy 317.292052 -120.020817) (xy 317.329553 -120.064091) (xy 317.360513 -120.112261) (xy 317.384302 -120.164348)
			(xy 317.400436 -120.21929) (xy 317.408585 -120.275969) (xy 317.408585 -120.333231) (xy 317.400436 -120.38991)
			(xy 317.384302 -120.444852) (xy 317.360513 -120.496939) (xy 317.329553 -120.545109) (xy 317.292052 -120.588383)
			(xy 317.248774 -120.625879) (xy 317.2006 -120.656834) (xy 317.148511 -120.680617) (xy 317.093567 -120.696745)
			(xy 317.036887 -120.704889) (xy 317.008256 -120.705372) (xy 316.993342 -120.705263) (xy 316.963593 -120.703102)
			(xy 316.94882 -120.701054) (xy 316.937898 -120.69953) (xy 316.916562 -120.705626) (xy 316.84976 -120.76303)
			(xy 316.841719 -120.770586) (xy 316.832512 -120.790615) (xy 316.83198 -120.801638) (xy 316.83198 -121.066306)
			(xy 316.832521 -121.077324) (xy 316.841739 -121.097341) (xy 316.84976 -121.104914) (xy 316.916562 -121.162318)
			(xy 316.937898 -121.168414) (xy 316.94882 -121.16689) (xy 316.963593 -121.164844) (xy 316.993342 -121.162682)
			(xy 317.008256 -121.162572) (xy 317.036889 -121.163088) (xy 317.093572 -121.171232) (xy 317.148519 -121.18736)
			(xy 317.200612 -121.211145) (xy 317.243606 -121.238772) (xy 329.7842 -121.238772) (xy 329.788271 -121.18315)
			(xy 329.800397 -121.128713) (xy 329.82032 -121.076622) (xy 329.847616 -121.027987) (xy 329.881702 -120.983844)
			(xy 329.921851 -120.945135) (xy 329.967209 -120.912684) (xy 330.016809 -120.887183) (xy 330.069593 -120.869176)
			(xy 330.124436 -120.859046) (xy 330.18017 -120.857009) (xy 330.235607 -120.863109) (xy 330.289564 -120.877215)
			(xy 330.340893 -120.899027) (xy 330.388499 -120.928081) (xy 330.431367 -120.963756) (xy 330.468584 -121.005293)
			(xy 330.499357 -121.051806) (xy 330.523029 -121.102303) (xy 330.539097 -121.15571) (xy 330.547217 -121.210886)
			(xy 330.547726 -121.238772) (xy 330.547217 -121.266658) (xy 330.539097 -121.321834) (xy 330.523029 -121.375241)
			(xy 330.499357 -121.425738) (xy 330.468584 -121.472251) (xy 330.435632 -121.509028) (xy 331.829408 -121.509028)
			(xy 331.833479 -121.453406) (xy 331.845605 -121.398969) (xy 331.865528 -121.346878) (xy 331.892824 -121.298243)
			(xy 331.92691 -121.2541) (xy 331.967059 -121.215391) (xy 332.012417 -121.18294) (xy 332.062017 -121.157439)
			(xy 332.114801 -121.139432) (xy 332.169644 -121.129302) (xy 332.225378 -121.127265) (xy 332.280815 -121.133365)
			(xy 332.334772 -121.147471) (xy 332.386101 -121.169283) (xy 332.433707 -121.198337) (xy 332.476575 -121.234012)
			(xy 332.513792 -121.275549) (xy 332.544565 -121.322062) (xy 332.568237 -121.372559) (xy 332.584305 -121.425966)
			(xy 332.592425 -121.481142) (xy 332.592934 -121.509028) (xy 332.592425 -121.536914) (xy 332.584305 -121.59209)
			(xy 332.568237 -121.645497) (xy 332.544565 -121.695994) (xy 332.513792 -121.742507) (xy 332.476575 -121.784044)
			(xy 332.433707 -121.819719) (xy 332.386101 -121.848773) (xy 332.334772 -121.870585) (xy 332.280815 -121.884691)
			(xy 332.225378 -121.890791) (xy 332.169644 -121.888754) (xy 332.114801 -121.878624) (xy 332.062017 -121.860617)
			(xy 332.012417 -121.835116) (xy 331.967059 -121.802665) (xy 331.92691 -121.763956) (xy 331.892824 -121.719813)
			(xy 331.865528 -121.671178) (xy 331.845605 -121.619087) (xy 331.833479 -121.56465) (xy 331.829408 -121.509028)
			(xy 330.435632 -121.509028) (xy 330.431367 -121.513788) (xy 330.388499 -121.549463) (xy 330.340893 -121.578517)
			(xy 330.289564 -121.600329) (xy 330.235607 -121.614435) (xy 330.18017 -121.620535) (xy 330.124436 -121.618498)
			(xy 330.069593 -121.608368) (xy 330.016809 -121.590361) (xy 329.967209 -121.56486) (xy 329.921851 -121.532409)
			(xy 329.881702 -121.4937) (xy 329.847616 -121.449557) (xy 329.82032 -121.400922) (xy 329.800397 -121.348831)
			(xy 329.788271 -121.294394) (xy 329.7842 -121.238772) (xy 317.243606 -121.238772) (xy 317.248788 -121.242102)
			(xy 317.292069 -121.2796) (xy 317.329572 -121.322876) (xy 317.360534 -121.37105) (xy 317.384324 -121.423139)
			(xy 317.400459 -121.478085) (xy 317.408609 -121.534767) (xy 317.408609 -121.592033) (xy 317.400459 -121.648715)
			(xy 317.384324 -121.703661) (xy 317.360534 -121.75575) (xy 317.329572 -121.803924) (xy 317.292069 -121.8472)
			(xy 317.248788 -121.884698) (xy 317.200612 -121.915655) (xy 317.148519 -121.93944) (xy 317.093572 -121.955568)
			(xy 317.036889 -121.963712) (xy 317.008256 -121.964196) (xy 316.980888 -121.963678) (xy 316.926658 -121.956241)
			(xy 316.873945 -121.941497) (xy 316.823726 -121.91972) (xy 316.776936 -121.891316) (xy 316.734444 -121.856812)
			(xy 316.69704 -121.816849) (xy 316.68085 -121.794778) (xy 316.675288 -121.787516) (xy 316.66018 -121.777231)
			(xy 316.651386 -121.774712) (xy 316.621668 -121.767346) (xy 316.612594 -121.765508) (xy 316.594228 -121.767717)
			(xy 316.585854 -121.771664) (xy 316.557736 -121.785726) (xy 316.498532 -121.806872) (xy 316.436992 -121.819721)
			(xy 316.374272 -121.824031) (xy 316.311552 -121.819721) (xy 316.250012 -121.806872) (xy 316.190808 -121.785726)
			(xy 316.16269 -121.771664) (xy 316.154315 -121.767721) (xy 316.13595 -121.765513) (xy 316.126876 -121.767346)
			(xy 316.097158 -121.774712) (xy 316.088376 -121.777252) (xy 316.073276 -121.787537) (xy 316.067694 -121.794778)
			(xy 316.05152 -121.816864) (xy 316.014116 -121.856833) (xy 315.971622 -121.891344) (xy 315.924831 -121.919755)
			(xy 315.874609 -121.941538) (xy 315.821892 -121.956288) (xy 315.767659 -121.963731) (xy 315.740288 -121.964196)
			(xy 315.711657 -121.963717) (xy 315.654979 -121.955566) (xy 315.600037 -121.939432) (xy 315.547951 -121.915644)
			(xy 315.49978 -121.884685) (xy 315.456506 -121.847186) (xy 315.419008 -121.80391) (xy 315.38805 -121.755738)
			(xy 315.364264 -121.703651) (xy 315.348132 -121.648709) (xy 315.339983 -121.592031) (xy 315.339983 -121.534769)
			(xy 315.348132 -121.478091) (xy 315.364264 -121.423149) (xy 315.38805 -121.371062) (xy 315.419008 -121.32289)
			(xy 315.456506 -121.279614) (xy 315.49978 -121.242115) (xy 315.547951 -121.211156) (xy 315.600037 -121.187368)
			(xy 315.654979 -121.171234) (xy 315.711657 -121.163083) (xy 315.740288 -121.162572) (xy 315.755202 -121.162677)
			(xy 315.784951 -121.164841) (xy 315.799724 -121.16689) (xy 315.810646 -121.168414) (xy 315.831982 -121.162318)
			(xy 315.898784 -121.104914) (xy 315.906796 -121.097332) (xy 315.916021 -121.077323) (xy 315.916564 -121.066306)
			(xy 315.916564 -120.801638) (xy 315.916016 -120.79062) (xy 315.906805 -120.770603) (xy 315.898784 -120.76303)
			(xy 315.831982 -120.705626) (xy 315.810646 -120.69953) (xy 315.799724 -120.701054) (xy 315.784951 -120.703106)
			(xy 315.755202 -120.705265) (xy 315.740288 -120.705372) (xy 315.711656 -120.704941) (xy 315.654974 -120.696789)
			(xy 315.600029 -120.680655) (xy 315.54794 -120.656865) (xy 315.499766 -120.625904) (xy 315.456489 -120.588403)
			(xy 315.418989 -120.545125) (xy 315.388029 -120.49695) (xy 315.364241 -120.44486) (xy 315.348108 -120.389914)
			(xy 315.339959 -120.333232) (xy 306.685537 -120.333232) (xy 306.670487 -120.345757) (xy 306.622881 -120.374811)
			(xy 306.571552 -120.396623) (xy 306.517595 -120.410729) (xy 306.462158 -120.416829) (xy 306.406424 -120.414792)
			(xy 306.351581 -120.404662) (xy 306.298797 -120.386655) (xy 306.249197 -120.361154) (xy 306.203839 -120.328703)
			(xy 306.16369 -120.289994) (xy 306.129604 -120.245851) (xy 306.102308 -120.197216) (xy 306.082385 -120.145125)
			(xy 306.070259 -120.090688) (xy 306.066188 -120.035066) (xy 304.848039 -120.035066) (xy 304.848038 -120.062368)
			(xy 304.840278 -120.116319) (xy 304.82492 -120.168616) (xy 304.802275 -120.218195) (xy 304.772805 -120.264047)
			(xy 304.737109 -120.305237) (xy 304.695915 -120.340929) (xy 304.65006 -120.370394) (xy 304.600478 -120.393034)
			(xy 304.54818 -120.408387) (xy 304.494228 -120.41614) (xy 304.439723 -120.416137) (xy 304.385772 -120.408376)
			(xy 304.333475 -120.393017) (xy 304.283897 -120.370371) (xy 304.238046 -120.340899) (xy 304.196856 -120.305203)
			(xy 304.161166 -120.264007) (xy 304.131701 -120.218152) (xy 304.109063 -120.16857) (xy 304.093711 -120.11627)
			(xy 304.085959 -120.062319) (xy 304.085498 -120.035066) (xy 304.086073 -120.004497) (xy 304.09577 -119.944134)
			(xy 304.104802 -119.914924) (xy 304.108664 -119.901906) (xy 304.110046 -119.874795) (xy 304.104234 -119.848278)
			(xy 304.091639 -119.824231) (xy 304.073153 -119.804352) (xy 304.050081 -119.790049) (xy 304.024055 -119.782331)
			(xy 303.996915 -119.781745) (xy 303.983644 -119.784622) (xy 303.960776 -119.789973) (xy 303.914163 -119.795706)
			(xy 303.89068 -119.796052) (xy 303.863428 -119.795523) (xy 303.80948 -119.787764) (xy 303.757185 -119.772405)
			(xy 303.707608 -119.749761) (xy 303.661758 -119.720291) (xy 303.62057 -119.684596) (xy 303.58488 -119.643403)
			(xy 303.555416 -119.59755) (xy 303.532778 -119.54797) (xy 303.517426 -119.495673) (xy 303.509673 -119.441724)
			(xy 303.14646 -119.441724) (xy 303.14646 -121.83491) (xy 304.084988 -121.83491) (xy 304.089059 -121.779288)
			(xy 304.101185 -121.724851) (xy 304.121108 -121.67276) (xy 304.148404 -121.624125) (xy 304.18249 -121.579982)
			(xy 304.222639 -121.541273) (xy 304.267997 -121.508822) (xy 304.317597 -121.483321) (xy 304.370381 -121.465314)
			(xy 304.425224 -121.455184) (xy 304.480958 -121.453147) (xy 304.536395 -121.459247) (xy 304.590352 -121.473353)
			(xy 304.641681 -121.495165) (xy 304.689287 -121.524219) (xy 304.732155 -121.559894) (xy 304.769372 -121.601431)
			(xy 304.800145 -121.647944) (xy 304.823817 -121.698441) (xy 304.839885 -121.751848) (xy 304.848005 -121.807024)
			(xy 304.848514 -121.83491) (xy 306.066188 -121.83491) (xy 306.070259 -121.779288) (xy 306.082385 -121.724851)
			(xy 306.102308 -121.67276) (xy 306.129604 -121.624125) (xy 306.16369 -121.579982) (xy 306.203839 -121.541273)
			(xy 306.249197 -121.508822) (xy 306.298797 -121.483321) (xy 306.351581 -121.465314) (xy 306.406424 -121.455184)
			(xy 306.462158 -121.453147) (xy 306.517595 -121.459247) (xy 306.571552 -121.473353) (xy 306.622881 -121.495165)
			(xy 306.670487 -121.524219) (xy 306.713355 -121.559894) (xy 306.750572 -121.601431) (xy 306.781345 -121.647944)
			(xy 306.805017 -121.698441) (xy 306.821085 -121.751848) (xy 306.829205 -121.807024) (xy 306.829714 -121.83491)
			(xy 306.829205 -121.862796) (xy 306.821085 -121.917972) (xy 306.805017 -121.971379) (xy 306.781345 -122.021876)
			(xy 306.750572 -122.068389) (xy 306.713355 -122.109926) (xy 306.693138 -122.126751) (xy 312.697599 -122.126751)
			(xy 312.697599 -122.069449) (xy 312.705753 -122.012731) (xy 312.721896 -121.957751) (xy 312.7457 -121.905627)
			(xy 312.776678 -121.857422) (xy 312.814202 -121.814116) (xy 312.857506 -121.77659) (xy 312.90571 -121.745609)
			(xy 312.957832 -121.721803) (xy 313.012812 -121.705658) (xy 313.069529 -121.6975) (xy 313.09818 -121.696988)
			(xy 313.12556 -121.697474) (xy 313.179809 -121.704939) (xy 313.232537 -121.719718) (xy 313.282763 -121.741537)
			(xy 313.329551 -121.76999) (xy 313.372031 -121.804546) (xy 313.409412 -121.844563) (xy 313.425586 -121.86666)
			(xy 313.431162 -121.873909) (xy 313.446261 -121.8842) (xy 313.45505 -121.886726) (xy 313.484768 -121.894092)
			(xy 313.49384 -121.895945) (xy 313.512208 -121.893725) (xy 313.520582 -121.889774) (xy 313.545156 -121.877404)
			(xy 313.596619 -121.857949) (xy 313.650042 -121.844799) (xy 313.704656 -121.838144) (xy 313.732164 -121.837704)
			(xy 313.759672 -121.838163) (xy 313.814286 -121.844809) (xy 313.86771 -121.857951) (xy 313.919175 -121.877399)
			(xy 313.943746 -121.889774) (xy 313.952133 -121.893686) (xy 313.970488 -121.895913) (xy 313.97956 -121.894092)
			(xy 314.009278 -121.886726) (xy 314.018059 -121.884179) (xy 314.033161 -121.8739) (xy 314.038742 -121.86666)
			(xy 314.054899 -121.844547) (xy 314.092272 -121.804513) (xy 314.134749 -121.769943) (xy 314.18154 -121.741483)
			(xy 314.231772 -121.719661) (xy 314.284507 -121.704886) (xy 314.338765 -121.697432) (xy 314.366148 -121.696988)
			(xy 314.394791 -121.697594) (xy 314.451492 -121.705753) (xy 314.506456 -121.721898) (xy 314.558563 -121.745699)
			(xy 314.606752 -121.776674) (xy 314.650043 -121.814191) (xy 314.687555 -121.857487) (xy 314.718524 -121.90568)
			(xy 314.742319 -121.957789) (xy 314.758457 -122.012755) (xy 314.766609 -122.069457) (xy 314.766609 -122.126743)
			(xy 314.758457 -122.183445) (xy 314.742319 -122.238411) (xy 314.718524 -122.29052) (xy 314.687555 -122.338713)
			(xy 314.650043 -122.382009) (xy 314.606752 -122.419526) (xy 314.558563 -122.4505) (xy 314.506456 -122.474302)
			(xy 314.451492 -122.490447) (xy 314.394791 -122.498606) (xy 314.366148 -122.49912) (xy 314.35123 -122.498952)
			(xy 314.321481 -122.496662) (xy 314.306712 -122.494548) (xy 314.29579 -122.493024) (xy 314.274454 -122.49912)
			(xy 314.244304 -122.525028) (xy 331.805532 -122.525028) (xy 331.809603 -122.469406) (xy 331.821729 -122.414969)
			(xy 331.841652 -122.362878) (xy 331.868948 -122.314243) (xy 331.903034 -122.2701) (xy 331.943183 -122.231391)
			(xy 331.988541 -122.19894) (xy 332.038141 -122.173439) (xy 332.090925 -122.155432) (xy 332.145768 -122.145302)
			(xy 332.201502 -122.143265) (xy 332.256939 -122.149365) (xy 332.310896 -122.163471) (xy 332.362225 -122.185283)
			(xy 332.409831 -122.214337) (xy 332.452699 -122.250012) (xy 332.489916 -122.291549) (xy 332.520689 -122.338062)
			(xy 332.544361 -122.388559) (xy 332.560429 -122.441966) (xy 332.568549 -122.497142) (xy 332.569058 -122.525028)
			(xy 332.568549 -122.552914) (xy 332.560429 -122.60809) (xy 332.544361 -122.661497) (xy 332.520689 -122.711994)
			(xy 332.489916 -122.758507) (xy 332.452699 -122.800044) (xy 332.409831 -122.835719) (xy 332.362225 -122.864773)
			(xy 332.310896 -122.886585) (xy 332.256939 -122.900691) (xy 332.201502 -122.906791) (xy 332.145768 -122.904754)
			(xy 332.090925 -122.894624) (xy 332.038141 -122.876617) (xy 331.988541 -122.851116) (xy 331.943183 -122.818665)
			(xy 331.903034 -122.779956) (xy 331.868948 -122.735813) (xy 331.841652 -122.687178) (xy 331.821729 -122.635087)
			(xy 331.809603 -122.58065) (xy 331.805532 -122.525028) (xy 314.244304 -122.525028) (xy 314.207652 -122.556524)
			(xy 314.199613 -122.564081) (xy 314.190405 -122.58411) (xy 314.189872 -122.595132) (xy 314.189872 -122.8598)
			(xy 314.190419 -122.870818) (xy 314.199633 -122.890834) (xy 314.207652 -122.898408) (xy 314.274454 -122.955812)
			(xy 314.29579 -122.961908) (xy 314.306712 -122.960384) (xy 314.321481 -122.958272) (xy 314.35123 -122.955986)
			(xy 314.366148 -122.955812) (xy 314.394792 -122.95637) (xy 314.451497 -122.96453) (xy 314.506464 -122.980675)
			(xy 314.558574 -123.004478) (xy 314.606766 -123.035455) (xy 314.65006 -123.072974) (xy 314.687574 -123.116272)
			(xy 314.718545 -123.164468) (xy 314.742342 -123.216581) (xy 314.758481 -123.27155) (xy 314.766633 -123.328255)
			(xy 314.766633 -123.364548) (xy 326.264298 -123.364548) (xy 326.264298 -123.310052) (xy 326.272053 -123.256109)
			(xy 326.287406 -123.20382) (xy 326.310044 -123.154247) (xy 326.339506 -123.108401) (xy 326.375192 -123.067214)
			(xy 326.416377 -123.031524) (xy 326.462221 -123.002058) (xy 326.511792 -122.979417) (xy 326.56408 -122.96406)
			(xy 326.618022 -122.9563) (xy 326.64527 -122.955812) (xy 326.67264 -122.956293) (xy 326.726818 -122.964107)
			(xy 326.779321 -122.979592) (xy 326.829068 -123.002431) (xy 326.875036 -123.032152) (xy 326.895968 -123.049792)
			(xy 326.90308 -123.055888) (xy 326.920098 -123.062238) (xy 327.005442 -123.062238) (xy 327.02246 -123.055888)
			(xy 327.029572 -123.049792) (xy 327.050505 -123.032151) (xy 327.096473 -123.002427) (xy 327.146219 -122.979581)
			(xy 327.198721 -122.964085) (xy 327.252899 -122.956256) (xy 327.307641 -122.956256) (xy 327.361819 -122.964085)
			(xy 327.414321 -122.979581) (xy 327.464067 -123.002427) (xy 327.510035 -123.032151) (xy 327.530968 -123.049792)
			(xy 327.53808 -123.055888) (xy 327.555098 -123.062238) (xy 327.640442 -123.062238) (xy 327.65746 -123.055888)
			(xy 327.664572 -123.049792) (xy 327.685503 -123.032151) (xy 327.731476 -123.00244) (xy 327.781224 -122.979604)
			(xy 327.833725 -122.964114) (xy 327.887901 -122.956286) (xy 327.91527 -122.955812) (xy 327.942526 -122.956233)
			(xy 327.996483 -122.963987) (xy 328.048787 -122.979341) (xy 328.098374 -123.001983) (xy 328.144233 -123.031452)
			(xy 328.185431 -123.067147) (xy 328.22113 -123.108343) (xy 328.250603 -123.1542) (xy 328.273248 -123.203785)
			(xy 328.288607 -123.256088) (xy 328.296365 -123.310044) (xy 328.296365 -123.364556) (xy 328.288607 -123.418512)
			(xy 328.273248 -123.470815) (xy 328.250603 -123.5204) (xy 328.22113 -123.566257) (xy 328.185431 -123.607453)
			(xy 328.144233 -123.643148) (xy 328.098374 -123.672617) (xy 328.048787 -123.695259) (xy 327.996483 -123.710613)
			(xy 327.942526 -123.718367) (xy 327.91527 -123.718828) (xy 327.887898 -123.718397) (xy 327.833717 -123.710573)
			(xy 327.781213 -123.695077) (xy 327.731466 -123.672227) (xy 327.685502 -123.642494) (xy 327.664572 -123.624848)
			(xy 327.65746 -123.618752) (xy 327.640442 -123.612402) (xy 327.555098 -123.612402) (xy 327.53808 -123.618752)
			(xy 327.530968 -123.624848) (xy 327.510035 -123.642489) (xy 327.464067 -123.672213) (xy 327.414321 -123.695059)
			(xy 327.361819 -123.710555) (xy 327.307641 -123.718384) (xy 327.252899 -123.718384) (xy 327.198721 -123.710555)
			(xy 327.146219 -123.695059) (xy 327.096473 -123.672213) (xy 327.050505 -123.642489) (xy 327.029572 -123.624848)
			(xy 327.02246 -123.618752) (xy 327.005442 -123.612402) (xy 326.920098 -123.612402) (xy 326.90308 -123.618752)
			(xy 326.895968 -123.624848) (xy 326.875014 -123.642461) (xy 326.829048 -123.672178) (xy 326.779306 -123.69502)
			(xy 326.72681 -123.710517) (xy 326.672638 -123.718351) (xy 326.64527 -123.718828) (xy 326.618022 -123.7183)
			(xy 326.56408 -123.71054) (xy 326.511792 -123.695183) (xy 326.462221 -123.672542) (xy 326.416377 -123.643076)
			(xy 326.375192 -123.607386) (xy 326.339506 -123.566199) (xy 326.310044 -123.520353) (xy 326.287406 -123.47078)
			(xy 326.272053 -123.418491) (xy 326.264298 -123.364548) (xy 314.766633 -123.364548) (xy 314.766633 -123.385544)
			(xy 314.758481 -123.44225) (xy 314.742342 -123.497219) (xy 314.718545 -123.549332) (xy 314.687574 -123.597528)
			(xy 314.65006 -123.640826) (xy 314.606766 -123.678345) (xy 314.558574 -123.709322) (xy 314.506464 -123.733125)
			(xy 314.451497 -123.74927) (xy 314.394792 -123.75743) (xy 314.366148 -123.757944) (xy 314.338767 -123.757498)
			(xy 314.284516 -123.750025) (xy 314.231788 -123.735237) (xy 314.181563 -123.713411) (xy 314.134775 -123.684953)
			(xy 314.092296 -123.650392) (xy 314.054916 -123.610371) (xy 314.038742 -123.588272) (xy 314.033149 -123.581038)
			(xy 314.018063 -123.570738) (xy 314.009278 -123.568206) (xy 313.97956 -123.56084) (xy 313.970486 -123.558998)
			(xy 313.95212 -123.56121) (xy 313.943746 -123.565158) (xy 313.919186 -123.577557) (xy 313.867718 -123.597004)
			(xy 313.81429 -123.610146) (xy 313.759673 -123.616792) (xy 313.732164 -123.617228) (xy 313.704655 -123.616806)
			(xy 313.650039 -123.61015) (xy 313.596615 -123.596998) (xy 313.545152 -123.577539) (xy 313.520582 -123.565158)
			(xy 313.512209 -123.56121) (xy 313.493842 -123.559005) (xy 313.484768 -123.56084) (xy 313.45505 -123.568206)
			(xy 313.446267 -123.570745) (xy 313.431168 -123.581031) (xy 313.425586 -123.588272) (xy 313.409421 -123.610379)
			(xy 313.372049 -123.650412) (xy 313.329572 -123.684981) (xy 313.282783 -123.713442) (xy 313.232553 -123.735264)
			(xy 313.179818 -123.750042) (xy 313.125563 -123.757499) (xy 313.09818 -123.757944) (xy 313.069531 -123.757476)
			(xy 313.012817 -123.749319) (xy 312.957841 -123.733174) (xy 312.905721 -123.70937) (xy 312.85752 -123.678391)
			(xy 312.814218 -123.640867) (xy 312.776697 -123.597564) (xy 312.745721 -123.549361) (xy 312.721919 -123.497241)
			(xy 312.705777 -123.442264) (xy 312.697623 -123.385549) (xy 312.697623 -123.328251) (xy 312.705777 -123.271536)
			(xy 312.721919 -123.216559) (xy 312.745721 -123.164439) (xy 312.776697 -123.116236) (xy 312.814218 -123.072933)
			(xy 312.85752 -123.035409) (xy 312.905721 -123.00443) (xy 312.957841 -122.980626) (xy 313.012817 -122.964481)
			(xy 313.069531 -122.956324) (xy 313.09818 -122.955812) (xy 313.113098 -122.955978) (xy 313.142847 -122.958269)
			(xy 313.157616 -122.960384) (xy 313.168538 -122.961908) (xy 313.189874 -122.955812) (xy 313.256676 -122.898408)
			(xy 313.264705 -122.890842) (xy 313.273917 -122.87082) (xy 313.274456 -122.8598) (xy 313.274456 -122.595132)
			(xy 313.273914 -122.584113) (xy 313.264699 -122.564096) (xy 313.256676 -122.556524) (xy 313.189874 -122.49912)
			(xy 313.168538 -122.493024) (xy 313.157616 -122.494548) (xy 313.142847 -122.496657) (xy 313.113098 -122.498945)
			(xy 313.09818 -122.49912) (xy 313.069529 -122.4987) (xy 313.012812 -122.490542) (xy 312.957832 -122.474397)
			(xy 312.90571 -122.450591) (xy 312.857506 -122.41961) (xy 312.814202 -122.382084) (xy 312.776678 -122.338778)
			(xy 312.7457 -122.290573) (xy 312.721896 -122.238449) (xy 312.705753 -122.183469) (xy 312.697599 -122.126751)
			(xy 306.693138 -122.126751) (xy 306.670487 -122.145601) (xy 306.622881 -122.174655) (xy 306.571552 -122.196467)
			(xy 306.517595 -122.210573) (xy 306.462158 -122.216673) (xy 306.406424 -122.214636) (xy 306.351581 -122.204506)
			(xy 306.298797 -122.186499) (xy 306.249197 -122.160998) (xy 306.203839 -122.128547) (xy 306.16369 -122.089838)
			(xy 306.129604 -122.045695) (xy 306.102308 -121.99706) (xy 306.082385 -121.944969) (xy 306.070259 -121.890532)
			(xy 306.066188 -121.83491) (xy 304.848514 -121.83491) (xy 304.848005 -121.862796) (xy 304.839885 -121.917972)
			(xy 304.823817 -121.971379) (xy 304.800145 -122.021876) (xy 304.769372 -122.068389) (xy 304.732155 -122.109926)
			(xy 304.689287 -122.145601) (xy 304.641681 -122.174655) (xy 304.590352 -122.196467) (xy 304.536395 -122.210573)
			(xy 304.480958 -122.216673) (xy 304.425224 -122.214636) (xy 304.370381 -122.204506) (xy 304.317597 -122.186499)
			(xy 304.267997 -122.160998) (xy 304.222639 -122.128547) (xy 304.18249 -122.089838) (xy 304.148404 -122.045695)
			(xy 304.121108 -121.99706) (xy 304.101185 -121.944969) (xy 304.089059 -121.890532) (xy 304.084988 -121.83491)
			(xy 303.14646 -121.83491) (xy 303.14646 -123.635008) (xy 304.084988 -123.635008) (xy 304.089059 -123.579386)
			(xy 304.101185 -123.524949) (xy 304.121108 -123.472858) (xy 304.148404 -123.424223) (xy 304.18249 -123.38008)
			(xy 304.222639 -123.341371) (xy 304.267997 -123.30892) (xy 304.317597 -123.283419) (xy 304.370381 -123.265412)
			(xy 304.425224 -123.255282) (xy 304.480958 -123.253245) (xy 304.536395 -123.259345) (xy 304.590352 -123.273451)
			(xy 304.641681 -123.295263) (xy 304.689287 -123.324317) (xy 304.732155 -123.359992) (xy 304.769372 -123.401529)
			(xy 304.800145 -123.448042) (xy 304.823817 -123.498539) (xy 304.839885 -123.551946) (xy 304.848005 -123.607122)
			(xy 304.848514 -123.635008) (xy 306.066188 -123.635008) (xy 306.070259 -123.579386) (xy 306.082385 -123.524949)
			(xy 306.102308 -123.472858) (xy 306.129604 -123.424223) (xy 306.16369 -123.38008) (xy 306.203839 -123.341371)
			(xy 306.249197 -123.30892) (xy 306.298797 -123.283419) (xy 306.351581 -123.265412) (xy 306.406424 -123.255282)
			(xy 306.462158 -123.253245) (xy 306.517595 -123.259345) (xy 306.571552 -123.273451) (xy 306.622881 -123.295263)
			(xy 306.670487 -123.324317) (xy 306.713355 -123.359992) (xy 306.750572 -123.401529) (xy 306.781345 -123.448042)
			(xy 306.805017 -123.498539) (xy 306.821085 -123.551946) (xy 306.829205 -123.607122) (xy 306.829714 -123.635008)
			(xy 306.829205 -123.662894) (xy 306.821085 -123.71807) (xy 306.805017 -123.771477) (xy 306.781345 -123.821974)
			(xy 306.750572 -123.868487) (xy 306.713355 -123.910024) (xy 306.685569 -123.933148) (xy 315.339747 -123.933148)
			(xy 315.339747 -123.875852) (xy 315.347901 -123.81914) (xy 315.364043 -123.764166) (xy 315.387843 -123.712048)
			(xy 315.418819 -123.663848) (xy 315.456339 -123.620547) (xy 315.499639 -123.583026) (xy 315.547838 -123.552049)
			(xy 315.599955 -123.528247) (xy 315.654929 -123.512103) (xy 315.71164 -123.503948) (xy 315.740288 -123.503436)
			(xy 315.767667 -123.503938) (xy 315.821915 -123.511403) (xy 315.874642 -123.526181) (xy 315.924866 -123.547998)
			(xy 315.971655 -123.576447) (xy 316.014135 -123.611) (xy 316.051518 -123.651013) (xy 316.067694 -123.673108)
			(xy 316.073258 -123.680367) (xy 316.088366 -123.690652) (xy 316.097158 -123.693174) (xy 316.126876 -123.70054)
			(xy 316.135948 -123.702392) (xy 316.154315 -123.700171) (xy 316.16269 -123.696222) (xy 316.187265 -123.683853)
			(xy 316.238727 -123.664397) (xy 316.29215 -123.651246) (xy 316.346764 -123.644591) (xy 316.374272 -123.644152)
			(xy 316.40178 -123.644602) (xy 316.456395 -123.65125) (xy 316.509819 -123.664394) (xy 316.561284 -123.683845)
			(xy 316.585854 -123.696222) (xy 316.59424 -123.700137) (xy 316.612596 -123.702363) (xy 316.621668 -123.70054)
			(xy 316.651386 -123.693174) (xy 316.660162 -123.690616) (xy 316.675266 -123.680344) (xy 316.68085 -123.673108)
			(xy 316.696987 -123.650979) (xy 316.734364 -123.610948) (xy 316.776846 -123.576382) (xy 316.823641 -123.547924)
			(xy 316.873875 -123.526105) (xy 316.926613 -123.511331) (xy 316.980872 -123.503879) (xy 317.008256 -123.503436)
			(xy 317.036908 -123.503916) (xy 317.09363 -123.512065) (xy 317.148614 -123.528205) (xy 317.200742 -123.552006)
			(xy 317.248952 -123.582983) (xy 317.292262 -123.620507) (xy 317.32979 -123.663813) (xy 317.360773 -123.712019)
			(xy 317.38458 -123.764144) (xy 317.400725 -123.819127) (xy 317.408881 -123.875848) (xy 317.408881 -123.933152)
			(xy 317.400725 -123.989873) (xy 317.38458 -124.044856) (xy 317.360773 -124.096981) (xy 317.32979 -124.145187)
			(xy 317.292262 -124.188493) (xy 317.248952 -124.226017) (xy 317.200742 -124.256994) (xy 317.148614 -124.280795)
			(xy 317.09363 -124.296935) (xy 317.036908 -124.305084) (xy 317.008256 -124.305568) (xy 316.993338 -124.305398)
			(xy 316.963589 -124.30311) (xy 316.94882 -124.300996) (xy 316.937898 -124.299472) (xy 316.916562 -124.305568)
			(xy 316.84976 -124.362972) (xy 316.841745 -124.370551) (xy 316.832524 -124.390563) (xy 316.83198 -124.40158)
			(xy 316.83198 -124.666248) (xy 316.832553 -124.677262) (xy 316.841748 -124.697279) (xy 316.84976 -124.704856)
			(xy 316.916562 -124.76226) (xy 316.937898 -124.768356) (xy 316.94882 -124.766832) (xy 316.963589 -124.764719)
			(xy 316.993338 -124.762434) (xy 317.008256 -124.76226) (xy 317.03691 -124.762692) (xy 317.093635 -124.770842)
			(xy 317.148623 -124.786982) (xy 317.200754 -124.810785) (xy 317.248966 -124.841764) (xy 317.292279 -124.87929)
			(xy 317.329809 -124.922599) (xy 317.360794 -124.970808) (xy 317.384602 -125.022936) (xy 317.400749 -125.077922)
			(xy 317.408905 -125.134646) (xy 317.408905 -125.191954) (xy 317.400749 -125.248678) (xy 317.384602 -125.303664)
			(xy 317.360794 -125.355792) (xy 317.329809 -125.404001) (xy 317.292279 -125.44731) (xy 317.248966 -125.484836)
			(xy 317.200754 -125.515815) (xy 317.148623 -125.539618) (xy 317.093635 -125.555758) (xy 317.03691 -125.563908)
			(xy 317.008256 -125.564392) (xy 316.980874 -125.563962) (xy 316.926622 -125.556489) (xy 316.873892 -125.5417)
			(xy 316.823666 -125.519872) (xy 316.776879 -125.491411) (xy 316.7344 -125.456846) (xy 316.697022 -125.416821)
			(xy 316.68085 -125.39472) (xy 316.6753 -125.387448) (xy 316.660182 -125.37717) (xy 316.651386 -125.374654)
			(xy 316.621668 -125.367288) (xy 316.612593 -125.365456) (xy 316.594229 -125.367663) (xy 316.585854 -125.371606)
			(xy 316.56129 -125.383998) (xy 316.509824 -125.403448) (xy 316.456397 -125.416592) (xy 316.401781 -125.42324)
			(xy 316.374272 -125.423676) (xy 316.346763 -125.423245) (xy 316.292148 -125.416591) (xy 316.238724 -125.403441)
			(xy 316.18726 -125.383985) (xy 316.16269 -125.371606) (xy 316.154316 -125.367662) (xy 316.13595 -125.365456)
			(xy 316.126876 -125.367288) (xy 316.097158 -125.374654) (xy 316.088371 -125.377182) (xy 316.073273 -125.387475)
			(xy 316.067694 -125.39472) (xy 316.051538 -125.416834) (xy 316.014163 -125.456864) (xy 315.971684 -125.491431)
			(xy 315.924893 -125.51989) (xy 315.874662 -125.541712) (xy 315.821927 -125.556489) (xy 315.767671 -125.563946)
			(xy 315.740288 -125.564392) (xy 315.711642 -125.563828) (xy 315.654934 -125.555673) (xy 315.599963 -125.539531)
			(xy 315.547849 -125.51573) (xy 315.499653 -125.484755) (xy 315.456356 -125.447236) (xy 315.418838 -125.403937)
			(xy 315.387864 -125.35574) (xy 315.364065 -125.303625) (xy 315.347924 -125.248654) (xy 315.339771 -125.191946)
			(xy 315.339771 -125.134654) (xy 315.347924 -125.077946) (xy 315.364065 -125.022975) (xy 315.387864 -124.97086)
			(xy 315.418838 -124.922663) (xy 315.456356 -124.879364) (xy 315.499653 -124.841845) (xy 315.547849 -124.81087)
			(xy 315.599963 -124.787069) (xy 315.654934 -124.770927) (xy 315.711642 -124.762772) (xy 315.740288 -124.76226)
			(xy 315.755206 -124.762425) (xy 315.784955 -124.764717) (xy 315.799724 -124.766832) (xy 315.810646 -124.768356)
			(xy 315.831982 -124.76226) (xy 315.898784 -124.704856) (xy 315.906777 -124.697257) (xy 315.916013 -124.677261)
			(xy 315.916564 -124.666248) (xy 315.916564 -124.40158) (xy 315.916048 -124.390558) (xy 315.906814 -124.370541)
			(xy 315.898784 -124.362972) (xy 315.831982 -124.305568) (xy 315.810646 -124.299472) (xy 315.799724 -124.300996)
			(xy 315.784955 -124.303104) (xy 315.755206 -124.305392) (xy 315.740288 -124.305568) (xy 315.71164 -124.305052)
			(xy 315.654929 -124.296897) (xy 315.599955 -124.280753) (xy 315.547838 -124.256951) (xy 315.499639 -124.225974)
			(xy 315.456339 -124.188453) (xy 315.418819 -124.145152) (xy 315.387843 -124.096952) (xy 315.364043 -124.044834)
			(xy 315.347901 -123.98986) (xy 315.339747 -123.933148) (xy 306.685569 -123.933148) (xy 306.670487 -123.945699)
			(xy 306.622881 -123.974753) (xy 306.571552 -123.996565) (xy 306.517595 -124.010671) (xy 306.462158 -124.016771)
			(xy 306.406424 -124.014734) (xy 306.351581 -124.004604) (xy 306.298797 -123.986597) (xy 306.249197 -123.961096)
			(xy 306.203839 -123.928645) (xy 306.16369 -123.889936) (xy 306.129604 -123.845793) (xy 306.102308 -123.797158)
			(xy 306.082385 -123.745067) (xy 306.070259 -123.69063) (xy 306.066188 -123.635008) (xy 304.848514 -123.635008)
			(xy 304.848005 -123.662894) (xy 304.839885 -123.71807) (xy 304.823817 -123.771477) (xy 304.800145 -123.821974)
			(xy 304.769372 -123.868487) (xy 304.732155 -123.910024) (xy 304.689287 -123.945699) (xy 304.641681 -123.974753)
			(xy 304.590352 -123.996565) (xy 304.536395 -124.010671) (xy 304.480958 -124.016771) (xy 304.425224 -124.014734)
			(xy 304.370381 -124.004604) (xy 304.317597 -123.986597) (xy 304.267997 -123.961096) (xy 304.222639 -123.928645)
			(xy 304.18249 -123.889936) (xy 304.148404 -123.845793) (xy 304.121108 -123.797158) (xy 304.101185 -123.745067)
			(xy 304.089059 -123.69063) (xy 304.084988 -123.635008) (xy 303.14646 -123.635008) (xy 303.14646 -124.769626)
			(xy 303.14692 -124.779503) (xy 303.154361 -124.797803) (xy 303.160938 -124.805186) (xy 303.161192 -124.80544)
			(xy 303.91481 -125.559058) (xy 303.922563 -125.566154) (xy 303.942081 -125.573882) (xy 303.96306 -125.573095)
			(xy 303.972722 -125.568964) (xy 304.074068 -125.52045) (xy 304.089562 -125.49251) (xy 304.087784 -125.476254)
			(xy 304.086727 -125.466) (xy 304.085582 -125.445414) (xy 304.085498 -125.435106) (xy 304.085961 -125.407853)
			(xy 304.093717 -125.353902) (xy 304.109073 -125.301604) (xy 304.131715 -125.252023) (xy 304.161183 -125.20617)
			(xy 304.196877 -125.164977) (xy 304.23807 -125.129283) (xy 304.283923 -125.099815) (xy 304.333504 -125.077173)
			(xy 304.385802 -125.061817) (xy 304.439753 -125.054061) (xy 304.467006 -125.053598) (xy 304.493897 -125.054065)
			(xy 304.547145 -125.061632) (xy 304.598803 -125.0766) (xy 304.647848 -125.098673) (xy 304.693308 -125.127414)
			(xy 304.734281 -125.162254) (xy 304.769957 -125.202501) (xy 304.799628 -125.247359) (xy 304.822707 -125.295938)
			(xy 304.838736 -125.347277) (xy 304.847398 -125.400358) (xy 304.848514 -125.427232) (xy 304.848514 -125.433582)
			(xy 304.848514 -125.435106) (xy 304.848094 -125.461073) (xy 304.84108 -125.512529) (xy 304.827142 -125.562557)
			(xy 304.806538 -125.610227) (xy 304.77965 -125.654657) (xy 304.763678 -125.675136) (xy 304.754534 -125.686566)
			(xy 304.750978 -125.715522) (xy 304.796698 -125.811534) (xy 304.796952 -125.812296) (xy 304.801132 -125.819924)
			(xy 304.813636 -125.831997) (xy 304.829468 -125.839171) (xy 304.8381 -125.840236) (xy 304.842672 -125.84049)
			(xy 306.07254 -125.84049)
		)
		(stroke
			(width 0)
			(type solid)
		)
		(fill yes)
		(layer "In13.Cu")
		(net "P3V3_NIC5")
	)
	(gr_poly
		(pts
			(xy 134.772654 -293.609776) (xy 134.782719 -293.609342) (xy 134.801307 -293.601612) (xy 134.808722 -293.59479)
			(xy 135.574278 -292.829234) (xy 135.574786 -292.828726) (xy 135.581362 -292.821342) (xy 135.588799 -292.803044)
			(xy 135.589264 -292.793166) (xy 135.589264 -279.364948) (xy 135.588702 -279.353353) (xy 135.578567 -279.332494)
			(xy 135.56035 -279.318143) (xy 135.549132 -279.315164) (xy 135.468856 -279.297634) (xy 135.309944 -279.255773)
			(xy 135.153255 -279.206235) (xy 134.99916 -279.149138) (xy 134.848023 -279.084616) (xy 134.700202 -279.012823)
			(xy 134.556046 -278.933927) (xy 134.415896 -278.848117) (xy 134.280084 -278.755594) (xy 134.148931 -278.656577)
			(xy 134.022748 -278.551301) (xy 133.901831 -278.440014) (xy 133.786469 -278.322981) (xy 133.676933 -278.200477)
			(xy 133.573482 -278.072792) (xy 133.476362 -277.940229) (xy 133.385802 -277.8031) (xy 133.302015 -277.661731)
			(xy 133.225201 -277.516455) (xy 133.155541 -277.367617) (xy 133.0932 -277.215568) (xy 133.038324 -277.060667)
			(xy 132.991045 -276.903282) (xy 132.951474 -276.743785) (xy 132.919704 -276.582552) (xy 132.89581 -276.419965)
			(xy 132.879849 -276.256409) (xy 132.87186 -276.09227) (xy 132.871859 -275.927937) (xy 132.879849 -275.763798)
			(xy 132.895809 -275.600242) (xy 132.919702 -275.437655) (xy 132.951472 -275.276422) (xy 132.991043 -275.116924)
			(xy 133.038322 -274.959539) (xy 133.093197 -274.804638) (xy 133.155538 -274.652589) (xy 133.225198 -274.503751)
			(xy 133.302012 -274.358475) (xy 133.385798 -274.217106) (xy 133.476358 -274.079977) (xy 133.573478 -273.947413)
			(xy 133.676929 -273.819729) (xy 133.786464 -273.697224) (xy 133.901827 -273.58019) (xy 134.022743 -273.468904)
			(xy 134.148926 -273.363627) (xy 134.280079 -273.26461) (xy 134.41589 -273.172087) (xy 134.55604 -273.086276)
			(xy 134.700196 -273.00738) (xy 134.848017 -272.935587) (xy 134.999153 -272.871065) (xy 135.153248 -272.813967)
			(xy 135.309937 -272.764429) (xy 135.468849 -272.722568) (xy 135.549132 -272.705068) (xy 135.560367 -272.7021)
			(xy 135.578639 -272.687784) (xy 135.588755 -272.666892) (xy 135.589264 -272.655284) (xy 135.589264 -268.708378)
			(xy 135.589693 -268.698311) (xy 135.59742 -268.679718) (xy 135.60425 -268.67231) (xy 137.085324 -267.191236)
			(xy 137.092168 -267.183838) (xy 137.099892 -267.165239) (xy 137.10031 -267.155168) (xy 137.10031 -261.196328)
			(xy 137.099895 -261.186302) (xy 137.092231 -261.167774) (xy 137.078058 -261.153591) (xy 137.059535 -261.145912)
			(xy 137.04951 -261.145528) (xy 133.230874 -261.145528) (xy 133.210972 -261.145384) (xy 133.171296 -261.142208)
			(xy 133.151626 -261.139178) (xy 133.125856 -261.134588) (xy 133.075428 -261.120543) (xy 133.026816 -261.101122)
			(xy 133.003544 -261.08914) (xy 133.003544 -261.088886) (xy 132.995416 -261.084568) (xy 132.966531 -261.0678)
			(xy 132.913256 -261.02752) (xy 132.889244 -261.004304) (xy 131.207764 -259.322824) (xy 131.199153 -259.315011)
			(xy 131.177191 -259.307452) (xy 131.1656 -259.308346) (xy 131.074414 -259.319776) (xy 131.054856 -259.332476)
			(xy 131.04876 -259.342636) (xy 131.03391 -259.366611) (xy 130.998259 -259.410306) (xy 130.956562 -259.448274)
			(xy 130.909729 -259.479688) (xy 130.858779 -259.503862) (xy 130.804825 -259.520269) (xy 130.749043 -259.528552)
			(xy 130.720846 -259.529072) (xy 130.693592 -259.528612) (xy 130.639638 -259.52086) (xy 130.587337 -259.505508)
			(xy 130.537753 -259.482867) (xy 130.491897 -259.4534) (xy 130.450701 -259.417706) (xy 130.415006 -259.376511)
			(xy 130.385538 -259.330656) (xy 130.362896 -259.281073) (xy 130.347542 -259.228772) (xy 130.339789 -259.174818)
			(xy 130.339338 -259.147564) (xy 130.339847 -259.119368) (xy 130.34815 -259.063592) (xy 130.364569 -259.009644)
			(xy 130.388748 -258.9587) (xy 130.42016 -258.911867) (xy 130.458121 -258.870167) (xy 130.501804 -258.834506)
			(xy 130.525774 -258.81965) (xy 130.535934 -258.813554) (xy 130.548634 -258.793996) (xy 130.560064 -258.70281)
			(xy 130.560965 -258.691213) (xy 130.553431 -258.669233) (xy 130.545586 -258.660646) (xy 130.358134 -258.473194)
			(xy 130.336115 -258.450477) (xy 130.297602 -258.400283) (xy 130.265972 -258.345491) (xy 130.241768 -258.287038)
			(xy 130.225405 -258.225924) (xy 130.217161 -258.163197) (xy 130.216656 -258.131564) (xy 130.217175 -258.099934)
			(xy 130.225436 -258.037216) (xy 130.241812 -257.976112) (xy 130.266023 -257.917668) (xy 130.297654 -257.862884)
			(xy 130.336165 -257.812697) (xy 130.380897 -257.767965) (xy 130.431084 -257.729454) (xy 130.485868 -257.697823)
			(xy 130.544312 -257.673612) (xy 130.605416 -257.657236) (xy 130.668134 -257.648975) (xy 130.699764 -257.648456)
			(xy 130.731395 -257.648977) (xy 130.794114 -257.657238) (xy 130.85522 -257.673612) (xy 130.913667 -257.697817)
			(xy 130.968457 -257.729441) (xy 131.018653 -257.767943) (xy 131.041394 -257.789934) (xy 132.85089 -259.599684)
			(xy 133.41604 -260.164834) (xy 133.423384 -260.171645) (xy 133.441847 -260.179374) (xy 133.451854 -260.17982)
			(xy 137.05459 -260.17982) (xy 137.063884 -260.178426) (xy 137.080616 -260.169905) (xy 137.093175 -260.155946)
			(xy 137.099887 -260.138409) (xy 137.10031 -260.12902) (xy 137.10031 -256.32664) (xy 137.099876 -256.316574)
			(xy 137.092148 -256.297985) (xy 137.085324 -256.290572) (xy 136.797034 -256.002282) (xy 136.797034 -255.993392)
			(xy 136.788398 -255.980438) (xy 136.771749 -255.955122) (xy 136.743929 -255.901292) (xy 136.722711 -255.844535)
			(xy 136.708396 -255.785656) (xy 136.701188 -255.725493) (xy 136.700768 -255.695196) (xy 136.700768 -252.137672)
			(xy 136.700225 -252.127687) (xy 136.692501 -252.109266) (xy 136.685782 -252.101858) (xy 136.389872 -251.805948)
			(xy 136.38276 -251.798582) (xy 136.363964 -251.790962) (xy 135.161274 -251.790962) (xy 135.15632 -251.790841)
			(xy 135.1466 -251.78892) (xy 135.14197 -251.787152) (xy 135.132826 -251.783342) (xy 135.131556 -251.782072)
			(xy 135.131131 -251.772058) (xy 135.123454 -251.753558) (xy 135.109282 -251.739405) (xy 135.090771 -251.731755)
			(xy 135.080756 -251.731272) (xy 133.056884 -251.731272) (xy 133.04679 -251.731765) (xy 133.028197 -251.739646)
			(xy 133.014064 -251.754069) (xy 133.009894 -251.763276) (xy 132.969254 -251.865892) (xy 132.975858 -251.896118)
			(xy 132.987542 -251.906786) (xy 133.00616 -251.924902) (xy 133.038818 -251.965297) (xy 133.065697 -252.009749)
			(xy 133.086298 -252.057435) (xy 133.100243 -252.107475) (xy 133.107272 -252.158943) (xy 133.107684 -252.184916)
			(xy 133.107198 -252.212167) (xy 133.099442 -252.266115) (xy 133.084087 -252.31841) (xy 133.061445 -252.367987)
			(xy 133.031979 -252.413837) (xy 132.996288 -252.455028) (xy 132.955097 -252.490719) (xy 132.909247 -252.520185)
			(xy 132.85967 -252.542827) (xy 132.807375 -252.558182) (xy 132.753427 -252.565938) (xy 132.698925 -252.565938)
			(xy 132.644977 -252.558182) (xy 132.592682 -252.542827) (xy 132.543105 -252.520185) (xy 132.497255 -252.490719)
			(xy 132.456064 -252.455028) (xy 132.420373 -252.413837) (xy 132.390907 -252.367987) (xy 132.368265 -252.31841)
			(xy 132.35291 -252.266115) (xy 132.345154 -252.212167) (xy 132.344668 -252.184916) (xy 132.345086 -252.158941)
			(xy 132.352095 -252.107467) (xy 132.366028 -252.057422) (xy 132.386626 -252.009731) (xy 132.413507 -251.965277)
			(xy 132.446175 -251.924885) (xy 132.46481 -251.906786) (xy 132.476494 -251.896118) (xy 132.483098 -251.865892)
			(xy 132.442458 -251.763276) (xy 132.438322 -251.754046) (xy 132.424188 -251.739599) (xy 132.405572 -251.731733)
			(xy 132.395468 -251.731272) (xy 125.933708 -251.731272) (xy 125.923637 -251.731693) (xy 125.905027 -251.739402)
			(xy 125.89764 -251.746258) (xy 125.548644 -252.095254) (xy 125.541245 -252.102097) (xy 125.522646 -252.109818)
			(xy 125.512576 -252.11024) (xy 123.070874 -252.11024) (xy 123.060807 -252.109811) (xy 123.042215 -252.102083)
			(xy 123.034806 -252.095254) (xy 122.68581 -251.746258) (xy 122.678698 -251.738892) (xy 122.659902 -251.731272)
			(xy 121.04878 -251.731272) (xy 121.039491 -251.731694) (xy 121.022132 -251.73832) (xy 121.008248 -251.750667)
			(xy 121.003568 -251.758704) (xy 120.955562 -251.851668) (xy 120.957594 -251.879862) (xy 120.965722 -251.891546)
			(xy 120.982311 -251.915873) (xy 121.0086 -251.968558) (xy 121.026488 -252.024654) (xy 121.035549 -252.082832)
			(xy 121.03608 -252.112272) (xy 121.035594 -252.139523) (xy 121.027838 -252.193471) (xy 121.012483 -252.245766)
			(xy 120.989841 -252.295343) (xy 120.960375 -252.341193) (xy 120.924684 -252.382384) (xy 120.883493 -252.418075)
			(xy 120.837643 -252.447541) (xy 120.788066 -252.470183) (xy 120.735771 -252.485538) (xy 120.681823 -252.493294)
			(xy 120.627321 -252.493294) (xy 120.573373 -252.485538) (xy 120.521078 -252.470183) (xy 120.471501 -252.447541)
			(xy 120.425651 -252.418075) (xy 120.38446 -252.382384) (xy 120.348769 -252.341193) (xy 120.319303 -252.295343)
			(xy 120.296661 -252.245766) (xy 120.281306 -252.193471) (xy 120.27355 -252.139523) (xy 120.273064 -252.112272)
			(xy 120.273605 -252.082831) (xy 120.282645 -252.024647) (xy 120.300521 -251.968545) (xy 120.326808 -251.915857)
			(xy 120.343422 -251.891546) (xy 120.35155 -251.879862) (xy 120.353582 -251.851668) (xy 120.305576 -251.758704)
			(xy 120.300953 -251.750617) (xy 120.287076 -251.738213) (xy 120.269672 -251.731616) (xy 120.260364 -251.731272)
			(xy 111.0361 -251.731272) (xy 111.017304 -251.738892) (xy 111.010192 -251.746258) (xy 109.65053 -253.10592)
			(xy 118.323612 -253.10592) (xy 118.327683 -253.050298) (xy 118.339809 -252.995861) (xy 118.359732 -252.94377)
			(xy 118.387028 -252.895135) (xy 118.421114 -252.850992) (xy 118.461263 -252.812283) (xy 118.506621 -252.779832)
			(xy 118.556221 -252.754331) (xy 118.609005 -252.736324) (xy 118.663848 -252.726194) (xy 118.719582 -252.724157)
			(xy 118.775019 -252.730257) (xy 118.828976 -252.744363) (xy 118.880305 -252.766175) (xy 118.927911 -252.795229)
			(xy 118.970779 -252.830904) (xy 119.007996 -252.872441) (xy 119.038769 -252.918954) (xy 119.062441 -252.969451)
			(xy 119.078509 -253.022858) (xy 119.086629 -253.078034) (xy 119.087138 -253.10592) (xy 119.086629 -253.133806)
			(xy 119.078509 -253.188982) (xy 119.062441 -253.242389) (xy 119.038769 -253.292886) (xy 119.007996 -253.339399)
			(xy 118.970779 -253.380936) (xy 118.962459 -253.38786) (xy 126.243078 -253.38786) (xy 126.247149 -253.332238)
			(xy 126.259275 -253.277801) (xy 126.279198 -253.22571) (xy 126.306494 -253.177075) (xy 126.34058 -253.132932)
			(xy 126.380729 -253.094223) (xy 126.426087 -253.061772) (xy 126.475687 -253.036271) (xy 126.528471 -253.018264)
			(xy 126.583314 -253.008134) (xy 126.639048 -253.006097) (xy 126.694485 -253.012197) (xy 126.748442 -253.026303)
			(xy 126.799771 -253.048115) (xy 126.847377 -253.077169) (xy 126.890245 -253.112844) (xy 126.927462 -253.154381)
			(xy 126.943461 -253.178564) (xy 128.285746 -253.178564) (xy 128.289817 -253.122942) (xy 128.301943 -253.068505)
			(xy 128.321866 -253.016414) (xy 128.349162 -252.967779) (xy 128.383248 -252.923636) (xy 128.423397 -252.884927)
			(xy 128.468755 -252.852476) (xy 128.518355 -252.826975) (xy 128.571139 -252.808968) (xy 128.625982 -252.798838)
			(xy 128.681716 -252.796801) (xy 128.737153 -252.802901) (xy 128.79111 -252.817007) (xy 128.842439 -252.838819)
			(xy 128.890045 -252.867873) (xy 128.932913 -252.903548) (xy 128.97013 -252.945085) (xy 129.000903 -252.991598)
			(xy 129.024575 -253.042095) (xy 129.040643 -253.095502) (xy 129.048763 -253.150678) (xy 129.049272 -253.178564)
			(xy 130.349242 -253.178564) (xy 130.353313 -253.122942) (xy 130.365439 -253.068505) (xy 130.385362 -253.016414)
			(xy 130.412658 -252.967779) (xy 130.446744 -252.923636) (xy 130.486893 -252.884927) (xy 130.532251 -252.852476)
			(xy 130.581851 -252.826975) (xy 130.634635 -252.808968) (xy 130.689478 -252.798838) (xy 130.745212 -252.796801)
			(xy 130.800649 -252.802901) (xy 130.854606 -252.817007) (xy 130.905935 -252.838819) (xy 130.953541 -252.867873)
			(xy 130.996409 -252.903548) (xy 131.033626 -252.945085) (xy 131.064399 -252.991598) (xy 131.088071 -253.042095)
			(xy 131.104139 -253.095502) (xy 131.112259 -253.150678) (xy 131.112768 -253.178564) (xy 131.112259 -253.20645)
			(xy 131.104139 -253.261626) (xy 131.088071 -253.315033) (xy 131.064399 -253.36553) (xy 131.033626 -253.412043)
			(xy 130.996409 -253.45358) (xy 130.953541 -253.489255) (xy 130.905935 -253.518309) (xy 130.854606 -253.540121)
			(xy 130.800649 -253.554227) (xy 130.745212 -253.560327) (xy 130.689478 -253.55829) (xy 130.634635 -253.54816)
			(xy 130.581851 -253.530153) (xy 130.532251 -253.504652) (xy 130.486893 -253.472201) (xy 130.446744 -253.433492)
			(xy 130.412658 -253.389349) (xy 130.385362 -253.340714) (xy 130.365439 -253.288623) (xy 130.353313 -253.234186)
			(xy 130.349242 -253.178564) (xy 129.049272 -253.178564) (xy 129.048763 -253.20645) (xy 129.040643 -253.261626)
			(xy 129.024575 -253.315033) (xy 129.000903 -253.36553) (xy 128.97013 -253.412043) (xy 128.932913 -253.45358)
			(xy 128.890045 -253.489255) (xy 128.842439 -253.518309) (xy 128.79111 -253.540121) (xy 128.737153 -253.554227)
			(xy 128.681716 -253.560327) (xy 128.625982 -253.55829) (xy 128.571139 -253.54816) (xy 128.518355 -253.530153)
			(xy 128.468755 -253.504652) (xy 128.423397 -253.472201) (xy 128.383248 -253.433492) (xy 128.349162 -253.389349)
			(xy 128.321866 -253.340714) (xy 128.301943 -253.288623) (xy 128.289817 -253.234186) (xy 128.285746 -253.178564)
			(xy 126.943461 -253.178564) (xy 126.958235 -253.200894) (xy 126.981907 -253.251391) (xy 126.997975 -253.304798)
			(xy 127.006095 -253.359974) (xy 127.006604 -253.38786) (xy 127.006095 -253.415746) (xy 126.997975 -253.470922)
			(xy 126.981907 -253.524329) (xy 126.958235 -253.574826) (xy 126.927462 -253.621339) (xy 126.890245 -253.662876)
			(xy 126.847377 -253.698551) (xy 126.799771 -253.727605) (xy 126.748442 -253.749417) (xy 126.694485 -253.763523)
			(xy 126.639048 -253.769623) (xy 126.583314 -253.767586) (xy 126.528471 -253.757456) (xy 126.475687 -253.739449)
			(xy 126.426087 -253.713948) (xy 126.380729 -253.681497) (xy 126.34058 -253.642788) (xy 126.306494 -253.598645)
			(xy 126.279198 -253.55001) (xy 126.259275 -253.497919) (xy 126.247149 -253.443482) (xy 126.243078 -253.38786)
			(xy 118.962459 -253.38786) (xy 118.927911 -253.416611) (xy 118.880305 -253.445665) (xy 118.828976 -253.467477)
			(xy 118.775019 -253.481583) (xy 118.719582 -253.487683) (xy 118.663848 -253.485646) (xy 118.609005 -253.475516)
			(xy 118.556221 -253.457509) (xy 118.506621 -253.432008) (xy 118.461263 -253.399557) (xy 118.421114 -253.360848)
			(xy 118.387028 -253.316705) (xy 118.359732 -253.26807) (xy 118.339809 -253.215979) (xy 118.327683 -253.161542)
			(xy 118.323612 -253.10592) (xy 109.65053 -253.10592) (xy 108.592112 -254.164338) (xy 117.675912 -254.164338)
			(xy 117.679983 -254.108716) (xy 117.692109 -254.054279) (xy 117.712032 -254.002188) (xy 117.739328 -253.953553)
			(xy 117.773414 -253.90941) (xy 117.813563 -253.870701) (xy 117.858921 -253.83825) (xy 117.908521 -253.812749)
			(xy 117.961305 -253.794742) (xy 118.016148 -253.784612) (xy 118.071882 -253.782575) (xy 118.127319 -253.788675)
			(xy 118.181276 -253.802781) (xy 118.232605 -253.824593) (xy 118.280211 -253.853647) (xy 118.323079 -253.889322)
			(xy 118.360296 -253.930859) (xy 118.391069 -253.977372) (xy 118.394651 -253.985014) (xy 121.718576 -253.985014)
			(xy 121.722647 -253.929392) (xy 121.734773 -253.874955) (xy 121.754696 -253.822864) (xy 121.781992 -253.774229)
			(xy 121.816078 -253.730086) (xy 121.856227 -253.691377) (xy 121.901585 -253.658926) (xy 121.951185 -253.633425)
			(xy 122.003969 -253.615418) (xy 122.058812 -253.605288) (xy 122.114546 -253.603251) (xy 122.169983 -253.609351)
			(xy 122.22394 -253.623457) (xy 122.275269 -253.645269) (xy 122.322875 -253.674323) (xy 122.365743 -253.709998)
			(xy 122.40296 -253.751535) (xy 122.433733 -253.798048) (xy 122.457405 -253.848545) (xy 122.473473 -253.901952)
			(xy 122.481593 -253.957128) (xy 122.482102 -253.985014) (xy 122.481593 -254.0129) (xy 122.473473 -254.068076)
			(xy 122.457405 -254.121483) (xy 122.433733 -254.17198) (xy 122.418791 -254.194564) (xy 130.317746 -254.194564)
			(xy 130.321817 -254.138942) (xy 130.333943 -254.084505) (xy 130.353866 -254.032414) (xy 130.381162 -253.983779)
			(xy 130.415248 -253.939636) (xy 130.455397 -253.900927) (xy 130.500755 -253.868476) (xy 130.550355 -253.842975)
			(xy 130.603139 -253.824968) (xy 130.657982 -253.814838) (xy 130.713716 -253.812801) (xy 130.769153 -253.818901)
			(xy 130.82311 -253.833007) (xy 130.874439 -253.854819) (xy 130.922045 -253.883873) (xy 130.964913 -253.919548)
			(xy 131.00213 -253.961085) (xy 131.032903 -254.007598) (xy 131.056575 -254.058095) (xy 131.072643 -254.111502)
			(xy 131.080763 -254.166678) (xy 131.081272 -254.194564) (xy 131.080763 -254.22245) (xy 131.072643 -254.277626)
			(xy 131.056575 -254.331033) (xy 131.032903 -254.38153) (xy 131.00213 -254.428043) (xy 130.964913 -254.46958)
			(xy 130.922045 -254.505255) (xy 130.874439 -254.534309) (xy 130.82311 -254.556121) (xy 130.769153 -254.570227)
			(xy 130.713716 -254.576327) (xy 130.657982 -254.57429) (xy 130.603139 -254.56416) (xy 130.550355 -254.546153)
			(xy 130.500755 -254.520652) (xy 130.455397 -254.488201) (xy 130.415248 -254.449492) (xy 130.381162 -254.405349)
			(xy 130.353866 -254.356714) (xy 130.333943 -254.304623) (xy 130.321817 -254.250186) (xy 130.317746 -254.194564)
			(xy 122.418791 -254.194564) (xy 122.40296 -254.218493) (xy 122.365743 -254.26003) (xy 122.322875 -254.295705)
			(xy 122.275269 -254.324759) (xy 122.22394 -254.346571) (xy 122.169983 -254.360677) (xy 122.114546 -254.366777)
			(xy 122.058812 -254.36474) (xy 122.003969 -254.35461) (xy 121.951185 -254.336603) (xy 121.901585 -254.311102)
			(xy 121.856227 -254.278651) (xy 121.816078 -254.239942) (xy 121.781992 -254.195799) (xy 121.754696 -254.147164)
			(xy 121.734773 -254.095073) (xy 121.722647 -254.040636) (xy 121.718576 -253.985014) (xy 118.394651 -253.985014)
			(xy 118.414741 -254.027869) (xy 118.430809 -254.081276) (xy 118.438929 -254.136452) (xy 118.439438 -254.164338)
			(xy 118.438929 -254.192224) (xy 118.430809 -254.2474) (xy 118.414741 -254.300807) (xy 118.391069 -254.351304)
			(xy 118.360296 -254.397817) (xy 118.323079 -254.439354) (xy 118.280211 -254.475029) (xy 118.232605 -254.504083)
			(xy 118.181276 -254.525895) (xy 118.127319 -254.540001) (xy 118.071882 -254.546101) (xy 118.016148 -254.544064)
			(xy 117.961305 -254.533934) (xy 117.908521 -254.515927) (xy 117.858921 -254.490426) (xy 117.813563 -254.457975)
			(xy 117.773414 -254.419266) (xy 117.739328 -254.375123) (xy 117.712032 -254.326488) (xy 117.692109 -254.274397)
			(xy 117.679983 -254.21996) (xy 117.675912 -254.164338) (xy 108.592112 -254.164338) (xy 107.518594 -255.237856)
			(xy 114.069019 -255.237856) (xy 114.069019 -255.183344) (xy 114.076777 -255.129387) (xy 114.092135 -255.077083)
			(xy 114.114781 -255.027497) (xy 114.144253 -254.981639) (xy 114.179952 -254.940442) (xy 114.22115 -254.904745)
			(xy 114.267009 -254.875274) (xy 114.316596 -254.85263) (xy 114.3689 -254.837274) (xy 114.422858 -254.829518)
			(xy 114.450114 -254.829056) (xy 114.481487 -254.829688) (xy 114.543386 -254.839967) (xy 114.602771 -254.860231)
			(xy 114.630708 -254.874522) (xy 114.64036 -254.879602) (xy 114.662204 -254.881126) (xy 114.754406 -254.846582)
			(xy 114.7699 -254.831342) (xy 114.77371 -254.820928) (xy 114.784422 -254.794132) (xy 114.812718 -254.743841)
			(xy 114.848266 -254.698384) (xy 114.890253 -254.6588) (xy 114.937724 -254.62599) (xy 114.989594 -254.600704)
			(xy 115.044681 -254.583519) (xy 115.101727 -254.574825) (xy 115.13058 -254.574294) (xy 115.157834 -254.574752)
			(xy 115.211787 -254.582507) (xy 115.264088 -254.597861) (xy 115.313671 -254.620503) (xy 115.359527 -254.64997)
			(xy 115.400722 -254.685664) (xy 115.436418 -254.726857) (xy 115.465888 -254.772712) (xy 115.488532 -254.822293)
			(xy 115.503889 -254.874593) (xy 115.511647 -254.928546) (xy 115.511647 -254.983054) (xy 115.503889 -255.037007)
			(xy 115.488532 -255.089307) (xy 115.465888 -255.138888) (xy 115.436418 -255.184743) (xy 115.432972 -255.18872)
			(xy 116.295422 -255.18872) (xy 116.299493 -255.133098) (xy 116.311619 -255.078661) (xy 116.331542 -255.02657)
			(xy 116.358838 -254.977935) (xy 116.392924 -254.933792) (xy 116.433073 -254.895083) (xy 116.478431 -254.862632)
			(xy 116.528031 -254.837131) (xy 116.580815 -254.819124) (xy 116.635658 -254.808994) (xy 116.691392 -254.806957)
			(xy 116.746829 -254.813057) (xy 116.800786 -254.827163) (xy 116.852115 -254.848975) (xy 116.899721 -254.878029)
			(xy 116.942589 -254.913704) (xy 116.979806 -254.955241) (xy 117.010579 -255.001754) (xy 117.034251 -255.052251)
			(xy 117.050319 -255.105658) (xy 117.051142 -255.11125) (xy 120.99366 -255.11125) (xy 120.997731 -255.055628)
			(xy 121.009857 -255.001191) (xy 121.02978 -254.9491) (xy 121.057076 -254.900465) (xy 121.091162 -254.856322)
			(xy 121.131311 -254.817613) (xy 121.176669 -254.785162) (xy 121.226269 -254.759661) (xy 121.279053 -254.741654)
			(xy 121.333896 -254.731524) (xy 121.38963 -254.729487) (xy 121.445067 -254.735587) (xy 121.499024 -254.749693)
			(xy 121.550353 -254.771505) (xy 121.597959 -254.800559) (xy 121.640827 -254.836234) (xy 121.678044 -254.877771)
			(xy 121.708817 -254.924284) (xy 121.732489 -254.974781) (xy 121.748557 -255.028188) (xy 121.756677 -255.083364)
			(xy 121.757186 -255.11125) (xy 121.756677 -255.139136) (xy 121.748557 -255.194312) (xy 121.743667 -255.210564)
			(xy 130.349242 -255.210564) (xy 130.353313 -255.154942) (xy 130.365439 -255.100505) (xy 130.385362 -255.048414)
			(xy 130.412658 -254.999779) (xy 130.446744 -254.955636) (xy 130.486893 -254.916927) (xy 130.532251 -254.884476)
			(xy 130.581851 -254.858975) (xy 130.634635 -254.840968) (xy 130.689478 -254.830838) (xy 130.745212 -254.828801)
			(xy 130.800649 -254.834901) (xy 130.854606 -254.849007) (xy 130.905935 -254.870819) (xy 130.953541 -254.899873)
			(xy 130.996409 -254.935548) (xy 131.033626 -254.977085) (xy 131.064399 -255.023598) (xy 131.088071 -255.074095)
			(xy 131.104139 -255.127502) (xy 131.112259 -255.182678) (xy 131.112768 -255.210564) (xy 131.112259 -255.23845)
			(xy 131.104139 -255.293626) (xy 131.088071 -255.347033) (xy 131.064399 -255.39753) (xy 131.033626 -255.444043)
			(xy 130.996409 -255.48558) (xy 130.953541 -255.521255) (xy 130.905935 -255.550309) (xy 130.854606 -255.572121)
			(xy 130.800649 -255.586227) (xy 130.745212 -255.592327) (xy 130.689478 -255.59029) (xy 130.634635 -255.58016)
			(xy 130.581851 -255.562153) (xy 130.532251 -255.536652) (xy 130.486893 -255.504201) (xy 130.446744 -255.465492)
			(xy 130.412658 -255.421349) (xy 130.385362 -255.372714) (xy 130.365439 -255.320623) (xy 130.353313 -255.266186)
			(xy 130.349242 -255.210564) (xy 121.743667 -255.210564) (xy 121.732489 -255.247719) (xy 121.708817 -255.298216)
			(xy 121.678044 -255.344729) (xy 121.640827 -255.386266) (xy 121.597959 -255.421941) (xy 121.550353 -255.450995)
			(xy 121.499024 -255.472807) (xy 121.445067 -255.486913) (xy 121.38963 -255.493013) (xy 121.333896 -255.490976)
			(xy 121.279053 -255.480846) (xy 121.226269 -255.462839) (xy 121.176669 -255.437338) (xy 121.131311 -255.404887)
			(xy 121.091162 -255.366178) (xy 121.057076 -255.322035) (xy 121.02978 -255.2734) (xy 121.009857 -255.221309)
			(xy 120.997731 -255.166872) (xy 120.99366 -255.11125) (xy 117.051142 -255.11125) (xy 117.058439 -255.160834)
			(xy 117.058948 -255.18872) (xy 117.058439 -255.216606) (xy 117.050319 -255.271782) (xy 117.034251 -255.325189)
			(xy 117.010579 -255.375686) (xy 116.979806 -255.422199) (xy 116.942589 -255.463736) (xy 116.899721 -255.499411)
			(xy 116.852115 -255.528465) (xy 116.800786 -255.550277) (xy 116.746829 -255.564383) (xy 116.691392 -255.570483)
			(xy 116.635658 -255.568446) (xy 116.580815 -255.558316) (xy 116.528031 -255.540309) (xy 116.478431 -255.514808)
			(xy 116.433073 -255.482357) (xy 116.392924 -255.443648) (xy 116.358838 -255.399505) (xy 116.331542 -255.35087)
			(xy 116.311619 -255.298779) (xy 116.299493 -255.244342) (xy 116.295422 -255.18872) (xy 115.432972 -255.18872)
			(xy 115.400722 -255.225936) (xy 115.359527 -255.26163) (xy 115.313671 -255.291097) (xy 115.264088 -255.313739)
			(xy 115.211787 -255.329093) (xy 115.157834 -255.336848) (xy 115.13058 -255.33731) (xy 115.099206 -255.336685)
			(xy 115.037307 -255.326403) (xy 114.977922 -255.306137) (xy 114.949986 -255.291844) (xy 114.940334 -255.286764)
			(xy 114.91849 -255.28524) (xy 114.826288 -255.319784) (xy 114.810794 -255.335024) (xy 114.806984 -255.345438)
			(xy 114.796259 -255.372229) (xy 114.767966 -255.422521) (xy 114.732422 -255.467979) (xy 114.690436 -255.507565)
			(xy 114.642967 -255.540375) (xy 114.591098 -255.565662) (xy 114.536012 -255.582848) (xy 114.478966 -255.591541)
			(xy 114.450114 -255.592072) (xy 114.422858 -255.591682) (xy 114.3689 -255.583926) (xy 114.316596 -255.56857)
			(xy 114.267009 -255.545926) (xy 114.22115 -255.516455) (xy 114.179952 -255.480758) (xy 114.144253 -255.439561)
			(xy 114.114781 -255.393703) (xy 114.092135 -255.344117) (xy 114.076777 -255.291813) (xy 114.069019 -255.237856)
			(xy 107.518594 -255.237856) (xy 106.529886 -256.226564) (xy 126.220472 -256.226564) (xy 126.224543 -256.170942)
			(xy 126.236669 -256.116505) (xy 126.256592 -256.064414) (xy 126.283888 -256.015779) (xy 126.317974 -255.971636)
			(xy 126.358123 -255.932927) (xy 126.403481 -255.900476) (xy 126.453081 -255.874975) (xy 126.505865 -255.856968)
			(xy 126.560708 -255.846838) (xy 126.616442 -255.844801) (xy 126.671879 -255.850901) (xy 126.725836 -255.865007)
			(xy 126.777165 -255.886819) (xy 126.824771 -255.915873) (xy 126.867639 -255.951548) (xy 126.904856 -255.993085)
			(xy 126.935629 -256.039598) (xy 126.959301 -256.090095) (xy 126.975369 -256.143502) (xy 126.983489 -256.198678)
			(xy 126.983998 -256.226564) (xy 128.285746 -256.226564) (xy 128.289817 -256.170942) (xy 128.301943 -256.116505)
			(xy 128.321866 -256.064414) (xy 128.349162 -256.015779) (xy 128.383248 -255.971636) (xy 128.423397 -255.932927)
			(xy 128.468755 -255.900476) (xy 128.518355 -255.874975) (xy 128.571139 -255.856968) (xy 128.625982 -255.846838)
			(xy 128.681716 -255.844801) (xy 128.737153 -255.850901) (xy 128.79111 -255.865007) (xy 128.842439 -255.886819)
			(xy 128.890045 -255.915873) (xy 128.932913 -255.951548) (xy 128.97013 -255.993085) (xy 129.000903 -256.039598)
			(xy 129.024575 -256.090095) (xy 129.040643 -256.143502) (xy 129.048763 -256.198678) (xy 129.049272 -256.226564)
			(xy 129.048763 -256.25445) (xy 129.040643 -256.309626) (xy 129.024575 -256.363033) (xy 129.000903 -256.41353)
			(xy 128.97013 -256.460043) (xy 128.932913 -256.50158) (xy 128.890045 -256.537255) (xy 128.842439 -256.566309)
			(xy 128.79111 -256.588121) (xy 128.737153 -256.602227) (xy 128.681716 -256.608327) (xy 128.625982 -256.60629)
			(xy 128.571139 -256.59616) (xy 128.518355 -256.578153) (xy 128.468755 -256.552652) (xy 128.423397 -256.520201)
			(xy 128.383248 -256.481492) (xy 128.349162 -256.437349) (xy 128.321866 -256.388714) (xy 128.301943 -256.336623)
			(xy 128.289817 -256.282186) (xy 128.285746 -256.226564) (xy 126.983998 -256.226564) (xy 126.983489 -256.25445)
			(xy 126.975369 -256.309626) (xy 126.959301 -256.363033) (xy 126.935629 -256.41353) (xy 126.904856 -256.460043)
			(xy 126.867639 -256.50158) (xy 126.824771 -256.537255) (xy 126.777165 -256.566309) (xy 126.725836 -256.588121)
			(xy 126.671879 -256.602227) (xy 126.616442 -256.608327) (xy 126.560708 -256.60629) (xy 126.505865 -256.59616)
			(xy 126.453081 -256.578153) (xy 126.403481 -256.552652) (xy 126.358123 -256.520201) (xy 126.317974 -256.481492)
			(xy 126.283888 -256.437349) (xy 126.256592 -256.388714) (xy 126.236669 -256.336623) (xy 126.224543 -256.282186)
			(xy 126.220472 -256.226564) (xy 106.529886 -256.226564) (xy 105.6259 -257.13055) (xy 116.295422 -257.13055)
			(xy 116.299493 -257.074928) (xy 116.311619 -257.020491) (xy 116.331542 -256.9684) (xy 116.358838 -256.919765)
			(xy 116.392924 -256.875622) (xy 116.433073 -256.836913) (xy 116.478431 -256.804462) (xy 116.528031 -256.778961)
			(xy 116.580815 -256.760954) (xy 116.635658 -256.750824) (xy 116.691392 -256.748787) (xy 116.746829 -256.754887)
			(xy 116.800786 -256.768993) (xy 116.852115 -256.790805) (xy 116.899721 -256.819859) (xy 116.942589 -256.855534)
			(xy 116.979806 -256.897071) (xy 117.010579 -256.943584) (xy 117.034251 -256.994081) (xy 117.050319 -257.047488)
			(xy 117.058439 -257.102664) (xy 117.058674 -257.115564) (xy 128.285746 -257.115564) (xy 128.289817 -257.059942)
			(xy 128.301943 -257.005505) (xy 128.321866 -256.953414) (xy 128.349162 -256.904779) (xy 128.383248 -256.860636)
			(xy 128.423397 -256.821927) (xy 128.468755 -256.789476) (xy 128.518355 -256.763975) (xy 128.571139 -256.745968)
			(xy 128.625982 -256.735838) (xy 128.681716 -256.733801) (xy 128.737153 -256.739901) (xy 128.79111 -256.754007)
			(xy 128.842439 -256.775819) (xy 128.890045 -256.804873) (xy 128.932913 -256.840548) (xy 128.97013 -256.882085)
			(xy 129.000903 -256.928598) (xy 129.024575 -256.979095) (xy 129.040643 -257.032502) (xy 129.048763 -257.087678)
			(xy 129.049272 -257.115564) (xy 129.048763 -257.14345) (xy 129.040643 -257.198626) (xy 129.024575 -257.252033)
			(xy 129.000903 -257.30253) (xy 128.97013 -257.349043) (xy 128.932913 -257.39058) (xy 128.890045 -257.426255)
			(xy 128.842439 -257.455309) (xy 128.79111 -257.477121) (xy 128.737153 -257.491227) (xy 128.681716 -257.497327)
			(xy 128.625982 -257.49529) (xy 128.571139 -257.48516) (xy 128.518355 -257.467153) (xy 128.468755 -257.441652)
			(xy 128.423397 -257.409201) (xy 128.383248 -257.370492) (xy 128.349162 -257.326349) (xy 128.321866 -257.277714)
			(xy 128.301943 -257.225623) (xy 128.289817 -257.171186) (xy 128.285746 -257.115564) (xy 117.058674 -257.115564)
			(xy 117.058948 -257.13055) (xy 117.058439 -257.158436) (xy 117.050319 -257.213612) (xy 117.034251 -257.267019)
			(xy 117.010579 -257.317516) (xy 116.979806 -257.364029) (xy 116.942589 -257.405566) (xy 116.899721 -257.441241)
			(xy 116.852115 -257.470295) (xy 116.800786 -257.492107) (xy 116.746829 -257.506213) (xy 116.691392 -257.512313)
			(xy 116.635658 -257.510276) (xy 116.580815 -257.500146) (xy 116.528031 -257.482139) (xy 116.478431 -257.456638)
			(xy 116.433073 -257.424187) (xy 116.392924 -257.385478) (xy 116.358838 -257.341335) (xy 116.331542 -257.2927)
			(xy 116.311619 -257.240609) (xy 116.299493 -257.186172) (xy 116.295422 -257.13055) (xy 105.6259 -257.13055)
			(xy 103.832914 -258.923536) (xy 108.0897 -258.923536) (xy 108.090164 -258.896092) (xy 108.098019 -258.841769)
			(xy 108.113586 -258.789134) (xy 108.136543 -258.739277) (xy 108.166414 -258.693229) (xy 108.202583 -258.651943)
			(xy 108.2443 -258.616273) (xy 108.267246 -258.60121) (xy 108.278168 -258.594098) (xy 108.290868 -258.571492)
			(xy 108.29163 -258.46024) (xy 108.279438 -258.43738) (xy 108.26877 -258.430268) (xy 108.24645 -258.415055)
			(xy 108.205883 -258.379395) (xy 108.170755 -258.338366) (xy 108.141768 -258.292791) (xy 108.119503 -258.243581)
			(xy 108.104405 -258.191721) (xy 108.096776 -258.13825) (xy 108.096304 -258.111244) (xy 108.096796 -258.083992)
			(xy 108.104548 -258.030041) (xy 108.119899 -257.977743) (xy 108.142537 -257.928162) (xy 108.172001 -257.882308)
			(xy 108.207692 -257.841115) (xy 108.248883 -257.805421) (xy 108.294734 -257.775952) (xy 108.344313 -257.75331)
			(xy 108.39661 -257.737954) (xy 108.45056 -257.730199) (xy 108.477812 -257.729736) (xy 108.504128 -257.73019)
			(xy 108.556263 -257.737408) (xy 108.606911 -257.75172) (xy 108.655113 -257.772855) (xy 108.699955 -257.80041)
			(xy 108.740587 -257.833865) (xy 108.758736 -257.852926) (xy 108.766252 -257.860335) (xy 108.785536 -257.868858)
			(xy 108.796074 -257.869436) (xy 108.87075 -257.869436) (xy 108.881297 -257.868883) (xy 108.900591 -257.860363)
			(xy 108.908088 -257.852926) (xy 108.926234 -257.833857) (xy 108.966851 -257.800377) (xy 109.011689 -257.772805)
			(xy 109.059895 -257.751664) (xy 109.11055 -257.737358) (xy 109.162693 -257.730158) (xy 109.189012 -257.729736)
			(xy 109.215328 -257.73019) (xy 109.267463 -257.737408) (xy 109.318111 -257.75172) (xy 109.366313 -257.772855)
			(xy 109.411155 -257.80041) (xy 109.451787 -257.833865) (xy 109.469936 -257.852926) (xy 109.477452 -257.860335)
			(xy 109.496736 -257.868858) (xy 109.507274 -257.869436) (xy 109.58195 -257.869436) (xy 109.592497 -257.868883)
			(xy 109.611791 -257.860363) (xy 109.619288 -257.852926) (xy 109.637434 -257.833857) (xy 109.678051 -257.800377)
			(xy 109.722889 -257.772805) (xy 109.771095 -257.751664) (xy 109.82175 -257.737358) (xy 109.873893 -257.730158)
			(xy 109.900212 -257.729736) (xy 109.927467 -257.730144) (xy 109.981422 -257.737904) (xy 110.033724 -257.753263)
			(xy 110.083307 -257.775911) (xy 110.129162 -257.805384) (xy 110.170356 -257.841083) (xy 110.20605 -257.882282)
			(xy 110.235516 -257.928142) (xy 110.258156 -257.977728) (xy 110.270431 -258.01955) (xy 116.422932 -258.01955)
			(xy 116.423402 -257.992297) (xy 116.431153 -257.938344) (xy 116.446505 -257.886044) (xy 116.469144 -257.836461)
			(xy 116.498611 -257.790606) (xy 116.534304 -257.749411) (xy 116.575498 -257.713717) (xy 116.621352 -257.684249)
			(xy 116.670934 -257.661608) (xy 116.723234 -257.646255) (xy 116.777187 -257.638503) (xy 116.80444 -257.638042)
			(xy 116.831497 -257.638464) (xy 116.885066 -257.646128) (xy 116.937014 -257.661283) (xy 116.986301 -257.683624)
			(xy 117.031938 -257.712704) (xy 117.073009 -257.747939) (xy 117.108691 -257.788623) (xy 117.138267 -257.833939)
			(xy 117.150134 -257.85826) (xy 117.154198 -257.866642) (xy 117.167406 -257.879596) (xy 117.246908 -257.913886)
			(xy 117.26545 -257.914648) (xy 117.27434 -257.9116) (xy 117.30367 -257.902497) (xy 117.364286 -257.892662)
			(xy 117.39499 -257.892042) (xy 117.422247 -257.892404) (xy 117.476206 -257.900161) (xy 117.528512 -257.915518)
			(xy 117.5781 -257.938163) (xy 117.62396 -257.967635) (xy 117.66516 -258.003333) (xy 117.700859 -258.044532)
			(xy 117.730332 -258.090391) (xy 117.749135 -258.131564) (xy 126.258572 -258.131564) (xy 126.262643 -258.075942)
			(xy 126.274769 -258.021505) (xy 126.294692 -257.969414) (xy 126.321988 -257.920779) (xy 126.356074 -257.876636)
			(xy 126.396223 -257.837927) (xy 126.441581 -257.805476) (xy 126.491181 -257.779975) (xy 126.543965 -257.761968)
			(xy 126.598808 -257.751838) (xy 126.654542 -257.749801) (xy 126.709979 -257.755901) (xy 126.763936 -257.770007)
			(xy 126.815265 -257.791819) (xy 126.862871 -257.820873) (xy 126.905739 -257.856548) (xy 126.942956 -257.898085)
			(xy 126.973729 -257.944598) (xy 126.997401 -257.995095) (xy 127.013469 -258.048502) (xy 127.021589 -258.103678)
			(xy 127.022098 -258.131564) (xy 127.021589 -258.15945) (xy 127.013469 -258.214626) (xy 126.997401 -258.268033)
			(xy 126.973729 -258.31853) (xy 126.942956 -258.365043) (xy 126.905739 -258.40658) (xy 126.862871 -258.442255)
			(xy 126.815265 -258.471309) (xy 126.763936 -258.493121) (xy 126.709979 -258.507227) (xy 126.654542 -258.513327)
			(xy 126.598808 -258.51129) (xy 126.543965 -258.50116) (xy 126.491181 -258.483153) (xy 126.441581 -258.457652)
			(xy 126.396223 -258.425201) (xy 126.356074 -258.386492) (xy 126.321988 -258.342349) (xy 126.294692 -258.293714)
			(xy 126.274769 -258.241623) (xy 126.262643 -258.187186) (xy 126.258572 -258.131564) (xy 117.749135 -258.131564)
			(xy 117.752978 -258.139979) (xy 117.768337 -258.192284) (xy 117.776095 -258.246243) (xy 117.776095 -258.300757)
			(xy 117.768337 -258.354716) (xy 117.752978 -258.407021) (xy 117.730332 -258.456609) (xy 117.700859 -258.502468)
			(xy 117.66516 -258.543667) (xy 117.62396 -258.579365) (xy 117.5781 -258.608837) (xy 117.528512 -258.631482)
			(xy 117.476206 -258.646839) (xy 117.422247 -258.654596) (xy 117.39499 -258.655058) (xy 117.374442 -258.654758)
			(xy 117.333586 -258.650305) (xy 117.313456 -258.646168) (xy 117.301518 -258.643628) (xy 117.27815 -258.649724)
			(xy 117.198394 -258.720336) (xy 117.189504 -258.742688) (xy 117.19052 -258.75488) (xy 117.192298 -258.79044)
			(xy 117.191812 -258.817691) (xy 117.184056 -258.871639) (xy 117.168701 -258.923934) (xy 117.146059 -258.973511)
			(xy 117.116593 -259.019361) (xy 117.080902 -259.060552) (xy 117.039711 -259.096243) (xy 116.993861 -259.125709)
			(xy 116.944284 -259.148351) (xy 116.891989 -259.163706) (xy 116.838041 -259.171462) (xy 116.783539 -259.171462)
			(xy 116.729591 -259.163706) (xy 116.677296 -259.148351) (xy 116.627719 -259.125709) (xy 116.581869 -259.096243)
			(xy 116.540678 -259.060552) (xy 116.504987 -259.019361) (xy 116.475521 -258.973511) (xy 116.452879 -258.923934)
			(xy 116.437524 -258.871639) (xy 116.429768 -258.817691) (xy 116.429282 -258.79044) (xy 116.429857 -258.761315)
			(xy 116.438719 -258.703744) (xy 116.456227 -258.648188) (xy 116.481976 -258.595939) (xy 116.515366 -258.548209)
			(xy 116.555622 -258.506109) (xy 116.57838 -258.487926) (xy 116.587778 -258.48056) (xy 116.598192 -258.459224)
			(xy 116.59743 -258.354068) (xy 116.586762 -258.332986) (xy 116.576856 -258.325874) (xy 116.553429 -258.307703)
			(xy 116.511899 -258.265397) (xy 116.477407 -258.21718) (xy 116.450783 -258.16421) (xy 116.432668 -258.107762)
			(xy 116.423496 -258.049192) (xy 116.422932 -258.01955) (xy 110.270431 -258.01955) (xy 110.273508 -258.030032)
			(xy 110.28126 -258.083989) (xy 110.28172 -258.111244) (xy 110.281231 -258.138687) (xy 110.273379 -258.193009)
			(xy 110.257816 -258.245642) (xy 110.234863 -258.295499) (xy 110.204996 -258.341547) (xy 110.168831 -258.382834)
			(xy 110.127118 -258.418506) (xy 110.104174 -258.43357) (xy 110.093252 -258.440682) (xy 110.080552 -258.463288)
			(xy 110.07979 -258.57454) (xy 110.091982 -258.5974) (xy 110.10265 -258.604512) (xy 110.124965 -258.619731)
			(xy 110.165531 -258.655391) (xy 110.200659 -258.696419) (xy 110.229646 -258.741994) (xy 110.251912 -258.791202)
			(xy 110.267012 -258.84306) (xy 110.274642 -258.89653) (xy 110.275116 -258.923536) (xy 110.274656 -258.950788)
			(xy 110.266894 -259.004736) (xy 110.262245 -259.020564) (xy 112.290096 -259.020564) (xy 112.294167 -258.964942)
			(xy 112.306293 -258.910505) (xy 112.326216 -258.858414) (xy 112.353512 -258.809779) (xy 112.387598 -258.765636)
			(xy 112.427747 -258.726927) (xy 112.473105 -258.694476) (xy 112.522705 -258.668975) (xy 112.575489 -258.650968)
			(xy 112.630332 -258.640838) (xy 112.686066 -258.638801) (xy 112.741503 -258.644901) (xy 112.79546 -258.659007)
			(xy 112.846789 -258.680819) (xy 112.894395 -258.709873) (xy 112.937263 -258.745548) (xy 112.97448 -258.787085)
			(xy 113.005253 -258.833598) (xy 113.028925 -258.884095) (xy 113.044993 -258.937502) (xy 113.053113 -258.992678)
			(xy 113.053622 -259.020564) (xy 113.179096 -259.020564) (xy 113.183167 -258.964942) (xy 113.195293 -258.910505)
			(xy 113.215216 -258.858414) (xy 113.242512 -258.809779) (xy 113.276598 -258.765636) (xy 113.316747 -258.726927)
			(xy 113.362105 -258.694476) (xy 113.411705 -258.668975) (xy 113.464489 -258.650968) (xy 113.519332 -258.640838)
			(xy 113.575066 -258.638801) (xy 113.630503 -258.644901) (xy 113.68446 -258.659007) (xy 113.735789 -258.680819)
			(xy 113.783395 -258.709873) (xy 113.826263 -258.745548) (xy 113.86348 -258.787085) (xy 113.894253 -258.833598)
			(xy 113.917925 -258.884095) (xy 113.933993 -258.937502) (xy 113.942113 -258.992678) (xy 113.942622 -259.020564)
			(xy 113.942113 -259.04845) (xy 113.933993 -259.103626) (xy 113.917925 -259.157033) (xy 113.894253 -259.20753)
			(xy 113.86348 -259.254043) (xy 113.826263 -259.29558) (xy 113.783395 -259.331255) (xy 113.735789 -259.360309)
			(xy 113.68446 -259.382121) (xy 113.630503 -259.396227) (xy 113.575066 -259.402327) (xy 113.519332 -259.40029)
			(xy 113.464489 -259.39016) (xy 113.411705 -259.372153) (xy 113.362105 -259.346652) (xy 113.316747 -259.314201)
			(xy 113.276598 -259.275492) (xy 113.242512 -259.231349) (xy 113.215216 -259.182714) (xy 113.195293 -259.130623)
			(xy 113.183167 -259.076186) (xy 113.179096 -259.020564) (xy 113.053622 -259.020564) (xy 113.053113 -259.04845)
			(xy 113.044993 -259.103626) (xy 113.028925 -259.157033) (xy 113.005253 -259.20753) (xy 112.97448 -259.254043)
			(xy 112.937263 -259.29558) (xy 112.894395 -259.331255) (xy 112.846789 -259.360309) (xy 112.79546 -259.382121)
			(xy 112.741503 -259.396227) (xy 112.686066 -259.402327) (xy 112.630332 -259.40029) (xy 112.575489 -259.39016)
			(xy 112.522705 -259.372153) (xy 112.473105 -259.346652) (xy 112.427747 -259.314201) (xy 112.387598 -259.275492)
			(xy 112.353512 -259.231349) (xy 112.326216 -259.182714) (xy 112.306293 -259.130623) (xy 112.294167 -259.076186)
			(xy 112.290096 -259.020564) (xy 110.262245 -259.020564) (xy 110.251535 -259.057031) (xy 110.22889 -259.106608)
			(xy 110.199421 -259.152457) (xy 110.163727 -259.193647) (xy 110.122535 -259.229338) (xy 110.076683 -259.258804)
			(xy 110.027104 -259.281445) (xy 109.974809 -259.2968) (xy 109.92086 -259.304558) (xy 109.893608 -259.305044)
			(xy 109.867291 -259.304618) (xy 109.815157 -259.29739) (xy 109.764508 -259.283071) (xy 109.716307 -259.261931)
			(xy 109.671466 -259.234372) (xy 109.630834 -259.200915) (xy 109.612684 -259.181854) (xy 109.605163 -259.174451)
			(xy 109.585883 -259.165926) (xy 109.575346 -259.165344) (xy 109.50067 -259.165344) (xy 109.490121 -259.165884)
			(xy 109.470825 -259.17441) (xy 109.463332 -259.181854) (xy 109.445173 -259.200909) (xy 109.404559 -259.234391)
			(xy 109.359724 -259.261966) (xy 109.311521 -259.283109) (xy 109.260867 -259.297418) (xy 109.208726 -259.304621)
			(xy 109.182408 -259.305044) (xy 109.156091 -259.304618) (xy 109.103957 -259.29739) (xy 109.053308 -259.283071)
			(xy 109.005107 -259.261931) (xy 108.960266 -259.234372) (xy 108.919634 -259.200915) (xy 108.901484 -259.181854)
			(xy 108.893963 -259.174451) (xy 108.874683 -259.165926) (xy 108.864146 -259.165344) (xy 108.78947 -259.165344)
			(xy 108.778921 -259.165884) (xy 108.759625 -259.17441) (xy 108.752132 -259.181854) (xy 108.733973 -259.200909)
			(xy 108.693359 -259.234391) (xy 108.648524 -259.261966) (xy 108.600321 -259.283109) (xy 108.549667 -259.297418)
			(xy 108.497526 -259.304621) (xy 108.471208 -259.305044) (xy 108.443959 -259.304515) (xy 108.390014 -259.29676)
			(xy 108.337723 -259.281408) (xy 108.288148 -259.258771) (xy 108.242299 -259.229308) (xy 108.20111 -259.193622)
			(xy 108.165418 -259.152436) (xy 108.135951 -259.106591) (xy 108.113307 -259.057019) (xy 108.097949 -259.004729)
			(xy 108.090188 -258.950785) (xy 108.0897 -258.923536) (xy 103.832914 -258.923536) (xy 103.221028 -259.535422)
			(xy 114.207542 -259.535422) (xy 114.211613 -259.4798) (xy 114.223739 -259.425363) (xy 114.243662 -259.373272)
			(xy 114.270958 -259.324637) (xy 114.305044 -259.280494) (xy 114.345193 -259.241785) (xy 114.390551 -259.209334)
			(xy 114.440151 -259.183833) (xy 114.492935 -259.165826) (xy 114.547778 -259.155696) (xy 114.603512 -259.153659)
			(xy 114.658949 -259.159759) (xy 114.712906 -259.173865) (xy 114.755017 -259.19176) (xy 123.580396 -259.19176)
			(xy 123.584467 -259.136138) (xy 123.596593 -259.081701) (xy 123.616516 -259.02961) (xy 123.643812 -258.980975)
			(xy 123.677898 -258.936832) (xy 123.718047 -258.898123) (xy 123.763405 -258.865672) (xy 123.813005 -258.840171)
			(xy 123.865789 -258.822164) (xy 123.920632 -258.812034) (xy 123.976366 -258.809997) (xy 124.031803 -258.816097)
			(xy 124.08576 -258.830203) (xy 124.137089 -258.852015) (xy 124.184695 -258.881069) (xy 124.227563 -258.916744)
			(xy 124.26478 -258.958281) (xy 124.295553 -259.004794) (xy 124.319225 -259.055291) (xy 124.335293 -259.108698)
			(xy 124.343413 -259.163874) (xy 124.343922 -259.19176) (xy 124.343413 -259.219646) (xy 124.335293 -259.274822)
			(xy 124.319225 -259.328229) (xy 124.295553 -259.378726) (xy 124.26478 -259.425239) (xy 124.227563 -259.466776)
			(xy 124.184695 -259.502451) (xy 124.137089 -259.531505) (xy 124.08576 -259.553317) (xy 124.031803 -259.567423)
			(xy 123.976366 -259.573523) (xy 123.920632 -259.571486) (xy 123.865789 -259.561356) (xy 123.813005 -259.543349)
			(xy 123.763405 -259.517848) (xy 123.718047 -259.485397) (xy 123.677898 -259.446688) (xy 123.643812 -259.402545)
			(xy 123.616516 -259.35391) (xy 123.596593 -259.301819) (xy 123.584467 -259.247382) (xy 123.580396 -259.19176)
			(xy 114.755017 -259.19176) (xy 114.764235 -259.195677) (xy 114.811841 -259.224731) (xy 114.854709 -259.260406)
			(xy 114.891926 -259.301943) (xy 114.922699 -259.348456) (xy 114.946371 -259.398953) (xy 114.962439 -259.45236)
			(xy 114.970559 -259.507536) (xy 114.971068 -259.535422) (xy 114.970559 -259.563308) (xy 114.962439 -259.618484)
			(xy 114.946371 -259.671891) (xy 114.922699 -259.722388) (xy 114.891926 -259.768901) (xy 114.854709 -259.810438)
			(xy 114.811841 -259.846113) (xy 114.764235 -259.875167) (xy 114.712906 -259.896979) (xy 114.658949 -259.911085)
			(xy 114.603512 -259.917185) (xy 114.547778 -259.915148) (xy 114.492935 -259.905018) (xy 114.440151 -259.887011)
			(xy 114.390551 -259.86151) (xy 114.345193 -259.829059) (xy 114.305044 -259.79035) (xy 114.270958 -259.746207)
			(xy 114.243662 -259.697572) (xy 114.223739 -259.645481) (xy 114.211613 -259.591044) (xy 114.207542 -259.535422)
			(xy 103.221028 -259.535422) (xy 102.084886 -260.671564) (xy 112.163096 -260.671564) (xy 112.167167 -260.615942)
			(xy 112.179293 -260.561505) (xy 112.199216 -260.509414) (xy 112.226512 -260.460779) (xy 112.260598 -260.416636)
			(xy 112.300747 -260.377927) (xy 112.346105 -260.345476) (xy 112.395705 -260.319975) (xy 112.448489 -260.301968)
			(xy 112.503332 -260.291838) (xy 112.559066 -260.289801) (xy 112.614503 -260.295901) (xy 112.66846 -260.310007)
			(xy 112.719789 -260.331819) (xy 112.767395 -260.360873) (xy 112.810263 -260.396548) (xy 112.84748 -260.438085)
			(xy 112.878253 -260.484598) (xy 112.901925 -260.535095) (xy 112.917993 -260.588502) (xy 112.926113 -260.643678)
			(xy 112.926622 -260.671564) (xy 112.926113 -260.69945) (xy 112.917993 -260.754626) (xy 112.901925 -260.808033)
			(xy 112.878253 -260.85853) (xy 112.84748 -260.905043) (xy 112.810263 -260.94658) (xy 112.767395 -260.982255)
			(xy 112.719789 -261.011309) (xy 112.66846 -261.033121) (xy 112.614503 -261.047227) (xy 112.559066 -261.053327)
			(xy 112.503332 -261.05129) (xy 112.448489 -261.04116) (xy 112.395705 -261.023153) (xy 112.346105 -260.997652)
			(xy 112.300747 -260.965201) (xy 112.260598 -260.926492) (xy 112.226512 -260.882349) (xy 112.199216 -260.833714)
			(xy 112.179293 -260.781623) (xy 112.167167 -260.727186) (xy 112.163096 -260.671564) (xy 102.084886 -260.671564)
			(xy 101.538786 -261.217664) (xy 114.140232 -261.217664) (xy 114.144303 -261.162042) (xy 114.156429 -261.107605)
			(xy 114.176352 -261.055514) (xy 114.203648 -261.006879) (xy 114.237734 -260.962736) (xy 114.277883 -260.924027)
			(xy 114.323241 -260.891576) (xy 114.372841 -260.866075) (xy 114.425625 -260.848068) (xy 114.480468 -260.837938)
			(xy 114.536202 -260.835901) (xy 114.591639 -260.842001) (xy 114.645596 -260.856107) (xy 114.696925 -260.877919)
			(xy 114.744531 -260.906973) (xy 114.787399 -260.942648) (xy 114.824616 -260.984185) (xy 114.855389 -261.030698)
			(xy 114.879061 -261.081195) (xy 114.895129 -261.134602) (xy 114.903249 -261.189778) (xy 114.903758 -261.217664)
			(xy 114.903249 -261.24555) (xy 114.895129 -261.300726) (xy 114.879061 -261.354133) (xy 114.855389 -261.40463)
			(xy 114.824616 -261.451143) (xy 114.787399 -261.49268) (xy 114.759795 -261.515652) (xy 119.394683 -261.515652)
			(xy 119.394683 -261.461148) (xy 119.402441 -261.407198) (xy 119.417797 -261.354901) (xy 119.44044 -261.305323)
			(xy 119.469909 -261.259471) (xy 119.505604 -261.218281) (xy 119.546797 -261.18259) (xy 119.592651 -261.153125)
			(xy 119.642231 -261.130486) (xy 119.694529 -261.115134) (xy 119.74848 -261.107381) (xy 119.775732 -261.10692)
			(xy 119.804331 -261.107398) (xy 119.860888 -261.115942) (xy 119.915535 -261.132832) (xy 119.967049 -261.157692)
			(xy 120.014274 -261.189963) (xy 120.033402 -261.207758) (xy 131.570982 -261.207758) (xy 131.575053 -261.152136)
			(xy 131.587179 -261.097699) (xy 131.607102 -261.045608) (xy 131.634398 -260.996973) (xy 131.668484 -260.95283)
			(xy 131.708633 -260.914121) (xy 131.753991 -260.88167) (xy 131.803591 -260.856169) (xy 131.856375 -260.838162)
			(xy 131.911218 -260.828032) (xy 131.966952 -260.825995) (xy 132.022389 -260.832095) (xy 132.076346 -260.846201)
			(xy 132.127675 -260.868013) (xy 132.175281 -260.897067) (xy 132.218149 -260.932742) (xy 132.255366 -260.974279)
			(xy 132.286139 -261.020792) (xy 132.309811 -261.071289) (xy 132.325879 -261.124696) (xy 132.333999 -261.179872)
			(xy 132.334508 -261.207758) (xy 132.333999 -261.235644) (xy 132.325879 -261.29082) (xy 132.309811 -261.344227)
			(xy 132.286139 -261.394724) (xy 132.255366 -261.441237) (xy 132.218149 -261.482774) (xy 132.175281 -261.518449)
			(xy 132.127675 -261.547503) (xy 132.076346 -261.569315) (xy 132.022389 -261.583421) (xy 131.966952 -261.589521)
			(xy 131.911218 -261.587484) (xy 131.856375 -261.577354) (xy 131.803591 -261.559347) (xy 131.753991 -261.533846)
			(xy 131.708633 -261.501395) (xy 131.668484 -261.462686) (xy 131.634398 -261.418543) (xy 131.607102 -261.369908)
			(xy 131.587179 -261.317817) (xy 131.575053 -261.26338) (xy 131.570982 -261.207758) (xy 120.033402 -261.207758)
			(xy 120.056152 -261.228922) (xy 120.091745 -261.273697) (xy 120.120256 -261.323283) (xy 120.141044 -261.37657)
			(xy 120.147842 -261.404354) (xy 120.150128 -261.413752) (xy 120.160288 -261.429246) (xy 120.231662 -261.479538)
			(xy 120.249442 -261.48411) (xy 120.259094 -261.483094) (xy 120.270352 -261.481798) (xy 120.292974 -261.480402)
			(xy 120.304306 -261.4803) (xy 120.331558 -261.48077) (xy 120.385506 -261.488528) (xy 120.437801 -261.503884)
			(xy 120.487378 -261.526526) (xy 120.533229 -261.555993) (xy 120.574419 -261.591685) (xy 120.610111 -261.632876)
			(xy 120.639577 -261.678727) (xy 120.662219 -261.728305) (xy 120.677574 -261.7806) (xy 120.682457 -261.814564)
			(xy 130.388104 -261.814564) (xy 130.392175 -261.758942) (xy 130.404301 -261.704505) (xy 130.424224 -261.652414)
			(xy 130.45152 -261.603779) (xy 130.485606 -261.559636) (xy 130.525755 -261.520927) (xy 130.571113 -261.488476)
			(xy 130.620713 -261.462975) (xy 130.673497 -261.444968) (xy 130.72834 -261.434838) (xy 130.784074 -261.432801)
			(xy 130.839511 -261.438901) (xy 130.893468 -261.453007) (xy 130.944797 -261.474819) (xy 130.992403 -261.503873)
			(xy 131.035271 -261.539548) (xy 131.072488 -261.581085) (xy 131.103261 -261.627598) (xy 131.126933 -261.678095)
			(xy 131.143001 -261.731502) (xy 131.151121 -261.786678) (xy 131.15163 -261.814564) (xy 131.151121 -261.84245)
			(xy 131.143001 -261.897626) (xy 131.126933 -261.951033) (xy 131.103261 -262.00153) (xy 131.072488 -262.048043)
			(xy 131.035271 -262.08958) (xy 130.992403 -262.125255) (xy 130.944797 -262.154309) (xy 130.893468 -262.176121)
			(xy 130.839511 -262.190227) (xy 130.784074 -262.196327) (xy 130.72834 -262.19429) (xy 130.673497 -262.18416)
			(xy 130.620713 -262.166153) (xy 130.571113 -262.140652) (xy 130.525755 -262.108201) (xy 130.485606 -262.069492)
			(xy 130.45152 -262.025349) (xy 130.424224 -261.976714) (xy 130.404301 -261.924623) (xy 130.392175 -261.870186)
			(xy 130.388104 -261.814564) (xy 120.682457 -261.814564) (xy 120.68533 -261.834548) (xy 120.68533 -261.889052)
			(xy 120.677574 -261.943) (xy 120.662219 -261.995295) (xy 120.639577 -262.044873) (xy 120.610111 -262.090724)
			(xy 120.574419 -262.131915) (xy 120.533229 -262.167607) (xy 120.487378 -262.197074) (xy 120.437801 -262.219716)
			(xy 120.385506 -262.235072) (xy 120.331558 -262.24283) (xy 120.304306 -262.243316) (xy 120.275709 -262.242776)
			(xy 120.219157 -262.234239) (xy 120.164512 -262.217355) (xy 120.113001 -262.192503) (xy 120.065776 -262.16024)
			(xy 120.023897 -262.121288) (xy 119.988302 -262.076522) (xy 119.959789 -262.026943) (xy 119.938997 -261.973663)
			(xy 119.932196 -261.945882) (xy 119.92991 -261.936484) (xy 119.91975 -261.92099) (xy 119.848376 -261.870698)
			(xy 119.830596 -261.866126) (xy 119.820944 -261.867142) (xy 119.809685 -261.868435) (xy 119.787064 -261.869833)
			(xy 119.775732 -261.869936) (xy 119.74848 -261.869419) (xy 119.694529 -261.861666) (xy 119.642231 -261.846314)
			(xy 119.592651 -261.823675) (xy 119.546797 -261.79421) (xy 119.505604 -261.758519) (xy 119.469909 -261.717329)
			(xy 119.44044 -261.671477) (xy 119.417797 -261.621899) (xy 119.402441 -261.569602) (xy 119.394683 -261.515652)
			(xy 114.759795 -261.515652) (xy 114.744531 -261.528355) (xy 114.696925 -261.557409) (xy 114.645596 -261.579221)
			(xy 114.591639 -261.593327) (xy 114.536202 -261.599427) (xy 114.480468 -261.59739) (xy 114.425625 -261.58726)
			(xy 114.372841 -261.569253) (xy 114.323241 -261.543752) (xy 114.277883 -261.511301) (xy 114.237734 -261.472592)
			(xy 114.203648 -261.428449) (xy 114.176352 -261.379814) (xy 114.156429 -261.327723) (xy 114.144303 -261.273286)
			(xy 114.140232 -261.217664) (xy 101.538786 -261.217664) (xy 100.560886 -262.195564) (xy 116.381782 -262.195564)
			(xy 116.385853 -262.139942) (xy 116.397979 -262.085505) (xy 116.417902 -262.033414) (xy 116.445198 -261.984779)
			(xy 116.479284 -261.940636) (xy 116.519433 -261.901927) (xy 116.564791 -261.869476) (xy 116.614391 -261.843975)
			(xy 116.667175 -261.825968) (xy 116.722018 -261.815838) (xy 116.777752 -261.813801) (xy 116.833189 -261.819901)
			(xy 116.887146 -261.834007) (xy 116.938475 -261.855819) (xy 116.986081 -261.884873) (xy 117.028949 -261.920548)
			(xy 117.066166 -261.962085) (xy 117.096939 -262.008598) (xy 117.120611 -262.059095) (xy 117.136679 -262.112502)
			(xy 117.144799 -262.167678) (xy 117.145308 -262.195564) (xy 117.144799 -262.22345) (xy 117.136679 -262.278626)
			(xy 117.120611 -262.332033) (xy 117.096939 -262.38253) (xy 117.066166 -262.429043) (xy 117.028949 -262.47058)
			(xy 116.986081 -262.506255) (xy 116.938475 -262.535309) (xy 116.887146 -262.557121) (xy 116.833189 -262.571227)
			(xy 116.777752 -262.577327) (xy 116.722018 -262.57529) (xy 116.667175 -262.56516) (xy 116.614391 -262.547153)
			(xy 116.564791 -262.521652) (xy 116.519433 -262.489201) (xy 116.479284 -262.450492) (xy 116.445198 -262.406349)
			(xy 116.417902 -262.357714) (xy 116.397979 -262.305623) (xy 116.385853 -262.251186) (xy 116.381782 -262.195564)
			(xy 100.560886 -262.195564) (xy 100.052886 -262.703564) (xy 112.163096 -262.703564) (xy 112.167167 -262.647942)
			(xy 112.179293 -262.593505) (xy 112.199216 -262.541414) (xy 112.226512 -262.492779) (xy 112.260598 -262.448636)
			(xy 112.300747 -262.409927) (xy 112.346105 -262.377476) (xy 112.395705 -262.351975) (xy 112.448489 -262.333968)
			(xy 112.503332 -262.323838) (xy 112.559066 -262.321801) (xy 112.614503 -262.327901) (xy 112.66846 -262.342007)
			(xy 112.719789 -262.363819) (xy 112.767395 -262.392873) (xy 112.810263 -262.428548) (xy 112.84748 -262.470085)
			(xy 112.878253 -262.516598) (xy 112.901925 -262.567095) (xy 112.906073 -262.580882) (xy 119.152922 -262.580882)
			(xy 119.156993 -262.52526) (xy 119.169119 -262.470823) (xy 119.189042 -262.418732) (xy 119.216338 -262.370097)
			(xy 119.250424 -262.325954) (xy 119.290573 -262.287245) (xy 119.335931 -262.254794) (xy 119.385531 -262.229293)
			(xy 119.438315 -262.211286) (xy 119.493158 -262.201156) (xy 119.548892 -262.199119) (xy 119.604329 -262.205219)
			(xy 119.658286 -262.219325) (xy 119.709615 -262.241137) (xy 119.757221 -262.270191) (xy 119.800089 -262.305866)
			(xy 119.837306 -262.347403) (xy 119.868079 -262.393916) (xy 119.891751 -262.444413) (xy 119.907819 -262.49782)
			(xy 119.915939 -262.552996) (xy 119.916448 -262.580882) (xy 119.915939 -262.608768) (xy 119.907819 -262.663944)
			(xy 119.891751 -262.717351) (xy 119.868079 -262.767848) (xy 119.837306 -262.814361) (xy 119.800089 -262.855898)
			(xy 119.757221 -262.891573) (xy 119.709615 -262.920627) (xy 119.658286 -262.942439) (xy 119.604329 -262.956545)
			(xy 119.548892 -262.962645) (xy 119.493158 -262.960608) (xy 119.438315 -262.950478) (xy 119.385531 -262.932471)
			(xy 119.335931 -262.90697) (xy 119.290573 -262.874519) (xy 119.250424 -262.83581) (xy 119.216338 -262.791667)
			(xy 119.189042 -262.743032) (xy 119.169119 -262.690941) (xy 119.156993 -262.636504) (xy 119.152922 -262.580882)
			(xy 112.906073 -262.580882) (xy 112.917993 -262.620502) (xy 112.926113 -262.675678) (xy 112.926622 -262.703564)
			(xy 112.926113 -262.73145) (xy 112.917993 -262.786626) (xy 112.901925 -262.840033) (xy 112.878253 -262.89053)
			(xy 112.84748 -262.937043) (xy 112.810263 -262.97858) (xy 112.767395 -263.014255) (xy 112.719789 -263.043309)
			(xy 112.66846 -263.065121) (xy 112.642667 -263.071864) (xy 116.381782 -263.071864) (xy 116.385853 -263.016242)
			(xy 116.397979 -262.961805) (xy 116.417902 -262.909714) (xy 116.445198 -262.861079) (xy 116.479284 -262.816936)
			(xy 116.519433 -262.778227) (xy 116.564791 -262.745776) (xy 116.614391 -262.720275) (xy 116.667175 -262.702268)
			(xy 116.722018 -262.692138) (xy 116.777752 -262.690101) (xy 116.833189 -262.696201) (xy 116.887146 -262.710307)
			(xy 116.938475 -262.732119) (xy 116.986081 -262.761173) (xy 117.028949 -262.796848) (xy 117.066166 -262.838385)
			(xy 117.096939 -262.884898) (xy 117.120611 -262.935395) (xy 117.136679 -262.988802) (xy 117.144799 -263.043978)
			(xy 117.145308 -263.071864) (xy 117.144799 -263.09975) (xy 117.136679 -263.154926) (xy 117.128121 -263.18337)
			(xy 122.968764 -263.18337) (xy 122.972835 -263.127748) (xy 122.984961 -263.073311) (xy 123.004884 -263.02122)
			(xy 123.03218 -262.972585) (xy 123.066266 -262.928442) (xy 123.106415 -262.889733) (xy 123.151773 -262.857282)
			(xy 123.201373 -262.831781) (xy 123.254157 -262.813774) (xy 123.309 -262.803644) (xy 123.364734 -262.801607)
			(xy 123.420171 -262.807707) (xy 123.474128 -262.821813) (xy 123.525457 -262.843625) (xy 123.573063 -262.872679)
			(xy 123.615931 -262.908354) (xy 123.653148 -262.949891) (xy 123.683921 -262.996404) (xy 123.707593 -263.046901)
			(xy 123.723661 -263.100308) (xy 123.731781 -263.155484) (xy 123.73229 -263.18337) (xy 123.731781 -263.211256)
			(xy 123.723661 -263.266432) (xy 123.707593 -263.319839) (xy 123.683921 -263.370336) (xy 123.653148 -263.416849)
			(xy 123.615931 -263.458386) (xy 123.573063 -263.494061) (xy 123.525457 -263.523115) (xy 123.474128 -263.544927)
			(xy 123.420171 -263.559033) (xy 123.364734 -263.565133) (xy 123.309 -263.563096) (xy 123.254157 -263.552966)
			(xy 123.201373 -263.534959) (xy 123.151773 -263.509458) (xy 123.106415 -263.477007) (xy 123.066266 -263.438298)
			(xy 123.03218 -263.394155) (xy 123.004884 -263.34552) (xy 122.984961 -263.293429) (xy 122.972835 -263.238992)
			(xy 122.968764 -263.18337) (xy 117.128121 -263.18337) (xy 117.120611 -263.208333) (xy 117.096939 -263.25883)
			(xy 117.066166 -263.305343) (xy 117.028949 -263.34688) (xy 116.986081 -263.382555) (xy 116.938475 -263.411609)
			(xy 116.887146 -263.433421) (xy 116.833189 -263.447527) (xy 116.777752 -263.453627) (xy 116.722018 -263.45159)
			(xy 116.667175 -263.44146) (xy 116.614391 -263.423453) (xy 116.564791 -263.397952) (xy 116.519433 -263.365501)
			(xy 116.479284 -263.326792) (xy 116.445198 -263.282649) (xy 116.417902 -263.234014) (xy 116.397979 -263.181923)
			(xy 116.385853 -263.127486) (xy 116.381782 -263.071864) (xy 112.642667 -263.071864) (xy 112.614503 -263.079227)
			(xy 112.559066 -263.085327) (xy 112.503332 -263.08329) (xy 112.448489 -263.07316) (xy 112.395705 -263.055153)
			(xy 112.346105 -263.029652) (xy 112.300747 -262.997201) (xy 112.260598 -262.958492) (xy 112.226512 -262.914349)
			(xy 112.199216 -262.865714) (xy 112.179293 -262.813623) (xy 112.167167 -262.759186) (xy 112.163096 -262.703564)
			(xy 100.052886 -262.703564) (xy 99.619308 -263.137142) (xy 99.611942 -263.144254) (xy 99.604322 -263.16305)
			(xy 99.604322 -264.12952) (xy 114.449096 -264.12952) (xy 114.453167 -264.073898) (xy 114.465293 -264.019461)
			(xy 114.485216 -263.96737) (xy 114.512512 -263.918735) (xy 114.546598 -263.874592) (xy 114.586747 -263.835883)
			(xy 114.632105 -263.803432) (xy 114.681705 -263.777931) (xy 114.734489 -263.759924) (xy 114.789332 -263.749794)
			(xy 114.845066 -263.747757) (xy 114.900503 -263.753857) (xy 114.95446 -263.767963) (xy 115.000755 -263.787636)
			(xy 117.571772 -263.787636) (xy 117.575843 -263.732014) (xy 117.587969 -263.677577) (xy 117.607892 -263.625486)
			(xy 117.635188 -263.576851) (xy 117.669274 -263.532708) (xy 117.709423 -263.493999) (xy 117.754781 -263.461548)
			(xy 117.804381 -263.436047) (xy 117.857165 -263.41804) (xy 117.912008 -263.40791) (xy 117.967742 -263.405873)
			(xy 118.023179 -263.411973) (xy 118.077136 -263.426079) (xy 118.128465 -263.447891) (xy 118.176071 -263.476945)
			(xy 118.218939 -263.51262) (xy 118.256156 -263.554157) (xy 118.286929 -263.60067) (xy 118.310601 -263.651167)
			(xy 118.326669 -263.704574) (xy 118.334789 -263.75975) (xy 118.335298 -263.787636) (xy 118.334789 -263.815522)
			(xy 118.333996 -263.82091) (xy 119.443752 -263.82091) (xy 119.447823 -263.765288) (xy 119.459949 -263.710851)
			(xy 119.479872 -263.65876) (xy 119.507168 -263.610125) (xy 119.541254 -263.565982) (xy 119.581403 -263.527273)
			(xy 119.626761 -263.494822) (xy 119.676361 -263.469321) (xy 119.729145 -263.451314) (xy 119.783988 -263.441184)
			(xy 119.839722 -263.439147) (xy 119.895159 -263.445247) (xy 119.949116 -263.459353) (xy 120.000445 -263.481165)
			(xy 120.048051 -263.510219) (xy 120.090919 -263.545894) (xy 120.128136 -263.587431) (xy 120.158909 -263.633944)
			(xy 120.182581 -263.684441) (xy 120.198649 -263.737848) (xy 120.206769 -263.793024) (xy 120.207278 -263.82091)
			(xy 120.206769 -263.848796) (xy 120.198649 -263.903972) (xy 120.182581 -263.957379) (xy 120.158909 -264.007876)
			(xy 120.128136 -264.054389) (xy 120.090919 -264.095926) (xy 120.050552 -264.12952) (xy 122.980194 -264.12952)
			(xy 122.984265 -264.073898) (xy 122.996391 -264.019461) (xy 123.016314 -263.96737) (xy 123.04361 -263.918735)
			(xy 123.077696 -263.874592) (xy 123.117845 -263.835883) (xy 123.163203 -263.803432) (xy 123.212803 -263.777931)
			(xy 123.265587 -263.759924) (xy 123.32043 -263.749794) (xy 123.376164 -263.747757) (xy 123.431601 -263.753857)
			(xy 123.485558 -263.767963) (xy 123.536887 -263.789775) (xy 123.584493 -263.818829) (xy 123.627361 -263.854504)
			(xy 123.664578 -263.896041) (xy 123.695351 -263.942554) (xy 123.719023 -263.993051) (xy 123.735091 -264.046458)
			(xy 123.743211 -264.101634) (xy 123.74372 -264.12952) (xy 123.743211 -264.157406) (xy 123.735091 -264.212582)
			(xy 123.719023 -264.265989) (xy 123.695351 -264.316486) (xy 123.664578 -264.362999) (xy 123.627361 -264.404536)
			(xy 123.584493 -264.440211) (xy 123.536887 -264.469265) (xy 123.485558 -264.491077) (xy 123.431601 -264.505183)
			(xy 123.376164 -264.511283) (xy 123.32043 -264.509246) (xy 123.265587 -264.499116) (xy 123.212803 -264.481109)
			(xy 123.163203 -264.455608) (xy 123.117845 -264.423157) (xy 123.077696 -264.384448) (xy 123.04361 -264.340305)
			(xy 123.016314 -264.29167) (xy 122.996391 -264.239579) (xy 122.984265 -264.185142) (xy 122.980194 -264.12952)
			(xy 120.050552 -264.12952) (xy 120.048051 -264.131601) (xy 120.000445 -264.160655) (xy 119.949116 -264.182467)
			(xy 119.895159 -264.196573) (xy 119.839722 -264.202673) (xy 119.783988 -264.200636) (xy 119.729145 -264.190506)
			(xy 119.676361 -264.172499) (xy 119.626761 -264.146998) (xy 119.581403 -264.114547) (xy 119.541254 -264.075838)
			(xy 119.507168 -264.031695) (xy 119.479872 -263.98306) (xy 119.459949 -263.930969) (xy 119.447823 -263.876532)
			(xy 119.443752 -263.82091) (xy 118.333996 -263.82091) (xy 118.326669 -263.870698) (xy 118.310601 -263.924105)
			(xy 118.286929 -263.974602) (xy 118.256156 -264.021115) (xy 118.218939 -264.062652) (xy 118.176071 -264.098327)
			(xy 118.128465 -264.127381) (xy 118.077136 -264.149193) (xy 118.023179 -264.163299) (xy 117.967742 -264.169399)
			(xy 117.912008 -264.167362) (xy 117.857165 -264.157232) (xy 117.804381 -264.139225) (xy 117.754781 -264.113724)
			(xy 117.709423 -264.081273) (xy 117.669274 -264.042564) (xy 117.635188 -263.998421) (xy 117.607892 -263.949786)
			(xy 117.587969 -263.897695) (xy 117.575843 -263.843258) (xy 117.571772 -263.787636) (xy 115.000755 -263.787636)
			(xy 115.005789 -263.789775) (xy 115.053395 -263.818829) (xy 115.096263 -263.854504) (xy 115.13348 -263.896041)
			(xy 115.164253 -263.942554) (xy 115.187925 -263.993051) (xy 115.203993 -264.046458) (xy 115.212113 -264.101634)
			(xy 115.212622 -264.12952) (xy 115.212113 -264.157406) (xy 115.203993 -264.212582) (xy 115.187925 -264.265989)
			(xy 115.164253 -264.316486) (xy 115.13348 -264.362999) (xy 115.096263 -264.404536) (xy 115.053395 -264.440211)
			(xy 115.005789 -264.469265) (xy 114.95446 -264.491077) (xy 114.900503 -264.505183) (xy 114.845066 -264.511283)
			(xy 114.789332 -264.509246) (xy 114.734489 -264.499116) (xy 114.681705 -264.481109) (xy 114.632105 -264.455608)
			(xy 114.586747 -264.423157) (xy 114.546598 -264.384448) (xy 114.512512 -264.340305) (xy 114.485216 -264.29167)
			(xy 114.465293 -264.239579) (xy 114.453167 -264.185142) (xy 114.449096 -264.12952) (xy 99.604322 -264.12952)
			(xy 99.604322 -264.93597) (xy 120.417334 -264.93597) (xy 120.421405 -264.880348) (xy 120.433531 -264.825911)
			(xy 120.453454 -264.77382) (xy 120.48075 -264.725185) (xy 120.514836 -264.681042) (xy 120.554985 -264.642333)
			(xy 120.600343 -264.609882) (xy 120.649943 -264.584381) (xy 120.702727 -264.566374) (xy 120.75757 -264.556244)
			(xy 120.813304 -264.554207) (xy 120.868741 -264.560307) (xy 120.922698 -264.574413) (xy 120.974027 -264.596225)
			(xy 121.021633 -264.625279) (xy 121.064501 -264.660954) (xy 121.101718 -264.702491) (xy 121.132491 -264.749004)
			(xy 121.156163 -264.799501) (xy 121.172231 -264.852908) (xy 121.180351 -264.908084) (xy 121.18086 -264.93597)
			(xy 121.180351 -264.963856) (xy 121.172231 -265.019032) (xy 121.156163 -265.072439) (xy 121.132491 -265.122936)
			(xy 121.101718 -265.169449) (xy 121.064501 -265.210986) (xy 121.021633 -265.246661) (xy 120.974027 -265.275715)
			(xy 120.922698 -265.297527) (xy 120.868741 -265.311633) (xy 120.813304 -265.317733) (xy 120.75757 -265.315696)
			(xy 120.702727 -265.305566) (xy 120.649943 -265.287559) (xy 120.600343 -265.262058) (xy 120.554985 -265.229607)
			(xy 120.514836 -265.190898) (xy 120.48075 -265.146755) (xy 120.453454 -265.09812) (xy 120.433531 -265.046029)
			(xy 120.421405 -264.991592) (xy 120.417334 -264.93597) (xy 99.604322 -264.93597) (xy 99.604322 -265.74369)
			(xy 99.604102 -265.750731) (xy 99.600243 -265.764271) (xy 99.596702 -265.77036) (xy 99.593146 -265.776456)
			(xy 99.589336 -265.789664) (xy 99.589336 -265.834114) (xy 119.246394 -265.834114) (xy 119.250465 -265.778492)
			(xy 119.262591 -265.724055) (xy 119.282514 -265.671964) (xy 119.30981 -265.623329) (xy 119.343896 -265.579186)
			(xy 119.384045 -265.540477) (xy 119.429403 -265.508026) (xy 119.479003 -265.482525) (xy 119.531787 -265.464518)
			(xy 119.58663 -265.454388) (xy 119.642364 -265.452351) (xy 119.697801 -265.458451) (xy 119.751758 -265.472557)
			(xy 119.803087 -265.494369) (xy 119.850693 -265.523423) (xy 119.893561 -265.559098) (xy 119.930778 -265.600635)
			(xy 119.961551 -265.647148) (xy 119.985223 -265.697645) (xy 120.001291 -265.751052) (xy 120.009411 -265.806228)
			(xy 120.00992 -265.834114) (xy 120.009411 -265.862) (xy 120.001291 -265.917176) (xy 119.985223 -265.970583)
			(xy 119.961551 -266.02108) (xy 119.930778 -266.067593) (xy 119.893561 -266.10913) (xy 119.850693 -266.144805)
			(xy 119.803087 -266.173859) (xy 119.751758 -266.195671) (xy 119.697801 -266.209777) (xy 119.642364 -266.215877)
			(xy 119.58663 -266.21384) (xy 119.531787 -266.20371) (xy 119.479003 -266.185703) (xy 119.429403 -266.160202)
			(xy 119.384045 -266.127751) (xy 119.343896 -266.089042) (xy 119.30981 -266.044899) (xy 119.282514 -265.996264)
			(xy 119.262591 -265.944173) (xy 119.250465 -265.889736) (xy 119.246394 -265.834114) (xy 99.589336 -265.834114)
			(xy 99.589336 -269.417038) (xy 102.50043 -269.417038) (xy 102.500935 -269.388299) (xy 102.509565 -269.331471)
			(xy 102.52662 -269.276581) (xy 102.551716 -269.22487) (xy 102.584283 -269.177507) (xy 102.603554 -269.15618)
			(xy 102.610158 -269.149068) (xy 102.61727 -269.131542) (xy 102.61727 -269.042134) (xy 102.610158 -269.024608)
			(xy 102.603554 -269.017496) (xy 102.584304 -268.996151) (xy 102.551734 -268.948794) (xy 102.526638 -268.897087)
			(xy 102.509582 -268.8422) (xy 102.500954 -268.785376) (xy 102.50043 -268.756638) (xy 102.500891 -268.729384)
			(xy 102.508644 -268.675431) (xy 102.523997 -268.623131) (xy 102.546638 -268.573549) (xy 102.576105 -268.527693)
			(xy 102.611799 -268.486499) (xy 102.652993 -268.450805) (xy 102.698849 -268.421338) (xy 102.748431 -268.398697)
			(xy 102.800731 -268.383344) (xy 102.854684 -268.375591) (xy 102.881938 -268.37513) (xy 102.909307 -268.375625)
			(xy 102.963485 -268.383435) (xy 103.015988 -268.398917) (xy 103.065736 -268.421752) (xy 103.111704 -268.451471)
			(xy 103.132636 -268.46911) (xy 103.139748 -268.475206) (xy 103.156766 -268.481556) (xy 103.24211 -268.481556)
			(xy 103.259128 -268.475206) (xy 103.26624 -268.46911) (xy 103.287173 -268.451469) (xy 103.333141 -268.421745)
			(xy 103.382887 -268.398899) (xy 103.435389 -268.383403) (xy 103.489567 -268.375574) (xy 103.544309 -268.375574)
			(xy 103.598487 -268.383403) (xy 103.650989 -268.398899) (xy 103.700735 -268.421745) (xy 103.746703 -268.451469)
			(xy 103.767636 -268.46911) (xy 103.774748 -268.475206) (xy 103.791766 -268.481556) (xy 103.87711 -268.481556)
			(xy 103.894128 -268.475206) (xy 103.90124 -268.46911) (xy 103.922173 -268.451469) (xy 103.968141 -268.421745)
			(xy 104.017887 -268.398899) (xy 104.070389 -268.383403) (xy 104.124567 -268.375574) (xy 104.179309 -268.375574)
			(xy 104.233487 -268.383403) (xy 104.285989 -268.398899) (xy 104.335735 -268.421745) (xy 104.381703 -268.451469)
			(xy 104.402636 -268.46911) (xy 104.409748 -268.475206) (xy 104.426766 -268.481556) (xy 104.51211 -268.481556)
			(xy 104.529128 -268.475206) (xy 104.53624 -268.46911) (xy 104.557173 -268.451469) (xy 104.603141 -268.421745)
			(xy 104.652887 -268.398899) (xy 104.705389 -268.383403) (xy 104.759567 -268.375574) (xy 104.814309 -268.375574)
			(xy 104.868487 -268.383403) (xy 104.920989 -268.398899) (xy 104.970735 -268.421745) (xy 105.016703 -268.451469)
			(xy 105.037636 -268.46911) (xy 105.044748 -268.475206) (xy 105.061766 -268.481556) (xy 105.14711 -268.481556)
			(xy 105.164128 -268.475206) (xy 105.17124 -268.46911) (xy 105.192185 -268.451487) (xy 105.238154 -268.421773)
			(xy 105.287898 -268.398933) (xy 105.340396 -268.383438) (xy 105.39457 -268.375606) (xy 105.421938 -268.37513)
			(xy 105.449192 -268.375543) (xy 105.503144 -268.383305) (xy 105.555443 -268.398667) (xy 105.605023 -268.421315)
			(xy 105.650875 -268.450789) (xy 105.692065 -268.486488) (xy 105.727756 -268.527686) (xy 105.757221 -268.573544)
			(xy 105.779859 -268.623129) (xy 105.795211 -268.67543) (xy 105.802963 -268.729384) (xy 105.803446 -268.756638)
			(xy 105.802933 -268.785377) (xy 105.794306 -268.842204) (xy 105.777253 -268.897095) (xy 105.752159 -268.948806)
			(xy 105.719593 -268.996169) (xy 105.700322 -269.017496) (xy 105.693718 -269.024608) (xy 105.686606 -269.042134)
			(xy 105.686606 -269.131542) (xy 105.693718 -269.149068) (xy 105.700322 -269.15618) (xy 105.719604 -269.177497)
			(xy 105.75217 -269.224861) (xy 105.777261 -269.276575) (xy 105.794309 -269.331468) (xy 105.802928 -269.388298)
			(xy 105.803446 -269.417038) (xy 124.88545 -269.417038) (xy 124.885949 -269.388298) (xy 124.89458 -269.33147)
			(xy 124.911636 -269.27658) (xy 124.936733 -269.224869) (xy 124.969302 -269.177507) (xy 124.988574 -269.15618)
			(xy 124.995178 -269.149068) (xy 125.00229 -269.131542) (xy 125.00229 -269.042134) (xy 124.995178 -269.024608)
			(xy 124.988574 -269.017496) (xy 124.969327 -268.996148) (xy 124.936756 -268.948792) (xy 124.911659 -268.897086)
			(xy 124.894602 -268.8422) (xy 124.885974 -268.785376) (xy 124.88545 -268.756638) (xy 124.886013 -268.72939)
			(xy 124.893764 -268.675447) (xy 124.909112 -268.623156) (xy 124.931746 -268.573582) (xy 124.961204 -268.527733)
			(xy 124.996887 -268.486544) (xy 125.038069 -268.450852) (xy 125.083912 -268.421384) (xy 125.133481 -268.39874)
			(xy 125.185769 -268.383381) (xy 125.23971 -268.375619) (xy 125.266958 -268.37513) (xy 125.294328 -268.375613)
			(xy 125.348506 -268.383426) (xy 125.40101 -268.398911) (xy 125.450757 -268.421749) (xy 125.496724 -268.45147)
			(xy 125.517656 -268.46911) (xy 125.524768 -268.475206) (xy 125.541786 -268.481556) (xy 125.62713 -268.481556)
			(xy 125.644148 -268.475206) (xy 125.65126 -268.46911) (xy 125.672193 -268.451469) (xy 125.718161 -268.421745)
			(xy 125.767907 -268.398899) (xy 125.820409 -268.383403) (xy 125.874587 -268.375574) (xy 125.929329 -268.375574)
			(xy 125.983507 -268.383403) (xy 126.036009 -268.398899) (xy 126.085755 -268.421745) (xy 126.131723 -268.451469)
			(xy 126.152656 -268.46911) (xy 126.159768 -268.475206) (xy 126.176786 -268.481556) (xy 126.26213 -268.481556)
			(xy 126.279148 -268.475206) (xy 126.28626 -268.46911) (xy 126.307193 -268.451469) (xy 126.353161 -268.421745)
			(xy 126.402907 -268.398899) (xy 126.455409 -268.383403) (xy 126.509587 -268.375574) (xy 126.564329 -268.375574)
			(xy 126.618507 -268.383403) (xy 126.671009 -268.398899) (xy 126.720755 -268.421745) (xy 126.766723 -268.451469)
			(xy 126.787656 -268.46911) (xy 126.794768 -268.475206) (xy 126.811786 -268.481556) (xy 126.89713 -268.481556)
			(xy 126.914148 -268.475206) (xy 126.92126 -268.46911) (xy 126.942193 -268.451469) (xy 126.988161 -268.421745)
			(xy 127.037907 -268.398899) (xy 127.090409 -268.383403) (xy 127.144587 -268.375574) (xy 127.199329 -268.375574)
			(xy 127.253507 -268.383403) (xy 127.306009 -268.398899) (xy 127.355755 -268.421745) (xy 127.401723 -268.451469)
			(xy 127.422656 -268.46911) (xy 127.429768 -268.475206) (xy 127.446786 -268.481556) (xy 127.53213 -268.481556)
			(xy 127.549148 -268.475206) (xy 127.55626 -268.46911) (xy 127.577198 -268.451478) (xy 127.623169 -268.421765)
			(xy 127.672915 -268.398927) (xy 127.725414 -268.383434) (xy 127.779589 -268.375605) (xy 127.806958 -268.37513)
			(xy 127.834212 -268.375594) (xy 127.888164 -268.383347) (xy 127.940465 -268.398699) (xy 127.990047 -268.42134)
			(xy 128.035902 -268.450807) (xy 128.077096 -268.486501) (xy 128.112791 -268.527695) (xy 128.142258 -268.573549)
			(xy 128.164899 -268.623132) (xy 128.180252 -268.675432) (xy 128.188005 -268.729384) (xy 128.188466 -268.756638)
			(xy 128.187948 -268.785377) (xy 128.179321 -268.842204) (xy 128.162269 -268.897094) (xy 128.137177 -268.948805)
			(xy 128.104612 -268.996168) (xy 128.085342 -269.017496) (xy 128.078738 -269.024608) (xy 128.071626 -269.042134)
			(xy 128.071626 -269.131542) (xy 128.078738 -269.149068) (xy 128.085342 -269.15618) (xy 128.104627 -269.177494)
			(xy 128.137192 -269.224859) (xy 128.162282 -269.276574) (xy 128.17933 -269.331468) (xy 128.187948 -269.388298)
			(xy 128.188466 -269.417038) (xy 128.18808 -269.444294) (xy 128.180317 -269.49825) (xy 128.164954 -269.550552)
			(xy 128.142304 -269.600135) (xy 128.112828 -269.64599) (xy 128.077126 -269.687183) (xy 128.035926 -269.722876)
			(xy 127.990064 -269.752343) (xy 127.940477 -269.774982) (xy 127.888171 -269.790334) (xy 127.834214 -269.798086)
			(xy 127.806958 -269.798546) (xy 127.779588 -269.798059) (xy 127.72541 -269.790248) (xy 127.672906 -269.774765)
			(xy 127.623159 -269.751927) (xy 127.577192 -269.722206) (xy 127.55626 -269.704566) (xy 127.549148 -269.69847)
			(xy 127.53213 -269.69212) (xy 127.446786 -269.69212) (xy 127.429768 -269.69847) (xy 127.422656 -269.704566)
			(xy 127.401723 -269.722207) (xy 127.355755 -269.751931) (xy 127.306009 -269.774777) (xy 127.253507 -269.790273)
			(xy 127.199329 -269.798102) (xy 127.144587 -269.798102) (xy 127.090409 -269.790273) (xy 127.037907 -269.774777)
			(xy 126.988161 -269.751931) (xy 126.942193 -269.722207) (xy 126.92126 -269.704566) (xy 126.914148 -269.69847)
			(xy 126.89713 -269.69212) (xy 126.811786 -269.69212) (xy 126.794768 -269.69847) (xy 126.787656 -269.704566)
			(xy 126.766723 -269.722207) (xy 126.720755 -269.751931) (xy 126.671009 -269.774777) (xy 126.618507 -269.790273)
			(xy 126.564329 -269.798102) (xy 126.509587 -269.798102) (xy 126.455409 -269.790273) (xy 126.402907 -269.774777)
			(xy 126.353161 -269.751931) (xy 126.307193 -269.722207) (xy 126.28626 -269.704566) (xy 126.279148 -269.69847)
			(xy 126.26213 -269.69212) (xy 126.176786 -269.69212) (xy 126.159768 -269.69847) (xy 126.152656 -269.704566)
			(xy 126.131723 -269.722207) (xy 126.085755 -269.751931) (xy 126.036009 -269.774777) (xy 125.983507 -269.790273)
			(xy 125.929329 -269.798102) (xy 125.874587 -269.798102) (xy 125.820409 -269.790273) (xy 125.767907 -269.774777)
			(xy 125.718161 -269.751931) (xy 125.672193 -269.722207) (xy 125.65126 -269.704566) (xy 125.644148 -269.69847)
			(xy 125.62713 -269.69212) (xy 125.541786 -269.69212) (xy 125.524768 -269.69847) (xy 125.517656 -269.704566)
			(xy 125.496709 -269.722187) (xy 125.450741 -269.751903) (xy 125.400997 -269.774743) (xy 125.3485 -269.790238)
			(xy 125.294326 -269.79807) (xy 125.266958 -269.798546) (xy 125.239707 -269.798061) (xy 125.185762 -269.7903)
			(xy 125.133469 -269.774942) (xy 125.083894 -269.752298) (xy 125.038046 -269.722831) (xy 124.996857 -269.68714)
			(xy 124.961166 -269.645951) (xy 124.9317 -269.600102) (xy 124.909057 -269.550527) (xy 124.893699 -269.498234)
			(xy 124.885938 -269.444289) (xy 124.88545 -269.417038) (xy 105.803446 -269.417038) (xy 105.802958 -269.444288)
			(xy 105.795197 -269.498234) (xy 105.779839 -269.550526) (xy 105.757196 -269.600101) (xy 105.727729 -269.64595)
			(xy 105.692038 -269.687138) (xy 105.65085 -269.722829) (xy 105.605001 -269.752296) (xy 105.555426 -269.774939)
			(xy 105.503134 -269.790297) (xy 105.449188 -269.798058) (xy 105.421938 -269.798546) (xy 105.394568 -269.798071)
			(xy 105.340389 -269.790257) (xy 105.287885 -269.774771) (xy 105.238138 -269.751931) (xy 105.192171 -269.722207)
			(xy 105.17124 -269.704566) (xy 105.164128 -269.69847) (xy 105.14711 -269.69212) (xy 105.061766 -269.69212)
			(xy 105.044748 -269.69847) (xy 105.037636 -269.704566) (xy 105.016703 -269.722207) (xy 104.970735 -269.751931)
			(xy 104.920989 -269.774777) (xy 104.868487 -269.790273) (xy 104.814309 -269.798102) (xy 104.759567 -269.798102)
			(xy 104.705389 -269.790273) (xy 104.652887 -269.774777) (xy 104.603141 -269.751931) (xy 104.557173 -269.722207)
			(xy 104.53624 -269.704566) (xy 104.529128 -269.69847) (xy 104.51211 -269.69212) (xy 104.426766 -269.69212)
			(xy 104.409748 -269.69847) (xy 104.402636 -269.704566) (xy 104.381703 -269.722207) (xy 104.335735 -269.751931)
			(xy 104.285989 -269.774777) (xy 104.233487 -269.790273) (xy 104.179309 -269.798102) (xy 104.124567 -269.798102)
			(xy 104.070389 -269.790273) (xy 104.017887 -269.774777) (xy 103.968141 -269.751931) (xy 103.922173 -269.722207)
			(xy 103.90124 -269.704566) (xy 103.894128 -269.69847) (xy 103.87711 -269.69212) (xy 103.791766 -269.69212)
			(xy 103.774748 -269.69847) (xy 103.767636 -269.704566) (xy 103.746703 -269.722207) (xy 103.700735 -269.751931)
			(xy 103.650989 -269.774777) (xy 103.598487 -269.790273) (xy 103.544309 -269.798102) (xy 103.489567 -269.798102)
			(xy 103.435389 -269.790273) (xy 103.382887 -269.774777) (xy 103.333141 -269.751931) (xy 103.287173 -269.722207)
			(xy 103.26624 -269.704566) (xy 103.259128 -269.69847) (xy 103.24211 -269.69212) (xy 103.156766 -269.69212)
			(xy 103.139748 -269.69847) (xy 103.132636 -269.704566) (xy 103.111697 -269.722196) (xy 103.065727 -269.751911)
			(xy 103.015981 -269.774749) (xy 102.963482 -269.790242) (xy 102.909307 -269.798071) (xy 102.881938 -269.798546)
			(xy 102.854689 -269.797987) (xy 102.800746 -269.790236) (xy 102.748455 -269.774888) (xy 102.698881 -269.752254)
			(xy 102.653032 -269.722795) (xy 102.611843 -269.687111) (xy 102.57615 -269.645929) (xy 102.546683 -269.600086)
			(xy 102.524039 -269.550516) (xy 102.50868 -269.498228) (xy 102.500919 -269.444286) (xy 102.50043 -269.417038)
			(xy 99.589336 -269.417038) (xy 99.589336 -277.864824) (xy 103.46563 -277.864824) (xy 103.466154 -277.835907)
			(xy 103.47488 -277.778736) (xy 103.492136 -277.723537) (xy 103.517527 -277.671575) (xy 103.55047 -277.624041)
			(xy 103.590211 -277.582024) (xy 103.612696 -277.563834) (xy 103.621438 -277.556252) (xy 103.631632 -277.535509)
			(xy 103.632254 -277.523956) (xy 103.632254 -277.443692) (xy 103.631704 -277.432121) (xy 103.621497 -277.411349)
			(xy 103.612696 -277.403814) (xy 103.590218 -277.385616) (xy 103.550483 -277.343598) (xy 103.517543 -277.296064)
			(xy 103.492154 -277.244104) (xy 103.474896 -277.188908) (xy 103.466166 -277.13174) (xy 103.46563 -277.102824)
			(xy 103.466211 -277.073416) (xy 103.475241 -277.015298) (xy 103.493076 -276.959253) (xy 103.519295 -276.906604)
			(xy 103.553276 -276.858599) (xy 103.594217 -276.816372) (xy 103.641148 -276.780922) (xy 103.666798 -276.766528)
			(xy 103.678736 -276.760178) (xy 103.69296 -276.737826) (xy 103.698802 -276.624288) (xy 103.686864 -276.600412)
			(xy 103.675942 -276.593046) (xy 103.654185 -276.577733) (xy 103.614705 -276.54207) (xy 103.580561 -276.50127)
			(xy 103.552414 -276.456123) (xy 103.530809 -276.407504) (xy 103.516166 -276.356357) (xy 103.508768 -276.303671)
			(xy 103.508302 -276.27707) (xy 103.50875 -276.249699) (xy 103.516572 -276.195519) (xy 103.532065 -276.143016)
			(xy 103.554911 -276.093269) (xy 103.584639 -276.047303) (xy 103.602282 -276.026372) (xy 103.608378 -276.01926)
			(xy 103.614728 -276.002242) (xy 103.614728 -275.916898) (xy 103.608378 -275.89988) (xy 103.602282 -275.892768)
			(xy 103.584659 -275.871823) (xy 103.554945 -275.825854) (xy 103.532106 -275.776109) (xy 103.516611 -275.723612)
			(xy 103.508779 -275.669438) (xy 103.508302 -275.64207) (xy 103.508854 -275.612246) (xy 103.518108 -275.55332)
			(xy 103.536418 -275.496551) (xy 103.563338 -275.443323) (xy 103.598212 -275.394931) (xy 103.618792 -275.373338)
			(xy 103.626158 -275.366226) (xy 103.633778 -275.34743) (xy 103.632762 -275.25472) (xy 103.624888 -275.236178)
			(xy 103.617522 -275.229066) (xy 103.599566 -275.211014) (xy 103.568068 -275.171012) (xy 103.542169 -275.127176)
			(xy 103.522329 -275.080286) (xy 103.508902 -275.031173) (xy 103.502124 -274.980711) (xy 103.501698 -274.955254)
			(xy 103.502135 -274.928001) (xy 103.509898 -274.874052) (xy 103.525259 -274.821756) (xy 103.547906 -274.772178)
			(xy 103.577378 -274.726327) (xy 103.613074 -274.685137) (xy 103.654269 -274.649447) (xy 103.700123 -274.619981)
			(xy 103.749704 -274.597341) (xy 103.802002 -274.581987) (xy 103.855953 -274.574231) (xy 103.883206 -274.573746)
			(xy 103.912124 -274.574243) (xy 103.969297 -274.582974) (xy 104.024497 -274.600235) (xy 104.076459 -274.62563)
			(xy 104.123992 -274.658579) (xy 104.166007 -274.698324) (xy 104.184196 -274.720812) (xy 104.191762 -274.72957)
			(xy 104.212518 -274.739755) (xy 104.224074 -274.74037) (xy 104.304338 -274.74037) (xy 104.315903 -274.739775)
			(xy 104.336675 -274.729599) (xy 104.344216 -274.720812) (xy 104.360969 -274.700029) (xy 104.399323 -274.662899)
			(xy 104.442477 -274.631477) (xy 104.489591 -274.606378) (xy 104.539743 -274.588092) (xy 104.591954 -274.576975)
			(xy 104.645206 -274.573245) (xy 104.698458 -274.576975) (xy 104.750669 -274.588092) (xy 104.800821 -274.606378)
			(xy 104.847935 -274.631477) (xy 104.891089 -274.662899) (xy 104.929443 -274.700029) (xy 104.946196 -274.720812)
			(xy 104.953762 -274.72957) (xy 104.974518 -274.739755) (xy 104.986074 -274.74037) (xy 105.066338 -274.74037)
			(xy 105.077903 -274.739775) (xy 105.098675 -274.729599) (xy 105.106216 -274.720812) (xy 105.124401 -274.698323)
			(xy 105.166422 -274.658588) (xy 105.213958 -274.625649) (xy 105.26592 -274.600262) (xy 105.321119 -274.583007)
			(xy 105.37829 -274.57428) (xy 105.407206 -274.573746) (xy 105.434455 -274.574272) (xy 105.488399 -274.582028)
			(xy 105.54069 -274.597382) (xy 105.590265 -274.62002) (xy 105.636113 -274.649483) (xy 105.677302 -274.68517)
			(xy 105.712993 -274.726355) (xy 105.742461 -274.7722) (xy 105.765104 -274.821772) (xy 105.780463 -274.874062)
			(xy 105.788225 -274.928005) (xy 105.788714 -274.955254) (xy 105.788173 -274.985079) (xy 105.778915 -275.044005)
			(xy 105.760602 -275.100774) (xy 105.73368 -275.154002) (xy 105.698805 -275.202393) (xy 105.678224 -275.223986)
			(xy 105.670858 -275.231098) (xy 105.663238 -275.249894) (xy 105.664254 -275.342604) (xy 105.672128 -275.361146)
			(xy 105.679494 -275.368258) (xy 105.697465 -275.386296) (xy 105.728961 -275.426301) (xy 105.754857 -275.47014)
			(xy 105.774694 -275.517034) (xy 105.788119 -275.566148) (xy 105.794894 -275.616612) (xy 105.795318 -275.64207)
			(xy 105.794809 -275.670988) (xy 105.786083 -275.728161) (xy 105.768825 -275.783361) (xy 105.743432 -275.835324)
			(xy 105.710485 -275.882857) (xy 105.67074 -275.924872) (xy 105.648252 -275.94306) (xy 105.639504 -275.950635)
			(xy 105.629315 -275.971384) (xy 105.628694 -275.982938) (xy 105.628694 -276.051264) (xy 109.061504 -276.051264)
			(xy 109.061948 -276.023893) (xy 109.069771 -275.969713) (xy 109.085265 -275.917209) (xy 109.108112 -275.867463)
			(xy 109.137841 -275.821497) (xy 109.155484 -275.800566) (xy 109.16158 -275.793454) (xy 109.16793 -275.776436)
			(xy 109.16793 -275.691092) (xy 109.16158 -275.674074) (xy 109.155484 -275.666962) (xy 109.13781 -275.646057)
			(xy 109.10809 -275.600083) (xy 109.085249 -275.550332) (xy 109.069757 -275.497826) (xy 109.061933 -275.443645)
			(xy 109.061937 -275.388901) (xy 109.069769 -275.334721) (xy 109.085268 -275.282217) (xy 109.108116 -275.232469)
			(xy 109.137843 -275.1865) (xy 109.155484 -275.165566) (xy 109.16158 -275.158454) (xy 109.16793 -275.141436)
			(xy 109.16793 -275.056092) (xy 109.16158 -275.039074) (xy 109.155484 -275.031962) (xy 109.137858 -275.011019)
			(xy 109.108145 -274.965049) (xy 109.085307 -274.915304) (xy 109.069812 -274.862806) (xy 109.06198 -274.808632)
			(xy 109.061504 -274.781264) (xy 109.061944 -274.754011) (xy 109.069706 -274.700061) (xy 109.085066 -274.647765)
			(xy 109.107713 -274.598187) (xy 109.137184 -274.552336) (xy 109.17288 -274.511146) (xy 109.214075 -274.475455)
			(xy 109.259929 -274.44599) (xy 109.30951 -274.42335) (xy 109.361808 -274.407996) (xy 109.415759 -274.400241)
			(xy 109.443012 -274.399756) (xy 109.470383 -274.400201) (xy 109.524564 -274.408022) (xy 109.577068 -274.423515)
			(xy 109.626814 -274.446362) (xy 109.67278 -274.476092) (xy 109.69371 -274.493736) (xy 109.700822 -274.499832)
			(xy 109.71784 -274.506182) (xy 109.803184 -274.506182) (xy 109.820202 -274.499832) (xy 109.827314 -274.493736)
			(xy 109.848272 -274.476129) (xy 109.894237 -274.446411) (xy 109.943978 -274.423569) (xy 109.996473 -274.40807)
			(xy 110.050645 -274.400234) (xy 110.078012 -274.399756) (xy 110.105262 -274.400267) (xy 110.159207 -274.408024)
			(xy 110.211499 -274.423379) (xy 110.261074 -274.446018) (xy 110.306922 -274.475483) (xy 110.348112 -274.511171)
			(xy 110.383803 -274.552358) (xy 110.41327 -274.598205) (xy 110.435913 -274.647779) (xy 110.451271 -274.70007)
			(xy 110.459032 -274.754014) (xy 110.45952 -274.781264) (xy 110.459052 -274.808634) (xy 110.451238 -274.862814)
			(xy 110.43575 -274.915318) (xy 110.412908 -274.965065) (xy 110.383182 -275.011031) (xy 110.36554 -275.031962)
			(xy 110.359444 -275.039074) (xy 110.353094 -275.056092) (xy 110.353094 -275.141436) (xy 110.359444 -275.158454)
			(xy 110.36554 -275.165566) (xy 110.383147 -275.186527) (xy 110.412876 -275.232489) (xy 110.435725 -275.28223)
			(xy 110.451226 -275.334728) (xy 110.459058 -275.388904) (xy 110.459062 -275.443642) (xy 110.451237 -275.497819)
			(xy 110.435744 -275.550319) (xy 110.412902 -275.600064) (xy 110.38318 -275.64603) (xy 110.36554 -275.666962)
			(xy 110.359444 -275.674074) (xy 110.353094 -275.691092) (xy 110.353094 -275.776436) (xy 110.359444 -275.793454)
			(xy 110.36554 -275.800566) (xy 110.383147 -275.821527) (xy 110.412876 -275.867489) (xy 110.435725 -275.91723)
			(xy 110.451226 -275.969728) (xy 110.459058 -276.023904) (xy 110.459062 -276.078642) (xy 110.451237 -276.132819)
			(xy 110.435744 -276.185319) (xy 110.412902 -276.235064) (xy 110.38318 -276.28103) (xy 110.36554 -276.301962)
			(xy 110.359444 -276.309074) (xy 110.353094 -276.326092) (xy 110.353094 -276.411436) (xy 110.359444 -276.428454)
			(xy 110.36554 -276.435566) (xy 110.381698 -276.454665) (xy 110.409391 -276.496327) (xy 110.431379 -276.541263)
			(xy 110.439708 -276.564852) (xy 110.443518 -276.576282) (xy 110.460282 -276.593046) (xy 110.559342 -276.626574)
			(xy 110.582964 -276.623526) (xy 110.59287 -276.616668) (xy 110.616626 -276.601325) (xy 110.667684 -276.577015)
			(xy 110.721771 -276.560506) (xy 110.777701 -276.552158) (xy 110.805976 -276.551644) (xy 110.833224 -276.5522)
			(xy 110.887167 -276.559952) (xy 110.939458 -276.575302) (xy 110.989031 -276.597937) (xy 111.03488 -276.627396)
			(xy 111.076069 -276.66308) (xy 111.111761 -276.704263) (xy 111.141229 -276.750105) (xy 111.163873 -276.799675)
			(xy 111.179232 -276.851962) (xy 111.186994 -276.905904) (xy 111.187484 -276.933152) (xy 111.18705 -276.959469)
			(xy 111.179827 -277.011604) (xy 111.165511 -277.062253) (xy 111.144372 -277.110455) (xy 111.116813 -277.155296)
			(xy 111.083356 -277.195927) (xy 111.064294 -277.214076) (xy 111.0569 -277.221604) (xy 111.048372 -277.240879)
			(xy 111.047784 -277.251414) (xy 111.047784 -277.32609) (xy 111.04831 -277.33664) (xy 111.056848 -277.355935)
			(xy 111.064294 -277.363428) (xy 111.083386 -277.38155) (xy 111.116863 -277.422173) (xy 111.144432 -277.467016)
			(xy 111.165568 -277.515226) (xy 111.17987 -277.565886) (xy 111.187065 -277.618032) (xy 111.187322 -277.634192)
			(xy 120.08485 -277.634192) (xy 120.085348 -277.606122) (xy 120.093588 -277.550589) (xy 120.109875 -277.496862)
			(xy 120.133856 -277.446101) (xy 120.165015 -277.3994) (xy 120.202679 -277.357769) (xy 120.224042 -277.339552)
			(xy 120.232678 -277.33244) (xy 120.24233 -277.312882) (xy 120.24487 -277.213314) (xy 120.236234 -277.193502)
			(xy 120.227852 -277.185882) (xy 120.208519 -277.167737) (xy 120.174597 -277.126988) (xy 120.146643 -277.081936)
			(xy 120.125194 -277.033447) (xy 120.110665 -276.982456) (xy 120.103334 -276.929944) (xy 120.102884 -276.903434)
			(xy 120.103387 -276.876182) (xy 120.111139 -276.822233) (xy 120.12649 -276.769937) (xy 120.149128 -276.720357)
			(xy 120.178592 -276.674504) (xy 120.214282 -276.633311) (xy 120.255471 -276.597617) (xy 120.30132 -276.568148)
			(xy 120.350897 -276.545505) (xy 120.403192 -276.530148) (xy 120.45714 -276.52239) (xy 120.484392 -276.521926)
			(xy 120.510644 -276.52235) (xy 120.562654 -276.529537) (xy 120.613186 -276.543791) (xy 120.661285 -276.564842)
			(xy 120.706042 -276.592292) (xy 120.74661 -276.625622) (xy 120.782223 -276.664202) (xy 120.797574 -276.685502)
			(xy 120.805448 -276.696678) (xy 120.829324 -276.708108) (xy 120.94337 -276.700234) (xy 120.965468 -276.685502)
			(xy 120.971564 -276.67331) (xy 120.983825 -276.650017) (xy 121.013792 -276.606742) (xy 121.049423 -276.567996)
			(xy 121.09004 -276.534514) (xy 121.134873 -276.506933) (xy 121.183072 -276.485774) (xy 121.233721 -276.47144)
			(xy 121.285859 -276.464203) (xy 121.312178 -276.46376) (xy 121.345706 -276.465284) (xy 121.355779 -276.465774)
			(xy 121.374985 -276.459662) (xy 121.390363 -276.446633) (xy 121.399547 -276.428692) (xy 121.401125 -276.408599)
			(xy 121.394855 -276.389444) (xy 121.381699 -276.374175) (xy 121.372884 -276.369272) (xy 121.351374 -276.358095)
			(xy 121.311121 -276.331087) (xy 121.29262 -276.315424) (xy 121.285508 -276.309328) (xy 121.26849 -276.302978)
			(xy 121.183146 -276.302978) (xy 121.166128 -276.309328) (xy 121.159016 -276.315424) (xy 121.138092 -276.333073)
			(xy 121.092116 -276.362782) (xy 121.042367 -276.385616) (xy 120.989865 -276.401105) (xy 120.935688 -276.408931)
			(xy 120.908318 -276.409404) (xy 120.881065 -276.408928) (xy 120.827115 -276.401173) (xy 120.774817 -276.385819)
			(xy 120.725237 -276.363179) (xy 120.679383 -276.333712) (xy 120.63819 -276.29802) (xy 120.602496 -276.256828)
			(xy 120.573028 -276.210976) (xy 120.550386 -276.161396) (xy 120.53503 -276.109099) (xy 120.527273 -276.055149)
			(xy 120.52681 -276.027896) (xy 120.527271 -276.000526) (xy 120.53509 -275.946346) (xy 120.55058 -275.893843)
			(xy 120.573423 -275.844096) (xy 120.603148 -275.79813) (xy 120.62079 -275.777198) (xy 120.626886 -275.770086)
			(xy 120.633236 -275.753068) (xy 120.633236 -275.667724) (xy 120.626886 -275.650706) (xy 120.62079 -275.643594)
			(xy 120.603147 -275.622664) (xy 120.573425 -275.576695) (xy 120.550582 -275.526948) (xy 120.535088 -275.474446)
			(xy 120.52726 -275.420267) (xy 120.527261 -275.365527) (xy 120.535089 -275.311349) (xy 120.550584 -275.258847)
			(xy 120.573428 -275.2091) (xy 120.603151 -275.163131) (xy 120.62079 -275.142198) (xy 120.626886 -275.135086)
			(xy 120.633236 -275.118068) (xy 120.633236 -275.032724) (xy 120.626886 -275.015706) (xy 120.62079 -275.008594)
			(xy 120.603133 -274.987676) (xy 120.573424 -274.941699) (xy 120.550592 -274.891948) (xy 120.535105 -274.839444)
			(xy 120.527282 -274.785266) (xy 120.52681 -274.757896) (xy 120.527252 -274.730642) (xy 120.53501 -274.67669)
			(xy 120.550367 -274.62439) (xy 120.573011 -274.574809) (xy 120.602481 -274.528955) (xy 120.638177 -274.487762)
			(xy 120.679373 -274.452068) (xy 120.725228 -274.422601) (xy 120.774811 -274.399959) (xy 120.827111 -274.384605)
			(xy 120.881064 -274.37685) (xy 120.908318 -274.376388) (xy 120.935688 -274.376846) (xy 120.989868 -274.384667)
			(xy 121.042371 -274.400158) (xy 121.092118 -274.423001) (xy 121.138084 -274.452726) (xy 121.159016 -274.470368)
			(xy 121.166128 -274.476464) (xy 121.183146 -274.482814) (xy 121.26849 -274.482814) (xy 121.285508 -274.476464)
			(xy 121.29262 -274.470368) (xy 121.313567 -274.452748) (xy 121.359536 -274.423034) (xy 121.40928 -274.400195)
			(xy 121.461777 -274.3847) (xy 121.51595 -274.376865) (xy 121.543318 -274.376388) (xy 121.57057 -274.376861)
			(xy 121.624517 -274.38462) (xy 121.676812 -274.399977) (xy 121.726389 -274.42262) (xy 121.772239 -274.452088)
			(xy 121.813429 -274.487781) (xy 121.849121 -274.528972) (xy 121.878587 -274.574823) (xy 121.901228 -274.624401)
			(xy 121.916583 -274.676696) (xy 121.92434 -274.730644) (xy 121.924826 -274.757896) (xy 121.924376 -274.785267)
			(xy 121.916557 -274.839447) (xy 121.901065 -274.891951) (xy 121.878219 -274.941698) (xy 121.84849 -274.987664)
			(xy 121.830846 -275.008594) (xy 121.82475 -275.015706) (xy 121.8184 -275.032724) (xy 121.8184 -275.118068)
			(xy 121.82475 -275.135086) (xy 121.830846 -275.142198) (xy 121.848484 -275.163133) (xy 121.878211 -275.2091)
			(xy 121.901058 -275.258846) (xy 121.916556 -275.311348) (xy 121.924385 -275.365526) (xy 121.924386 -275.420268)
			(xy 121.916557 -275.474447) (xy 121.90106 -275.526949) (xy 121.878214 -275.576695) (xy 121.848488 -275.622662)
			(xy 121.830846 -275.643594) (xy 121.82475 -275.650706) (xy 121.8184 -275.667724) (xy 121.8184 -275.753068)
			(xy 121.82475 -275.770086) (xy 121.830846 -275.777198) (xy 121.848489 -275.798127) (xy 121.878202 -275.8441)
			(xy 121.901038 -275.893848) (xy 121.916528 -275.94635) (xy 121.924354 -276.000526) (xy 121.924826 -276.027896)
			(xy 121.924546 -276.046184) (xy 124.460254 -276.046184) (xy 124.460698 -276.018813) (xy 124.468519 -275.964632)
			(xy 124.484012 -275.912128) (xy 124.506859 -275.862382) (xy 124.53659 -275.816416) (xy 124.554234 -275.795486)
			(xy 124.56033 -275.788374) (xy 124.56668 -275.771356) (xy 124.56668 -275.686012) (xy 124.56033 -275.668994)
			(xy 124.554234 -275.661882) (xy 124.536625 -275.640925) (xy 124.506908 -275.59496) (xy 124.484065 -275.545219)
			(xy 124.468567 -275.492723) (xy 124.460732 -275.438552) (xy 124.460254 -275.411184) (xy 124.460763 -275.383934)
			(xy 124.46852 -275.329989) (xy 124.483876 -275.277697) (xy 124.506516 -275.228122) (xy 124.53598 -275.182274)
			(xy 124.571669 -275.141085) (xy 124.612856 -275.105394) (xy 124.658703 -275.075927) (xy 124.708277 -275.053283)
			(xy 124.760568 -275.037925) (xy 124.814512 -275.030164) (xy 124.841762 -275.029676) (xy 124.869132 -275.030146)
			(xy 124.923312 -275.03796) (xy 124.975816 -275.053447) (xy 125.025563 -275.076288) (xy 125.071529 -275.106014)
			(xy 125.09246 -275.123656) (xy 125.099572 -275.129752) (xy 125.11659 -275.136102) (xy 125.201934 -275.136102)
			(xy 125.218952 -275.129752) (xy 125.226064 -275.123656) (xy 125.246997 -275.106015) (xy 125.292965 -275.076291)
			(xy 125.342711 -275.053445) (xy 125.395213 -275.037949) (xy 125.449391 -275.03012) (xy 125.504133 -275.03012)
			(xy 125.558311 -275.037949) (xy 125.610813 -275.053445) (xy 125.660559 -275.076291) (xy 125.706527 -275.106015)
			(xy 125.72746 -275.123656) (xy 125.734572 -275.129752) (xy 125.75159 -275.136102) (xy 125.836934 -275.136102)
			(xy 125.853952 -275.129752) (xy 125.861064 -275.123656) (xy 125.881997 -275.106015) (xy 125.927965 -275.076291)
			(xy 125.977711 -275.053445) (xy 126.030213 -275.037949) (xy 126.084391 -275.03012) (xy 126.139133 -275.03012)
			(xy 126.193311 -275.037949) (xy 126.245813 -275.053445) (xy 126.295559 -275.076291) (xy 126.341527 -275.106015)
			(xy 126.36246 -275.123656) (xy 126.369572 -275.129752) (xy 126.38659 -275.136102) (xy 126.471934 -275.136102)
			(xy 126.488952 -275.129752) (xy 126.496064 -275.123656) (xy 126.516997 -275.106015) (xy 126.562965 -275.076291)
			(xy 126.612711 -275.053445) (xy 126.665213 -275.037949) (xy 126.719391 -275.03012) (xy 126.774133 -275.03012)
			(xy 126.828311 -275.037949) (xy 126.880813 -275.053445) (xy 126.930559 -275.076291) (xy 126.976527 -275.106015)
			(xy 126.99746 -275.123656) (xy 127.004572 -275.129752) (xy 127.02159 -275.136102) (xy 127.106934 -275.136102)
			(xy 127.123952 -275.129752) (xy 127.131064 -275.123656) (xy 127.151993 -275.106013) (xy 127.197967 -275.076303)
			(xy 127.247716 -275.053469) (xy 127.300217 -275.037978) (xy 127.354393 -275.03015) (xy 127.381762 -275.029676)
			(xy 127.409013 -275.030191) (xy 127.462961 -275.037942) (xy 127.515257 -275.053292) (xy 127.564836 -275.075929)
			(xy 127.610689 -275.105392) (xy 127.651882 -275.14108) (xy 127.687576 -275.182268) (xy 127.717045 -275.228116)
			(xy 127.739689 -275.277692) (xy 127.755047 -275.329986) (xy 127.762806 -275.383933) (xy 127.76327 -275.411184)
			(xy 127.762802 -275.438554) (xy 127.754986 -275.492734) (xy 127.739497 -275.545237) (xy 127.716656 -275.594984)
			(xy 127.686931 -275.640951) (xy 127.66929 -275.661882) (xy 127.663194 -275.668994) (xy 127.656844 -275.686012)
			(xy 127.656844 -275.771356) (xy 127.663194 -275.788374) (xy 127.66929 -275.795486) (xy 127.686934 -275.816414)
			(xy 127.716646 -275.862388) (xy 127.739481 -275.912136) (xy 127.754971 -275.964638) (xy 127.762797 -276.018815)
			(xy 127.76327 -276.046184) (xy 127.76283 -276.073438) (xy 127.755074 -276.127392) (xy 127.739718 -276.179693)
			(xy 127.717075 -276.229275) (xy 127.687605 -276.27513) (xy 127.651908 -276.316324) (xy 127.610713 -276.352018)
			(xy 127.564856 -276.381485) (xy 127.515272 -276.404126) (xy 127.46297 -276.419479) (xy 127.409016 -276.427231)
			(xy 127.381762 -276.427692) (xy 127.354393 -276.427192) (xy 127.300215 -276.419382) (xy 127.247712 -276.403901)
			(xy 127.197965 -276.381067) (xy 127.151997 -276.35135) (xy 127.131064 -276.333712) (xy 127.123952 -276.327616)
			(xy 127.106934 -276.321266) (xy 127.02159 -276.321266) (xy 127.004572 -276.327616) (xy 126.99746 -276.333712)
			(xy 126.976527 -276.351353) (xy 126.930559 -276.381077) (xy 126.880813 -276.403923) (xy 126.828311 -276.419419)
			(xy 126.774133 -276.427248) (xy 126.719391 -276.427248) (xy 126.665213 -276.419419) (xy 126.612711 -276.403923)
			(xy 126.562965 -276.381077) (xy 126.516997 -276.351353) (xy 126.496064 -276.333712) (xy 126.488952 -276.327616)
			(xy 126.471934 -276.321266) (xy 126.38659 -276.321266) (xy 126.369572 -276.327616) (xy 126.36246 -276.333712)
			(xy 126.341527 -276.351353) (xy 126.295559 -276.381077) (xy 126.245813 -276.403923) (xy 126.193311 -276.419419)
			(xy 126.139133 -276.427248) (xy 126.084391 -276.427248) (xy 126.030213 -276.419419) (xy 125.977711 -276.403923)
			(xy 125.927965 -276.381077) (xy 125.881997 -276.351353) (xy 125.861064 -276.333712) (xy 125.853952 -276.327616)
			(xy 125.836934 -276.321266) (xy 125.75159 -276.321266) (xy 125.734572 -276.327616) (xy 125.72746 -276.333712)
			(xy 125.706527 -276.351353) (xy 125.660559 -276.381077) (xy 125.610813 -276.403923) (xy 125.558311 -276.419419)
			(xy 125.504133 -276.427248) (xy 125.449391 -276.427248) (xy 125.395213 -276.419419) (xy 125.342711 -276.403923)
			(xy 125.292965 -276.381077) (xy 125.246997 -276.351353) (xy 125.226064 -276.333712) (xy 125.218952 -276.327616)
			(xy 125.201934 -276.321266) (xy 125.11659 -276.321266) (xy 125.099572 -276.327616) (xy 125.09246 -276.333712)
			(xy 125.071518 -276.351338) (xy 125.025547 -276.381052) (xy 124.975803 -276.40389) (xy 124.923304 -276.419384)
			(xy 124.86913 -276.427216) (xy 124.841762 -276.427692) (xy 124.814509 -276.427257) (xy 124.760559 -276.419495)
			(xy 124.708262 -276.404135) (xy 124.658684 -276.381488) (xy 124.612833 -276.352016) (xy 124.571642 -276.316319)
			(xy 124.535951 -276.275124) (xy 124.506486 -276.229269) (xy 124.483846 -276.179687) (xy 124.468493 -276.127388)
			(xy 124.460739 -276.073437) (xy 124.460254 -276.046184) (xy 121.924546 -276.046184) (xy 121.924387 -276.056524)
			(xy 121.915839 -276.113137) (xy 121.898921 -276.167835) (xy 121.874013 -276.219388) (xy 121.841674 -276.266636)
			(xy 121.802633 -276.308517) (xy 121.757768 -276.344087) (xy 121.708088 -276.372547) (xy 121.654709 -276.393257)
			(xy 121.626884 -276.400006) (xy 121.613422 -276.403054) (xy 121.593102 -276.422358) (xy 121.561098 -276.535134)
			(xy 121.568464 -276.562312) (xy 121.57837 -276.571964) (xy 121.596267 -276.58999) (xy 121.627628 -276.629949)
			(xy 121.653411 -276.673716) (xy 121.673158 -276.720517) (xy 121.686522 -276.769523) (xy 121.693266 -276.81987)
			(xy 121.693686 -276.845268) (xy 121.693215 -276.872521) (xy 121.685462 -276.926473) (xy 121.670109 -276.978772)
			(xy 121.647468 -277.028353) (xy 121.618001 -277.074208) (xy 121.582308 -277.115401) (xy 121.541116 -277.151095)
			(xy 121.495262 -277.180563) (xy 121.445681 -277.203205) (xy 121.393383 -277.21856) (xy 121.339431 -277.226314)
			(xy 121.312178 -277.226776) (xy 121.285925 -277.226374) (xy 121.233915 -277.219182) (xy 121.183382 -277.204925)
			(xy 121.135283 -277.18387) (xy 121.090527 -277.156417) (xy 121.049959 -277.123084) (xy 121.014347 -277.084501)
			(xy 120.998996 -277.0632) (xy 120.991122 -277.052024) (xy 120.967246 -277.040594) (xy 120.8532 -277.048468)
			(xy 120.831102 -277.0632) (xy 120.825006 -277.075392) (xy 120.812694 -277.098751) (xy 120.782606 -277.142141)
			(xy 120.746822 -277.180968) (xy 120.726708 -277.198074) (xy 120.718072 -277.205186) (xy 120.70842 -277.224744)
			(xy 120.70588 -277.324312) (xy 120.714516 -277.344124) (xy 120.722898 -277.351744) (xy 120.742185 -277.369935)
			(xy 120.776113 -277.410673) (xy 120.804075 -277.455716) (xy 120.825531 -277.504195) (xy 120.84007 -277.555179)
			(xy 120.847411 -277.607684) (xy 120.847866 -277.634192) (xy 120.84738 -277.661443) (xy 120.839624 -277.715391)
			(xy 120.834827 -277.731728) (xy 120.970292 -277.731728) (xy 120.974363 -277.676106) (xy 120.986489 -277.621669)
			(xy 121.006412 -277.569578) (xy 121.033708 -277.520943) (xy 121.067794 -277.4768) (xy 121.107943 -277.438091)
			(xy 121.153301 -277.40564) (xy 121.202901 -277.380139) (xy 121.255685 -277.362132) (xy 121.310528 -277.352002)
			(xy 121.366262 -277.349965) (xy 121.421699 -277.356065) (xy 121.475656 -277.370171) (xy 121.526985 -277.391983)
			(xy 121.574591 -277.421037) (xy 121.617459 -277.456712) (xy 121.654676 -277.498249) (xy 121.685449 -277.544762)
			(xy 121.709121 -277.595259) (xy 121.723891 -277.644352) (xy 127.083566 -277.644352) (xy 127.084018 -277.618036)
			(xy 127.09124 -277.565902) (xy 127.105554 -277.515255) (xy 127.126689 -277.467053) (xy 127.154244 -277.422211)
			(xy 127.187696 -277.381579) (xy 127.206756 -277.363428) (xy 127.214141 -277.355892) (xy 127.222676 -277.336623)
			(xy 127.223266 -277.32609) (xy 127.223266 -277.251414) (xy 127.222753 -277.240862) (xy 127.214208 -277.221566)
			(xy 127.206756 -277.214076) (xy 127.187676 -277.195942) (xy 127.154196 -277.155323) (xy 127.126624 -277.110482)
			(xy 127.105485 -277.062275) (xy 127.091181 -277.011616) (xy 127.083985 -276.959472) (xy 127.083566 -276.933152)
			(xy 127.084052 -276.905901) (xy 127.091808 -276.851953) (xy 127.107163 -276.799658) (xy 127.129805 -276.750081)
			(xy 127.159271 -276.704231) (xy 127.194962 -276.66304) (xy 127.236153 -276.627349) (xy 127.282003 -276.597883)
			(xy 127.33158 -276.575241) (xy 127.383875 -276.559886) (xy 127.437823 -276.55213) (xy 127.492325 -276.55213)
			(xy 127.546273 -276.559886) (xy 127.598568 -276.575241) (xy 127.648145 -276.597883) (xy 127.693995 -276.627349)
			(xy 127.735186 -276.66304) (xy 127.770877 -276.704231) (xy 127.800343 -276.750081) (xy 127.822985 -276.799658)
			(xy 127.83834 -276.851953) (xy 127.846096 -276.905901) (xy 127.846582 -276.933152) (xy 127.846149 -276.959469)
			(xy 127.838926 -277.011604) (xy 127.824609 -277.062253) (xy 127.803471 -277.110455) (xy 127.775912 -277.155296)
			(xy 127.742454 -277.195927) (xy 127.723392 -277.214076) (xy 127.715998 -277.221604) (xy 127.70747 -277.240879)
			(xy 127.706882 -277.251414) (xy 127.706882 -277.32609) (xy 127.707408 -277.33664) (xy 127.715946 -277.355935)
			(xy 127.723392 -277.363428) (xy 127.742483 -277.381551) (xy 127.775961 -277.422173) (xy 127.80353 -277.467016)
			(xy 127.824666 -277.515226) (xy 127.838968 -277.565886) (xy 127.846163 -277.618032) (xy 127.846582 -277.644352)
			(xy 127.846096 -277.671603) (xy 127.83834 -277.725551) (xy 127.822985 -277.777846) (xy 127.800343 -277.827423)
			(xy 127.770877 -277.873273) (xy 127.735186 -277.914464) (xy 127.693995 -277.950155) (xy 127.648145 -277.979621)
			(xy 127.598568 -278.002263) (xy 127.546273 -278.017618) (xy 127.492325 -278.025374) (xy 127.437823 -278.025374)
			(xy 127.383875 -278.017618) (xy 127.33158 -278.002263) (xy 127.282003 -277.979621) (xy 127.236153 -277.950155)
			(xy 127.194962 -277.914464) (xy 127.159271 -277.873273) (xy 127.129805 -277.827423) (xy 127.107163 -277.777846)
			(xy 127.091808 -277.725551) (xy 127.084052 -277.671603) (xy 127.083566 -277.644352) (xy 121.723891 -277.644352)
			(xy 121.725189 -277.648666) (xy 121.733309 -277.703842) (xy 121.733818 -277.731728) (xy 121.733309 -277.759614)
			(xy 121.725189 -277.81479) (xy 121.709121 -277.868197) (xy 121.685449 -277.918694) (xy 121.654676 -277.965207)
			(xy 121.617459 -278.006744) (xy 121.574591 -278.042419) (xy 121.526985 -278.071473) (xy 121.475656 -278.093285)
			(xy 121.421699 -278.107391) (xy 121.366262 -278.113491) (xy 121.310528 -278.111454) (xy 121.255685 -278.101324)
			(xy 121.202901 -278.083317) (xy 121.153301 -278.057816) (xy 121.107943 -278.025365) (xy 121.067794 -277.986656)
			(xy 121.033708 -277.942513) (xy 121.006412 -277.893878) (xy 120.986489 -277.841787) (xy 120.974363 -277.78735)
			(xy 120.970292 -277.731728) (xy 120.834827 -277.731728) (xy 120.824269 -277.767686) (xy 120.801627 -277.817263)
			(xy 120.772161 -277.863113) (xy 120.73647 -277.904304) (xy 120.695279 -277.939995) (xy 120.649429 -277.969461)
			(xy 120.599852 -277.992103) (xy 120.547557 -278.007458) (xy 120.493609 -278.015214) (xy 120.439107 -278.015214)
			(xy 120.385159 -278.007458) (xy 120.332864 -277.992103) (xy 120.283287 -277.969461) (xy 120.237437 -277.939995)
			(xy 120.196246 -277.904304) (xy 120.160555 -277.863113) (xy 120.131089 -277.817263) (xy 120.108447 -277.767686)
			(xy 120.093092 -277.715391) (xy 120.085336 -277.661443) (xy 120.08485 -277.634192) (xy 111.187322 -277.634192)
			(xy 111.187484 -277.644352) (xy 111.187 -277.671605) (xy 111.179249 -277.725556) (xy 111.163898 -277.777855)
			(xy 111.141259 -277.827437) (xy 111.111794 -277.873291) (xy 111.076102 -277.914485) (xy 111.03491 -277.950179)
			(xy 110.989058 -277.979648) (xy 110.939478 -278.002289) (xy 110.88718 -278.017644) (xy 110.833229 -278.025398)
			(xy 110.805976 -278.02586) (xy 110.779505 -278.025464) (xy 110.72707 -278.018167) (xy 110.676147 -278.003687)
			(xy 110.627717 -277.982304) (xy 110.582709 -277.954428) (xy 110.541989 -277.920596) (xy 110.506339 -277.881457)
			(xy 110.476445 -277.837763) (xy 110.452882 -277.790355) (xy 110.436101 -277.740144) (xy 110.430818 -277.714202)
			(xy 110.428532 -277.701756) (xy 110.413292 -277.682198) (xy 110.31347 -277.638002) (xy 110.288832 -277.639526)
			(xy 110.27791 -277.646384) (xy 110.255255 -277.659759) (xy 110.207064 -277.680861) (xy 110.156431 -277.695147)
			(xy 110.104317 -277.702345) (xy 110.078012 -277.702772) (xy 110.050758 -277.702333) (xy 109.996804 -277.694577)
			(xy 109.944504 -277.679221) (xy 109.894921 -277.656577) (xy 109.849066 -277.627107) (xy 109.807872 -277.591411)
			(xy 109.772179 -277.550215) (xy 109.742711 -277.504358) (xy 109.720071 -277.454774) (xy 109.704718 -277.402472)
			(xy 109.696965 -277.348518) (xy 109.696504 -277.321264) (xy 109.696948 -277.293893) (xy 109.704771 -277.239713)
			(xy 109.720265 -277.187209) (xy 109.743112 -277.137463) (xy 109.772841 -277.091497) (xy 109.790484 -277.070566)
			(xy 109.79658 -277.063454) (xy 109.80293 -277.046436) (xy 109.80293 -276.961092) (xy 109.79658 -276.944074)
			(xy 109.790484 -276.936962) (xy 109.772858 -276.916019) (xy 109.743145 -276.870049) (xy 109.720307 -276.820304)
			(xy 109.704812 -276.767806) (xy 109.69698 -276.713632) (xy 109.696504 -276.686264) (xy 109.697083 -276.656788)
			(xy 109.706142 -276.598536) (xy 109.724056 -276.542372) (xy 109.750396 -276.489632) (xy 109.784537 -276.441572)
			(xy 109.804708 -276.420072) (xy 109.811249 -276.412742) (xy 109.81869 -276.394578) (xy 109.819186 -276.384766)
			(xy 109.819186 -276.331426) (xy 109.81182 -276.324568) (xy 109.804477 -276.318045) (xy 109.786323 -276.310594)
			(xy 109.776514 -276.31009) (xy 109.74451 -276.31009) (xy 109.734698 -276.310593) (xy 109.716533 -276.318027)
			(xy 109.709204 -276.324568) (xy 109.687705 -276.344742) (xy 109.639645 -276.378886) (xy 109.586906 -276.405232)
			(xy 109.530741 -276.423153) (xy 109.472489 -276.432223) (xy 109.443012 -276.432772) (xy 109.415758 -276.432333)
			(xy 109.361804 -276.424577) (xy 109.309504 -276.409221) (xy 109.259921 -276.386577) (xy 109.214066 -276.357107)
			(xy 109.172872 -276.321411) (xy 109.137179 -276.280215) (xy 109.107711 -276.234358) (xy 109.085071 -276.184774)
			(xy 109.069718 -276.132472) (xy 109.061965 -276.078518) (xy 109.061504 -276.051264) (xy 105.628694 -276.051264)
			(xy 105.628694 -276.063202) (xy 105.629265 -276.07477) (xy 105.63946 -276.09554) (xy 105.648252 -276.10308)
			(xy 105.670737 -276.121269) (xy 105.710469 -276.163291) (xy 105.743407 -276.210827) (xy 105.768794 -276.262788)
			(xy 105.786051 -276.317985) (xy 105.794782 -276.375154) (xy 105.795318 -276.40407) (xy 105.794817 -276.431322)
			(xy 105.787064 -276.485271) (xy 105.771712 -276.537567) (xy 105.749074 -276.587147) (xy 105.71961 -276.632999)
			(xy 105.68392 -276.674192) (xy 105.642731 -276.709886) (xy 105.596882 -276.739355) (xy 105.547305 -276.761998)
			(xy 105.49501 -276.777356) (xy 105.441062 -276.785114) (xy 105.41381 -276.785578) (xy 105.384893 -276.785061)
			(xy 105.327721 -276.776333) (xy 105.272522 -276.759075) (xy 105.22056 -276.733683) (xy 105.173026 -276.700739)
			(xy 105.13101 -276.660998) (xy 105.11282 -276.638512) (xy 105.105243 -276.629765) (xy 105.084496 -276.619573)
			(xy 105.072942 -276.618954) (xy 104.992678 -276.618954) (xy 104.981113 -276.61955) (xy 104.96034 -276.629725)
			(xy 104.9528 -276.638512) (xy 104.942769 -276.651117) (xy 104.920893 -276.674769) (xy 104.909112 -276.685756)
			(xy 104.900222 -276.693884) (xy 104.891586 -276.715982) (xy 104.901492 -276.82063) (xy 104.913938 -276.84095)
			(xy 104.924098 -276.8473) (xy 104.947407 -276.862306) (xy 104.989845 -276.897971) (xy 105.026673 -276.939405)
			(xy 105.057113 -276.985734) (xy 105.080524 -277.035983) (xy 105.096413 -277.089091) (xy 105.104446 -277.143941)
			(xy 105.104946 -277.171658) (xy 105.10446 -277.198909) (xy 105.096704 -277.252857) (xy 105.081349 -277.305152)
			(xy 105.058707 -277.354729) (xy 105.029241 -277.400579) (xy 104.99355 -277.44177) (xy 104.952359 -277.477461)
			(xy 104.906509 -277.506927) (xy 104.856932 -277.529569) (xy 104.804637 -277.544924) (xy 104.750689 -277.55268)
			(xy 104.696187 -277.55268) (xy 104.642239 -277.544924) (xy 104.589944 -277.529569) (xy 104.540367 -277.506927)
			(xy 104.494517 -277.477461) (xy 104.453326 -277.44177) (xy 104.417635 -277.400579) (xy 104.388169 -277.354729)
			(xy 104.365527 -277.305152) (xy 104.350172 -277.252857) (xy 104.342416 -277.198909) (xy 104.34193 -277.171658)
			(xy 104.342402 -277.14524) (xy 104.349686 -277.09291) (xy 104.364122 -277.042085) (xy 104.385435 -276.99374)
			(xy 104.413216 -276.948798) (xy 104.446934 -276.908121) (xy 104.466136 -276.889972) (xy 104.475026 -276.881844)
			(xy 104.483662 -276.859746) (xy 104.473756 -276.755098) (xy 104.46131 -276.734778) (xy 104.45115 -276.728428)
			(xy 104.429535 -276.714589) (xy 104.389877 -276.68201) (xy 104.354959 -276.644394) (xy 104.325417 -276.602424)
			(xy 104.313228 -276.579838) (xy 104.30764 -276.56917) (xy 104.28859 -276.5552) (xy 104.18445 -276.537928)
			(xy 104.161844 -276.544786) (xy 104.152954 -276.553168) (xy 104.1341 -276.57061) (xy 104.09256 -276.600817)
			(xy 104.07015 -276.613366) (xy 104.058212 -276.619716) (xy 104.043988 -276.642068) (xy 104.038146 -276.755606)
			(xy 104.050084 -276.779482) (xy 104.061006 -276.786848) (xy 104.082749 -276.802181) (xy 104.122231 -276.837839)
			(xy 104.156378 -276.878635) (xy 104.184528 -276.923778) (xy 104.206135 -276.972394) (xy 104.22078 -277.02354)
			(xy 104.22818 -277.076224) (xy 104.228646 -277.102824) (xy 104.228093 -277.13174) (xy 104.219374 -277.18891)
			(xy 104.202124 -277.244109) (xy 104.176739 -277.296072) (xy 104.143801 -277.343606) (xy 104.104064 -277.385623)
			(xy 104.08158 -277.403814) (xy 104.072813 -277.411371) (xy 104.062633 -277.432133) (xy 104.062022 -277.443692)
			(xy 104.062022 -277.523956) (xy 104.06261 -277.535522) (xy 104.072792 -277.556293) (xy 104.08158 -277.563834)
			(xy 104.104076 -277.582011) (xy 104.143811 -277.624033) (xy 104.176749 -277.671571) (xy 104.202136 -277.723535)
			(xy 104.219389 -277.778735) (xy 104.228114 -277.835907) (xy 104.228646 -277.864824) (xy 104.22816 -277.892075)
			(xy 104.220404 -277.946023) (xy 104.205049 -277.998318) (xy 104.182407 -278.047895) (xy 104.152941 -278.093745)
			(xy 104.11725 -278.134936) (xy 104.076059 -278.170627) (xy 104.030209 -278.200093) (xy 103.980632 -278.222735)
			(xy 103.928337 -278.23809) (xy 103.874389 -278.245846) (xy 103.819887 -278.245846) (xy 103.765939 -278.23809)
			(xy 103.713644 -278.222735) (xy 103.664067 -278.200093) (xy 103.618217 -278.170627) (xy 103.577026 -278.134936)
			(xy 103.541335 -278.093745) (xy 103.511869 -278.047895) (xy 103.489227 -277.998318) (xy 103.473872 -277.946023)
			(xy 103.466116 -277.892075) (xy 103.46563 -277.864824) (xy 99.589336 -277.864824) (xy 99.589336 -280.617168)
			(xy 105.533444 -280.617168) (xy 105.53393 -280.589917) (xy 105.541686 -280.535969) (xy 105.557041 -280.483674)
			(xy 105.579683 -280.434097) (xy 105.609149 -280.388247) (xy 105.64484 -280.347056) (xy 105.686031 -280.311365)
			(xy 105.731881 -280.281899) (xy 105.781458 -280.259257) (xy 105.833753 -280.243902) (xy 105.887701 -280.236146)
			(xy 105.942203 -280.236146) (xy 105.996151 -280.243902) (xy 106.048446 -280.259257) (xy 106.098023 -280.281899)
			(xy 106.143873 -280.311365) (xy 106.185064 -280.347056) (xy 106.220755 -280.388247) (xy 106.250221 -280.434097)
			(xy 106.272863 -280.483674) (xy 106.288218 -280.535969) (xy 106.295974 -280.589917) (xy 106.29646 -280.617168)
			(xy 106.296402 -280.627794) (xy 106.295259 -280.649015) (xy 106.294174 -280.659586) (xy 106.292904 -280.669238)
			(xy 106.29773 -280.687526) (xy 106.349292 -280.758392) (xy 106.365294 -280.768552) (xy 106.374692 -280.770584)
			(xy 106.390186 -280.77414) (xy 106.399838 -280.776426) (xy 106.418888 -280.773886) (xy 106.497628 -280.728674)
			(xy 106.509566 -280.713434) (xy 106.51236 -280.703782) (xy 106.520447 -280.677692) (xy 106.542991 -280.627942)
			(xy 106.572402 -280.581917) (xy 106.60808 -280.54056) (xy 106.649294 -280.504717) (xy 106.6952 -280.475122)
			(xy 106.74486 -280.452379) (xy 106.797257 -280.436956) (xy 106.851318 -280.429166) (xy 106.878628 -280.4287)
			(xy 106.9038 -280.429089) (xy 106.953707 -280.435711) (xy 107.002311 -280.448836) (xy 107.025694 -280.458164)
			(xy 107.035854 -280.462482) (xy 107.05719 -280.461974) (xy 107.145328 -280.420064) (xy 107.159298 -280.403808)
			(xy 107.162346 -280.39314) (xy 107.171111 -280.365228) (xy 107.196048 -280.312306) (xy 107.228773 -280.263812)
			(xy 107.26852 -280.220885) (xy 107.314357 -280.184531) (xy 107.365207 -280.155603) (xy 107.419879 -280.13478)
			(xy 107.477089 -280.12255) (xy 107.506262 -280.120344) (xy 107.517946 -280.119582) (xy 107.538012 -280.108406)
			(xy 107.597448 -280.02484) (xy 107.601512 -280.002234) (xy 107.59821 -279.991058) (xy 107.591446 -279.965556)
			(xy 107.584179 -279.913298) (xy 107.583732 -279.886918) (xy 107.584218 -279.859667) (xy 107.591974 -279.805719)
			(xy 107.607329 -279.753424) (xy 107.629971 -279.703847) (xy 107.659437 -279.657997) (xy 107.695128 -279.616806)
			(xy 107.736319 -279.581115) (xy 107.782169 -279.551649) (xy 107.831746 -279.529007) (xy 107.884041 -279.513652)
			(xy 107.937989 -279.505896) (xy 107.992491 -279.505896) (xy 108.046439 -279.513652) (xy 108.098734 -279.529007)
			(xy 108.148311 -279.551649) (xy 108.194161 -279.581115) (xy 108.235352 -279.616806) (xy 108.271043 -279.657997)
			(xy 108.300509 -279.703847) (xy 108.323151 -279.753424) (xy 108.338506 -279.805719) (xy 108.346262 -279.859667)
			(xy 108.346748 -279.886918) (xy 108.346265 -279.915793) (xy 108.337582 -279.972885) (xy 108.320385 -280.028015)
			(xy 108.295069 -280.07992) (xy 108.262214 -280.127412) (xy 108.222571 -280.169404) (xy 108.177046 -280.204936)
			(xy 108.126683 -280.233195) (xy 108.072634 -280.253533) (xy 108.016135 -280.265486) (xy 107.987338 -280.267664)
			(xy 107.975654 -280.268426) (xy 107.955588 -280.279602) (xy 107.896152 -280.363168) (xy 107.892088 -280.385774)
			(xy 107.89539 -280.39695) (xy 107.902155 -280.422452) (xy 107.909422 -280.47471) (xy 107.909868 -280.50109)
			(xy 107.9091 -280.535173) (xy 107.896969 -280.602251) (xy 107.891764 -280.617168) (xy 113.693956 -280.617168)
			(xy 113.694442 -280.589917) (xy 113.702198 -280.535969) (xy 113.717553 -280.483674) (xy 113.740195 -280.434097)
			(xy 113.769661 -280.388247) (xy 113.805352 -280.347056) (xy 113.846543 -280.311365) (xy 113.892393 -280.281899)
			(xy 113.94197 -280.259257) (xy 113.994265 -280.243902) (xy 114.048213 -280.236146) (xy 114.102715 -280.236146)
			(xy 114.156663 -280.243902) (xy 114.208958 -280.259257) (xy 114.258535 -280.281899) (xy 114.304385 -280.311365)
			(xy 114.345576 -280.347056) (xy 114.381267 -280.388247) (xy 114.410733 -280.434097) (xy 114.433375 -280.483674)
			(xy 114.44873 -280.535969) (xy 114.456486 -280.589917) (xy 114.456972 -280.617168) (xy 114.456914 -280.627794)
			(xy 114.455771 -280.649015) (xy 114.454686 -280.659586) (xy 114.453416 -280.669238) (xy 114.458242 -280.687526)
			(xy 114.509804 -280.758392) (xy 114.525806 -280.768552) (xy 114.535204 -280.770584) (xy 114.550698 -280.77414)
			(xy 114.56035 -280.776426) (xy 114.5794 -280.773886) (xy 114.65814 -280.728674) (xy 114.670078 -280.713434)
			(xy 114.672872 -280.703782) (xy 114.680948 -280.677689) (xy 114.703493 -280.627938) (xy 114.732906 -280.581913)
			(xy 114.768585 -280.540556) (xy 114.8098 -280.504713) (xy 114.855708 -280.475118) (xy 114.905369 -280.452376)
			(xy 114.957767 -280.436953) (xy 115.01183 -280.429165) (xy 115.03914 -280.4287) (xy 115.064312 -280.429085)
			(xy 115.114219 -280.435709) (xy 115.162823 -280.448835) (xy 115.186206 -280.458164) (xy 115.196366 -280.462482)
			(xy 115.217702 -280.461974) (xy 115.30584 -280.420064) (xy 115.31981 -280.403808) (xy 115.322858 -280.39314)
			(xy 115.331613 -280.365225) (xy 115.356551 -280.312302) (xy 115.389277 -280.263808) (xy 115.429026 -280.220881)
			(xy 115.474864 -280.184527) (xy 115.525716 -280.1556) (xy 115.580389 -280.134778) (xy 115.6376 -280.122549)
			(xy 115.666774 -280.120344) (xy 115.678458 -280.119582) (xy 115.698524 -280.108406) (xy 115.75796 -280.02484)
			(xy 115.762024 -280.002234) (xy 115.758722 -279.991058) (xy 115.751959 -279.965556) (xy 115.744691 -279.913298)
			(xy 115.744244 -279.886918) (xy 115.74473 -279.859667) (xy 115.752486 -279.805719) (xy 115.767841 -279.753424)
			(xy 115.790483 -279.703847) (xy 115.819949 -279.657997) (xy 115.85564 -279.616806) (xy 115.896831 -279.581115)
			(xy 115.942681 -279.551649) (xy 115.992258 -279.529007) (xy 116.044553 -279.513652) (xy 116.098501 -279.505896)
			(xy 116.153003 -279.505896) (xy 116.206951 -279.513652) (xy 116.259246 -279.529007) (xy 116.308823 -279.551649)
			(xy 116.354673 -279.581115) (xy 116.395864 -279.616806) (xy 116.431555 -279.657997) (xy 116.461021 -279.703847)
			(xy 116.483663 -279.753424) (xy 116.499018 -279.805719) (xy 116.506774 -279.859667) (xy 116.50726 -279.886918)
			(xy 116.506766 -279.915792) (xy 116.498083 -279.972884) (xy 116.480887 -280.028012) (xy 116.455572 -280.079916)
			(xy 116.422718 -280.127408) (xy 116.383076 -280.1694) (xy 116.337553 -280.204933) (xy 116.287192 -280.233192)
			(xy 116.233144 -280.253531) (xy 116.176647 -280.265485) (xy 116.14785 -280.267664) (xy 116.136166 -280.268426)
			(xy 116.1161 -280.279602) (xy 116.056664 -280.363168) (xy 116.0526 -280.385774) (xy 116.055902 -280.39695)
			(xy 116.062667 -280.422452) (xy 116.069934 -280.47471) (xy 116.07038 -280.50109) (xy 116.069612 -280.535173)
			(xy 116.05748 -280.602251) (xy 116.052276 -280.617168) (xy 122.192542 -280.617168) (xy 122.193028 -280.589917)
			(xy 122.200784 -280.535969) (xy 122.216139 -280.483674) (xy 122.238781 -280.434097) (xy 122.268247 -280.388247)
			(xy 122.303938 -280.347056) (xy 122.345129 -280.311365) (xy 122.390979 -280.281899) (xy 122.440556 -280.259257)
			(xy 122.492851 -280.243902) (xy 122.546799 -280.236146) (xy 122.601301 -280.236146) (xy 122.655249 -280.243902)
			(xy 122.707544 -280.259257) (xy 122.757121 -280.281899) (xy 122.802971 -280.311365) (xy 122.844162 -280.347056)
			(xy 122.879853 -280.388247) (xy 122.909319 -280.434097) (xy 122.931961 -280.483674) (xy 122.947316 -280.535969)
			(xy 122.955072 -280.589917) (xy 122.955558 -280.617168) (xy 122.9555 -280.627794) (xy 122.954357 -280.649015)
			(xy 122.953272 -280.659586) (xy 122.952002 -280.669238) (xy 122.956828 -280.687526) (xy 123.00839 -280.758392)
			(xy 123.024392 -280.768552) (xy 123.03379 -280.770584) (xy 123.049284 -280.77414) (xy 123.058936 -280.776426)
			(xy 123.077986 -280.773886) (xy 123.156726 -280.728674) (xy 123.168664 -280.713434) (xy 123.171458 -280.703782)
			(xy 123.179458 -280.677663) (xy 123.202009 -280.627907) (xy 123.23143 -280.58188) (xy 123.267119 -280.540521)
			(xy 123.308344 -280.50468) (xy 123.354262 -280.475088) (xy 123.403934 -280.452352) (xy 123.456341 -280.436937)
			(xy 123.510412 -280.429159) (xy 123.537726 -280.4287) (xy 123.562898 -280.42909) (xy 123.612805 -280.435711)
			(xy 123.661409 -280.448836) (xy 123.684792 -280.458164) (xy 123.694952 -280.462482) (xy 123.716288 -280.461974)
			(xy 123.804426 -280.420064) (xy 123.818396 -280.403808) (xy 123.821444 -280.39314) (xy 123.830211 -280.365229)
			(xy 123.855147 -280.312307) (xy 123.887872 -280.263813) (xy 123.927619 -280.220886) (xy 123.973456 -280.184532)
			(xy 124.024306 -280.155604) (xy 124.078977 -280.134781) (xy 124.136187 -280.12255) (xy 124.16536 -280.120344)
			(xy 124.177044 -280.119582) (xy 124.19711 -280.108406) (xy 124.256546 -280.02484) (xy 124.26061 -280.002234)
			(xy 124.257308 -279.991058) (xy 124.250544 -279.965556) (xy 124.243277 -279.913298) (xy 124.24283 -279.886918)
			(xy 124.243316 -279.859667) (xy 124.251072 -279.805719) (xy 124.266427 -279.753424) (xy 124.289069 -279.703847)
			(xy 124.318535 -279.657997) (xy 124.354226 -279.616806) (xy 124.395417 -279.581115) (xy 124.441267 -279.551649)
			(xy 124.490844 -279.529007) (xy 124.543139 -279.513652) (xy 124.597087 -279.505896) (xy 124.651589 -279.505896)
			(xy 124.705537 -279.513652) (xy 124.757832 -279.529007) (xy 124.807409 -279.551649) (xy 124.853259 -279.581115)
			(xy 124.89445 -279.616806) (xy 124.930141 -279.657997) (xy 124.959607 -279.703847) (xy 124.982249 -279.753424)
			(xy 124.997604 -279.805719) (xy 125.00536 -279.859667) (xy 125.005846 -279.886918) (xy 125.005365 -279.915793)
			(xy 124.996681 -279.972886) (xy 124.979485 -280.028015) (xy 124.954169 -280.07992) (xy 124.921313 -280.127412)
			(xy 124.88167 -280.169405) (xy 124.836145 -280.204937) (xy 124.785782 -280.233195) (xy 124.731732 -280.253533)
			(xy 124.675233 -280.265486) (xy 124.646436 -280.267664) (xy 124.634752 -280.268426) (xy 124.614686 -280.279602)
			(xy 124.55525 -280.363168) (xy 124.551186 -280.385774) (xy 124.554488 -280.39695) (xy 124.561253 -280.422452)
			(xy 124.56852 -280.47471) (xy 124.568966 -280.50109) (xy 124.568199 -280.535173) (xy 124.556067 -280.602251)
			(xy 124.550862 -280.617168) (xy 130.353054 -280.617168) (xy 130.35354 -280.589917) (xy 130.361296 -280.535969)
			(xy 130.376651 -280.483674) (xy 130.399293 -280.434097) (xy 130.428759 -280.388247) (xy 130.46445 -280.347056)
			(xy 130.505641 -280.311365) (xy 130.551491 -280.281899) (xy 130.601068 -280.259257) (xy 130.653363 -280.243902)
			(xy 130.707311 -280.236146) (xy 130.761813 -280.236146) (xy 130.815761 -280.243902) (xy 130.868056 -280.259257)
			(xy 130.917633 -280.281899) (xy 130.963483 -280.311365) (xy 131.004674 -280.347056) (xy 131.040365 -280.388247)
			(xy 131.069831 -280.434097) (xy 131.092473 -280.483674) (xy 131.107828 -280.535969) (xy 131.115584 -280.589917)
			(xy 131.11607 -280.617168) (xy 131.116012 -280.627794) (xy 131.114869 -280.649015) (xy 131.113784 -280.659586)
			(xy 131.112514 -280.669238) (xy 131.11734 -280.687526) (xy 131.168902 -280.758392) (xy 131.184904 -280.768552)
			(xy 131.194302 -280.770584) (xy 131.209796 -280.77414) (xy 131.219448 -280.776426) (xy 131.238498 -280.773886)
			(xy 131.317238 -280.728674) (xy 131.329176 -280.713434) (xy 131.33197 -280.703782) (xy 131.340048 -280.677689)
			(xy 131.362592 -280.627938) (xy 131.392005 -280.581913) (xy 131.427684 -280.540556) (xy 131.468899 -280.504713)
			(xy 131.514807 -280.475118) (xy 131.564468 -280.452377) (xy 131.616865 -280.436954) (xy 131.670928 -280.429165)
			(xy 131.698238 -280.4287) (xy 131.72341 -280.429086) (xy 131.773317 -280.435709) (xy 131.821921 -280.448835)
			(xy 131.845304 -280.458164) (xy 131.855464 -280.462482) (xy 131.8768 -280.461974) (xy 131.964938 -280.420064)
			(xy 131.978908 -280.403808) (xy 131.981956 -280.39314) (xy 131.990713 -280.365225) (xy 132.01565 -280.312303)
			(xy 132.048377 -280.263809) (xy 132.088125 -280.220881) (xy 132.133963 -280.184528) (xy 132.184814 -280.155601)
			(xy 132.239487 -280.134778) (xy 132.296699 -280.12255) (xy 132.325872 -280.120344) (xy 132.337556 -280.119582)
			(xy 132.357622 -280.108406) (xy 132.417058 -280.02484) (xy 132.421122 -280.002234) (xy 132.41782 -279.991058)
			(xy 132.411057 -279.965556) (xy 132.403789 -279.913298) (xy 132.403342 -279.886918) (xy 132.403828 -279.859667)
			(xy 132.411584 -279.805719) (xy 132.426939 -279.753424) (xy 132.449581 -279.703847) (xy 132.479047 -279.657997)
			(xy 132.514738 -279.616806) (xy 132.555929 -279.581115) (xy 132.601779 -279.551649) (xy 132.651356 -279.529007)
			(xy 132.703651 -279.513652) (xy 132.757599 -279.505896) (xy 132.812101 -279.505896) (xy 132.866049 -279.513652)
			(xy 132.918344 -279.529007) (xy 132.967921 -279.551649) (xy 133.013771 -279.581115) (xy 133.054962 -279.616806)
			(xy 133.090653 -279.657997) (xy 133.120119 -279.703847) (xy 133.142761 -279.753424) (xy 133.158116 -279.805719)
			(xy 133.165872 -279.859667) (xy 133.166358 -279.886918) (xy 133.165866 -279.915792) (xy 133.157183 -279.972884)
			(xy 133.139987 -280.028013) (xy 133.114672 -280.079917) (xy 133.081817 -280.127408) (xy 133.042175 -280.169401)
			(xy 132.996652 -280.204933) (xy 132.94629 -280.233192) (xy 132.892242 -280.253531) (xy 132.835745 -280.265485)
			(xy 132.806948 -280.267664) (xy 132.795264 -280.268426) (xy 132.775198 -280.279602) (xy 132.715762 -280.363168)
			(xy 132.711698 -280.385774) (xy 132.715 -280.39695) (xy 132.721765 -280.422452) (xy 132.729032 -280.47471)
			(xy 132.729478 -280.50109) (xy 132.72871 -280.535173) (xy 132.716578 -280.602251) (xy 132.705348 -280.63444)
			(xy 132.701284 -280.645616) (xy 132.703824 -280.669492) (xy 132.761228 -280.758138) (xy 132.781802 -280.77033)
			(xy 132.79374 -280.771092) (xy 132.822349 -280.773546) (xy 132.878415 -280.785926) (xy 132.931995 -280.806566)
			(xy 132.981878 -280.835) (xy 133.026939 -280.870584) (xy 133.06616 -280.912518) (xy 133.098658 -280.959854)
			(xy 133.123698 -281.011523) (xy 133.125308 -281.01671) (xy 133.856982 -281.01671) (xy 133.861053 -280.961088)
			(xy 133.873179 -280.906651) (xy 133.893102 -280.85456) (xy 133.920398 -280.805925) (xy 133.954484 -280.761782)
			(xy 133.994633 -280.723073) (xy 134.039991 -280.690622) (xy 134.089591 -280.665121) (xy 134.142375 -280.647114)
			(xy 134.197218 -280.636984) (xy 134.252952 -280.634947) (xy 134.308389 -280.641047) (xy 134.362346 -280.655153)
			(xy 134.413675 -280.676965) (xy 134.461281 -280.706019) (xy 134.504149 -280.741694) (xy 134.541366 -280.783231)
			(xy 134.572139 -280.829744) (xy 134.595811 -280.880241) (xy 134.611879 -280.933648) (xy 134.619999 -280.988824)
			(xy 134.620508 -281.01671) (xy 134.619999 -281.044596) (xy 134.611879 -281.099772) (xy 134.595811 -281.153179)
			(xy 134.572139 -281.203676) (xy 134.541366 -281.250189) (xy 134.504149 -281.291726) (xy 134.461281 -281.327401)
			(xy 134.413675 -281.356455) (xy 134.362346 -281.378267) (xy 134.308389 -281.392373) (xy 134.252952 -281.398473)
			(xy 134.197218 -281.396436) (xy 134.142375 -281.386306) (xy 134.089591 -281.368299) (xy 134.039991 -281.342798)
			(xy 133.994633 -281.310347) (xy 133.954484 -281.271638) (xy 133.920398 -281.227495) (xy 133.893102 -281.17886)
			(xy 133.873179 -281.126769) (xy 133.861053 -281.072332) (xy 133.856982 -281.01671) (xy 133.125308 -281.01671)
			(xy 133.140715 -281.066361) (xy 133.149325 -281.123129) (xy 133.149848 -281.151838) (xy 133.149362 -281.179089)
			(xy 133.141606 -281.233037) (xy 133.126251 -281.285332) (xy 133.103609 -281.334909) (xy 133.074143 -281.380759)
			(xy 133.038452 -281.42195) (xy 132.997261 -281.457641) (xy 132.951411 -281.487107) (xy 132.901834 -281.509749)
			(xy 132.849539 -281.525104) (xy 132.795591 -281.53286) (xy 132.741089 -281.53286) (xy 132.687141 -281.525104)
			(xy 132.634846 -281.509749) (xy 132.585269 -281.487107) (xy 132.539419 -281.457641) (xy 132.498228 -281.42195)
			(xy 132.462537 -281.380759) (xy 132.433071 -281.334909) (xy 132.410429 -281.285332) (xy 132.395074 -281.233037)
			(xy 132.387318 -281.179089) (xy 132.386832 -281.151838) (xy 132.387581 -281.117754) (xy 132.399725 -281.050676)
			(xy 132.410962 -281.018488) (xy 132.415026 -281.007312) (xy 132.412486 -280.983436) (xy 132.355082 -280.89479)
			(xy 132.334508 -280.882598) (xy 132.32257 -280.881836) (xy 132.291272 -280.87909) (xy 132.230127 -280.86467)
			(xy 132.200904 -280.853134) (xy 132.190744 -280.848816) (xy 132.169408 -280.849324) (xy 132.08127 -280.891234)
			(xy 132.0673 -280.90749) (xy 132.064252 -280.918158) (xy 132.056057 -280.944129) (xy 132.033378 -280.993638)
			(xy 132.003889 -281.03942) (xy 131.968191 -281.080544) (xy 131.927007 -281.116173) (xy 131.881176 -281.145585)
			(xy 131.831628 -281.168181) (xy 131.779371 -281.183502) (xy 131.725466 -281.191236) (xy 131.698238 -281.191716)
			(xy 131.674882 -281.191348) (xy 131.628524 -281.185619) (xy 131.605782 -281.180286) (xy 131.59613 -281.178)
			(xy 131.57708 -281.18054) (xy 131.49834 -281.225752) (xy 131.486402 -281.240992) (xy 131.483608 -281.250644)
			(xy 131.475566 -281.276749) (xy 131.453016 -281.3265) (xy 131.423599 -281.372525) (xy 131.387915 -281.413882)
			(xy 131.346695 -281.449723) (xy 131.300783 -281.479317) (xy 131.251118 -281.502056) (xy 131.198717 -281.517477)
			(xy 131.144652 -281.525262) (xy 131.11734 -281.525726) (xy 131.090089 -281.525208) (xy 131.036141 -281.517456)
			(xy 130.983845 -281.502106) (xy 130.934266 -281.47947) (xy 130.888414 -281.450008) (xy 130.847221 -281.41432)
			(xy 130.811527 -281.373133) (xy 130.782058 -281.327285) (xy 130.759414 -281.277709) (xy 130.744056 -281.225416)
			(xy 130.736297 -281.171469) (xy 130.735832 -281.144218) (xy 130.735889 -281.133592) (xy 130.737032 -281.112371)
			(xy 130.738118 -281.1018) (xy 130.739388 -281.092148) (xy 130.734562 -281.07386) (xy 130.683 -281.002994)
			(xy 130.666998 -280.992834) (xy 130.6576 -280.990802) (xy 130.6293 -280.984437) (xy 130.574912 -280.964276)
			(xy 130.524204 -280.936113) (xy 130.478344 -280.900597) (xy 130.43839 -280.858547) (xy 130.405263 -280.810934)
			(xy 130.379727 -280.758853) (xy 130.36237 -280.703506) (xy 130.353593 -280.64617) (xy 130.353054 -280.617168)
			(xy 124.550862 -280.617168) (xy 124.544836 -280.63444) (xy 124.540772 -280.645616) (xy 124.543312 -280.669492)
			(xy 124.600716 -280.758138) (xy 124.62129 -280.77033) (xy 124.633228 -280.771092) (xy 124.661836 -280.773556)
			(xy 124.717902 -280.785935) (xy 124.771482 -280.806573) (xy 124.821365 -280.835005) (xy 124.866426 -280.870589)
			(xy 124.905648 -280.912521) (xy 124.938145 -280.959856) (xy 124.95745 -280.999692) (xy 125.69647 -280.999692)
			(xy 125.700541 -280.94407) (xy 125.712667 -280.889633) (xy 125.73259 -280.837542) (xy 125.759886 -280.788907)
			(xy 125.793972 -280.744764) (xy 125.834121 -280.706055) (xy 125.879479 -280.673604) (xy 125.929079 -280.648103)
			(xy 125.981863 -280.630096) (xy 126.036706 -280.619966) (xy 126.09244 -280.617929) (xy 126.147877 -280.624029)
			(xy 126.201834 -280.638135) (xy 126.253163 -280.659947) (xy 126.300769 -280.689001) (xy 126.343637 -280.724676)
			(xy 126.380854 -280.766213) (xy 126.411627 -280.812726) (xy 126.435299 -280.863223) (xy 126.451367 -280.91663)
			(xy 126.459487 -280.971806) (xy 126.459996 -280.999692) (xy 126.459487 -281.027578) (xy 126.451367 -281.082754)
			(xy 126.435299 -281.136161) (xy 126.411627 -281.186658) (xy 126.380854 -281.233171) (xy 126.343637 -281.274708)
			(xy 126.300769 -281.310383) (xy 126.253163 -281.339437) (xy 126.201834 -281.361249) (xy 126.147877 -281.375355)
			(xy 126.09244 -281.381455) (xy 126.036706 -281.379418) (xy 125.981863 -281.369288) (xy 125.929079 -281.351281)
			(xy 125.879479 -281.32578) (xy 125.834121 -281.293329) (xy 125.793972 -281.25462) (xy 125.759886 -281.210477)
			(xy 125.73259 -281.161842) (xy 125.712667 -281.109751) (xy 125.700541 -281.055314) (xy 125.69647 -280.999692)
			(xy 124.95745 -280.999692) (xy 124.963185 -281.011525) (xy 124.980203 -281.066362) (xy 124.988813 -281.12313)
			(xy 124.989336 -281.151838) (xy 124.98885 -281.179089) (xy 124.981094 -281.233037) (xy 124.965739 -281.285332)
			(xy 124.943097 -281.334909) (xy 124.913631 -281.380759) (xy 124.87794 -281.42195) (xy 124.836749 -281.457641)
			(xy 124.790899 -281.487107) (xy 124.741322 -281.509749) (xy 124.689027 -281.525104) (xy 124.635079 -281.53286)
			(xy 124.580577 -281.53286) (xy 124.526629 -281.525104) (xy 124.474334 -281.509749) (xy 124.424757 -281.487107)
			(xy 124.378907 -281.457641) (xy 124.337716 -281.42195) (xy 124.302025 -281.380759) (xy 124.272559 -281.334909)
			(xy 124.249917 -281.285332) (xy 124.234562 -281.233037) (xy 124.226806 -281.179089) (xy 124.22632 -281.151838)
			(xy 124.22707 -281.117754) (xy 124.239214 -281.050676) (xy 124.25045 -281.018488) (xy 124.254514 -281.007312)
			(xy 124.251974 -280.983436) (xy 124.19457 -280.89479) (xy 124.173996 -280.882598) (xy 124.162058 -280.881836)
			(xy 124.13076 -280.879093) (xy 124.069615 -280.864671) (xy 124.040392 -280.853134) (xy 124.030232 -280.848816)
			(xy 124.008896 -280.849324) (xy 123.920758 -280.891234) (xy 123.906788 -280.90749) (xy 123.90374 -280.918158)
			(xy 123.895555 -280.944132) (xy 123.872875 -280.993643) (xy 123.843386 -281.039425) (xy 123.807686 -281.080549)
			(xy 123.766501 -281.116178) (xy 123.720668 -281.145589) (xy 123.671119 -281.168184) (xy 123.618861 -281.183504)
			(xy 123.564955 -281.191237) (xy 123.537726 -281.191716) (xy 123.51437 -281.19135) (xy 123.468011 -281.18562)
			(xy 123.44527 -281.180286) (xy 123.435618 -281.178) (xy 123.416568 -281.18054) (xy 123.337828 -281.225752)
			(xy 123.32589 -281.240992) (xy 123.323096 -281.250644) (xy 123.315064 -281.276752) (xy 123.292514 -281.326504)
			(xy 123.263095 -281.37253) (xy 123.22741 -281.413886) (xy 123.186189 -281.449728) (xy 123.140276 -281.479321)
			(xy 123.090609 -281.50206) (xy 123.038207 -281.517479) (xy 122.98414 -281.525263) (xy 122.956828 -281.525726)
			(xy 122.929577 -281.525219) (xy 122.875628 -281.517466) (xy 122.823332 -281.502114) (xy 122.773753 -281.479477)
			(xy 122.727901 -281.450013) (xy 122.686709 -281.414324) (xy 122.651015 -281.373136) (xy 122.621546 -281.327287)
			(xy 122.598902 -281.277711) (xy 122.583544 -281.225417) (xy 122.575785 -281.171469) (xy 122.57532 -281.144218)
			(xy 122.575377 -281.133592) (xy 122.57652 -281.112371) (xy 122.577606 -281.1018) (xy 122.578876 -281.092148)
			(xy 122.57405 -281.07386) (xy 122.522488 -281.002994) (xy 122.506486 -280.992834) (xy 122.497088 -280.990802)
			(xy 122.468786 -280.984445) (xy 122.414398 -280.964282) (xy 122.36369 -280.936118) (xy 122.317831 -280.900601)
			(xy 122.277877 -280.85855) (xy 122.24475 -280.810936) (xy 122.219214 -280.758854) (xy 122.201858 -280.703507)
			(xy 122.193081 -280.64617) (xy 122.192542 -280.617168) (xy 116.052276 -280.617168) (xy 116.04625 -280.63444)
			(xy 116.042186 -280.645616) (xy 116.044726 -280.669492) (xy 116.10213 -280.758138) (xy 116.122704 -280.77033)
			(xy 116.134642 -280.771092) (xy 116.163251 -280.773544) (xy 116.219318 -280.785925) (xy 116.272897 -280.806565)
			(xy 116.32278 -280.834999) (xy 116.367841 -280.870584) (xy 116.407062 -280.912517) (xy 116.43956 -280.959853)
			(xy 116.4646 -281.011523) (xy 116.46621 -281.01671) (xy 117.197884 -281.01671) (xy 117.201955 -280.961088)
			(xy 117.214081 -280.906651) (xy 117.234004 -280.85456) (xy 117.2613 -280.805925) (xy 117.295386 -280.761782)
			(xy 117.335535 -280.723073) (xy 117.380893 -280.690622) (xy 117.430493 -280.665121) (xy 117.483277 -280.647114)
			(xy 117.53812 -280.636984) (xy 117.593854 -280.634947) (xy 117.649291 -280.641047) (xy 117.703248 -280.655153)
			(xy 117.754577 -280.676965) (xy 117.802183 -280.706019) (xy 117.845051 -280.741694) (xy 117.882268 -280.783231)
			(xy 117.913041 -280.829744) (xy 117.936713 -280.880241) (xy 117.952781 -280.933648) (xy 117.960901 -280.988824)
			(xy 117.96141 -281.01671) (xy 117.960901 -281.044596) (xy 117.952781 -281.099772) (xy 117.936713 -281.153179)
			(xy 117.913041 -281.203676) (xy 117.882268 -281.250189) (xy 117.845051 -281.291726) (xy 117.802183 -281.327401)
			(xy 117.754577 -281.356455) (xy 117.703248 -281.378267) (xy 117.649291 -281.392373) (xy 117.593854 -281.398473)
			(xy 117.53812 -281.396436) (xy 117.483277 -281.386306) (xy 117.430493 -281.368299) (xy 117.380893 -281.342798)
			(xy 117.335535 -281.310347) (xy 117.295386 -281.271638) (xy 117.2613 -281.227495) (xy 117.234004 -281.17886)
			(xy 117.214081 -281.126769) (xy 117.201955 -281.072332) (xy 117.197884 -281.01671) (xy 116.46621 -281.01671)
			(xy 116.481617 -281.066361) (xy 116.490227 -281.123129) (xy 116.49075 -281.151838) (xy 116.490264 -281.179089)
			(xy 116.482508 -281.233037) (xy 116.467153 -281.285332) (xy 116.444511 -281.334909) (xy 116.415045 -281.380759)
			(xy 116.379354 -281.42195) (xy 116.338163 -281.457641) (xy 116.292313 -281.487107) (xy 116.242736 -281.509749)
			(xy 116.190441 -281.525104) (xy 116.136493 -281.53286) (xy 116.081991 -281.53286) (xy 116.028043 -281.525104)
			(xy 115.975748 -281.509749) (xy 115.926171 -281.487107) (xy 115.880321 -281.457641) (xy 115.83913 -281.42195)
			(xy 115.803439 -281.380759) (xy 115.773973 -281.334909) (xy 115.751331 -281.285332) (xy 115.735976 -281.233037)
			(xy 115.72822 -281.179089) (xy 115.727734 -281.151838) (xy 115.728483 -281.117754) (xy 115.740627 -281.050676)
			(xy 115.751864 -281.018488) (xy 115.755928 -281.007312) (xy 115.753388 -280.983436) (xy 115.695984 -280.89479)
			(xy 115.67541 -280.882598) (xy 115.663472 -280.881836) (xy 115.632174 -280.879089) (xy 115.571029 -280.86467)
			(xy 115.541806 -280.853134) (xy 115.531646 -280.848816) (xy 115.51031 -280.849324) (xy 115.422172 -280.891234)
			(xy 115.408202 -280.90749) (xy 115.405154 -280.918158) (xy 115.396957 -280.944128) (xy 115.374278 -280.993638)
			(xy 115.34479 -281.039419) (xy 115.309091 -281.080543) (xy 115.267908 -281.116173) (xy 115.222077 -281.145584)
			(xy 115.17253 -281.16818) (xy 115.120273 -281.183501) (xy 115.066368 -281.191236) (xy 115.03914 -281.191716)
			(xy 115.015784 -281.191347) (xy 114.969426 -281.185619) (xy 114.946684 -281.180286) (xy 114.937032 -281.178)
			(xy 114.917982 -281.18054) (xy 114.839242 -281.225752) (xy 114.827304 -281.240992) (xy 114.82451 -281.250644)
			(xy 114.816466 -281.276748) (xy 114.793917 -281.326499) (xy 114.764499 -281.372524) (xy 114.728816 -281.413881)
			(xy 114.687596 -281.449723) (xy 114.641685 -281.479316) (xy 114.59202 -281.502056) (xy 114.539619 -281.517476)
			(xy 114.485554 -281.525262) (xy 114.458242 -281.525726) (xy 114.430991 -281.525206) (xy 114.377043 -281.517455)
			(xy 114.324747 -281.502105) (xy 114.275169 -281.479469) (xy 114.229316 -281.450007) (xy 114.188123 -281.414319)
			(xy 114.152429 -281.373132) (xy 114.12296 -281.327284) (xy 114.100316 -281.277709) (xy 114.084958 -281.225416)
			(xy 114.077199 -281.171469) (xy 114.076734 -281.144218) (xy 114.076791 -281.133592) (xy 114.077934 -281.112371)
			(xy 114.07902 -281.1018) (xy 114.08029 -281.092148) (xy 114.075464 -281.07386) (xy 114.023902 -281.002994)
			(xy 114.0079 -280.992834) (xy 113.998502 -280.990802) (xy 113.970202 -280.984435) (xy 113.915815 -280.964275)
			(xy 113.865106 -280.936112) (xy 113.819246 -280.900596) (xy 113.779292 -280.858547) (xy 113.746165 -280.810933)
			(xy 113.720629 -280.758853) (xy 113.703272 -280.703506) (xy 113.694495 -280.64617) (xy 113.693956 -280.617168)
			(xy 107.891764 -280.617168) (xy 107.885738 -280.63444) (xy 107.881674 -280.645616) (xy 107.884214 -280.669492)
			(xy 107.941618 -280.758138) (xy 107.962192 -280.77033) (xy 107.97413 -280.771092) (xy 108.002738 -280.773554)
			(xy 108.058804 -280.785934) (xy 108.112384 -280.806572) (xy 108.162267 -280.835004) (xy 108.207328 -280.870588)
			(xy 108.24655 -280.912521) (xy 108.279047 -280.959856) (xy 108.304087 -281.011525) (xy 108.321105 -281.066362)
			(xy 108.329715 -281.12313) (xy 108.330238 -281.151838) (xy 108.329975 -281.16657) (xy 108.75594 -281.16657)
			(xy 108.760011 -281.110948) (xy 108.772137 -281.056511) (xy 108.79206 -281.00442) (xy 108.819356 -280.955785)
			(xy 108.853442 -280.911642) (xy 108.893591 -280.872933) (xy 108.938949 -280.840482) (xy 108.988549 -280.814981)
			(xy 109.041333 -280.796974) (xy 109.096176 -280.786844) (xy 109.15191 -280.784807) (xy 109.207347 -280.790907)
			(xy 109.261304 -280.805013) (xy 109.312633 -280.826825) (xy 109.360239 -280.855879) (xy 109.403107 -280.891554)
			(xy 109.440324 -280.933091) (xy 109.471097 -280.979604) (xy 109.494769 -281.030101) (xy 109.510837 -281.083508)
			(xy 109.518957 -281.138684) (xy 109.519466 -281.16657) (xy 109.518957 -281.194456) (xy 109.510837 -281.249632)
			(xy 109.494769 -281.303039) (xy 109.471097 -281.353536) (xy 109.440324 -281.400049) (xy 109.403107 -281.441586)
			(xy 109.360239 -281.477261) (xy 109.312633 -281.506315) (xy 109.261304 -281.528127) (xy 109.207347 -281.542233)
			(xy 109.15191 -281.548333) (xy 109.096176 -281.546296) (xy 109.041333 -281.536166) (xy 108.988549 -281.518159)
			(xy 108.938949 -281.492658) (xy 108.893591 -281.460207) (xy 108.853442 -281.421498) (xy 108.819356 -281.377355)
			(xy 108.79206 -281.32872) (xy 108.772137 -281.276629) (xy 108.760011 -281.222192) (xy 108.75594 -281.16657)
			(xy 108.329975 -281.16657) (xy 108.329752 -281.179089) (xy 108.321996 -281.233037) (xy 108.306641 -281.285332)
			(xy 108.283999 -281.334909) (xy 108.254533 -281.380759) (xy 108.218842 -281.42195) (xy 108.177651 -281.457641)
			(xy 108.131801 -281.487107) (xy 108.082224 -281.509749) (xy 108.029929 -281.525104) (xy 107.975981 -281.53286)
			(xy 107.921479 -281.53286) (xy 107.867531 -281.525104) (xy 107.815236 -281.509749) (xy 107.765659 -281.487107)
			(xy 107.719809 -281.457641) (xy 107.678618 -281.42195) (xy 107.642927 -281.380759) (xy 107.613461 -281.334909)
			(xy 107.590819 -281.285332) (xy 107.575464 -281.233037) (xy 107.567708 -281.179089) (xy 107.567222 -281.151838)
			(xy 107.567971 -281.117754) (xy 107.580116 -281.050676) (xy 107.591352 -281.018488) (xy 107.595416 -281.007312)
			(xy 107.592876 -280.983436) (xy 107.535472 -280.89479) (xy 107.514898 -280.882598) (xy 107.50296 -280.881836)
			(xy 107.471662 -280.879092) (xy 107.410517 -280.864671) (xy 107.381294 -280.853134) (xy 107.371134 -280.848816)
			(xy 107.349798 -280.849324) (xy 107.26166 -280.891234) (xy 107.24769 -280.90749) (xy 107.244642 -280.918158)
			(xy 107.236455 -280.944132) (xy 107.213776 -280.993642) (xy 107.184286 -281.039424) (xy 107.148587 -281.080548)
			(xy 107.107402 -281.116177) (xy 107.06157 -281.145588) (xy 107.012021 -281.168184) (xy 106.959763 -281.183504)
			(xy 106.905857 -281.191237) (xy 106.878628 -281.191716) (xy 106.855272 -281.19135) (xy 106.808913 -281.185619)
			(xy 106.786172 -281.180286) (xy 106.77652 -281.178) (xy 106.75747 -281.18054) (xy 106.67873 -281.225752)
			(xy 106.666792 -281.240992) (xy 106.663998 -281.250644) (xy 106.655965 -281.276752) (xy 106.633414 -281.326504)
			(xy 106.603996 -281.372529) (xy 106.568311 -281.413886) (xy 106.52709 -281.449727) (xy 106.481177 -281.47932)
			(xy 106.431511 -281.502059) (xy 106.379109 -281.517479) (xy 106.325042 -281.525263) (xy 106.29773 -281.525726)
			(xy 106.270479 -281.525217) (xy 106.21653 -281.517464) (xy 106.164234 -281.502113) (xy 106.114656 -281.479475)
			(xy 106.068803 -281.450012) (xy 106.027611 -281.414323) (xy 105.991917 -281.373135) (xy 105.962448 -281.327287)
			(xy 105.939804 -281.277711) (xy 105.924446 -281.225417) (xy 105.916687 -281.171469) (xy 105.916222 -281.144218)
			(xy 105.916279 -281.133592) (xy 105.917422 -281.112371) (xy 105.918508 -281.1018) (xy 105.919778 -281.092148)
			(xy 105.914952 -281.07386) (xy 105.86339 -281.002994) (xy 105.847388 -280.992834) (xy 105.83799 -280.990802)
			(xy 105.809688 -280.984444) (xy 105.755301 -280.964281) (xy 105.704593 -280.936117) (xy 105.658733 -280.9006)
			(xy 105.618779 -280.85855) (xy 105.585652 -280.810935) (xy 105.560116 -280.758854) (xy 105.54276 -280.703507)
			(xy 105.533983 -280.64617) (xy 105.533444 -280.617168) (xy 99.589336 -280.617168) (xy 99.589336 -282.904438)
			(xy 101.903022 -282.904438) (xy 101.903506 -282.876864) (xy 101.911454 -282.822292) (xy 101.927175 -282.769432)
			(xy 101.950341 -282.719386) (xy 101.980471 -282.673196) (xy 102.016936 -282.631824) (xy 102.037642 -282.613608)
			(xy 102.045759 -282.606005) (xy 102.055112 -282.585853) (xy 102.055676 -282.574746) (xy 102.055676 -282.49753)
			(xy 102.055115 -282.486419) (xy 102.045772 -282.46626) (xy 102.037642 -282.458668) (xy 102.016973 -282.440412)
			(xy 101.980505 -282.399048) (xy 101.950375 -282.352863) (xy 101.927208 -282.302821) (xy 101.911489 -282.249965)
			(xy 101.903545 -282.195397) (xy 101.903542 -282.140253) (xy 101.911479 -282.085683) (xy 101.927191 -282.032825)
			(xy 101.950351 -281.98278) (xy 101.980476 -281.936592) (xy 102.016937 -281.895223) (xy 102.037642 -281.877008)
			(xy 102.045759 -281.869405) (xy 102.055112 -281.849253) (xy 102.055676 -281.838146) (xy 102.055676 -281.76093)
			(xy 102.055115 -281.749819) (xy 102.045772 -281.72966) (xy 102.037642 -281.722068) (xy 102.016921 -281.703868)
			(xy 101.980449 -281.662498) (xy 101.950317 -281.616306) (xy 101.927153 -281.566256) (xy 101.911439 -281.513391)
			(xy 101.903504 -281.458814) (xy 101.903022 -281.431238) (xy 101.903491 -281.403985) (xy 101.911243 -281.350032)
			(xy 101.926596 -281.297733) (xy 101.949236 -281.248151) (xy 101.978703 -281.202296) (xy 102.014397 -281.161102)
			(xy 102.05559 -281.125408) (xy 102.101444 -281.09594) (xy 102.151025 -281.073299) (xy 102.203325 -281.057945)
			(xy 102.257277 -281.050191) (xy 102.28453 -281.04973) (xy 102.312387 -281.050204) (xy 102.367506 -281.058332)
			(xy 102.420859 -281.074383) (xy 102.471313 -281.098016) (xy 102.517798 -281.128729) (xy 102.559327 -281.165871)
			(xy 102.595019 -281.208652) (xy 102.624116 -281.256165) (xy 102.646 -281.307402) (xy 102.653592 -281.33421)
			(xy 102.655878 -281.3431) (xy 102.666546 -281.35834) (xy 102.738428 -281.406092) (xy 102.756462 -281.410156)
			(xy 102.765606 -281.408886) (xy 102.778623 -281.407218) (xy 102.804807 -281.405437) (xy 102.81793 -281.40533)
			(xy 102.831053 -281.405425) (xy 102.857239 -281.407203) (xy 102.870254 -281.408886) (xy 102.879398 -281.410156)
			(xy 102.897432 -281.406092) (xy 102.969314 -281.35834) (xy 102.979982 -281.3431) (xy 102.982268 -281.33421)
			(xy 102.989866 -281.307402) (xy 103.011728 -281.256153) (xy 103.040812 -281.208628) (xy 103.076499 -281.165839)
			(xy 103.118029 -281.128694) (xy 103.16452 -281.097985) (xy 103.214983 -281.074364) (xy 103.268345 -281.058334)
			(xy 103.323471 -281.050234) (xy 103.35133 -281.04973) (xy 103.378585 -281.050127) (xy 103.432541 -281.057889)
			(xy 103.484842 -281.073251) (xy 103.534425 -281.0959) (xy 103.58028 -281.125374) (xy 103.621473 -281.161075)
			(xy 103.657166 -281.202275) (xy 103.686633 -281.248135) (xy 103.709273 -281.297722) (xy 103.724625 -281.350026)
			(xy 103.732378 -281.403983) (xy 103.732838 -281.431238) (xy 103.732367 -281.458537) (xy 103.724591 -281.512579)
			(xy 103.709189 -281.564959) (xy 103.686476 -281.614609) (xy 103.656915 -281.660512) (xy 103.639366 -281.681428)
			(xy 103.633016 -281.688794) (xy 103.626666 -281.706574) (xy 103.630222 -281.795982) (xy 103.637842 -281.813254)
			(xy 103.6447 -281.820112) (xy 103.665831 -281.841741) (xy 103.701631 -281.89047) (xy 103.729295 -281.944237)
			(xy 103.735566 -281.963368) (xy 108.281722 -281.963368) (xy 108.285793 -281.907746) (xy 108.297919 -281.853309)
			(xy 108.317842 -281.801218) (xy 108.345138 -281.752583) (xy 108.379224 -281.70844) (xy 108.419373 -281.669731)
			(xy 108.464731 -281.63728) (xy 108.514331 -281.611779) (xy 108.567115 -281.593772) (xy 108.621958 -281.583642)
			(xy 108.677692 -281.581605) (xy 108.733129 -281.587705) (xy 108.787086 -281.601811) (xy 108.838415 -281.623623)
			(xy 108.886021 -281.652677) (xy 108.928889 -281.688352) (xy 108.966106 -281.729889) (xy 108.996879 -281.776402)
			(xy 109.020551 -281.826899) (xy 109.036619 -281.880306) (xy 109.044739 -281.935482) (xy 109.045248 -281.963368)
			(xy 109.044739 -281.991254) (xy 109.036619 -282.04643) (xy 109.020551 -282.099837) (xy 108.996879 -282.150334)
			(xy 108.966106 -282.196847) (xy 108.928889 -282.238384) (xy 108.886021 -282.274059) (xy 108.838415 -282.303113)
			(xy 108.787086 -282.324925) (xy 108.733129 -282.339031) (xy 108.677692 -282.345131) (xy 108.621958 -282.343094)
			(xy 108.567115 -282.332964) (xy 108.514331 -282.314957) (xy 108.464731 -282.289456) (xy 108.419373 -282.257005)
			(xy 108.379224 -282.218296) (xy 108.345138 -282.174153) (xy 108.317842 -282.125518) (xy 108.297919 -282.073427)
			(xy 108.285793 -282.01899) (xy 108.281722 -281.963368) (xy 103.735566 -281.963368) (xy 103.74813 -282.001695)
			(xy 103.757663 -282.061405) (xy 103.758238 -282.091638) (xy 103.757742 -282.119276) (xy 103.74975 -282.173971)
			(xy 103.733952 -282.226942) (xy 103.710681 -282.277081) (xy 103.680421 -282.323338) (xy 103.66248 -282.344368)
			(xy 103.654098 -282.35402) (xy 103.648256 -282.378404) (xy 103.675434 -282.484576) (xy 103.692452 -282.503118)
			(xy 103.70439 -282.507436) (xy 103.731799 -282.517772) (xy 103.783314 -282.545654) (xy 103.829959 -282.581086)
			(xy 103.870637 -282.623235) (xy 103.904391 -282.671108) (xy 103.930427 -282.72358) (xy 103.948133 -282.779416)
			(xy 103.957092 -282.837304) (xy 103.957628 -282.866592) (xy 103.957115 -282.893842) (xy 103.957113 -282.893854)
			(xy 104.287247 -282.893854) (xy 104.287247 -282.839346) (xy 104.295005 -282.785392) (xy 104.310362 -282.733091)
			(xy 104.333007 -282.683509) (xy 104.362477 -282.637654) (xy 104.398174 -282.59646) (xy 104.43937 -282.560765)
			(xy 104.485226 -282.531297) (xy 104.53481 -282.508655) (xy 104.587111 -282.493301) (xy 104.641066 -282.485546)
			(xy 104.66832 -282.485084) (xy 104.695692 -282.485518) (xy 104.749873 -282.49334) (xy 104.802377 -282.508836)
			(xy 104.852124 -282.531685) (xy 104.898088 -282.561418) (xy 104.919018 -282.579064) (xy 104.92613 -282.58516)
			(xy 104.943148 -282.59151) (xy 105.028492 -282.59151) (xy 105.04551 -282.58516) (xy 105.052622 -282.579064)
			(xy 105.073568 -282.561442) (xy 105.119538 -282.531729) (xy 105.169282 -282.50889) (xy 105.221779 -282.493395)
			(xy 105.275952 -282.485561) (xy 105.30332 -282.485084) (xy 105.33057 -282.485587) (xy 105.384514 -282.493346)
			(xy 105.436805 -282.508702) (xy 105.486379 -282.531344) (xy 105.532226 -282.56081) (xy 105.573413 -282.596501)
			(xy 105.609102 -282.63769) (xy 105.638565 -282.683538) (xy 105.661205 -282.733113) (xy 105.676558 -282.785405)
			(xy 105.684314 -282.83935) (xy 105.684314 -282.89385) (xy 105.682792 -282.904438) (xy 110.063534 -282.904438)
			(xy 110.064014 -282.876864) (xy 110.071962 -282.822291) (xy 110.087683 -282.769431) (xy 110.110851 -282.719385)
			(xy 110.140981 -282.673195) (xy 110.177447 -282.631824) (xy 110.198154 -282.613608) (xy 110.206273 -282.606006)
			(xy 110.215625 -282.585854) (xy 110.216188 -282.574746) (xy 110.216188 -282.49753) (xy 110.215623 -282.48642)
			(xy 110.206283 -282.466261) (xy 110.198154 -282.458668) (xy 110.177484 -282.440412) (xy 110.141016 -282.399048)
			(xy 110.110884 -282.352864) (xy 110.087717 -282.302822) (xy 110.071997 -282.249966) (xy 110.064053 -282.195397)
			(xy 110.064049 -282.140252) (xy 110.071987 -282.085682) (xy 110.087699 -282.032824) (xy 110.11086 -281.982779)
			(xy 110.140986 -281.936591) (xy 110.177449 -281.895222) (xy 110.198154 -281.877008) (xy 110.206273 -281.869406)
			(xy 110.215625 -281.849254) (xy 110.216188 -281.838146) (xy 110.216188 -281.76093) (xy 110.215623 -281.74982)
			(xy 110.206283 -281.729661) (xy 110.198154 -281.722068) (xy 110.177415 -281.703887) (xy 110.140949 -281.662511)
			(xy 110.110821 -281.616314) (xy 110.087661 -281.566261) (xy 110.07195 -281.513393) (xy 110.064016 -281.458814)
			(xy 110.063534 -281.431238) (xy 110.063991 -281.403984) (xy 110.071744 -281.350031) (xy 110.087097 -281.29773)
			(xy 110.109738 -281.248147) (xy 110.139206 -281.202292) (xy 110.174901 -281.161098) (xy 110.216095 -281.125404)
			(xy 110.261951 -281.095936) (xy 110.311534 -281.073296) (xy 110.363835 -281.057943) (xy 110.417788 -281.050191)
			(xy 110.445042 -281.04973) (xy 110.4729 -281.050193) (xy 110.528019 -281.058323) (xy 110.581372 -281.074376)
			(xy 110.631826 -281.09801) (xy 110.678311 -281.128725) (xy 110.71984 -281.165867) (xy 110.755531 -281.20865)
			(xy 110.784628 -281.256164) (xy 110.806512 -281.307402) (xy 110.814104 -281.33421) (xy 110.81639 -281.3431)
			(xy 110.827058 -281.35834) (xy 110.89894 -281.406092) (xy 110.916974 -281.410156) (xy 110.926118 -281.408886)
			(xy 110.939135 -281.407217) (xy 110.965319 -281.405437) (xy 110.978442 -281.40533) (xy 110.991565 -281.405424)
			(xy 111.017751 -281.407203) (xy 111.030766 -281.408886) (xy 111.03991 -281.410156) (xy 111.057944 -281.406092)
			(xy 111.129826 -281.35834) (xy 111.140494 -281.3431) (xy 111.14278 -281.33421) (xy 111.150367 -281.307399)
			(xy 111.17223 -281.256149) (xy 111.201315 -281.208623) (xy 111.237003 -281.165834) (xy 111.278535 -281.12869)
			(xy 111.325028 -281.097981) (xy 111.375492 -281.074361) (xy 111.428855 -281.058331) (xy 111.483983 -281.050233)
			(xy 111.511842 -281.04973) (xy 111.539096 -281.050139) (xy 111.593048 -281.057902) (xy 111.645347 -281.073264)
			(xy 111.694927 -281.095913) (xy 111.740779 -281.125387) (xy 111.78197 -281.161087) (xy 111.817661 -281.202285)
			(xy 111.847125 -281.248143) (xy 111.869764 -281.297728) (xy 111.885115 -281.35003) (xy 111.892867 -281.403984)
			(xy 111.89335 -281.431238) (xy 111.892876 -281.458537) (xy 111.8851 -281.512578) (xy 111.869699 -281.564959)
			(xy 111.846986 -281.614608) (xy 111.817427 -281.660512) (xy 111.799878 -281.681428) (xy 111.793528 -281.688794)
			(xy 111.787178 -281.706574) (xy 111.790734 -281.795982) (xy 111.798354 -281.813254) (xy 111.805212 -281.820112)
			(xy 111.826328 -281.841756) (xy 111.862133 -281.890479) (xy 111.889802 -281.944242) (xy 111.896073 -281.963368)
			(xy 116.442234 -281.963368) (xy 116.446305 -281.907746) (xy 116.458431 -281.853309) (xy 116.478354 -281.801218)
			(xy 116.50565 -281.752583) (xy 116.539736 -281.70844) (xy 116.579885 -281.669731) (xy 116.625243 -281.63728)
			(xy 116.674843 -281.611779) (xy 116.727627 -281.593772) (xy 116.78247 -281.583642) (xy 116.838204 -281.581605)
			(xy 116.893641 -281.587705) (xy 116.947598 -281.601811) (xy 116.998927 -281.623623) (xy 117.046533 -281.652677)
			(xy 117.089401 -281.688352) (xy 117.126618 -281.729889) (xy 117.157391 -281.776402) (xy 117.181063 -281.826899)
			(xy 117.197131 -281.880306) (xy 117.205251 -281.935482) (xy 117.20576 -281.963368) (xy 117.205251 -281.991254)
			(xy 117.197131 -282.04643) (xy 117.181063 -282.099837) (xy 117.157391 -282.150334) (xy 117.126618 -282.196847)
			(xy 117.089401 -282.238384) (xy 117.046533 -282.274059) (xy 116.998927 -282.303113) (xy 116.947598 -282.324925)
			(xy 116.893641 -282.339031) (xy 116.838204 -282.345131) (xy 116.78247 -282.343094) (xy 116.727627 -282.332964)
			(xy 116.674843 -282.314957) (xy 116.625243 -282.289456) (xy 116.579885 -282.257005) (xy 116.539736 -282.218296)
			(xy 116.50565 -282.174153) (xy 116.478354 -282.125518) (xy 116.458431 -282.073427) (xy 116.446305 -282.01899)
			(xy 116.442234 -281.963368) (xy 111.896073 -281.963368) (xy 111.90864 -282.001697) (xy 111.918175 -282.061406)
			(xy 111.91875 -282.091638) (xy 111.918251 -282.119276) (xy 111.910259 -282.173971) (xy 111.894462 -282.226942)
			(xy 111.871191 -282.27708) (xy 111.840932 -282.323338) (xy 111.822992 -282.344368) (xy 111.81461 -282.35402)
			(xy 111.808768 -282.378404) (xy 111.835946 -282.484576) (xy 111.852964 -282.503118) (xy 111.864902 -282.507436)
			(xy 111.892314 -282.517765) (xy 111.943828 -282.545649) (xy 111.990473 -282.581082) (xy 112.03115 -282.623232)
			(xy 112.064904 -282.671106) (xy 112.09094 -282.723579) (xy 112.108645 -282.779416) (xy 112.117604 -282.837304)
			(xy 112.11814 -282.866592) (xy 112.117605 -282.893855) (xy 112.447747 -282.893855) (xy 112.447747 -282.839345)
			(xy 112.455505 -282.78539) (xy 112.470863 -282.733089) (xy 112.493509 -282.683505) (xy 112.52298 -282.63765)
			(xy 112.558678 -282.596455) (xy 112.599876 -282.560761) (xy 112.645734 -282.531293) (xy 112.695319 -282.508652)
			(xy 112.747622 -282.493299) (xy 112.801577 -282.485545) (xy 112.828832 -282.485084) (xy 112.856204 -282.485511)
			(xy 112.910385 -282.493335) (xy 112.96289 -282.508832) (xy 113.012636 -282.531683) (xy 113.0586 -282.561418)
			(xy 113.07953 -282.579064) (xy 113.086642 -282.58516) (xy 113.10366 -282.59151) (xy 113.189004 -282.59151)
			(xy 113.206022 -282.58516) (xy 113.213134 -282.579064) (xy 113.234076 -282.561437) (xy 113.280046 -282.531724)
			(xy 113.329791 -282.508887) (xy 113.38229 -282.493393) (xy 113.436464 -282.48556) (xy 113.463832 -282.485084)
			(xy 113.491081 -282.485588) (xy 113.545024 -282.493348) (xy 113.597314 -282.508706) (xy 113.646886 -282.531348)
			(xy 113.692732 -282.560815) (xy 113.733917 -282.596505) (xy 113.769605 -282.637694) (xy 113.799067 -282.683542)
			(xy 113.821706 -282.733116) (xy 113.837059 -282.785407) (xy 113.844814 -282.839351) (xy 113.844814 -282.893849)
			(xy 113.843292 -282.904438) (xy 118.56212 -282.904438) (xy 118.562605 -282.876864) (xy 118.570552 -282.822292)
			(xy 118.586273 -282.769432) (xy 118.60944 -282.719386) (xy 118.639569 -282.673196) (xy 118.676034 -282.631824)
			(xy 118.69674 -282.613608) (xy 118.704857 -282.606004) (xy 118.71421 -282.585853) (xy 118.714774 -282.574746)
			(xy 118.714774 -282.49753) (xy 118.714214 -282.486419) (xy 118.704871 -282.46626) (xy 118.69674 -282.458668)
			(xy 118.676071 -282.440412) (xy 118.639604 -282.399047) (xy 118.609473 -282.352863) (xy 118.586307 -282.302821)
			(xy 118.570588 -282.249965) (xy 118.562644 -282.195397) (xy 118.56264 -282.140253) (xy 118.570577 -282.085683)
			(xy 118.586289 -282.032825) (xy 118.609449 -281.98278) (xy 118.639574 -281.936592) (xy 118.676035 -281.895223)
			(xy 118.69674 -281.877008) (xy 118.704857 -281.869404) (xy 118.71421 -281.849253) (xy 118.714774 -281.838146)
			(xy 118.714774 -281.76093) (xy 118.714214 -281.749819) (xy 118.704871 -281.72966) (xy 118.69674 -281.722068)
			(xy 118.676018 -281.703868) (xy 118.639547 -281.662498) (xy 118.609415 -281.616306) (xy 118.586251 -281.566256)
			(xy 118.570537 -281.513391) (xy 118.562602 -281.458814) (xy 118.56212 -281.431238) (xy 118.562591 -281.403985)
			(xy 118.570343 -281.350033) (xy 118.585696 -281.297733) (xy 118.608336 -281.248151) (xy 118.637803 -281.202297)
			(xy 118.673496 -281.161103) (xy 118.714689 -281.125409) (xy 118.760543 -281.095941) (xy 118.810124 -281.073299)
			(xy 118.862423 -281.057945) (xy 118.916375 -281.050191) (xy 118.943628 -281.04973) (xy 118.971485 -281.050206)
			(xy 119.026604 -281.058334) (xy 119.079956 -281.074385) (xy 119.130411 -281.098017) (xy 119.176896 -281.12873)
			(xy 119.218425 -281.165871) (xy 119.254117 -281.208652) (xy 119.283214 -281.256166) (xy 119.305098 -281.307402)
			(xy 119.31269 -281.33421) (xy 119.314976 -281.3431) (xy 119.325644 -281.35834) (xy 119.397526 -281.406092)
			(xy 119.41556 -281.410156) (xy 119.424704 -281.408886) (xy 119.437721 -281.407218) (xy 119.463905 -281.405438)
			(xy 119.477028 -281.40533) (xy 119.490151 -281.405425) (xy 119.516337 -281.407203) (xy 119.529352 -281.408886)
			(xy 119.538496 -281.410156) (xy 119.55653 -281.406092) (xy 119.628412 -281.35834) (xy 119.63908 -281.3431)
			(xy 119.641366 -281.33421) (xy 119.648875 -281.307374) (xy 119.670745 -281.25612) (xy 119.699839 -281.208591)
			(xy 119.735536 -281.1658) (xy 119.777078 -281.128657) (xy 119.823581 -281.097951) (xy 119.874056 -281.074336)
			(xy 119.927429 -281.058315) (xy 119.982565 -281.050227) (xy 120.010428 -281.04973) (xy 120.037683 -281.050129)
			(xy 120.091639 -281.057891) (xy 120.14394 -281.073252) (xy 120.193523 -281.095901) (xy 120.239378 -281.125375)
			(xy 120.280571 -281.161076) (xy 120.316264 -281.202275) (xy 120.345731 -281.248135) (xy 120.368371 -281.297722)
			(xy 120.383723 -281.350026) (xy 120.391476 -281.403983) (xy 120.391936 -281.431238) (xy 120.391466 -281.458537)
			(xy 120.383689 -281.512579) (xy 120.368287 -281.564959) (xy 120.345574 -281.614609) (xy 120.316013 -281.660512)
			(xy 120.298464 -281.681428) (xy 120.292114 -281.688794) (xy 120.285764 -281.706574) (xy 120.28932 -281.795982)
			(xy 120.29694 -281.813254) (xy 120.303798 -281.820112) (xy 120.324929 -281.841741) (xy 120.360729 -281.89047)
			(xy 120.388393 -281.944237) (xy 120.394664 -281.963368) (xy 124.94082 -281.963368) (xy 124.944891 -281.907746)
			(xy 124.957017 -281.853309) (xy 124.97694 -281.801218) (xy 125.004236 -281.752583) (xy 125.038322 -281.70844)
			(xy 125.078471 -281.669731) (xy 125.123829 -281.63728) (xy 125.173429 -281.611779) (xy 125.226213 -281.593772)
			(xy 125.281056 -281.583642) (xy 125.33679 -281.581605) (xy 125.392227 -281.587705) (xy 125.446184 -281.601811)
			(xy 125.497513 -281.623623) (xy 125.545119 -281.652677) (xy 125.587987 -281.688352) (xy 125.625204 -281.729889)
			(xy 125.655977 -281.776402) (xy 125.679649 -281.826899) (xy 125.695717 -281.880306) (xy 125.703837 -281.935482)
			(xy 125.704346 -281.963368) (xy 125.703837 -281.991254) (xy 125.695717 -282.04643) (xy 125.679649 -282.099837)
			(xy 125.655977 -282.150334) (xy 125.625204 -282.196847) (xy 125.587987 -282.238384) (xy 125.545119 -282.274059)
			(xy 125.497513 -282.303113) (xy 125.446184 -282.324925) (xy 125.392227 -282.339031) (xy 125.33679 -282.345131)
			(xy 125.281056 -282.343094) (xy 125.226213 -282.332964) (xy 125.173429 -282.314957) (xy 125.123829 -282.289456)
			(xy 125.078471 -282.257005) (xy 125.038322 -282.218296) (xy 125.004236 -282.174153) (xy 124.97694 -282.125518)
			(xy 124.957017 -282.073427) (xy 124.944891 -282.01899) (xy 124.94082 -281.963368) (xy 120.394664 -281.963368)
			(xy 120.407228 -282.001695) (xy 120.416761 -282.061405) (xy 120.417336 -282.091638) (xy 120.41684 -282.119276)
			(xy 120.408848 -282.173971) (xy 120.393051 -282.226942) (xy 120.369779 -282.277081) (xy 120.339519 -282.323339)
			(xy 120.321578 -282.344368) (xy 120.313196 -282.35402) (xy 120.307354 -282.378404) (xy 120.334532 -282.484576)
			(xy 120.35155 -282.503118) (xy 120.363488 -282.507436) (xy 120.390896 -282.517773) (xy 120.442411 -282.545655)
			(xy 120.489057 -282.581087) (xy 120.529735 -282.623235) (xy 120.563489 -282.671108) (xy 120.589525 -282.72358)
			(xy 120.607231 -282.779417) (xy 120.61619 -282.837304) (xy 120.616726 -282.866592) (xy 120.616192 -282.893854)
			(xy 120.946347 -282.893854) (xy 120.946347 -282.839346) (xy 120.954105 -282.785392) (xy 120.969462 -282.733092)
			(xy 120.992107 -282.683509) (xy 121.021577 -282.637654) (xy 121.057273 -282.59646) (xy 121.098469 -282.560766)
			(xy 121.144325 -282.531298) (xy 121.193909 -282.508656) (xy 121.24621 -282.493301) (xy 121.300164 -282.485546)
			(xy 121.327418 -282.485084) (xy 121.35479 -282.485519) (xy 121.408971 -282.493341) (xy 121.461475 -282.508836)
			(xy 121.511222 -282.531686) (xy 121.557186 -282.561418) (xy 121.578116 -282.579064) (xy 121.585228 -282.58516)
			(xy 121.602246 -282.59151) (xy 121.68759 -282.59151) (xy 121.704608 -282.58516) (xy 121.71172 -282.579064)
			(xy 121.732667 -282.561443) (xy 121.778636 -282.53173) (xy 121.82838 -282.508891) (xy 121.880877 -282.493396)
			(xy 121.93505 -282.485561) (xy 121.962418 -282.485084) (xy 121.989668 -282.485587) (xy 122.043612 -282.493345)
			(xy 122.095904 -282.508702) (xy 122.145478 -282.531343) (xy 122.191325 -282.56081) (xy 122.232512 -282.5965)
			(xy 122.268201 -282.637689) (xy 122.297665 -282.683538) (xy 122.320305 -282.733113) (xy 122.335658 -282.785405)
			(xy 122.343414 -282.83935) (xy 122.343414 -282.89385) (xy 122.341892 -282.904438) (xy 126.722632 -282.904438)
			(xy 126.723113 -282.876864) (xy 126.731061 -282.822291) (xy 126.746782 -282.769431) (xy 126.769949 -282.719385)
			(xy 126.800079 -282.673195) (xy 126.836545 -282.631824) (xy 126.857252 -282.613608) (xy 126.86537 -282.606006)
			(xy 126.874723 -282.585854) (xy 126.875286 -282.574746) (xy 126.875286 -282.49753) (xy 126.874722 -282.48642)
			(xy 126.865381 -282.466261) (xy 126.857252 -282.458668) (xy 126.836582 -282.440412) (xy 126.800114 -282.399048)
			(xy 126.769982 -282.352864) (xy 126.746815 -282.302822) (xy 126.731096 -282.249966) (xy 126.723152 -282.195397)
			(xy 126.723148 -282.140252) (xy 126.731085 -282.085682) (xy 126.746798 -282.032824) (xy 126.769959 -281.982779)
			(xy 126.800084 -281.936591) (xy 126.836547 -281.895222) (xy 126.857252 -281.877008) (xy 126.86537 -281.869406)
			(xy 126.874723 -281.849254) (xy 126.875286 -281.838146) (xy 126.875286 -281.76093) (xy 126.874722 -281.74982)
			(xy 126.865381 -281.729661) (xy 126.857252 -281.722068) (xy 126.836513 -281.703888) (xy 126.800046 -281.662511)
			(xy 126.769919 -281.616315) (xy 126.746759 -281.566261) (xy 126.731048 -281.513393) (xy 126.723114 -281.458814)
			(xy 126.722632 -281.431238) (xy 126.723091 -281.403984) (xy 126.730844 -281.350031) (xy 126.746197 -281.297731)
			(xy 126.768838 -281.248148) (xy 126.798306 -281.202293) (xy 126.834 -281.161099) (xy 126.875194 -281.125404)
			(xy 126.92105 -281.095937) (xy 126.970633 -281.073296) (xy 127.022933 -281.057943) (xy 127.076886 -281.050191)
			(xy 127.10414 -281.04973) (xy 127.131997 -281.050195) (xy 127.187117 -281.058325) (xy 127.240469 -281.074377)
			(xy 127.290924 -281.098011) (xy 127.337409 -281.128725) (xy 127.378938 -281.165868) (xy 127.414629 -281.20865)
			(xy 127.443726 -281.256164) (xy 127.46561 -281.307402) (xy 127.473202 -281.33421) (xy 127.475488 -281.3431)
			(xy 127.486156 -281.35834) (xy 127.558038 -281.406092) (xy 127.576072 -281.410156) (xy 127.585216 -281.408886)
			(xy 127.598233 -281.407217) (xy 127.624417 -281.405437) (xy 127.63754 -281.40533) (xy 127.650663 -281.405424)
			(xy 127.676849 -281.407203) (xy 127.689864 -281.408886) (xy 127.699008 -281.410156) (xy 127.717042 -281.406092)
			(xy 127.788924 -281.35834) (xy 127.799592 -281.3431) (xy 127.801878 -281.33421) (xy 127.809467 -281.307399)
			(xy 127.83133 -281.256149) (xy 127.860415 -281.208624) (xy 127.896103 -281.165835) (xy 127.937634 -281.12869)
			(xy 127.984126 -281.097982) (xy 128.034591 -281.074361) (xy 128.087954 -281.058332) (xy 128.143081 -281.050234)
			(xy 128.17094 -281.04973) (xy 128.198194 -281.050141) (xy 128.252146 -281.057904) (xy 128.304445 -281.073266)
			(xy 128.354025 -281.095914) (xy 128.399877 -281.125388) (xy 128.441068 -281.161088) (xy 128.476758 -281.202286)
			(xy 128.506223 -281.248144) (xy 128.528862 -281.297728) (xy 128.544213 -281.35003) (xy 128.551965 -281.403984)
			(xy 128.552448 -281.431238) (xy 128.551975 -281.458537) (xy 128.544199 -281.512578) (xy 128.528797 -281.564959)
			(xy 128.506085 -281.614608) (xy 128.476525 -281.660512) (xy 128.458976 -281.681428) (xy 128.452626 -281.688794)
			(xy 128.446276 -281.706574) (xy 128.449832 -281.795982) (xy 128.457452 -281.813254) (xy 128.46431 -281.820112)
			(xy 128.485426 -281.841756) (xy 128.521231 -281.890479) (xy 128.5489 -281.944242) (xy 128.555171 -281.963368)
			(xy 133.101332 -281.963368) (xy 133.105403 -281.907746) (xy 133.117529 -281.853309) (xy 133.137452 -281.801218)
			(xy 133.164748 -281.752583) (xy 133.198834 -281.70844) (xy 133.238983 -281.669731) (xy 133.284341 -281.63728)
			(xy 133.333941 -281.611779) (xy 133.386725 -281.593772) (xy 133.441568 -281.583642) (xy 133.497302 -281.581605)
			(xy 133.552739 -281.587705) (xy 133.606696 -281.601811) (xy 133.658025 -281.623623) (xy 133.705631 -281.652677)
			(xy 133.748499 -281.688352) (xy 133.785716 -281.729889) (xy 133.816489 -281.776402) (xy 133.840161 -281.826899)
			(xy 133.856229 -281.880306) (xy 133.864349 -281.935482) (xy 133.864858 -281.963368) (xy 133.864349 -281.991254)
			(xy 133.856229 -282.04643) (xy 133.840161 -282.099837) (xy 133.816489 -282.150334) (xy 133.785716 -282.196847)
			(xy 133.748499 -282.238384) (xy 133.705631 -282.274059) (xy 133.658025 -282.303113) (xy 133.606696 -282.324925)
			(xy 133.552739 -282.339031) (xy 133.497302 -282.345131) (xy 133.441568 -282.343094) (xy 133.386725 -282.332964)
			(xy 133.333941 -282.314957) (xy 133.284341 -282.289456) (xy 133.238983 -282.257005) (xy 133.198834 -282.218296)
			(xy 133.164748 -282.174153) (xy 133.137452 -282.125518) (xy 133.117529 -282.073427) (xy 133.105403 -282.01899)
			(xy 133.101332 -281.963368) (xy 128.555171 -281.963368) (xy 128.567738 -282.001697) (xy 128.577273 -282.061406)
			(xy 128.577848 -282.091638) (xy 128.577349 -282.119276) (xy 128.569357 -282.173971) (xy 128.553561 -282.226942)
			(xy 128.530289 -282.27708) (xy 128.50003 -282.323338) (xy 128.48209 -282.344368) (xy 128.473708 -282.35402)
			(xy 128.467866 -282.378404) (xy 128.495044 -282.484576) (xy 128.512062 -282.503118) (xy 128.524 -282.507436)
			(xy 128.551411 -282.517766) (xy 128.602926 -282.54565) (xy 128.64957 -282.581083) (xy 128.690248 -282.623232)
			(xy 128.724002 -282.671106) (xy 128.750038 -282.723579) (xy 128.767743 -282.779416) (xy 128.776702 -282.837304)
			(xy 128.777238 -282.866592) (xy 128.776703 -282.893855) (xy 129.106847 -282.893855) (xy 129.106847 -282.839345)
			(xy 129.114605 -282.785391) (xy 129.129963 -282.733089) (xy 129.152608 -282.683506) (xy 129.18208 -282.637651)
			(xy 129.217777 -282.596456) (xy 129.258975 -282.560762) (xy 129.304832 -282.531294) (xy 129.354417 -282.508653)
			(xy 129.40672 -282.493299) (xy 129.460675 -282.485545) (xy 129.48793 -282.485084) (xy 129.515302 -282.485512)
			(xy 129.569483 -282.493336) (xy 129.621988 -282.508833) (xy 129.671734 -282.531683) (xy 129.717698 -282.561418)
			(xy 129.738628 -282.579064) (xy 129.74574 -282.58516) (xy 129.762758 -282.59151) (xy 129.848102 -282.59151)
			(xy 129.86512 -282.58516) (xy 129.872232 -282.579064) (xy 129.893174 -282.561438) (xy 129.939145 -282.531725)
			(xy 129.98889 -282.508887) (xy 130.041388 -282.493393) (xy 130.095562 -282.485561) (xy 130.12293 -282.485084)
			(xy 130.150179 -282.485588) (xy 130.204123 -282.493348) (xy 130.256413 -282.508705) (xy 130.305985 -282.531347)
			(xy 130.351831 -282.560814) (xy 130.393017 -282.596505) (xy 130.428704 -282.637693) (xy 130.458167 -282.683541)
			(xy 130.480805 -282.733115) (xy 130.496159 -282.785407) (xy 130.503914 -282.839351) (xy 130.503914 -282.893849)
			(xy 130.496159 -282.947793) (xy 130.480805 -283.000085) (xy 130.458167 -283.049659) (xy 130.428704 -283.095507)
			(xy 130.393017 -283.136695) (xy 130.351831 -283.172386) (xy 130.305985 -283.201853) (xy 130.256413 -283.224495)
			(xy 130.204123 -283.239852) (xy 130.150179 -283.247612) (xy 130.12293 -283.2481) (xy 130.09556 -283.247616)
			(xy 130.041382 -283.239803) (xy 129.988879 -283.224318) (xy 129.939132 -283.20148) (xy 129.893164 -283.171759)
			(xy 129.872232 -283.15412) (xy 129.86512 -283.148024) (xy 129.848102 -283.141674) (xy 129.762758 -283.141674)
			(xy 129.74574 -283.148024) (xy 129.738628 -283.15412) (xy 129.717699 -283.171763) (xy 129.671725 -283.201473)
			(xy 129.621977 -283.224308) (xy 129.569475 -283.239798) (xy 129.515299 -283.247626) (xy 129.48793 -283.2481)
			(xy 129.460675 -283.247655) (xy 129.40672 -283.239901) (xy 129.354417 -283.224547) (xy 129.304832 -283.201906)
			(xy 129.258975 -283.172438) (xy 129.217777 -283.136744) (xy 129.18208 -283.095549) (xy 129.152608 -283.049694)
			(xy 129.129963 -283.000111) (xy 129.114605 -282.947809) (xy 129.106847 -282.893855) (xy 128.776703 -282.893855)
			(xy 128.776652 -282.89643) (xy 128.767344 -282.955376) (xy 128.758696 -282.98394) (xy 128.755394 -282.994354)
			(xy 128.75768 -283.015944) (xy 128.807718 -283.100526) (xy 128.825498 -283.112972) (xy 128.836166 -283.115004)
			(xy 128.861983 -283.120344) (xy 128.911899 -283.137313) (xy 128.959003 -283.160993) (xy 129.002398 -283.190934)
			(xy 129.041256 -283.226565) (xy 129.074838 -283.267208) (xy 129.102503 -283.312087) (xy 129.123725 -283.360349)
			(xy 129.138099 -283.411073) (xy 129.145351 -283.463293) (xy 129.145792 -283.489654) (xy 129.145209 -283.519777)
			(xy 129.135733 -283.579274) (xy 129.117026 -283.636542) (xy 129.089553 -283.690159) (xy 129.053995 -283.738793)
			(xy 129.033016 -283.760418) (xy 129.02565 -283.76753) (xy 129.01803 -283.786326) (xy 129.01803 -283.878782)
			(xy 129.02565 -283.897578) (xy 129.033016 -283.90469) (xy 129.054019 -283.926293) (xy 129.089584 -283.974928)
			(xy 129.117059 -284.02855) (xy 129.131438 -284.072584) (xy 134.033006 -284.072584) (xy 134.033461 -284.045213)
			(xy 134.041281 -283.991034) (xy 134.056773 -283.93853) (xy 134.079617 -283.888784) (xy 134.109344 -283.842817)
			(xy 134.126986 -283.821886) (xy 134.133082 -283.814774) (xy 134.139432 -283.797756) (xy 134.139432 -283.712412)
			(xy 134.133082 -283.695394) (xy 134.126986 -283.688282) (xy 134.10937 -283.667332) (xy 134.079655 -283.621364)
			(xy 134.056815 -283.571621) (xy 134.041318 -283.519124) (xy 134.033484 -283.464952) (xy 134.033006 -283.437584)
			(xy 134.033492 -283.410333) (xy 134.041248 -283.356385) (xy 134.056603 -283.30409) (xy 134.079245 -283.254513)
			(xy 134.108711 -283.208663) (xy 134.144402 -283.167472) (xy 134.185593 -283.131781) (xy 134.231443 -283.102315)
			(xy 134.28102 -283.079673) (xy 134.333315 -283.064318) (xy 134.387263 -283.056562) (xy 134.441765 -283.056562)
			(xy 134.495713 -283.064318) (xy 134.548008 -283.079673) (xy 134.597585 -283.102315) (xy 134.643435 -283.131781)
			(xy 134.684626 -283.167472) (xy 134.720317 -283.208663) (xy 134.749783 -283.254513) (xy 134.772425 -283.30409)
			(xy 134.78778 -283.356385) (xy 134.795536 -283.410333) (xy 134.796022 -283.437584) (xy 134.795566 -283.464955)
			(xy 134.787748 -283.519135) (xy 134.772258 -283.571639) (xy 134.749414 -283.621386) (xy 134.719685 -283.667351)
			(xy 134.702042 -283.688282) (xy 134.695946 -283.695394) (xy 134.689596 -283.712412) (xy 134.689596 -283.797756)
			(xy 134.695946 -283.814774) (xy 134.702042 -283.821886) (xy 134.719695 -283.842807) (xy 134.749403 -283.888783)
			(xy 134.772236 -283.938534) (xy 134.787724 -283.991037) (xy 134.79555 -284.045214) (xy 134.796022 -284.072584)
			(xy 134.795536 -284.099835) (xy 134.78778 -284.153783) (xy 134.772425 -284.206078) (xy 134.749783 -284.255655)
			(xy 134.720317 -284.301505) (xy 134.684626 -284.342696) (xy 134.643435 -284.378387) (xy 134.597585 -284.407853)
			(xy 134.548008 -284.430495) (xy 134.495713 -284.44585) (xy 134.441765 -284.453606) (xy 134.387263 -284.453606)
			(xy 134.333315 -284.44585) (xy 134.28102 -284.430495) (xy 134.231443 -284.407853) (xy 134.185593 -284.378387)
			(xy 134.144402 -284.342696) (xy 134.108711 -284.301505) (xy 134.079245 -284.255655) (xy 134.056603 -284.206078)
			(xy 134.041248 -284.153783) (xy 134.033492 -284.099835) (xy 134.033006 -284.072584) (xy 129.131438 -284.072584)
			(xy 129.135762 -284.085825) (xy 129.145227 -284.145328) (xy 129.145792 -284.175454) (xy 129.145306 -284.202705)
			(xy 129.13755 -284.256653) (xy 129.122195 -284.308948) (xy 129.099553 -284.358525) (xy 129.070087 -284.404375)
			(xy 129.034396 -284.445566) (xy 128.993205 -284.481257) (xy 128.947355 -284.510723) (xy 128.897778 -284.533365)
			(xy 128.845483 -284.54872) (xy 128.791535 -284.556476) (xy 128.737033 -284.556476) (xy 128.683085 -284.54872)
			(xy 128.63079 -284.533365) (xy 128.581213 -284.510723) (xy 128.535363 -284.481257) (xy 128.494172 -284.445566)
			(xy 128.458481 -284.404375) (xy 128.429015 -284.358525) (xy 128.406373 -284.308948) (xy 128.391018 -284.256653)
			(xy 128.383262 -284.202705) (xy 128.382776 -284.175454) (xy 128.383374 -284.145332) (xy 128.392847 -284.085836)
			(xy 128.411551 -284.028568) (xy 128.439021 -283.974951) (xy 128.474575 -283.926316) (xy 128.495552 -283.90469)
			(xy 128.502918 -283.897578) (xy 128.510538 -283.878782) (xy 128.510538 -283.786326) (xy 128.502918 -283.76753)
			(xy 128.495552 -283.760418) (xy 128.474564 -283.7388) (xy 128.438995 -283.69017) (xy 128.411515 -283.636552)
			(xy 128.392809 -283.57928) (xy 128.383342 -283.519779) (xy 128.382776 -283.489654) (xy 128.383349 -283.459815)
			(xy 128.392666 -283.400869) (xy 128.401318 -283.372306) (xy 128.40462 -283.361892) (xy 128.402334 -283.340302)
			(xy 128.352296 -283.25572) (xy 128.334516 -283.243274) (xy 128.323848 -283.241242) (xy 128.295998 -283.235391)
			(xy 128.242335 -283.216454) (xy 128.192078 -283.18976) (xy 128.146341 -283.155899) (xy 128.106139 -283.115622)
			(xy 128.072363 -283.069823) (xy 128.045761 -283.019516) (xy 128.026924 -282.965818) (xy 128.02108 -282.937966)
			(xy 128.01854 -282.925774) (xy 128.002792 -282.905962) (xy 127.902716 -282.862528) (xy 127.87757 -282.86456)
			(xy 127.866902 -282.871164) (xy 127.843932 -282.885202) (xy 127.794858 -282.907333) (xy 127.743156 -282.922329)
			(xy 127.689857 -282.929892) (xy 127.66294 -282.930346) (xy 127.644921 -282.930129) (xy 127.609046 -282.926692)
			(xy 127.591312 -282.923488) (xy 127.581914 -282.92171) (xy 127.562864 -282.92552) (xy 127.48768 -282.973272)
			(xy 127.47625 -282.98902) (xy 127.473964 -282.998418) (xy 127.466566 -283.025463) (xy 127.444939 -283.07719)
			(xy 127.415976 -283.125197) (xy 127.380301 -283.16845) (xy 127.338682 -283.206018) (xy 127.292014 -283.237092)
			(xy 127.241301 -283.261004) (xy 127.187636 -283.27724) (xy 127.132173 -283.285449) (xy 127.10414 -283.285946)
			(xy 127.07689 -283.285408) (xy 127.022944 -283.277657) (xy 126.970649 -283.262308) (xy 126.921072 -283.239673)
			(xy 126.875221 -283.210213) (xy 126.834028 -283.174527) (xy 126.798334 -283.133342) (xy 126.768864 -283.087497)
			(xy 126.746219 -283.037924) (xy 126.73086 -282.985633) (xy 126.723098 -282.931688) (xy 126.722632 -282.904438)
			(xy 122.341892 -282.904438) (xy 122.335658 -282.947795) (xy 122.320305 -283.000087) (xy 122.297665 -283.049662)
			(xy 122.268201 -283.095511) (xy 122.232512 -283.1367) (xy 122.191325 -283.17239) (xy 122.145478 -283.201857)
			(xy 122.095904 -283.224498) (xy 122.043612 -283.239855) (xy 121.989668 -283.247613) (xy 121.962418 -283.2481)
			(xy 121.935048 -283.247623) (xy 121.88087 -283.239808) (xy 121.828367 -283.224321) (xy 121.778619 -283.201482)
			(xy 121.732652 -283.17176) (xy 121.71172 -283.15412) (xy 121.704608 -283.148024) (xy 121.68759 -283.141674)
			(xy 121.602246 -283.141674) (xy 121.585228 -283.148024) (xy 121.578116 -283.15412) (xy 121.557191 -283.171768)
			(xy 121.511216 -283.201478) (xy 121.461467 -283.224312) (xy 121.408965 -283.239801) (xy 121.354788 -283.247627)
			(xy 121.327418 -283.2481) (xy 121.300164 -283.247654) (xy 121.24621 -283.239899) (xy 121.193909 -283.224544)
			(xy 121.144325 -283.201902) (xy 121.098469 -283.172434) (xy 121.057273 -283.13674) (xy 121.021577 -283.095546)
			(xy 120.992107 -283.049691) (xy 120.969462 -283.000108) (xy 120.954105 -282.947808) (xy 120.946347 -282.893854)
			(xy 120.616192 -282.893854) (xy 120.616141 -282.89643) (xy 120.606832 -282.955376) (xy 120.598184 -282.98394)
			(xy 120.594882 -282.994354) (xy 120.597168 -283.015944) (xy 120.647206 -283.100526) (xy 120.664986 -283.112972)
			(xy 120.675654 -283.115004) (xy 120.701469 -283.120353) (xy 120.751385 -283.13732) (xy 120.798489 -283.160999)
			(xy 120.841884 -283.190938) (xy 120.880743 -283.226569) (xy 120.914325 -283.26721) (xy 120.94199 -283.312089)
			(xy 120.963212 -283.36035) (xy 120.977587 -283.411074) (xy 120.984839 -283.463293) (xy 120.98528 -283.489654)
			(xy 120.984672 -283.519776) (xy 120.975198 -283.57927) (xy 120.956496 -283.636537) (xy 120.929029 -283.690155)
			(xy 120.893479 -283.738791) (xy 120.872504 -283.760418) (xy 120.865138 -283.76753) (xy 120.857518 -283.786326)
			(xy 120.857518 -283.878782) (xy 120.865138 -283.897578) (xy 120.872504 -283.90469) (xy 120.893505 -283.926295)
			(xy 120.929071 -283.97493) (xy 120.956547 -284.028551) (xy 120.970926 -284.072584) (xy 125.872494 -284.072584)
			(xy 125.872952 -284.045214) (xy 125.880772 -283.991034) (xy 125.896263 -283.938531) (xy 125.919107 -283.888784)
			(xy 125.948832 -283.842818) (xy 125.966474 -283.821886) (xy 125.97257 -283.814774) (xy 125.97892 -283.797756)
			(xy 125.97892 -283.712412) (xy 125.97257 -283.695394) (xy 125.966474 -283.688282) (xy 125.948856 -283.667333)
			(xy 125.919142 -283.621365) (xy 125.896302 -283.571621) (xy 125.880806 -283.519124) (xy 125.872972 -283.464952)
			(xy 125.872494 -283.437584) (xy 125.87298 -283.410333) (xy 125.880736 -283.356385) (xy 125.896091 -283.30409)
			(xy 125.918733 -283.254513) (xy 125.948199 -283.208663) (xy 125.98389 -283.167472) (xy 126.025081 -283.131781)
			(xy 126.070931 -283.102315) (xy 126.120508 -283.079673) (xy 126.172803 -283.064318) (xy 126.226751 -283.056562)
			(xy 126.281253 -283.056562) (xy 126.335201 -283.064318) (xy 126.387496 -283.079673) (xy 126.437073 -283.102315)
			(xy 126.482923 -283.131781) (xy 126.524114 -283.167472) (xy 126.559805 -283.208663) (xy 126.589271 -283.254513)
			(xy 126.611913 -283.30409) (xy 126.627268 -283.356385) (xy 126.635024 -283.410333) (xy 126.63551 -283.437584)
			(xy 126.635032 -283.464954) (xy 126.627217 -283.519132) (xy 126.61173 -283.571635) (xy 126.588891 -283.621382)
			(xy 126.55917 -283.66735) (xy 126.54153 -283.688282) (xy 126.535434 -283.695394) (xy 126.529084 -283.712412)
			(xy 126.529084 -283.797756) (xy 126.535434 -283.814774) (xy 126.54153 -283.821886) (xy 126.559181 -283.842809)
			(xy 126.58889 -283.888785) (xy 126.611723 -283.938534) (xy 126.627211 -283.991037) (xy 126.635037 -284.045214)
			(xy 126.63551 -284.072584) (xy 126.635024 -284.099835) (xy 126.627268 -284.153783) (xy 126.611913 -284.206078)
			(xy 126.589271 -284.255655) (xy 126.559805 -284.301505) (xy 126.524114 -284.342696) (xy 126.482923 -284.378387)
			(xy 126.437073 -284.407853) (xy 126.387496 -284.430495) (xy 126.335201 -284.44585) (xy 126.281253 -284.453606)
			(xy 126.226751 -284.453606) (xy 126.172803 -284.44585) (xy 126.120508 -284.430495) (xy 126.070931 -284.407853)
			(xy 126.025081 -284.378387) (xy 125.98389 -284.342696) (xy 125.948199 -284.301505) (xy 125.918733 -284.255655)
			(xy 125.896091 -284.206078) (xy 125.880736 -284.153783) (xy 125.87298 -284.099835) (xy 125.872494 -284.072584)
			(xy 120.970926 -284.072584) (xy 120.97525 -284.085825) (xy 120.984715 -284.145328) (xy 120.98528 -284.175454)
			(xy 120.984794 -284.202705) (xy 120.977038 -284.256653) (xy 120.961683 -284.308948) (xy 120.939041 -284.358525)
			(xy 120.909575 -284.404375) (xy 120.873884 -284.445566) (xy 120.832693 -284.481257) (xy 120.786843 -284.510723)
			(xy 120.737266 -284.533365) (xy 120.684971 -284.54872) (xy 120.631023 -284.556476) (xy 120.576521 -284.556476)
			(xy 120.522573 -284.54872) (xy 120.470278 -284.533365) (xy 120.420701 -284.510723) (xy 120.374851 -284.481257)
			(xy 120.33366 -284.445566) (xy 120.297969 -284.404375) (xy 120.268503 -284.358525) (xy 120.245861 -284.308948)
			(xy 120.230506 -284.256653) (xy 120.22275 -284.202705) (xy 120.222264 -284.175454) (xy 120.222865 -284.145332)
			(xy 120.232338 -284.085837) (xy 120.251042 -284.028569) (xy 120.278511 -283.974951) (xy 120.314064 -283.926316)
			(xy 120.33504 -283.90469) (xy 120.342406 -283.897578) (xy 120.350026 -283.878782) (xy 120.350026 -283.786326)
			(xy 120.342406 -283.76753) (xy 120.33504 -283.760418) (xy 120.31405 -283.738802) (xy 120.278482 -283.690171)
			(xy 120.251003 -283.636553) (xy 120.232297 -283.57928) (xy 120.22283 -283.519779) (xy 120.222264 -283.489654)
			(xy 120.222837 -283.459815) (xy 120.232154 -283.400869) (xy 120.240806 -283.372306) (xy 120.244108 -283.361892)
			(xy 120.241822 -283.340302) (xy 120.191784 -283.25572) (xy 120.174004 -283.243274) (xy 120.163336 -283.241242)
			(xy 120.135485 -283.2354) (xy 120.081821 -283.216461) (xy 120.031564 -283.189765) (xy 119.985828 -283.155903)
			(xy 119.945626 -283.115625) (xy 119.91185 -283.069825) (xy 119.885249 -283.019517) (xy 119.866412 -282.965818)
			(xy 119.860568 -282.937966) (xy 119.858028 -282.925774) (xy 119.84228 -282.905962) (xy 119.742204 -282.862528)
			(xy 119.717058 -282.86456) (xy 119.70639 -282.871164) (xy 119.683423 -282.885207) (xy 119.634348 -282.907337)
			(xy 119.582645 -282.922332) (xy 119.529345 -282.929892) (xy 119.502428 -282.930346) (xy 119.484408 -282.93013)
			(xy 119.448534 -282.926693) (xy 119.4308 -282.923488) (xy 119.421402 -282.92171) (xy 119.402352 -282.92552)
			(xy 119.327168 -282.973272) (xy 119.315738 -282.98902) (xy 119.313452 -282.998418) (xy 119.306065 -283.025466)
			(xy 119.284437 -283.077194) (xy 119.255473 -283.125202) (xy 119.219797 -283.168455) (xy 119.178176 -283.206023)
			(xy 119.131506 -283.237097) (xy 119.080793 -283.261008) (xy 119.027126 -283.277242) (xy 118.971662 -283.285449)
			(xy 118.943628 -283.285946) (xy 118.916379 -283.285396) (xy 118.862436 -283.277644) (xy 118.810145 -283.262294)
			(xy 118.76057 -283.239659) (xy 118.714721 -283.2102) (xy 118.673532 -283.174515) (xy 118.63784 -283.133331)
			(xy 118.608372 -283.087488) (xy 118.585729 -283.037917) (xy 118.57037 -282.985629) (xy 118.562609 -282.931687)
			(xy 118.56212 -282.904438) (xy 113.843292 -282.904438) (xy 113.837059 -282.947793) (xy 113.821706 -283.000084)
			(xy 113.799067 -283.049658) (xy 113.769605 -283.095506) (xy 113.733917 -283.136695) (xy 113.692732 -283.172385)
			(xy 113.646886 -283.201852) (xy 113.597314 -283.224494) (xy 113.545024 -283.239852) (xy 113.491081 -283.247612)
			(xy 113.463832 -283.2481) (xy 113.436462 -283.247615) (xy 113.382284 -283.239802) (xy 113.329781 -283.224317)
			(xy 113.280034 -283.20148) (xy 113.234066 -283.171759) (xy 113.213134 -283.15412) (xy 113.206022 -283.148024)
			(xy 113.189004 -283.141674) (xy 113.10366 -283.141674) (xy 113.086642 -283.148024) (xy 113.07953 -283.15412)
			(xy 113.0586 -283.171762) (xy 113.012626 -283.201472) (xy 112.962878 -283.224308) (xy 112.910377 -283.239798)
			(xy 112.856201 -283.247626) (xy 112.828832 -283.2481) (xy 112.801577 -283.247655) (xy 112.747622 -283.239901)
			(xy 112.695319 -283.224548) (xy 112.645734 -283.201907) (xy 112.599876 -283.172439) (xy 112.558678 -283.136745)
			(xy 112.52298 -283.09555) (xy 112.493509 -283.049695) (xy 112.470863 -283.000111) (xy 112.455505 -282.94781)
			(xy 112.447747 -282.893855) (xy 112.117605 -282.893855) (xy 112.117554 -282.89643) (xy 112.108246 -282.955376)
			(xy 112.099598 -282.98394) (xy 112.096296 -282.994354) (xy 112.098582 -283.015944) (xy 112.14862 -283.100526)
			(xy 112.1664 -283.112972) (xy 112.177068 -283.115004) (xy 112.202885 -283.120343) (xy 112.252801 -283.137311)
			(xy 112.299905 -283.160992) (xy 112.3433 -283.190933) (xy 112.382158 -283.226565) (xy 112.41574 -283.267207)
			(xy 112.443405 -283.312087) (xy 112.464627 -283.360349) (xy 112.479001 -283.411073) (xy 112.486253 -283.463293)
			(xy 112.486694 -283.489654) (xy 112.48611 -283.519777) (xy 112.476635 -283.579274) (xy 112.457928 -283.636542)
			(xy 112.430454 -283.690159) (xy 112.394897 -283.738793) (xy 112.373918 -283.760418) (xy 112.366552 -283.76753)
			(xy 112.358932 -283.786326) (xy 112.358932 -283.878782) (xy 112.366552 -283.897578) (xy 112.373918 -283.90469)
			(xy 112.394922 -283.926293) (xy 112.430486 -283.974928) (xy 112.457962 -284.02855) (xy 112.47234 -284.072584)
			(xy 117.373908 -284.072584) (xy 117.374363 -284.045213) (xy 117.382183 -283.991034) (xy 117.397675 -283.93853)
			(xy 117.420519 -283.888784) (xy 117.450246 -283.842817) (xy 117.467888 -283.821886) (xy 117.473984 -283.814774)
			(xy 117.480334 -283.797756) (xy 117.480334 -283.712412) (xy 117.473984 -283.695394) (xy 117.467888 -283.688282)
			(xy 117.450272 -283.667331) (xy 117.420557 -283.621363) (xy 117.397717 -283.571621) (xy 117.38222 -283.519124)
			(xy 117.374386 -283.464952) (xy 117.373908 -283.437584) (xy 117.374394 -283.410333) (xy 117.38215 -283.356385)
			(xy 117.397505 -283.30409) (xy 117.420147 -283.254513) (xy 117.449613 -283.208663) (xy 117.485304 -283.167472)
			(xy 117.526495 -283.131781) (xy 117.572345 -283.102315) (xy 117.621922 -283.079673) (xy 117.674217 -283.064318)
			(xy 117.728165 -283.056562) (xy 117.782667 -283.056562) (xy 117.836615 -283.064318) (xy 117.88891 -283.079673)
			(xy 117.938487 -283.102315) (xy 117.984337 -283.131781) (xy 118.025528 -283.167472) (xy 118.061219 -283.208663)
			(xy 118.090685 -283.254513) (xy 118.113327 -283.30409) (xy 118.128682 -283.356385) (xy 118.136438 -283.410333)
			(xy 118.136924 -283.437584) (xy 118.136467 -283.464955) (xy 118.12865 -283.519135) (xy 118.11316 -283.571639)
			(xy 118.090315 -283.621386) (xy 118.060587 -283.667351) (xy 118.042944 -283.688282) (xy 118.036848 -283.695394)
			(xy 118.030498 -283.712412) (xy 118.030498 -283.797756) (xy 118.036848 -283.814774) (xy 118.042944 -283.821886)
			(xy 118.060597 -283.842807) (xy 118.090306 -283.888783) (xy 118.113138 -283.938534) (xy 118.128626 -283.991037)
			(xy 118.136452 -284.045214) (xy 118.136924 -284.072584) (xy 118.136438 -284.099835) (xy 118.128682 -284.153783)
			(xy 118.113327 -284.206078) (xy 118.090685 -284.255655) (xy 118.061219 -284.301505) (xy 118.025528 -284.342696)
			(xy 117.984337 -284.378387) (xy 117.938487 -284.407853) (xy 117.88891 -284.430495) (xy 117.836615 -284.44585)
			(xy 117.782667 -284.453606) (xy 117.728165 -284.453606) (xy 117.674217 -284.44585) (xy 117.621922 -284.430495)
			(xy 117.572345 -284.407853) (xy 117.526495 -284.378387) (xy 117.485304 -284.342696) (xy 117.449613 -284.301505)
			(xy 117.420147 -284.255655) (xy 117.397505 -284.206078) (xy 117.38215 -284.153783) (xy 117.374394 -284.099835)
			(xy 117.373908 -284.072584) (xy 112.47234 -284.072584) (xy 112.476664 -284.085825) (xy 112.486129 -284.145328)
			(xy 112.486694 -284.175454) (xy 112.486208 -284.202705) (xy 112.478452 -284.256653) (xy 112.463097 -284.308948)
			(xy 112.440455 -284.358525) (xy 112.410989 -284.404375) (xy 112.375298 -284.445566) (xy 112.334107 -284.481257)
			(xy 112.288257 -284.510723) (xy 112.23868 -284.533365) (xy 112.186385 -284.54872) (xy 112.132437 -284.556476)
			(xy 112.077935 -284.556476) (xy 112.023987 -284.54872) (xy 111.971692 -284.533365) (xy 111.922115 -284.510723)
			(xy 111.876265 -284.481257) (xy 111.835074 -284.445566) (xy 111.799383 -284.404375) (xy 111.769917 -284.358525)
			(xy 111.747275 -284.308948) (xy 111.73192 -284.256653) (xy 111.724164 -284.202705) (xy 111.723678 -284.175454)
			(xy 111.724275 -284.145332) (xy 111.733748 -284.085836) (xy 111.752453 -284.028568) (xy 111.779923 -283.974951)
			(xy 111.815477 -283.926316) (xy 111.836454 -283.90469) (xy 111.84382 -283.897578) (xy 111.85144 -283.878782)
			(xy 111.85144 -283.786326) (xy 111.84382 -283.76753) (xy 111.836454 -283.760418) (xy 111.815467 -283.738799)
			(xy 111.779897 -283.69017) (xy 111.752417 -283.636552) (xy 111.733711 -283.57928) (xy 111.724244 -283.519779)
			(xy 111.723678 -283.489654) (xy 111.72425 -283.459815) (xy 111.733568 -283.400869) (xy 111.74222 -283.372306)
			(xy 111.745522 -283.361892) (xy 111.743236 -283.340302) (xy 111.693198 -283.25572) (xy 111.675418 -283.243274)
			(xy 111.66475 -283.241242) (xy 111.636901 -283.23539) (xy 111.583237 -283.216453) (xy 111.53298 -283.189759)
			(xy 111.487243 -283.155898) (xy 111.447041 -283.115622) (xy 111.413265 -283.069823) (xy 111.386664 -283.019516)
			(xy 111.367826 -282.965818) (xy 111.361982 -282.937966) (xy 111.359442 -282.925774) (xy 111.343694 -282.905962)
			(xy 111.243618 -282.862528) (xy 111.218472 -282.86456) (xy 111.207804 -282.871164) (xy 111.184833 -282.885201)
			(xy 111.13576 -282.907332) (xy 111.084058 -282.922329) (xy 111.030759 -282.929892) (xy 111.003842 -282.930346)
			(xy 110.985823 -282.930129) (xy 110.949948 -282.926692) (xy 110.932214 -282.923488) (xy 110.922816 -282.92171)
			(xy 110.903766 -282.92552) (xy 110.828582 -282.973272) (xy 110.817152 -282.98902) (xy 110.814866 -282.998418)
			(xy 110.807467 -283.025462) (xy 110.785839 -283.07719) (xy 110.756877 -283.125197) (xy 110.721202 -283.168449)
			(xy 110.679583 -283.206017) (xy 110.632915 -283.237092) (xy 110.582203 -283.261004) (xy 110.528538 -283.277239)
			(xy 110.473075 -283.285448) (xy 110.445042 -283.285946) (xy 110.417792 -283.285406) (xy 110.363846 -283.277655)
			(xy 110.311552 -283.262307) (xy 110.261974 -283.239672) (xy 110.216123 -283.210212) (xy 110.17493 -283.174526)
			(xy 110.139236 -283.133341) (xy 110.109767 -283.087496) (xy 110.087121 -283.037923) (xy 110.071762 -282.985633)
			(xy 110.064 -282.931688) (xy 110.063534 -282.904438) (xy 105.682792 -282.904438) (xy 105.676558 -282.947795)
			(xy 105.661205 -283.000087) (xy 105.638565 -283.049662) (xy 105.609102 -283.09551) (xy 105.573413 -283.136699)
			(xy 105.532226 -283.17239) (xy 105.486379 -283.201856) (xy 105.436805 -283.224498) (xy 105.384514 -283.239854)
			(xy 105.33057 -283.247613) (xy 105.30332 -283.2481) (xy 105.27595 -283.247622) (xy 105.221772 -283.239807)
			(xy 105.169269 -283.224321) (xy 105.119522 -283.201482) (xy 105.073554 -283.17176) (xy 105.052622 -283.15412)
			(xy 105.04551 -283.148024) (xy 105.028492 -283.141674) (xy 104.943148 -283.141674) (xy 104.92613 -283.148024)
			(xy 104.919018 -283.15412) (xy 104.898093 -283.171767) (xy 104.852118 -283.201477) (xy 104.802368 -283.224311)
			(xy 104.749866 -283.2398) (xy 104.69569 -283.247627) (xy 104.66832 -283.2481) (xy 104.641066 -283.247654)
			(xy 104.587111 -283.239899) (xy 104.53481 -283.224545) (xy 104.485226 -283.201903) (xy 104.43937 -283.172435)
			(xy 104.398174 -283.13674) (xy 104.362477 -283.095546) (xy 104.333007 -283.049691) (xy 104.310362 -283.000109)
			(xy 104.295005 -282.947808) (xy 104.287247 -282.893854) (xy 103.957113 -282.893854) (xy 103.94936 -282.947788)
			(xy 103.934007 -283.000081) (xy 103.911368 -283.049657) (xy 103.881904 -283.095506) (xy 103.846216 -283.136696)
			(xy 103.805029 -283.172388) (xy 103.759181 -283.201855) (xy 103.709607 -283.224497) (xy 103.657315 -283.239854)
			(xy 103.60337 -283.247613) (xy 103.57612 -283.2481) (xy 103.549739 -283.247582) (xy 103.497478 -283.240334)
			(xy 103.446716 -283.225947) (xy 103.398425 -283.204695) (xy 103.353526 -283.176985) (xy 103.312879 -283.143347)
			(xy 103.27726 -283.104423) (xy 103.247351 -283.060959) (xy 103.223723 -283.013784) (xy 103.206829 -282.9638)
			(xy 103.20147 -282.937966) (xy 103.19893 -282.925774) (xy 103.183182 -282.905962) (xy 103.083106 -282.862528)
			(xy 103.05796 -282.86456) (xy 103.047292 -282.871164) (xy 103.024324 -282.885206) (xy 102.97525 -282.907336)
			(xy 102.923547 -282.922331) (xy 102.870247 -282.929892) (xy 102.84333 -282.930346) (xy 102.825311 -282.93013)
			(xy 102.789436 -282.926693) (xy 102.771702 -282.923488) (xy 102.762304 -282.92171) (xy 102.743254 -282.92552)
			(xy 102.66807 -282.973272) (xy 102.65664 -282.98902) (xy 102.654354 -282.998418) (xy 102.646966 -283.025465)
			(xy 102.625337 -283.077194) (xy 102.596373 -283.125201) (xy 102.560697 -283.168454) (xy 102.519077 -283.206022)
			(xy 102.472407 -283.237096) (xy 102.421694 -283.261007) (xy 102.368028 -283.277242) (xy 102.312564 -283.285449)
			(xy 102.28453 -283.285946) (xy 102.257281 -283.285394) (xy 102.203338 -283.277643) (xy 102.151047 -283.262293)
			(xy 102.101472 -283.239658) (xy 102.055624 -283.210199) (xy 102.014434 -283.174514) (xy 101.978742 -283.133331)
			(xy 101.949274 -283.087487) (xy 101.926631 -283.037917) (xy 101.911272 -282.985629) (xy 101.903511 -282.931687)
			(xy 101.903022 -282.904438) (xy 99.589336 -282.904438) (xy 99.589336 -284.175454) (xy 103.562656 -284.175454)
			(xy 103.566727 -284.119832) (xy 103.578853 -284.065395) (xy 103.598776 -284.013304) (xy 103.626072 -283.964669)
			(xy 103.660158 -283.920526) (xy 103.700307 -283.881817) (xy 103.745665 -283.849366) (xy 103.795265 -283.823865)
			(xy 103.848049 -283.805858) (xy 103.902892 -283.795728) (xy 103.958626 -283.793691) (xy 104.014063 -283.799791)
			(xy 104.06802 -283.813897) (xy 104.119349 -283.835709) (xy 104.166955 -283.864763) (xy 104.209823 -283.900438)
			(xy 104.24704 -283.941975) (xy 104.277813 -283.988488) (xy 104.301485 -284.038985) (xy 104.311594 -284.072584)
			(xy 109.213396 -284.072584) (xy 109.213854 -284.045213) (xy 109.221674 -283.991034) (xy 109.237165 -283.938531)
			(xy 109.260008 -283.888784) (xy 109.289734 -283.842818) (xy 109.307376 -283.821886) (xy 109.313472 -283.814774)
			(xy 109.319822 -283.797756) (xy 109.319822 -283.712412) (xy 109.313472 -283.695394) (xy 109.307376 -283.688282)
			(xy 109.289758 -283.667333) (xy 109.260044 -283.621364) (xy 109.237204 -283.571621) (xy 109.221708 -283.519124)
			(xy 109.213874 -283.464952) (xy 109.213396 -283.437584) (xy 109.213882 -283.410333) (xy 109.221638 -283.356385)
			(xy 109.236993 -283.30409) (xy 109.259635 -283.254513) (xy 109.289101 -283.208663) (xy 109.324792 -283.167472)
			(xy 109.365983 -283.131781) (xy 109.411833 -283.102315) (xy 109.46141 -283.079673) (xy 109.513705 -283.064318)
			(xy 109.567653 -283.056562) (xy 109.622155 -283.056562) (xy 109.676103 -283.064318) (xy 109.728398 -283.079673)
			(xy 109.777975 -283.102315) (xy 109.823825 -283.131781) (xy 109.865016 -283.167472) (xy 109.900707 -283.208663)
			(xy 109.930173 -283.254513) (xy 109.952815 -283.30409) (xy 109.96817 -283.356385) (xy 109.975926 -283.410333)
			(xy 109.976412 -283.437584) (xy 109.975934 -283.464954) (xy 109.968118 -283.519132) (xy 109.952632 -283.571635)
			(xy 109.929793 -283.621382) (xy 109.900072 -283.66735) (xy 109.882432 -283.688282) (xy 109.876336 -283.695394)
			(xy 109.869986 -283.712412) (xy 109.869986 -283.797756) (xy 109.876336 -283.814774) (xy 109.882432 -283.821886)
			(xy 109.900083 -283.842808) (xy 109.929792 -283.888784) (xy 109.952625 -283.938534) (xy 109.968113 -283.991037)
			(xy 109.975939 -284.045214) (xy 109.976412 -284.072584) (xy 109.975926 -284.099835) (xy 109.96817 -284.153783)
			(xy 109.952815 -284.206078) (xy 109.930173 -284.255655) (xy 109.900707 -284.301505) (xy 109.865016 -284.342696)
			(xy 109.823825 -284.378387) (xy 109.777975 -284.407853) (xy 109.728398 -284.430495) (xy 109.676103 -284.44585)
			(xy 109.622155 -284.453606) (xy 109.567653 -284.453606) (xy 109.513705 -284.44585) (xy 109.46141 -284.430495)
			(xy 109.411833 -284.407853) (xy 109.365983 -284.378387) (xy 109.324792 -284.342696) (xy 109.289101 -284.301505)
			(xy 109.259635 -284.255655) (xy 109.236993 -284.206078) (xy 109.221638 -284.153783) (xy 109.213882 -284.099835)
			(xy 109.213396 -284.072584) (xy 104.311594 -284.072584) (xy 104.317553 -284.092392) (xy 104.325673 -284.147568)
			(xy 104.326182 -284.175454) (xy 104.325673 -284.20334) (xy 104.317553 -284.258516) (xy 104.301485 -284.311923)
			(xy 104.277813 -284.36242) (xy 104.24704 -284.408933) (xy 104.209823 -284.45047) (xy 104.166955 -284.486145)
			(xy 104.119349 -284.515199) (xy 104.06802 -284.537011) (xy 104.014063 -284.551117) (xy 103.958626 -284.557217)
			(xy 103.902892 -284.55518) (xy 103.848049 -284.54505) (xy 103.795265 -284.527043) (xy 103.745665 -284.501542)
			(xy 103.700307 -284.469091) (xy 103.660158 -284.430382) (xy 103.626072 -284.386239) (xy 103.598776 -284.337604)
			(xy 103.578853 -284.285513) (xy 103.566727 -284.231076) (xy 103.562656 -284.175454) (xy 99.589336 -284.175454)
			(xy 99.589336 -286.238696) (xy 99.590017 -286.250759) (xy 99.60104 -286.272221) (xy 99.610418 -286.279844)
			(xy 99.610672 -286.279844) (xy 99.615778 -286.283302) (xy 99.627203 -286.287931) (xy 99.633278 -286.288988)
			(xy 99.717651 -286.301051) (xy 99.885237 -286.33222) (xy 100.051141 -286.371365) (xy 100.214984 -286.418396)
			(xy 100.376392 -286.473206) (xy 100.534995 -286.535668) (xy 100.69043 -286.605642) (xy 100.842343 -286.682966)
			(xy 100.990386 -286.767463) (xy 101.024828 -286.789368) (xy 108.672374 -286.789368) (xy 108.676445 -286.733746)
			(xy 108.688571 -286.679309) (xy 108.708494 -286.627218) (xy 108.73579 -286.578583) (xy 108.769876 -286.53444)
			(xy 108.810025 -286.495731) (xy 108.855383 -286.46328) (xy 108.904983 -286.437779) (xy 108.957767 -286.419772)
			(xy 109.01261 -286.409642) (xy 109.068344 -286.407605) (xy 109.123781 -286.413705) (xy 109.177738 -286.427811)
			(xy 109.229067 -286.449623) (xy 109.276673 -286.478677) (xy 109.319541 -286.514352) (xy 109.356758 -286.555889)
			(xy 109.387531 -286.602402) (xy 109.411203 -286.652899) (xy 109.427271 -286.706306) (xy 109.429365 -286.720534)
			(xy 109.558834 -286.720534) (xy 109.562905 -286.664912) (xy 109.575031 -286.610475) (xy 109.594954 -286.558384)
			(xy 109.62225 -286.509749) (xy 109.656336 -286.465606) (xy 109.696485 -286.426897) (xy 109.741843 -286.394446)
			(xy 109.791443 -286.368945) (xy 109.844227 -286.350938) (xy 109.89907 -286.340808) (xy 109.954804 -286.338771)
			(xy 110.010241 -286.344871) (xy 110.064198 -286.358977) (xy 110.115527 -286.380789) (xy 110.163133 -286.409843)
			(xy 110.206001 -286.445518) (xy 110.243218 -286.487055) (xy 110.273991 -286.533568) (xy 110.297663 -286.584065)
			(xy 110.313731 -286.637472) (xy 110.321851 -286.692648) (xy 110.32236 -286.720534) (xy 110.321851 -286.74842)
			(xy 110.31575 -286.789876) (xy 125.407926 -286.789876) (xy 125.411997 -286.734254) (xy 125.424123 -286.679817)
			(xy 125.444046 -286.627726) (xy 125.471342 -286.579091) (xy 125.505428 -286.534948) (xy 125.545577 -286.496239)
			(xy 125.590935 -286.463788) (xy 125.640535 -286.438287) (xy 125.693319 -286.42028) (xy 125.748162 -286.41015)
			(xy 125.803896 -286.408113) (xy 125.859333 -286.414213) (xy 125.91329 -286.428319) (xy 125.964619 -286.450131)
			(xy 126.012225 -286.479185) (xy 126.055093 -286.51486) (xy 126.09231 -286.556397) (xy 126.123083 -286.60291)
			(xy 126.146755 -286.653407) (xy 126.162213 -286.704786) (xy 126.29464 -286.704786) (xy 126.298711 -286.649164)
			(xy 126.310837 -286.594727) (xy 126.33076 -286.542636) (xy 126.358056 -286.494001) (xy 126.392142 -286.449858)
			(xy 126.432291 -286.411149) (xy 126.477649 -286.378698) (xy 126.527249 -286.353197) (xy 126.580033 -286.33519)
			(xy 126.634876 -286.32506) (xy 126.69061 -286.323023) (xy 126.746047 -286.329123) (xy 126.800004 -286.343229)
			(xy 126.851333 -286.365041) (xy 126.898939 -286.394095) (xy 126.941807 -286.42977) (xy 126.979024 -286.471307)
			(xy 127.009797 -286.51782) (xy 127.033469 -286.568317) (xy 127.049537 -286.621724) (xy 127.057657 -286.6769)
			(xy 127.058166 -286.704786) (xy 127.057657 -286.732672) (xy 127.049537 -286.787848) (xy 127.033469 -286.841255)
			(xy 127.009797 -286.891752) (xy 126.979024 -286.938265) (xy 126.941807 -286.979802) (xy 126.898939 -287.015477)
			(xy 126.851333 -287.044531) (xy 126.800004 -287.066343) (xy 126.746047 -287.080449) (xy 126.69061 -287.086549)
			(xy 126.634876 -287.084512) (xy 126.580033 -287.074382) (xy 126.527249 -287.056375) (xy 126.477649 -287.030874)
			(xy 126.432291 -286.998423) (xy 126.392142 -286.959714) (xy 126.358056 -286.915571) (xy 126.33076 -286.866936)
			(xy 126.310837 -286.814845) (xy 126.298711 -286.760408) (xy 126.29464 -286.704786) (xy 126.162213 -286.704786)
			(xy 126.162823 -286.706814) (xy 126.170943 -286.76199) (xy 126.171452 -286.789876) (xy 126.170943 -286.817762)
			(xy 126.162823 -286.872938) (xy 126.146755 -286.926345) (xy 126.123083 -286.976842) (xy 126.09231 -287.023355)
			(xy 126.055093 -287.064892) (xy 126.012225 -287.100567) (xy 125.964619 -287.129621) (xy 125.91329 -287.151433)
			(xy 125.859333 -287.165539) (xy 125.803896 -287.171639) (xy 125.748162 -287.169602) (xy 125.693319 -287.159472)
			(xy 125.640535 -287.141465) (xy 125.590935 -287.115964) (xy 125.545577 -287.083513) (xy 125.505428 -287.044804)
			(xy 125.471342 -287.000661) (xy 125.444046 -286.952026) (xy 125.424123 -286.899935) (xy 125.411997 -286.845498)
			(xy 125.407926 -286.789876) (xy 110.31575 -286.789876) (xy 110.313731 -286.803596) (xy 110.297663 -286.857003)
			(xy 110.273991 -286.9075) (xy 110.243218 -286.954013) (xy 110.206001 -286.99555) (xy 110.163133 -287.031225)
			(xy 110.115527 -287.060279) (xy 110.064198 -287.082091) (xy 110.010241 -287.096197) (xy 109.954804 -287.102297)
			(xy 109.89907 -287.10026) (xy 109.844227 -287.09013) (xy 109.791443 -287.072123) (xy 109.741843 -287.046622)
			(xy 109.696485 -287.014171) (xy 109.656336 -286.975462) (xy 109.62225 -286.931319) (xy 109.594954 -286.882684)
			(xy 109.575031 -286.830593) (xy 109.562905 -286.776156) (xy 109.558834 -286.720534) (xy 109.429365 -286.720534)
			(xy 109.435391 -286.761482) (xy 109.4359 -286.789368) (xy 109.435391 -286.817254) (xy 109.427271 -286.87243)
			(xy 109.411203 -286.925837) (xy 109.387531 -286.976334) (xy 109.356758 -287.022847) (xy 109.319541 -287.064384)
			(xy 109.276673 -287.100059) (xy 109.229067 -287.129113) (xy 109.177738 -287.150925) (xy 109.123781 -287.165031)
			(xy 109.068344 -287.171131) (xy 109.01261 -287.169094) (xy 108.957767 -287.158964) (xy 108.904983 -287.140957)
			(xy 108.855383 -287.115456) (xy 108.810025 -287.083005) (xy 108.769876 -287.044296) (xy 108.73579 -287.000153)
			(xy 108.708494 -286.951518) (xy 108.688571 -286.899427) (xy 108.676445 -286.84499) (xy 108.672374 -286.789368)
			(xy 101.024828 -286.789368) (xy 101.13422 -286.858941) (xy 101.273517 -286.957191) (xy 101.407958 -287.061987)
			(xy 101.537235 -287.17309) (xy 101.661053 -287.290245) (xy 101.77913 -287.413187) (xy 101.891194 -287.541632)
			(xy 101.996989 -287.675287) (xy 102.096275 -287.813847) (xy 102.188823 -287.956995) (xy 102.274423 -288.104403)
			(xy 102.352878 -288.255735) (xy 102.424008 -288.410644) (xy 102.487652 -288.568777) (xy 102.543664 -288.729771)
			(xy 102.591916 -288.893259) (xy 102.632297 -289.058867) (xy 102.664716 -289.226215) (xy 102.689097 -289.394922)
			(xy 102.705385 -289.564602) (xy 102.713544 -289.734866) (xy 102.714044 -289.820096) (xy 102.713542 -289.904743)
			(xy 102.7055 -290.073846) (xy 102.68944 -290.242376) (xy 102.665398 -290.409954) (xy 102.633427 -290.576202)
			(xy 102.593601 -290.740744) (xy 102.546007 -290.903211) (xy 102.490755 -291.063235) (xy 102.427969 -291.220455)
			(xy 102.357789 -291.374518) (xy 102.280375 -291.525075) (xy 102.195901 -291.671787) (xy 102.104558 -291.814324)
			(xy 102.006551 -291.952364) (xy 101.902101 -292.085596) (xy 101.791444 -292.213719) (xy 101.67483 -292.336444)
			(xy 101.552521 -292.453495) (xy 101.489002 -292.509448) (xy 101.480366 -292.516814) (xy 101.471476 -292.536626)
			(xy 101.471476 -293.121842) (xy 101.47194 -293.131718) (xy 101.479386 -293.150012) (xy 101.485954 -293.157402)
			(xy 101.486208 -293.157656) (xy 101.923596 -293.59479) (xy 101.924104 -293.595298) (xy 101.931485 -293.601878)
			(xy 101.949785 -293.609318) (xy 101.959664 -293.609776)
		)
		(stroke
			(width 0)
			(type solid)
		)
		(fill yes)
		(layer "In13.Cu")
		(net "GND")
	)
	(gr_poly
		(pts
			(xy 366.97285 -293.609776) (xy 366.978859 -293.609609) (xy 366.990541 -293.606784) (xy 366.995964 -293.604188)
			(xy 366.99944 -293.602351) (xy 367.005823 -293.597762) (xy 367.008664 -293.595044) (xy 367.774982 -292.828726)
			(xy 367.780177 -292.822975) (xy 367.787148 -292.809142) (xy 367.788698 -292.801548) (xy 367.78946 -292.793166)
			(xy 367.78946 -279.364948) (xy 367.788886 -279.353319) (xy 367.778673 -279.332422) (xy 367.760337 -279.318113)
			(xy 367.749074 -279.315164) (xy 367.668802 -279.297629) (xy 367.509899 -279.255758) (xy 367.35322 -279.206211)
			(xy 367.199135 -279.149106) (xy 367.048008 -279.084577) (xy 366.900197 -279.012777) (xy 366.756051 -278.933877)
			(xy 366.615912 -278.848061) (xy 366.48011 -278.755535) (xy 366.348967 -278.656515) (xy 366.222794 -278.551237)
			(xy 366.101887 -278.439949) (xy 365.986534 -278.322915) (xy 365.877007 -278.200412) (xy 365.773566 -278.072728)
			(xy 365.676454 -277.940167) (xy 365.585901 -277.803041) (xy 365.502122 -277.661674) (xy 365.425315 -277.516403)
			(xy 365.355661 -277.367568) (xy 365.293326 -277.215524) (xy 365.238455 -277.060628) (xy 365.19118 -276.903249)
			(xy 365.151613 -276.743757) (xy 365.119845 -276.58253) (xy 365.095954 -276.419949) (xy 365.079995 -276.256399)
			(xy 365.072006 -276.092267) (xy 365.072006 -275.92794) (xy 365.079994 -275.763807) (xy 365.095953 -275.600257)
			(xy 365.119844 -275.437677) (xy 365.151611 -275.27645) (xy 365.191179 -275.116958) (xy 365.238453 -274.959578)
			(xy 365.293323 -274.804682) (xy 365.355659 -274.652638) (xy 365.425312 -274.503803) (xy 365.502119 -274.358531)
			(xy 365.585898 -274.217165) (xy 365.67645 -274.080039) (xy 365.773562 -273.947477) (xy 365.877003 -273.819793)
			(xy 365.98653 -273.697289) (xy 366.101882 -273.580255) (xy 366.222789 -273.468967) (xy 366.348962 -273.363689)
			(xy 366.480105 -273.264669) (xy 366.615906 -273.172142) (xy 366.756045 -273.086327) (xy 366.900191 -273.007426)
			(xy 367.048002 -272.935626) (xy 367.199128 -272.871097) (xy 367.353214 -272.813991) (xy 367.509893 -272.764444)
			(xy 367.668796 -272.722573) (xy 367.749074 -272.705068) (xy 367.760345 -272.70213) (xy 367.778702 -272.687835)
			(xy 367.788895 -272.666919) (xy 367.78946 -272.655284) (xy 367.78946 -255.914652) (xy 367.789364 -255.909774)
			(xy 367.787577 -255.900185) (xy 367.785904 -255.895602) (xy 367.782094 -255.886458) (xy 362.594144 -250.698254)
			(xy 362.587032 -250.690888) (xy 362.038392 -250.142248) (xy 362.035598 -250.139708) (xy 362.034328 -250.138692)
			(xy 362.03016 -250.135513) (xy 362.020816 -250.130767) (xy 362.015786 -250.129294) (xy 362.002578 -250.127516)
			(xy 359.664762 -250.127516) (xy 359.661714 -250.12777) (xy 359.660698 -250.12777) (xy 359.646588 -250.129297)
			(xy 359.619974 -250.139119) (xy 359.597087 -250.155883) (xy 359.579695 -250.178295) (xy 359.569138 -250.204627)
			(xy 359.566231 -250.232846) (xy 359.568242 -250.246896) (xy 359.57098 -250.263397) (xy 359.573909 -250.296719)
			(xy 359.574084 -250.313444) (xy 359.573598 -250.340713) (xy 359.565836 -250.394697) (xy 359.550471 -250.447027)
			(xy 359.527814 -250.496637) (xy 359.498328 -250.542518) (xy 359.462613 -250.583735) (xy 359.421396 -250.61945)
			(xy 359.375515 -250.648936) (xy 359.325905 -250.671593) (xy 359.273575 -250.686958) (xy 359.219591 -250.69472)
			(xy 359.165053 -250.69472) (xy 359.111069 -250.686958) (xy 359.058739 -250.671593) (xy 359.009129 -250.648936)
			(xy 358.963248 -250.61945) (xy 358.922031 -250.583735) (xy 358.886316 -250.542518) (xy 358.85683 -250.496637)
			(xy 358.834173 -250.447027) (xy 358.818808 -250.394697) (xy 358.811046 -250.340713) (xy 358.81056 -250.313444)
			(xy 358.810737 -250.296719) (xy 358.81366 -250.263396) (xy 358.816402 -250.246896) (xy 358.818426 -250.232845)
			(xy 358.815519 -250.204618) (xy 358.804962 -250.178278) (xy 358.787569 -250.155857) (xy 358.764681 -250.139083)
			(xy 358.738063 -250.12925) (xy 358.723946 -250.12777) (xy 358.72293 -250.12777) (xy 358.719882 -250.127516)
			(xy 355.678232 -250.127516) (xy 355.668446 -250.127965) (xy 355.650292 -250.135281) (xy 355.642926 -250.14174)
			(xy 355.494082 -250.285504) (xy 355.486102 -250.29397) (xy 355.478136 -250.315804) (xy 355.478842 -250.327414)
			(xy 355.488748 -250.418854) (xy 355.50094 -250.438666) (xy 355.5111 -250.444762) (xy 355.534254 -250.459799)
			(xy 355.576372 -250.49549) (xy 355.612904 -250.536881) (xy 355.643085 -250.583108) (xy 355.666285 -250.633203)
			(xy 355.682019 -250.686121) (xy 355.689957 -250.740754) (xy 355.690424 -250.768358) (xy 355.690424 -250.768612)
			(xy 355.690191 -250.787018) (xy 355.686631 -250.823658) (xy 355.683312 -250.841764) (xy 355.680772 -250.854718)
			(xy 355.6889 -250.879864) (xy 355.763576 -250.947428) (xy 355.770237 -250.953033) (xy 355.786275 -250.959768)
			(xy 355.803645 -250.960717) (xy 355.81209 -250.958604) (xy 355.838779 -250.951152) (xy 355.893605 -250.943125)
			(xy 355.92131 -250.942602) (xy 355.94856 -250.943089) (xy 356.002506 -250.950846) (xy 356.054798 -250.966202)
			(xy 356.104373 -250.988844) (xy 356.150221 -251.01831) (xy 356.191409 -251.054001) (xy 356.227098 -251.09519)
			(xy 356.256563 -251.141039) (xy 356.279202 -251.190614) (xy 356.294556 -251.242907) (xy 356.302312 -251.296853)
			(xy 356.302312 -251.32411) (xy 357.063292 -251.32411) (xy 357.067363 -251.268488) (xy 357.079489 -251.214051)
			(xy 357.099412 -251.16196) (xy 357.126708 -251.113325) (xy 357.160794 -251.069182) (xy 357.200943 -251.030473)
			(xy 357.246301 -250.998022) (xy 357.295901 -250.972521) (xy 357.348685 -250.954514) (xy 357.403528 -250.944384)
			(xy 357.459262 -250.942347) (xy 357.514699 -250.948447) (xy 357.568656 -250.962553) (xy 357.619985 -250.984365)
			(xy 357.667591 -251.013419) (xy 357.710459 -251.049094) (xy 357.747676 -251.090631) (xy 357.778449 -251.137144)
			(xy 357.802121 -251.187641) (xy 357.818189 -251.241048) (xy 357.826309 -251.296224) (xy 357.826818 -251.32411)
			(xy 357.826309 -251.351996) (xy 357.818189 -251.407172) (xy 357.802121 -251.460579) (xy 357.778449 -251.511076)
			(xy 357.747676 -251.557589) (xy 357.710459 -251.599126) (xy 357.667591 -251.634801) (xy 357.619985 -251.663855)
			(xy 357.568656 -251.685667) (xy 357.514699 -251.699773) (xy 357.459262 -251.705873) (xy 357.403528 -251.703836)
			(xy 357.348685 -251.693706) (xy 357.295901 -251.675699) (xy 357.246301 -251.650198) (xy 357.200943 -251.617747)
			(xy 357.160794 -251.579038) (xy 357.126708 -251.534895) (xy 357.099412 -251.48626) (xy 357.079489 -251.434169)
			(xy 357.067363 -251.379732) (xy 357.063292 -251.32411) (xy 356.302312 -251.32411) (xy 356.302312 -251.351354)
			(xy 356.294555 -251.405299) (xy 356.2792 -251.457592) (xy 356.25656 -251.507167) (xy 356.227094 -251.553016)
			(xy 356.191404 -251.594204) (xy 356.150216 -251.629894) (xy 356.104367 -251.65936) (xy 356.054792 -251.682)
			(xy 356.002499 -251.697355) (xy 355.948554 -251.705112) (xy 355.894053 -251.705112) (xy 355.840107 -251.697356)
			(xy 355.787814 -251.682002) (xy 355.738239 -251.659363) (xy 355.69239 -251.629898) (xy 355.651201 -251.594209)
			(xy 355.61551 -251.553021) (xy 355.586044 -251.507173) (xy 355.563402 -251.457598) (xy 355.548046 -251.405306)
			(xy 355.540289 -251.35136) (xy 355.539802 -251.32411) (xy 355.539802 -251.323856) (xy 355.540037 -251.30545)
			(xy 355.5436 -251.268811) (xy 355.546914 -251.250704) (xy 355.549454 -251.23775) (xy 355.541326 -251.212604)
			(xy 355.46665 -251.14504) (xy 355.459992 -251.139425) (xy 355.443952 -251.132672) (xy 355.426575 -251.131713)
			(xy 355.418136 -251.133864) (xy 355.391447 -251.141317) (xy 355.336621 -251.149347) (xy 355.308916 -251.149866)
			(xy 355.280365 -251.149327) (xy 355.223902 -251.140807) (xy 355.169338 -251.12397) (xy 355.117892 -251.099191)
			(xy 355.070711 -251.067024) (xy 355.02885 -251.028187) (xy 354.993242 -250.983547) (xy 354.978462 -250.959112)
			(xy 354.97262 -250.948952) (xy 354.953062 -250.935998) (xy 354.862384 -250.923298) (xy 354.850813 -250.922235)
			(xy 354.828728 -250.929382) (xy 354.819966 -250.937014) (xy 354.241862 -251.49556) (xy 354.223225 -251.512902)
			(xy 354.181622 -251.542239) (xy 354.136022 -251.564869) (xy 354.087498 -251.58026) (xy 354.037191 -251.58805)
			(xy 354.011738 -251.588524) (xy 351.91954 -251.588524) (xy 351.909515 -251.588937) (xy 351.890989 -251.596601)
			(xy 351.87681 -251.610775) (xy 351.86914 -251.629299) (xy 351.86874 -251.639324) (xy 351.86874 -252.112272)
			(xy 352.47275 -252.112272) (xy 352.476821 -252.05665) (xy 352.488947 -252.002213) (xy 352.50887 -251.950122)
			(xy 352.536166 -251.901487) (xy 352.570252 -251.857344) (xy 352.610401 -251.818635) (xy 352.655759 -251.786184)
			(xy 352.705359 -251.760683) (xy 352.758143 -251.742676) (xy 352.812986 -251.732546) (xy 352.86872 -251.730509)
			(xy 352.924157 -251.736609) (xy 352.978114 -251.750715) (xy 353.029443 -251.772527) (xy 353.077049 -251.801581)
			(xy 353.119917 -251.837256) (xy 353.157134 -251.878793) (xy 353.187907 -251.925306) (xy 353.211579 -251.975803)
			(xy 353.227647 -252.02921) (xy 353.230115 -252.045978) (xy 359.438954 -252.045978) (xy 359.443025 -251.990356)
			(xy 359.455151 -251.935919) (xy 359.475074 -251.883828) (xy 359.50237 -251.835193) (xy 359.536456 -251.79105)
			(xy 359.576605 -251.752341) (xy 359.621963 -251.71989) (xy 359.671563 -251.694389) (xy 359.724347 -251.676382)
			(xy 359.77919 -251.666252) (xy 359.834924 -251.664215) (xy 359.890361 -251.670315) (xy 359.944318 -251.684421)
			(xy 359.995647 -251.706233) (xy 360.043253 -251.735287) (xy 360.086121 -251.770962) (xy 360.123338 -251.812499)
			(xy 360.154111 -251.859012) (xy 360.177783 -251.909509) (xy 360.193851 -251.962916) (xy 360.201971 -252.018092)
			(xy 360.20248 -252.045978) (xy 360.201971 -252.073864) (xy 360.193851 -252.12904) (xy 360.177783 -252.182447)
			(xy 360.154111 -252.232944) (xy 360.123338 -252.279457) (xy 360.086121 -252.320994) (xy 360.043253 -252.356669)
			(xy 359.995647 -252.385723) (xy 359.944318 -252.407535) (xy 359.890361 -252.421641) (xy 359.834924 -252.427741)
			(xy 359.77919 -252.425704) (xy 359.724347 -252.415574) (xy 359.671563 -252.397567) (xy 359.621963 -252.372066)
			(xy 359.576605 -252.339615) (xy 359.536456 -252.300906) (xy 359.50237 -252.256763) (xy 359.475074 -252.208128)
			(xy 359.455151 -252.156037) (xy 359.443025 -252.1016) (xy 359.438954 -252.045978) (xy 353.230115 -252.045978)
			(xy 353.235767 -252.084386) (xy 353.236276 -252.112272) (xy 353.235767 -252.140158) (xy 353.227647 -252.195334)
			(xy 353.211579 -252.248741) (xy 353.187907 -252.299238) (xy 353.157134 -252.345751) (xy 353.119917 -252.387288)
			(xy 353.077049 -252.422963) (xy 353.029443 -252.452017) (xy 352.978114 -252.473829) (xy 352.924157 -252.487935)
			(xy 352.86872 -252.494035) (xy 352.812986 -252.491998) (xy 352.758143 -252.481868) (xy 352.705359 -252.463861)
			(xy 352.655759 -252.43836) (xy 352.610401 -252.405909) (xy 352.570252 -252.3672) (xy 352.536166 -252.323057)
			(xy 352.50887 -252.274422) (xy 352.488947 -252.222331) (xy 352.476821 -252.167894) (xy 352.47275 -252.112272)
			(xy 351.86874 -252.112272) (xy 351.86874 -253.38786) (xy 358.443274 -253.38786) (xy 358.447345 -253.332238)
			(xy 358.459471 -253.277801) (xy 358.479394 -253.22571) (xy 358.50669 -253.177075) (xy 358.540776 -253.132932)
			(xy 358.580925 -253.094223) (xy 358.626283 -253.061772) (xy 358.675883 -253.036271) (xy 358.728667 -253.018264)
			(xy 358.78351 -253.008134) (xy 358.839244 -253.006097) (xy 358.894681 -253.012197) (xy 358.948638 -253.026303)
			(xy 358.999967 -253.048115) (xy 359.047573 -253.077169) (xy 359.090441 -253.112844) (xy 359.127658 -253.154381)
			(xy 359.143657 -253.178564) (xy 360.485942 -253.178564) (xy 360.490013 -253.122942) (xy 360.502139 -253.068505)
			(xy 360.522062 -253.016414) (xy 360.549358 -252.967779) (xy 360.583444 -252.923636) (xy 360.623593 -252.884927)
			(xy 360.668951 -252.852476) (xy 360.718551 -252.826975) (xy 360.771335 -252.808968) (xy 360.826178 -252.798838)
			(xy 360.881912 -252.796801) (xy 360.937349 -252.802901) (xy 360.991306 -252.817007) (xy 361.042635 -252.838819)
			(xy 361.090241 -252.867873) (xy 361.133109 -252.903548) (xy 361.170326 -252.945085) (xy 361.201099 -252.991598)
			(xy 361.224771 -253.042095) (xy 361.240839 -253.095502) (xy 361.248959 -253.150678) (xy 361.249468 -253.178564)
			(xy 362.549438 -253.178564) (xy 362.553509 -253.122942) (xy 362.565635 -253.068505) (xy 362.585558 -253.016414)
			(xy 362.612854 -252.967779) (xy 362.64694 -252.923636) (xy 362.687089 -252.884927) (xy 362.732447 -252.852476)
			(xy 362.782047 -252.826975) (xy 362.834831 -252.808968) (xy 362.889674 -252.798838) (xy 362.945408 -252.796801)
			(xy 363.000845 -252.802901) (xy 363.054802 -252.817007) (xy 363.106131 -252.838819) (xy 363.153737 -252.867873)
			(xy 363.196605 -252.903548) (xy 363.233822 -252.945085) (xy 363.264595 -252.991598) (xy 363.288267 -253.042095)
			(xy 363.304335 -253.095502) (xy 363.312455 -253.150678) (xy 363.312964 -253.178564) (xy 363.312455 -253.20645)
			(xy 363.304335 -253.261626) (xy 363.288267 -253.315033) (xy 363.264595 -253.36553) (xy 363.233822 -253.412043)
			(xy 363.196605 -253.45358) (xy 363.153737 -253.489255) (xy 363.106131 -253.518309) (xy 363.054802 -253.540121)
			(xy 363.000845 -253.554227) (xy 362.945408 -253.560327) (xy 362.889674 -253.55829) (xy 362.834831 -253.54816)
			(xy 362.782047 -253.530153) (xy 362.732447 -253.504652) (xy 362.687089 -253.472201) (xy 362.64694 -253.433492)
			(xy 362.612854 -253.389349) (xy 362.585558 -253.340714) (xy 362.565635 -253.288623) (xy 362.553509 -253.234186)
			(xy 362.549438 -253.178564) (xy 361.249468 -253.178564) (xy 361.248959 -253.20645) (xy 361.240839 -253.261626)
			(xy 361.224771 -253.315033) (xy 361.201099 -253.36553) (xy 361.170326 -253.412043) (xy 361.133109 -253.45358)
			(xy 361.090241 -253.489255) (xy 361.042635 -253.518309) (xy 360.991306 -253.540121) (xy 360.937349 -253.554227)
			(xy 360.881912 -253.560327) (xy 360.826178 -253.55829) (xy 360.771335 -253.54816) (xy 360.718551 -253.530153)
			(xy 360.668951 -253.504652) (xy 360.623593 -253.472201) (xy 360.583444 -253.433492) (xy 360.549358 -253.389349)
			(xy 360.522062 -253.340714) (xy 360.502139 -253.288623) (xy 360.490013 -253.234186) (xy 360.485942 -253.178564)
			(xy 359.143657 -253.178564) (xy 359.158431 -253.200894) (xy 359.182103 -253.251391) (xy 359.198171 -253.304798)
			(xy 359.206291 -253.359974) (xy 359.2068 -253.38786) (xy 359.206291 -253.415746) (xy 359.198171 -253.470922)
			(xy 359.182103 -253.524329) (xy 359.158431 -253.574826) (xy 359.127658 -253.621339) (xy 359.090441 -253.662876)
			(xy 359.047573 -253.698551) (xy 358.999967 -253.727605) (xy 358.948638 -253.749417) (xy 358.894681 -253.763523)
			(xy 358.839244 -253.769623) (xy 358.78351 -253.767586) (xy 358.728667 -253.757456) (xy 358.675883 -253.739449)
			(xy 358.626283 -253.713948) (xy 358.580925 -253.681497) (xy 358.540776 -253.642788) (xy 358.50669 -253.598645)
			(xy 358.479394 -253.55001) (xy 358.459471 -253.497919) (xy 358.447345 -253.443482) (xy 358.443274 -253.38786)
			(xy 351.86874 -253.38786) (xy 351.86874 -253.399798) (xy 351.868316 -253.409867) (xy 351.860595 -253.428466)
			(xy 351.853754 -253.435866) (xy 351.304606 -253.985014) (xy 353.918772 -253.985014) (xy 353.922843 -253.929392)
			(xy 353.934969 -253.874955) (xy 353.954892 -253.822864) (xy 353.982188 -253.774229) (xy 354.016274 -253.730086)
			(xy 354.056423 -253.691377) (xy 354.101781 -253.658926) (xy 354.151381 -253.633425) (xy 354.204165 -253.615418)
			(xy 354.259008 -253.605288) (xy 354.314742 -253.603251) (xy 354.370179 -253.609351) (xy 354.424136 -253.623457)
			(xy 354.475465 -253.645269) (xy 354.523071 -253.674323) (xy 354.565939 -253.709998) (xy 354.603156 -253.751535)
			(xy 354.633929 -253.798048) (xy 354.657601 -253.848545) (xy 354.673669 -253.901952) (xy 354.681789 -253.957128)
			(xy 354.682298 -253.985014) (xy 354.681789 -254.0129) (xy 354.673669 -254.068076) (xy 354.657601 -254.121483)
			(xy 354.633929 -254.17198) (xy 354.618987 -254.194564) (xy 362.517942 -254.194564) (xy 362.522013 -254.138942)
			(xy 362.534139 -254.084505) (xy 362.554062 -254.032414) (xy 362.581358 -253.983779) (xy 362.615444 -253.939636)
			(xy 362.655593 -253.900927) (xy 362.700951 -253.868476) (xy 362.750551 -253.842975) (xy 362.803335 -253.824968)
			(xy 362.858178 -253.814838) (xy 362.913912 -253.812801) (xy 362.969349 -253.818901) (xy 363.023306 -253.833007)
			(xy 363.074635 -253.854819) (xy 363.122241 -253.883873) (xy 363.165109 -253.919548) (xy 363.202326 -253.961085)
			(xy 363.233099 -254.007598) (xy 363.256771 -254.058095) (xy 363.272839 -254.111502) (xy 363.280959 -254.166678)
			(xy 363.281468 -254.194564) (xy 363.280959 -254.22245) (xy 363.272839 -254.277626) (xy 363.256771 -254.331033)
			(xy 363.233099 -254.38153) (xy 363.202326 -254.428043) (xy 363.165109 -254.46958) (xy 363.122241 -254.505255)
			(xy 363.074635 -254.534309) (xy 363.023306 -254.556121) (xy 362.969349 -254.570227) (xy 362.913912 -254.576327)
			(xy 362.858178 -254.57429) (xy 362.803335 -254.56416) (xy 362.750551 -254.546153) (xy 362.700951 -254.520652)
			(xy 362.655593 -254.488201) (xy 362.615444 -254.449492) (xy 362.581358 -254.405349) (xy 362.554062 -254.356714)
			(xy 362.534139 -254.304623) (xy 362.522013 -254.250186) (xy 362.517942 -254.194564) (xy 354.618987 -254.194564)
			(xy 354.603156 -254.218493) (xy 354.565939 -254.26003) (xy 354.523071 -254.295705) (xy 354.475465 -254.324759)
			(xy 354.424136 -254.346571) (xy 354.370179 -254.360677) (xy 354.314742 -254.366777) (xy 354.259008 -254.36474)
			(xy 354.204165 -254.35461) (xy 354.151381 -254.336603) (xy 354.101781 -254.311102) (xy 354.056423 -254.278651)
			(xy 354.016274 -254.239942) (xy 353.982188 -254.195799) (xy 353.954892 -254.147164) (xy 353.934969 -254.095073)
			(xy 353.922843 -254.040636) (xy 353.918772 -253.985014) (xy 351.304606 -253.985014) (xy 350.924368 -254.365252)
			(xy 350.92085 -254.368985) (xy 350.915228 -254.377562) (xy 350.913192 -254.38227) (xy 350.909636 -254.390906)
			(xy 350.909636 -254.79756) (xy 350.909521 -254.802515) (xy 350.907611 -254.81224) (xy 350.905826 -254.816864)
			(xy 350.89846 -254.83439) (xy 350.895158 -254.848106) (xy 350.894904 -254.853186) (xy 350.894904 -255.11125)
			(xy 353.193856 -255.11125) (xy 353.197927 -255.055628) (xy 353.210053 -255.001191) (xy 353.229976 -254.9491)
			(xy 353.257272 -254.900465) (xy 353.291358 -254.856322) (xy 353.331507 -254.817613) (xy 353.376865 -254.785162)
			(xy 353.426465 -254.759661) (xy 353.479249 -254.741654) (xy 353.534092 -254.731524) (xy 353.589826 -254.729487)
			(xy 353.645263 -254.735587) (xy 353.69922 -254.749693) (xy 353.750549 -254.771505) (xy 353.798155 -254.800559)
			(xy 353.841023 -254.836234) (xy 353.87824 -254.877771) (xy 353.909013 -254.924284) (xy 353.932685 -254.974781)
			(xy 353.948753 -255.028188) (xy 353.956873 -255.083364) (xy 353.957382 -255.11125) (xy 353.956873 -255.139136)
			(xy 353.948753 -255.194312) (xy 353.932685 -255.247719) (xy 353.909013 -255.298216) (xy 353.87824 -255.344729)
			(xy 353.861902 -255.362964) (xy 364.277908 -255.362964) (xy 364.281979 -255.307342) (xy 364.294105 -255.252905)
			(xy 364.314028 -255.200814) (xy 364.341324 -255.152179) (xy 364.37541 -255.108036) (xy 364.415559 -255.069327)
			(xy 364.460917 -255.036876) (xy 364.510517 -255.011375) (xy 364.563301 -254.993368) (xy 364.618144 -254.983238)
			(xy 364.673878 -254.981201) (xy 364.729315 -254.987301) (xy 364.783272 -255.001407) (xy 364.834601 -255.023219)
			(xy 364.882207 -255.052273) (xy 364.925075 -255.087948) (xy 364.962292 -255.129485) (xy 364.993065 -255.175998)
			(xy 365.016737 -255.226495) (xy 365.032805 -255.279902) (xy 365.040925 -255.335078) (xy 365.041434 -255.362964)
			(xy 365.040925 -255.39085) (xy 365.032805 -255.446026) (xy 365.016737 -255.499433) (xy 364.993065 -255.54993)
			(xy 364.962292 -255.596443) (xy 364.925075 -255.63798) (xy 364.882207 -255.673655) (xy 364.834601 -255.702709)
			(xy 364.783272 -255.724521) (xy 364.729315 -255.738627) (xy 364.673878 -255.744727) (xy 364.618144 -255.74269)
			(xy 364.563301 -255.73256) (xy 364.510517 -255.714553) (xy 364.460917 -255.689052) (xy 364.415559 -255.656601)
			(xy 364.37541 -255.617892) (xy 364.341324 -255.573749) (xy 364.314028 -255.525114) (xy 364.294105 -255.473023)
			(xy 364.281979 -255.418586) (xy 364.277908 -255.362964) (xy 353.861902 -255.362964) (xy 353.841023 -255.386266)
			(xy 353.798155 -255.421941) (xy 353.750549 -255.450995) (xy 353.69922 -255.472807) (xy 353.645263 -255.486913)
			(xy 353.589826 -255.493013) (xy 353.534092 -255.490976) (xy 353.479249 -255.480846) (xy 353.426465 -255.462839)
			(xy 353.376865 -255.437338) (xy 353.331507 -255.404887) (xy 353.291358 -255.366178) (xy 353.257272 -255.322035)
			(xy 353.229976 -255.2734) (xy 353.210053 -255.221309) (xy 353.197927 -255.166872) (xy 353.193856 -255.11125)
			(xy 350.894904 -255.11125) (xy 350.894904 -255.532636) (xy 350.89435 -255.562618) (xy 350.884975 -255.621844)
			(xy 350.866445 -255.678872) (xy 350.839218 -255.732298) (xy 350.803963 -255.780803) (xy 350.783144 -255.802384)
			(xy 350.358964 -256.226564) (xy 358.420668 -256.226564) (xy 358.424739 -256.170942) (xy 358.436865 -256.116505)
			(xy 358.456788 -256.064414) (xy 358.484084 -256.015779) (xy 358.51817 -255.971636) (xy 358.558319 -255.932927)
			(xy 358.603677 -255.900476) (xy 358.653277 -255.874975) (xy 358.706061 -255.856968) (xy 358.760904 -255.846838)
			(xy 358.816638 -255.844801) (xy 358.872075 -255.850901) (xy 358.926032 -255.865007) (xy 358.977361 -255.886819)
			(xy 359.024967 -255.915873) (xy 359.067835 -255.951548) (xy 359.105052 -255.993085) (xy 359.135825 -256.039598)
			(xy 359.159497 -256.090095) (xy 359.175565 -256.143502) (xy 359.183685 -256.198678) (xy 359.184194 -256.226564)
			(xy 360.485942 -256.226564) (xy 360.490013 -256.170942) (xy 360.502139 -256.116505) (xy 360.522062 -256.064414)
			(xy 360.549358 -256.015779) (xy 360.583444 -255.971636) (xy 360.623593 -255.932927) (xy 360.668951 -255.900476)
			(xy 360.718551 -255.874975) (xy 360.771335 -255.856968) (xy 360.826178 -255.846838) (xy 360.881912 -255.844801)
			(xy 360.937349 -255.850901) (xy 360.991306 -255.865007) (xy 361.042635 -255.886819) (xy 361.090241 -255.915873)
			(xy 361.133109 -255.951548) (xy 361.170326 -255.993085) (xy 361.201099 -256.039598) (xy 361.224771 -256.090095)
			(xy 361.240839 -256.143502) (xy 361.248959 -256.198678) (xy 361.249468 -256.226564) (xy 361.248959 -256.25445)
			(xy 361.240839 -256.309626) (xy 361.224771 -256.363033) (xy 361.201099 -256.41353) (xy 361.170326 -256.460043)
			(xy 361.133109 -256.50158) (xy 361.090241 -256.537255) (xy 361.042635 -256.566309) (xy 360.991306 -256.588121)
			(xy 360.937349 -256.602227) (xy 360.91193 -256.605024) (xy 365.598708 -256.605024) (xy 365.602779 -256.549402)
			(xy 365.614905 -256.494965) (xy 365.634828 -256.442874) (xy 365.662124 -256.394239) (xy 365.69621 -256.350096)
			(xy 365.736359 -256.311387) (xy 365.781717 -256.278936) (xy 365.831317 -256.253435) (xy 365.884101 -256.235428)
			(xy 365.938944 -256.225298) (xy 365.994678 -256.223261) (xy 366.050115 -256.229361) (xy 366.104072 -256.243467)
			(xy 366.155401 -256.265279) (xy 366.203007 -256.294333) (xy 366.245875 -256.330008) (xy 366.283092 -256.371545)
			(xy 366.313865 -256.418058) (xy 366.337537 -256.468555) (xy 366.353605 -256.521962) (xy 366.361725 -256.577138)
			(xy 366.362234 -256.605024) (xy 366.361725 -256.63291) (xy 366.353605 -256.688086) (xy 366.337537 -256.741493)
			(xy 366.313865 -256.79199) (xy 366.283092 -256.838503) (xy 366.245875 -256.88004) (xy 366.203007 -256.915715)
			(xy 366.155401 -256.944769) (xy 366.104072 -256.966581) (xy 366.050115 -256.980687) (xy 365.994678 -256.986787)
			(xy 365.938944 -256.98475) (xy 365.884101 -256.97462) (xy 365.831317 -256.956613) (xy 365.781717 -256.931112)
			(xy 365.736359 -256.898661) (xy 365.69621 -256.859952) (xy 365.662124 -256.815809) (xy 365.634828 -256.767174)
			(xy 365.614905 -256.715083) (xy 365.602779 -256.660646) (xy 365.598708 -256.605024) (xy 360.91193 -256.605024)
			(xy 360.881912 -256.608327) (xy 360.826178 -256.60629) (xy 360.771335 -256.59616) (xy 360.718551 -256.578153)
			(xy 360.668951 -256.552652) (xy 360.623593 -256.520201) (xy 360.583444 -256.481492) (xy 360.549358 -256.437349)
			(xy 360.522062 -256.388714) (xy 360.502139 -256.336623) (xy 360.490013 -256.282186) (xy 360.485942 -256.226564)
			(xy 359.184194 -256.226564) (xy 359.183685 -256.25445) (xy 359.175565 -256.309626) (xy 359.159497 -256.363033)
			(xy 359.135825 -256.41353) (xy 359.105052 -256.460043) (xy 359.067835 -256.50158) (xy 359.024967 -256.537255)
			(xy 358.977361 -256.566309) (xy 358.926032 -256.588121) (xy 358.872075 -256.602227) (xy 358.816638 -256.608327)
			(xy 358.760904 -256.60629) (xy 358.706061 -256.59616) (xy 358.653277 -256.578153) (xy 358.603677 -256.552652)
			(xy 358.558319 -256.520201) (xy 358.51817 -256.481492) (xy 358.484084 -256.437349) (xy 358.456788 -256.388714)
			(xy 358.436865 -256.336623) (xy 358.424739 -256.282186) (xy 358.420668 -256.226564) (xy 350.358964 -256.226564)
			(xy 349.71863 -256.866898) (xy 349.697053 -256.887633) (xy 349.648636 -256.922795) (xy 349.595318 -256.949956)
			(xy 349.538409 -256.968448) (xy 349.479309 -256.977816) (xy 349.44939 -256.978404) (xy 349.358458 -256.978404)
			(xy 349.353378 -256.978658) (xy 349.345561 -256.9797) (xy 349.331075 -256.985908) (xy 349.32493 -256.99085)
			(xy 349.320612 -256.995168) (xy 349.27032 -257.050286) (xy 349.267272 -257.054096) (xy 349.261684 -257.063494)
			(xy 349.259906 -257.068574) (xy 349.256096 -257.07975) (xy 349.257112 -257.09118) (xy 349.257112 -257.091434)
			(xy 349.258425 -257.115564) (xy 360.485942 -257.115564) (xy 360.490013 -257.059942) (xy 360.502139 -257.005505)
			(xy 360.522062 -256.953414) (xy 360.549358 -256.904779) (xy 360.583444 -256.860636) (xy 360.623593 -256.821927)
			(xy 360.668951 -256.789476) (xy 360.718551 -256.763975) (xy 360.771335 -256.745968) (xy 360.826178 -256.735838)
			(xy 360.881912 -256.733801) (xy 360.937349 -256.739901) (xy 360.991306 -256.754007) (xy 361.042635 -256.775819)
			(xy 361.090241 -256.804873) (xy 361.133109 -256.840548) (xy 361.170326 -256.882085) (xy 361.201099 -256.928598)
			(xy 361.224771 -256.979095) (xy 361.240839 -257.032502) (xy 361.248959 -257.087678) (xy 361.249468 -257.115564)
			(xy 361.248959 -257.14345) (xy 361.240839 -257.198626) (xy 361.224771 -257.252033) (xy 361.201099 -257.30253)
			(xy 361.170326 -257.349043) (xy 361.133109 -257.39058) (xy 361.090241 -257.426255) (xy 361.042635 -257.455309)
			(xy 360.991306 -257.477121) (xy 360.937349 -257.491227) (xy 360.881912 -257.497327) (xy 360.826178 -257.49529)
			(xy 360.771335 -257.48516) (xy 360.718551 -257.467153) (xy 360.668951 -257.441652) (xy 360.623593 -257.409201)
			(xy 360.583444 -257.370492) (xy 360.549358 -257.326349) (xy 360.522062 -257.277714) (xy 360.502139 -257.225623)
			(xy 360.490013 -257.171186) (xy 360.485942 -257.115564) (xy 349.258425 -257.115564) (xy 349.259144 -257.128772)
			(xy 349.259144 -257.13182) (xy 349.258575 -257.159015) (xy 349.250678 -257.212833) (xy 349.235218 -257.264983)
			(xy 349.212508 -257.31441) (xy 349.183009 -257.36011) (xy 349.147319 -257.401157) (xy 349.106161 -257.43672)
			(xy 349.06037 -257.466077) (xy 349.010873 -257.488633) (xy 348.958675 -257.503932) (xy 348.904833 -257.511662)
			(xy 348.877636 -257.512058) (xy 348.850383 -257.511597) (xy 348.796431 -257.503844) (xy 348.744131 -257.488491)
			(xy 348.69455 -257.465849) (xy 348.648696 -257.436382) (xy 348.607503 -257.400687) (xy 348.57181 -257.359493)
			(xy 348.542344 -257.313638) (xy 348.519705 -257.264056) (xy 348.504353 -257.211756) (xy 348.496602 -257.157803)
			(xy 348.496128 -257.13055) (xy 348.496181 -257.120562) (xy 348.497199 -257.100613) (xy 348.49816 -257.090672)
			(xy 348.49816 -257.08991) (xy 348.498652 -257.08018) (xy 348.493173 -257.061501) (xy 348.487492 -257.053588)
			(xy 348.432882 -256.99339) (xy 348.428056 -256.989072) (xy 348.42127 -256.984162) (xy 348.405439 -256.978717)
			(xy 348.397068 -256.978404) (xy 344.870532 -256.978404) (xy 344.863042 -256.978711) (xy 344.848717 -256.983103)
			(xy 344.842338 -256.98704) (xy 344.837766 -256.990088) (xy 343.808395 -258.01955) (xy 348.623128 -258.01955)
			(xy 348.623602 -257.992297) (xy 348.631353 -257.938344) (xy 348.646705 -257.886044) (xy 348.669344 -257.836462)
			(xy 348.69881 -257.790607) (xy 348.734503 -257.749413) (xy 348.775696 -257.713718) (xy 348.82155 -257.684251)
			(xy 348.871131 -257.661609) (xy 348.923431 -257.646256) (xy 348.977383 -257.638503) (xy 349.004636 -257.638042)
			(xy 349.031693 -257.638468) (xy 349.085261 -257.646131) (xy 349.13721 -257.661285) (xy 349.186497 -257.683626)
			(xy 349.232134 -257.712706) (xy 349.273205 -257.74794) (xy 349.308887 -257.788624) (xy 349.338463 -257.83394)
			(xy 349.35033 -257.85826) (xy 349.354394 -257.866896) (xy 349.367602 -257.879596) (xy 349.447104 -257.913886)
			(xy 349.465646 -257.914648) (xy 349.474536 -257.9116) (xy 349.503804 -257.90251) (xy 349.564292 -257.892677)
			(xy 349.594932 -257.892042) (xy 349.595186 -257.892042) (xy 349.622443 -257.892404) (xy 349.676403 -257.90016)
			(xy 349.728709 -257.915517) (xy 349.778298 -257.938162) (xy 349.824158 -257.967633) (xy 349.865358 -258.003332)
			(xy 349.901058 -258.04453) (xy 349.930531 -258.09039) (xy 349.949335 -258.131564) (xy 358.458768 -258.131564)
			(xy 358.462839 -258.075942) (xy 358.474965 -258.021505) (xy 358.494888 -257.969414) (xy 358.522184 -257.920779)
			(xy 358.55627 -257.876636) (xy 358.596419 -257.837927) (xy 358.641777 -257.805476) (xy 358.691377 -257.779975)
			(xy 358.744161 -257.761968) (xy 358.799004 -257.751838) (xy 358.854738 -257.749801) (xy 358.910175 -257.755901)
			(xy 358.964132 -257.770007) (xy 359.015461 -257.791819) (xy 359.063067 -257.820873) (xy 359.105935 -257.856548)
			(xy 359.143152 -257.898085) (xy 359.173925 -257.944598) (xy 359.197597 -257.995095) (xy 359.213665 -258.048502)
			(xy 359.221785 -258.103678) (xy 359.222294 -258.131564) (xy 362.517942 -258.131564) (xy 362.522013 -258.075942)
			(xy 362.534139 -258.021505) (xy 362.554062 -257.969414) (xy 362.581358 -257.920779) (xy 362.615444 -257.876636)
			(xy 362.655593 -257.837927) (xy 362.700951 -257.805476) (xy 362.750551 -257.779975) (xy 362.803335 -257.761968)
			(xy 362.858178 -257.751838) (xy 362.913912 -257.749801) (xy 362.969349 -257.755901) (xy 363.023306 -257.770007)
			(xy 363.074635 -257.791819) (xy 363.122241 -257.820873) (xy 363.165109 -257.856548) (xy 363.202326 -257.898085)
			(xy 363.233099 -257.944598) (xy 363.256771 -257.995095) (xy 363.272839 -258.048502) (xy 363.280959 -258.103678)
			(xy 363.281468 -258.131564) (xy 363.280959 -258.15945) (xy 363.272839 -258.214626) (xy 363.256771 -258.268033)
			(xy 363.233099 -258.31853) (xy 363.202326 -258.365043) (xy 363.165109 -258.40658) (xy 363.122241 -258.442255)
			(xy 363.074635 -258.471309) (xy 363.023306 -258.493121) (xy 362.969349 -258.507227) (xy 362.913912 -258.513327)
			(xy 362.858178 -258.51129) (xy 362.803335 -258.50116) (xy 362.750551 -258.483153) (xy 362.700951 -258.457652)
			(xy 362.655593 -258.425201) (xy 362.615444 -258.386492) (xy 362.581358 -258.342349) (xy 362.554062 -258.293714)
			(xy 362.534139 -258.241623) (xy 362.522013 -258.187186) (xy 362.517942 -258.131564) (xy 359.222294 -258.131564)
			(xy 359.221785 -258.15945) (xy 359.213665 -258.214626) (xy 359.197597 -258.268033) (xy 359.173925 -258.31853)
			(xy 359.143152 -258.365043) (xy 359.105935 -258.40658) (xy 359.063067 -258.442255) (xy 359.015461 -258.471309)
			(xy 358.964132 -258.493121) (xy 358.910175 -258.507227) (xy 358.854738 -258.513327) (xy 358.799004 -258.51129)
			(xy 358.744161 -258.50116) (xy 358.691377 -258.483153) (xy 358.641777 -258.457652) (xy 358.596419 -258.425201)
			(xy 358.55627 -258.386492) (xy 358.522184 -258.342349) (xy 358.494888 -258.293714) (xy 358.474965 -258.241623)
			(xy 358.462839 -258.187186) (xy 358.458768 -258.131564) (xy 349.949335 -258.131564) (xy 349.953178 -258.139978)
			(xy 349.968537 -258.192284) (xy 349.976295 -258.246243) (xy 349.976295 -258.300757) (xy 349.968537 -258.354716)
			(xy 349.953178 -258.407022) (xy 349.930531 -258.45661) (xy 349.901058 -258.50247) (xy 349.865358 -258.543668)
			(xy 349.824158 -258.579367) (xy 349.778298 -258.608838) (xy 349.728709 -258.631483) (xy 349.676403 -258.64684)
			(xy 349.622443 -258.654596) (xy 349.595186 -258.655058) (xy 349.574638 -258.654758) (xy 349.533782 -258.650305)
			(xy 349.513652 -258.646168) (xy 349.513398 -258.646168) (xy 349.501664 -258.644425) (xy 349.478765 -258.650502)
			(xy 349.469456 -258.657852) (xy 349.39859 -258.720336) (xy 349.3897 -258.742688) (xy 349.390716 -258.754626)
			(xy 349.390716 -258.755134) (xy 349.392494 -258.79044) (xy 349.392008 -258.817691) (xy 349.384252 -258.871639)
			(xy 349.368897 -258.923934) (xy 349.346255 -258.973511) (xy 349.316789 -259.019361) (xy 349.281098 -259.060552)
			(xy 349.239907 -259.096243) (xy 349.194057 -259.125709) (xy 349.14448 -259.148351) (xy 349.092185 -259.163706)
			(xy 349.038237 -259.171462) (xy 348.983735 -259.171462) (xy 348.929787 -259.163706) (xy 348.877492 -259.148351)
			(xy 348.827915 -259.125709) (xy 348.782065 -259.096243) (xy 348.740874 -259.060552) (xy 348.705183 -259.019361)
			(xy 348.675717 -258.973511) (xy 348.653075 -258.923934) (xy 348.63772 -258.871639) (xy 348.629964 -258.817691)
			(xy 348.629478 -258.79044) (xy 348.630055 -258.761315) (xy 348.638916 -258.703744) (xy 348.656424 -258.648188)
			(xy 348.682173 -258.595939) (xy 348.715562 -258.548209) (xy 348.755818 -258.506109) (xy 348.778576 -258.487926)
			(xy 348.787566 -258.480272) (xy 348.797904 -258.459082) (xy 348.798388 -258.447286) (xy 348.797626 -258.354068)
			(xy 348.786704 -258.332986) (xy 348.777052 -258.325874) (xy 348.753624 -258.307704) (xy 348.712094 -258.265398)
			(xy 348.677603 -258.21718) (xy 348.650979 -258.164211) (xy 348.632864 -258.107762) (xy 348.623692 -258.049192)
			(xy 348.623128 -258.01955) (xy 343.808395 -258.01955) (xy 342.807469 -259.020564) (xy 344.490292 -259.020564)
			(xy 344.494363 -258.964942) (xy 344.506489 -258.910505) (xy 344.526412 -258.858414) (xy 344.553708 -258.809779)
			(xy 344.587794 -258.765636) (xy 344.627943 -258.726927) (xy 344.673301 -258.694476) (xy 344.722901 -258.668975)
			(xy 344.775685 -258.650968) (xy 344.830528 -258.640838) (xy 344.886262 -258.638801) (xy 344.941699 -258.644901)
			(xy 344.995656 -258.659007) (xy 345.046985 -258.680819) (xy 345.094591 -258.709873) (xy 345.137459 -258.745548)
			(xy 345.174676 -258.787085) (xy 345.205449 -258.833598) (xy 345.229121 -258.884095) (xy 345.245189 -258.937502)
			(xy 345.253309 -258.992678) (xy 345.253818 -259.020564) (xy 345.379292 -259.020564) (xy 345.383363 -258.964942)
			(xy 345.395489 -258.910505) (xy 345.415412 -258.858414) (xy 345.442708 -258.809779) (xy 345.476794 -258.765636)
			(xy 345.516943 -258.726927) (xy 345.562301 -258.694476) (xy 345.611901 -258.668975) (xy 345.664685 -258.650968)
			(xy 345.719528 -258.640838) (xy 345.775262 -258.638801) (xy 345.830699 -258.644901) (xy 345.884656 -258.659007)
			(xy 345.935985 -258.680819) (xy 345.983591 -258.709873) (xy 346.026459 -258.745548) (xy 346.063676 -258.787085)
			(xy 346.094449 -258.833598) (xy 346.118121 -258.884095) (xy 346.134189 -258.937502) (xy 346.142309 -258.992678)
			(xy 346.142818 -259.020564) (xy 346.142309 -259.04845) (xy 346.134189 -259.103626) (xy 346.118121 -259.157033)
			(xy 346.094449 -259.20753) (xy 346.063676 -259.254043) (xy 346.026459 -259.29558) (xy 345.983591 -259.331255)
			(xy 345.935985 -259.360309) (xy 345.884656 -259.382121) (xy 345.830699 -259.396227) (xy 345.775262 -259.402327)
			(xy 345.719528 -259.40029) (xy 345.664685 -259.39016) (xy 345.611901 -259.372153) (xy 345.562301 -259.346652)
			(xy 345.516943 -259.314201) (xy 345.476794 -259.275492) (xy 345.442708 -259.231349) (xy 345.415412 -259.182714)
			(xy 345.395489 -259.130623) (xy 345.383363 -259.076186) (xy 345.379292 -259.020564) (xy 345.253818 -259.020564)
			(xy 345.253309 -259.04845) (xy 345.245189 -259.103626) (xy 345.229121 -259.157033) (xy 345.205449 -259.20753)
			(xy 345.174676 -259.254043) (xy 345.137459 -259.29558) (xy 345.094591 -259.331255) (xy 345.046985 -259.360309)
			(xy 344.995656 -259.382121) (xy 344.941699 -259.396227) (xy 344.886262 -259.402327) (xy 344.830528 -259.40029)
			(xy 344.775685 -259.39016) (xy 344.722901 -259.372153) (xy 344.673301 -259.346652) (xy 344.627943 -259.314201)
			(xy 344.587794 -259.275492) (xy 344.553708 -259.231349) (xy 344.526412 -259.182714) (xy 344.506489 -259.130623)
			(xy 344.494363 -259.076186) (xy 344.490292 -259.020564) (xy 342.807469 -259.020564) (xy 342.292656 -259.535422)
			(xy 346.407738 -259.535422) (xy 346.411809 -259.4798) (xy 346.423935 -259.425363) (xy 346.443858 -259.373272)
			(xy 346.471154 -259.324637) (xy 346.50524 -259.280494) (xy 346.545389 -259.241785) (xy 346.590747 -259.209334)
			(xy 346.640347 -259.183833) (xy 346.693131 -259.165826) (xy 346.747974 -259.155696) (xy 346.803708 -259.153659)
			(xy 346.859145 -259.159759) (xy 346.913102 -259.173865) (xy 346.955213 -259.19176) (xy 355.780592 -259.19176)
			(xy 355.784663 -259.136138) (xy 355.796789 -259.081701) (xy 355.816712 -259.02961) (xy 355.844008 -258.980975)
			(xy 355.878094 -258.936832) (xy 355.918243 -258.898123) (xy 355.963601 -258.865672) (xy 356.013201 -258.840171)
			(xy 356.065985 -258.822164) (xy 356.120828 -258.812034) (xy 356.176562 -258.809997) (xy 356.231999 -258.816097)
			(xy 356.285956 -258.830203) (xy 356.337285 -258.852015) (xy 356.384891 -258.881069) (xy 356.427759 -258.916744)
			(xy 356.464976 -258.958281) (xy 356.495749 -259.004794) (xy 356.519421 -259.055291) (xy 356.535489 -259.108698)
			(xy 356.541209 -259.147564) (xy 362.539024 -259.147564) (xy 362.543095 -259.091942) (xy 362.555221 -259.037505)
			(xy 362.575144 -258.985414) (xy 362.60244 -258.936779) (xy 362.636526 -258.892636) (xy 362.676675 -258.853927)
			(xy 362.722033 -258.821476) (xy 362.771633 -258.795975) (xy 362.824417 -258.777968) (xy 362.87926 -258.767838)
			(xy 362.934994 -258.765801) (xy 362.990431 -258.771901) (xy 363.044388 -258.786007) (xy 363.095717 -258.807819)
			(xy 363.143323 -258.836873) (xy 363.186191 -258.872548) (xy 363.223408 -258.914085) (xy 363.254181 -258.960598)
			(xy 363.277853 -259.011095) (xy 363.293921 -259.064502) (xy 363.302041 -259.119678) (xy 363.30255 -259.147564)
			(xy 363.302041 -259.17545) (xy 363.293921 -259.230626) (xy 363.277853 -259.284033) (xy 363.254181 -259.33453)
			(xy 363.223408 -259.381043) (xy 363.186191 -259.42258) (xy 363.143323 -259.458255) (xy 363.095717 -259.487309)
			(xy 363.044388 -259.509121) (xy 362.990431 -259.523227) (xy 362.934994 -259.529327) (xy 362.87926 -259.52729)
			(xy 362.824417 -259.51716) (xy 362.771633 -259.499153) (xy 362.722033 -259.473652) (xy 362.676675 -259.441201)
			(xy 362.636526 -259.402492) (xy 362.60244 -259.358349) (xy 362.575144 -259.309714) (xy 362.555221 -259.257623)
			(xy 362.543095 -259.203186) (xy 362.539024 -259.147564) (xy 356.541209 -259.147564) (xy 356.543609 -259.163874)
			(xy 356.544118 -259.19176) (xy 356.543609 -259.219646) (xy 356.535489 -259.274822) (xy 356.519421 -259.328229)
			(xy 356.495749 -259.378726) (xy 356.464976 -259.425239) (xy 356.427759 -259.466776) (xy 356.384891 -259.502451)
			(xy 356.337285 -259.531505) (xy 356.285956 -259.553317) (xy 356.231999 -259.567423) (xy 356.176562 -259.573523)
			(xy 356.120828 -259.571486) (xy 356.065985 -259.561356) (xy 356.013201 -259.543349) (xy 355.963601 -259.517848)
			(xy 355.918243 -259.485397) (xy 355.878094 -259.446688) (xy 355.844008 -259.402545) (xy 355.816712 -259.35391)
			(xy 355.796789 -259.301819) (xy 355.784663 -259.247382) (xy 355.780592 -259.19176) (xy 346.955213 -259.19176)
			(xy 346.964431 -259.195677) (xy 347.012037 -259.224731) (xy 347.054905 -259.260406) (xy 347.092122 -259.301943)
			(xy 347.122895 -259.348456) (xy 347.146567 -259.398953) (xy 347.162635 -259.45236) (xy 347.170755 -259.507536)
			(xy 347.171264 -259.535422) (xy 347.170755 -259.563308) (xy 347.162635 -259.618484) (xy 347.146567 -259.671891)
			(xy 347.122895 -259.722388) (xy 347.092122 -259.768901) (xy 347.054905 -259.810438) (xy 347.012037 -259.846113)
			(xy 346.964431 -259.875167) (xy 346.913102 -259.896979) (xy 346.859145 -259.911085) (xy 346.803708 -259.917185)
			(xy 346.747974 -259.915148) (xy 346.693131 -259.905018) (xy 346.640347 -259.887011) (xy 346.590747 -259.86151)
			(xy 346.545389 -259.829059) (xy 346.50524 -259.79035) (xy 346.471154 -259.746207) (xy 346.443858 -259.697572)
			(xy 346.423935 -259.645481) (xy 346.411809 -259.591044) (xy 346.407738 -259.535422) (xy 342.292656 -259.535422)
			(xy 341.956644 -259.871464) (xy 341.93503 -259.892245) (xy 341.886526 -259.927487) (xy 341.833108 -259.954711)
			(xy 341.776089 -259.973246) (xy 341.716874 -259.982636) (xy 341.686896 -259.983224) (xy 341.367872 -259.983224)
			(xy 341.358858 -259.983589) (xy 341.341949 -259.989845) (xy 341.334852 -259.995416) (xy 341.316764 -260.0103)
			(xy 341.277194 -260.035365) (xy 341.234492 -260.054617) (xy 341.189508 -260.067673) (xy 341.143134 -260.074276)
			(xy 341.119714 -260.074664) (xy 334.975708 -260.074664) (xy 334.965639 -260.075087) (xy 334.947038 -260.082807)
			(xy 334.93964 -260.08965) (xy 333.706978 -261.322566) (xy 333.70647 -261.329678) (xy 333.70647 -261.346442)
			(xy 340.147402 -261.346442) (xy 340.14783 -261.320127) (xy 340.155073 -261.267996) (xy 340.1694 -261.217353)
			(xy 340.190539 -261.169154) (xy 340.218092 -261.124312) (xy 340.251538 -261.083674) (xy 340.270592 -261.065518)
			(xy 340.277986 -261.05799) (xy 340.286515 -261.038715) (xy 340.287102 -261.02818) (xy 340.287102 -260.953504)
			(xy 340.286583 -260.942953) (xy 340.278041 -260.923658) (xy 340.270592 -260.916166) (xy 340.251525 -260.898022)
			(xy 340.21807 -260.857389) (xy 340.190512 -260.812547) (xy 340.169376 -260.764344) (xy 340.155061 -260.713694)
			(xy 340.147839 -260.661559) (xy 340.147402 -260.635242) (xy 340.147894 -260.60799) (xy 340.155646 -260.554039)
			(xy 340.170997 -260.501741) (xy 340.193635 -260.452161) (xy 340.2231 -260.406307) (xy 340.258791 -260.365114)
			(xy 340.299981 -260.329419) (xy 340.345833 -260.299951) (xy 340.395411 -260.277308) (xy 340.447708 -260.261953)
			(xy 340.501658 -260.254197) (xy 340.52891 -260.253734) (xy 340.555225 -260.254184) (xy 340.607354 -260.261421)
			(xy 340.657998 -260.275743) (xy 340.706197 -260.296878) (xy 340.75104 -260.324428) (xy 340.791678 -260.35787)
			(xy 340.809834 -260.376924) (xy 340.817351 -260.384332) (xy 340.836634 -260.392855) (xy 340.847172 -260.393434)
			(xy 340.921848 -260.393434) (xy 340.932395 -260.39288) (xy 340.95169 -260.384361) (xy 340.959186 -260.376924)
			(xy 340.97736 -260.357887) (xy 341.017985 -260.324427) (xy 341.062821 -260.296865) (xy 341.111019 -260.275723)
			(xy 341.161663 -260.261402) (xy 341.213795 -260.254174) (xy 341.24011 -260.253734) (xy 341.267365 -260.254146)
			(xy 341.32132 -260.261905) (xy 341.373621 -260.277265) (xy 341.423205 -260.299911) (xy 341.46906 -260.329384)
			(xy 341.510253 -260.365083) (xy 341.545947 -260.406282) (xy 341.575414 -260.452141) (xy 341.598054 -260.501727)
			(xy 341.613406 -260.554031) (xy 341.621158 -260.607987) (xy 341.621618 -260.635242) (xy 341.621173 -260.661557)
			(xy 341.619783 -260.671564) (xy 344.363292 -260.671564) (xy 344.367363 -260.615942) (xy 344.379489 -260.561505)
			(xy 344.399412 -260.509414) (xy 344.426708 -260.460779) (xy 344.460794 -260.416636) (xy 344.500943 -260.377927)
			(xy 344.546301 -260.345476) (xy 344.595901 -260.319975) (xy 344.648685 -260.301968) (xy 344.703528 -260.291838)
			(xy 344.759262 -260.289801) (xy 344.814699 -260.295901) (xy 344.868656 -260.310007) (xy 344.919985 -260.331819)
			(xy 344.967591 -260.360873) (xy 345.010459 -260.396548) (xy 345.047676 -260.438085) (xy 345.078449 -260.484598)
			(xy 345.102121 -260.535095) (xy 345.118189 -260.588502) (xy 345.126309 -260.643678) (xy 345.126818 -260.671564)
			(xy 345.126309 -260.69945) (xy 345.118189 -260.754626) (xy 345.102121 -260.808033) (xy 345.078449 -260.85853)
			(xy 345.047676 -260.905043) (xy 345.010459 -260.94658) (xy 344.967591 -260.982255) (xy 344.919985 -261.011309)
			(xy 344.868656 -261.033121) (xy 344.814699 -261.047227) (xy 344.759262 -261.053327) (xy 344.703528 -261.05129)
			(xy 344.648685 -261.04116) (xy 344.595901 -261.023153) (xy 344.546301 -260.997652) (xy 344.500943 -260.965201)
			(xy 344.460794 -260.926492) (xy 344.426708 -260.882349) (xy 344.399412 -260.833714) (xy 344.379489 -260.781623)
			(xy 344.367363 -260.727186) (xy 344.363292 -260.671564) (xy 341.619783 -260.671564) (xy 341.613933 -260.713686)
			(xy 341.599609 -260.764329) (xy 341.578472 -260.812528) (xy 341.550922 -260.857371) (xy 341.517481 -260.89801)
			(xy 341.498428 -260.916166) (xy 341.491043 -260.923702) (xy 341.482508 -260.942971) (xy 341.481918 -260.953504)
			(xy 341.481918 -261.02818) (xy 341.482439 -261.038731) (xy 341.490979 -261.058026) (xy 341.498428 -261.065518)
			(xy 341.517491 -261.083666) (xy 341.550946 -261.124298) (xy 341.578503 -261.16914) (xy 341.59964 -261.217342)
			(xy 341.599731 -261.217664) (xy 346.340428 -261.217664) (xy 346.344499 -261.162042) (xy 346.356625 -261.107605)
			(xy 346.376548 -261.055514) (xy 346.403844 -261.006879) (xy 346.43793 -260.962736) (xy 346.478079 -260.924027)
			(xy 346.523437 -260.891576) (xy 346.573037 -260.866075) (xy 346.625821 -260.848068) (xy 346.680664 -260.837938)
			(xy 346.736398 -260.835901) (xy 346.791835 -260.842001) (xy 346.845792 -260.856107) (xy 346.897121 -260.877919)
			(xy 346.944727 -260.906973) (xy 346.987595 -260.942648) (xy 347.024812 -260.984185) (xy 347.055585 -261.030698)
			(xy 347.079257 -261.081195) (xy 347.095325 -261.134602) (xy 347.103445 -261.189778) (xy 347.103954 -261.217664)
			(xy 347.103445 -261.24555) (xy 347.095325 -261.300726) (xy 347.079257 -261.354133) (xy 347.055585 -261.40463)
			(xy 347.024812 -261.451143) (xy 346.987595 -261.49268) (xy 346.959991 -261.515652) (xy 351.594883 -261.515652)
			(xy 351.594883 -261.461148) (xy 351.60264 -261.407198) (xy 351.617997 -261.354902) (xy 351.64064 -261.305324)
			(xy 351.670108 -261.259473) (xy 351.705802 -261.218282) (xy 351.746995 -261.182591) (xy 351.792848 -261.153126)
			(xy 351.842428 -261.130487) (xy 351.894726 -261.115135) (xy 351.948676 -261.107381) (xy 351.975928 -261.10692)
			(xy 352.004527 -261.107402) (xy 352.061083 -261.115945) (xy 352.115731 -261.132835) (xy 352.167244 -261.157694)
			(xy 352.214469 -261.189964) (xy 352.232231 -261.206488) (xy 364.15802 -261.206488) (xy 364.162091 -261.150866)
			(xy 364.174217 -261.096429) (xy 364.19414 -261.044338) (xy 364.221436 -260.995703) (xy 364.255522 -260.95156)
			(xy 364.295671 -260.912851) (xy 364.341029 -260.8804) (xy 364.390629 -260.854899) (xy 364.443413 -260.836892)
			(xy 364.498256 -260.826762) (xy 364.55399 -260.824725) (xy 364.609427 -260.830825) (xy 364.663384 -260.844931)
			(xy 364.714713 -260.866743) (xy 364.762319 -260.895797) (xy 364.805187 -260.931472) (xy 364.842404 -260.973009)
			(xy 364.873177 -261.019522) (xy 364.896849 -261.070019) (xy 364.912917 -261.123426) (xy 364.921037 -261.178602)
			(xy 364.921546 -261.206488) (xy 364.921037 -261.234374) (xy 364.912917 -261.28955) (xy 364.896849 -261.342957)
			(xy 364.873177 -261.393454) (xy 364.842404 -261.439967) (xy 364.805187 -261.481504) (xy 364.762319 -261.517179)
			(xy 364.714713 -261.546233) (xy 364.663384 -261.568045) (xy 364.609427 -261.582151) (xy 364.55399 -261.588251)
			(xy 364.498256 -261.586214) (xy 364.443413 -261.576084) (xy 364.390629 -261.558077) (xy 364.341029 -261.532576)
			(xy 364.295671 -261.500125) (xy 364.255522 -261.461416) (xy 364.221436 -261.417273) (xy 364.19414 -261.368638)
			(xy 364.174217 -261.316547) (xy 364.162091 -261.26211) (xy 364.15802 -261.206488) (xy 352.232231 -261.206488)
			(xy 352.256348 -261.228923) (xy 352.291941 -261.273698) (xy 352.320451 -261.323284) (xy 352.34124 -261.37657)
			(xy 352.348038 -261.404354) (xy 352.350455 -261.413351) (xy 352.360755 -261.428854) (xy 352.368104 -261.43458)
			(xy 352.42373 -261.474204) (xy 352.431597 -261.479254) (xy 352.449714 -261.483806) (xy 352.459036 -261.483094)
			(xy 352.45929 -261.483094) (xy 352.470548 -261.481798) (xy 352.49317 -261.480402) (xy 352.504502 -261.4803)
			(xy 352.531754 -261.48077) (xy 352.585702 -261.488527) (xy 352.637998 -261.503882) (xy 352.687576 -261.526524)
			(xy 352.733427 -261.555991) (xy 352.774618 -261.591683) (xy 352.81031 -261.632874) (xy 352.839777 -261.678726)
			(xy 352.862418 -261.728304) (xy 352.877774 -261.7806) (xy 352.88553 -261.834548) (xy 352.88553 -261.889052)
			(xy 352.877774 -261.943) (xy 352.862418 -261.995296) (xy 352.839777 -262.044874) (xy 352.81031 -262.090726)
			(xy 352.774618 -262.131917) (xy 352.733427 -262.167609) (xy 352.687576 -262.197076) (xy 352.637998 -262.219718)
			(xy 352.585702 -262.235073) (xy 352.531754 -262.24283) (xy 352.504502 -262.243316) (xy 352.475905 -262.242779)
			(xy 352.419353 -262.234242) (xy 352.364708 -262.217357) (xy 352.313196 -262.192505) (xy 352.265972 -262.160241)
			(xy 352.224093 -262.121289) (xy 352.188498 -262.076522) (xy 352.159985 -262.026943) (xy 352.139193 -261.973663)
			(xy 352.132392 -261.945882) (xy 352.129951 -261.936894) (xy 352.119667 -261.921386) (xy 352.112326 -261.915656)
			(xy 352.0567 -261.876032) (xy 352.048823 -261.870999) (xy 352.030714 -261.866435) (xy 352.021394 -261.867142)
			(xy 352.02114 -261.867142) (xy 352.009881 -261.868435) (xy 351.98726 -261.869833) (xy 351.975928 -261.869936)
			(xy 351.948676 -261.869419) (xy 351.894726 -261.861665) (xy 351.842428 -261.846313) (xy 351.792848 -261.823674)
			(xy 351.746995 -261.794209) (xy 351.705802 -261.758518) (xy 351.670108 -261.717327) (xy 351.64064 -261.671476)
			(xy 351.617997 -261.621898) (xy 351.60264 -261.569602) (xy 351.594883 -261.515652) (xy 346.959991 -261.515652)
			(xy 346.944727 -261.528355) (xy 346.897121 -261.557409) (xy 346.845792 -261.579221) (xy 346.791835 -261.593327)
			(xy 346.736398 -261.599427) (xy 346.680664 -261.59739) (xy 346.625821 -261.58726) (xy 346.573037 -261.569253)
			(xy 346.523437 -261.543752) (xy 346.478079 -261.511301) (xy 346.43793 -261.472592) (xy 346.403844 -261.428449)
			(xy 346.376548 -261.379814) (xy 346.356625 -261.327723) (xy 346.344499 -261.273286) (xy 346.340428 -261.217664)
			(xy 341.599731 -261.217664) (xy 341.613956 -261.267991) (xy 341.62118 -261.320126) (xy 341.621618 -261.346442)
			(xy 341.621161 -261.373694) (xy 341.613399 -261.427642) (xy 341.598039 -261.479937) (xy 341.575394 -261.529513)
			(xy 341.545924 -261.575363) (xy 341.51023 -261.616553) (xy 341.469038 -261.652244) (xy 341.423185 -261.681709)
			(xy 341.373607 -261.704351) (xy 341.321311 -261.719706) (xy 341.267362 -261.727464) (xy 341.24011 -261.72795)
			(xy 341.213796 -261.727492) (xy 341.161666 -261.720257) (xy 341.111022 -261.705938) (xy 341.062823 -261.684803)
			(xy 341.01798 -261.657255) (xy 340.977342 -261.623813) (xy 340.959186 -261.60476) (xy 340.951664 -261.597359)
			(xy 340.932385 -261.588832) (xy 340.921848 -261.58825) (xy 340.847172 -261.58825) (xy 340.836627 -261.588819)
			(xy 340.817332 -261.597328) (xy 340.809834 -261.60476) (xy 340.791715 -261.623852) (xy 340.751076 -261.657304)
			(xy 340.706228 -261.684856) (xy 340.65802 -261.705988) (xy 340.607367 -261.720298) (xy 340.555228 -261.727515)
			(xy 340.52891 -261.72795) (xy 340.501661 -261.727413) (xy 340.447717 -261.719659) (xy 340.395426 -261.704307)
			(xy 340.345852 -261.68167) (xy 340.300003 -261.652209) (xy 340.258814 -261.616523) (xy 340.223123 -261.575338)
			(xy 340.193655 -261.529494) (xy 340.171011 -261.479923) (xy 340.155653 -261.427634) (xy 340.147891 -261.373691)
			(xy 340.147402 -261.346442) (xy 333.70647 -261.346442) (xy 333.70647 -262.504682) (xy 338.447378 -262.504682)
			(xy 338.451449 -262.44906) (xy 338.463575 -262.394623) (xy 338.483498 -262.342532) (xy 338.510794 -262.293897)
			(xy 338.54488 -262.249754) (xy 338.585029 -262.211045) (xy 338.630387 -262.178594) (xy 338.679987 -262.153093)
			(xy 338.732771 -262.135086) (xy 338.787614 -262.124956) (xy 338.843348 -262.122919) (xy 338.898785 -262.129019)
			(xy 338.952742 -262.143125) (xy 339.004071 -262.164937) (xy 339.051677 -262.193991) (xy 339.053567 -262.195564)
			(xy 348.581978 -262.195564) (xy 348.586049 -262.139942) (xy 348.598175 -262.085505) (xy 348.618098 -262.033414)
			(xy 348.645394 -261.984779) (xy 348.67948 -261.940636) (xy 348.719629 -261.901927) (xy 348.764987 -261.869476)
			(xy 348.814587 -261.843975) (xy 348.867371 -261.825968) (xy 348.922214 -261.815838) (xy 348.977948 -261.813801)
			(xy 349.033385 -261.819901) (xy 349.087342 -261.834007) (xy 349.138671 -261.855819) (xy 349.186277 -261.884873)
			(xy 349.229145 -261.920548) (xy 349.266362 -261.962085) (xy 349.297135 -262.008598) (xy 349.320807 -262.059095)
			(xy 349.336875 -262.112502) (xy 349.344995 -262.167678) (xy 349.345504 -262.195564) (xy 349.344995 -262.22345)
			(xy 349.336875 -262.278626) (xy 349.320807 -262.332033) (xy 349.297135 -262.38253) (xy 349.266362 -262.429043)
			(xy 349.229145 -262.47058) (xy 349.186277 -262.506255) (xy 349.138671 -262.535309) (xy 349.087342 -262.557121)
			(xy 349.033385 -262.571227) (xy 348.977948 -262.577327) (xy 348.922214 -262.57529) (xy 348.867371 -262.56516)
			(xy 348.814587 -262.547153) (xy 348.764987 -262.521652) (xy 348.719629 -262.489201) (xy 348.67948 -262.450492)
			(xy 348.645394 -262.406349) (xy 348.618098 -262.357714) (xy 348.598175 -262.305623) (xy 348.586049 -262.251186)
			(xy 348.581978 -262.195564) (xy 339.053567 -262.195564) (xy 339.094545 -262.229666) (xy 339.131762 -262.271203)
			(xy 339.162535 -262.317716) (xy 339.186207 -262.368213) (xy 339.202275 -262.42162) (xy 339.210395 -262.476796)
			(xy 339.210904 -262.504682) (xy 339.210395 -262.532568) (xy 339.202275 -262.587744) (xy 339.186207 -262.641151)
			(xy 339.162535 -262.691648) (xy 339.154651 -262.703564) (xy 344.363292 -262.703564) (xy 344.367363 -262.647942)
			(xy 344.379489 -262.593505) (xy 344.399412 -262.541414) (xy 344.426708 -262.492779) (xy 344.460794 -262.448636)
			(xy 344.500943 -262.409927) (xy 344.546301 -262.377476) (xy 344.595901 -262.351975) (xy 344.648685 -262.333968)
			(xy 344.703528 -262.323838) (xy 344.759262 -262.321801) (xy 344.814699 -262.327901) (xy 344.868656 -262.342007)
			(xy 344.919985 -262.363819) (xy 344.967591 -262.392873) (xy 345.010459 -262.428548) (xy 345.047676 -262.470085)
			(xy 345.078449 -262.516598) (xy 345.102121 -262.567095) (xy 345.106269 -262.580882) (xy 351.353118 -262.580882)
			(xy 351.357189 -262.52526) (xy 351.369315 -262.470823) (xy 351.389238 -262.418732) (xy 351.416534 -262.370097)
			(xy 351.45062 -262.325954) (xy 351.490769 -262.287245) (xy 351.536127 -262.254794) (xy 351.585727 -262.229293)
			(xy 351.638511 -262.211286) (xy 351.693354 -262.201156) (xy 351.749088 -262.199119) (xy 351.804525 -262.205219)
			(xy 351.858482 -262.219325) (xy 351.909811 -262.241137) (xy 351.957417 -262.270191) (xy 352.000285 -262.305866)
			(xy 352.037502 -262.347403) (xy 352.068275 -262.393916) (xy 352.091947 -262.444413) (xy 352.108015 -262.49782)
			(xy 352.116135 -262.552996) (xy 352.116644 -262.580882) (xy 352.116135 -262.608768) (xy 352.108015 -262.663944)
			(xy 352.091947 -262.717351) (xy 352.068275 -262.767848) (xy 352.037502 -262.814361) (xy 352.000285 -262.855898)
			(xy 351.957417 -262.891573) (xy 351.909811 -262.920627) (xy 351.858482 -262.942439) (xy 351.804525 -262.956545)
			(xy 351.749088 -262.962645) (xy 351.693354 -262.960608) (xy 351.638511 -262.950478) (xy 351.585727 -262.932471)
			(xy 351.536127 -262.90697) (xy 351.490769 -262.874519) (xy 351.45062 -262.83581) (xy 351.416534 -262.791667)
			(xy 351.389238 -262.743032) (xy 351.369315 -262.690941) (xy 351.357189 -262.636504) (xy 351.353118 -262.580882)
			(xy 345.106269 -262.580882) (xy 345.118189 -262.620502) (xy 345.126309 -262.675678) (xy 345.126818 -262.703564)
			(xy 345.126309 -262.73145) (xy 345.118189 -262.786626) (xy 345.102121 -262.840033) (xy 345.078449 -262.89053)
			(xy 345.047676 -262.937043) (xy 345.010459 -262.97858) (xy 344.967591 -263.014255) (xy 344.919985 -263.043309)
			(xy 344.868656 -263.065121) (xy 344.842863 -263.071864) (xy 348.581978 -263.071864) (xy 348.586049 -263.016242)
			(xy 348.598175 -262.961805) (xy 348.618098 -262.909714) (xy 348.645394 -262.861079) (xy 348.67948 -262.816936)
			(xy 348.719629 -262.778227) (xy 348.764987 -262.745776) (xy 348.814587 -262.720275) (xy 348.867371 -262.702268)
			(xy 348.922214 -262.692138) (xy 348.977948 -262.690101) (xy 349.033385 -262.696201) (xy 349.087342 -262.710307)
			(xy 349.138671 -262.732119) (xy 349.186277 -262.761173) (xy 349.229145 -262.796848) (xy 349.266362 -262.838385)
			(xy 349.297135 -262.884898) (xy 349.320807 -262.935395) (xy 349.336875 -262.988802) (xy 349.344995 -263.043978)
			(xy 349.345504 -263.071864) (xy 349.344995 -263.09975) (xy 349.336875 -263.154926) (xy 349.328317 -263.18337)
			(xy 355.16896 -263.18337) (xy 355.173031 -263.127748) (xy 355.185157 -263.073311) (xy 355.20508 -263.02122)
			(xy 355.232376 -262.972585) (xy 355.266462 -262.928442) (xy 355.306611 -262.889733) (xy 355.351969 -262.857282)
			(xy 355.401569 -262.831781) (xy 355.454353 -262.813774) (xy 355.509196 -262.803644) (xy 355.56493 -262.801607)
			(xy 355.620367 -262.807707) (xy 355.674324 -262.821813) (xy 355.725653 -262.843625) (xy 355.773259 -262.872679)
			(xy 355.816127 -262.908354) (xy 355.853344 -262.949891) (xy 355.884117 -262.996404) (xy 355.907789 -263.046901)
			(xy 355.923857 -263.100308) (xy 355.931977 -263.155484) (xy 355.932486 -263.18337) (xy 355.931977 -263.211256)
			(xy 355.923857 -263.266432) (xy 355.907789 -263.319839) (xy 355.884117 -263.370336) (xy 355.853344 -263.416849)
			(xy 355.816127 -263.458386) (xy 355.773259 -263.494061) (xy 355.725653 -263.523115) (xy 355.674324 -263.544927)
			(xy 355.620367 -263.559033) (xy 355.56493 -263.565133) (xy 355.509196 -263.563096) (xy 355.454353 -263.552966)
			(xy 355.401569 -263.534959) (xy 355.351969 -263.509458) (xy 355.306611 -263.477007) (xy 355.266462 -263.438298)
			(xy 355.232376 -263.394155) (xy 355.20508 -263.34552) (xy 355.185157 -263.293429) (xy 355.173031 -263.238992)
			(xy 355.16896 -263.18337) (xy 349.328317 -263.18337) (xy 349.320807 -263.208333) (xy 349.297135 -263.25883)
			(xy 349.266362 -263.305343) (xy 349.229145 -263.34688) (xy 349.186277 -263.382555) (xy 349.138671 -263.411609)
			(xy 349.087342 -263.433421) (xy 349.033385 -263.447527) (xy 348.977948 -263.453627) (xy 348.922214 -263.45159)
			(xy 348.867371 -263.44146) (xy 348.814587 -263.423453) (xy 348.764987 -263.397952) (xy 348.719629 -263.365501)
			(xy 348.67948 -263.326792) (xy 348.645394 -263.282649) (xy 348.618098 -263.234014) (xy 348.598175 -263.181923)
			(xy 348.586049 -263.127486) (xy 348.581978 -263.071864) (xy 344.842863 -263.071864) (xy 344.814699 -263.079227)
			(xy 344.759262 -263.085327) (xy 344.703528 -263.08329) (xy 344.648685 -263.07316) (xy 344.595901 -263.055153)
			(xy 344.546301 -263.029652) (xy 344.500943 -262.997201) (xy 344.460794 -262.958492) (xy 344.426708 -262.914349)
			(xy 344.399412 -262.865714) (xy 344.379489 -262.813623) (xy 344.367363 -262.759186) (xy 344.363292 -262.703564)
			(xy 339.154651 -262.703564) (xy 339.131762 -262.738161) (xy 339.094545 -262.779698) (xy 339.051677 -262.815373)
			(xy 339.004071 -262.844427) (xy 338.952742 -262.866239) (xy 338.898785 -262.880345) (xy 338.843348 -262.886445)
			(xy 338.787614 -262.884408) (xy 338.732771 -262.874278) (xy 338.679987 -262.856271) (xy 338.630387 -262.83077)
			(xy 338.585029 -262.798319) (xy 338.54488 -262.75961) (xy 338.510794 -262.715467) (xy 338.483498 -262.666832)
			(xy 338.463575 -262.614741) (xy 338.451449 -262.560304) (xy 338.447378 -262.504682) (xy 333.70647 -262.504682)
			(xy 333.70647 -262.947912) (xy 333.708248 -262.961374) (xy 333.710788 -262.968486) (xy 333.723234 -262.996426)
			(xy 333.7306 -263.003284) (xy 333.749317 -263.021398) (xy 333.782162 -263.061822) (xy 333.809201 -263.106338)
			(xy 333.829933 -263.15412) (xy 333.843971 -263.204278) (xy 333.851054 -263.255879) (xy 333.851504 -263.281922)
			(xy 333.851504 -263.285224) (xy 333.850996 -263.296654) (xy 333.850996 -263.296908) (xy 333.850234 -263.308846)
			(xy 333.849472 -263.319514) (xy 333.853028 -263.32942) (xy 333.854883 -263.334248) (xy 333.860264 -263.343077)
			(xy 333.863696 -263.346946) (xy 333.914496 -263.401556) (xy 333.920911 -263.407948) (xy 333.937047 -263.416141)
			(xy 333.945992 -263.417558) (xy 333.951834 -263.417812) (xy 334.09255 -263.417812) (xy 334.097122 -263.41705)
			(xy 334.122935 -263.412672) (xy 334.175083 -263.40797) (xy 334.201262 -263.407652) (xy 334.202024 -263.407652)
			(xy 334.23565 -263.408122) (xy 334.302459 -263.415823) (xy 334.367948 -263.43112) (xy 334.431255 -263.453814)
			(xy 334.491548 -263.483606) (xy 334.548035 -263.520103) (xy 334.599973 -263.562826) (xy 334.646678 -263.611214)
			(xy 334.687538 -263.66463) (xy 334.722015 -263.722372) (xy 334.749656 -263.783681) (xy 334.760316 -263.815576)
			(xy 334.760316 -263.81583) (xy 334.762358 -263.821494) (xy 334.768638 -263.831764) (xy 334.772762 -263.83615)
			(xy 334.913986 -263.977374) (xy 334.921273 -263.984063) (xy 334.939469 -263.991768) (xy 334.959228 -263.991986)
			(xy 334.968596 -263.988804) (xy 334.983113 -263.983235) (xy 335.012869 -263.974211) (xy 335.028032 -263.97077)
			(xy 335.039828 -263.967536) (xy 335.058682 -263.952016) (xy 335.0641 -263.941052) (xy 335.101692 -263.853676)
			(xy 335.099914 -263.829292) (xy 335.09331 -263.818624) (xy 335.080196 -263.796153) (xy 335.059503 -263.748417)
			(xy 335.045479 -263.698314) (xy 335.038384 -263.646772) (xy 335.037938 -263.620758) (xy 335.037938 -263.620504)
			(xy 335.038424 -263.593253) (xy 335.04618 -263.539305) (xy 335.061535 -263.48701) (xy 335.084177 -263.437433)
			(xy 335.113643 -263.391583) (xy 335.149334 -263.350392) (xy 335.190525 -263.314701) (xy 335.236375 -263.285235)
			(xy 335.285952 -263.262593) (xy 335.338247 -263.247238) (xy 335.392195 -263.239482) (xy 335.446697 -263.239482)
			(xy 335.500645 -263.247238) (xy 335.55294 -263.262593) (xy 335.602517 -263.285235) (xy 335.648367 -263.314701)
			(xy 335.689558 -263.350392) (xy 335.725249 -263.391583) (xy 335.754715 -263.437433) (xy 335.777357 -263.48701)
			(xy 335.792712 -263.539305) (xy 335.800468 -263.593253) (xy 335.800954 -263.620504) (xy 335.800429 -263.649291)
			(xy 335.791778 -263.706212) (xy 335.774674 -263.761187) (xy 335.749503 -263.812968) (xy 335.716839 -263.86038)
			(xy 335.677422 -263.902346) (xy 335.632147 -263.937913) (xy 335.582042 -263.966274) (xy 335.528245 -263.986785)
			(xy 335.500218 -263.993376) (xy 335.488433 -263.996622) (xy 335.469609 -264.012155) (xy 335.46415 -264.023094)
			(xy 335.431384 -264.099294) (xy 335.427287 -264.110696) (xy 335.428995 -264.134829) (xy 335.434686 -264.145522)
			(xy 335.447858 -264.168008) (xy 335.468649 -264.215793) (xy 335.48274 -264.265964) (xy 335.489119 -264.312146)
			(xy 335.602324 -264.312146) (xy 335.606395 -264.256524) (xy 335.618521 -264.202087) (xy 335.638444 -264.149996)
			(xy 335.66574 -264.101361) (xy 335.699826 -264.057218) (xy 335.739975 -264.018509) (xy 335.785333 -263.986058)
			(xy 335.834933 -263.960557) (xy 335.887717 -263.94255) (xy 335.94256 -263.93242) (xy 335.998294 -263.930383)
			(xy 336.053731 -263.936483) (xy 336.107688 -263.950589) (xy 336.159017 -263.972401) (xy 336.206623 -264.001455)
			(xy 336.249491 -264.03713) (xy 336.286708 -264.078667) (xy 336.317481 -264.12518) (xy 336.319516 -264.12952)
			(xy 346.649292 -264.12952) (xy 346.653363 -264.073898) (xy 346.665489 -264.019461) (xy 346.685412 -263.96737)
			(xy 346.712708 -263.918735) (xy 346.746794 -263.874592) (xy 346.786943 -263.835883) (xy 346.832301 -263.803432)
			(xy 346.881901 -263.777931) (xy 346.934685 -263.759924) (xy 346.989528 -263.749794) (xy 347.045262 -263.747757)
			(xy 347.100699 -263.753857) (xy 347.154656 -263.767963) (xy 347.200951 -263.787636) (xy 349.771968 -263.787636)
			(xy 349.776039 -263.732014) (xy 349.788165 -263.677577) (xy 349.808088 -263.625486) (xy 349.835384 -263.576851)
			(xy 349.86947 -263.532708) (xy 349.909619 -263.493999) (xy 349.954977 -263.461548) (xy 350.004577 -263.436047)
			(xy 350.057361 -263.41804) (xy 350.112204 -263.40791) (xy 350.167938 -263.405873) (xy 350.223375 -263.411973)
			(xy 350.277332 -263.426079) (xy 350.328661 -263.447891) (xy 350.376267 -263.476945) (xy 350.419135 -263.51262)
			(xy 350.456352 -263.554157) (xy 350.487125 -263.60067) (xy 350.510797 -263.651167) (xy 350.526865 -263.704574)
			(xy 350.534985 -263.75975) (xy 350.535494 -263.787636) (xy 350.534985 -263.815522) (xy 350.534192 -263.82091)
			(xy 351.643948 -263.82091) (xy 351.648019 -263.765288) (xy 351.660145 -263.710851) (xy 351.680068 -263.65876)
			(xy 351.707364 -263.610125) (xy 351.74145 -263.565982) (xy 351.781599 -263.527273) (xy 351.826957 -263.494822)
			(xy 351.876557 -263.469321) (xy 351.929341 -263.451314) (xy 351.984184 -263.441184) (xy 352.039918 -263.439147)
			(xy 352.095355 -263.445247) (xy 352.149312 -263.459353) (xy 352.200641 -263.481165) (xy 352.248247 -263.510219)
			(xy 352.291115 -263.545894) (xy 352.328332 -263.587431) (xy 352.359105 -263.633944) (xy 352.382777 -263.684441)
			(xy 352.398845 -263.737848) (xy 352.406965 -263.793024) (xy 352.407474 -263.82091) (xy 352.406965 -263.848796)
			(xy 352.398845 -263.903972) (xy 352.382777 -263.957379) (xy 352.359105 -264.007876) (xy 352.328332 -264.054389)
			(xy 352.291115 -264.095926) (xy 352.281574 -264.103866) (xy 355.18039 -264.103866) (xy 355.184461 -264.048244)
			(xy 355.196587 -263.993807) (xy 355.21651 -263.941716) (xy 355.243806 -263.893081) (xy 355.277892 -263.848938)
			(xy 355.318041 -263.810229) (xy 355.363399 -263.777778) (xy 355.412999 -263.752277) (xy 355.465783 -263.73427)
			(xy 355.520626 -263.72414) (xy 355.57636 -263.722103) (xy 355.631797 -263.728203) (xy 355.685754 -263.742309)
			(xy 355.737083 -263.764121) (xy 355.784689 -263.793175) (xy 355.827557 -263.82885) (xy 355.864774 -263.870387)
			(xy 355.895547 -263.9169) (xy 355.919219 -263.967397) (xy 355.935287 -264.020804) (xy 355.943407 -264.07598)
			(xy 355.943916 -264.103866) (xy 355.943407 -264.131752) (xy 355.935287 -264.186928) (xy 355.919219 -264.240335)
			(xy 355.895547 -264.290832) (xy 355.864774 -264.337345) (xy 355.827557 -264.378882) (xy 355.784689 -264.414557)
			(xy 355.737083 -264.443611) (xy 355.685754 -264.465423) (xy 355.631797 -264.479529) (xy 355.57636 -264.485629)
			(xy 355.520626 -264.483592) (xy 355.465783 -264.473462) (xy 355.412999 -264.455455) (xy 355.363399 -264.429954)
			(xy 355.318041 -264.397503) (xy 355.277892 -264.358794) (xy 355.243806 -264.314651) (xy 355.21651 -264.266016)
			(xy 355.196587 -264.213925) (xy 355.184461 -264.159488) (xy 355.18039 -264.103866) (xy 352.281574 -264.103866)
			(xy 352.248247 -264.131601) (xy 352.200641 -264.160655) (xy 352.149312 -264.182467) (xy 352.095355 -264.196573)
			(xy 352.039918 -264.202673) (xy 351.984184 -264.200636) (xy 351.929341 -264.190506) (xy 351.876557 -264.172499)
			(xy 351.826957 -264.146998) (xy 351.781599 -264.114547) (xy 351.74145 -264.075838) (xy 351.707364 -264.031695)
			(xy 351.680068 -263.98306) (xy 351.660145 -263.930969) (xy 351.648019 -263.876532) (xy 351.643948 -263.82091)
			(xy 350.534192 -263.82091) (xy 350.526865 -263.870698) (xy 350.510797 -263.924105) (xy 350.487125 -263.974602)
			(xy 350.456352 -264.021115) (xy 350.419135 -264.062652) (xy 350.376267 -264.098327) (xy 350.328661 -264.127381)
			(xy 350.277332 -264.149193) (xy 350.223375 -264.163299) (xy 350.167938 -264.169399) (xy 350.112204 -264.167362)
			(xy 350.057361 -264.157232) (xy 350.004577 -264.139225) (xy 349.954977 -264.113724) (xy 349.909619 -264.081273)
			(xy 349.86947 -264.042564) (xy 349.835384 -263.998421) (xy 349.808088 -263.949786) (xy 349.788165 -263.897695)
			(xy 349.776039 -263.843258) (xy 349.771968 -263.787636) (xy 347.200951 -263.787636) (xy 347.205985 -263.789775)
			(xy 347.253591 -263.818829) (xy 347.296459 -263.854504) (xy 347.333676 -263.896041) (xy 347.364449 -263.942554)
			(xy 347.388121 -263.993051) (xy 347.404189 -264.046458) (xy 347.412309 -264.101634) (xy 347.412818 -264.12952)
			(xy 347.412309 -264.157406) (xy 347.404189 -264.212582) (xy 347.388121 -264.265989) (xy 347.364449 -264.316486)
			(xy 347.333676 -264.362999) (xy 347.296459 -264.404536) (xy 347.253591 -264.440211) (xy 347.205985 -264.469265)
			(xy 347.154656 -264.491077) (xy 347.100699 -264.505183) (xy 347.045262 -264.511283) (xy 346.989528 -264.509246)
			(xy 346.934685 -264.499116) (xy 346.881901 -264.481109) (xy 346.832301 -264.455608) (xy 346.786943 -264.423157)
			(xy 346.746794 -264.384448) (xy 346.712708 -264.340305) (xy 346.685412 -264.29167) (xy 346.665489 -264.239579)
			(xy 346.653363 -264.185142) (xy 346.649292 -264.12952) (xy 336.319516 -264.12952) (xy 336.341153 -264.175677)
			(xy 336.357221 -264.229084) (xy 336.365341 -264.28426) (xy 336.36585 -264.312146) (xy 336.365341 -264.340032)
			(xy 336.357221 -264.395208) (xy 336.341153 -264.448615) (xy 336.317481 -264.499112) (xy 336.286708 -264.545625)
			(xy 336.249491 -264.587162) (xy 336.206623 -264.622837) (xy 336.159017 -264.651891) (xy 336.107688 -264.673703)
			(xy 336.053731 -264.687809) (xy 335.998294 -264.693909) (xy 335.94256 -264.691872) (xy 335.887717 -264.681742)
			(xy 335.834933 -264.663735) (xy 335.785333 -264.638234) (xy 335.739975 -264.605783) (xy 335.699826 -264.567074)
			(xy 335.66574 -264.522931) (xy 335.638444 -264.474296) (xy 335.618521 -264.422205) (xy 335.606395 -264.367768)
			(xy 335.602324 -264.312146) (xy 335.489119 -264.312146) (xy 335.48987 -264.317586) (xy 335.490312 -264.343642)
			(xy 335.489757 -264.373173) (xy 335.480653 -264.431528) (xy 335.46267 -264.487785) (xy 335.436236 -264.540601)
			(xy 335.401983 -264.588715) (xy 335.360727 -264.630979) (xy 335.313454 -264.666384) (xy 335.28762 -264.6807)
			(xy 335.275174 -264.687304) (xy 335.260696 -264.71118) (xy 335.260696 -264.93597) (xy 352.61753 -264.93597)
			(xy 352.621601 -264.880348) (xy 352.633727 -264.825911) (xy 352.65365 -264.77382) (xy 352.680946 -264.725185)
			(xy 352.715032 -264.681042) (xy 352.755181 -264.642333) (xy 352.800539 -264.609882) (xy 352.850139 -264.584381)
			(xy 352.902923 -264.566374) (xy 352.957766 -264.556244) (xy 353.0135 -264.554207) (xy 353.068937 -264.560307)
			(xy 353.122894 -264.574413) (xy 353.174223 -264.596225) (xy 353.221829 -264.625279) (xy 353.264697 -264.660954)
			(xy 353.301914 -264.702491) (xy 353.332687 -264.749004) (xy 353.356359 -264.799501) (xy 353.372427 -264.852908)
			(xy 353.380547 -264.908084) (xy 353.381056 -264.93597) (xy 353.380547 -264.963856) (xy 353.372427 -265.019032)
			(xy 353.356359 -265.072439) (xy 353.332687 -265.122936) (xy 353.301914 -265.169449) (xy 353.264697 -265.210986)
			(xy 353.221829 -265.246661) (xy 353.174223 -265.275715) (xy 353.122894 -265.297527) (xy 353.068937 -265.311633)
			(xy 353.0135 -265.317733) (xy 352.957766 -265.315696) (xy 352.902923 -265.305566) (xy 352.850139 -265.287559)
			(xy 352.800539 -265.262058) (xy 352.755181 -265.229607) (xy 352.715032 -265.190898) (xy 352.680946 -265.146755)
			(xy 352.65365 -265.09812) (xy 352.633727 -265.046029) (xy 352.621601 -264.991592) (xy 352.61753 -264.93597)
			(xy 335.260696 -264.93597) (xy 335.260696 -265.241278) (xy 335.260237 -265.274132) (xy 335.252883 -265.339427)
			(xy 335.238264 -265.403489) (xy 335.216565 -265.46551) (xy 335.188058 -265.524713) (xy 335.153102 -265.580351)
			(xy 335.112137 -265.631726) (xy 335.089246 -265.655298) (xy 334.91043 -265.834114) (xy 351.44659 -265.834114)
			(xy 351.450661 -265.778492) (xy 351.462787 -265.724055) (xy 351.48271 -265.671964) (xy 351.510006 -265.623329)
			(xy 351.544092 -265.579186) (xy 351.584241 -265.540477) (xy 351.629599 -265.508026) (xy 351.679199 -265.482525)
			(xy 351.731983 -265.464518) (xy 351.786826 -265.454388) (xy 351.84256 -265.452351) (xy 351.897997 -265.458451)
			(xy 351.951954 -265.472557) (xy 352.003283 -265.494369) (xy 352.050889 -265.523423) (xy 352.093757 -265.559098)
			(xy 352.130974 -265.600635) (xy 352.161747 -265.647148) (xy 352.185419 -265.697645) (xy 352.201487 -265.751052)
			(xy 352.209607 -265.806228) (xy 352.210116 -265.834114) (xy 352.209607 -265.862) (xy 352.201487 -265.917176)
			(xy 352.185419 -265.970583) (xy 352.161747 -266.02108) (xy 352.130974 -266.067593) (xy 352.093757 -266.10913)
			(xy 352.050889 -266.144805) (xy 352.003283 -266.173859) (xy 351.951954 -266.195671) (xy 351.897997 -266.209777)
			(xy 351.84256 -266.215877) (xy 351.786826 -266.21384) (xy 351.731983 -266.20371) (xy 351.679199 -266.185703)
			(xy 351.629599 -266.160202) (xy 351.584241 -266.127751) (xy 351.544092 -266.089042) (xy 351.510006 -266.044899)
			(xy 351.48271 -265.996264) (xy 351.462787 -265.944173) (xy 351.450661 -265.889736) (xy 351.44659 -265.834114)
			(xy 334.91043 -265.834114) (xy 334.843374 -265.90117) (xy 334.81981 -265.924068) (xy 334.768426 -265.965022)
			(xy 334.712784 -265.999971) (xy 334.653581 -266.028475) (xy 334.59156 -266.050176) (xy 334.527501 -266.064803)
			(xy 334.462208 -266.072172) (xy 334.429354 -266.07262) (xy 333.289148 -266.07262) (xy 333.256293 -266.072162)
			(xy 333.190996 -266.064811) (xy 333.126933 -266.050195) (xy 333.064909 -266.028499) (xy 333.005704 -265.999995)
			(xy 332.950062 -265.965041) (xy 332.898684 -265.924078) (xy 332.875128 -265.90117) (xy 332.799944 -265.825986)
			(xy 332.792547 -265.819139) (xy 332.773947 -265.811412) (xy 332.763876 -265.811) (xy 332.318614 -265.811)
			(xy 332.308551 -265.811439) (xy 332.289969 -265.819175) (xy 332.282546 -265.825986) (xy 331.804518 -266.304014)
			(xy 331.797672 -266.311413) (xy 331.78994 -266.330011) (xy 331.789532 -266.340082) (xy 331.789532 -269.417038)
			(xy 334.700626 -269.417038) (xy 334.701132 -269.388299) (xy 334.709762 -269.331471) (xy 334.726817 -269.276581)
			(xy 334.751912 -269.22487) (xy 334.784479 -269.177507) (xy 334.80375 -269.15618) (xy 334.810354 -269.149322)
			(xy 334.817466 -269.131288) (xy 334.817466 -269.042388) (xy 334.810354 -269.024354) (xy 334.80375 -269.017496)
			(xy 334.784499 -268.996152) (xy 334.75193 -268.948795) (xy 334.726833 -268.897087) (xy 334.709778 -268.8422)
			(xy 334.70115 -268.785376) (xy 334.700626 -268.756638) (xy 334.701091 -268.729385) (xy 334.708843 -268.675432)
			(xy 334.724196 -268.623132) (xy 334.746837 -268.57355) (xy 334.776304 -268.527695) (xy 334.811998 -268.486501)
			(xy 334.853192 -268.450807) (xy 334.899046 -268.421339) (xy 334.948628 -268.398698) (xy 335.000928 -268.383344)
			(xy 335.054881 -268.375591) (xy 335.082134 -268.37513) (xy 335.109505 -268.375569) (xy 335.163686 -268.383392)
			(xy 335.21619 -268.398887) (xy 335.265936 -268.421735) (xy 335.311901 -268.451466) (xy 335.332832 -268.46911)
			(xy 335.333086 -268.469364) (xy 335.340167 -268.474958) (xy 335.357088 -268.481199) (xy 335.366106 -268.481556)
			(xy 335.433162 -268.481556) (xy 335.442178 -268.48119) (xy 335.459096 -268.47495) (xy 335.466182 -268.469364)
			(xy 335.466182 -268.46911) (xy 335.466436 -268.46911) (xy 335.487369 -268.451469) (xy 335.533337 -268.421745)
			(xy 335.583083 -268.398899) (xy 335.635585 -268.383403) (xy 335.689763 -268.375574) (xy 335.744505 -268.375574)
			(xy 335.798683 -268.383403) (xy 335.851185 -268.398899) (xy 335.900931 -268.421745) (xy 335.946899 -268.451469)
			(xy 335.967832 -268.46911) (xy 335.968086 -268.469364) (xy 335.975167 -268.474958) (xy 335.992088 -268.481199)
			(xy 336.001106 -268.481556) (xy 336.068162 -268.481556) (xy 336.077178 -268.48119) (xy 336.094096 -268.47495)
			(xy 336.101182 -268.469364) (xy 336.101182 -268.46911) (xy 336.101436 -268.46911) (xy 336.122369 -268.451469)
			(xy 336.168337 -268.421745) (xy 336.218083 -268.398899) (xy 336.270585 -268.383403) (xy 336.324763 -268.375574)
			(xy 336.379505 -268.375574) (xy 336.433683 -268.383403) (xy 336.486185 -268.398899) (xy 336.535931 -268.421745)
			(xy 336.581899 -268.451469) (xy 336.602832 -268.46911) (xy 336.603086 -268.469364) (xy 336.610167 -268.474958)
			(xy 336.627088 -268.481199) (xy 336.636106 -268.481556) (xy 336.703162 -268.481556) (xy 336.712178 -268.48119)
			(xy 336.729096 -268.47495) (xy 336.736182 -268.469364) (xy 336.736182 -268.46911) (xy 336.736436 -268.46911)
			(xy 336.757369 -268.451469) (xy 336.803337 -268.421745) (xy 336.853083 -268.398899) (xy 336.905585 -268.383403)
			(xy 336.959763 -268.375574) (xy 337.014505 -268.375574) (xy 337.068683 -268.383403) (xy 337.121185 -268.398899)
			(xy 337.170931 -268.421745) (xy 337.216899 -268.451469) (xy 337.237832 -268.46911) (xy 337.238086 -268.469364)
			(xy 337.245167 -268.474958) (xy 337.262088 -268.481199) (xy 337.271106 -268.481556) (xy 337.338162 -268.481556)
			(xy 337.347178 -268.48119) (xy 337.364096 -268.47495) (xy 337.371182 -268.469364) (xy 337.371182 -268.46911)
			(xy 337.371436 -268.46911) (xy 337.392383 -268.451489) (xy 337.438351 -268.421774) (xy 337.488095 -268.398935)
			(xy 337.540593 -268.383439) (xy 337.594766 -268.375606) (xy 337.622134 -268.37513) (xy 337.649389 -268.375523)
			(xy 337.703345 -268.383286) (xy 337.755646 -268.398648) (xy 337.805229 -268.421297) (xy 337.851084 -268.450773)
			(xy 337.892277 -268.486474) (xy 337.927971 -268.527674) (xy 337.957437 -268.573534) (xy 337.980077 -268.623121)
			(xy 337.995429 -268.675426) (xy 338.003182 -268.729382) (xy 338.003642 -268.756638) (xy 338.00313 -268.785377)
			(xy 337.994503 -268.842205) (xy 337.977449 -268.897095) (xy 337.952356 -268.948807) (xy 337.919789 -268.996169)
			(xy 337.900518 -269.017496) (xy 337.893914 -269.024354) (xy 337.886802 -269.042388) (xy 337.886802 -269.131288)
			(xy 337.893914 -269.149322) (xy 337.900518 -269.15618) (xy 337.919799 -269.177498) (xy 337.952366 -269.224862)
			(xy 337.977457 -269.276575) (xy 337.994505 -269.331469) (xy 338.003124 -269.388298) (xy 338.003642 -269.417038)
			(xy 357.085646 -269.417038) (xy 357.086146 -269.388298) (xy 357.094777 -269.331471) (xy 357.111833 -269.27658)
			(xy 357.13693 -269.224869) (xy 357.169498 -269.177507) (xy 357.18877 -269.15618) (xy 357.195374 -269.149322)
			(xy 357.202486 -269.131288) (xy 357.202486 -269.042388) (xy 357.195374 -269.024354) (xy 357.18877 -269.017496)
			(xy 357.169523 -268.996149) (xy 357.136952 -268.948793) (xy 357.111854 -268.897086) (xy 357.094798 -268.8422)
			(xy 357.08617 -268.785376) (xy 357.085646 -268.756638) (xy 357.086213 -268.72939) (xy 357.093964 -268.675447)
			(xy 357.109312 -268.623157) (xy 357.131945 -268.573583) (xy 357.161403 -268.527735) (xy 357.197086 -268.486545)
			(xy 357.238267 -268.450853) (xy 357.284109 -268.421385) (xy 357.333678 -268.398741) (xy 357.385965 -268.383381)
			(xy 357.439906 -268.375619) (xy 357.467154 -268.37513) (xy 357.494524 -268.375616) (xy 357.548702 -268.383428)
			(xy 357.601205 -268.398912) (xy 357.650953 -268.421749) (xy 357.69692 -268.45147) (xy 357.717852 -268.46911)
			(xy 357.718106 -268.469364) (xy 357.725181 -268.474967) (xy 357.742107 -268.481202) (xy 357.751126 -268.481556)
			(xy 357.818182 -268.481556) (xy 357.827199 -268.4812) (xy 357.844117 -268.474953) (xy 357.851202 -268.469364)
			(xy 357.851202 -268.46911) (xy 357.851456 -268.46911) (xy 357.872389 -268.451469) (xy 357.918357 -268.421745)
			(xy 357.968103 -268.398899) (xy 358.020605 -268.383403) (xy 358.074783 -268.375574) (xy 358.129525 -268.375574)
			(xy 358.183703 -268.383403) (xy 358.236205 -268.398899) (xy 358.285951 -268.421745) (xy 358.331919 -268.451469)
			(xy 358.352852 -268.46911) (xy 358.353106 -268.469364) (xy 358.360181 -268.474967) (xy 358.377107 -268.481202)
			(xy 358.386126 -268.481556) (xy 358.453182 -268.481556) (xy 358.462199 -268.4812) (xy 358.479117 -268.474953)
			(xy 358.486202 -268.469364) (xy 358.486202 -268.46911) (xy 358.486456 -268.46911) (xy 358.507389 -268.451469)
			(xy 358.553357 -268.421745) (xy 358.603103 -268.398899) (xy 358.655605 -268.383403) (xy 358.709783 -268.375574)
			(xy 358.764525 -268.375574) (xy 358.818703 -268.383403) (xy 358.871205 -268.398899) (xy 358.920951 -268.421745)
			(xy 358.966919 -268.451469) (xy 358.987852 -268.46911) (xy 358.988106 -268.469364) (xy 358.995181 -268.474967)
			(xy 359.012107 -268.481202) (xy 359.021126 -268.481556) (xy 359.088182 -268.481556) (xy 359.097199 -268.4812)
			(xy 359.114117 -268.474953) (xy 359.121202 -268.469364) (xy 359.121202 -268.46911) (xy 359.121456 -268.46911)
			(xy 359.142389 -268.451469) (xy 359.188357 -268.421745) (xy 359.238103 -268.398899) (xy 359.290605 -268.383403)
			(xy 359.344783 -268.375574) (xy 359.399525 -268.375574) (xy 359.453703 -268.383403) (xy 359.506205 -268.398899)
			(xy 359.555951 -268.421745) (xy 359.601919 -268.451469) (xy 359.622852 -268.46911) (xy 359.623106 -268.469364)
			(xy 359.630181 -268.474967) (xy 359.647107 -268.481202) (xy 359.656126 -268.481556) (xy 359.723182 -268.481556)
			(xy 359.732199 -268.4812) (xy 359.749117 -268.474953) (xy 359.756202 -268.469364) (xy 359.756202 -268.46911)
			(xy 359.756456 -268.46911) (xy 359.777395 -268.45148) (xy 359.823366 -268.421766) (xy 359.873112 -268.398928)
			(xy 359.925611 -268.383435) (xy 359.979785 -268.375605) (xy 360.007154 -268.37513) (xy 360.034407 -268.375598)
			(xy 360.08836 -268.38335) (xy 360.14066 -268.398702) (xy 360.190243 -268.421342) (xy 360.236098 -268.450809)
			(xy 360.277292 -268.486502) (xy 360.312987 -268.527696) (xy 360.342454 -268.57355) (xy 360.365095 -268.623132)
			(xy 360.380448 -268.675432) (xy 360.388201 -268.729385) (xy 360.388662 -268.756638) (xy 360.388145 -268.785377)
			(xy 360.379518 -268.842204) (xy 360.362466 -268.897094) (xy 360.337373 -268.948806) (xy 360.304808 -268.996169)
			(xy 360.285538 -269.017496) (xy 360.278934 -269.024354) (xy 360.271822 -269.042388) (xy 360.271822 -269.131288)
			(xy 360.278934 -269.149322) (xy 360.285538 -269.15618) (xy 360.304823 -269.177495) (xy 360.337388 -269.22486)
			(xy 360.362478 -269.276574) (xy 360.379525 -269.331468) (xy 360.388144 -269.388298) (xy 360.388662 -269.417038)
			(xy 360.38828 -269.444294) (xy 360.380517 -269.49825) (xy 360.365154 -269.550552) (xy 360.342504 -269.600136)
			(xy 360.313027 -269.645991) (xy 360.277325 -269.687184) (xy 360.236124 -269.722878) (xy 360.190262 -269.752344)
			(xy 360.140674 -269.774983) (xy 360.088368 -269.790335) (xy 360.03441 -269.798086) (xy 360.007154 -269.798546)
			(xy 359.979784 -269.798061) (xy 359.925605 -269.79025) (xy 359.873102 -269.774766) (xy 359.823355 -269.751928)
			(xy 359.777388 -269.722206) (xy 359.756456 -269.704566) (xy 359.756202 -269.704312) (xy 359.749118 -269.698721)
			(xy 359.732199 -269.692477) (xy 359.723182 -269.69212) (xy 359.656126 -269.69212) (xy 359.64711 -269.692485)
			(xy 359.630193 -269.698727) (xy 359.623106 -269.704312) (xy 359.623106 -269.704566) (xy 359.622852 -269.704566)
			(xy 359.601919 -269.722207) (xy 359.555951 -269.751931) (xy 359.506205 -269.774777) (xy 359.453703 -269.790273)
			(xy 359.399525 -269.798102) (xy 359.344783 -269.798102) (xy 359.290605 -269.790273) (xy 359.238103 -269.774777)
			(xy 359.188357 -269.751931) (xy 359.142389 -269.722207) (xy 359.121456 -269.704566) (xy 359.121202 -269.704312)
			(xy 359.114118 -269.698721) (xy 359.097199 -269.692477) (xy 359.088182 -269.69212) (xy 359.021126 -269.69212)
			(xy 359.01211 -269.692485) (xy 358.995193 -269.698727) (xy 358.988106 -269.704312) (xy 358.988106 -269.704566)
			(xy 358.987852 -269.704566) (xy 358.966919 -269.722207) (xy 358.920951 -269.751931) (xy 358.871205 -269.774777)
			(xy 358.818703 -269.790273) (xy 358.764525 -269.798102) (xy 358.709783 -269.798102) (xy 358.655605 -269.790273)
			(xy 358.603103 -269.774777) (xy 358.553357 -269.751931) (xy 358.507389 -269.722207) (xy 358.486456 -269.704566)
			(xy 358.486202 -269.704312) (xy 358.479118 -269.698721) (xy 358.462199 -269.692477) (xy 358.453182 -269.69212)
			(xy 358.386126 -269.69212) (xy 358.37711 -269.692485) (xy 358.360193 -269.698727) (xy 358.353106 -269.704312)
			(xy 358.353106 -269.704566) (xy 358.352852 -269.704566) (xy 358.331919 -269.722207) (xy 358.285951 -269.751931)
			(xy 358.236205 -269.774777) (xy 358.183703 -269.790273) (xy 358.129525 -269.798102) (xy 358.074783 -269.798102)
			(xy 358.020605 -269.790273) (xy 357.968103 -269.774777) (xy 357.918357 -269.751931) (xy 357.872389 -269.722207)
			(xy 357.851456 -269.704566) (xy 357.851202 -269.704312) (xy 357.844118 -269.698721) (xy 357.827199 -269.692477)
			(xy 357.818182 -269.69212) (xy 357.751126 -269.69212) (xy 357.74211 -269.692485) (xy 357.725193 -269.698727)
			(xy 357.718106 -269.704312) (xy 357.718106 -269.704566) (xy 357.717852 -269.704566) (xy 357.696907 -269.722189)
			(xy 357.650938 -269.751904) (xy 357.601194 -269.774744) (xy 357.548696 -269.790239) (xy 357.494522 -269.79807)
			(xy 357.467154 -269.798546) (xy 357.439903 -269.798065) (xy 357.385957 -269.790303) (xy 357.333665 -269.774944)
			(xy 357.28409 -269.752301) (xy 357.238242 -269.722833) (xy 357.197053 -269.687141) (xy 357.161362 -269.645952)
			(xy 357.131896 -269.600103) (xy 357.109253 -269.550528) (xy 357.093895 -269.498235) (xy 357.086134 -269.444289)
			(xy 357.085646 -269.417038) (xy 338.003642 -269.417038) (xy 338.003158 -269.444289) (xy 337.995397 -269.498235)
			(xy 337.980039 -269.550527) (xy 337.957396 -269.600102) (xy 337.927928 -269.645951) (xy 337.892237 -269.68714)
			(xy 337.851048 -269.722831) (xy 337.805199 -269.752297) (xy 337.755624 -269.77494) (xy 337.703331 -269.790298)
			(xy 337.649385 -269.798058) (xy 337.622134 -269.798546) (xy 337.594764 -269.798073) (xy 337.540585 -269.790259)
			(xy 337.488081 -269.774772) (xy 337.438334 -269.751932) (xy 337.392367 -269.722207) (xy 337.371436 -269.704566)
			(xy 337.371182 -269.704312) (xy 337.364104 -269.698713) (xy 337.347181 -269.692473) (xy 337.338162 -269.69212)
			(xy 337.271106 -269.69212) (xy 337.262089 -269.692475) (xy 337.245172 -269.698724) (xy 337.238086 -269.704312)
			(xy 337.238086 -269.704566) (xy 337.237832 -269.704566) (xy 337.216899 -269.722207) (xy 337.170931 -269.751931)
			(xy 337.121185 -269.774777) (xy 337.068683 -269.790273) (xy 337.014505 -269.798102) (xy 336.959763 -269.798102)
			(xy 336.905585 -269.790273) (xy 336.853083 -269.774777) (xy 336.803337 -269.751931) (xy 336.757369 -269.722207)
			(xy 336.736436 -269.704566) (xy 336.736182 -269.704312) (xy 336.729104 -269.698713) (xy 336.712181 -269.692473)
			(xy 336.703162 -269.69212) (xy 336.636106 -269.69212) (xy 336.627089 -269.692475) (xy 336.610172 -269.698724)
			(xy 336.603086 -269.704312) (xy 336.603086 -269.704566) (xy 336.602832 -269.704566) (xy 336.581899 -269.722207)
			(xy 336.535931 -269.751931) (xy 336.486185 -269.774777) (xy 336.433683 -269.790273) (xy 336.379505 -269.798102)
			(xy 336.324763 -269.798102) (xy 336.270585 -269.790273) (xy 336.218083 -269.774777) (xy 336.168337 -269.751931)
			(xy 336.122369 -269.722207) (xy 336.101436 -269.704566) (xy 336.101182 -269.704312) (xy 336.094104 -269.698713)
			(xy 336.077181 -269.692473) (xy 336.068162 -269.69212) (xy 336.001106 -269.69212) (xy 335.992089 -269.692475)
			(xy 335.975172 -269.698724) (xy 335.968086 -269.704312) (xy 335.968086 -269.704566) (xy 335.967832 -269.704566)
			(xy 335.946899 -269.722207) (xy 335.900931 -269.751931) (xy 335.851185 -269.774777) (xy 335.798683 -269.790273)
			(xy 335.744505 -269.798102) (xy 335.689763 -269.798102) (xy 335.635585 -269.790273) (xy 335.583083 -269.774777)
			(xy 335.533337 -269.751931) (xy 335.487369 -269.722207) (xy 335.466436 -269.704566) (xy 335.466182 -269.704312)
			(xy 335.459104 -269.698713) (xy 335.442181 -269.692473) (xy 335.433162 -269.69212) (xy 335.366106 -269.69212)
			(xy 335.357089 -269.692475) (xy 335.340172 -269.698724) (xy 335.333086 -269.704312) (xy 335.333086 -269.704566)
			(xy 335.332832 -269.704566) (xy 335.311894 -269.722198) (xy 335.265924 -269.751912) (xy 335.216178 -269.77475)
			(xy 335.163678 -269.790243) (xy 335.109503 -269.798072) (xy 335.082134 -269.798546) (xy 335.054885 -269.79799)
			(xy 335.000942 -269.790239) (xy 334.948651 -269.77489) (xy 334.899077 -269.752256) (xy 334.853228 -269.722797)
			(xy 334.812038 -269.687113) (xy 334.776346 -269.64593) (xy 334.746878 -269.600087) (xy 334.724235 -269.550516)
			(xy 334.708876 -269.498228) (xy 334.701115 -269.444287) (xy 334.700626 -269.417038) (xy 331.789532 -269.417038)
			(xy 331.789532 -277.864824) (xy 335.665826 -277.864824) (xy 335.666352 -277.835907) (xy 335.675078 -277.778736)
			(xy 335.692334 -277.723537) (xy 335.717724 -277.671575) (xy 335.750667 -277.624041) (xy 335.790407 -277.582024)
			(xy 335.812892 -277.563834) (xy 335.821673 -277.556201) (xy 335.831871 -277.53532) (xy 335.83245 -277.523702)
			(xy 335.83245 -277.443946) (xy 335.831945 -277.432309) (xy 335.821734 -277.411399) (xy 335.812892 -277.403814)
			(xy 335.790414 -277.385617) (xy 335.750678 -277.343598) (xy 335.717739 -277.296065) (xy 335.69235 -277.244104)
			(xy 335.675092 -277.188908) (xy 335.666362 -277.13174) (xy 335.665826 -277.102824) (xy 335.666409 -277.073417)
			(xy 335.675439 -277.015299) (xy 335.693274 -276.959253) (xy 335.719492 -276.906605) (xy 335.753473 -276.858599)
			(xy 335.794413 -276.816372) (xy 335.841345 -276.780923) (xy 335.866994 -276.766528) (xy 335.878932 -276.760178)
			(xy 335.893156 -276.737826) (xy 335.898998 -276.624288) (xy 335.88706 -276.600412) (xy 335.876138 -276.593046)
			(xy 335.85438 -276.577735) (xy 335.814901 -276.542071) (xy 335.780757 -276.50127) (xy 335.75261 -276.456123)
			(xy 335.731005 -276.407505) (xy 335.716362 -276.356357) (xy 335.708964 -276.303671) (xy 335.708498 -276.27707)
			(xy 335.708947 -276.249699) (xy 335.716769 -276.195519) (xy 335.732262 -276.143016) (xy 335.755108 -276.09327)
			(xy 335.784835 -276.047303) (xy 335.802478 -276.026372) (xy 335.802732 -276.026118) (xy 335.808321 -276.019033)
			(xy 335.814565 -276.002115) (xy 335.814924 -275.993098) (xy 335.814924 -275.926042) (xy 335.814542 -275.917028)
			(xy 335.808311 -275.900111) (xy 335.802732 -275.893022) (xy 335.802478 -275.893022) (xy 335.802478 -275.892768)
			(xy 335.784854 -275.871824) (xy 335.755141 -275.825854) (xy 335.732302 -275.77611) (xy 335.716807 -275.723612)
			(xy 335.708975 -275.669438) (xy 335.708498 -275.64207) (xy 335.708498 -275.641816) (xy 335.709069 -275.612017)
			(xy 335.718346 -275.553146) (xy 335.736663 -275.496434) (xy 335.763574 -275.443258) (xy 335.798424 -275.394912)
			(xy 335.818988 -275.373338) (xy 335.826354 -275.365972) (xy 335.833974 -275.34743) (xy 335.832958 -275.25472)
			(xy 335.825084 -275.236178) (xy 335.817718 -275.229066) (xy 335.799761 -275.211015) (xy 335.768263 -275.171012)
			(xy 335.742365 -275.127176) (xy 335.722525 -275.080286) (xy 335.709097 -275.031173) (xy 335.70232 -274.980711)
			(xy 335.701894 -274.955254) (xy 335.702335 -274.928002) (xy 335.710098 -274.874052) (xy 335.725459 -274.821756)
			(xy 335.748106 -274.772179) (xy 335.777577 -274.726329) (xy 335.813273 -274.685139) (xy 335.854467 -274.649448)
			(xy 335.900321 -274.619983) (xy 335.949901 -274.597342) (xy 336.002199 -274.581988) (xy 336.056149 -274.574232)
			(xy 336.083402 -274.573746) (xy 336.11232 -274.574246) (xy 336.169493 -274.582976) (xy 336.224693 -274.600237)
			(xy 336.276655 -274.625632) (xy 336.324188 -274.658579) (xy 336.366203 -274.698324) (xy 336.384392 -274.720812)
			(xy 336.39201 -274.729607) (xy 336.412903 -274.739797) (xy 336.424524 -274.74037) (xy 336.50428 -274.74037)
			(xy 336.51591 -274.739816) (xy 336.536821 -274.729639) (xy 336.544412 -274.720812) (xy 336.561165 -274.700029)
			(xy 336.599519 -274.662899) (xy 336.642673 -274.631477) (xy 336.689787 -274.606378) (xy 336.739939 -274.588092)
			(xy 336.79215 -274.576975) (xy 336.845402 -274.573245) (xy 336.898654 -274.576975) (xy 336.950865 -274.588092)
			(xy 337.001017 -274.606378) (xy 337.048131 -274.631477) (xy 337.091285 -274.662899) (xy 337.129639 -274.700029)
			(xy 337.146392 -274.720812) (xy 337.15401 -274.729607) (xy 337.174903 -274.739797) (xy 337.186524 -274.74037)
			(xy 337.26628 -274.74037) (xy 337.27791 -274.739816) (xy 337.298821 -274.729639) (xy 337.306412 -274.720812)
			(xy 337.324599 -274.698325) (xy 337.366619 -274.65859) (xy 337.414155 -274.625651) (xy 337.466117 -274.600263)
			(xy 337.521315 -274.583007) (xy 337.578486 -274.57428) (xy 337.607402 -274.573746) (xy 337.634651 -274.574276)
			(xy 337.688595 -274.582031) (xy 337.740886 -274.597384) (xy 337.79046 -274.620022) (xy 337.836308 -274.649485)
			(xy 337.877497 -274.685171) (xy 337.913189 -274.726356) (xy 337.942656 -274.772201) (xy 337.9653 -274.821773)
			(xy 337.980659 -274.874062) (xy 337.988421 -274.928005) (xy 337.98891 -274.955254) (xy 337.98891 -274.955508)
			(xy 337.988352 -274.985307) (xy 337.979071 -275.044178) (xy 337.960751 -275.100891) (xy 337.933837 -275.154067)
			(xy 337.898985 -275.202413) (xy 337.87842 -275.223986) (xy 337.871054 -275.231352) (xy 337.863434 -275.249894)
			(xy 337.86445 -275.342604) (xy 337.872324 -275.361146) (xy 337.87969 -275.368258) (xy 337.89766 -275.386296)
			(xy 337.929156 -275.426302) (xy 337.955053 -275.470141) (xy 337.97489 -275.517034) (xy 337.988315 -275.566148)
			(xy 337.99509 -275.616612) (xy 337.995514 -275.64207) (xy 337.995007 -275.670988) (xy 337.98628 -275.728161)
			(xy 337.969022 -275.783361) (xy 337.943629 -275.835324) (xy 337.910681 -275.882857) (xy 337.870936 -275.924872)
			(xy 337.848448 -275.94306) (xy 337.83966 -275.950685) (xy 337.829468 -275.971573) (xy 337.82889 -275.983192)
			(xy 337.82889 -276.051264) (xy 341.2617 -276.051264) (xy 341.262145 -276.023893) (xy 341.269968 -275.969713)
			(xy 341.285462 -275.91721) (xy 341.308308 -275.867463) (xy 341.338037 -275.821497) (xy 341.35568 -275.800566)
			(xy 341.355934 -275.800312) (xy 341.361525 -275.793229) (xy 341.367768 -275.776309) (xy 341.368126 -275.767292)
			(xy 341.368126 -275.700236) (xy 341.367746 -275.691222) (xy 341.361514 -275.674305) (xy 341.355934 -275.667216)
			(xy 341.35568 -275.667216) (xy 341.35568 -275.666962) (xy 341.338006 -275.646057) (xy 341.308286 -275.600083)
			(xy 341.285446 -275.550332) (xy 341.269954 -275.497826) (xy 341.26213 -275.443645) (xy 341.262134 -275.388901)
			(xy 341.269966 -275.334721) (xy 341.285465 -275.282217) (xy 341.308312 -275.232469) (xy 341.338039 -275.1865)
			(xy 341.35568 -275.165566) (xy 341.355934 -275.165312) (xy 341.361525 -275.158229) (xy 341.367768 -275.141309)
			(xy 341.368126 -275.132292) (xy 341.368126 -275.065236) (xy 341.367746 -275.056222) (xy 341.361514 -275.039305)
			(xy 341.355934 -275.032216) (xy 341.35568 -275.032216) (xy 341.35568 -275.031962) (xy 341.338053 -275.01102)
			(xy 341.30834 -274.96505) (xy 341.285502 -274.915305) (xy 341.270008 -274.862806) (xy 341.262176 -274.808632)
			(xy 341.2617 -274.781264) (xy 341.262144 -274.754011) (xy 341.269906 -274.700062) (xy 341.285266 -274.647766)
			(xy 341.307912 -274.598188) (xy 341.337383 -274.552337) (xy 341.373079 -274.511147) (xy 341.414273 -274.475456)
			(xy 341.460127 -274.445991) (xy 341.509707 -274.423351) (xy 341.562005 -274.407997) (xy 341.615955 -274.400241)
			(xy 341.643208 -274.399756) (xy 341.670579 -274.400204) (xy 341.724759 -274.408024) (xy 341.777263 -274.423516)
			(xy 341.82701 -274.446363) (xy 341.872975 -274.476092) (xy 341.893906 -274.493736) (xy 341.89416 -274.49399)
			(xy 341.901255 -274.499565) (xy 341.918165 -274.505819) (xy 341.92718 -274.506182) (xy 341.994236 -274.506182)
			(xy 342.003255 -274.505846) (xy 342.020172 -274.499584) (xy 342.027256 -274.49399) (xy 342.027256 -274.493736)
			(xy 342.02751 -274.493736) (xy 342.048432 -274.476084) (xy 342.094407 -274.446373) (xy 342.144157 -274.423539)
			(xy 342.19666 -274.408051) (xy 342.250838 -274.400227) (xy 342.278208 -274.399756) (xy 342.305458 -274.40027)
			(xy 342.359403 -274.408027) (xy 342.411695 -274.423381) (xy 342.46127 -274.446021) (xy 342.507118 -274.475484)
			(xy 342.548307 -274.511173) (xy 342.583999 -274.552359) (xy 342.613466 -274.598206) (xy 342.636109 -274.647779)
			(xy 342.651467 -274.70007) (xy 342.659228 -274.754014) (xy 342.659716 -274.781264) (xy 342.659249 -274.808634)
			(xy 342.651435 -274.862814) (xy 342.635947 -274.915318) (xy 342.613105 -274.965065) (xy 342.583379 -275.011031)
			(xy 342.565736 -275.031962) (xy 342.565482 -275.032216) (xy 342.559881 -275.039292) (xy 342.553643 -275.056217)
			(xy 342.55329 -275.065236) (xy 342.55329 -275.132292) (xy 342.553653 -275.141308) (xy 342.559897 -275.158225)
			(xy 342.565482 -275.165312) (xy 342.565736 -275.165312) (xy 342.565736 -275.165566) (xy 342.583343 -275.186527)
			(xy 342.613072 -275.232489) (xy 342.635922 -275.28223) (xy 342.651422 -275.334728) (xy 342.659255 -275.388904)
			(xy 342.659259 -275.443642) (xy 342.651434 -275.497819) (xy 342.635941 -275.550319) (xy 342.613098 -275.600064)
			(xy 342.583376 -275.64603) (xy 342.565736 -275.666962) (xy 342.565482 -275.667216) (xy 342.559881 -275.674292)
			(xy 342.553643 -275.691217) (xy 342.55329 -275.700236) (xy 342.55329 -275.767292) (xy 342.553653 -275.776308)
			(xy 342.559897 -275.793225) (xy 342.565482 -275.800312) (xy 342.565736 -275.800312) (xy 342.565736 -275.800566)
			(xy 342.583343 -275.821527) (xy 342.613072 -275.867489) (xy 342.635922 -275.91723) (xy 342.651422 -275.969728)
			(xy 342.659255 -276.023904) (xy 342.659255 -276.027896) (xy 352.727006 -276.027896) (xy 352.727468 -276.000526)
			(xy 352.735287 -275.946346) (xy 352.750777 -275.893843) (xy 352.773619 -275.844096) (xy 352.803344 -275.79813)
			(xy 352.820986 -275.777198) (xy 352.82124 -275.776944) (xy 352.826819 -275.769853) (xy 352.833069 -275.752939)
			(xy 352.833432 -275.743924) (xy 352.833432 -275.676868) (xy 352.833083 -275.66785) (xy 352.826829 -275.650934)
			(xy 352.82124 -275.643848) (xy 352.820986 -275.643848) (xy 352.820986 -275.643594) (xy 352.803343 -275.622664)
			(xy 352.773622 -275.576694) (xy 352.750779 -275.526948) (xy 352.735285 -275.474445) (xy 352.727457 -275.420267)
			(xy 352.727458 -275.365527) (xy 352.735286 -275.311349) (xy 352.750781 -275.258847) (xy 352.773624 -275.2091)
			(xy 352.803347 -275.163132) (xy 352.820986 -275.142198) (xy 352.82124 -275.141944) (xy 352.826819 -275.134853)
			(xy 352.833069 -275.117939) (xy 352.833432 -275.108924) (xy 352.833432 -275.041868) (xy 352.833083 -275.03285)
			(xy 352.826829 -275.015934) (xy 352.82124 -275.008848) (xy 352.820986 -275.008848) (xy 352.820986 -275.008594)
			(xy 352.803328 -274.987677) (xy 352.77362 -274.9417) (xy 352.750788 -274.891948) (xy 352.735301 -274.839444)
			(xy 352.727477 -274.785266) (xy 352.727006 -274.757896) (xy 352.727452 -274.730642) (xy 352.73521 -274.67669)
			(xy 352.750567 -274.624391) (xy 352.773211 -274.57481) (xy 352.80268 -274.528956) (xy 352.838376 -274.487763)
			(xy 352.879571 -274.45207) (xy 352.925426 -274.422602) (xy 352.975008 -274.39996) (xy 353.027308 -274.384606)
			(xy 353.08126 -274.37685) (xy 353.108514 -274.376388) (xy 353.135884 -274.376849) (xy 353.190064 -274.384668)
			(xy 353.242567 -274.400159) (xy 353.292313 -274.423002) (xy 353.33828 -274.452727) (xy 353.359212 -274.470368)
			(xy 353.359466 -274.470622) (xy 353.366556 -274.476203) (xy 353.38347 -274.482452) (xy 353.392486 -274.482814)
			(xy 353.459542 -274.482814) (xy 353.468556 -274.482426) (xy 353.485473 -274.4762) (xy 353.492562 -274.470622)
			(xy 353.492562 -274.470368) (xy 353.492816 -274.470368) (xy 353.513765 -274.45275) (xy 353.559734 -274.423036)
			(xy 353.609477 -274.400196) (xy 353.661974 -274.3847) (xy 353.716146 -274.376866) (xy 353.743514 -274.376388)
			(xy 353.770765 -274.376865) (xy 353.824713 -274.384623) (xy 353.877008 -274.39998) (xy 353.926585 -274.422622)
			(xy 353.972435 -274.45209) (xy 354.013625 -274.487782) (xy 354.049316 -274.528973) (xy 354.078783 -274.574824)
			(xy 354.101424 -274.624401) (xy 354.116779 -274.676697) (xy 354.124536 -274.730645) (xy 354.125022 -274.757896)
			(xy 354.124573 -274.785267) (xy 354.116754 -274.839448) (xy 354.101262 -274.891952) (xy 354.078416 -274.941698)
			(xy 354.048686 -274.987664) (xy 354.031042 -275.008594) (xy 354.030788 -275.008848) (xy 354.025216 -275.015944)
			(xy 354.018961 -275.032854) (xy 354.018596 -275.041868) (xy 354.018596 -275.108924) (xy 354.018943 -275.117942)
			(xy 354.025198 -275.134859) (xy 354.030788 -275.141944) (xy 354.031042 -275.141944) (xy 354.031042 -275.142198)
			(xy 354.04868 -275.163133) (xy 354.078407 -275.2091) (xy 354.101255 -275.258846) (xy 354.116753 -275.311347)
			(xy 354.124582 -275.365526) (xy 354.124583 -275.420268) (xy 354.116754 -275.474447) (xy 354.101257 -275.526949)
			(xy 354.07841 -275.576695) (xy 354.048684 -275.622662) (xy 354.031042 -275.643594) (xy 354.030788 -275.643848)
			(xy 354.025216 -275.650944) (xy 354.018961 -275.667854) (xy 354.018596 -275.676868) (xy 354.018596 -275.743924)
			(xy 354.018943 -275.752942) (xy 354.025198 -275.769859) (xy 354.030788 -275.776944) (xy 354.031042 -275.776944)
			(xy 354.031042 -275.777198) (xy 354.04868 -275.798133) (xy 354.078407 -275.8441) (xy 354.101255 -275.893846)
			(xy 354.116753 -275.946347) (xy 354.124582 -276.000526) (xy 354.124583 -276.046184) (xy 356.66045 -276.046184)
			(xy 356.660895 -276.018813) (xy 356.668716 -275.964632) (xy 356.684209 -275.912129) (xy 356.707056 -275.862382)
			(xy 356.736786 -275.816417) (xy 356.75443 -275.795486) (xy 356.754684 -275.795232) (xy 356.760262 -275.788139)
			(xy 356.766514 -275.771227) (xy 356.766876 -275.762212) (xy 356.766876 -275.695156) (xy 356.766497 -275.686141)
			(xy 356.760265 -275.669224) (xy 356.754684 -275.662136) (xy 356.75443 -275.662136) (xy 356.75443 -275.661882)
			(xy 356.736821 -275.640926) (xy 356.707103 -275.59496) (xy 356.684261 -275.545219) (xy 356.668763 -275.492723)
			(xy 356.660928 -275.438552) (xy 356.66045 -275.411184) (xy 356.660963 -275.383934) (xy 356.66872 -275.32999)
			(xy 356.684075 -275.277698) (xy 356.706715 -275.228124) (xy 356.736179 -275.182275) (xy 356.771868 -275.141086)
			(xy 356.813054 -275.105395) (xy 356.858901 -275.075928) (xy 356.908474 -275.053285) (xy 356.960764 -275.037926)
			(xy 357.014708 -275.030165) (xy 357.041958 -275.029676) (xy 357.069328 -275.030148) (xy 357.123508 -275.037962)
			(xy 357.176012 -275.053448) (xy 357.225759 -275.076289) (xy 357.271725 -275.106014) (xy 357.292656 -275.123656)
			(xy 357.29291 -275.12391) (xy 357.299989 -275.129508) (xy 357.316912 -275.135748) (xy 357.32593 -275.136102)
			(xy 357.392986 -275.136102) (xy 357.402002 -275.135738) (xy 357.418919 -275.129495) (xy 357.426006 -275.12391)
			(xy 357.426006 -275.123656) (xy 357.42626 -275.123656) (xy 357.447193 -275.106015) (xy 357.493161 -275.076291)
			(xy 357.542907 -275.053445) (xy 357.595409 -275.037949) (xy 357.649587 -275.03012) (xy 357.704329 -275.03012)
			(xy 357.758507 -275.037949) (xy 357.811009 -275.053445) (xy 357.860755 -275.076291) (xy 357.906723 -275.106015)
			(xy 357.927656 -275.123656) (xy 357.92791 -275.12391) (xy 357.934989 -275.129508) (xy 357.951912 -275.135748)
			(xy 357.96093 -275.136102) (xy 358.027986 -275.136102) (xy 358.037002 -275.135738) (xy 358.053919 -275.129495)
			(xy 358.061006 -275.12391) (xy 358.061006 -275.123656) (xy 358.06126 -275.123656) (xy 358.082193 -275.106015)
			(xy 358.128161 -275.076291) (xy 358.177907 -275.053445) (xy 358.230409 -275.037949) (xy 358.284587 -275.03012)
			(xy 358.339329 -275.03012) (xy 358.393507 -275.037949) (xy 358.446009 -275.053445) (xy 358.495755 -275.076291)
			(xy 358.541723 -275.106015) (xy 358.562656 -275.123656) (xy 358.56291 -275.12391) (xy 358.569989 -275.129508)
			(xy 358.586912 -275.135748) (xy 358.59593 -275.136102) (xy 358.662986 -275.136102) (xy 358.672002 -275.135738)
			(xy 358.688919 -275.129495) (xy 358.696006 -275.12391) (xy 358.696006 -275.123656) (xy 358.69626 -275.123656)
			(xy 358.717193 -275.106015) (xy 358.763161 -275.076291) (xy 358.812907 -275.053445) (xy 358.865409 -275.037949)
			(xy 358.919587 -275.03012) (xy 358.974329 -275.03012) (xy 359.028507 -275.037949) (xy 359.081009 -275.053445)
			(xy 359.130755 -275.076291) (xy 359.176723 -275.106015) (xy 359.197656 -275.123656) (xy 359.19791 -275.12391)
			(xy 359.204989 -275.129508) (xy 359.221912 -275.135748) (xy 359.23093 -275.136102) (xy 359.297986 -275.136102)
			(xy 359.307002 -275.135738) (xy 359.323919 -275.129495) (xy 359.331006 -275.12391) (xy 359.331006 -275.123656)
			(xy 359.33126 -275.123656) (xy 359.35219 -275.106015) (xy 359.398164 -275.076305) (xy 359.447912 -275.05347)
			(xy 359.500413 -275.037979) (xy 359.554589 -275.03015) (xy 359.581958 -275.029676) (xy 359.609209 -275.030194)
			(xy 359.663157 -275.037945) (xy 359.715453 -275.053295) (xy 359.765032 -275.075932) (xy 359.810885 -275.105394)
			(xy 359.852077 -275.141082) (xy 359.887772 -275.182269) (xy 359.917241 -275.228117) (xy 359.939885 -275.277693)
			(xy 359.955242 -275.329986) (xy 359.963002 -275.383933) (xy 359.963466 -275.411184) (xy 359.962999 -275.438554)
			(xy 359.955183 -275.492734) (xy 359.939694 -275.545237) (xy 359.916852 -275.594984) (xy 359.887128 -275.640951)
			(xy 359.869486 -275.661882) (xy 359.869232 -275.662136) (xy 359.863658 -275.669231) (xy 359.857406 -275.686142)
			(xy 359.85704 -275.695156) (xy 359.85704 -275.762212) (xy 359.857382 -275.771231) (xy 359.863639 -275.788148)
			(xy 359.869232 -275.795232) (xy 359.869486 -275.795232) (xy 359.869486 -275.795486) (xy 359.88713 -275.816414)
			(xy 359.916841 -275.862388) (xy 359.939677 -275.912136) (xy 359.955167 -275.964638) (xy 359.962993 -276.018815)
			(xy 359.963466 -276.046184) (xy 359.96303 -276.073438) (xy 359.955274 -276.127392) (xy 359.939918 -276.179693)
			(xy 359.917274 -276.229276) (xy 359.887804 -276.275131) (xy 359.852107 -276.316325) (xy 359.810911 -276.352019)
			(xy 359.765053 -276.381486) (xy 359.715469 -276.404127) (xy 359.663167 -276.419479) (xy 359.609212 -276.427232)
			(xy 359.581958 -276.427692) (xy 359.554589 -276.427194) (xy 359.500411 -276.419384) (xy 359.447908 -276.403903)
			(xy 359.398161 -276.381068) (xy 359.352193 -276.35135) (xy 359.33126 -276.333712) (xy 359.331006 -276.333458)
			(xy 359.323926 -276.327863) (xy 359.307004 -276.321622) (xy 359.297986 -276.321266) (xy 359.23093 -276.321266)
			(xy 359.221915 -276.321645) (xy 359.204999 -276.327878) (xy 359.19791 -276.333458) (xy 359.19791 -276.333712)
			(xy 359.197656 -276.333712) (xy 359.176723 -276.351353) (xy 359.130755 -276.381077) (xy 359.081009 -276.403923)
			(xy 359.028507 -276.419419) (xy 358.974329 -276.427248) (xy 358.919587 -276.427248) (xy 358.865409 -276.419419)
			(xy 358.812907 -276.403923) (xy 358.763161 -276.381077) (xy 358.717193 -276.351353) (xy 358.69626 -276.333712)
			(xy 358.696006 -276.333458) (xy 358.688926 -276.327863) (xy 358.672004 -276.321622) (xy 358.662986 -276.321266)
			(xy 358.59593 -276.321266) (xy 358.586915 -276.321645) (xy 358.569999 -276.327878) (xy 358.56291 -276.333458)
			(xy 358.56291 -276.333712) (xy 358.562656 -276.333712) (xy 358.541723 -276.351353) (xy 358.495755 -276.381077)
			(xy 358.446009 -276.403923) (xy 358.393507 -276.419419) (xy 358.339329 -276.427248) (xy 358.284587 -276.427248)
			(xy 358.230409 -276.419419) (xy 358.177907 -276.403923) (xy 358.128161 -276.381077) (xy 358.082193 -276.351353)
			(xy 358.06126 -276.333712) (xy 358.061006 -276.333458) (xy 358.053926 -276.327863) (xy 358.037004 -276.321622)
			(xy 358.027986 -276.321266) (xy 357.96093 -276.321266) (xy 357.951915 -276.321645) (xy 357.934999 -276.327878)
			(xy 357.92791 -276.333458) (xy 357.92791 -276.333712) (xy 357.927656 -276.333712) (xy 357.906723 -276.351353)
			(xy 357.860755 -276.381077) (xy 357.811009 -276.403923) (xy 357.758507 -276.419419) (xy 357.704329 -276.427248)
			(xy 357.649587 -276.427248) (xy 357.595409 -276.419419) (xy 357.542907 -276.403923) (xy 357.493161 -276.381077)
			(xy 357.447193 -276.351353) (xy 357.42626 -276.333712) (xy 357.426006 -276.333458) (xy 357.418926 -276.327863)
			(xy 357.402004 -276.321622) (xy 357.392986 -276.321266) (xy 357.32593 -276.321266) (xy 357.316915 -276.321645)
			(xy 357.299999 -276.327878) (xy 357.29291 -276.333458) (xy 357.29291 -276.333712) (xy 357.292656 -276.333712)
			(xy 357.271715 -276.35134) (xy 357.225745 -276.381053) (xy 357.175999 -276.403891) (xy 357.123501 -276.419385)
			(xy 357.069327 -276.427216) (xy 357.041958 -276.427692) (xy 357.014705 -276.427261) (xy 356.960754 -276.419499)
			(xy 356.908458 -276.404137) (xy 356.858879 -276.38149) (xy 356.813028 -276.352018) (xy 356.771838 -276.316321)
			(xy 356.736147 -276.275125) (xy 356.706682 -276.22927) (xy 356.684042 -276.179688) (xy 356.668689 -276.127389)
			(xy 356.660935 -276.073437) (xy 356.66045 -276.046184) (xy 354.124583 -276.046184) (xy 354.124583 -276.055268)
			(xy 354.116754 -276.109447) (xy 354.101257 -276.161949) (xy 354.07841 -276.211695) (xy 354.048684 -276.257662)
			(xy 354.031042 -276.278594) (xy 354.030788 -276.278848) (xy 354.025216 -276.285944) (xy 354.018961 -276.302854)
			(xy 354.018596 -276.311868) (xy 354.018596 -276.378924) (xy 354.018943 -276.387942) (xy 354.025198 -276.404859)
			(xy 354.030788 -276.411944) (xy 354.031042 -276.411944) (xy 354.031042 -276.412198) (xy 354.048701 -276.433114)
			(xy 354.078408 -276.479092) (xy 354.10124 -276.528844) (xy 354.116727 -276.581348) (xy 354.124551 -276.635526)
			(xy 354.125022 -276.662896) (xy 354.124536 -276.690147) (xy 354.11678 -276.744095) (xy 354.101425 -276.79639)
			(xy 354.078783 -276.845967) (xy 354.049317 -276.891817) (xy 354.013626 -276.933008) (xy 353.972435 -276.968699)
			(xy 353.926585 -276.998165) (xy 353.877008 -277.020807) (xy 353.824713 -277.036162) (xy 353.770765 -277.043918)
			(xy 353.716263 -277.043918) (xy 353.662315 -277.036162) (xy 353.61002 -277.020807) (xy 353.560443 -276.998165)
			(xy 353.514593 -276.968699) (xy 353.473402 -276.933008) (xy 353.437711 -276.891817) (xy 353.408245 -276.845967)
			(xy 353.385603 -276.79639) (xy 353.370248 -276.744095) (xy 353.362492 -276.690147) (xy 353.362006 -276.662896)
			(xy 353.362542 -276.633418) (xy 353.371612 -276.575165) (xy 353.389535 -276.519) (xy 353.415885 -276.466261)
			(xy 353.450035 -276.418203) (xy 353.47021 -276.396704) (xy 353.476737 -276.389364) (xy 353.484187 -276.371208)
			(xy 353.484688 -276.361398) (xy 353.484688 -276.308058) (xy 353.477322 -276.3012) (xy 353.469975 -276.294682)
			(xy 353.451824 -276.287227) (xy 353.442016 -276.286722) (xy 353.410012 -276.286722) (xy 353.400199 -276.287218)
			(xy 353.382034 -276.294656) (xy 353.374706 -276.3012) (xy 353.353196 -276.321362) (xy 353.30514 -276.35551)
			(xy 353.252404 -276.38186) (xy 353.196241 -276.399783) (xy 353.13799 -276.408854) (xy 353.108514 -276.409404)
			(xy 353.081261 -276.408932) (xy 353.027311 -276.401176) (xy 352.975013 -276.385822) (xy 352.925432 -276.363181)
			(xy 352.879579 -276.333714) (xy 352.838386 -276.298021) (xy 352.802692 -276.256829) (xy 352.773224 -276.210977)
			(xy 352.750581 -276.161397) (xy 352.735226 -276.109099) (xy 352.727469 -276.055149) (xy 352.727006 -276.027896)
			(xy 342.659255 -276.027896) (xy 342.659259 -276.078642) (xy 342.651434 -276.132819) (xy 342.635941 -276.185319)
			(xy 342.613098 -276.235064) (xy 342.583376 -276.28103) (xy 342.565736 -276.301962) (xy 342.565482 -276.302216)
			(xy 342.559881 -276.309292) (xy 342.553643 -276.326217) (xy 342.55329 -276.335236) (xy 342.55329 -276.402292)
			(xy 342.553653 -276.411308) (xy 342.559897 -276.428225) (xy 342.565482 -276.435312) (xy 342.565736 -276.435312)
			(xy 342.565736 -276.43582) (xy 342.581886 -276.454875) (xy 342.609553 -276.496465) (xy 342.631554 -276.54131)
			(xy 342.639904 -276.564852) (xy 342.643714 -276.576282) (xy 342.660224 -276.593046) (xy 342.748108 -276.622764)
			(xy 342.759411 -276.62603) (xy 342.782715 -276.622965) (xy 342.792812 -276.616922) (xy 342.793066 -276.616668)
			(xy 342.816823 -276.601327) (xy 342.867881 -276.577017) (xy 342.921967 -276.560507) (xy 342.977897 -276.552158)
			(xy 343.006172 -276.551644) (xy 343.03342 -276.552204) (xy 343.087363 -276.559956) (xy 343.139653 -276.575305)
			(xy 343.189227 -276.597939) (xy 343.235075 -276.627398) (xy 343.276265 -276.663082) (xy 343.311956 -276.704264)
			(xy 343.341424 -276.750106) (xy 343.364069 -276.799675) (xy 343.379428 -276.851963) (xy 343.38719 -276.905904)
			(xy 343.38768 -276.933152) (xy 343.387254 -276.959467) (xy 343.380011 -277.011598) (xy 343.365685 -277.062242)
			(xy 343.344544 -277.110441) (xy 343.316991 -277.155283) (xy 343.283545 -277.195921) (xy 343.26449 -277.214076)
			(xy 343.257095 -277.221603) (xy 343.248567 -277.240879) (xy 343.24798 -277.251414) (xy 343.24798 -277.32609)
			(xy 343.248507 -277.33664) (xy 343.257044 -277.355935) (xy 343.26449 -277.363428) (xy 343.28355 -277.381579)
			(xy 343.317007 -277.422209) (xy 343.344566 -277.467051) (xy 343.365704 -277.515252) (xy 343.38002 -277.565901)
			(xy 343.387243 -277.618036) (xy 343.387511 -277.634192) (xy 352.285046 -277.634192) (xy 352.285601 -277.605067)
			(xy 352.294469 -277.547495) (xy 352.311982 -277.49194) (xy 352.337734 -277.43969) (xy 352.371127 -277.391961)
			(xy 352.411385 -277.349861) (xy 352.434144 -277.331678) (xy 352.443288 -277.324566) (xy 352.453702 -277.304246)
			(xy 352.455988 -277.213568) (xy 352.455627 -277.202192) (xy 352.446251 -277.181483) (xy 352.437954 -277.17369)
			(xy 352.417226 -277.155498) (xy 352.380759 -277.114124) (xy 352.35063 -277.06793) (xy 352.327467 -277.017878)
			(xy 352.311754 -276.965013) (xy 352.303818 -276.910436) (xy 352.303334 -276.88286) (xy 352.30382 -276.855609)
			(xy 352.311576 -276.801661) (xy 352.326931 -276.749366) (xy 352.349573 -276.699789) (xy 352.379039 -276.653939)
			(xy 352.41473 -276.612748) (xy 352.455921 -276.577057) (xy 352.501771 -276.547591) (xy 352.551348 -276.524949)
			(xy 352.603643 -276.509594) (xy 352.657591 -276.501838) (xy 352.712093 -276.501838) (xy 352.766041 -276.509594)
			(xy 352.818336 -276.524949) (xy 352.867913 -276.547591) (xy 352.913763 -276.577057) (xy 352.954954 -276.612748)
			(xy 352.990645 -276.653939) (xy 353.020111 -276.699789) (xy 353.042753 -276.749366) (xy 353.058108 -276.801661)
			(xy 353.065864 -276.855609) (xy 353.06635 -276.88286) (xy 353.065762 -276.911984) (xy 353.056902 -276.969554)
			(xy 353.039395 -277.025109) (xy 353.013649 -277.077359) (xy 352.980262 -277.125088) (xy 352.940009 -277.16719)
			(xy 352.917252 -277.185374) (xy 352.908108 -277.192486) (xy 352.897694 -277.212806) (xy 352.895408 -277.303484)
			(xy 352.895798 -277.314857) (xy 352.905153 -277.335566) (xy 352.913442 -277.343362) (xy 352.934146 -277.36158)
			(xy 352.970615 -277.402949) (xy 353.000747 -277.449137) (xy 353.023914 -277.499184) (xy 353.039632 -277.552045)
			(xy 353.040313 -277.556722) (xy 353.207826 -277.556722) (xy 353.211897 -277.5011) (xy 353.224023 -277.446663)
			(xy 353.243946 -277.394572) (xy 353.271242 -277.345937) (xy 353.305328 -277.301794) (xy 353.345477 -277.263085)
			(xy 353.390835 -277.230634) (xy 353.440435 -277.205133) (xy 353.493219 -277.187126) (xy 353.548062 -277.176996)
			(xy 353.603796 -277.174959) (xy 353.659233 -277.181059) (xy 353.71319 -277.195165) (xy 353.764519 -277.216977)
			(xy 353.812125 -277.246031) (xy 353.854993 -277.281706) (xy 353.89221 -277.323243) (xy 353.922983 -277.369756)
			(xy 353.946655 -277.420253) (xy 353.962723 -277.47366) (xy 353.970843 -277.528836) (xy 353.971352 -277.556722)
			(xy 353.970843 -277.584608) (xy 353.962723 -277.639784) (xy 353.961349 -277.644352) (xy 359.283762 -277.644352)
			(xy 359.284178 -277.618036) (xy 359.29142 -277.565904) (xy 359.305748 -277.51526) (xy 359.32689 -277.467061)
			(xy 359.354446 -277.422219) (xy 359.387895 -277.381582) (xy 359.406952 -277.363428) (xy 359.414336 -277.355891)
			(xy 359.422872 -277.336623) (xy 359.423462 -277.32609) (xy 359.423462 -277.251414) (xy 359.42295 -277.240862)
			(xy 359.414404 -277.221566) (xy 359.406952 -277.214076) (xy 359.387883 -277.195935) (xy 359.354429 -277.155301)
			(xy 359.326873 -277.110457) (xy 359.305737 -277.062254) (xy 359.291422 -277.011604) (xy 359.2842 -276.959469)
			(xy 359.283762 -276.933152) (xy 359.284248 -276.905901) (xy 359.292004 -276.851953) (xy 359.307359 -276.799658)
			(xy 359.330001 -276.750081) (xy 359.359467 -276.704231) (xy 359.395158 -276.66304) (xy 359.436349 -276.627349)
			(xy 359.482199 -276.597883) (xy 359.531776 -276.575241) (xy 359.584071 -276.559886) (xy 359.638019 -276.55213)
			(xy 359.692521 -276.55213) (xy 359.746469 -276.559886) (xy 359.798764 -276.575241) (xy 359.848341 -276.597883)
			(xy 359.894191 -276.627349) (xy 359.935382 -276.66304) (xy 359.971073 -276.704231) (xy 360.000539 -276.750081)
			(xy 360.023181 -276.799658) (xy 360.038536 -276.851953) (xy 360.046292 -276.905901) (xy 360.046778 -276.933152)
			(xy 360.046352 -276.959467) (xy 360.03911 -277.011598) (xy 360.024783 -277.062242) (xy 360.003643 -277.110441)
			(xy 359.976089 -277.155283) (xy 359.942643 -277.195921) (xy 359.923588 -277.214076) (xy 359.916193 -277.221603)
			(xy 359.907665 -277.240879) (xy 359.907078 -277.251414) (xy 359.907078 -277.32609) (xy 359.907605 -277.33664)
			(xy 359.916142 -277.355935) (xy 359.923588 -277.363428) (xy 359.942648 -277.381579) (xy 359.976105 -277.42221)
			(xy 360.003664 -277.467051) (xy 360.024802 -277.515252) (xy 360.039118 -277.565901) (xy 360.046341 -277.618036)
			(xy 360.046778 -277.644352) (xy 360.046292 -277.671603) (xy 360.038536 -277.725551) (xy 360.023181 -277.777846)
			(xy 360.000539 -277.827423) (xy 359.971073 -277.873273) (xy 359.935382 -277.914464) (xy 359.894191 -277.950155)
			(xy 359.848341 -277.979621) (xy 359.798764 -278.002263) (xy 359.746469 -278.017618) (xy 359.692521 -278.025374)
			(xy 359.638019 -278.025374) (xy 359.584071 -278.017618) (xy 359.531776 -278.002263) (xy 359.482199 -277.979621)
			(xy 359.436349 -277.950155) (xy 359.395158 -277.914464) (xy 359.359467 -277.873273) (xy 359.330001 -277.827423)
			(xy 359.307359 -277.777846) (xy 359.292004 -277.725551) (xy 359.284248 -277.671603) (xy 359.283762 -277.644352)
			(xy 353.961349 -277.644352) (xy 353.946655 -277.693191) (xy 353.922983 -277.743688) (xy 353.89221 -277.790201)
			(xy 353.854993 -277.831738) (xy 353.812125 -277.867413) (xy 353.764519 -277.896467) (xy 353.71319 -277.918279)
			(xy 353.659233 -277.932385) (xy 353.603796 -277.938485) (xy 353.548062 -277.936448) (xy 353.493219 -277.926318)
			(xy 353.440435 -277.908311) (xy 353.390835 -277.88281) (xy 353.345477 -277.850359) (xy 353.305328 -277.81165)
			(xy 353.271242 -277.767507) (xy 353.243946 -277.718872) (xy 353.224023 -277.666781) (xy 353.211897 -277.612344)
			(xy 353.207826 -277.556722) (xy 353.040313 -277.556722) (xy 353.047575 -277.606618) (xy 353.048062 -277.634192)
			(xy 353.047576 -277.661443) (xy 353.03982 -277.715391) (xy 353.024465 -277.767686) (xy 353.001823 -277.817263)
			(xy 352.972357 -277.863113) (xy 352.936666 -277.904304) (xy 352.895475 -277.939995) (xy 352.849625 -277.969461)
			(xy 352.800048 -277.992103) (xy 352.747753 -278.007458) (xy 352.693805 -278.015214) (xy 352.639303 -278.015214)
			(xy 352.585355 -278.007458) (xy 352.53306 -277.992103) (xy 352.483483 -277.969461) (xy 352.437633 -277.939995)
			(xy 352.396442 -277.904304) (xy 352.360751 -277.863113) (xy 352.331285 -277.817263) (xy 352.308643 -277.767686)
			(xy 352.293288 -277.715391) (xy 352.285532 -277.661443) (xy 352.285046 -277.634192) (xy 343.387511 -277.634192)
			(xy 343.38768 -277.644352) (xy 343.3872 -277.671605) (xy 343.379449 -277.725557) (xy 343.364097 -277.777856)
			(xy 343.341458 -277.827438) (xy 343.311993 -277.873293) (xy 343.276301 -277.914486) (xy 343.235109 -277.950181)
			(xy 343.189255 -277.979649) (xy 343.139675 -278.00229) (xy 343.087376 -278.017645) (xy 343.033425 -278.025399)
			(xy 343.006172 -278.02586) (xy 342.979701 -278.025468) (xy 342.927265 -278.01817) (xy 342.876343 -278.00369)
			(xy 342.827912 -277.982306) (xy 342.782904 -277.95443) (xy 342.742184 -277.920597) (xy 342.706535 -277.881457)
			(xy 342.676641 -277.837764) (xy 342.653077 -277.790356) (xy 342.636297 -277.740144) (xy 342.631014 -277.714202)
			(xy 342.628728 -277.701756) (xy 342.613488 -277.682452) (xy 342.513666 -277.638002) (xy 342.488774 -277.63978)
			(xy 342.478106 -277.646384) (xy 342.455508 -277.659731) (xy 342.40744 -277.680798) (xy 342.356939 -277.695082)
			(xy 342.304957 -277.702314) (xy 342.278716 -277.702772) (xy 342.278208 -277.702772) (xy 342.250954 -277.702337)
			(xy 342.197 -277.69458) (xy 342.144699 -277.679223) (xy 342.095117 -277.656579) (xy 342.049262 -277.627109)
			(xy 342.008068 -277.591412) (xy 341.972374 -277.550216) (xy 341.942907 -277.504359) (xy 341.920267 -277.454774)
			(xy 341.904914 -277.402473) (xy 341.897161 -277.348518) (xy 341.8967 -277.321264) (xy 341.897145 -277.293893)
			(xy 341.904968 -277.239713) (xy 341.920462 -277.18721) (xy 341.943308 -277.137463) (xy 341.973037 -277.091497)
			(xy 341.99068 -277.070566) (xy 341.990934 -277.070312) (xy 341.996525 -277.063229) (xy 342.002768 -277.046309)
			(xy 342.003126 -277.037292) (xy 342.003126 -276.970236) (xy 342.002746 -276.961222) (xy 341.996514 -276.944305)
			(xy 341.990934 -276.937216) (xy 341.99068 -276.937216) (xy 341.99068 -276.936962) (xy 341.973053 -276.91602)
			(xy 341.94334 -276.87005) (xy 341.920502 -276.820305) (xy 341.905008 -276.767806) (xy 341.897176 -276.713632)
			(xy 341.8967 -276.686264) (xy 341.89728 -276.656788) (xy 341.906339 -276.598537) (xy 341.924252 -276.542372)
			(xy 341.950593 -276.489632) (xy 341.984733 -276.441573) (xy 342.004904 -276.420072) (xy 342.011444 -276.412742)
			(xy 342.018886 -276.394578) (xy 342.019382 -276.384766) (xy 342.019382 -276.331426) (xy 342.012016 -276.324568)
			(xy 342.004674 -276.318043) (xy 341.986519 -276.310593) (xy 341.97671 -276.31009) (xy 341.944706 -276.31009)
			(xy 341.934893 -276.310591) (xy 341.916729 -276.318026) (xy 341.9094 -276.324568) (xy 341.887903 -276.344744)
			(xy 341.839843 -276.378888) (xy 341.787102 -276.405234) (xy 341.730938 -276.423154) (xy 341.672685 -276.432223)
			(xy 341.643208 -276.432772) (xy 341.615954 -276.432337) (xy 341.562 -276.42458) (xy 341.509699 -276.409223)
			(xy 341.460117 -276.386579) (xy 341.414262 -276.357109) (xy 341.373068 -276.321412) (xy 341.337374 -276.280216)
			(xy 341.307907 -276.234359) (xy 341.285267 -276.184774) (xy 341.269914 -276.132473) (xy 341.262161 -276.078518)
			(xy 341.2617 -276.051264) (xy 337.82889 -276.051264) (xy 337.82889 -276.062948) (xy 337.829419 -276.074581)
			(xy 337.839615 -276.09549) (xy 337.848448 -276.10308) (xy 337.870932 -276.12127) (xy 337.910665 -276.163292)
			(xy 337.943602 -276.210827) (xy 337.96899 -276.262788) (xy 337.986247 -276.317985) (xy 337.994978 -276.375154)
			(xy 337.995514 -276.40407) (xy 337.995017 -276.431322) (xy 337.987264 -276.485271) (xy 337.971912 -276.537568)
			(xy 337.949274 -276.587148) (xy 337.919809 -276.633001) (xy 337.884119 -276.674194) (xy 337.84293 -276.709888)
			(xy 337.797079 -276.739356) (xy 337.747502 -276.762) (xy 337.695206 -276.777356) (xy 337.641258 -276.785114)
			(xy 337.614006 -276.785578) (xy 337.585089 -276.785064) (xy 337.527917 -276.776335) (xy 337.472718 -276.759077)
			(xy 337.420756 -276.733684) (xy 337.373222 -276.70074) (xy 337.331206 -276.660998) (xy 337.313016 -276.638512)
			(xy 337.30539 -276.629724) (xy 337.284504 -276.619529) (xy 337.272884 -276.618954) (xy 337.193128 -276.618954)
			(xy 337.181497 -276.619505) (xy 337.160586 -276.629683) (xy 337.152996 -276.638512) (xy 337.142965 -276.651117)
			(xy 337.121089 -276.674769) (xy 337.109308 -276.685756) (xy 337.100418 -276.693884) (xy 337.091782 -276.715982)
			(xy 337.100418 -276.808692) (xy 337.102114 -276.820317) (xy 337.114422 -276.840299) (xy 337.12404 -276.847046)
			(xy 337.124294 -276.8473) (xy 337.147602 -276.862308) (xy 337.190041 -276.897972) (xy 337.226868 -276.939406)
			(xy 337.257308 -276.985735) (xy 337.28072 -277.035983) (xy 337.296609 -277.089091) (xy 337.304642 -277.143941)
			(xy 337.305142 -277.171658) (xy 337.304656 -277.198909) (xy 337.2969 -277.252857) (xy 337.281545 -277.305152)
			(xy 337.258903 -277.354729) (xy 337.229437 -277.400579) (xy 337.193746 -277.44177) (xy 337.152555 -277.477461)
			(xy 337.106705 -277.506927) (xy 337.057128 -277.529569) (xy 337.004833 -277.544924) (xy 336.950885 -277.55268)
			(xy 336.896383 -277.55268) (xy 336.842435 -277.544924) (xy 336.79014 -277.529569) (xy 336.740563 -277.506927)
			(xy 336.694713 -277.477461) (xy 336.653522 -277.44177) (xy 336.617831 -277.400579) (xy 336.588365 -277.354729)
			(xy 336.565723 -277.305152) (xy 336.550368 -277.252857) (xy 336.542612 -277.198909) (xy 336.542126 -277.171658)
			(xy 336.542599 -277.14524) (xy 336.549883 -277.09291) (xy 336.564319 -277.042086) (xy 336.585632 -276.99374)
			(xy 336.613413 -276.948798) (xy 336.647131 -276.908121) (xy 336.666332 -276.889972) (xy 336.675222 -276.881844)
			(xy 336.683858 -276.859746) (xy 336.675222 -276.767036) (xy 336.673535 -276.755408) (xy 336.661222 -276.735426)
			(xy 336.6516 -276.728682) (xy 336.651346 -276.728428) (xy 336.62973 -276.71459) (xy 336.590072 -276.682011)
			(xy 336.555155 -276.644394) (xy 336.525613 -276.602425) (xy 336.513424 -276.579838) (xy 336.507836 -276.56917)
			(xy 336.488786 -276.5552) (xy 336.396584 -276.539706) (xy 336.38488 -276.538458) (xy 336.362394 -276.545319)
			(xy 336.353404 -276.552914) (xy 336.35315 -276.553168) (xy 336.334296 -276.57061) (xy 336.292756 -276.600817)
			(xy 336.270346 -276.613366) (xy 336.258408 -276.619716) (xy 336.244184 -276.642068) (xy 336.238342 -276.755606)
			(xy 336.25028 -276.779482) (xy 336.261202 -276.786848) (xy 336.282944 -276.802182) (xy 336.322426 -276.83784)
			(xy 336.356574 -276.878636) (xy 336.384724 -276.923779) (xy 336.406331 -276.972394) (xy 336.420976 -277.02354)
			(xy 336.428376 -277.076224) (xy 336.428842 -277.102824) (xy 336.428291 -277.13174) (xy 336.419572 -277.188911)
			(xy 336.402322 -277.24411) (xy 336.376936 -277.296072) (xy 336.343997 -277.343607) (xy 336.30426 -277.385624)
			(xy 336.281776 -277.403814) (xy 336.272968 -277.411421) (xy 336.262786 -277.432322) (xy 336.262218 -277.443946)
			(xy 336.262218 -277.523702) (xy 336.262764 -277.535333) (xy 336.272947 -277.556243) (xy 336.281776 -277.563834)
			(xy 336.304271 -277.582012) (xy 336.344006 -277.624034) (xy 336.376945 -277.671571) (xy 336.402331 -277.723535)
			(xy 336.419585 -277.778735) (xy 336.42831 -277.835907) (xy 336.428842 -277.864824) (xy 336.428356 -277.892075)
			(xy 336.4206 -277.946023) (xy 336.405245 -277.998318) (xy 336.382603 -278.047895) (xy 336.353137 -278.093745)
			(xy 336.317446 -278.134936) (xy 336.276255 -278.170627) (xy 336.230405 -278.200093) (xy 336.180828 -278.222735)
			(xy 336.128533 -278.23809) (xy 336.074585 -278.245846) (xy 336.020083 -278.245846) (xy 335.966135 -278.23809)
			(xy 335.91384 -278.222735) (xy 335.864263 -278.200093) (xy 335.818413 -278.170627) (xy 335.777222 -278.134936)
			(xy 335.741531 -278.093745) (xy 335.712065 -278.047895) (xy 335.689423 -277.998318) (xy 335.674068 -277.946023)
			(xy 335.666312 -277.892075) (xy 335.665826 -277.864824) (xy 331.789532 -277.864824) (xy 331.789532 -280.617168)
			(xy 337.73364 -280.617168) (xy 337.734126 -280.589917) (xy 337.741882 -280.535969) (xy 337.757237 -280.483674)
			(xy 337.779879 -280.434097) (xy 337.809345 -280.388247) (xy 337.845036 -280.347056) (xy 337.886227 -280.311365)
			(xy 337.932077 -280.281899) (xy 337.981654 -280.259257) (xy 338.033949 -280.243902) (xy 338.087897 -280.236146)
			(xy 338.142399 -280.236146) (xy 338.196347 -280.243902) (xy 338.248642 -280.259257) (xy 338.298219 -280.281899)
			(xy 338.344069 -280.311365) (xy 338.38526 -280.347056) (xy 338.420951 -280.388247) (xy 338.450417 -280.434097)
			(xy 338.473059 -280.483674) (xy 338.488414 -280.535969) (xy 338.49617 -280.589917) (xy 338.496656 -280.617168)
			(xy 338.496598 -280.627794) (xy 338.495455 -280.649015) (xy 338.49437 -280.659586) (xy 338.493354 -280.668984)
			(xy 338.49818 -280.687272) (xy 338.544154 -280.750772) (xy 338.549989 -280.758052) (xy 338.565609 -280.768223)
			(xy 338.574634 -280.770584) (xy 338.574888 -280.770584) (xy 338.590382 -280.77414) (xy 338.599902 -280.776057)
			(xy 338.619109 -280.773298) (xy 338.62772 -280.768806) (xy 338.688934 -280.733754) (xy 338.697206 -280.728551)
			(xy 338.709356 -280.713269) (xy 338.712556 -280.704036) (xy 338.712556 -280.703782) (xy 338.720558 -280.677663)
			(xy 338.743109 -280.627908) (xy 338.77253 -280.58188) (xy 338.808218 -280.540522) (xy 338.849443 -280.50468)
			(xy 338.895361 -280.475089) (xy 338.945032 -280.452352) (xy 338.997439 -280.436938) (xy 339.05151 -280.429159)
			(xy 339.078824 -280.4287) (xy 339.103996 -280.42909) (xy 339.153903 -280.435712) (xy 339.202507 -280.448836)
			(xy 339.22589 -280.458164) (xy 339.236034 -280.461859) (xy 339.257598 -280.461342) (xy 339.267546 -280.457148)
			(xy 339.345524 -280.420064) (xy 339.359494 -280.403808) (xy 339.362542 -280.39314) (xy 339.371311 -280.365229)
			(xy 339.396247 -280.312307) (xy 339.428972 -280.263814) (xy 339.468718 -280.220887) (xy 339.514554 -280.184532)
			(xy 339.565404 -280.155604) (xy 339.620075 -280.134781) (xy 339.677285 -280.122551) (xy 339.706458 -280.120344)
			(xy 339.706712 -280.120344) (xy 339.717987 -280.118994) (xy 339.737774 -280.107918) (xy 339.744812 -280.099008)
			(xy 339.797644 -280.02484) (xy 339.801454 -280.002234) (xy 339.798406 -279.991058) (xy 339.791642 -279.965556)
			(xy 339.784375 -279.913298) (xy 339.783928 -279.886918) (xy 339.784414 -279.859667) (xy 339.79217 -279.805719)
			(xy 339.807525 -279.753424) (xy 339.830167 -279.703847) (xy 339.859633 -279.657997) (xy 339.895324 -279.616806)
			(xy 339.936515 -279.581115) (xy 339.982365 -279.551649) (xy 340.031942 -279.529007) (xy 340.084237 -279.513652)
			(xy 340.138185 -279.505896) (xy 340.192687 -279.505896) (xy 340.246635 -279.513652) (xy 340.29893 -279.529007)
			(xy 340.348507 -279.551649) (xy 340.394357 -279.581115) (xy 340.435548 -279.616806) (xy 340.471239 -279.657997)
			(xy 340.500705 -279.703847) (xy 340.523347 -279.753424) (xy 340.538702 -279.805719) (xy 340.546458 -279.859667)
			(xy 340.546944 -279.886918) (xy 340.546465 -279.915793) (xy 340.537781 -279.972886) (xy 340.520585 -280.028016)
			(xy 340.495269 -280.079921) (xy 340.462413 -280.127413) (xy 340.422769 -280.169405) (xy 340.377244 -280.204938)
			(xy 340.326881 -280.233196) (xy 340.272831 -280.253534) (xy 340.216331 -280.265486) (xy 340.187534 -280.267664)
			(xy 340.18728 -280.267664) (xy 340.176012 -280.269044) (xy 340.156226 -280.280102) (xy 340.14918 -280.289)
			(xy 340.096348 -280.363168) (xy 340.092538 -280.385774) (xy 340.095586 -280.39695) (xy 340.102351 -280.422452)
			(xy 340.109618 -280.47471) (xy 340.110064 -280.50109) (xy 340.109297 -280.535173) (xy 340.097165 -280.602251)
			(xy 340.09196 -280.617168) (xy 345.894152 -280.617168) (xy 345.894638 -280.589917) (xy 345.902394 -280.535969)
			(xy 345.917749 -280.483674) (xy 345.940391 -280.434097) (xy 345.969857 -280.388247) (xy 346.005548 -280.347056)
			(xy 346.046739 -280.311365) (xy 346.092589 -280.281899) (xy 346.142166 -280.259257) (xy 346.194461 -280.243902)
			(xy 346.248409 -280.236146) (xy 346.302911 -280.236146) (xy 346.356859 -280.243902) (xy 346.409154 -280.259257)
			(xy 346.458731 -280.281899) (xy 346.504581 -280.311365) (xy 346.545772 -280.347056) (xy 346.581463 -280.388247)
			(xy 346.610929 -280.434097) (xy 346.633571 -280.483674) (xy 346.648926 -280.535969) (xy 346.656682 -280.589917)
			(xy 346.657168 -280.617168) (xy 346.65711 -280.627794) (xy 346.655967 -280.649015) (xy 346.654882 -280.659586)
			(xy 346.653866 -280.668984) (xy 346.658692 -280.687272) (xy 346.704666 -280.750772) (xy 346.710497 -280.758056)
			(xy 346.72612 -280.768224) (xy 346.735146 -280.770584) (xy 346.7354 -280.770584) (xy 346.750894 -280.77414)
			(xy 346.76042 -280.776008) (xy 346.77962 -280.773282) (xy 346.788232 -280.768806) (xy 346.849446 -280.733754)
			(xy 346.85772 -280.728555) (xy 346.869869 -280.71327) (xy 346.873068 -280.704036) (xy 346.873068 -280.703782)
			(xy 346.881148 -280.67769) (xy 346.903692 -280.627939) (xy 346.933104 -280.581914) (xy 346.968783 -280.540557)
			(xy 347.009998 -280.504714) (xy 347.055905 -280.475119) (xy 347.105566 -280.452377) (xy 347.157964 -280.436954)
			(xy 347.212026 -280.429165) (xy 347.239336 -280.4287) (xy 347.264508 -280.429087) (xy 347.314415 -280.435709)
			(xy 347.363019 -280.448835) (xy 347.386402 -280.458164) (xy 347.396544 -280.461866) (xy 347.41811 -280.461344)
			(xy 347.428058 -280.457148) (xy 347.506036 -280.420064) (xy 347.520006 -280.403808) (xy 347.523054 -280.39314)
			(xy 347.531813 -280.365226) (xy 347.55675 -280.312303) (xy 347.589476 -280.263809) (xy 347.629224 -280.220882)
			(xy 347.675062 -280.184528) (xy 347.725913 -280.155601) (xy 347.780586 -280.134779) (xy 347.837797 -280.12255)
			(xy 347.86697 -280.120344) (xy 347.867224 -280.120344) (xy 347.8785 -280.119) (xy 347.898286 -280.10792)
			(xy 347.905324 -280.099008) (xy 347.958156 -280.02484) (xy 347.961966 -280.002234) (xy 347.958918 -279.991058)
			(xy 347.952155 -279.965556) (xy 347.944887 -279.913298) (xy 347.94444 -279.886918) (xy 347.944926 -279.859667)
			(xy 347.952682 -279.805719) (xy 347.968037 -279.753424) (xy 347.990679 -279.703847) (xy 348.020145 -279.657997)
			(xy 348.055836 -279.616806) (xy 348.097027 -279.581115) (xy 348.142877 -279.551649) (xy 348.192454 -279.529007)
			(xy 348.244749 -279.513652) (xy 348.298697 -279.505896) (xy 348.353199 -279.505896) (xy 348.407147 -279.513652)
			(xy 348.459442 -279.529007) (xy 348.509019 -279.551649) (xy 348.554869 -279.581115) (xy 348.59606 -279.616806)
			(xy 348.631751 -279.657997) (xy 348.661217 -279.703847) (xy 348.683859 -279.753424) (xy 348.699214 -279.805719)
			(xy 348.70697 -279.859667) (xy 348.707456 -279.886918) (xy 348.706966 -279.915793) (xy 348.698282 -279.972884)
			(xy 348.681086 -280.028013) (xy 348.655771 -280.079917) (xy 348.622917 -280.127409) (xy 348.583274 -280.169402)
			(xy 348.537751 -280.204934) (xy 348.487389 -280.233193) (xy 348.433341 -280.253532) (xy 348.376843 -280.265485)
			(xy 348.348046 -280.267664) (xy 348.347792 -280.267664) (xy 348.336525 -280.26905) (xy 348.316738 -280.280103)
			(xy 348.309692 -280.289) (xy 348.25686 -280.363168) (xy 348.25305 -280.385774) (xy 348.256098 -280.39695)
			(xy 348.262863 -280.422452) (xy 348.27013 -280.47471) (xy 348.270576 -280.50109) (xy 348.269808 -280.535173)
			(xy 348.257676 -280.602251) (xy 348.252472 -280.617168) (xy 354.392738 -280.617168) (xy 354.393224 -280.589917)
			(xy 354.40098 -280.535969) (xy 354.416335 -280.483674) (xy 354.438977 -280.434097) (xy 354.468443 -280.388247)
			(xy 354.504134 -280.347056) (xy 354.545325 -280.311365) (xy 354.591175 -280.281899) (xy 354.640752 -280.259257)
			(xy 354.693047 -280.243902) (xy 354.746995 -280.236146) (xy 354.801497 -280.236146) (xy 354.855445 -280.243902)
			(xy 354.90774 -280.259257) (xy 354.957317 -280.281899) (xy 355.003167 -280.311365) (xy 355.044358 -280.347056)
			(xy 355.080049 -280.388247) (xy 355.109515 -280.434097) (xy 355.132157 -280.483674) (xy 355.147512 -280.535969)
			(xy 355.155268 -280.589917) (xy 355.155754 -280.617168) (xy 355.155696 -280.627794) (xy 355.154553 -280.649015)
			(xy 355.153468 -280.659586) (xy 355.152452 -280.668984) (xy 355.157278 -280.687272) (xy 355.203252 -280.750772)
			(xy 355.209088 -280.758052) (xy 355.224707 -280.768222) (xy 355.233732 -280.770584) (xy 355.233986 -280.770584)
			(xy 355.24948 -280.77414) (xy 355.259 -280.776056) (xy 355.278207 -280.773298) (xy 355.286818 -280.768806)
			(xy 355.348032 -280.733754) (xy 355.356304 -280.728551) (xy 355.368454 -280.713269) (xy 355.371654 -280.704036)
			(xy 355.371654 -280.703782) (xy 355.379657 -280.677664) (xy 355.402208 -280.627909) (xy 355.431629 -280.581881)
			(xy 355.467317 -280.540523) (xy 355.508542 -280.504681) (xy 355.55446 -280.475089) (xy 355.604131 -280.452353)
			(xy 355.656538 -280.436938) (xy 355.710608 -280.429159) (xy 355.737922 -280.4287) (xy 355.763094 -280.429091)
			(xy 355.813001 -280.435712) (xy 355.861605 -280.448836) (xy 355.884988 -280.458164) (xy 355.895133 -280.461858)
			(xy 355.916696 -280.461341) (xy 355.926644 -280.457148) (xy 356.004622 -280.420064) (xy 356.018592 -280.403808)
			(xy 356.02164 -280.39314) (xy 356.03041 -280.36523) (xy 356.055346 -280.312308) (xy 356.088071 -280.263814)
			(xy 356.127817 -280.220887) (xy 356.173653 -280.184533) (xy 356.224503 -280.155605) (xy 356.279174 -280.134781)
			(xy 356.336383 -280.122551) (xy 356.365556 -280.120344) (xy 356.36581 -280.120344) (xy 356.377085 -280.118993)
			(xy 356.396872 -280.107918) (xy 356.40391 -280.099008) (xy 356.456742 -280.02484) (xy 356.460552 -280.002234)
			(xy 356.457504 -279.991058) (xy 356.45074 -279.965556) (xy 356.443473 -279.913298) (xy 356.443026 -279.886918)
			(xy 356.443512 -279.859667) (xy 356.451268 -279.805719) (xy 356.466623 -279.753424) (xy 356.489265 -279.703847)
			(xy 356.518731 -279.657997) (xy 356.554422 -279.616806) (xy 356.595613 -279.581115) (xy 356.641463 -279.551649)
			(xy 356.69104 -279.529007) (xy 356.743335 -279.513652) (xy 356.797283 -279.505896) (xy 356.851785 -279.505896)
			(xy 356.905733 -279.513652) (xy 356.958028 -279.529007) (xy 357.007605 -279.551649) (xy 357.053455 -279.581115)
			(xy 357.094646 -279.616806) (xy 357.130337 -279.657997) (xy 357.159803 -279.703847) (xy 357.182445 -279.753424)
			(xy 357.1978 -279.805719) (xy 357.205556 -279.859667) (xy 357.206042 -279.886918) (xy 357.205565 -279.915793)
			(xy 357.196881 -279.972886) (xy 357.179684 -280.028016) (xy 357.154368 -280.079921) (xy 357.121512 -280.127413)
			(xy 357.081868 -280.169406) (xy 357.036343 -280.204938) (xy 356.985979 -280.233196) (xy 356.931929 -280.253534)
			(xy 356.87543 -280.265486) (xy 356.846632 -280.267664) (xy 356.846378 -280.267664) (xy 356.83511 -280.269043)
			(xy 356.815323 -280.280101) (xy 356.808278 -280.289) (xy 356.755446 -280.363168) (xy 356.751636 -280.385774)
			(xy 356.754684 -280.39695) (xy 356.761449 -280.422452) (xy 356.768716 -280.47471) (xy 356.769162 -280.50109)
			(xy 356.768395 -280.535173) (xy 356.756263 -280.602251) (xy 356.751058 -280.617168) (xy 362.55325 -280.617168)
			(xy 362.553736 -280.589917) (xy 362.561492 -280.535969) (xy 362.576847 -280.483674) (xy 362.599489 -280.434097)
			(xy 362.628955 -280.388247) (xy 362.664646 -280.347056) (xy 362.705837 -280.311365) (xy 362.751687 -280.281899)
			(xy 362.801264 -280.259257) (xy 362.853559 -280.243902) (xy 362.907507 -280.236146) (xy 362.962009 -280.236146)
			(xy 363.015957 -280.243902) (xy 363.068252 -280.259257) (xy 363.117829 -280.281899) (xy 363.163679 -280.311365)
			(xy 363.20487 -280.347056) (xy 363.240561 -280.388247) (xy 363.270027 -280.434097) (xy 363.292669 -280.483674)
			(xy 363.308024 -280.535969) (xy 363.31578 -280.589917) (xy 363.316266 -280.617168) (xy 363.316208 -280.627794)
			(xy 363.315065 -280.649015) (xy 363.31398 -280.659586) (xy 363.312964 -280.668984) (xy 363.31779 -280.687272)
			(xy 363.363764 -280.750772) (xy 363.369595 -280.758056) (xy 363.385218 -280.768224) (xy 363.394244 -280.770584)
			(xy 363.394498 -280.770584) (xy 363.409992 -280.77414) (xy 363.419518 -280.776007) (xy 363.438718 -280.773282)
			(xy 363.44733 -280.768806) (xy 363.508544 -280.733754) (xy 363.516818 -280.728554) (xy 363.528967 -280.71327)
			(xy 363.532166 -280.704036) (xy 363.532166 -280.703782) (xy 363.540248 -280.67769) (xy 363.562792 -280.62794)
			(xy 363.592204 -280.581915) (xy 363.627882 -280.540558) (xy 363.669097 -280.504715) (xy 363.715004 -280.47512)
			(xy 363.764665 -280.452378) (xy 363.817062 -280.436954) (xy 363.871124 -280.429166) (xy 363.898434 -280.4287)
			(xy 363.923606 -280.429087) (xy 363.973513 -280.43571) (xy 364.022117 -280.448835) (xy 364.0455 -280.458164)
			(xy 364.055643 -280.461865) (xy 364.077208 -280.461344) (xy 364.087156 -280.457148) (xy 364.165134 -280.420064)
			(xy 364.179104 -280.403808) (xy 364.182152 -280.39314) (xy 364.190912 -280.365226) (xy 364.215849 -280.312304)
			(xy 364.248575 -280.26381) (xy 364.288323 -280.220883) (xy 364.33416 -280.184529) (xy 364.385012 -280.155602)
			(xy 364.439684 -280.134779) (xy 364.496895 -280.12255) (xy 364.526068 -280.120344) (xy 364.526322 -280.120344)
			(xy 364.537598 -280.118999) (xy 364.557384 -280.10792) (xy 364.564422 -280.099008) (xy 364.617254 -280.02484)
			(xy 364.621064 -280.002234) (xy 364.618016 -279.991058) (xy 364.611252 -279.965556) (xy 364.603985 -279.913298)
			(xy 364.603538 -279.886918) (xy 364.604024 -279.859667) (xy 364.61178 -279.805719) (xy 364.627135 -279.753424)
			(xy 364.649777 -279.703847) (xy 364.679243 -279.657997) (xy 364.714934 -279.616806) (xy 364.756125 -279.581115)
			(xy 364.801975 -279.551649) (xy 364.851552 -279.529007) (xy 364.903847 -279.513652) (xy 364.957795 -279.505896)
			(xy 365.012297 -279.505896) (xy 365.066245 -279.513652) (xy 365.11854 -279.529007) (xy 365.168117 -279.551649)
			(xy 365.213967 -279.581115) (xy 365.255158 -279.616806) (xy 365.290849 -279.657997) (xy 365.320315 -279.703847)
			(xy 365.342957 -279.753424) (xy 365.358312 -279.805719) (xy 365.366068 -279.859667) (xy 365.366554 -279.886918)
			(xy 365.366066 -279.915793) (xy 365.357382 -279.972885) (xy 365.340186 -280.028014) (xy 365.314871 -280.079918)
			(xy 365.282016 -280.12741) (xy 365.242373 -280.169402) (xy 365.19685 -280.204934) (xy 365.146488 -280.233193)
			(xy 365.092439 -280.253532) (xy 365.035941 -280.265485) (xy 365.007144 -280.267664) (xy 365.00689 -280.267664)
			(xy 364.995623 -280.269049) (xy 364.975836 -280.280103) (xy 364.96879 -280.289) (xy 364.915958 -280.363168)
			(xy 364.912148 -280.385774) (xy 364.915196 -280.39695) (xy 364.921961 -280.422452) (xy 364.929228 -280.47471)
			(xy 364.929674 -280.50109) (xy 364.928906 -280.535173) (xy 364.916774 -280.602251) (xy 364.905544 -280.63444)
			(xy 364.901226 -280.64587) (xy 364.903766 -280.669492) (xy 364.96117 -280.758138) (xy 364.981998 -280.77033)
			(xy 364.993936 -280.771092) (xy 365.022544 -280.773549) (xy 365.078611 -280.785929) (xy 365.13219 -280.806569)
			(xy 365.182073 -280.835001) (xy 365.227134 -280.870586) (xy 365.266356 -280.912519) (xy 365.298854 -280.959855)
			(xy 365.323894 -281.011524) (xy 365.325503 -281.01671) (xy 366.057178 -281.01671) (xy 366.061249 -280.961088)
			(xy 366.073375 -280.906651) (xy 366.093298 -280.85456) (xy 366.120594 -280.805925) (xy 366.15468 -280.761782)
			(xy 366.194829 -280.723073) (xy 366.240187 -280.690622) (xy 366.289787 -280.665121) (xy 366.342571 -280.647114)
			(xy 366.397414 -280.636984) (xy 366.453148 -280.634947) (xy 366.508585 -280.641047) (xy 366.562542 -280.655153)
			(xy 366.613871 -280.676965) (xy 366.661477 -280.706019) (xy 366.704345 -280.741694) (xy 366.741562 -280.783231)
			(xy 366.772335 -280.829744) (xy 366.796007 -280.880241) (xy 366.812075 -280.933648) (xy 366.820195 -280.988824)
			(xy 366.820704 -281.01671) (xy 366.820195 -281.044596) (xy 366.812075 -281.099772) (xy 366.796007 -281.153179)
			(xy 366.772335 -281.203676) (xy 366.741562 -281.250189) (xy 366.704345 -281.291726) (xy 366.661477 -281.327401)
			(xy 366.613871 -281.356455) (xy 366.562542 -281.378267) (xy 366.508585 -281.392373) (xy 366.453148 -281.398473)
			(xy 366.397414 -281.396436) (xy 366.342571 -281.386306) (xy 366.289787 -281.368299) (xy 366.240187 -281.342798)
			(xy 366.194829 -281.310347) (xy 366.15468 -281.271638) (xy 366.120594 -281.227495) (xy 366.093298 -281.17886)
			(xy 366.073375 -281.126769) (xy 366.061249 -281.072332) (xy 366.057178 -281.01671) (xy 365.325503 -281.01671)
			(xy 365.340911 -281.066362) (xy 365.349521 -281.123129) (xy 365.350044 -281.151838) (xy 365.349558 -281.179089)
			(xy 365.341802 -281.233037) (xy 365.326447 -281.285332) (xy 365.303805 -281.334909) (xy 365.274339 -281.380759)
			(xy 365.238648 -281.42195) (xy 365.197457 -281.457641) (xy 365.151607 -281.487107) (xy 365.10203 -281.509749)
			(xy 365.049735 -281.525104) (xy 364.995787 -281.53286) (xy 364.941285 -281.53286) (xy 364.887337 -281.525104)
			(xy 364.835042 -281.509749) (xy 364.785465 -281.487107) (xy 364.739615 -281.457641) (xy 364.698424 -281.42195)
			(xy 364.662733 -281.380759) (xy 364.633267 -281.334909) (xy 364.610625 -281.285332) (xy 364.59527 -281.233037)
			(xy 364.587514 -281.179089) (xy 364.587028 -281.151838) (xy 364.587777 -281.117754) (xy 364.599921 -281.050676)
			(xy 364.611158 -281.018488) (xy 364.615476 -281.007058) (xy 364.612936 -280.983436) (xy 364.555532 -280.89479)
			(xy 364.534704 -280.882598) (xy 364.522766 -280.881836) (xy 364.491468 -280.879091) (xy 364.430323 -280.86467)
			(xy 364.4011 -280.853134) (xy 364.390957 -280.849433) (xy 364.369392 -280.849954) (xy 364.359444 -280.85415)
			(xy 364.281466 -280.891234) (xy 364.267496 -280.90749) (xy 364.264448 -280.918158) (xy 364.256256 -280.94413)
			(xy 364.233577 -280.99364) (xy 364.204088 -281.039422) (xy 364.168389 -281.080545) (xy 364.127205 -281.116175)
			(xy 364.081373 -281.145586) (xy 364.031825 -281.168182) (xy 363.979568 -281.183502) (xy 363.925663 -281.191237)
			(xy 363.898434 -281.191716) (xy 363.875078 -281.191348) (xy 363.828719 -281.185619) (xy 363.805978 -281.180286)
			(xy 363.796454 -281.178399) (xy 363.777251 -281.181137) (xy 363.76864 -281.18562) (xy 363.707426 -281.220672)
			(xy 363.699158 -281.22588) (xy 363.687004 -281.241158) (xy 363.683804 -281.25039) (xy 363.683804 -281.250644)
			(xy 363.675765 -281.27675) (xy 363.653216 -281.326501) (xy 363.623798 -281.372527) (xy 363.588113 -281.413883)
			(xy 363.546893 -281.449725) (xy 363.500981 -281.479318) (xy 363.451315 -281.502058) (xy 363.398914 -281.517477)
			(xy 363.344848 -281.525263) (xy 363.317536 -281.525726) (xy 363.290285 -281.525211) (xy 363.236337 -281.51746)
			(xy 363.184041 -281.502109) (xy 363.134462 -281.479472) (xy 363.08861 -281.45001) (xy 363.047417 -281.414321)
			(xy 363.011723 -281.373134) (xy 362.982254 -281.327285) (xy 362.95961 -281.27771) (xy 362.944252 -281.225416)
			(xy 362.936493 -281.171469) (xy 362.936028 -281.144218) (xy 362.936085 -281.133592) (xy 362.937228 -281.112371)
			(xy 362.938314 -281.1018) (xy 362.93933 -281.092402) (xy 362.934504 -281.074114) (xy 362.88853 -281.010614)
			(xy 362.882703 -281.003326) (xy 362.867077 -280.99316) (xy 362.85805 -280.990802) (xy 362.857796 -280.990802)
			(xy 362.829495 -280.984439) (xy 362.775108 -280.964278) (xy 362.724399 -280.936114) (xy 362.67854 -280.900598)
			(xy 362.638586 -280.858548) (xy 362.605459 -280.810934) (xy 362.579922 -280.758853) (xy 362.562566 -280.703507)
			(xy 362.553789 -280.64617) (xy 362.55325 -280.617168) (xy 356.751058 -280.617168) (xy 356.745032 -280.63444)
			(xy 356.740714 -280.64587) (xy 356.743254 -280.669492) (xy 356.800658 -280.758138) (xy 356.821486 -280.77033)
			(xy 356.833424 -280.771092) (xy 356.862031 -280.773559) (xy 356.918098 -280.785938) (xy 356.971677 -280.806576)
			(xy 357.02156 -280.835007) (xy 357.066621 -280.87059) (xy 357.105843 -280.912522) (xy 357.138341 -280.959857)
			(xy 357.157646 -280.999692) (xy 357.896666 -280.999692) (xy 357.900737 -280.94407) (xy 357.912863 -280.889633)
			(xy 357.932786 -280.837542) (xy 357.960082 -280.788907) (xy 357.994168 -280.744764) (xy 358.034317 -280.706055)
			(xy 358.079675 -280.673604) (xy 358.129275 -280.648103) (xy 358.182059 -280.630096) (xy 358.236902 -280.619966)
			(xy 358.292636 -280.617929) (xy 358.348073 -280.624029) (xy 358.40203 -280.638135) (xy 358.453359 -280.659947)
			(xy 358.500965 -280.689001) (xy 358.543833 -280.724676) (xy 358.58105 -280.766213) (xy 358.611823 -280.812726)
			(xy 358.635495 -280.863223) (xy 358.651563 -280.91663) (xy 358.659683 -280.971806) (xy 358.660192 -280.999692)
			(xy 358.659683 -281.027578) (xy 358.651563 -281.082754) (xy 358.635495 -281.136161) (xy 358.611823 -281.186658)
			(xy 358.58105 -281.233171) (xy 358.543833 -281.274708) (xy 358.500965 -281.310383) (xy 358.453359 -281.339437)
			(xy 358.40203 -281.361249) (xy 358.348073 -281.375355) (xy 358.292636 -281.381455) (xy 358.236902 -281.379418)
			(xy 358.182059 -281.369288) (xy 358.129275 -281.351281) (xy 358.079675 -281.32578) (xy 358.034317 -281.293329)
			(xy 357.994168 -281.25462) (xy 357.960082 -281.210477) (xy 357.932786 -281.161842) (xy 357.912863 -281.109751)
			(xy 357.900737 -281.055314) (xy 357.896666 -280.999692) (xy 357.157646 -280.999692) (xy 357.163381 -281.011526)
			(xy 357.180399 -281.066362) (xy 357.189009 -281.12313) (xy 357.189532 -281.151838) (xy 357.189046 -281.179089)
			(xy 357.18129 -281.233037) (xy 357.165935 -281.285332) (xy 357.143293 -281.334909) (xy 357.113827 -281.380759)
			(xy 357.078136 -281.42195) (xy 357.036945 -281.457641) (xy 356.991095 -281.487107) (xy 356.941518 -281.509749)
			(xy 356.889223 -281.525104) (xy 356.835275 -281.53286) (xy 356.780773 -281.53286) (xy 356.726825 -281.525104)
			(xy 356.67453 -281.509749) (xy 356.624953 -281.487107) (xy 356.579103 -281.457641) (xy 356.537912 -281.42195)
			(xy 356.502221 -281.380759) (xy 356.472755 -281.334909) (xy 356.450113 -281.285332) (xy 356.434758 -281.233037)
			(xy 356.427002 -281.179089) (xy 356.426516 -281.151838) (xy 356.427266 -281.117754) (xy 356.43941 -281.050676)
			(xy 356.450646 -281.018488) (xy 356.454964 -281.007058) (xy 356.452424 -280.983436) (xy 356.39502 -280.89479)
			(xy 356.374192 -280.882598) (xy 356.362254 -280.881836) (xy 356.330956 -280.879094) (xy 356.269811 -280.864671)
			(xy 356.240588 -280.853134) (xy 356.230447 -280.849426) (xy 356.20888 -280.849952) (xy 356.198932 -280.85415)
			(xy 356.120954 -280.891234) (xy 356.106984 -280.90749) (xy 356.103936 -280.918158) (xy 356.095755 -280.944134)
			(xy 356.073075 -280.993644) (xy 356.043585 -281.039426) (xy 356.007884 -281.08055) (xy 355.966699 -281.11618)
			(xy 355.920866 -281.14559) (xy 355.871316 -281.168185) (xy 355.819057 -281.183505) (xy 355.765151 -281.191237)
			(xy 355.737922 -281.191716) (xy 355.714566 -281.191351) (xy 355.668207 -281.18562) (xy 355.645466 -281.180286)
			(xy 355.635943 -281.178393) (xy 355.616739 -281.181135) (xy 355.608128 -281.18562) (xy 355.546914 -281.220672)
			(xy 355.538644 -281.225877) (xy 355.526491 -281.241157) (xy 355.523292 -281.25039) (xy 355.523292 -281.250644)
			(xy 355.515264 -281.276753) (xy 355.492713 -281.326506) (xy 355.463294 -281.372531) (xy 355.427609 -281.413888)
			(xy 355.386387 -281.449729) (xy 355.340473 -281.479322) (xy 355.290806 -281.502061) (xy 355.238403 -281.51748)
			(xy 355.184336 -281.525263) (xy 355.157024 -281.525726) (xy 355.129773 -281.525222) (xy 355.075824 -281.517469)
			(xy 355.023528 -281.502117) (xy 354.973949 -281.479479) (xy 354.928097 -281.450015) (xy 354.886904 -281.414325)
			(xy 354.85121 -281.373137) (xy 354.821741 -281.327288) (xy 354.799098 -281.277711) (xy 354.78374 -281.225417)
			(xy 354.775981 -281.171469) (xy 354.775516 -281.144218) (xy 354.775573 -281.133592) (xy 354.776716 -281.112371)
			(xy 354.777802 -281.1018) (xy 354.778818 -281.092402) (xy 354.773992 -281.074114) (xy 354.728018 -281.010614)
			(xy 354.722196 -281.003322) (xy 354.706566 -280.993159) (xy 354.697538 -280.990802) (xy 354.697284 -280.990802)
			(xy 354.668981 -280.984448) (xy 354.614594 -280.964285) (xy 354.563886 -280.93612) (xy 354.518026 -280.900602)
			(xy 354.478073 -280.858552) (xy 354.444946 -280.810936) (xy 354.41941 -280.758855) (xy 354.402054 -280.703508)
			(xy 354.393277 -280.646171) (xy 354.392738 -280.617168) (xy 348.252472 -280.617168) (xy 348.246446 -280.63444)
			(xy 348.242128 -280.64587) (xy 348.244668 -280.669492) (xy 348.302072 -280.758138) (xy 348.3229 -280.77033)
			(xy 348.334838 -280.771092) (xy 348.363446 -280.773547) (xy 348.419513 -280.785928) (xy 348.473093 -280.806567)
			(xy 348.522976 -280.835) (xy 348.568036 -280.870585) (xy 348.607258 -280.912518) (xy 348.639756 -280.959854)
			(xy 348.664796 -281.011524) (xy 348.666405 -281.01671) (xy 349.39808 -281.01671) (xy 349.402151 -280.961088)
			(xy 349.414277 -280.906651) (xy 349.4342 -280.85456) (xy 349.461496 -280.805925) (xy 349.495582 -280.761782)
			(xy 349.535731 -280.723073) (xy 349.581089 -280.690622) (xy 349.630689 -280.665121) (xy 349.683473 -280.647114)
			(xy 349.738316 -280.636984) (xy 349.79405 -280.634947) (xy 349.849487 -280.641047) (xy 349.903444 -280.655153)
			(xy 349.954773 -280.676965) (xy 350.002379 -280.706019) (xy 350.045247 -280.741694) (xy 350.082464 -280.783231)
			(xy 350.113237 -280.829744) (xy 350.136909 -280.880241) (xy 350.152977 -280.933648) (xy 350.161097 -280.988824)
			(xy 350.161606 -281.01671) (xy 350.161097 -281.044596) (xy 350.152977 -281.099772) (xy 350.136909 -281.153179)
			(xy 350.113237 -281.203676) (xy 350.082464 -281.250189) (xy 350.045247 -281.291726) (xy 350.002379 -281.327401)
			(xy 349.954773 -281.356455) (xy 349.903444 -281.378267) (xy 349.849487 -281.392373) (xy 349.79405 -281.398473)
			(xy 349.738316 -281.396436) (xy 349.683473 -281.386306) (xy 349.630689 -281.368299) (xy 349.581089 -281.342798)
			(xy 349.535731 -281.310347) (xy 349.495582 -281.271638) (xy 349.461496 -281.227495) (xy 349.4342 -281.17886)
			(xy 349.414277 -281.126769) (xy 349.402151 -281.072332) (xy 349.39808 -281.01671) (xy 348.666405 -281.01671)
			(xy 348.681813 -281.066361) (xy 348.690423 -281.123129) (xy 348.690946 -281.151838) (xy 348.69046 -281.179089)
			(xy 348.682704 -281.233037) (xy 348.667349 -281.285332) (xy 348.644707 -281.334909) (xy 348.615241 -281.380759)
			(xy 348.57955 -281.42195) (xy 348.538359 -281.457641) (xy 348.492509 -281.487107) (xy 348.442932 -281.509749)
			(xy 348.390637 -281.525104) (xy 348.336689 -281.53286) (xy 348.282187 -281.53286) (xy 348.228239 -281.525104)
			(xy 348.175944 -281.509749) (xy 348.126367 -281.487107) (xy 348.080517 -281.457641) (xy 348.039326 -281.42195)
			(xy 348.003635 -281.380759) (xy 347.974169 -281.334909) (xy 347.951527 -281.285332) (xy 347.936172 -281.233037)
			(xy 347.928416 -281.179089) (xy 347.92793 -281.151838) (xy 347.928679 -281.117754) (xy 347.940823 -281.050676)
			(xy 347.95206 -281.018488) (xy 347.956378 -281.007058) (xy 347.953838 -280.983436) (xy 347.896434 -280.89479)
			(xy 347.875606 -280.882598) (xy 347.863668 -280.881836) (xy 347.83237 -280.87909) (xy 347.771225 -280.86467)
			(xy 347.742002 -280.853134) (xy 347.731859 -280.849434) (xy 347.710294 -280.849955) (xy 347.700346 -280.85415)
			(xy 347.622368 -280.891234) (xy 347.608398 -280.90749) (xy 347.60535 -280.918158) (xy 347.597156 -280.944129)
			(xy 347.574477 -280.993639) (xy 347.544989 -281.039421) (xy 347.50929 -281.080545) (xy 347.468106 -281.116174)
			(xy 347.422275 -281.145586) (xy 347.372727 -281.168181) (xy 347.320469 -281.183502) (xy 347.266565 -281.191236)
			(xy 347.239336 -281.191716) (xy 347.21598 -281.191348) (xy 347.169622 -281.185619) (xy 347.14688 -281.180286)
			(xy 347.137356 -281.1784) (xy 347.118153 -281.181137) (xy 347.109542 -281.18562) (xy 347.048328 -281.220672)
			(xy 347.04006 -281.225881) (xy 347.027906 -281.241158) (xy 347.024706 -281.25039) (xy 347.024706 -281.250644)
			(xy 347.016665 -281.276749) (xy 346.994116 -281.326501) (xy 346.964698 -281.372526) (xy 346.929014 -281.413882)
			(xy 346.887794 -281.449724) (xy 346.841882 -281.479318) (xy 346.792217 -281.502057) (xy 346.739815 -281.517477)
			(xy 346.68575 -281.525262) (xy 346.658438 -281.525726) (xy 346.631187 -281.525209) (xy 346.577239 -281.517458)
			(xy 346.524943 -281.502108) (xy 346.475364 -281.479471) (xy 346.429512 -281.450009) (xy 346.388319 -281.41432)
			(xy 346.352625 -281.373133) (xy 346.323156 -281.327285) (xy 346.300512 -281.277709) (xy 346.285154 -281.225416)
			(xy 346.277395 -281.171469) (xy 346.27693 -281.144218) (xy 346.276987 -281.133592) (xy 346.27813 -281.112371)
			(xy 346.279216 -281.1018) (xy 346.280232 -281.092402) (xy 346.275406 -281.074114) (xy 346.229432 -281.010614)
			(xy 346.223605 -281.003327) (xy 346.207979 -280.993161) (xy 346.198952 -280.990802) (xy 346.198698 -280.990802)
			(xy 346.170398 -280.984438) (xy 346.11601 -280.964277) (xy 346.065302 -280.936114) (xy 346.019442 -280.900598)
			(xy 345.979488 -280.858548) (xy 345.946361 -280.810934) (xy 345.920825 -280.758853) (xy 345.903468 -280.703507)
			(xy 345.894691 -280.64617) (xy 345.894152 -280.617168) (xy 340.09196 -280.617168) (xy 340.085934 -280.63444)
			(xy 340.081616 -280.64587) (xy 340.084156 -280.669492) (xy 340.14156 -280.758138) (xy 340.162388 -280.77033)
			(xy 340.174326 -280.771092) (xy 340.202934 -280.773558) (xy 340.259 -280.785936) (xy 340.312579 -280.806574)
			(xy 340.362462 -280.835006) (xy 340.407523 -280.87059) (xy 340.446745 -280.912522) (xy 340.479243 -280.959857)
			(xy 340.498548 -280.999692) (xy 341.055196 -280.999692) (xy 341.059267 -280.94407) (xy 341.071393 -280.889633)
			(xy 341.091316 -280.837542) (xy 341.118612 -280.788907) (xy 341.152698 -280.744764) (xy 341.192847 -280.706055)
			(xy 341.238205 -280.673604) (xy 341.287805 -280.648103) (xy 341.340589 -280.630096) (xy 341.395432 -280.619966)
			(xy 341.451166 -280.617929) (xy 341.506603 -280.624029) (xy 341.56056 -280.638135) (xy 341.611889 -280.659947)
			(xy 341.659495 -280.689001) (xy 341.702363 -280.724676) (xy 341.73958 -280.766213) (xy 341.770353 -280.812726)
			(xy 341.794025 -280.863223) (xy 341.810093 -280.91663) (xy 341.818213 -280.971806) (xy 341.818722 -280.999692)
			(xy 341.818213 -281.027578) (xy 341.810093 -281.082754) (xy 341.794025 -281.136161) (xy 341.770353 -281.186658)
			(xy 341.73958 -281.233171) (xy 341.702363 -281.274708) (xy 341.659495 -281.310383) (xy 341.611889 -281.339437)
			(xy 341.56056 -281.361249) (xy 341.506603 -281.375355) (xy 341.451166 -281.381455) (xy 341.395432 -281.379418)
			(xy 341.340589 -281.369288) (xy 341.287805 -281.351281) (xy 341.238205 -281.32578) (xy 341.192847 -281.293329)
			(xy 341.152698 -281.25462) (xy 341.118612 -281.210477) (xy 341.091316 -281.161842) (xy 341.071393 -281.109751)
			(xy 341.059267 -281.055314) (xy 341.055196 -280.999692) (xy 340.498548 -280.999692) (xy 340.504283 -281.011525)
			(xy 340.521301 -281.066362) (xy 340.529911 -281.12313) (xy 340.530434 -281.151838) (xy 340.529948 -281.179089)
			(xy 340.522192 -281.233037) (xy 340.506837 -281.285332) (xy 340.484195 -281.334909) (xy 340.454729 -281.380759)
			(xy 340.419038 -281.42195) (xy 340.377847 -281.457641) (xy 340.331997 -281.487107) (xy 340.28242 -281.509749)
			(xy 340.230125 -281.525104) (xy 340.176177 -281.53286) (xy 340.121675 -281.53286) (xy 340.067727 -281.525104)
			(xy 340.015432 -281.509749) (xy 339.965855 -281.487107) (xy 339.920005 -281.457641) (xy 339.878814 -281.42195)
			(xy 339.843123 -281.380759) (xy 339.813657 -281.334909) (xy 339.791015 -281.285332) (xy 339.77566 -281.233037)
			(xy 339.767904 -281.179089) (xy 339.767418 -281.151838) (xy 339.768168 -281.117754) (xy 339.780312 -281.050676)
			(xy 339.791548 -281.018488) (xy 339.795866 -281.007058) (xy 339.793326 -280.983436) (xy 339.735922 -280.89479)
			(xy 339.715094 -280.882598) (xy 339.703156 -280.881836) (xy 339.671858 -280.879093) (xy 339.610713 -280.864671)
			(xy 339.58149 -280.853134) (xy 339.571349 -280.849427) (xy 339.549782 -280.849952) (xy 339.539834 -280.85415)
			(xy 339.461856 -280.891234) (xy 339.447886 -280.90749) (xy 339.444838 -280.918158) (xy 339.436655 -280.944133)
			(xy 339.413975 -280.993643) (xy 339.384485 -281.039426) (xy 339.348785 -281.080549) (xy 339.3076 -281.116179)
			(xy 339.261767 -281.14559) (xy 339.212218 -281.168185) (xy 339.159959 -281.183504) (xy 339.106053 -281.191237)
			(xy 339.078824 -281.191716) (xy 339.055468 -281.19135) (xy 339.009109 -281.18562) (xy 338.986368 -281.180286)
			(xy 338.976845 -281.178394) (xy 338.957641 -281.181135) (xy 338.94903 -281.18562) (xy 338.887816 -281.220672)
			(xy 338.879546 -281.225878) (xy 338.867393 -281.241157) (xy 338.864194 -281.25039) (xy 338.864194 -281.250644)
			(xy 338.856164 -281.276753) (xy 338.833614 -281.326505) (xy 338.804195 -281.37253) (xy 338.76851 -281.413887)
			(xy 338.727288 -281.449729) (xy 338.681375 -281.479322) (xy 338.631708 -281.50206) (xy 338.579305 -281.517479)
			(xy 338.525238 -281.525263) (xy 338.497926 -281.525726) (xy 338.470675 -281.525221) (xy 338.416726 -281.517468)
			(xy 338.36443 -281.502116) (xy 338.314851 -281.479478) (xy 338.268999 -281.450014) (xy 338.227806 -281.414325)
			(xy 338.192112 -281.373136) (xy 338.162644 -281.327287) (xy 338.14 -281.277711) (xy 338.124642 -281.225417)
			(xy 338.116883 -281.171469) (xy 338.116418 -281.144218) (xy 338.116475 -281.133592) (xy 338.117618 -281.112371)
			(xy 338.118704 -281.1018) (xy 338.11972 -281.092402) (xy 338.114894 -281.074114) (xy 338.06892 -281.010614)
			(xy 338.063097 -281.003323) (xy 338.047468 -280.993159) (xy 338.03844 -280.990802) (xy 338.038186 -280.990802)
			(xy 338.009884 -280.984446) (xy 337.955496 -280.964284) (xy 337.904788 -280.936119) (xy 337.858928 -280.900602)
			(xy 337.818975 -280.858551) (xy 337.785848 -280.810936) (xy 337.760312 -280.758855) (xy 337.742956 -280.703507)
			(xy 337.734179 -280.64617) (xy 337.73364 -280.617168) (xy 331.789532 -280.617168) (xy 331.789532 -282.904438)
			(xy 334.103218 -282.904438) (xy 334.103704 -282.876864) (xy 334.111651 -282.822292) (xy 334.127372 -282.769432)
			(xy 334.150538 -282.719386) (xy 334.180667 -282.673196) (xy 334.217132 -282.631824) (xy 334.237838 -282.613608)
			(xy 334.245916 -282.606056) (xy 334.255267 -282.586042) (xy 334.255872 -282.575) (xy 334.255872 -282.497276)
			(xy 334.255271 -282.486231) (xy 334.24593 -282.466209) (xy 334.237838 -282.458668) (xy 334.217116 -282.440469)
			(xy 334.180645 -282.399098) (xy 334.150513 -282.352906) (xy 334.127349 -282.302856) (xy 334.111635 -282.249991)
			(xy 334.1037 -282.195414) (xy 334.103218 -282.167838) (xy 334.103704 -282.140264) (xy 334.111651 -282.085692)
			(xy 334.127372 -282.032832) (xy 334.150538 -281.982786) (xy 334.180667 -281.936596) (xy 334.217132 -281.895224)
			(xy 334.237838 -281.877008) (xy 334.245916 -281.869456) (xy 334.255267 -281.849442) (xy 334.255872 -281.8384)
			(xy 334.255872 -281.760676) (xy 334.255271 -281.749631) (xy 334.24593 -281.729609) (xy 334.237838 -281.722068)
			(xy 334.217116 -281.703869) (xy 334.180645 -281.662498) (xy 334.150513 -281.616306) (xy 334.127349 -281.566256)
			(xy 334.111635 -281.513391) (xy 334.1037 -281.458814) (xy 334.103218 -281.431238) (xy 334.103691 -281.403985)
			(xy 334.111443 -281.350033) (xy 334.126796 -281.297734) (xy 334.149436 -281.248152) (xy 334.178902 -281.202297)
			(xy 334.214595 -281.161104) (xy 334.255788 -281.125409) (xy 334.301641 -281.095941) (xy 334.351222 -281.0733)
			(xy 334.403521 -281.057946) (xy 334.457473 -281.050192) (xy 334.484726 -281.04973) (xy 334.512583 -281.050207)
			(xy 334.567702 -281.058335) (xy 334.621054 -281.074386) (xy 334.671509 -281.098018) (xy 334.717994 -281.128731)
			(xy 334.759523 -281.165872) (xy 334.795215 -281.208653) (xy 334.824311 -281.256166) (xy 334.846196 -281.307402)
			(xy 334.853788 -281.33421) (xy 334.856074 -281.3431) (xy 334.866742 -281.35834) (xy 334.938624 -281.406092)
			(xy 334.956658 -281.410156) (xy 334.965802 -281.408886) (xy 334.978819 -281.407219) (xy 335.005003 -281.405438)
			(xy 335.018126 -281.40533) (xy 335.031249 -281.405426) (xy 335.057435 -281.407203) (xy 335.07045 -281.408886)
			(xy 335.079594 -281.410156) (xy 335.097628 -281.406092) (xy 335.16951 -281.35834) (xy 335.180178 -281.3431)
			(xy 335.182464 -281.33421) (xy 335.189975 -281.307375) (xy 335.211845 -281.25612) (xy 335.240938 -281.208592)
			(xy 335.276635 -281.165801) (xy 335.318177 -281.128657) (xy 335.36468 -281.097952) (xy 335.415154 -281.074337)
			(xy 335.468527 -281.058315) (xy 335.523663 -281.050228) (xy 335.551526 -281.04973) (xy 335.578781 -281.050131)
			(xy 335.632736 -281.057892) (xy 335.685038 -281.073254) (xy 335.734621 -281.095902) (xy 335.780476 -281.125376)
			(xy 335.821669 -281.161076) (xy 335.857362 -281.202276) (xy 335.886829 -281.248136) (xy 335.909469 -281.297722)
			(xy 335.924821 -281.350026) (xy 335.932574 -281.403983) (xy 335.933034 -281.431238) (xy 335.932564 -281.458537)
			(xy 335.924788 -281.512579) (xy 335.909386 -281.564959) (xy 335.886672 -281.614609) (xy 335.857111 -281.660512)
			(xy 335.839562 -281.681428) (xy 335.833212 -281.688794) (xy 335.826862 -281.706574) (xy 335.830164 -281.795728)
			(xy 335.838038 -281.813508) (xy 335.844896 -281.820112) (xy 335.866027 -281.841742) (xy 335.901827 -281.89047)
			(xy 335.929491 -281.944237) (xy 335.935762 -281.963368) (xy 340.481918 -281.963368) (xy 340.485989 -281.907746)
			(xy 340.498115 -281.853309) (xy 340.518038 -281.801218) (xy 340.545334 -281.752583) (xy 340.57942 -281.70844)
			(xy 340.619569 -281.669731) (xy 340.664927 -281.63728) (xy 340.714527 -281.611779) (xy 340.767311 -281.593772)
			(xy 340.822154 -281.583642) (xy 340.877888 -281.581605) (xy 340.933325 -281.587705) (xy 340.987282 -281.601811)
			(xy 341.038611 -281.623623) (xy 341.086217 -281.652677) (xy 341.129085 -281.688352) (xy 341.166302 -281.729889)
			(xy 341.197075 -281.776402) (xy 341.220747 -281.826899) (xy 341.236815 -281.880306) (xy 341.244935 -281.935482)
			(xy 341.245444 -281.963368) (xy 341.244935 -281.991254) (xy 341.236815 -282.04643) (xy 341.220747 -282.099837)
			(xy 341.197075 -282.150334) (xy 341.166302 -282.196847) (xy 341.129085 -282.238384) (xy 341.086217 -282.274059)
			(xy 341.038611 -282.303113) (xy 340.987282 -282.324925) (xy 340.933325 -282.339031) (xy 340.877888 -282.345131)
			(xy 340.822154 -282.343094) (xy 340.767311 -282.332964) (xy 340.714527 -282.314957) (xy 340.664927 -282.289456)
			(xy 340.619569 -282.257005) (xy 340.57942 -282.218296) (xy 340.545334 -282.174153) (xy 340.518038 -282.125518)
			(xy 340.498115 -282.073427) (xy 340.485989 -282.01899) (xy 340.481918 -281.963368) (xy 335.935762 -281.963368)
			(xy 335.948326 -282.001695) (xy 335.957859 -282.061405) (xy 335.958434 -282.091638) (xy 335.957939 -282.119276)
			(xy 335.949947 -282.173971) (xy 335.934149 -282.226942) (xy 335.910877 -282.277081) (xy 335.880617 -282.323339)
			(xy 335.862676 -282.344368) (xy 335.854294 -282.353766) (xy 335.848452 -282.37815) (xy 335.872582 -282.47213)
			(xy 335.876286 -282.484074) (xy 335.893061 -282.502583) (xy 335.904586 -282.507436) (xy 335.931994 -282.517774)
			(xy 335.983509 -282.545656) (xy 336.030154 -282.581087) (xy 336.070833 -282.623236) (xy 336.104587 -282.671109)
			(xy 336.130623 -282.72358) (xy 336.148329 -282.779417) (xy 336.157288 -282.837304) (xy 336.157824 -282.866592)
			(xy 336.15729 -282.893854) (xy 336.487447 -282.893854) (xy 336.487447 -282.839346) (xy 336.495205 -282.785392)
			(xy 336.510562 -282.733092) (xy 336.533206 -282.68351) (xy 336.562676 -282.637655) (xy 336.598372 -282.596461)
			(xy 336.639568 -282.560767) (xy 336.685424 -282.531299) (xy 336.735007 -282.508657) (xy 336.787308 -282.493302)
			(xy 336.841262 -282.485546) (xy 336.868516 -282.485084) (xy 336.895888 -282.48552) (xy 336.950069 -282.493342)
			(xy 337.002573 -282.508837) (xy 337.052319 -282.531686) (xy 337.098284 -282.561419) (xy 337.119214 -282.579064)
			(xy 337.119468 -282.579318) (xy 337.126558 -282.584899) (xy 337.143472 -282.591149) (xy 337.152488 -282.59151)
			(xy 337.219544 -282.59151) (xy 337.228558 -282.591124) (xy 337.245475 -282.584896) (xy 337.252564 -282.579318)
			(xy 337.252564 -282.579064) (xy 337.252818 -282.579064) (xy 337.273766 -282.561444) (xy 337.319735 -282.531731)
			(xy 337.369478 -282.508892) (xy 337.421975 -282.493396) (xy 337.476148 -282.485562) (xy 337.503516 -282.485084)
			(xy 337.530766 -282.485587) (xy 337.584711 -282.493345) (xy 337.637003 -282.508701) (xy 337.686577 -282.531343)
			(xy 337.732424 -282.560809) (xy 337.773612 -282.5965) (xy 337.809301 -282.637689) (xy 337.838765 -282.683537)
			(xy 337.861404 -282.733112) (xy 337.876758 -282.785405) (xy 337.884514 -282.83935) (xy 337.884514 -282.89385)
			(xy 337.882992 -282.904438) (xy 342.26373 -282.904438) (xy 342.264211 -282.876864) (xy 342.272159 -282.822291)
			(xy 342.28788 -282.769431) (xy 342.311047 -282.719385) (xy 342.341178 -282.673195) (xy 342.377644 -282.631824)
			(xy 342.39835 -282.613608) (xy 342.40643 -282.606057) (xy 342.415779 -282.586042) (xy 342.416384 -282.575)
			(xy 342.416384 -282.497276) (xy 342.415779 -282.486231) (xy 342.40644 -282.466209) (xy 342.39835 -282.458668)
			(xy 342.37761 -282.440488) (xy 342.341144 -282.399112) (xy 342.311017 -282.352915) (xy 342.287857 -282.302861)
			(xy 342.272146 -282.249993) (xy 342.264212 -282.195414) (xy 342.26373 -282.167838) (xy 342.264211 -282.140264)
			(xy 342.272159 -282.085691) (xy 342.28788 -282.032831) (xy 342.311047 -281.982785) (xy 342.341178 -281.936595)
			(xy 342.377644 -281.895224) (xy 342.39835 -281.877008) (xy 342.40643 -281.869457) (xy 342.415779 -281.849442)
			(xy 342.416384 -281.8384) (xy 342.416384 -281.760676) (xy 342.415779 -281.749631) (xy 342.40644 -281.729609)
			(xy 342.39835 -281.722068) (xy 342.37761 -281.703888) (xy 342.341144 -281.662512) (xy 342.311017 -281.616315)
			(xy 342.287857 -281.566261) (xy 342.272146 -281.513393) (xy 342.264212 -281.458814) (xy 342.26373 -281.431238)
			(xy 342.264191 -281.403984) (xy 342.271944 -281.350031) (xy 342.287297 -281.297731) (xy 342.309938 -281.248149)
			(xy 342.339405 -281.202293) (xy 342.375099 -281.161099) (xy 342.416293 -281.125405) (xy 342.462149 -281.095938)
			(xy 342.511731 -281.073297) (xy 342.564031 -281.057944) (xy 342.617984 -281.050191) (xy 342.645238 -281.04973)
			(xy 342.673095 -281.050197) (xy 342.728214 -281.058326) (xy 342.781567 -281.074378) (xy 342.832022 -281.098012)
			(xy 342.878507 -281.128726) (xy 342.920036 -281.165868) (xy 342.955727 -281.20865) (xy 342.984824 -281.256165)
			(xy 343.006708 -281.307402) (xy 343.0143 -281.33421) (xy 343.016586 -281.3431) (xy 343.027254 -281.35834)
			(xy 343.099136 -281.406092) (xy 343.11717 -281.410156) (xy 343.126314 -281.408886) (xy 343.139331 -281.407217)
			(xy 343.165515 -281.405437) (xy 343.178638 -281.40533) (xy 343.191761 -281.405424) (xy 343.217947 -281.407203)
			(xy 343.230962 -281.408886) (xy 343.240106 -281.410156) (xy 343.25814 -281.406092) (xy 343.330022 -281.35834)
			(xy 343.34069 -281.3431) (xy 343.342976 -281.33421) (xy 343.350566 -281.3074) (xy 343.37243 -281.25615)
			(xy 343.401514 -281.208625) (xy 343.437202 -281.165835) (xy 343.478733 -281.128691) (xy 343.525225 -281.097982)
			(xy 343.575689 -281.074362) (xy 343.629052 -281.058332) (xy 343.684179 -281.050234) (xy 343.712038 -281.04973)
			(xy 343.739292 -281.050143) (xy 343.793244 -281.057905) (xy 343.845543 -281.073267) (xy 343.895123 -281.095915)
			(xy 343.940975 -281.125389) (xy 343.982165 -281.161088) (xy 344.017856 -281.202286) (xy 344.047321 -281.248144)
			(xy 344.069959 -281.297729) (xy 344.085311 -281.35003) (xy 344.093063 -281.403984) (xy 344.093546 -281.431238)
			(xy 344.093073 -281.458537) (xy 344.085297 -281.512578) (xy 344.069896 -281.564959) (xy 344.047183 -281.614608)
			(xy 344.017623 -281.660512) (xy 344.000074 -281.681428) (xy 343.993724 -281.688794) (xy 343.987374 -281.706574)
			(xy 343.990676 -281.795728) (xy 343.99855 -281.813508) (xy 344.005408 -281.820112) (xy 344.026523 -281.841756)
			(xy 344.062329 -281.890479) (xy 344.089998 -281.944242) (xy 344.096269 -281.963368) (xy 348.64243 -281.963368)
			(xy 348.646501 -281.907746) (xy 348.658627 -281.853309) (xy 348.67855 -281.801218) (xy 348.705846 -281.752583)
			(xy 348.739932 -281.70844) (xy 348.780081 -281.669731) (xy 348.825439 -281.63728) (xy 348.875039 -281.611779)
			(xy 348.927823 -281.593772) (xy 348.982666 -281.583642) (xy 349.0384 -281.581605) (xy 349.093837 -281.587705)
			(xy 349.147794 -281.601811) (xy 349.199123 -281.623623) (xy 349.246729 -281.652677) (xy 349.289597 -281.688352)
			(xy 349.326814 -281.729889) (xy 349.357587 -281.776402) (xy 349.381259 -281.826899) (xy 349.397327 -281.880306)
			(xy 349.405447 -281.935482) (xy 349.405956 -281.963368) (xy 349.405447 -281.991254) (xy 349.397327 -282.04643)
			(xy 349.381259 -282.099837) (xy 349.357587 -282.150334) (xy 349.326814 -282.196847) (xy 349.289597 -282.238384)
			(xy 349.246729 -282.274059) (xy 349.199123 -282.303113) (xy 349.147794 -282.324925) (xy 349.093837 -282.339031)
			(xy 349.0384 -282.345131) (xy 348.982666 -282.343094) (xy 348.927823 -282.332964) (xy 348.875039 -282.314957)
			(xy 348.825439 -282.289456) (xy 348.780081 -282.257005) (xy 348.739932 -282.218296) (xy 348.705846 -282.174153)
			(xy 348.67855 -282.125518) (xy 348.658627 -282.073427) (xy 348.646501 -282.01899) (xy 348.64243 -281.963368)
			(xy 344.096269 -281.963368) (xy 344.108836 -282.001697) (xy 344.118371 -282.061406) (xy 344.118946 -282.091638)
			(xy 344.118448 -282.119276) (xy 344.110456 -282.173971) (xy 344.094659 -282.226942) (xy 344.071388 -282.27708)
			(xy 344.041128 -282.323338) (xy 344.023188 -282.344368) (xy 344.014806 -282.353766) (xy 344.008964 -282.37815)
			(xy 344.033094 -282.47213) (xy 344.036792 -282.484077) (xy 344.053571 -282.502585) (xy 344.065098 -282.507436)
			(xy 344.092509 -282.517767) (xy 344.144023 -282.545651) (xy 344.190668 -282.581084) (xy 344.231346 -282.623233)
			(xy 344.2651 -282.671107) (xy 344.291136 -282.723579) (xy 344.308841 -282.779416) (xy 344.3178 -282.837304)
			(xy 344.318336 -282.866592) (xy 344.317801 -282.893855) (xy 344.647947 -282.893855) (xy 344.647947 -282.839345)
			(xy 344.655705 -282.785391) (xy 344.671063 -282.73309) (xy 344.693708 -282.683507) (xy 344.723179 -282.637651)
			(xy 344.758877 -282.596457) (xy 344.800074 -282.560763) (xy 344.845931 -282.531295) (xy 344.895516 -282.508653)
			(xy 344.947818 -282.493299) (xy 345.001773 -282.485545) (xy 345.029028 -282.485084) (xy 345.0564 -282.485513)
			(xy 345.110581 -282.493337) (xy 345.163086 -282.508833) (xy 345.212832 -282.531684) (xy 345.258796 -282.561418)
			(xy 345.279726 -282.579064) (xy 345.27998 -282.579318) (xy 345.287067 -282.584904) (xy 345.303983 -282.591151)
			(xy 345.313 -282.59151) (xy 345.380056 -282.59151) (xy 345.389071 -282.59113) (xy 345.405988 -282.584898)
			(xy 345.413076 -282.579318) (xy 345.413076 -282.579064) (xy 345.41333 -282.579064) (xy 345.434273 -282.561439)
			(xy 345.480243 -282.531726) (xy 345.529988 -282.508888) (xy 345.582486 -282.493394) (xy 345.63666 -282.485561)
			(xy 345.664028 -282.485084) (xy 345.691277 -282.485588) (xy 345.745221 -282.493347) (xy 345.797511 -282.508704)
			(xy 345.847084 -282.531347) (xy 345.89293 -282.560813) (xy 345.934116 -282.596504) (xy 345.969804 -282.637693)
			(xy 345.999267 -282.683541) (xy 346.021905 -282.733115) (xy 346.037259 -282.785406) (xy 346.045014 -282.839351)
			(xy 346.045014 -282.893849) (xy 346.043492 -282.904438) (xy 350.762316 -282.904438) (xy 350.762802 -282.876864)
			(xy 350.77075 -282.822292) (xy 350.78647 -282.769432) (xy 350.809637 -282.719386) (xy 350.839766 -282.673196)
			(xy 350.87623 -282.631824) (xy 350.896936 -282.613608) (xy 350.905014 -282.606055) (xy 350.914365 -282.586042)
			(xy 350.91497 -282.575) (xy 350.91497 -282.497276) (xy 350.914369 -282.48623) (xy 350.905028 -282.466208)
			(xy 350.896936 -282.458668) (xy 350.876213 -282.440469) (xy 350.839742 -282.399099) (xy 350.809611 -282.352907)
			(xy 350.786447 -282.302856) (xy 350.770733 -282.249991) (xy 350.762798 -282.195414) (xy 350.762316 -282.167838)
			(xy 350.762802 -282.140264) (xy 350.77075 -282.085692) (xy 350.78647 -282.032832) (xy 350.809637 -281.982786)
			(xy 350.839766 -281.936596) (xy 350.87623 -281.895224) (xy 350.896936 -281.877008) (xy 350.905014 -281.869455)
			(xy 350.914365 -281.849442) (xy 350.91497 -281.8384) (xy 350.91497 -281.760676) (xy 350.914369 -281.74963)
			(xy 350.905028 -281.729608) (xy 350.896936 -281.722068) (xy 350.876213 -281.703869) (xy 350.839742 -281.662499)
			(xy 350.809611 -281.616307) (xy 350.786447 -281.566256) (xy 350.770733 -281.513391) (xy 350.762798 -281.458814)
			(xy 350.762316 -281.431238) (xy 350.762791 -281.403985) (xy 350.770543 -281.350033) (xy 350.785896 -281.297734)
			(xy 350.808535 -281.248153) (xy 350.838002 -281.202298) (xy 350.873694 -281.161104) (xy 350.914887 -281.12541)
			(xy 350.96074 -281.095942) (xy 351.010321 -281.0733) (xy 351.06262 -281.057946) (xy 351.116571 -281.050192)
			(xy 351.143824 -281.04973) (xy 351.171681 -281.050209) (xy 351.226799 -281.058337) (xy 351.280152 -281.074387)
			(xy 351.330606 -281.098019) (xy 351.377091 -281.128732) (xy 351.418621 -281.165872) (xy 351.454312 -281.208653)
			(xy 351.483409 -281.256166) (xy 351.505294 -281.307402) (xy 351.512886 -281.33421) (xy 351.515172 -281.3431)
			(xy 351.52584 -281.35834) (xy 351.597722 -281.406092) (xy 351.615756 -281.410156) (xy 351.6249 -281.408886)
			(xy 351.637917 -281.407219) (xy 351.664101 -281.405438) (xy 351.677224 -281.40533) (xy 351.690347 -281.405426)
			(xy 351.716533 -281.407203) (xy 351.729548 -281.408886) (xy 351.738692 -281.410156) (xy 351.756726 -281.406092)
			(xy 351.828608 -281.35834) (xy 351.839276 -281.3431) (xy 351.841562 -281.33421) (xy 351.849075 -281.307376)
			(xy 351.870945 -281.256121) (xy 351.900038 -281.208593) (xy 351.935734 -281.165802) (xy 351.977276 -281.128658)
			(xy 352.023779 -281.097952) (xy 352.074253 -281.074337) (xy 352.127626 -281.058316) (xy 352.182761 -281.050228)
			(xy 352.210624 -281.04973) (xy 352.237879 -281.050133) (xy 352.291834 -281.057894) (xy 352.344136 -281.073255)
			(xy 352.393718 -281.095903) (xy 352.439573 -281.125377) (xy 352.480767 -281.161077) (xy 352.51646 -281.202276)
			(xy 352.545927 -281.248136) (xy 352.568567 -281.297722) (xy 352.583919 -281.350026) (xy 352.591672 -281.403983)
			(xy 352.592132 -281.431238) (xy 352.591663 -281.458537) (xy 352.583886 -281.512579) (xy 352.568484 -281.564959)
			(xy 352.54577 -281.614609) (xy 352.51621 -281.660512) (xy 352.49866 -281.681428) (xy 352.49231 -281.688794)
			(xy 352.48596 -281.706574) (xy 352.489262 -281.795728) (xy 352.497136 -281.813508) (xy 352.503994 -281.820112)
			(xy 352.525124 -281.841742) (xy 352.560925 -281.890471) (xy 352.588589 -281.944237) (xy 352.59486 -281.963368)
			(xy 357.141016 -281.963368) (xy 357.145087 -281.907746) (xy 357.157213 -281.853309) (xy 357.177136 -281.801218)
			(xy 357.204432 -281.752583) (xy 357.238518 -281.70844) (xy 357.278667 -281.669731) (xy 357.324025 -281.63728)
			(xy 357.373625 -281.611779) (xy 357.426409 -281.593772) (xy 357.481252 -281.583642) (xy 357.536986 -281.581605)
			(xy 357.592423 -281.587705) (xy 357.64638 -281.601811) (xy 357.697709 -281.623623) (xy 357.745315 -281.652677)
			(xy 357.788183 -281.688352) (xy 357.8254 -281.729889) (xy 357.856173 -281.776402) (xy 357.879845 -281.826899)
			(xy 357.895913 -281.880306) (xy 357.904033 -281.935482) (xy 357.904542 -281.963368) (xy 357.904033 -281.991254)
			(xy 357.895913 -282.04643) (xy 357.879845 -282.099837) (xy 357.856173 -282.150334) (xy 357.8254 -282.196847)
			(xy 357.788183 -282.238384) (xy 357.745315 -282.274059) (xy 357.697709 -282.303113) (xy 357.64638 -282.324925)
			(xy 357.592423 -282.339031) (xy 357.536986 -282.345131) (xy 357.481252 -282.343094) (xy 357.426409 -282.332964)
			(xy 357.373625 -282.314957) (xy 357.324025 -282.289456) (xy 357.278667 -282.257005) (xy 357.238518 -282.218296)
			(xy 357.204432 -282.174153) (xy 357.177136 -282.125518) (xy 357.157213 -282.073427) (xy 357.145087 -282.01899)
			(xy 357.141016 -281.963368) (xy 352.59486 -281.963368) (xy 352.607424 -282.001695) (xy 352.616957 -282.061405)
			(xy 352.617532 -282.091638) (xy 352.617037 -282.119276) (xy 352.609045 -282.173971) (xy 352.593248 -282.226942)
			(xy 352.569975 -282.277081) (xy 352.539715 -282.323339) (xy 352.521774 -282.344368) (xy 352.513392 -282.353766)
			(xy 352.50755 -282.37815) (xy 352.53168 -282.47213) (xy 352.535385 -282.484074) (xy 352.552159 -282.502583)
			(xy 352.563684 -282.507436) (xy 352.591092 -282.517775) (xy 352.642607 -282.545657) (xy 352.689252 -282.581088)
			(xy 352.72993 -282.623236) (xy 352.763685 -282.671109) (xy 352.789721 -282.723581) (xy 352.807427 -282.779417)
			(xy 352.816386 -282.837304) (xy 352.816922 -282.866592) (xy 352.816388 -282.893854) (xy 353.146547 -282.893854)
			(xy 353.146547 -282.839346) (xy 353.154305 -282.785393) (xy 353.169662 -282.733093) (xy 353.192306 -282.683511)
			(xy 353.221776 -282.637656) (xy 353.257472 -282.596462) (xy 353.298667 -282.560767) (xy 353.344523 -282.531299)
			(xy 353.394106 -282.508657) (xy 353.446406 -282.493302) (xy 353.50036 -282.485546) (xy 353.527614 -282.485084)
			(xy 353.554986 -282.485521) (xy 353.609167 -282.493343) (xy 353.661671 -282.508838) (xy 353.711417 -282.531686)
			(xy 353.757382 -282.561419) (xy 353.778312 -282.579064) (xy 353.778566 -282.579318) (xy 353.785657 -282.584898)
			(xy 353.80257 -282.591148) (xy 353.811586 -282.59151) (xy 353.878642 -282.59151) (xy 353.887656 -282.591123)
			(xy 353.904573 -282.584896) (xy 353.911662 -282.579318) (xy 353.911662 -282.579064) (xy 353.911916 -282.579064)
			(xy 353.932864 -282.561445) (xy 353.978833 -282.531732) (xy 354.028577 -282.508892) (xy 354.081074 -282.493396)
			(xy 354.135246 -282.485562) (xy 354.162614 -282.485084) (xy 354.189864 -282.485587) (xy 354.243809 -282.493345)
			(xy 354.296101 -282.508701) (xy 354.345676 -282.531342) (xy 354.391523 -282.560808) (xy 354.432711 -282.596499)
			(xy 354.4684 -282.637688) (xy 354.497865 -282.683537) (xy 354.520504 -282.733112) (xy 354.535858 -282.785405)
			(xy 354.543614 -282.83935) (xy 354.543614 -282.89385) (xy 354.542092 -282.904438) (xy 358.922828 -282.904438)
			(xy 358.92331 -282.876864) (xy 358.931258 -282.822291) (xy 358.946979 -282.769431) (xy 358.970146 -282.719385)
			(xy 359.000276 -282.673195) (xy 359.036742 -282.631824) (xy 359.057448 -282.613608) (xy 359.065528 -282.606057)
			(xy 359.074877 -282.586042) (xy 359.075482 -282.575) (xy 359.075482 -282.497276) (xy 359.074877 -282.486231)
			(xy 359.065539 -282.466209) (xy 359.057448 -282.458668) (xy 359.036728 -282.440466) (xy 359.000256 -282.399097)
			(xy 358.970124 -282.352905) (xy 358.946959 -282.302855) (xy 358.931246 -282.24999) (xy 358.92331 -282.195413)
			(xy 358.922828 -282.167838) (xy 358.92331 -282.140264) (xy 358.931258 -282.085691) (xy 358.946979 -282.032831)
			(xy 358.970146 -281.982785) (xy 359.000276 -281.936595) (xy 359.036742 -281.895224) (xy 359.057448 -281.877008)
			(xy 359.065528 -281.869457) (xy 359.074877 -281.849442) (xy 359.075482 -281.8384) (xy 359.075482 -281.760676)
			(xy 359.074877 -281.749631) (xy 359.065539 -281.729609) (xy 359.057448 -281.722068) (xy 359.036728 -281.703866)
			(xy 359.000256 -281.662497) (xy 358.970124 -281.616305) (xy 358.946959 -281.566255) (xy 358.931246 -281.51339)
			(xy 358.92331 -281.458813) (xy 358.922828 -281.431238) (xy 358.923291 -281.403984) (xy 358.931043 -281.350032)
			(xy 358.946397 -281.297732) (xy 358.969037 -281.248149) (xy 358.998505 -281.202294) (xy 359.034199 -281.1611)
			(xy 359.075393 -281.125406) (xy 359.121247 -281.095938) (xy 359.17083 -281.073297) (xy 359.22313 -281.057944)
			(xy 359.277082 -281.050191) (xy 359.304336 -281.04973) (xy 359.332193 -281.050198) (xy 359.387312 -281.058328)
			(xy 359.440665 -281.07438) (xy 359.491119 -281.098013) (xy 359.537604 -281.128727) (xy 359.579133 -281.165869)
			(xy 359.614825 -281.208651) (xy 359.643922 -281.256165) (xy 359.665806 -281.307402) (xy 359.673398 -281.33421)
			(xy 359.675684 -281.3431) (xy 359.686352 -281.35834) (xy 359.758234 -281.406092) (xy 359.776268 -281.410156)
			(xy 359.785412 -281.408886) (xy 359.798429 -281.407218) (xy 359.824613 -281.405437) (xy 359.837736 -281.40533)
			(xy 359.850859 -281.405425) (xy 359.877045 -281.407203) (xy 359.89006 -281.408886) (xy 359.899204 -281.410156)
			(xy 359.917238 -281.406092) (xy 359.98912 -281.35834) (xy 359.999788 -281.3431) (xy 360.002074 -281.33421)
			(xy 360.009666 -281.3074) (xy 360.031529 -281.256151) (xy 360.060614 -281.208626) (xy 360.096301 -281.165836)
			(xy 360.137832 -281.128692) (xy 360.184324 -281.097983) (xy 360.234788 -281.074362) (xy 360.28815 -281.058332)
			(xy 360.343277 -281.050234) (xy 360.371136 -281.04973) (xy 360.398392 -281.050122) (xy 360.452347 -281.057884)
			(xy 360.504649 -281.073247) (xy 360.554231 -281.095896) (xy 360.600086 -281.125372) (xy 360.64128 -281.161073)
			(xy 360.676973 -281.202273) (xy 360.706439 -281.248134) (xy 360.729079 -281.297721) (xy 360.744431 -281.350025)
			(xy 360.752184 -281.403982) (xy 360.752644 -281.431238) (xy 360.752172 -281.458537) (xy 360.744396 -281.512578)
			(xy 360.728994 -281.564959) (xy 360.706281 -281.614608) (xy 360.676721 -281.660512) (xy 360.659172 -281.681428)
			(xy 360.652822 -281.688794) (xy 360.646472 -281.706574) (xy 360.649774 -281.795728) (xy 360.657648 -281.813508)
			(xy 360.664506 -281.820112) (xy 360.685621 -281.841757) (xy 360.721427 -281.89048) (xy 360.749095 -281.944242)
			(xy 360.755366 -281.963368) (xy 365.301528 -281.963368) (xy 365.305599 -281.907746) (xy 365.317725 -281.853309)
			(xy 365.337648 -281.801218) (xy 365.364944 -281.752583) (xy 365.39903 -281.70844) (xy 365.439179 -281.669731)
			(xy 365.484537 -281.63728) (xy 365.534137 -281.611779) (xy 365.586921 -281.593772) (xy 365.641764 -281.583642)
			(xy 365.697498 -281.581605) (xy 365.752935 -281.587705) (xy 365.806892 -281.601811) (xy 365.858221 -281.623623)
			(xy 365.905827 -281.652677) (xy 365.948695 -281.688352) (xy 365.985912 -281.729889) (xy 366.016685 -281.776402)
			(xy 366.040357 -281.826899) (xy 366.056425 -281.880306) (xy 366.064545 -281.935482) (xy 366.065054 -281.963368)
			(xy 366.064545 -281.991254) (xy 366.056425 -282.04643) (xy 366.040357 -282.099837) (xy 366.016685 -282.150334)
			(xy 365.985912 -282.196847) (xy 365.948695 -282.238384) (xy 365.905827 -282.274059) (xy 365.858221 -282.303113)
			(xy 365.806892 -282.324925) (xy 365.752935 -282.339031) (xy 365.697498 -282.345131) (xy 365.641764 -282.343094)
			(xy 365.586921 -282.332964) (xy 365.534137 -282.314957) (xy 365.484537 -282.289456) (xy 365.439179 -282.257005)
			(xy 365.39903 -282.218296) (xy 365.364944 -282.174153) (xy 365.337648 -282.125518) (xy 365.317725 -282.073427)
			(xy 365.305599 -282.01899) (xy 365.301528 -281.963368) (xy 360.755366 -281.963368) (xy 360.767934 -282.001698)
			(xy 360.777469 -282.061406) (xy 360.778044 -282.091638) (xy 360.777546 -282.119276) (xy 360.769554 -282.173971)
			(xy 360.753757 -282.226942) (xy 360.730486 -282.27708) (xy 360.700226 -282.323338) (xy 360.682286 -282.344368)
			(xy 360.673904 -282.353766) (xy 360.668062 -282.37815) (xy 360.692192 -282.47213) (xy 360.695891 -282.484077)
			(xy 360.712669 -282.502585) (xy 360.724196 -282.507436) (xy 360.751606 -282.517769) (xy 360.803121 -282.545652)
			(xy 360.849766 -282.581084) (xy 360.890444 -282.623233) (xy 360.924198 -282.671107) (xy 360.950234 -282.723579)
			(xy 360.967939 -282.779416) (xy 360.976898 -282.837304) (xy 360.977434 -282.866592) (xy 360.976899 -282.893855)
			(xy 361.307047 -282.893855) (xy 361.307047 -282.839345) (xy 361.314805 -282.785391) (xy 361.330163 -282.73309)
			(xy 361.352808 -282.683507) (xy 361.382279 -282.637652) (xy 361.417976 -282.596458) (xy 361.459173 -282.560763)
			(xy 361.50503 -282.531295) (xy 361.554614 -282.508654) (xy 361.606917 -282.4933) (xy 361.660871 -282.485546)
			(xy 361.688126 -282.485084) (xy 361.715498 -282.485514) (xy 361.769679 -282.493338) (xy 361.822183 -282.508834)
			(xy 361.87193 -282.531684) (xy 361.917894 -282.561418) (xy 361.938824 -282.579064) (xy 361.939078 -282.579318)
			(xy 361.946165 -282.584904) (xy 361.963082 -282.59115) (xy 361.972098 -282.59151) (xy 362.039154 -282.59151)
			(xy 362.048168 -282.591129) (xy 362.065085 -282.584898) (xy 362.072174 -282.579318) (xy 362.072174 -282.579064)
			(xy 362.072428 -282.579064) (xy 362.093372 -282.56144) (xy 362.139342 -282.531727) (xy 362.189087 -282.508889)
			(xy 362.241584 -282.493394) (xy 362.295758 -282.485561) (xy 362.323126 -282.485084) (xy 362.350375 -282.485588)
			(xy 362.404319 -282.493347) (xy 362.45661 -282.508704) (xy 362.506183 -282.531346) (xy 362.552029 -282.560812)
			(xy 362.593215 -282.596503) (xy 362.628903 -282.637692) (xy 362.658366 -282.68354) (xy 362.681005 -282.733115)
			(xy 362.696359 -282.785406) (xy 362.704114 -282.839351) (xy 362.704114 -282.893849) (xy 362.696359 -282.947794)
			(xy 362.681005 -283.000085) (xy 362.658366 -283.04966) (xy 362.628903 -283.095508) (xy 362.593215 -283.136697)
			(xy 362.552029 -283.172388) (xy 362.506183 -283.201854) (xy 362.45661 -283.224496) (xy 362.404319 -283.239853)
			(xy 362.350375 -283.247612) (xy 362.323126 -283.2481) (xy 362.295756 -283.247619) (xy 362.241578 -283.239805)
			(xy 362.189075 -283.224319) (xy 362.139328 -283.201481) (xy 362.09336 -283.17176) (xy 362.072428 -283.15412)
			(xy 362.072174 -283.153866) (xy 362.065073 -283.1483) (xy 362.048167 -283.142042) (xy 362.039154 -283.141674)
			(xy 361.972098 -283.141674) (xy 361.963082 -283.142036) (xy 361.946165 -283.148281) (xy 361.939078 -283.153866)
			(xy 361.939078 -283.15412) (xy 361.938824 -283.15412) (xy 361.917896 -283.171764) (xy 361.871922 -283.201475)
			(xy 361.822173 -283.224309) (xy 361.769672 -283.239799) (xy 361.715495 -283.247626) (xy 361.688126 -283.2481)
			(xy 361.660871 -283.247654) (xy 361.606917 -283.2399) (xy 361.554614 -283.224546) (xy 361.50503 -283.201905)
			(xy 361.459173 -283.172437) (xy 361.417976 -283.136742) (xy 361.382279 -283.095548) (xy 361.352808 -283.049693)
			(xy 361.330163 -283.00011) (xy 361.314805 -282.947809) (xy 361.307047 -282.893855) (xy 360.976899 -282.893855)
			(xy 360.976849 -282.89643) (xy 360.96754 -282.955376) (xy 360.958892 -282.98394) (xy 360.95559 -282.994354)
			(xy 360.957876 -283.015944) (xy 361.008168 -283.100526) (xy 361.02544 -283.112972) (xy 361.036362 -283.115004)
			(xy 361.062178 -283.120347) (xy 361.112094 -283.137315) (xy 361.159199 -283.160995) (xy 361.202593 -283.190935)
			(xy 361.241451 -283.226566) (xy 361.275033 -283.267209) (xy 361.302699 -283.312088) (xy 361.323921 -283.360349)
			(xy 361.338295 -283.411073) (xy 361.345547 -283.463293) (xy 361.345988 -283.489654) (xy 361.345406 -283.519777)
			(xy 361.33593 -283.579274) (xy 361.317223 -283.636542) (xy 361.289749 -283.69016) (xy 361.254191 -283.738794)
			(xy 361.233212 -283.760418) (xy 361.226373 -283.767819) (xy 361.218652 -283.786417) (xy 361.218226 -283.796486)
			(xy 361.218226 -283.868622) (xy 361.218633 -283.878693) (xy 361.226366 -283.897291) (xy 361.233212 -283.90469)
			(xy 361.254215 -283.926294) (xy 361.28978 -283.974929) (xy 361.317255 -284.02855) (xy 361.331634 -284.072584)
			(xy 366.233202 -284.072584) (xy 366.233658 -284.045213) (xy 366.241478 -283.991034) (xy 366.25697 -283.938531)
			(xy 366.279814 -283.888784) (xy 366.30954 -283.842817) (xy 366.327182 -283.821886) (xy 366.327436 -283.821632)
			(xy 366.333019 -283.814543) (xy 366.339267 -283.797628) (xy 366.339628 -283.788612) (xy 366.339628 -283.721556)
			(xy 366.339238 -283.712543) (xy 366.333013 -283.695626) (xy 366.327436 -283.688536) (xy 366.327182 -283.688536)
			(xy 366.327182 -283.688282) (xy 366.309565 -283.667332) (xy 366.279851 -283.621364) (xy 366.257011 -283.571621)
			(xy 366.241514 -283.519124) (xy 366.23368 -283.464952) (xy 366.233202 -283.437584) (xy 366.233688 -283.410333)
			(xy 366.241444 -283.356385) (xy 366.256799 -283.30409) (xy 366.279441 -283.254513) (xy 366.308907 -283.208663)
			(xy 366.344598 -283.167472) (xy 366.385789 -283.131781) (xy 366.431639 -283.102315) (xy 366.481216 -283.079673)
			(xy 366.533511 -283.064318) (xy 366.587459 -283.056562) (xy 366.641961 -283.056562) (xy 366.695909 -283.064318)
			(xy 366.748204 -283.079673) (xy 366.797781 -283.102315) (xy 366.843631 -283.131781) (xy 366.884822 -283.167472)
			(xy 366.920513 -283.208663) (xy 366.949979 -283.254513) (xy 366.972621 -283.30409) (xy 366.987976 -283.356385)
			(xy 366.995732 -283.410333) (xy 366.996218 -283.437584) (xy 366.995763 -283.464955) (xy 366.987945 -283.519135)
			(xy 366.972455 -283.571639) (xy 366.94961 -283.621386) (xy 366.919882 -283.667352) (xy 366.902238 -283.688282)
			(xy 366.901984 -283.688536) (xy 366.896416 -283.695635) (xy 366.890159 -283.712542) (xy 366.889792 -283.721556)
			(xy 366.889792 -283.788612) (xy 366.890145 -283.797629) (xy 366.896396 -283.814546) (xy 366.901984 -283.821632)
			(xy 366.902238 -283.821632) (xy 366.902238 -283.821886) (xy 366.91989 -283.842807) (xy 366.949599 -283.888784)
			(xy 366.972432 -283.938534) (xy 366.98792 -283.991037) (xy 366.995746 -284.045214) (xy 366.996218 -284.072584)
			(xy 366.995732 -284.099835) (xy 366.987976 -284.153783) (xy 366.972621 -284.206078) (xy 366.949979 -284.255655)
			(xy 366.920513 -284.301505) (xy 366.884822 -284.342696) (xy 366.843631 -284.378387) (xy 366.797781 -284.407853)
			(xy 366.748204 -284.430495) (xy 366.695909 -284.44585) (xy 366.641961 -284.453606) (xy 366.587459 -284.453606)
			(xy 366.533511 -284.44585) (xy 366.481216 -284.430495) (xy 366.431639 -284.407853) (xy 366.385789 -284.378387)
			(xy 366.344598 -284.342696) (xy 366.308907 -284.301505) (xy 366.279441 -284.255655) (xy 366.256799 -284.206078)
			(xy 366.241444 -284.153783) (xy 366.233688 -284.099835) (xy 366.233202 -284.072584) (xy 361.331634 -284.072584)
			(xy 361.335958 -284.085825) (xy 361.345423 -284.145328) (xy 361.345988 -284.175454) (xy 361.345502 -284.202705)
			(xy 361.337746 -284.256653) (xy 361.322391 -284.308948) (xy 361.299749 -284.358525) (xy 361.270283 -284.404375)
			(xy 361.234592 -284.445566) (xy 361.193401 -284.481257) (xy 361.147551 -284.510723) (xy 361.097974 -284.533365)
			(xy 361.045679 -284.54872) (xy 360.991731 -284.556476) (xy 360.937229 -284.556476) (xy 360.883281 -284.54872)
			(xy 360.830986 -284.533365) (xy 360.781409 -284.510723) (xy 360.735559 -284.481257) (xy 360.694368 -284.445566)
			(xy 360.658677 -284.404375) (xy 360.629211 -284.358525) (xy 360.606569 -284.308948) (xy 360.591214 -284.256653)
			(xy 360.583458 -284.202705) (xy 360.582972 -284.175454) (xy 360.583571 -284.145332) (xy 360.593044 -284.085836)
			(xy 360.611748 -284.028568) (xy 360.639218 -283.974951) (xy 360.674771 -283.926316) (xy 360.695748 -283.90469)
			(xy 360.702578 -283.897281) (xy 360.710305 -283.878689) (xy 360.710734 -283.868622) (xy 360.710734 -283.796486)
			(xy 360.710334 -283.786414) (xy 360.702597 -283.767815) (xy 360.695748 -283.760418) (xy 360.67476 -283.7388)
			(xy 360.63919 -283.690171) (xy 360.611711 -283.636552) (xy 360.593005 -283.57928) (xy 360.583538 -283.519779)
			(xy 360.582972 -283.489654) (xy 360.583545 -283.459815) (xy 360.592862 -283.400869) (xy 360.601514 -283.372306)
			(xy 360.604816 -283.361892) (xy 360.60253 -283.340302) (xy 360.552238 -283.25572) (xy 360.534966 -283.243274)
			(xy 360.524044 -283.241242) (xy 360.496194 -283.235394) (xy 360.44253 -283.216457) (xy 360.392273 -283.189761)
			(xy 360.346537 -283.1559) (xy 360.306335 -283.115623) (xy 360.272559 -283.069824) (xy 360.245957 -283.019517)
			(xy 360.22712 -282.965818) (xy 360.221276 -282.937966) (xy 360.218736 -282.92552) (xy 360.203496 -282.906216)
			(xy 360.102404 -282.862528) (xy 360.077766 -282.864306) (xy 360.067098 -282.871164) (xy 360.044129 -282.885204)
			(xy 359.995055 -282.907334) (xy 359.943352 -282.92233) (xy 359.890053 -282.929892) (xy 359.863136 -282.930346)
			(xy 359.845117 -282.930129) (xy 359.809242 -282.926692) (xy 359.791508 -282.923488) (xy 359.781856 -282.92171)
			(xy 359.762806 -282.925266) (xy 359.687876 -282.973272) (xy 359.676446 -282.98902) (xy 359.67416 -282.998418)
			(xy 359.666766 -283.025464) (xy 359.645138 -283.077192) (xy 359.616175 -283.125199) (xy 359.5805 -283.168452)
			(xy 359.53888 -283.20602) (xy 359.492211 -283.237094) (xy 359.441498 -283.261006) (xy 359.387833 -283.27724)
			(xy 359.33237 -283.285449) (xy 359.304336 -283.285946) (xy 359.277087 -283.285388) (xy 359.223144 -283.277638)
			(xy 359.170853 -283.262289) (xy 359.121279 -283.239655) (xy 359.07543 -283.210196) (xy 359.03424 -283.174512)
			(xy 358.998548 -283.133329) (xy 358.969081 -283.087486) (xy 358.946437 -283.037916) (xy 358.931078 -282.985628)
			(xy 358.923317 -282.931687) (xy 358.922828 -282.904438) (xy 354.542092 -282.904438) (xy 354.535858 -282.947795)
			(xy 354.520504 -283.000088) (xy 354.497865 -283.049663) (xy 354.4684 -283.095512) (xy 354.432711 -283.136701)
			(xy 354.391523 -283.172392) (xy 354.345676 -283.201858) (xy 354.296101 -283.224499) (xy 354.243809 -283.239855)
			(xy 354.189864 -283.247613) (xy 354.162614 -283.2481) (xy 354.135244 -283.247626) (xy 354.081065 -283.23981)
			(xy 354.028562 -283.224323) (xy 353.978815 -283.201483) (xy 353.932848 -283.17176) (xy 353.911916 -283.15412)
			(xy 353.911662 -283.153866) (xy 353.904565 -283.148295) (xy 353.887656 -283.14204) (xy 353.878642 -283.141674)
			(xy 353.811586 -283.141674) (xy 353.802569 -283.14203) (xy 353.785653 -283.148279) (xy 353.778566 -283.153866)
			(xy 353.778566 -283.15412) (xy 353.778312 -283.15412) (xy 353.757389 -283.17177) (xy 353.711413 -283.20148)
			(xy 353.661663 -283.224313) (xy 353.609161 -283.239802) (xy 353.554984 -283.247627) (xy 353.527614 -283.2481)
			(xy 353.50036 -283.247654) (xy 353.446406 -283.239898) (xy 353.394106 -283.224543) (xy 353.344523 -283.201901)
			(xy 353.298667 -283.172433) (xy 353.257472 -283.136738) (xy 353.221776 -283.095544) (xy 353.192306 -283.049689)
			(xy 353.169662 -283.000107) (xy 353.154305 -282.947807) (xy 353.146547 -282.893854) (xy 352.816388 -282.893854)
			(xy 352.816337 -282.89643) (xy 352.807028 -282.955376) (xy 352.79838 -282.98394) (xy 352.795078 -282.994354)
			(xy 352.797364 -283.015944) (xy 352.847656 -283.100526) (xy 352.864928 -283.112972) (xy 352.87585 -283.115004)
			(xy 352.901664 -283.120356) (xy 352.951581 -283.137322) (xy 352.998685 -283.161001) (xy 353.04208 -283.19094)
			(xy 353.080938 -283.22657) (xy 353.11452 -283.267211) (xy 353.142186 -283.31209) (xy 353.163408 -283.360351)
			(xy 353.177783 -283.411074) (xy 353.185035 -283.463294) (xy 353.185476 -283.489654) (xy 353.184869 -283.519776)
			(xy 353.175396 -283.57927) (xy 353.156693 -283.636537) (xy 353.129225 -283.690155) (xy 353.093675 -283.738792)
			(xy 353.0727 -283.760418) (xy 353.06586 -283.767818) (xy 353.05814 -283.786417) (xy 353.057714 -283.796486)
			(xy 353.057714 -283.868622) (xy 353.058125 -283.878693) (xy 353.065855 -283.897291) (xy 353.0727 -283.90469)
			(xy 353.093701 -283.926296) (xy 353.129266 -283.97493) (xy 353.156743 -284.028551) (xy 353.171122 -284.072584)
			(xy 358.07269 -284.072584) (xy 358.073149 -284.045214) (xy 358.080969 -283.991034) (xy 358.09646 -283.938531)
			(xy 358.119303 -283.888784) (xy 358.149028 -283.842818) (xy 358.16667 -283.821886) (xy 358.166924 -283.821632)
			(xy 358.172506 -283.814542) (xy 358.178755 -283.797628) (xy 358.179116 -283.788612) (xy 358.179116 -283.721556)
			(xy 358.178729 -283.712542) (xy 358.172502 -283.695625) (xy 358.166924 -283.688536) (xy 358.16667 -283.688536)
			(xy 358.16667 -283.688282) (xy 358.149051 -283.667334) (xy 358.119337 -283.621365) (xy 358.096498 -283.571621)
			(xy 358.081002 -283.519125) (xy 358.073168 -283.464952) (xy 358.07269 -283.437584) (xy 358.073176 -283.410333)
			(xy 358.080932 -283.356385) (xy 358.096287 -283.30409) (xy 358.118929 -283.254513) (xy 358.148395 -283.208663)
			(xy 358.184086 -283.167472) (xy 358.225277 -283.131781) (xy 358.271127 -283.102315) (xy 358.320704 -283.079673)
			(xy 358.372999 -283.064318) (xy 358.426947 -283.056562) (xy 358.481449 -283.056562) (xy 358.535397 -283.064318)
			(xy 358.587692 -283.079673) (xy 358.637269 -283.102315) (xy 358.683119 -283.131781) (xy 358.72431 -283.167472)
			(xy 358.760001 -283.208663) (xy 358.789467 -283.254513) (xy 358.812109 -283.30409) (xy 358.827464 -283.356385)
			(xy 358.83522 -283.410333) (xy 358.835706 -283.437584) (xy 358.835229 -283.464954) (xy 358.827414 -283.519132)
			(xy 358.811927 -283.571635) (xy 358.789088 -283.621382) (xy 358.759366 -283.66735) (xy 358.741726 -283.688282)
			(xy 358.741472 -283.688536) (xy 358.735903 -283.695634) (xy 358.729647 -283.712542) (xy 358.72928 -283.721556)
			(xy 358.72928 -283.788612) (xy 358.729636 -283.797629) (xy 358.735885 -283.814546) (xy 358.741472 -283.821632)
			(xy 358.741726 -283.821632) (xy 358.741726 -283.821886) (xy 358.759376 -283.842809) (xy 358.789085 -283.888785)
			(xy 358.811919 -283.938535) (xy 358.827407 -283.991037) (xy 358.835233 -284.045214) (xy 358.835706 -284.072584)
			(xy 358.83522 -284.099835) (xy 358.827464 -284.153783) (xy 358.812109 -284.206078) (xy 358.789467 -284.255655)
			(xy 358.760001 -284.301505) (xy 358.72431 -284.342696) (xy 358.683119 -284.378387) (xy 358.637269 -284.407853)
			(xy 358.587692 -284.430495) (xy 358.535397 -284.44585) (xy 358.481449 -284.453606) (xy 358.426947 -284.453606)
			(xy 358.372999 -284.44585) (xy 358.320704 -284.430495) (xy 358.271127 -284.407853) (xy 358.225277 -284.378387)
			(xy 358.184086 -284.342696) (xy 358.148395 -284.301505) (xy 358.118929 -284.255655) (xy 358.096287 -284.206078)
			(xy 358.080932 -284.153783) (xy 358.073176 -284.099835) (xy 358.07269 -284.072584) (xy 353.171122 -284.072584)
			(xy 353.175446 -284.085826) (xy 353.184911 -284.145328) (xy 353.185476 -284.175454) (xy 353.18499 -284.202705)
			(xy 353.177234 -284.256653) (xy 353.161879 -284.308948) (xy 353.139237 -284.358525) (xy 353.109771 -284.404375)
			(xy 353.07408 -284.445566) (xy 353.032889 -284.481257) (xy 352.987039 -284.510723) (xy 352.937462 -284.533365)
			(xy 352.885167 -284.54872) (xy 352.831219 -284.556476) (xy 352.776717 -284.556476) (xy 352.722769 -284.54872)
			(xy 352.670474 -284.533365) (xy 352.620897 -284.510723) (xy 352.575047 -284.481257) (xy 352.533856 -284.445566)
			(xy 352.498165 -284.404375) (xy 352.468699 -284.358525) (xy 352.446057 -284.308948) (xy 352.430702 -284.256653)
			(xy 352.422946 -284.202705) (xy 352.42246 -284.175454) (xy 352.423062 -284.145332) (xy 352.432535 -284.085837)
			(xy 352.451239 -284.028569) (xy 352.478708 -283.974952) (xy 352.51426 -283.926316) (xy 352.535236 -283.90469)
			(xy 352.542078 -283.897292) (xy 352.549796 -283.878691) (xy 352.550222 -283.868622) (xy 352.550222 -283.796486)
			(xy 352.549824 -283.786413) (xy 352.542086 -283.767815) (xy 352.535236 -283.760418) (xy 352.514246 -283.738802)
			(xy 352.478677 -283.690172) (xy 352.451198 -283.636553) (xy 352.432493 -283.579281) (xy 352.423026 -283.519779)
			(xy 352.42246 -283.489654) (xy 352.423033 -283.459815) (xy 352.43235 -283.400869) (xy 352.441002 -283.372306)
			(xy 352.444304 -283.361892) (xy 352.442018 -283.340302) (xy 352.391726 -283.25572) (xy 352.374454 -283.243274)
			(xy 352.363532 -283.241242) (xy 352.33568 -283.235403) (xy 352.282016 -283.216463) (xy 352.231759 -283.189767)
			(xy 352.186023 -283.155904) (xy 352.145822 -283.115626) (xy 352.112046 -283.069825) (xy 352.085445 -283.019518)
			(xy 352.066608 -282.965818) (xy 352.060764 -282.937966) (xy 352.058224 -282.92552) (xy 352.042984 -282.906216)
			(xy 351.941892 -282.862528) (xy 351.917254 -282.864306) (xy 351.906586 -282.871164) (xy 351.883596 -282.885167)
			(xy 351.834529 -282.907307) (xy 351.782833 -282.922313) (xy 351.729539 -282.929886) (xy 351.702624 -282.930346)
			(xy 351.684604 -282.930131) (xy 351.64873 -282.926693) (xy 351.630996 -282.923488) (xy 351.621344 -282.92171)
			(xy 351.602294 -282.925266) (xy 351.527364 -282.973272) (xy 351.515934 -282.98902) (xy 351.513648 -282.998418)
			(xy 351.506265 -283.025467) (xy 351.484636 -283.077196) (xy 351.455672 -283.125203) (xy 351.419995 -283.168456)
			(xy 351.378374 -283.206024) (xy 351.331704 -283.237098) (xy 351.28099 -283.261009) (xy 351.227323 -283.277243)
			(xy 351.171858 -283.28545) (xy 351.143824 -283.285946) (xy 351.116575 -283.2854) (xy 351.062632 -283.277647)
			(xy 351.01034 -283.262297) (xy 350.960766 -283.239662) (xy 350.914917 -283.210201) (xy 350.873728 -283.174516)
			(xy 350.838036 -283.133333) (xy 350.808568 -283.087489) (xy 350.785925 -283.037918) (xy 350.770566 -282.985629)
			(xy 350.762805 -282.931687) (xy 350.762316 -282.904438) (xy 346.043492 -282.904438) (xy 346.037259 -282.947794)
			(xy 346.021905 -283.000085) (xy 345.999267 -283.049659) (xy 345.969804 -283.095507) (xy 345.934116 -283.136696)
			(xy 345.89293 -283.172387) (xy 345.847084 -283.201853) (xy 345.797511 -283.224496) (xy 345.745221 -283.239853)
			(xy 345.691277 -283.247612) (xy 345.664028 -283.2481) (xy 345.636658 -283.247618) (xy 345.58248 -283.239804)
			(xy 345.529977 -283.224318) (xy 345.48023 -283.20148) (xy 345.434262 -283.171759) (xy 345.41333 -283.15412)
			(xy 345.413076 -283.153866) (xy 345.406003 -283.148259) (xy 345.389076 -283.142026) (xy 345.380056 -283.141674)
			(xy 345.313 -283.141674) (xy 345.303984 -283.142037) (xy 345.287067 -283.148281) (xy 345.27998 -283.153866)
			(xy 345.27998 -283.15412) (xy 345.279726 -283.15412) (xy 345.258798 -283.171763) (xy 345.212823 -283.201474)
			(xy 345.163075 -283.224309) (xy 345.110574 -283.239799) (xy 345.056397 -283.247626) (xy 345.029028 -283.2481)
			(xy 345.001773 -283.247655) (xy 344.947818 -283.239901) (xy 344.895516 -283.224547) (xy 344.845931 -283.201905)
			(xy 344.800074 -283.172437) (xy 344.758877 -283.136743) (xy 344.723179 -283.095549) (xy 344.693708 -283.049693)
			(xy 344.671063 -283.00011) (xy 344.655705 -282.947809) (xy 344.647947 -282.893855) (xy 344.317801 -282.893855)
			(xy 344.31775 -282.89643) (xy 344.308442 -282.955376) (xy 344.299794 -282.98394) (xy 344.296492 -282.994354)
			(xy 344.298778 -283.015944) (xy 344.34907 -283.100526) (xy 344.366342 -283.112972) (xy 344.377264 -283.115004)
			(xy 344.403081 -283.120346) (xy 344.452997 -283.137314) (xy 344.500101 -283.160994) (xy 344.543495 -283.190935)
			(xy 344.582354 -283.226566) (xy 344.615935 -283.267208) (xy 344.643601 -283.312088) (xy 344.664823 -283.360349)
			(xy 344.679197 -283.411073) (xy 344.686449 -283.463293) (xy 344.68689 -283.489654) (xy 344.686307 -283.519777)
			(xy 344.676832 -283.579274) (xy 344.658125 -283.636542) (xy 344.630651 -283.69016) (xy 344.595093 -283.738793)
			(xy 344.574114 -283.760418) (xy 344.567275 -283.767819) (xy 344.559554 -283.786418) (xy 344.559128 -283.796486)
			(xy 344.559128 -283.868622) (xy 344.559535 -283.878693) (xy 344.567268 -283.897291) (xy 344.574114 -283.90469)
			(xy 344.595117 -283.926294) (xy 344.630682 -283.974929) (xy 344.658157 -284.02855) (xy 344.672536 -284.072584)
			(xy 349.574104 -284.072584) (xy 349.57456 -284.045213) (xy 349.58238 -283.991034) (xy 349.597871 -283.938531)
			(xy 349.620715 -283.888784) (xy 349.650442 -283.842817) (xy 349.668084 -283.821886) (xy 349.668338 -283.821632)
			(xy 349.673922 -283.814544) (xy 349.680169 -283.797628) (xy 349.68053 -283.788612) (xy 349.68053 -283.721556)
			(xy 349.68014 -283.712543) (xy 349.673915 -283.695626) (xy 349.668338 -283.688536) (xy 349.668084 -283.688536)
			(xy 349.668084 -283.688282) (xy 349.650467 -283.667332) (xy 349.620753 -283.621364) (xy 349.597913 -283.571621)
			(xy 349.582416 -283.519124) (xy 349.574582 -283.464952) (xy 349.574104 -283.437584) (xy 349.57459 -283.410333)
			(xy 349.582346 -283.356385) (xy 349.597701 -283.30409) (xy 349.620343 -283.254513) (xy 349.649809 -283.208663)
			(xy 349.6855 -283.167472) (xy 349.726691 -283.131781) (xy 349.772541 -283.102315) (xy 349.822118 -283.079673)
			(xy 349.874413 -283.064318) (xy 349.928361 -283.056562) (xy 349.982863 -283.056562) (xy 350.036811 -283.064318)
			(xy 350.089106 -283.079673) (xy 350.138683 -283.102315) (xy 350.184533 -283.131781) (xy 350.225724 -283.167472)
			(xy 350.261415 -283.208663) (xy 350.290881 -283.254513) (xy 350.313523 -283.30409) (xy 350.328878 -283.356385)
			(xy 350.336634 -283.410333) (xy 350.33712 -283.437584) (xy 350.336664 -283.464955) (xy 350.328847 -283.519135)
			(xy 350.313356 -283.571639) (xy 350.290512 -283.621386) (xy 350.260783 -283.667351) (xy 350.24314 -283.688282)
			(xy 350.242886 -283.688536) (xy 350.237319 -283.695636) (xy 350.231061 -283.712542) (xy 350.230694 -283.721556)
			(xy 350.230694 -283.788612) (xy 350.231047 -283.797629) (xy 350.237297 -283.814546) (xy 350.242886 -283.821632)
			(xy 350.24314 -283.821632) (xy 350.24314 -283.821886) (xy 350.260793 -283.842807) (xy 350.290501 -283.888784)
			(xy 350.313334 -283.938534) (xy 350.328822 -283.991037) (xy 350.336648 -284.045214) (xy 350.33712 -284.072584)
			(xy 350.336634 -284.099835) (xy 350.328878 -284.153783) (xy 350.313523 -284.206078) (xy 350.290881 -284.255655)
			(xy 350.261415 -284.301505) (xy 350.225724 -284.342696) (xy 350.184533 -284.378387) (xy 350.138683 -284.407853)
			(xy 350.089106 -284.430495) (xy 350.036811 -284.44585) (xy 349.982863 -284.453606) (xy 349.928361 -284.453606)
			(xy 349.874413 -284.44585) (xy 349.822118 -284.430495) (xy 349.772541 -284.407853) (xy 349.726691 -284.378387)
			(xy 349.6855 -284.342696) (xy 349.649809 -284.301505) (xy 349.620343 -284.255655) (xy 349.597701 -284.206078)
			(xy 349.582346 -284.153783) (xy 349.57459 -284.099835) (xy 349.574104 -284.072584) (xy 344.672536 -284.072584)
			(xy 344.67686 -284.085825) (xy 344.686325 -284.145328) (xy 344.68689 -284.175454) (xy 344.686404 -284.202705)
			(xy 344.678648 -284.256653) (xy 344.663293 -284.308948) (xy 344.640651 -284.358525) (xy 344.611185 -284.404375)
			(xy 344.575494 -284.445566) (xy 344.534303 -284.481257) (xy 344.488453 -284.510723) (xy 344.438876 -284.533365)
			(xy 344.386581 -284.54872) (xy 344.332633 -284.556476) (xy 344.278131 -284.556476) (xy 344.224183 -284.54872)
			(xy 344.171888 -284.533365) (xy 344.122311 -284.510723) (xy 344.076461 -284.481257) (xy 344.03527 -284.445566)
			(xy 343.999579 -284.404375) (xy 343.970113 -284.358525) (xy 343.947471 -284.308948) (xy 343.932116 -284.256653)
			(xy 343.92436 -284.202705) (xy 343.923874 -284.175454) (xy 343.924472 -284.145332) (xy 343.933946 -284.085836)
			(xy 343.95265 -284.028568) (xy 343.98012 -283.974951) (xy 344.015673 -283.926316) (xy 344.03665 -283.90469)
			(xy 344.04348 -283.897282) (xy 344.051207 -283.878689) (xy 344.051636 -283.868622) (xy 344.051636 -283.796486)
			(xy 344.051235 -283.786414) (xy 344.043499 -283.767815) (xy 344.03665 -283.760418) (xy 344.015662 -283.7388)
			(xy 343.980093 -283.69017) (xy 343.952613 -283.636552) (xy 343.933907 -283.57928) (xy 343.92444 -283.519779)
			(xy 343.923874 -283.489654) (xy 343.924447 -283.459815) (xy 343.933764 -283.400869) (xy 343.942416 -283.372306)
			(xy 343.945718 -283.361892) (xy 343.943432 -283.340302) (xy 343.89314 -283.25572) (xy 343.875868 -283.243274)
			(xy 343.864946 -283.241242) (xy 343.837096 -283.235393) (xy 343.783432 -283.216456) (xy 343.733175 -283.18976)
			(xy 343.687439 -283.155899) (xy 343.647237 -283.115623) (xy 343.613461 -283.069823) (xy 343.586859 -283.019517)
			(xy 343.568022 -282.965818) (xy 343.562178 -282.937966) (xy 343.559638 -282.92552) (xy 343.544398 -282.906216)
			(xy 343.443306 -282.862528) (xy 343.418668 -282.864306) (xy 343.408 -282.871164) (xy 343.38503 -282.885203)
			(xy 343.335956 -282.907334) (xy 343.284254 -282.92233) (xy 343.230955 -282.929892) (xy 343.204038 -282.930346)
			(xy 343.186019 -282.930129) (xy 343.150144 -282.926692) (xy 343.13241 -282.923488) (xy 343.122758 -282.92171)
			(xy 343.103708 -282.925266) (xy 343.028778 -282.973272) (xy 343.017348 -282.98902) (xy 343.015062 -282.998418)
			(xy 343.007666 -283.025463) (xy 342.986039 -283.077191) (xy 342.957076 -283.125198) (xy 342.9214 -283.168451)
			(xy 342.879781 -283.206019) (xy 342.833112 -283.237093) (xy 342.7824 -283.261005) (xy 342.728735 -283.27724)
			(xy 342.673272 -283.285449) (xy 342.645238 -283.285946) (xy 342.617989 -283.285387) (xy 342.564046 -283.277636)
			(xy 342.511755 -283.262288) (xy 342.462181 -283.239654) (xy 342.416332 -283.210195) (xy 342.375143 -283.174511)
			(xy 342.33945 -283.133329) (xy 342.309983 -283.087486) (xy 342.287339 -283.037916) (xy 342.27198 -282.985628)
			(xy 342.264219 -282.931686) (xy 342.26373 -282.904438) (xy 337.882992 -282.904438) (xy 337.876758 -282.947795)
			(xy 337.861404 -283.000088) (xy 337.838765 -283.049663) (xy 337.809301 -283.095511) (xy 337.773612 -283.1367)
			(xy 337.732424 -283.172391) (xy 337.686577 -283.201857) (xy 337.637003 -283.224499) (xy 337.584711 -283.239855)
			(xy 337.530766 -283.247613) (xy 337.503516 -283.2481) (xy 337.476146 -283.247625) (xy 337.421967 -283.239809)
			(xy 337.369464 -283.224322) (xy 337.319717 -283.201482) (xy 337.27375 -283.17176) (xy 337.252818 -283.15412)
			(xy 337.252564 -283.153866) (xy 337.245466 -283.148296) (xy 337.228558 -283.142041) (xy 337.219544 -283.141674)
			(xy 337.152488 -283.141674) (xy 337.143471 -283.142031) (xy 337.126555 -283.148279) (xy 337.119468 -283.153866)
			(xy 337.119468 -283.15412) (xy 337.119214 -283.15412) (xy 337.09829 -283.171769) (xy 337.052315 -283.201479)
			(xy 337.002565 -283.224312) (xy 336.950063 -283.239801) (xy 336.895886 -283.247627) (xy 336.868516 -283.2481)
			(xy 336.841262 -283.247654) (xy 336.787308 -283.239898) (xy 336.735007 -283.224543) (xy 336.685424 -283.201901)
			(xy 336.639568 -283.172433) (xy 336.598372 -283.136739) (xy 336.562676 -283.095545) (xy 336.533206 -283.04969)
			(xy 336.510562 -283.000108) (xy 336.495205 -282.947808) (xy 336.487447 -282.893854) (xy 336.15729 -282.893854)
			(xy 336.157239 -282.89643) (xy 336.14793 -282.955376) (xy 336.139282 -282.98394) (xy 336.13598 -282.994354)
			(xy 336.138266 -283.015944) (xy 336.188558 -283.100526) (xy 336.20583 -283.112972) (xy 336.216752 -283.115004)
			(xy 336.242567 -283.120354) (xy 336.292483 -283.137321) (xy 336.339587 -283.161) (xy 336.382982 -283.190939)
			(xy 336.421841 -283.226569) (xy 336.455423 -283.267211) (xy 336.483088 -283.31209) (xy 336.50431 -283.36035)
			(xy 336.518685 -283.411074) (xy 336.525937 -283.463294) (xy 336.526378 -283.489654) (xy 336.52577 -283.519776)
			(xy 336.516297 -283.57927) (xy 336.497594 -283.636537) (xy 336.470127 -283.690155) (xy 336.434577 -283.738792)
			(xy 336.413602 -283.760418) (xy 336.406762 -283.767818) (xy 336.399042 -283.786417) (xy 336.398616 -283.796486)
			(xy 336.398616 -283.868622) (xy 336.399026 -283.878693) (xy 336.406757 -283.897291) (xy 336.413602 -283.90469)
			(xy 336.434603 -283.926296) (xy 336.470168 -283.97493) (xy 336.497645 -284.028551) (xy 336.512024 -284.072584)
			(xy 341.413592 -284.072584) (xy 341.414051 -284.045214) (xy 341.421871 -283.991034) (xy 341.437361 -283.938531)
			(xy 341.460205 -283.888784) (xy 341.48993 -283.842818) (xy 341.507572 -283.821886) (xy 341.507826 -283.821632)
			(xy 341.513408 -283.814543) (xy 341.519657 -283.797628) (xy 341.520018 -283.788612) (xy 341.520018 -283.721556)
			(xy 341.51963 -283.712542) (xy 341.513404 -283.695625) (xy 341.507826 -283.688536) (xy 341.507572 -283.688536)
			(xy 341.507572 -283.688282) (xy 341.489954 -283.667333) (xy 341.46024 -283.621365) (xy 341.4374 -283.571621)
			(xy 341.421904 -283.519125) (xy 341.41407 -283.464952) (xy 341.413592 -283.437584) (xy 341.414078 -283.410333)
			(xy 341.421834 -283.356385) (xy 341.437189 -283.30409) (xy 341.459831 -283.254513) (xy 341.489297 -283.208663)
			(xy 341.524988 -283.167472) (xy 341.566179 -283.131781) (xy 341.612029 -283.102315) (xy 341.661606 -283.079673)
			(xy 341.713901 -283.064318) (xy 341.767849 -283.056562) (xy 341.822351 -283.056562) (xy 341.876299 -283.064318)
			(xy 341.928594 -283.079673) (xy 341.978171 -283.102315) (xy 342.024021 -283.131781) (xy 342.065212 -283.167472)
			(xy 342.100903 -283.208663) (xy 342.130369 -283.254513) (xy 342.153011 -283.30409) (xy 342.168366 -283.356385)
			(xy 342.176122 -283.410333) (xy 342.176608 -283.437584) (xy 342.176131 -283.464954) (xy 342.168315 -283.519132)
			(xy 342.152829 -283.571635) (xy 342.12999 -283.621382) (xy 342.100268 -283.66735) (xy 342.082628 -283.688282)
			(xy 342.082374 -283.688536) (xy 342.076805 -283.695635) (xy 342.070549 -283.712542) (xy 342.070182 -283.721556)
			(xy 342.070182 -283.788612) (xy 342.070537 -283.797629) (xy 342.076787 -283.814546) (xy 342.082374 -283.821632)
			(xy 342.082628 -283.821632) (xy 342.082628 -283.821886) (xy 342.100278 -283.842809) (xy 342.129988 -283.888785)
			(xy 342.152821 -283.938535) (xy 342.168309 -283.991037) (xy 342.176135 -284.045214) (xy 342.176608 -284.072584)
			(xy 342.176122 -284.099835) (xy 342.168366 -284.153783) (xy 342.153011 -284.206078) (xy 342.130369 -284.255655)
			(xy 342.100903 -284.301505) (xy 342.065212 -284.342696) (xy 342.024021 -284.378387) (xy 341.978171 -284.407853)
			(xy 341.928594 -284.430495) (xy 341.876299 -284.44585) (xy 341.822351 -284.453606) (xy 341.767849 -284.453606)
			(xy 341.713901 -284.44585) (xy 341.661606 -284.430495) (xy 341.612029 -284.407853) (xy 341.566179 -284.378387)
			(xy 341.524988 -284.342696) (xy 341.489297 -284.301505) (xy 341.459831 -284.255655) (xy 341.437189 -284.206078)
			(xy 341.421834 -284.153783) (xy 341.414078 -284.099835) (xy 341.413592 -284.072584) (xy 336.512024 -284.072584)
			(xy 336.516348 -284.085826) (xy 336.525813 -284.145328) (xy 336.526378 -284.175454) (xy 336.525892 -284.202705)
			(xy 336.518136 -284.256653) (xy 336.502781 -284.308948) (xy 336.480139 -284.358525) (xy 336.450673 -284.404375)
			(xy 336.414982 -284.445566) (xy 336.373791 -284.481257) (xy 336.327941 -284.510723) (xy 336.278364 -284.533365)
			(xy 336.226069 -284.54872) (xy 336.172121 -284.556476) (xy 336.117619 -284.556476) (xy 336.063671 -284.54872)
			(xy 336.011376 -284.533365) (xy 335.961799 -284.510723) (xy 335.915949 -284.481257) (xy 335.874758 -284.445566)
			(xy 335.839067 -284.404375) (xy 335.809601 -284.358525) (xy 335.786959 -284.308948) (xy 335.771604 -284.256653)
			(xy 335.763848 -284.202705) (xy 335.763362 -284.175454) (xy 335.763964 -284.145332) (xy 335.773437 -284.085837)
			(xy 335.79214 -284.028569) (xy 335.819609 -283.974951) (xy 335.855162 -283.926316) (xy 335.876138 -283.90469)
			(xy 335.88298 -283.897292) (xy 335.890698 -283.878691) (xy 335.891124 -283.868622) (xy 335.891124 -283.796486)
			(xy 335.890726 -283.786413) (xy 335.882988 -283.767815) (xy 335.876138 -283.760418) (xy 335.855148 -283.738802)
			(xy 335.819579 -283.690172) (xy 335.7921 -283.636553) (xy 335.773395 -283.57928) (xy 335.763928 -283.519779)
			(xy 335.763362 -283.489654) (xy 335.763935 -283.459815) (xy 335.773252 -283.400869) (xy 335.781904 -283.372306)
			(xy 335.785206 -283.361892) (xy 335.78292 -283.340302) (xy 335.732628 -283.25572) (xy 335.715356 -283.243274)
			(xy 335.704434 -283.241242) (xy 335.676582 -283.235401) (xy 335.622919 -283.216462) (xy 335.572662 -283.189766)
			(xy 335.526925 -283.155903) (xy 335.486724 -283.115625) (xy 335.452948 -283.069825) (xy 335.426347 -283.019518)
			(xy 335.40751 -282.965818) (xy 335.401666 -282.937966) (xy 335.399126 -282.92552) (xy 335.383886 -282.906216)
			(xy 335.282794 -282.862528) (xy 335.258156 -282.864306) (xy 335.247488 -282.871164) (xy 335.224497 -282.885167)
			(xy 335.175431 -282.907306) (xy 335.123735 -282.922312) (xy 335.070441 -282.929886) (xy 335.043526 -282.930346)
			(xy 335.025506 -282.930131) (xy 334.989632 -282.926693) (xy 334.971898 -282.923488) (xy 334.962246 -282.92171)
			(xy 334.943196 -282.925266) (xy 334.868266 -282.973272) (xy 334.856836 -282.98902) (xy 334.85455 -282.998418)
			(xy 334.847165 -283.025466) (xy 334.825537 -283.077195) (xy 334.796572 -283.125203) (xy 334.760896 -283.168456)
			(xy 334.719275 -283.206023) (xy 334.672605 -283.237097) (xy 334.621891 -283.261008) (xy 334.568224 -283.277242)
			(xy 334.51276 -283.28545) (xy 334.484726 -283.285946) (xy 334.457477 -283.285398) (xy 334.403534 -283.277646)
			(xy 334.351242 -283.262296) (xy 334.301668 -283.23966) (xy 334.255819 -283.2102) (xy 334.21463 -283.174516)
			(xy 334.178938 -283.133332) (xy 334.14947 -283.087488) (xy 334.126827 -283.037918) (xy 334.111468 -282.985629)
			(xy 334.103707 -282.931687) (xy 334.103218 -282.904438) (xy 331.789532 -282.904438) (xy 331.789532 -286.238188)
			(xy 331.78988 -286.246892) (xy 331.79569 -286.2633) (xy 331.806647 -286.276826) (xy 331.813916 -286.281622)
			(xy 331.82306 -286.28721) (xy 331.907647 -286.299054) (xy 332.075675 -286.329815) (xy 332.242037 -286.36859)
			(xy 332.40635 -286.41529) (xy 332.568238 -286.469807) (xy 332.727328 -286.532017) (xy 332.883256 -286.601777)
			(xy 333.035662 -286.678926) (xy 333.071802 -286.699452) (xy 340.924132 -286.699452) (xy 340.928203 -286.64383)
			(xy 340.940329 -286.589393) (xy 340.960252 -286.537302) (xy 340.987548 -286.488667) (xy 341.021634 -286.444524)
			(xy 341.061783 -286.405815) (xy 341.107141 -286.373364) (xy 341.156741 -286.347863) (xy 341.209525 -286.329856)
			(xy 341.264368 -286.319726) (xy 341.320102 -286.317689) (xy 341.375539 -286.323789) (xy 341.429496 -286.337895)
			(xy 341.480825 -286.359707) (xy 341.528431 -286.388761) (xy 341.571299 -286.424436) (xy 341.608516 -286.465973)
			(xy 341.639289 -286.512486) (xy 341.662961 -286.562983) (xy 341.672993 -286.596328) (xy 341.832182 -286.596328)
			(xy 341.836253 -286.540706) (xy 341.848379 -286.486269) (xy 341.868302 -286.434178) (xy 341.895598 -286.385543)
			(xy 341.929684 -286.3414) (xy 341.969833 -286.302691) (xy 342.015191 -286.27024) (xy 342.064791 -286.244739)
			(xy 342.117575 -286.226732) (xy 342.172418 -286.216602) (xy 342.228152 -286.214565) (xy 342.283589 -286.220665)
			(xy 342.337546 -286.234771) (xy 342.388875 -286.256583) (xy 342.436481 -286.285637) (xy 342.479349 -286.321312)
			(xy 342.516566 -286.362849) (xy 342.547339 -286.409362) (xy 342.571011 -286.459859) (xy 342.587079 -286.513266)
			(xy 342.595199 -286.568442) (xy 342.595708 -286.596328) (xy 342.595199 -286.624214) (xy 342.587079 -286.67939)
			(xy 342.571011 -286.732797) (xy 342.547339 -286.783294) (xy 342.518786 -286.826452) (xy 357.611932 -286.826452)
			(xy 357.616003 -286.77083) (xy 357.628129 -286.716393) (xy 357.648052 -286.664302) (xy 357.675348 -286.615667)
			(xy 357.709434 -286.571524) (xy 357.749583 -286.532815) (xy 357.794941 -286.500364) (xy 357.844541 -286.474863)
			(xy 357.897325 -286.456856) (xy 357.952168 -286.446726) (xy 358.007902 -286.444689) (xy 358.063339 -286.450789)
			(xy 358.117296 -286.464895) (xy 358.168625 -286.486707) (xy 358.216231 -286.515761) (xy 358.259099 -286.551436)
			(xy 358.296316 -286.592973) (xy 358.327089 -286.639486) (xy 358.350761 -286.689983) (xy 358.365531 -286.739076)
			(xy 358.56494 -286.739076) (xy 358.569011 -286.683454) (xy 358.581137 -286.629017) (xy 358.60106 -286.576926)
			(xy 358.628356 -286.528291) (xy 358.662442 -286.484148) (xy 358.702591 -286.445439) (xy 358.747949 -286.412988)
			(xy 358.797549 -286.387487) (xy 358.850333 -286.36948) (xy 358.905176 -286.35935) (xy 358.96091 -286.357313)
			(xy 359.016347 -286.363413) (xy 359.070304 -286.377519) (xy 359.121633 -286.399331) (xy 359.169239 -286.428385)
			(xy 359.212107 -286.46406) (xy 359.249324 -286.505597) (xy 359.280097 -286.55211) (xy 359.303769 -286.602607)
			(xy 359.319837 -286.656014) (xy 359.327957 -286.71119) (xy 359.328466 -286.739076) (xy 359.327957 -286.766962)
			(xy 359.319837 -286.822138) (xy 359.303769 -286.875545) (xy 359.280097 -286.926042) (xy 359.249324 -286.972555)
			(xy 359.212107 -287.014092) (xy 359.169239 -287.049767) (xy 359.121633 -287.078821) (xy 359.070304 -287.100633)
			(xy 359.016347 -287.114739) (xy 358.96091 -287.120839) (xy 358.905176 -287.118802) (xy 358.850333 -287.108672)
			(xy 358.797549 -287.090665) (xy 358.747949 -287.065164) (xy 358.702591 -287.032713) (xy 358.662442 -286.994004)
			(xy 358.628356 -286.949861) (xy 358.60106 -286.901226) (xy 358.581137 -286.849135) (xy 358.569011 -286.794698)
			(xy 358.56494 -286.739076) (xy 358.365531 -286.739076) (xy 358.366829 -286.74339) (xy 358.374949 -286.798566)
			(xy 358.375458 -286.826452) (xy 358.374949 -286.854338) (xy 358.366829 -286.909514) (xy 358.350761 -286.962921)
			(xy 358.327089 -287.013418) (xy 358.296316 -287.059931) (xy 358.259099 -287.101468) (xy 358.216231 -287.137143)
			(xy 358.168625 -287.166197) (xy 358.117296 -287.188009) (xy 358.063339 -287.202115) (xy 358.007902 -287.208215)
			(xy 357.952168 -287.206178) (xy 357.897325 -287.196048) (xy 357.844541 -287.178041) (xy 357.794941 -287.15254)
			(xy 357.749583 -287.120089) (xy 357.709434 -287.08138) (xy 357.675348 -287.037237) (xy 357.648052 -286.988602)
			(xy 357.628129 -286.936511) (xy 357.616003 -286.882074) (xy 357.611932 -286.826452) (xy 342.518786 -286.826452)
			(xy 342.516566 -286.829807) (xy 342.479349 -286.871344) (xy 342.436481 -286.907019) (xy 342.388875 -286.936073)
			(xy 342.337546 -286.957885) (xy 342.283589 -286.971991) (xy 342.228152 -286.978091) (xy 342.172418 -286.976054)
			(xy 342.117575 -286.965924) (xy 342.064791 -286.947917) (xy 342.015191 -286.922416) (xy 341.969833 -286.889965)
			(xy 341.929684 -286.851256) (xy 341.895598 -286.807113) (xy 341.868302 -286.758478) (xy 341.848379 -286.706387)
			(xy 341.836253 -286.65195) (xy 341.832182 -286.596328) (xy 341.672993 -286.596328) (xy 341.679029 -286.61639)
			(xy 341.687149 -286.671566) (xy 341.687658 -286.699452) (xy 341.687149 -286.727338) (xy 341.679029 -286.782514)
			(xy 341.662961 -286.835921) (xy 341.639289 -286.886418) (xy 341.608516 -286.932931) (xy 341.571299 -286.974468)
			(xy 341.528431 -287.010143) (xy 341.480825 -287.039197) (xy 341.429496 -287.061009) (xy 341.375539 -287.075115)
			(xy 341.320102 -287.081215) (xy 341.264368 -287.079178) (xy 341.209525 -287.069048) (xy 341.156741 -287.051041)
			(xy 341.107141 -287.02554) (xy 341.061783 -286.993089) (xy 341.021634 -286.95438) (xy 340.987548 -286.910237)
			(xy 340.960252 -286.861602) (xy 340.940329 -286.809511) (xy 340.928203 -286.755074) (xy 340.924132 -286.699452)
			(xy 333.071802 -286.699452) (xy 333.184198 -286.763288) (xy 333.328522 -286.854668) (xy 333.468303 -286.952857)
			(xy 333.60322 -287.05763) (xy 333.732962 -287.168745) (xy 333.857233 -287.285948) (xy 333.975747 -287.408969)
			(xy 334.088231 -287.537527) (xy 334.194428 -287.671326) (xy 334.294093 -287.810058) (xy 334.386998 -287.953405)
			(xy 334.472929 -288.101038) (xy 334.551689 -288.252619) (xy 334.623098 -288.407798) (xy 334.686991 -288.56622)
			(xy 334.743221 -288.72752) (xy 334.79166 -288.89133) (xy 334.832196 -289.057271) (xy 334.864736 -289.224964)
			(xy 334.889205 -289.394023) (xy 334.905548 -289.564061) (xy 334.913727 -289.734686) (xy 334.91424 -289.820096)
			(xy 334.913747 -289.90474) (xy 334.905724 -290.073839) (xy 334.889682 -290.242366) (xy 334.865658 -290.409941)
			(xy 334.833704 -290.576186) (xy 334.793894 -290.740728) (xy 334.746317 -290.903193) (xy 334.69108 -291.063217)
			(xy 334.628308 -291.220437) (xy 334.558143 -291.3745) (xy 334.480742 -291.525059) (xy 334.396281 -291.671772)
			(xy 334.304949 -291.814311) (xy 334.206954 -291.952353) (xy 334.102515 -292.085586) (xy 333.991869 -292.213711)
			(xy 333.875264 -292.336438) (xy 333.752964 -292.453491) (xy 333.689452 -292.509448) (xy 333.688944 -292.509448)
			(xy 333.68869 -292.509956) (xy 333.684773 -292.513603) (xy 333.67838 -292.522185) (xy 333.67599 -292.526974)
			(xy 333.671672 -292.536626) (xy 333.671672 -293.121842) (xy 333.67218 -293.128446) (xy 333.673487 -293.136459)
			(xy 333.680476 -293.151103) (xy 333.685896 -293.157148) (xy 333.901288 -293.372286) (xy 334.123792 -293.59479)
			(xy 334.1243 -293.595298) (xy 334.130048 -293.6005) (xy 334.143878 -293.607488) (xy 334.151478 -293.609014)
			(xy 334.15986 -293.609776)
		)
		(stroke
			(width 0)
			(type solid)
		)
		(fill yes)
		(layer "In13.Cu")
		(net "GND")
	)
	(gr_poly
		(pts
			(xy 400.421094 -416.614102) (xy 400.431116 -416.613684) (xy 400.449636 -416.606015) (xy 400.46381 -416.591842)
			(xy 400.471482 -416.573324) (xy 400.471894 -416.563302) (xy 400.471894 -416.202876) (xy 400.472321 -416.192808)
			(xy 400.480041 -416.174209) (xy 400.48688 -416.166808) (xy 401.05965 -415.594038) (xy 401.064849 -415.588289)
			(xy 401.071827 -415.574457) (xy 401.073366 -415.56686) (xy 401.074128 -415.558478) (xy 401.074128 -395.582394)
			(xy 401.07378 -395.573703) (xy 401.067932 -395.557337) (xy 401.062698 -395.55039) (xy 401.059396 -395.54658)
			(xy 400.88312 -395.370304) (xy 400.876271 -395.362906) (xy 400.868532 -395.344308) (xy 400.868134 -395.334236)
			(xy 400.868134 -394.201904) (xy 400.868557 -394.191834) (xy 400.876274 -394.173232) (xy 400.88312 -394.165836)
			(xy 401.239228 -393.809728) (xy 401.246627 -393.802883) (xy 401.265225 -393.795154) (xy 401.275296 -393.794742)
			(xy 414.077658 -393.794742) (xy 414.087723 -393.795177) (xy 414.106308 -393.802911) (xy 414.113726 -393.809728)
			(xy 414.212278 -393.90828) (xy 414.219114 -393.915682) (xy 414.226823 -393.93428) (xy 414.227264 -393.944348)
			(xy 414.227264 -394.010642) (xy 414.228026 -394.019024) (xy 414.229545 -394.026626) (xy 414.236539 -394.040453)
			(xy 414.241742 -394.046202) (xy 414.379918 -394.184378) (xy 416.325556 -394.184378) (xy 416.329627 -394.128756)
			(xy 416.341753 -394.074319) (xy 416.361676 -394.022228) (xy 416.388972 -393.973593) (xy 416.423058 -393.92945)
			(xy 416.463207 -393.890741) (xy 416.508565 -393.85829) (xy 416.558165 -393.832789) (xy 416.610949 -393.814782)
			(xy 416.665792 -393.804652) (xy 416.721526 -393.802615) (xy 416.776963 -393.808715) (xy 416.83092 -393.822821)
			(xy 416.882249 -393.844633) (xy 416.929855 -393.873687) (xy 416.972723 -393.909362) (xy 417.00994 -393.950899)
			(xy 417.040713 -393.997412) (xy 417.064385 -394.047909) (xy 417.080453 -394.101316) (xy 417.088573 -394.156492)
			(xy 417.089082 -394.184378) (xy 417.088573 -394.212264) (xy 417.080453 -394.26744) (xy 417.064385 -394.320847)
			(xy 417.040713 -394.371344) (xy 417.00994 -394.417857) (xy 416.972723 -394.459394) (xy 416.929855 -394.495069)
			(xy 416.882249 -394.524123) (xy 416.83092 -394.545935) (xy 416.776963 -394.560041) (xy 416.721526 -394.566141)
			(xy 416.665792 -394.564104) (xy 416.610949 -394.553974) (xy 416.558165 -394.535967) (xy 416.508565 -394.510466)
			(xy 416.463207 -394.478015) (xy 416.423058 -394.439306) (xy 416.388972 -394.395163) (xy 416.361676 -394.346528)
			(xy 416.341753 -394.294437) (xy 416.329627 -394.24) (xy 416.325556 -394.184378) (xy 414.379918 -394.184378)
			(xy 414.462722 -394.267182) (xy 414.472882 -394.275056) (xy 414.474152 -394.275818) (xy 414.47974 -394.278866)
			(xy 414.486598 -394.280644) (xy 414.486852 -394.280644) (xy 414.497665 -394.283945) (xy 414.515148 -394.298236)
			(xy 414.524838 -394.318631) (xy 414.52546 -394.32992) (xy 414.52546 -397.822887) (xy 419.004818 -397.822887)
			(xy 419.004822 -397.757448) (xy 419.013611 -397.692601) (xy 419.031025 -397.62952) (xy 419.05675 -397.569349)
			(xy 419.073076 -397.540988) (xy 419.076393 -397.534965) (xy 419.079998 -397.5217) (xy 419.080188 -397.514826)
			(xy 419.080188 -396.765526) (xy 419.079987 -396.758653) (xy 419.076385 -396.745391) (xy 419.073076 -396.739364)
			(xy 419.056744 -396.711008) (xy 419.031025 -396.650836) (xy 419.013617 -396.587756) (xy 419.004834 -396.52291)
			(xy 419.004835 -396.457472) (xy 419.01362 -396.392627) (xy 419.031031 -396.329548) (xy 419.056752 -396.269377)
			(xy 419.073076 -396.241016) (xy 419.076383 -396.234988) (xy 419.079994 -396.221727) (xy 419.080188 -396.214854)
			(xy 419.080188 -395.92885) (xy 419.080606 -395.918675) (xy 419.088384 -395.899872) (xy 419.102772 -395.885484)
			(xy 419.121575 -395.877706) (xy 419.13175 -395.877288) (xy 419.84803 -395.877288) (xy 419.85821 -395.87764)
			(xy 419.877015 -395.885445) (xy 419.8914 -395.899852) (xy 419.899175 -395.91867) (xy 419.899592 -395.92885)
			(xy 419.899592 -396.214854) (xy 419.899803 -396.221726) (xy 419.903398 -396.234989) (xy 419.906704 -396.241016)
			(xy 419.923016 -396.269382) (xy 419.948733 -396.329553) (xy 419.96614 -396.39263) (xy 419.974924 -396.457474)
			(xy 419.974925 -396.522909) (xy 419.966143 -396.587753) (xy 419.948738 -396.650831) (xy 419.923024 -396.711002)
			(xy 419.906704 -396.739364) (xy 419.903402 -396.745395) (xy 419.899788 -396.758654) (xy 419.899592 -396.765526)
			(xy 419.899592 -397.514826) (xy 419.899775 -397.5217) (xy 419.903389 -397.534963) (xy 419.906704 -397.540988)
			(xy 419.922993 -397.569367) (xy 419.948711 -397.629535) (xy 419.966121 -397.69261) (xy 419.974908 -397.757451)
			(xy 419.974912 -397.822884) (xy 419.966134 -397.887726) (xy 419.948733 -397.950803) (xy 419.923022 -398.010974)
			(xy 419.906704 -398.039336) (xy 419.903377 -398.045355) (xy 419.899779 -398.058623) (xy 419.899592 -398.065498)
			(xy 419.899592 -398.351502) (xy 419.899069 -398.361656) (xy 419.891299 -398.38042) (xy 419.876943 -398.394784)
			(xy 419.858184 -398.402563) (xy 419.84803 -398.403064) (xy 419.13175 -398.403064) (xy 419.121582 -398.402595)
			(xy 419.102789 -398.394827) (xy 419.088402 -398.380455) (xy 419.080615 -398.36167) (xy 419.080188 -398.351502)
			(xy 419.080188 -398.065498) (xy 419.079999 -398.058625) (xy 419.076389 -398.045362) (xy 419.073076 -398.039336)
			(xy 419.05672 -398.010993) (xy 419.031004 -397.950818) (xy 419.013598 -397.887735) (xy 419.004818 -397.822887)
			(xy 414.52546 -397.822887) (xy 414.52546 -398.890236) (xy 421.204136 -398.890236) (xy 421.204704 -398.857507)
			(xy 421.213561 -398.792649) (xy 421.23105 -398.729569) (xy 421.256856 -398.66941) (xy 421.273224 -398.641062)
			(xy 421.276554 -398.635045) (xy 421.28015 -398.621775) (xy 421.280336 -398.6149) (xy 421.280336 -397.865346)
			(xy 421.280122 -397.858474) (xy 421.276528 -397.845212) (xy 421.273224 -397.839184) (xy 421.256854 -397.810837)
			(xy 421.231053 -397.750677) (xy 421.213564 -397.687597) (xy 421.204705 -397.622739) (xy 421.204136 -397.59001)
			(xy 421.204693 -397.55728) (xy 421.213552 -397.492422) (xy 421.231046 -397.429342) (xy 421.256855 -397.369184)
			(xy 421.273224 -397.340836) (xy 421.276528 -397.334806) (xy 421.28014 -397.321546) (xy 421.280336 -397.314674)
			(xy 421.280336 -397.028924) (xy 421.280736 -397.018799) (xy 421.288483 -397.000089) (xy 421.302805 -396.985772)
			(xy 421.321518 -396.978032) (xy 421.331644 -396.977616) (xy 422.047924 -396.977616) (xy 422.058036 -396.978066)
			(xy 422.076718 -396.985814) (xy 422.091013 -397.000122) (xy 422.098744 -397.018811) (xy 422.099232 -397.028924)
			(xy 422.099232 -397.314674) (xy 422.09943 -397.321547) (xy 422.103034 -397.33481) (xy 422.106344 -397.340836)
			(xy 422.122719 -397.36918) (xy 422.148519 -397.429341) (xy 422.166007 -397.492422) (xy 422.174864 -397.557281)
			(xy 422.175432 -397.59001) (xy 422.174844 -397.622739) (xy 422.165994 -397.687596) (xy 422.14851 -397.750676)
			(xy 422.131575 -397.790162) (xy 423.404284 -397.790162) (xy 423.404857 -397.757433) (xy 423.413711 -397.692575)
			(xy 423.431199 -397.629495) (xy 423.457005 -397.569336) (xy 423.473372 -397.540988) (xy 423.476689 -397.534964)
			(xy 423.480294 -397.5217) (xy 423.480484 -397.514826) (xy 423.480484 -396.765526) (xy 423.480284 -396.758653)
			(xy 423.476681 -396.745391) (xy 423.473372 -396.739364) (xy 423.456989 -396.711024) (xy 423.431192 -396.650861)
			(xy 423.413708 -396.587779) (xy 423.404852 -396.52292) (xy 423.404284 -396.49019) (xy 423.40487 -396.457461)
			(xy 423.41372 -396.392604) (xy 423.431205 -396.329524) (xy 423.457006 -396.269365) (xy 423.473372 -396.241016)
			(xy 423.476679 -396.234988) (xy 423.48029 -396.221727) (xy 423.480484 -396.214854) (xy 423.480484 -395.92885)
			(xy 423.480969 -395.918721) (xy 423.488688 -395.899993) (xy 423.502976 -395.885633) (xy 423.521666 -395.87782)
			(xy 423.531792 -395.877288) (xy 424.248072 -395.877288) (xy 424.258223 -395.877744) (xy 424.276972 -395.885528)
			(xy 424.291296 -395.899914) (xy 424.298999 -395.918697) (xy 424.29938 -395.92885) (xy 424.29938 -396.214854)
			(xy 424.299592 -396.221726) (xy 424.303187 -396.234988) (xy 424.306492 -396.241016) (xy 424.322863 -396.269362)
			(xy 424.348664 -396.329523) (xy 424.366152 -396.392603) (xy 424.375011 -396.457461) (xy 424.37558 -396.49019)
			(xy 424.375035 -396.52292) (xy 424.366173 -396.587779) (xy 424.348677 -396.65086) (xy 424.322863 -396.711017)
			(xy 424.306492 -396.739364) (xy 424.303189 -396.745395) (xy 424.299576 -396.758654) (xy 424.29938 -396.765526)
			(xy 424.29938 -397.514826) (xy 424.299565 -397.5217) (xy 424.303178 -397.534962) (xy 424.306492 -397.540988)
			(xy 424.315899 -397.557291) (xy 425.604789 -397.557291) (xy 425.613571 -397.492447) (xy 425.630976 -397.429369)
			(xy 425.656691 -397.369198) (xy 425.673012 -397.340836) (xy 425.676315 -397.334806) (xy 425.679928 -397.321546)
			(xy 425.680124 -397.314674) (xy 425.680124 -397.028924) (xy 425.680542 -397.018768) (xy 425.688334 -397.000012)
			(xy 425.702732 -396.985687) (xy 425.721528 -396.97799) (xy 425.731686 -396.977616) (xy 426.447966 -396.977616)
			(xy 426.458088 -396.978154) (xy 426.476803 -396.985866) (xy 426.49116 -397.000137) (xy 426.498984 -397.018806)
			(xy 426.499528 -397.028924) (xy 426.499528 -397.314674) (xy 426.499726 -397.321547) (xy 426.50333 -397.33481)
			(xy 426.50664 -397.340836) (xy 426.522971 -397.369192) (xy 426.548689 -397.429364) (xy 426.566097 -397.492444)
			(xy 426.57488 -397.55729) (xy 426.574879 -397.622727) (xy 426.566094 -397.687573) (xy 426.548684 -397.750652)
			(xy 426.522964 -397.810823) (xy 426.51602 -397.822887) (xy 427.804904 -397.822887) (xy 427.804908 -397.757448)
			(xy 427.813697 -397.692601) (xy 427.831111 -397.629521) (xy 427.856835 -397.569349) (xy 427.87316 -397.540988)
			(xy 427.876476 -397.534964) (xy 427.880081 -397.5217) (xy 427.880272 -397.514826) (xy 427.880272 -396.765526)
			(xy 427.880074 -396.758653) (xy 427.87647 -396.74539) (xy 427.87316 -396.739364) (xy 427.856829 -396.711008)
			(xy 427.831111 -396.650836) (xy 427.813703 -396.587756) (xy 427.80492 -396.52291) (xy 427.804921 -396.457473)
			(xy 427.813706 -396.392627) (xy 427.831116 -396.329548) (xy 427.856836 -396.269377) (xy 427.87316 -396.241016)
			(xy 427.876466 -396.234987) (xy 427.880077 -396.221727) (xy 427.880272 -396.214854) (xy 427.880272 -395.92885)
			(xy 427.880706 -395.918677) (xy 427.88848 -395.899877) (xy 427.902864 -395.885489) (xy 427.921662 -395.877709)
			(xy 427.931834 -395.877288) (xy 428.648114 -395.877288) (xy 428.658293 -395.877654) (xy 428.677097 -395.885453)
			(xy 428.691483 -395.899857) (xy 428.699259 -395.918671) (xy 428.699676 -395.92885) (xy 428.699676 -396.214854)
			(xy 428.699888 -396.221726) (xy 428.703483 -396.234988) (xy 428.706788 -396.241016) (xy 428.723101 -396.269382)
			(xy 428.748818 -396.329553) (xy 428.766226 -396.39263) (xy 428.77501 -396.457474) (xy 428.775011 -396.522909)
			(xy 428.766229 -396.587753) (xy 428.748824 -396.650831) (xy 428.723109 -396.711002) (xy 428.706788 -396.739364)
			(xy 428.703485 -396.745394) (xy 428.699872 -396.758654) (xy 428.699676 -396.765526) (xy 428.699676 -397.514826)
			(xy 428.699861 -397.5217) (xy 428.703474 -397.534962) (xy 428.706788 -397.540988) (xy 428.723077 -397.569367)
			(xy 428.748796 -397.629535) (xy 428.766207 -397.692609) (xy 428.774994 -397.757451) (xy 428.774998 -397.822884)
			(xy 428.76622 -397.887727) (xy 428.748818 -397.950804) (xy 428.723107 -398.010975) (xy 428.706788 -398.039336)
			(xy 428.70346 -398.045354) (xy 428.699863 -398.058623) (xy 428.699676 -398.065498) (xy 428.699676 -398.351502)
			(xy 428.699169 -398.361658) (xy 428.691396 -398.380425) (xy 428.677035 -398.394789) (xy 428.65827 -398.402566)
			(xy 428.648114 -398.403064) (xy 427.931834 -398.403064) (xy 427.921665 -398.402608) (xy 427.902871 -398.394835)
			(xy 427.888485 -398.380459) (xy 427.880699 -398.361671) (xy 427.880272 -398.351502) (xy 427.880272 -398.065498)
			(xy 427.880084 -398.058624) (xy 427.876473 -398.045362) (xy 427.87316 -398.039336) (xy 427.856805 -398.010993)
			(xy 427.831089 -397.950818) (xy 427.813684 -397.887735) (xy 427.804904 -397.822887) (xy 426.51602 -397.822887)
			(xy 426.50664 -397.839184) (xy 426.503334 -397.845213) (xy 426.499723 -397.858473) (xy 426.499528 -397.865346)
			(xy 426.499528 -398.6149) (xy 426.499717 -398.621774) (xy 426.503327 -398.635036) (xy 426.50664 -398.641062)
			(xy 426.522993 -398.669406) (xy 426.548709 -398.729581) (xy 426.566115 -398.792663) (xy 426.574895 -398.857511)
			(xy 426.574893 -398.890236) (xy 430.00422 -398.890236) (xy 430.004777 -398.857506) (xy 430.013635 -398.792647)
			(xy 430.031128 -398.729567) (xy 430.056938 -398.66941) (xy 430.073308 -398.641062) (xy 430.076637 -398.635044)
			(xy 430.080233 -398.621775) (xy 430.08042 -398.6149) (xy 430.08042 -397.865346) (xy 430.080208 -397.858474)
			(xy 430.076613 -397.845212) (xy 430.073308 -397.839184) (xy 430.056937 -397.810838) (xy 430.031136 -397.750677)
			(xy 430.013648 -397.687597) (xy 430.004789 -397.622739) (xy 430.00422 -397.59001) (xy 430.004765 -397.55728)
			(xy 430.013627 -397.492421) (xy 430.031123 -397.42934) (xy 430.056937 -397.369183) (xy 430.073308 -397.340836)
			(xy 430.076611 -397.334805) (xy 430.080224 -397.321546) (xy 430.08042 -397.314674) (xy 430.08042 -397.028924)
			(xy 430.080836 -397.018801) (xy 430.08858 -397.000094) (xy 430.102897 -396.985778) (xy 430.121605 -396.978035)
			(xy 430.131728 -396.977616) (xy 430.848008 -396.977616) (xy 430.858133 -396.97801) (xy 430.87684 -396.985764)
			(xy 430.891154 -397.000087) (xy 430.898896 -397.018799) (xy 430.899316 -397.028924) (xy 430.899316 -397.314674)
			(xy 430.899516 -397.321547) (xy 430.903119 -397.334809) (xy 430.906428 -397.340836) (xy 430.922811 -397.369176)
			(xy 430.948608 -397.429339) (xy 430.966092 -397.492421) (xy 430.974948 -397.55728) (xy 430.975516 -397.59001)
			(xy 430.97493 -397.622739) (xy 430.96608 -397.687596) (xy 430.948595 -397.750676) (xy 430.922794 -397.810835)
			(xy 430.915836 -397.822887) (xy 432.204694 -397.822887) (xy 432.204698 -397.757448) (xy 432.213486 -397.692601)
			(xy 432.2309 -397.629521) (xy 432.256623 -397.569349) (xy 432.272948 -397.540988) (xy 432.276263 -397.534963)
			(xy 432.279869 -397.5217) (xy 432.28006 -397.514826) (xy 432.28006 -396.765526) (xy 432.279863 -396.758653)
			(xy 432.276259 -396.74539) (xy 432.272948 -396.739364) (xy 432.256617 -396.711008) (xy 432.2309 -396.650835)
			(xy 432.213492 -396.587756) (xy 432.20471 -396.52291) (xy 432.204711 -396.457473) (xy 432.213496 -396.392628)
			(xy 432.230905 -396.329548) (xy 432.256625 -396.269377) (xy 432.272948 -396.241016) (xy 432.276253 -396.234986)
			(xy 432.279865 -396.221727) (xy 432.28006 -396.214854) (xy 432.28006 -395.92885) (xy 432.280505 -395.918679)
			(xy 432.288278 -395.899881) (xy 432.302658 -395.885494) (xy 432.321451 -395.877711) (xy 432.331622 -395.877288)
			(xy 433.047902 -395.877288) (xy 433.05808 -395.877663) (xy 433.076884 -395.885458) (xy 433.091271 -395.899859)
			(xy 433.099047 -395.918672) (xy 433.099464 -395.92885) (xy 433.099464 -396.214854) (xy 433.099678 -396.221726)
			(xy 433.103272 -396.234988) (xy 433.106576 -396.241016) (xy 433.122889 -396.269382) (xy 433.148607 -396.329552)
			(xy 433.166015 -396.39263) (xy 433.1748 -396.457474) (xy 433.1748 -396.49019) (xy 436.603656 -396.49019)
			(xy 436.607647 -396.428023) (xy 436.619556 -396.366876) (xy 436.639185 -396.307755) (xy 436.666214 -396.251629)
			(xy 436.700198 -396.19942) (xy 436.74058 -396.151985) (xy 436.786696 -396.110104) (xy 436.837788 -396.074464)
			(xy 436.893019 -396.04565) (xy 436.951481 -396.024136) (xy 437.012215 -396.010274) (xy 437.074222 -396.004292)
			(xy 437.136485 -396.006288) (xy 437.197982 -396.016231) (xy 437.257703 -396.033955) (xy 437.314666 -396.059172)
			(xy 437.367937 -396.091465) (xy 437.416642 -396.130305) (xy 437.459979 -396.175055) (xy 437.497239 -396.224979)
			(xy 437.527808 -396.279258) (xy 437.551186 -396.337001) (xy 437.566987 -396.397259) (xy 437.574953 -396.459042)
			(xy 437.575452 -396.49019) (xy 437.574953 -396.521338) (xy 437.566987 -396.583121) (xy 437.551186 -396.643379)
			(xy 437.527808 -396.701122) (xy 437.497239 -396.755401) (xy 437.459979 -396.805325) (xy 437.416642 -396.850075)
			(xy 437.367937 -396.888915) (xy 437.314666 -396.921208) (xy 437.257703 -396.946425) (xy 437.197982 -396.964149)
			(xy 437.136485 -396.974092) (xy 437.074222 -396.976088) (xy 437.012215 -396.970106) (xy 436.951481 -396.956244)
			(xy 436.893019 -396.93473) (xy 436.837788 -396.905916) (xy 436.786696 -396.870276) (xy 436.74058 -396.828395)
			(xy 436.700198 -396.78096) (xy 436.666214 -396.728751) (xy 436.639185 -396.672625) (xy 436.619556 -396.613504)
			(xy 436.607647 -396.552357) (xy 436.603656 -396.49019) (xy 433.1748 -396.49019) (xy 433.174801 -396.522909)
			(xy 433.166019 -396.587753) (xy 433.148613 -396.650831) (xy 433.122897 -396.711003) (xy 433.106576 -396.739364)
			(xy 433.103272 -396.745394) (xy 433.09966 -396.758654) (xy 433.099464 -396.765526) (xy 433.099464 -397.514826)
			(xy 433.099651 -397.5217) (xy 433.103263 -397.534962) (xy 433.106576 -397.540988) (xy 433.115934 -397.557291)
			(xy 434.404875 -397.557291) (xy 434.413657 -397.492447) (xy 434.431062 -397.429369) (xy 434.456776 -397.369198)
			(xy 434.473096 -397.340836) (xy 434.476398 -397.334805) (xy 434.480012 -397.321546) (xy 434.480208 -397.314674)
			(xy 434.480208 -397.028924) (xy 434.480641 -397.01877) (xy 434.48843 -397.000017) (xy 434.502824 -396.985692)
			(xy 434.521614 -396.977993) (xy 434.53177 -396.977616) (xy 435.24805 -396.977616) (xy 435.258171 -396.978167)
			(xy 435.276886 -396.985874) (xy 435.291243 -397.00014) (xy 435.299068 -397.018807) (xy 435.299612 -397.028924)
			(xy 435.299612 -397.314674) (xy 435.299813 -397.321547) (xy 435.303415 -397.334809) (xy 435.306724 -397.340836)
			(xy 435.323056 -397.369192) (xy 435.348775 -397.429364) (xy 435.366183 -397.492444) (xy 435.374966 -397.55729)
			(xy 435.374965 -397.622728) (xy 435.36618 -397.687573) (xy 435.348769 -397.750652) (xy 435.33188 -397.790162)
			(xy 436.603656 -397.790162) (xy 436.607647 -397.727995) (xy 436.619556 -397.666848) (xy 436.639185 -397.607727)
			(xy 436.666214 -397.551601) (xy 436.700198 -397.499392) (xy 436.74058 -397.451957) (xy 436.786696 -397.410076)
			(xy 436.837788 -397.374436) (xy 436.893019 -397.345622) (xy 436.951481 -397.324108) (xy 437.012215 -397.310246)
			(xy 437.074222 -397.304264) (xy 437.136485 -397.30626) (xy 437.197982 -397.316203) (xy 437.257703 -397.333927)
			(xy 437.314666 -397.359144) (xy 437.367937 -397.391437) (xy 437.416642 -397.430277) (xy 437.459979 -397.475027)
			(xy 437.497239 -397.524951) (xy 437.527808 -397.57923) (xy 437.532172 -397.59001) (xy 438.803804 -397.59001)
			(xy 438.807795 -397.527843) (xy 438.819704 -397.466696) (xy 438.839333 -397.407575) (xy 438.866362 -397.351449)
			(xy 438.900346 -397.29924) (xy 438.940728 -397.251805) (xy 438.986844 -397.209924) (xy 439.037936 -397.174284)
			(xy 439.093167 -397.14547) (xy 439.151629 -397.123956) (xy 439.212363 -397.110094) (xy 439.27437 -397.104112)
			(xy 439.336633 -397.106108) (xy 439.39813 -397.116051) (xy 439.457851 -397.133775) (xy 439.514814 -397.158992)
			(xy 439.568085 -397.191285) (xy 439.61679 -397.230125) (xy 439.660127 -397.274875) (xy 439.697387 -397.324799)
			(xy 439.727956 -397.379078) (xy 439.751334 -397.436821) (xy 439.767135 -397.497079) (xy 439.775101 -397.558862)
			(xy 439.7756 -397.59001) (xy 439.775101 -397.621158) (xy 439.767135 -397.682941) (xy 439.751334 -397.743199)
			(xy 439.727956 -397.800942) (xy 439.697387 -397.855221) (xy 439.660127 -397.905145) (xy 439.61679 -397.949895)
			(xy 439.568085 -397.988735) (xy 439.514814 -398.021028) (xy 439.457851 -398.046245) (xy 439.39813 -398.063969)
			(xy 439.336633 -398.073912) (xy 439.27437 -398.075908) (xy 439.212363 -398.069926) (xy 439.151629 -398.056064)
			(xy 439.093167 -398.03455) (xy 439.037936 -398.005736) (xy 438.986844 -397.970096) (xy 438.940728 -397.928215)
			(xy 438.900346 -397.88078) (xy 438.866362 -397.828571) (xy 438.839333 -397.772445) (xy 438.819704 -397.713324)
			(xy 438.807795 -397.652177) (xy 438.803804 -397.59001) (xy 437.532172 -397.59001) (xy 437.551186 -397.636973)
			(xy 437.566987 -397.697231) (xy 437.574953 -397.759014) (xy 437.575452 -397.790162) (xy 437.574953 -397.82131)
			(xy 437.566987 -397.883093) (xy 437.551186 -397.943351) (xy 437.527808 -398.001094) (xy 437.497239 -398.055373)
			(xy 437.463901 -398.100042) (xy 459.541382 -398.100042) (xy 459.545364 -397.972056) (xy 459.557296 -397.844565)
			(xy 459.57713 -397.718062) (xy 459.604791 -397.593037) (xy 459.640171 -397.469974) (xy 459.683133 -397.349348)
			(xy 459.733511 -397.231627) (xy 459.791111 -397.117265) (xy 459.855709 -397.006706) (xy 459.927056 -396.900376)
			(xy 460.004875 -396.798688) (xy 460.088865 -396.702034) (xy 460.178702 -396.610789) (xy 460.274038 -396.525306)
			(xy 460.374503 -396.445915) (xy 460.479711 -396.372923) (xy 460.589252 -396.306614) (xy 460.702704 -396.247243)
			(xy 460.819628 -396.195039) (xy 460.939571 -396.150206) (xy 461.062069 -396.112917) (xy 461.186649 -396.083315)
			(xy 461.312827 -396.061516) (xy 461.440117 -396.047603) (xy 461.568026 -396.041631) (xy 461.696059 -396.043622)
			(xy 461.82372 -396.05357) (xy 461.950516 -396.071434) (xy 462.075955 -396.097147) (xy 462.199554 -396.130609)
			(xy 462.320833 -396.17169) (xy 462.439324 -396.220232) (xy 462.554568 -396.276046) (xy 462.666118 -396.338917)
			(xy 462.773545 -396.408601) (xy 462.876431 -396.484829) (xy 462.974379 -396.567306) (xy 463.06701 -396.655713)
			(xy 463.153966 -396.749708) (xy 463.23491 -396.848927) (xy 463.309529 -396.952986) (xy 463.377534 -397.061483)
			(xy 463.438662 -397.173998) (xy 463.492677 -397.290096) (xy 463.53937 -397.409327) (xy 463.57856 -397.531231)
			(xy 463.610096 -397.655335) (xy 463.633855 -397.781159) (xy 463.649745 -397.908218) (xy 463.657706 -398.036018)
			(xy 463.658204 -398.100042) (xy 463.657706 -398.164066) (xy 463.649745 -398.291866) (xy 463.633855 -398.418925)
			(xy 463.610096 -398.544749) (xy 463.57856 -398.668853) (xy 463.53937 -398.790757) (xy 463.492677 -398.909988)
			(xy 463.438662 -399.026086) (xy 463.377534 -399.138601) (xy 463.309529 -399.247098) (xy 463.23491 -399.351157)
			(xy 463.153966 -399.450376) (xy 463.06701 -399.544371) (xy 462.974379 -399.632778) (xy 462.876431 -399.715255)
			(xy 462.773545 -399.791483) (xy 462.666118 -399.861167) (xy 462.554568 -399.924038) (xy 462.439324 -399.979852)
			(xy 462.320833 -400.028394) (xy 462.199554 -400.069475) (xy 462.075955 -400.102937) (xy 461.950516 -400.12865)
			(xy 461.82372 -400.146514) (xy 461.696059 -400.156462) (xy 461.568026 -400.158453) (xy 461.440117 -400.152481)
			(xy 461.312827 -400.138568) (xy 461.186649 -400.116769) (xy 461.062069 -400.087167) (xy 460.939571 -400.049878)
			(xy 460.819628 -400.005045) (xy 460.702704 -399.952841) (xy 460.589252 -399.89347) (xy 460.479711 -399.827161)
			(xy 460.374503 -399.754169) (xy 460.274038 -399.674778) (xy 460.178702 -399.589295) (xy 460.088865 -399.49805)
			(xy 460.004875 -399.401396) (xy 459.927056 -399.299708) (xy 459.855709 -399.193378) (xy 459.791111 -399.082819)
			(xy 459.733511 -398.968457) (xy 459.683133 -398.850736) (xy 459.640171 -398.73011) (xy 459.604791 -398.607047)
			(xy 459.57713 -398.482022) (xy 459.557296 -398.355519) (xy 459.545364 -398.228028) (xy 459.541382 -398.100042)
			(xy 437.463901 -398.100042) (xy 437.459979 -398.105297) (xy 437.416642 -398.150047) (xy 437.367937 -398.188887)
			(xy 437.314666 -398.22118) (xy 437.257703 -398.246397) (xy 437.197982 -398.264121) (xy 437.136485 -398.274064)
			(xy 437.074222 -398.27606) (xy 437.012215 -398.270078) (xy 436.951481 -398.256216) (xy 436.893019 -398.234702)
			(xy 436.837788 -398.205888) (xy 436.786696 -398.170248) (xy 436.74058 -398.128367) (xy 436.700198 -398.080932)
			(xy 436.666214 -398.028723) (xy 436.639185 -397.972597) (xy 436.619556 -397.913476) (xy 436.607647 -397.852329)
			(xy 436.603656 -397.790162) (xy 435.33188 -397.790162) (xy 435.323048 -397.810823) (xy 435.306724 -397.839184)
			(xy 435.303417 -397.845212) (xy 435.299806 -397.858473) (xy 435.299612 -397.865346) (xy 435.299612 -398.6149)
			(xy 435.299803 -398.621773) (xy 435.303412 -398.635036) (xy 435.306724 -398.641062) (xy 435.323078 -398.669406)
			(xy 435.348795 -398.729581) (xy 435.366201 -398.792663) (xy 435.374981 -398.857511) (xy 435.374979 -398.890236)
			(xy 438.803804 -398.890236) (xy 438.807795 -398.828069) (xy 438.819704 -398.766922) (xy 438.839333 -398.707801)
			(xy 438.866362 -398.651675) (xy 438.900346 -398.599466) (xy 438.940728 -398.552031) (xy 438.986844 -398.51015)
			(xy 439.037936 -398.47451) (xy 439.093167 -398.445696) (xy 439.151629 -398.424182) (xy 439.212363 -398.41032)
			(xy 439.27437 -398.404338) (xy 439.336633 -398.406334) (xy 439.39813 -398.416277) (xy 439.457851 -398.434001)
			(xy 439.514814 -398.459218) (xy 439.568085 -398.491511) (xy 439.61679 -398.530351) (xy 439.660127 -398.575101)
			(xy 439.697387 -398.625025) (xy 439.727956 -398.679304) (xy 439.751334 -398.737047) (xy 439.767135 -398.797305)
			(xy 439.775101 -398.859088) (xy 439.7756 -398.890236) (xy 439.775101 -398.921384) (xy 439.767135 -398.983167)
			(xy 439.751334 -399.043425) (xy 439.727956 -399.101168) (xy 439.697387 -399.155447) (xy 439.660127 -399.205371)
			(xy 439.61679 -399.250121) (xy 439.568085 -399.288961) (xy 439.514814 -399.321254) (xy 439.457851 -399.346471)
			(xy 439.39813 -399.364195) (xy 439.336633 -399.374138) (xy 439.27437 -399.376134) (xy 439.212363 -399.370152)
			(xy 439.151629 -399.35629) (xy 439.093167 -399.334776) (xy 439.037936 -399.305962) (xy 438.986844 -399.270322)
			(xy 438.940728 -399.228441) (xy 438.900346 -399.181006) (xy 438.866362 -399.128797) (xy 438.839333 -399.072671)
			(xy 438.819704 -399.01355) (xy 438.807795 -398.952403) (xy 438.803804 -398.890236) (xy 435.374979 -398.890236)
			(xy 435.374977 -398.922951) (xy 435.366188 -398.987798) (xy 435.348774 -399.050878) (xy 435.32305 -399.111049)
			(xy 435.306724 -399.13941) (xy 435.303407 -399.145434) (xy 435.299802 -399.158698) (xy 435.299612 -399.165572)
			(xy 435.299612 -399.451576) (xy 435.299159 -399.461727) (xy 435.291374 -399.480477) (xy 435.276987 -399.494801)
			(xy 435.258203 -399.502503) (xy 435.24805 -399.502884) (xy 434.53177 -399.502884) (xy 434.521644 -399.502399)
			(xy 434.502927 -399.494666) (xy 434.488573 -399.480379) (xy 434.48075 -399.461699) (xy 434.480208 -399.451576)
			(xy 434.480208 -399.165572) (xy 434.480026 -399.158698) (xy 434.476411 -399.145435) (xy 434.473096 -399.13941)
			(xy 434.456806 -399.111031) (xy 434.431087 -399.050864) (xy 434.413678 -398.987789) (xy 434.404891 -398.922948)
			(xy 434.404887 -398.857514) (xy 434.413665 -398.792672) (xy 434.431067 -398.729595) (xy 434.456778 -398.669424)
			(xy 434.473096 -398.641062) (xy 434.476424 -398.635044) (xy 434.480021 -398.621775) (xy 434.480208 -398.6149)
			(xy 434.480208 -397.865346) (xy 434.479997 -397.858474) (xy 434.476402 -397.845211) (xy 434.473096 -397.839184)
			(xy 434.456784 -397.810818) (xy 434.431067 -397.750647) (xy 434.41366 -397.68757) (xy 434.404876 -397.622726)
			(xy 434.404875 -397.557291) (xy 433.115934 -397.557291) (xy 433.122866 -397.569367) (xy 433.148585 -397.629534)
			(xy 433.165996 -397.692609) (xy 433.174784 -397.75745) (xy 433.174788 -397.822884) (xy 433.16601 -397.887727)
			(xy 433.148607 -397.950804) (xy 433.122895 -398.010975) (xy 433.106576 -398.039336) (xy 433.103247 -398.045353)
			(xy 433.099651 -398.058623) (xy 433.099464 -398.065498) (xy 433.099464 -398.351502) (xy 433.098968 -398.36166)
			(xy 433.091194 -398.380428) (xy 433.076828 -398.394794) (xy 433.05806 -398.402568) (xy 433.047902 -398.403064)
			(xy 432.331622 -398.403064) (xy 432.321452 -398.402618) (xy 432.302658 -398.394841) (xy 432.288273 -398.380462)
			(xy 432.280487 -398.361672) (xy 432.28006 -398.351502) (xy 432.28006 -398.065498) (xy 432.279874 -398.058624)
			(xy 432.276262 -398.045361) (xy 432.272948 -398.039336) (xy 432.256593 -398.010993) (xy 432.230878 -397.950817)
			(xy 432.213473 -397.887735) (xy 432.204694 -397.822887) (xy 430.915836 -397.822887) (xy 430.906428 -397.839184)
			(xy 430.903121 -397.845212) (xy 430.89951 -397.858473) (xy 430.899316 -397.865346) (xy 430.899316 -398.6149)
			(xy 430.899506 -398.621773) (xy 430.903116 -398.635036) (xy 430.906428 -398.641062) (xy 430.922781 -398.669418)
			(xy 430.948585 -398.729575) (xy 430.966078 -398.792653) (xy 430.974943 -398.857508) (xy 430.975516 -398.890236)
			(xy 430.974942 -398.922965) (xy 430.966088 -398.987823) (xy 430.9486 -399.050903) (xy 430.922795 -399.111062)
			(xy 430.906428 -399.13941) (xy 430.903112 -399.145434) (xy 430.899507 -399.158698) (xy 430.899316 -399.165572)
			(xy 430.899316 -399.451576) (xy 430.898865 -399.461695) (xy 430.891128 -399.480395) (xy 430.876822 -399.49471)
			(xy 430.858127 -399.502459) (xy 430.848008 -399.502884) (xy 430.131728 -399.502884) (xy 430.121605 -399.502461)
			(xy 430.102899 -399.494719) (xy 430.088583 -399.480404) (xy 430.08084 -399.461699) (xy 430.08042 -399.451576)
			(xy 430.08042 -399.165572) (xy 430.080236 -399.158698) (xy 430.076622 -399.145436) (xy 430.073308 -399.13941)
			(xy 430.056947 -399.111058) (xy 430.031144 -399.0509) (xy 430.013653 -398.987821) (xy 430.004791 -398.922965)
			(xy 430.00422 -398.890236) (xy 426.574893 -398.890236) (xy 426.574891 -398.922951) (xy 426.566102 -398.987797)
			(xy 426.548689 -399.050877) (xy 426.522965 -399.111049) (xy 426.50664 -399.13941) (xy 426.503325 -399.145435)
			(xy 426.499719 -399.158698) (xy 426.499528 -399.165572) (xy 426.499528 -399.451576) (xy 426.499059 -399.461725)
			(xy 426.491277 -399.480472) (xy 426.476895 -399.494795) (xy 426.458117 -399.502501) (xy 426.447966 -399.502884)
			(xy 425.731686 -399.502884) (xy 425.721561 -399.502385) (xy 425.702845 -399.494657) (xy 425.68849 -399.480375)
			(xy 425.680667 -399.461698) (xy 425.680124 -399.451576) (xy 425.680124 -399.165572) (xy 425.67994 -399.158698)
			(xy 425.676326 -399.145436) (xy 425.673012 -399.13941) (xy 425.656721 -399.111032) (xy 425.631002 -399.050864)
			(xy 425.613592 -398.987789) (xy 425.604805 -398.922948) (xy 425.604801 -398.857514) (xy 425.613579 -398.792672)
			(xy 425.630982 -398.729594) (xy 425.656693 -398.669423) (xy 425.673012 -398.641062) (xy 425.676341 -398.635044)
			(xy 425.679937 -398.621775) (xy 425.680124 -398.6149) (xy 425.680124 -397.865346) (xy 425.679912 -397.858474)
			(xy 425.676317 -397.845212) (xy 425.673012 -397.839184) (xy 425.656699 -397.810818) (xy 425.630982 -397.750647)
			(xy 425.613574 -397.68757) (xy 425.60479 -397.622726) (xy 425.604789 -397.557291) (xy 424.315899 -397.557291)
			(xy 424.322852 -397.56934) (xy 424.348655 -397.629499) (xy 424.366147 -397.692577) (xy 424.375009 -397.757433)
			(xy 424.37558 -397.790162) (xy 424.375022 -397.822892) (xy 424.366164 -397.88775) (xy 424.348672 -397.950831)
			(xy 424.322862 -398.010988) (xy 424.306492 -398.039336) (xy 424.303164 -398.045354) (xy 424.299567 -398.058623)
			(xy 424.29938 -398.065498) (xy 424.29938 -398.351502) (xy 424.298876 -398.361626) (xy 424.291151 -398.380344)
			(xy 424.27687 -398.394699) (xy 424.258194 -398.402522) (xy 424.248072 -398.403064) (xy 423.531792 -398.403064)
			(xy 423.521633 -398.402684) (xy 423.502873 -398.394879) (xy 423.488549 -398.380469) (xy 423.480856 -398.361663)
			(xy 423.480484 -398.351502) (xy 423.480484 -398.065498) (xy 423.480295 -398.058625) (xy 423.476685 -398.045362)
			(xy 423.473372 -398.039336) (xy 423.457018 -398.01098) (xy 423.431214 -397.950823) (xy 423.413721 -397.887746)
			(xy 423.404857 -397.82289) (xy 423.404284 -397.790162) (xy 422.131575 -397.790162) (xy 422.122709 -397.810835)
			(xy 422.106344 -397.839184) (xy 422.103039 -397.845213) (xy 422.099427 -397.858473) (xy 422.099232 -397.865346)
			(xy 422.099232 -398.6149) (xy 422.09942 -398.621774) (xy 422.103031 -398.635036) (xy 422.106344 -398.641062)
			(xy 422.122689 -398.669423) (xy 422.148497 -398.729578) (xy 422.165993 -398.792654) (xy 422.174859 -398.857508)
			(xy 422.175432 -398.890236) (xy 422.174856 -398.922965) (xy 422.166003 -398.987823) (xy 422.148515 -399.050903)
			(xy 422.122711 -399.111062) (xy 422.106344 -399.13941) (xy 422.103029 -399.145435) (xy 422.099423 -399.158698)
			(xy 422.099232 -399.165572) (xy 422.099232 -399.451576) (xy 422.098696 -399.461679) (xy 422.090972 -399.480351)
			(xy 422.076691 -399.494645) (xy 422.058027 -399.502387) (xy 422.047924 -399.502884) (xy 421.331644 -399.502884)
			(xy 421.321522 -399.502447) (xy 421.302817 -399.494711) (xy 421.2885 -399.4804) (xy 421.280756 -399.461697)
			(xy 421.280336 -399.451576) (xy 421.280336 -399.165572) (xy 421.28015 -399.158698) (xy 421.276537 -399.145436)
			(xy 421.273224 -399.13941) (xy 421.256865 -399.111057) (xy 421.231061 -399.050899) (xy 421.213569 -398.987821)
			(xy 421.204707 -398.922965) (xy 421.204136 -398.890236) (xy 414.52546 -398.890236) (xy 414.52546 -401.7228)
			(xy 419.004827 -401.7228) (xy 419.004829 -401.657362) (xy 419.013616 -401.592516) (xy 419.031029 -401.529436)
			(xy 419.056751 -401.469265) (xy 419.073076 -401.440904) (xy 419.076388 -401.434878) (xy 419.079996 -401.421615)
			(xy 419.080188 -401.414742) (xy 419.080188 -400.665442) (xy 419.079981 -400.65857) (xy 419.076383 -400.645307)
			(xy 419.073076 -400.63928) (xy 419.056758 -400.610916) (xy 419.031038 -400.550746) (xy 419.013628 -400.487668)
			(xy 419.004843 -400.422824) (xy 419.004842 -400.357387) (xy 419.013626 -400.292542) (xy 419.031034 -400.229464)
			(xy 419.056753 -400.169293) (xy 419.073076 -400.140932) (xy 419.076378 -400.134901) (xy 419.079992 -400.121642)
			(xy 419.080188 -400.11477) (xy 419.080188 -399.828766) (xy 419.080537 -399.818586) (xy 419.088343 -399.799781)
			(xy 419.102752 -399.785395) (xy 419.121569 -399.777621) (xy 419.13175 -399.777204) (xy 419.84803 -399.777204)
			(xy 419.858186 -399.777708) (xy 419.876949 -399.785486) (xy 419.891312 -399.799848) (xy 419.899091 -399.818611)
			(xy 419.899592 -399.828766) (xy 419.899592 -400.11477) (xy 419.899796 -400.121642) (xy 419.903396 -400.134905)
			(xy 419.906704 -400.140932) (xy 419.92303 -400.169291) (xy 419.948745 -400.229463) (xy 419.966151 -400.292542)
			(xy 419.974933 -400.357387) (xy 419.974932 -400.422823) (xy 419.966149 -400.487668) (xy 419.948741 -400.550747)
			(xy 419.923025 -400.610918) (xy 419.906704 -400.63928) (xy 419.903397 -400.645308) (xy 419.899786 -400.658569)
			(xy 419.899592 -400.665442) (xy 419.899592 -401.414742) (xy 419.899807 -401.421614) (xy 419.9034 -401.434876)
			(xy 419.906704 -401.440904) (xy 419.923006 -401.469276) (xy 419.948723 -401.529445) (xy 419.966132 -401.592522)
			(xy 419.974917 -401.657364) (xy 419.97492 -401.722798) (xy 419.96614 -401.787641) (xy 419.948736 -401.850719)
			(xy 419.923023 -401.91089) (xy 419.906704 -401.939252) (xy 419.903371 -401.945268) (xy 419.899777 -401.958538)
			(xy 419.899592 -401.965414) (xy 419.899592 -402.251418) (xy 419.899082 -402.261573) (xy 419.891308 -402.280337)
			(xy 419.876947 -402.294701) (xy 419.858185 -402.30248) (xy 419.84803 -402.30298) (xy 419.13175 -402.30298)
			(xy 419.121584 -402.302496) (xy 419.102794 -402.29473) (xy 419.088408 -402.280363) (xy 419.080618 -402.261584)
			(xy 419.080188 -402.251418) (xy 419.080188 -401.965414) (xy 419.079992 -401.958541) (xy 419.076387 -401.945278)
			(xy 419.073076 -401.939252) (xy 419.056734 -401.910901) (xy 419.031016 -401.850728) (xy 419.013609 -401.787647)
			(xy 419.004827 -401.7228) (xy 414.52546 -401.7228) (xy 414.52546 -402.790152) (xy 421.204136 -402.790152)
			(xy 421.204711 -402.757423) (xy 421.213566 -402.692565) (xy 421.231053 -402.629485) (xy 421.256857 -402.569327)
			(xy 421.273224 -402.540978) (xy 421.276548 -402.534958) (xy 421.280147 -402.521691) (xy 421.280336 -402.514816)
			(xy 421.280336 -401.765516) (xy 421.280133 -401.758644) (xy 421.276532 -401.745381) (xy 421.273224 -401.739354)
			(xy 421.256842 -401.711014) (xy 421.231044 -401.650851) (xy 421.213559 -401.587769) (xy 421.204703 -401.52291)
			(xy 421.204136 -401.49018) (xy 421.204724 -401.457451) (xy 421.213574 -401.392594) (xy 421.231058 -401.329514)
			(xy 421.256859 -401.269355) (xy 421.273224 -401.241006) (xy 421.276538 -401.234981) (xy 421.280144 -401.221718)
			(xy 421.280336 -401.214844) (xy 421.280336 -400.92884) (xy 421.28075 -400.918716) (xy 421.288491 -400.900006)
			(xy 421.302809 -400.885689) (xy 421.32152 -400.877949) (xy 421.331644 -400.877532) (xy 422.047924 -400.877532)
			(xy 422.058052 -400.877897) (xy 422.076762 -400.885659) (xy 422.091077 -400.899991) (xy 422.098816 -400.918711)
			(xy 422.099232 -400.92884) (xy 422.099232 -401.214844) (xy 422.099441 -401.221716) (xy 422.103037 -401.234979)
			(xy 422.106344 -401.241006) (xy 422.122707 -401.269357) (xy 422.14851 -401.329515) (xy 422.166001 -401.392594)
			(xy 422.174862 -401.457451) (xy 422.175432 -401.49018) (xy 422.174876 -401.52291) (xy 422.166016 -401.587768)
			(xy 422.148523 -401.650848) (xy 422.131693 -401.690078) (xy 423.404284 -401.690078) (xy 423.404865 -401.657349)
			(xy 423.413716 -401.592491) (xy 423.431202 -401.529411) (xy 423.457006 -401.469253) (xy 423.473372 -401.440904)
			(xy 423.476683 -401.434878) (xy 423.480292 -401.421615) (xy 423.480484 -401.414742) (xy 423.480484 -400.665442)
			(xy 423.480278 -400.65857) (xy 423.476679 -400.645307) (xy 423.473372 -400.63928) (xy 423.456996 -400.610937)
			(xy 423.431197 -400.550775) (xy 423.413711 -400.487694) (xy 423.404853 -400.422835) (xy 423.404284 -400.390106)
			(xy 423.404832 -400.357376) (xy 423.413693 -400.292517) (xy 423.431189 -400.229437) (xy 423.457001 -400.169279)
			(xy 423.473372 -400.140932) (xy 423.476673 -400.134901) (xy 423.480288 -400.121642) (xy 423.480484 -400.11477)
			(xy 423.480484 -399.828766) (xy 423.4809 -399.818632) (xy 423.488647 -399.799901) (xy 423.502955 -399.785545)
			(xy 423.521659 -399.777735) (xy 423.531792 -399.777204) (xy 424.248072 -399.777204) (xy 424.258225 -399.777644)
			(xy 424.276977 -399.785431) (xy 424.291302 -399.799823) (xy 424.299002 -399.818611) (xy 424.29938 -399.828766)
			(xy 424.29938 -400.11477) (xy 424.299586 -400.121642) (xy 424.303185 -400.134905) (xy 424.306492 -400.140932)
			(xy 424.32287 -400.169275) (xy 424.348669 -400.229437) (xy 424.366155 -400.292518) (xy 424.375012 -400.357376)
			(xy 424.37558 -400.390106) (xy 424.374997 -400.422835) (xy 424.366147 -400.487693) (xy 424.348662 -400.550773)
			(xy 424.322859 -400.610931) (xy 424.306492 -400.63928) (xy 424.303184 -400.645308) (xy 424.299574 -400.658569)
			(xy 424.29938 -400.665442) (xy 424.29938 -401.414742) (xy 424.299597 -401.421613) (xy 424.303189 -401.434876)
			(xy 424.306492 -401.440904) (xy 424.322858 -401.469253) (xy 424.34866 -401.529412) (xy 424.36615 -401.592492)
			(xy 424.37501 -401.657349) (xy 424.37558 -401.690078) (xy 424.375029 -401.722808) (xy 424.366169 -401.787667)
			(xy 424.348675 -401.850747) (xy 424.322863 -401.910905) (xy 424.306492 -401.939252) (xy 424.303158 -401.945267)
			(xy 424.299565 -401.958538) (xy 424.29938 -401.965414) (xy 424.29938 -402.251418) (xy 424.298889 -402.261543)
			(xy 424.291159 -402.280261) (xy 424.276874 -402.294616) (xy 424.258195 -402.302438) (xy 424.248072 -402.30298)
			(xy 423.531792 -402.30298) (xy 423.521635 -402.302584) (xy 423.502879 -402.294782) (xy 423.488555 -402.280378)
			(xy 423.480859 -402.261577) (xy 423.480484 -402.251418) (xy 423.480484 -401.965414) (xy 423.480289 -401.958541)
			(xy 423.476683 -401.945278) (xy 423.473372 -401.939252) (xy 423.456985 -401.910915) (xy 423.431189 -401.850751)
			(xy 423.413705 -401.787668) (xy 423.404851 -401.722808) (xy 423.404284 -401.690078) (xy 422.131693 -401.690078)
			(xy 422.122714 -401.711006) (xy 422.106344 -401.739354) (xy 422.103049 -401.745388) (xy 422.09943 -401.758645)
			(xy 422.099232 -401.765516) (xy 422.099232 -402.514816) (xy 422.099414 -402.52169) (xy 422.103029 -402.534953)
			(xy 422.106344 -402.540978) (xy 422.122695 -402.569335) (xy 422.148502 -402.629491) (xy 422.165996 -402.692568)
			(xy 422.17486 -402.757424) (xy 422.175432 -402.790152) (xy 422.174863 -402.822879) (xy 425.604757 -402.822879)
			(xy 425.604762 -402.757439) (xy 425.613551 -402.692592) (xy 425.630965 -402.629512) (xy 425.656687 -402.56934)
			(xy 425.673012 -402.540978) (xy 425.676335 -402.534958) (xy 425.679935 -402.521691) (xy 425.680124 -402.514816)
			(xy 425.680124 -401.765516) (xy 425.679923 -401.758643) (xy 425.676321 -401.745381) (xy 425.673012 -401.739354)
			(xy 425.656674 -401.711002) (xy 425.630959 -401.650828) (xy 425.613554 -401.587748) (xy 425.604773 -401.522902)
			(xy 425.604775 -401.457464) (xy 425.613561 -401.392619) (xy 425.63097 -401.329539) (xy 425.656689 -401.269368)
			(xy 425.673012 -401.241006) (xy 425.676325 -401.234981) (xy 425.679932 -401.221717) (xy 425.680124 -401.214844)
			(xy 425.680124 -400.92884) (xy 425.680555 -400.918686) (xy 425.688342 -400.899929) (xy 425.702736 -400.885604)
			(xy 425.72153 -400.877907) (xy 425.731686 -400.877532) (xy 426.447966 -400.877532) (xy 426.45809 -400.878054)
			(xy 426.476808 -400.88577) (xy 426.491165 -400.900045) (xy 426.498987 -400.918719) (xy 426.499528 -400.92884)
			(xy 426.499528 -401.214844) (xy 426.499738 -401.221716) (xy 426.503334 -401.234979) (xy 426.50664 -401.241006)
			(xy 426.522946 -401.269376) (xy 426.548666 -401.329545) (xy 426.566077 -401.392622) (xy 426.574863 -401.457465)
			(xy 426.574865 -401.522901) (xy 426.566084 -401.587744) (xy 426.548678 -401.650822) (xy 426.522962 -401.710993)
			(xy 426.516167 -401.7228) (xy 427.804913 -401.7228) (xy 427.804916 -401.657362) (xy 427.813702 -401.592516)
			(xy 427.831114 -401.529436) (xy 427.856836 -401.469265) (xy 427.87316 -401.440904) (xy 427.87647 -401.434877)
			(xy 427.880079 -401.421615) (xy 427.880272 -401.414742) (xy 427.880272 -400.665442) (xy 427.880067 -400.65857)
			(xy 427.876468 -400.645307) (xy 427.87316 -400.63928) (xy 427.856842 -400.610916) (xy 427.831123 -400.550746)
			(xy 427.813714 -400.487668) (xy 427.804929 -400.422823) (xy 427.804928 -400.357387) (xy 427.813712 -400.292542)
			(xy 427.83112 -400.229464) (xy 427.856838 -400.169293) (xy 427.87316 -400.140932) (xy 427.87646 -400.1349)
			(xy 427.880075 -400.121642) (xy 427.880272 -400.11477) (xy 427.880272 -399.828766) (xy 427.880706 -399.818602)
			(xy 427.888498 -399.799825) (xy 427.902883 -399.78546) (xy 427.921669 -399.777693) (xy 427.931834 -399.777204)
			(xy 428.648114 -399.777204) (xy 428.658268 -399.777721) (xy 428.677031 -399.785494) (xy 428.691395 -399.799852)
			(xy 428.699175 -399.818612) (xy 428.699676 -399.828766) (xy 428.699676 -400.11477) (xy 428.699882 -400.121642)
			(xy 428.703481 -400.134905) (xy 428.706788 -400.140932) (xy 428.723114 -400.169291) (xy 428.74883 -400.229463)
			(xy 428.766237 -400.292542) (xy 428.775019 -400.357387) (xy 428.775018 -400.422824) (xy 428.766235 -400.487668)
			(xy 428.748827 -400.550747) (xy 428.72311 -400.610918) (xy 428.706788 -400.63928) (xy 428.70348 -400.645308)
			(xy 428.69987 -400.658569) (xy 428.699676 -400.665442) (xy 428.699676 -401.414742) (xy 428.699893 -401.421613)
			(xy 428.703484 -401.434876) (xy 428.706788 -401.440904) (xy 428.723091 -401.469276) (xy 428.748809 -401.529445)
			(xy 428.766218 -401.592521) (xy 428.775003 -401.657364) (xy 428.775006 -401.722799) (xy 428.766225 -401.787642)
			(xy 428.748821 -401.850719) (xy 428.723108 -401.91089) (xy 428.706788 -401.939252) (xy 428.703454 -401.945267)
			(xy 428.699861 -401.958538) (xy 428.699676 -401.965414) (xy 428.699676 -402.251418) (xy 428.699182 -402.261575)
			(xy 428.691404 -402.280342) (xy 428.677039 -402.294706) (xy 428.658271 -402.302483) (xy 428.648114 -402.30298)
			(xy 427.931834 -402.30298) (xy 427.921667 -402.302509) (xy 427.902876 -402.294738) (xy 427.888491 -402.280367)
			(xy 427.880702 -402.261585) (xy 427.880272 -402.251418) (xy 427.880272 -401.965414) (xy 427.880078 -401.958541)
			(xy 427.876471 -401.945278) (xy 427.87316 -401.939252) (xy 427.856818 -401.910901) (xy 427.831102 -401.850728)
			(xy 427.813695 -401.787647) (xy 427.804913 -401.7228) (xy 426.516167 -401.7228) (xy 426.50664 -401.739354)
			(xy 426.503345 -401.745388) (xy 426.499726 -401.758645) (xy 426.499528 -401.765516) (xy 426.499528 -402.514816)
			(xy 426.499711 -402.52169) (xy 426.503325 -402.534953) (xy 426.50664 -402.540978) (xy 426.522922 -402.569361)
			(xy 426.548645 -402.629527) (xy 426.566058 -402.692601) (xy 426.574847 -402.757442) (xy 426.57485 -402.790152)
			(xy 430.00422 -402.790152) (xy 430.004784 -402.757422) (xy 430.01364 -402.692564) (xy 430.031131 -402.629484)
			(xy 430.056939 -402.569326) (xy 430.073308 -402.540978) (xy 430.076631 -402.534958) (xy 430.080231 -402.521691)
			(xy 430.08042 -402.514816) (xy 430.08042 -401.765516) (xy 430.08022 -401.758643) (xy 430.076617 -401.745381)
			(xy 430.073308 -401.739354) (xy 430.056925 -401.711014) (xy 430.031127 -401.650851) (xy 430.013642 -401.587769)
			(xy 430.004787 -401.52291) (xy 430.00422 -401.49018) (xy 430.004796 -401.457451) (xy 430.013649 -401.392593)
			(xy 430.031136 -401.329513) (xy 430.056941 -401.269354) (xy 430.073308 -401.241006) (xy 430.076621 -401.234981)
			(xy 430.080228 -401.221717) (xy 430.08042 -401.214844) (xy 430.08042 -400.92884) (xy 430.080849 -400.918718)
			(xy 430.088588 -400.900011) (xy 430.102901 -400.885695) (xy 430.121606 -400.877952) (xy 430.131728 -400.877532)
			(xy 430.848008 -400.877532) (xy 430.858135 -400.87791) (xy 430.876845 -400.885667) (xy 430.89116 -400.899996)
			(xy 430.898899 -400.918713) (xy 430.899316 -400.92884) (xy 430.899316 -401.214844) (xy 430.899527 -401.221716)
			(xy 430.903122 -401.234979) (xy 430.906428 -401.241006) (xy 430.922799 -401.269352) (xy 430.948599 -401.329513)
			(xy 430.966087 -401.392593) (xy 430.974946 -401.457451) (xy 430.975516 -401.49018) (xy 430.974962 -401.52291)
			(xy 430.966102 -401.587769) (xy 430.948609 -401.650849) (xy 430.922798 -401.711006) (xy 430.915987 -401.7228)
			(xy 432.204703 -401.7228) (xy 432.204705 -401.657362) (xy 432.213492 -401.592516) (xy 432.230903 -401.529437)
			(xy 432.256624 -401.469265) (xy 432.272948 -401.440904) (xy 432.276257 -401.434877) (xy 432.279867 -401.421615)
			(xy 432.28006 -401.414742) (xy 432.28006 -400.665442) (xy 432.279857 -400.65857) (xy 432.276257 -400.645307)
			(xy 432.272948 -400.63928) (xy 432.256631 -400.610916) (xy 432.230912 -400.550746) (xy 432.213503 -400.487667)
			(xy 432.204719 -400.422823) (xy 432.204718 -400.357387) (xy 432.213501 -400.292543) (xy 432.230909 -400.229464)
			(xy 432.256626 -400.169293) (xy 432.272948 -400.140932) (xy 432.276247 -400.1349) (xy 432.279863 -400.121642)
			(xy 432.28006 -400.11477) (xy 432.28006 -399.828766) (xy 432.280506 -399.818603) (xy 432.288296 -399.799829)
			(xy 432.302676 -399.785464) (xy 432.321459 -399.777695) (xy 432.331622 -399.777204) (xy 433.047902 -399.777204)
			(xy 433.058056 -399.777731) (xy 433.076818 -399.7855) (xy 433.091182 -399.799855) (xy 433.098963 -399.818613)
			(xy 433.099464 -399.828766) (xy 433.099464 -400.11477) (xy 433.099672 -400.121642) (xy 433.10327 -400.134905)
			(xy 433.106576 -400.140932) (xy 433.122903 -400.169291) (xy 433.148619 -400.229463) (xy 433.166026 -400.292542)
			(xy 433.174809 -400.357387) (xy 433.174808 -400.390106) (xy 436.603656 -400.390106) (xy 436.607647 -400.327939)
			(xy 436.619556 -400.266792) (xy 436.639185 -400.207671) (xy 436.666214 -400.151545) (xy 436.700198 -400.099336)
			(xy 436.74058 -400.051901) (xy 436.786696 -400.01002) (xy 436.837788 -399.97438) (xy 436.893019 -399.945566)
			(xy 436.951481 -399.924052) (xy 437.012215 -399.91019) (xy 437.074222 -399.904208) (xy 437.136485 -399.906204)
			(xy 437.197982 -399.916147) (xy 437.257703 -399.933871) (xy 437.314666 -399.959088) (xy 437.367937 -399.991381)
			(xy 437.416642 -400.030221) (xy 437.459979 -400.074971) (xy 437.497239 -400.124895) (xy 437.527808 -400.179174)
			(xy 437.551186 -400.236917) (xy 437.566987 -400.297175) (xy 437.574953 -400.358958) (xy 437.575452 -400.390106)
			(xy 437.574953 -400.421254) (xy 437.566987 -400.483037) (xy 437.551186 -400.543295) (xy 437.527808 -400.601038)
			(xy 437.497239 -400.655317) (xy 437.459979 -400.705241) (xy 437.416642 -400.749991) (xy 437.369142 -400.78787)
			(xy 446.249042 -400.78787) (xy 446.253113 -400.732248) (xy 446.265239 -400.677811) (xy 446.285162 -400.62572)
			(xy 446.312458 -400.577085) (xy 446.346544 -400.532942) (xy 446.386693 -400.494233) (xy 446.432051 -400.461782)
			(xy 446.481651 -400.436281) (xy 446.534435 -400.418274) (xy 446.589278 -400.408144) (xy 446.645012 -400.406107)
			(xy 446.700449 -400.412207) (xy 446.754406 -400.426313) (xy 446.805735 -400.448125) (xy 446.853341 -400.477179)
			(xy 446.896209 -400.512854) (xy 446.933426 -400.554391) (xy 446.964199 -400.600904) (xy 446.987871 -400.651401)
			(xy 447.003939 -400.704808) (xy 447.012059 -400.759984) (xy 447.012568 -400.78787) (xy 447.012059 -400.815756)
			(xy 447.003939 -400.870932) (xy 446.987871 -400.924339) (xy 446.964199 -400.974836) (xy 446.933426 -401.021349)
			(xy 446.896209 -401.062886) (xy 446.853341 -401.098561) (xy 446.805735 -401.127615) (xy 446.754406 -401.149427)
			(xy 446.700449 -401.163533) (xy 446.645012 -401.169633) (xy 446.589278 -401.167596) (xy 446.534435 -401.157466)
			(xy 446.481651 -401.139459) (xy 446.432051 -401.113958) (xy 446.386693 -401.081507) (xy 446.346544 -401.042798)
			(xy 446.312458 -400.998655) (xy 446.285162 -400.95002) (xy 446.265239 -400.897929) (xy 446.253113 -400.843492)
			(xy 446.249042 -400.78787) (xy 437.369142 -400.78787) (xy 437.367937 -400.788831) (xy 437.314666 -400.821124)
			(xy 437.257703 -400.846341) (xy 437.197982 -400.864065) (xy 437.136485 -400.874008) (xy 437.074222 -400.876004)
			(xy 437.012215 -400.870022) (xy 436.951481 -400.85616) (xy 436.893019 -400.834646) (xy 436.837788 -400.805832)
			(xy 436.786696 -400.770192) (xy 436.74058 -400.728311) (xy 436.700198 -400.680876) (xy 436.666214 -400.628667)
			(xy 436.639185 -400.572541) (xy 436.619556 -400.51342) (xy 436.607647 -400.452273) (xy 436.603656 -400.390106)
			(xy 433.174808 -400.390106) (xy 433.174808 -400.422824) (xy 433.166024 -400.487668) (xy 433.148616 -400.550747)
			(xy 433.122898 -400.610919) (xy 433.106576 -400.63928) (xy 433.103267 -400.645307) (xy 433.099658 -400.658569)
			(xy 433.099464 -400.665442) (xy 433.099464 -401.414742) (xy 433.099682 -401.421613) (xy 433.103273 -401.434876)
			(xy 433.106576 -401.440904) (xy 433.122879 -401.469276) (xy 433.148598 -401.529445) (xy 433.166007 -401.592521)
			(xy 433.174793 -401.657364) (xy 433.174795 -401.722799) (xy 433.166015 -401.787642) (xy 433.14861 -401.85072)
			(xy 433.122896 -401.910891) (xy 433.106576 -401.939252) (xy 433.103241 -401.945267) (xy 433.099649 -401.958538)
			(xy 433.099464 -401.965414) (xy 433.099464 -402.251418) (xy 433.098982 -402.261577) (xy 433.091202 -402.280346)
			(xy 433.076833 -402.294711) (xy 433.058061 -402.302485) (xy 433.047902 -402.30298) (xy 432.331622 -402.30298)
			(xy 432.321454 -402.302518) (xy 432.302663 -402.294744) (xy 432.288278 -402.28037) (xy 432.28049 -402.261586)
			(xy 432.28006 -402.251418) (xy 432.28006 -401.965414) (xy 432.279868 -401.958541) (xy 432.27626 -401.945278)
			(xy 432.272948 -401.939252) (xy 432.256607 -401.910901) (xy 432.230891 -401.850728) (xy 432.213484 -401.787647)
			(xy 432.204703 -401.7228) (xy 430.915987 -401.7228) (xy 430.906428 -401.739354) (xy 430.903132 -401.745388)
			(xy 430.899514 -401.758644) (xy 430.899316 -401.765516) (xy 430.899316 -402.514816) (xy 430.8995 -402.52169)
			(xy 430.903113 -402.534953) (xy 430.906428 -402.540978) (xy 430.922787 -402.569331) (xy 430.94859 -402.629489)
			(xy 430.966081 -402.692567) (xy 430.974944 -402.757423) (xy 430.975516 -402.790152) (xy 430.974949 -402.822879)
			(xy 434.404843 -402.822879) (xy 434.404849 -402.757439) (xy 434.413637 -402.692592) (xy 434.43105 -402.629512)
			(xy 434.456772 -402.56934) (xy 434.473096 -402.540978) (xy 434.476418 -402.534957) (xy 434.480019 -402.52169)
			(xy 434.480208 -402.514816) (xy 434.480208 -401.765516) (xy 434.480009 -401.758643) (xy 434.476406 -401.74538)
			(xy 434.473096 -401.739354) (xy 434.456758 -401.711002) (xy 434.431044 -401.650828) (xy 434.41364 -401.587747)
			(xy 434.404859 -401.522902) (xy 434.404861 -401.457464) (xy 434.413647 -401.392619) (xy 434.431056 -401.32954)
			(xy 434.456774 -401.269368) (xy 434.473096 -401.241006) (xy 434.476408 -401.23498) (xy 434.480016 -401.221717)
			(xy 434.480208 -401.214844) (xy 434.480208 -400.92884) (xy 434.480655 -400.918688) (xy 434.488438 -400.899934)
			(xy 434.502828 -400.885609) (xy 434.521616 -400.87791) (xy 434.53177 -400.877532) (xy 435.24805 -400.877532)
			(xy 435.258173 -400.878067) (xy 435.276891 -400.885777) (xy 435.291249 -400.900049) (xy 435.299071 -400.918721)
			(xy 435.299612 -400.92884) (xy 435.299612 -401.214844) (xy 435.299824 -401.221716) (xy 435.303418 -401.234979)
			(xy 435.306724 -401.241006) (xy 435.32303 -401.269376) (xy 435.348752 -401.329545) (xy 435.366163 -401.392622)
			(xy 435.374949 -401.457465) (xy 435.374952 -401.522901) (xy 435.36617 -401.587745) (xy 435.348763 -401.650823)
			(xy 435.331985 -401.690078) (xy 436.603656 -401.690078) (xy 436.607647 -401.627911) (xy 436.619556 -401.566764)
			(xy 436.639185 -401.507643) (xy 436.666214 -401.451517) (xy 436.700198 -401.399308) (xy 436.74058 -401.351873)
			(xy 436.786696 -401.309992) (xy 436.837788 -401.274352) (xy 436.893019 -401.245538) (xy 436.951481 -401.224024)
			(xy 437.012215 -401.210162) (xy 437.074222 -401.20418) (xy 437.136485 -401.206176) (xy 437.197982 -401.216119)
			(xy 437.257703 -401.233843) (xy 437.314666 -401.25906) (xy 437.367937 -401.291353) (xy 437.416642 -401.330193)
			(xy 437.459979 -401.374943) (xy 437.497239 -401.424867) (xy 437.527808 -401.479146) (xy 437.532275 -401.49018)
			(xy 438.803804 -401.49018) (xy 438.807795 -401.428013) (xy 438.819704 -401.366866) (xy 438.839333 -401.307745)
			(xy 438.866362 -401.251619) (xy 438.900346 -401.19941) (xy 438.940728 -401.151975) (xy 438.986844 -401.110094)
			(xy 439.037936 -401.074454) (xy 439.093167 -401.04564) (xy 439.151629 -401.024126) (xy 439.212363 -401.010264)
			(xy 439.27437 -401.004282) (xy 439.336633 -401.006278) (xy 439.39813 -401.016221) (xy 439.457851 -401.033945)
			(xy 439.514814 -401.059162) (xy 439.568085 -401.091455) (xy 439.61679 -401.130295) (xy 439.660127 -401.175045)
			(xy 439.697387 -401.224969) (xy 439.727956 -401.279248) (xy 439.751334 -401.336991) (xy 439.760066 -401.370292)
			(xy 448.261484 -401.370292) (xy 448.265555 -401.31467) (xy 448.277681 -401.260233) (xy 448.297604 -401.208142)
			(xy 448.3249 -401.159507) (xy 448.358986 -401.115364) (xy 448.399135 -401.076655) (xy 448.444493 -401.044204)
			(xy 448.494093 -401.018703) (xy 448.546877 -401.000696) (xy 448.60172 -400.990566) (xy 448.657454 -400.988529)
			(xy 448.712891 -400.994629) (xy 448.766848 -401.008735) (xy 448.818177 -401.030547) (xy 448.865783 -401.059601)
			(xy 448.908651 -401.095276) (xy 448.945868 -401.136813) (xy 448.976641 -401.183326) (xy 449.000313 -401.233823)
			(xy 449.016381 -401.28723) (xy 449.024501 -401.342406) (xy 449.02501 -401.370292) (xy 449.024501 -401.398178)
			(xy 449.016381 -401.453354) (xy 449.000313 -401.506761) (xy 448.976641 -401.557258) (xy 448.945868 -401.603771)
			(xy 448.908651 -401.645308) (xy 448.865783 -401.680983) (xy 448.818177 -401.710037) (xy 448.766848 -401.731849)
			(xy 448.712891 -401.745955) (xy 448.657454 -401.752055) (xy 448.60172 -401.750018) (xy 448.546877 -401.739888)
			(xy 448.494093 -401.721881) (xy 448.444493 -401.69638) (xy 448.399135 -401.663929) (xy 448.358986 -401.62522)
			(xy 448.3249 -401.581077) (xy 448.297604 -401.532442) (xy 448.277681 -401.480351) (xy 448.265555 -401.425914)
			(xy 448.261484 -401.370292) (xy 439.760066 -401.370292) (xy 439.767135 -401.397249) (xy 439.775101 -401.459032)
			(xy 439.7756 -401.49018) (xy 439.775101 -401.521328) (xy 439.767135 -401.583111) (xy 439.751334 -401.643369)
			(xy 439.727956 -401.701112) (xy 439.697387 -401.755391) (xy 439.660127 -401.805315) (xy 439.61679 -401.850065)
			(xy 439.568085 -401.888905) (xy 439.514814 -401.921198) (xy 439.457851 -401.946415) (xy 439.39813 -401.964139)
			(xy 439.336633 -401.974082) (xy 439.27437 -401.976078) (xy 439.212363 -401.970096) (xy 439.151629 -401.956234)
			(xy 439.093167 -401.93472) (xy 439.037936 -401.905906) (xy 438.986844 -401.870266) (xy 438.940728 -401.828385)
			(xy 438.900346 -401.78095) (xy 438.866362 -401.728741) (xy 438.839333 -401.672615) (xy 438.819704 -401.613494)
			(xy 438.807795 -401.552347) (xy 438.803804 -401.49018) (xy 437.532275 -401.49018) (xy 437.551186 -401.536889)
			(xy 437.566987 -401.597147) (xy 437.574953 -401.65893) (xy 437.575452 -401.690078) (xy 437.574953 -401.721226)
			(xy 437.566987 -401.783009) (xy 437.551186 -401.843267) (xy 437.527808 -401.90101) (xy 437.497239 -401.955289)
			(xy 437.459979 -402.005213) (xy 437.416642 -402.049963) (xy 437.367937 -402.088803) (xy 437.314666 -402.121096)
			(xy 437.257703 -402.146313) (xy 437.197982 -402.164037) (xy 437.136485 -402.17398) (xy 437.074222 -402.175976)
			(xy 437.012215 -402.169994) (xy 436.951481 -402.156132) (xy 436.893019 -402.134618) (xy 436.837788 -402.105804)
			(xy 436.786696 -402.070164) (xy 436.74058 -402.028283) (xy 436.700198 -401.980848) (xy 436.666214 -401.928639)
			(xy 436.639185 -401.872513) (xy 436.619556 -401.813392) (xy 436.607647 -401.752245) (xy 436.603656 -401.690078)
			(xy 435.331985 -401.690078) (xy 435.323046 -401.710993) (xy 435.306724 -401.739354) (xy 435.303427 -401.745388)
			(xy 435.29981 -401.758644) (xy 435.299612 -401.765516) (xy 435.299612 -402.514816) (xy 435.299796 -402.52169)
			(xy 435.303409 -402.534953) (xy 435.306724 -402.540978) (xy 435.323007 -402.569361) (xy 435.34873 -402.629527)
			(xy 435.366144 -402.692601) (xy 435.374933 -402.757442) (xy 435.374936 -402.790152) (xy 438.803804 -402.790152)
			(xy 438.807795 -402.727985) (xy 438.819704 -402.666838) (xy 438.839333 -402.607717) (xy 438.866362 -402.551591)
			(xy 438.900346 -402.499382) (xy 438.940728 -402.451947) (xy 438.986844 -402.410066) (xy 439.037936 -402.374426)
			(xy 439.093167 -402.345612) (xy 439.151629 -402.324098) (xy 439.212363 -402.310236) (xy 439.27437 -402.304254)
			(xy 439.336633 -402.30625) (xy 439.39813 -402.316193) (xy 439.457851 -402.333917) (xy 439.514814 -402.359134)
			(xy 439.568085 -402.391427) (xy 439.61679 -402.430267) (xy 439.660127 -402.475017) (xy 439.697387 -402.524941)
			(xy 439.727956 -402.57922) (xy 439.751334 -402.636963) (xy 439.767135 -402.697221) (xy 439.775101 -402.759004)
			(xy 439.7756 -402.790152) (xy 439.775101 -402.8213) (xy 439.767135 -402.883083) (xy 439.751334 -402.943341)
			(xy 439.727956 -403.001084) (xy 439.697387 -403.055363) (xy 439.660127 -403.105287) (xy 439.61679 -403.150037)
			(xy 439.568085 -403.188877) (xy 439.514814 -403.22117) (xy 439.457851 -403.246387) (xy 439.39813 -403.264111)
			(xy 439.336633 -403.274054) (xy 439.27437 -403.27605) (xy 439.212363 -403.270068) (xy 439.151629 -403.256206)
			(xy 439.093167 -403.234692) (xy 439.037936 -403.205878) (xy 438.986844 -403.170238) (xy 438.940728 -403.128357)
			(xy 438.900346 -403.080922) (xy 438.866362 -403.028713) (xy 438.839333 -402.972587) (xy 438.819704 -402.913466)
			(xy 438.807795 -402.852319) (xy 438.803804 -402.790152) (xy 435.374936 -402.790152) (xy 435.374939 -402.822876)
			(xy 435.366161 -402.887718) (xy 435.348757 -402.950795) (xy 435.323044 -403.010965) (xy 435.306724 -403.039326)
			(xy 435.303402 -403.045347) (xy 435.2998 -403.058613) (xy 435.299612 -403.065488) (xy 435.299612 -403.351492)
			(xy 435.299172 -403.361644) (xy 435.291381 -403.380394) (xy 435.27699 -403.394717) (xy 435.258204 -403.402419)
			(xy 435.24805 -403.4028) (xy 434.53177 -403.4028) (xy 434.521646 -403.402299) (xy 434.502932 -403.394569)
			(xy 434.488578 -403.380288) (xy 434.480753 -403.361613) (xy 434.480208 -403.351492) (xy 434.480208 -403.065488)
			(xy 434.48002 -403.058615) (xy 434.476409 -403.045352) (xy 434.473096 -403.039326) (xy 434.456734 -403.010987)
			(xy 434.431023 -402.95081) (xy 434.413621 -402.887727) (xy 434.404843 -402.822879) (xy 430.974949 -402.822879)
			(xy 430.974949 -402.822881) (xy 430.966093 -402.88774) (xy 430.948603 -402.95082) (xy 430.922796 -403.010978)
			(xy 430.906428 -403.039326) (xy 430.903106 -403.045347) (xy 430.899504 -403.058614) (xy 430.899316 -403.065488)
			(xy 430.899316 -403.351492) (xy 430.898809 -403.361598) (xy 430.891077 -403.380273) (xy 430.876787 -403.394568)
			(xy 430.858114 -403.402306) (xy 430.848008 -403.4028) (xy 430.131728 -403.4028) (xy 430.121607 -403.402361)
			(xy 430.102904 -403.394622) (xy 430.088589 -403.380313) (xy 430.080843 -403.361613) (xy 430.08042 -403.351492)
			(xy 430.08042 -403.065488) (xy 430.08023 -403.058615) (xy 430.07662 -403.045352) (xy 430.073308 -403.039326)
			(xy 430.056954 -403.010971) (xy 430.031149 -402.950813) (xy 430.013656 -402.887736) (xy 430.004792 -402.82288)
			(xy 430.00422 -402.790152) (xy 426.57485 -402.790152) (xy 426.574853 -402.822876) (xy 426.566075 -402.887718)
			(xy 426.548672 -402.950795) (xy 426.52296 -403.010965) (xy 426.50664 -403.039326) (xy 426.503319 -403.045348)
			(xy 426.499717 -403.058614) (xy 426.499528 -403.065488) (xy 426.499528 -403.351492) (xy 426.499072 -403.361642)
			(xy 426.491285 -403.380389) (xy 426.476899 -403.394712) (xy 426.458118 -403.402417) (xy 426.447966 -403.4028)
			(xy 425.731686 -403.4028) (xy 425.721563 -403.402286) (xy 425.70285 -403.394561) (xy 425.688495 -403.380284)
			(xy 425.68067 -403.361612) (xy 425.680124 -403.351492) (xy 425.680124 -403.065488) (xy 425.679934 -403.058615)
			(xy 425.676324 -403.045352) (xy 425.673012 -403.039326) (xy 425.65665 -403.010987) (xy 425.630938 -402.95081)
			(xy 425.613535 -402.887727) (xy 425.604757 -402.822879) (xy 422.174863 -402.822879) (xy 422.174863 -402.822881)
			(xy 422.166008 -402.887739) (xy 422.148518 -402.95082) (xy 422.122712 -403.010978) (xy 422.106344 -403.039326)
			(xy 422.103024 -403.045348) (xy 422.099421 -403.058614) (xy 422.099232 -403.065488) (xy 422.099232 -403.351492)
			(xy 422.098709 -403.361596) (xy 422.09098 -403.380268) (xy 422.076695 -403.394562) (xy 422.058028 -403.402303)
			(xy 422.047924 -403.4028) (xy 421.331644 -403.4028) (xy 421.321524 -403.402348) (xy 421.302822 -403.394614)
			(xy 421.288506 -403.380308) (xy 421.280759 -403.361611) (xy 421.280336 -403.351492) (xy 421.280336 -403.065488)
			(xy 421.280144 -403.058615) (xy 421.276535 -403.045352) (xy 421.273224 -403.039326) (xy 421.256871 -403.01097)
			(xy 421.231066 -402.950813) (xy 421.213572 -402.887736) (xy 421.204708 -402.82288) (xy 421.204136 -402.790152)
			(xy 414.52546 -402.790152) (xy 414.52546 -405.622714) (xy 419.004836 -405.622714) (xy 419.004837 -405.557276)
			(xy 419.013622 -405.492431) (xy 419.031032 -405.429352) (xy 419.056752 -405.369181) (xy 419.073076 -405.34082)
			(xy 419.076382 -405.334791) (xy 419.079994 -405.321531) (xy 419.080188 -405.314658) (xy 419.080188 -404.565358)
			(xy 419.079975 -404.558486) (xy 419.076381 -404.545223) (xy 419.073076 -404.539196) (xy 419.056771 -404.510825)
			(xy 419.03105 -404.450656) (xy 419.013638 -404.38758) (xy 419.004852 -404.322737) (xy 419.004849 -404.257301)
			(xy 419.013631 -404.192457) (xy 419.031037 -404.129379) (xy 419.056754 -404.069209) (xy 419.073076 -404.040848)
			(xy 419.076408 -404.034832) (xy 419.080003 -404.021562) (xy 419.080188 -404.014686) (xy 419.080188 -403.728682)
			(xy 419.08055 -403.718503) (xy 419.088351 -403.699698) (xy 419.102756 -403.685313) (xy 419.12157 -403.677537)
			(xy 419.13175 -403.67712) (xy 419.84803 -403.67712) (xy 419.858187 -403.677608) (xy 419.876954 -403.685389)
			(xy 419.891317 -403.699756) (xy 419.899094 -403.718524) (xy 419.899592 -403.728682) (xy 419.899592 -404.014686)
			(xy 419.89979 -404.021559) (xy 419.903394 -404.034822) (xy 419.906704 -404.040848) (xy 419.923044 -404.069199)
			(xy 419.948757 -404.129373) (xy 419.966162 -404.192454) (xy 419.974942 -404.2573) (xy 419.974939 -404.322738)
			(xy 419.966154 -404.387583) (xy 419.948745 -404.450662) (xy 419.923026 -404.510834) (xy 419.906704 -404.539196)
			(xy 419.903391 -404.545221) (xy 419.899784 -404.558485) (xy 419.899592 -404.565358) (xy 419.899592 -405.314658)
			(xy 419.899801 -405.32153) (xy 419.903398 -405.334793) (xy 419.906704 -405.34082) (xy 419.92302 -405.369185)
			(xy 419.948736 -405.429355) (xy 419.966143 -405.492433) (xy 419.974926 -405.557277) (xy 419.974927 -405.622713)
			(xy 419.966145 -405.687557) (xy 419.948739 -405.750635) (xy 419.923024 -405.810806) (xy 419.906704 -405.839168)
			(xy 419.903401 -405.845198) (xy 419.899788 -405.858458) (xy 419.899592 -405.86533) (xy 419.899592 -406.151334)
			(xy 419.899095 -406.16149) (xy 419.891315 -406.180254) (xy 419.876951 -406.194617) (xy 419.858186 -406.202396)
			(xy 419.84803 -406.202896) (xy 419.13175 -406.202896) (xy 419.121586 -406.202396) (xy 419.102799 -406.194634)
			(xy 419.088413 -406.180272) (xy 419.08062 -406.161497) (xy 419.080188 -406.151334) (xy 419.080188 -405.86533)
			(xy 419.079986 -405.858458) (xy 419.076385 -405.845195) (xy 419.073076 -405.839168) (xy 419.056748 -405.81081)
			(xy 419.031028 -405.750638) (xy 419.01362 -405.687559) (xy 419.004836 -405.622714) (xy 414.52546 -405.622714)
			(xy 414.52546 -406.690068) (xy 421.204136 -406.690068) (xy 421.204718 -406.657339) (xy 421.213571 -406.592482)
			(xy 421.231056 -406.529402) (xy 421.256858 -406.469243) (xy 421.273224 -406.440894) (xy 421.276543 -406.434871)
			(xy 421.280145 -406.421606) (xy 421.280336 -406.414732) (xy 421.280336 -405.665432) (xy 421.280127 -405.65856)
			(xy 421.27653 -405.645297) (xy 421.273224 -405.63927) (xy 421.256849 -405.610926) (xy 421.231049 -405.550765)
			(xy 421.213562 -405.487684) (xy 421.204705 -405.422825) (xy 421.204136 -405.390096) (xy 421.204686 -405.357366)
			(xy 421.213548 -405.292507) (xy 421.231043 -405.229428) (xy 421.256854 -405.16927) (xy 421.273224 -405.140922)
			(xy 421.276533 -405.134894) (xy 421.280142 -405.121633) (xy 421.280336 -405.11476) (xy 421.280336 -404.828756)
			(xy 421.28075 -404.81864) (xy 421.288509 -404.799954) (xy 421.302828 -404.785659) (xy 421.321527 -404.777933)
			(xy 421.331644 -404.777448) (xy 422.047924 -404.777448) (xy 422.058028 -404.777964) (xy 422.076697 -404.7857)
			(xy 422.090989 -404.799986) (xy 422.098732 -404.818652) (xy 422.099232 -404.828756) (xy 422.099232 -405.11476)
			(xy 422.099435 -405.121632) (xy 422.103035 -405.134895) (xy 422.106344 -405.140922) (xy 422.122713 -405.169269)
			(xy 422.148515 -405.229429) (xy 422.166004 -405.292509) (xy 422.174863 -405.357367) (xy 422.175432 -405.390096)
			(xy 422.174883 -405.422826) (xy 422.166021 -405.487685) (xy 422.148526 -405.550765) (xy 422.131694 -405.589994)
			(xy 423.404284 -405.589994) (xy 423.404872 -405.557265) (xy 423.413721 -405.492408) (xy 423.431205 -405.429328)
			(xy 423.457007 -405.369169) (xy 423.473372 -405.34082) (xy 423.476678 -405.334791) (xy 423.48029 -405.321531)
			(xy 423.480484 -405.314658) (xy 423.480484 -404.565358) (xy 423.480272 -404.558486) (xy 423.476678 -404.545223)
			(xy 423.473372 -404.539196) (xy 423.457002 -404.510849) (xy 423.431202 -404.450689) (xy 423.413714 -404.387608)
			(xy 423.404854 -404.322751) (xy 423.404284 -404.290022) (xy 423.404839 -404.257292) (xy 423.413698 -404.192434)
			(xy 423.431192 -404.129353) (xy 423.457002 -404.069196) (xy 423.473372 -404.040848) (xy 423.476703 -404.034831)
			(xy 423.480299 -404.021561) (xy 423.480484 -404.014686) (xy 423.480484 -403.728682) (xy 423.480913 -403.718549)
			(xy 423.488655 -403.699819) (xy 423.502959 -403.685461) (xy 423.521661 -403.677651) (xy 423.531792 -403.67712)
			(xy 424.248072 -403.67712) (xy 424.258227 -403.677545) (xy 424.276983 -403.685335) (xy 424.291308 -403.699731)
			(xy 424.299005 -403.718525) (xy 424.29938 -403.728682) (xy 424.29938 -404.014686) (xy 424.29958 -404.021559)
			(xy 424.303183 -404.034821) (xy 424.306492 -404.040848) (xy 424.322876 -404.069187) (xy 424.348674 -404.12935)
			(xy 424.366158 -404.192433) (xy 424.375013 -404.257292) (xy 424.37558 -404.290022) (xy 424.375004 -404.322751)
			(xy 424.366152 -404.387609) (xy 424.348665 -404.450689) (xy 424.322859 -404.510848) (xy 424.306492 -404.539196)
			(xy 424.303178 -404.545221) (xy 424.299572 -404.558484) (xy 424.29938 -404.565358) (xy 424.29938 -405.314658)
			(xy 424.29959 -405.32153) (xy 424.303186 -405.334793) (xy 424.306492 -405.34082) (xy 424.322865 -405.369165)
			(xy 424.348665 -405.429326) (xy 424.366153 -405.492407) (xy 424.375011 -405.557265) (xy 424.37558 -405.589994)
			(xy 424.375037 -405.622724) (xy 424.366174 -405.687583) (xy 424.348678 -405.750664) (xy 424.322864 -405.810821)
			(xy 424.306492 -405.839168) (xy 424.303188 -405.845198) (xy 424.299576 -405.858458) (xy 424.29938 -405.86533)
			(xy 424.29938 -406.151334) (xy 424.298902 -406.16146) (xy 424.291167 -406.180179) (xy 424.276878 -406.194533)
			(xy 424.258196 -406.202355) (xy 424.248072 -406.202896) (xy 423.531792 -406.202896) (xy 423.521637 -406.202485)
			(xy 423.502884 -406.194686) (xy 423.48856 -406.180286) (xy 423.480862 -406.161491) (xy 423.480484 -406.151334)
			(xy 423.480484 -405.86533) (xy 423.480282 -405.858457) (xy 423.476681 -405.845195) (xy 423.473372 -405.839168)
			(xy 423.456991 -405.810827) (xy 423.431194 -405.750664) (xy 423.413708 -405.687582) (xy 423.404852 -405.622724)
			(xy 423.404284 -405.589994) (xy 422.131694 -405.589994) (xy 422.122715 -405.610922) (xy 422.106344 -405.63927)
			(xy 422.103043 -405.645302) (xy 422.099428 -405.65856) (xy 422.099232 -405.665432) (xy 422.099232 -406.414732)
			(xy 422.099408 -406.421606) (xy 422.103027 -406.434869) (xy 422.106344 -406.440894) (xy 422.122702 -406.469248)
			(xy 422.148507 -406.529405) (xy 422.165999 -406.592483) (xy 422.174861 -406.657339) (xy 422.175432 -406.690068)
			(xy 422.17487 -406.722792) (xy 425.604766 -406.722792) (xy 425.60477 -406.657353) (xy 425.613557 -406.592507)
			(xy 425.630968 -406.529428) (xy 425.656688 -406.469256) (xy 425.673012 -406.440894) (xy 425.67633 -406.434871)
			(xy 425.679933 -406.421606) (xy 425.680124 -406.414732) (xy 425.680124 -405.665432) (xy 425.679917 -405.65856)
			(xy 425.676319 -405.645297) (xy 425.673012 -405.63927) (xy 425.656687 -405.61091) (xy 425.630971 -405.550738)
			(xy 425.613565 -405.487659) (xy 425.604782 -405.422815) (xy 425.604782 -405.357378) (xy 425.613566 -405.292534)
			(xy 425.630974 -405.229455) (xy 425.65669 -405.169284) (xy 425.673012 -405.140922) (xy 425.67632 -405.134894)
			(xy 425.67993 -405.121633) (xy 425.680124 -405.11476) (xy 425.680124 -404.828756) (xy 425.680486 -404.818596)
			(xy 425.688301 -404.799838) (xy 425.702716 -404.785515) (xy 425.721523 -404.777822) (xy 425.731686 -404.777448)
			(xy 426.447966 -404.777448) (xy 426.458091 -404.777955) (xy 426.476813 -404.785673) (xy 426.491171 -404.799953)
			(xy 426.49899 -404.818633) (xy 426.499528 -404.828756) (xy 426.499528 -405.11476) (xy 426.499732 -405.121632)
			(xy 426.503332 -405.134895) (xy 426.50664 -405.140922) (xy 426.522959 -405.169285) (xy 426.548679 -405.229455)
			(xy 426.566088 -405.292534) (xy 426.574872 -405.357378) (xy 426.574873 -405.422815) (xy 426.566089 -405.487659)
			(xy 426.548681 -405.550738) (xy 426.522963 -405.610909) (xy 426.516169 -405.622714) (xy 427.804922 -405.622714)
			(xy 427.804923 -405.557276) (xy 427.813708 -405.492431) (xy 427.831117 -405.429352) (xy 427.856837 -405.369181)
			(xy 427.87316 -405.34082) (xy 427.876464 -405.33479) (xy 427.880077 -405.321531) (xy 427.880272 -405.314658)
			(xy 427.880272 -404.565358) (xy 427.880061 -404.558486) (xy 427.876466 -404.545223) (xy 427.87316 -404.539196)
			(xy 427.856856 -404.510825) (xy 427.831135 -404.450656) (xy 427.813724 -404.387579) (xy 427.804938 -404.322737)
			(xy 427.804936 -404.257301) (xy 427.813717 -404.192458) (xy 427.831123 -404.12938) (xy 427.856839 -404.069209)
			(xy 427.87316 -404.040848) (xy 427.87649 -404.034831) (xy 427.880086 -404.021561) (xy 427.880272 -404.014686)
			(xy 427.880272 -403.728682) (xy 427.88065 -403.718505) (xy 427.888447 -403.699703) (xy 427.902847 -403.685318)
			(xy 427.921657 -403.67754) (xy 427.931834 -403.67712) (xy 428.648114 -403.67712) (xy 428.65827 -403.677622)
			(xy 428.677036 -403.685397) (xy 428.6914 -403.69976) (xy 428.699178 -403.718526) (xy 428.699676 -403.728682)
			(xy 428.699676 -404.014686) (xy 428.699876 -404.021559) (xy 428.703479 -404.034821) (xy 428.706788 -404.040848)
			(xy 428.723128 -404.069199) (xy 428.748842 -404.129373) (xy 428.766248 -404.192454) (xy 428.775028 -404.2573)
			(xy 428.775026 -404.322738) (xy 428.76624 -404.387583) (xy 428.74883 -404.450663) (xy 428.723111 -404.510834)
			(xy 428.706788 -404.539196) (xy 428.703474 -404.545221) (xy 428.699868 -404.558484) (xy 428.699676 -404.565358)
			(xy 428.699676 -405.314658) (xy 428.699887 -405.32153) (xy 428.703482 -405.334793) (xy 428.706788 -405.34082)
			(xy 428.723104 -405.369184) (xy 428.748821 -405.429355) (xy 428.766229 -405.492433) (xy 428.775012 -405.557277)
			(xy 428.775013 -405.622713) (xy 428.766231 -405.687557) (xy 428.748824 -405.750635) (xy 428.723109 -405.810806)
			(xy 428.706788 -405.839168) (xy 428.703484 -405.845198) (xy 428.699872 -405.858458) (xy 428.699676 -405.86533)
			(xy 428.699676 -406.151334) (xy 428.699195 -406.161492) (xy 428.691412 -406.180259) (xy 428.677043 -406.194623)
			(xy 428.658272 -406.202399) (xy 428.648114 -406.202896) (xy 427.931834 -406.202896) (xy 427.921683 -406.202339)
			(xy 427.902921 -406.194583) (xy 427.888556 -406.180236) (xy 427.880774 -406.161485) (xy 427.880272 -406.151334)
			(xy 427.880272 -405.86533) (xy 427.880072 -405.858457) (xy 427.87647 -405.845194) (xy 427.87316 -405.839168)
			(xy 427.856832 -405.81081) (xy 427.831114 -405.750638) (xy 427.813705 -405.687559) (xy 427.804922 -405.622714)
			(xy 426.516169 -405.622714) (xy 426.50664 -405.63927) (xy 426.503339 -405.645302) (xy 426.499724 -405.65856)
			(xy 426.499528 -405.665432) (xy 426.499528 -406.414732) (xy 426.499704 -406.421606) (xy 426.503323 -406.434869)
			(xy 426.50664 -406.440894) (xy 426.522936 -406.46927) (xy 426.548657 -406.529437) (xy 426.566069 -406.592513)
			(xy 426.574856 -406.657355) (xy 426.574858 -406.690068) (xy 430.00422 -406.690068) (xy 430.004791 -406.657339)
			(xy 430.013645 -406.59248) (xy 430.031134 -406.5294) (xy 430.05694 -406.469242) (xy 430.073308 -406.440894)
			(xy 430.076625 -406.434871) (xy 430.080229 -406.421606) (xy 430.08042 -406.414732) (xy 430.08042 -405.665432)
			(xy 430.080213 -405.65856) (xy 430.076615 -405.645297) (xy 430.073308 -405.63927) (xy 430.056931 -405.610927)
			(xy 430.031132 -405.550765) (xy 430.013645 -405.487684) (xy 430.004788 -405.422826) (xy 430.00422 -405.390096)
			(xy 430.004759 -405.357365) (xy 430.013622 -405.292506) (xy 430.03112 -405.229426) (xy 430.056936 -405.169269)
			(xy 430.073308 -405.140922) (xy 430.076615 -405.134894) (xy 430.080226 -405.121633) (xy 430.08042 -405.11476)
			(xy 430.08042 -404.828756) (xy 430.08085 -404.818642) (xy 430.088605 -404.799959) (xy 430.102919 -404.785665)
			(xy 430.121613 -404.777935) (xy 430.131728 -404.777448) (xy 430.848008 -404.777448) (xy 430.858111 -404.777977)
			(xy 430.876779 -404.785708) (xy 430.891072 -404.799991) (xy 430.898815 -404.818654) (xy 430.899316 -404.828756)
			(xy 430.899316 -405.11476) (xy 430.899521 -405.121632) (xy 430.90312 -405.134895) (xy 430.906428 -405.140922)
			(xy 430.922805 -405.169265) (xy 430.948603 -405.229427) (xy 430.96609 -405.292508) (xy 430.974947 -405.357366)
			(xy 430.975516 -405.390096) (xy 430.974969 -405.422826) (xy 430.966107 -405.487685) (xy 430.948612 -405.550765)
			(xy 430.922799 -405.610923) (xy 430.91599 -405.622713) (xy 432.204712 -405.622713) (xy 432.204713 -405.557276)
			(xy 432.213497 -405.492431) (xy 432.230906 -405.429352) (xy 432.256625 -405.369181) (xy 432.272948 -405.34082)
			(xy 432.276251 -405.33479) (xy 432.279865 -405.32153) (xy 432.28006 -405.314658) (xy 432.28006 -404.565358)
			(xy 432.279851 -404.558486) (xy 432.276255 -404.545223) (xy 432.272948 -404.539196) (xy 432.256644 -404.510825)
			(xy 432.230924 -404.450656) (xy 432.213514 -404.387579) (xy 432.204728 -404.322737) (xy 432.204725 -404.257301)
			(xy 432.213506 -404.192458) (xy 432.230912 -404.12938) (xy 432.256627 -404.069209) (xy 432.272948 -404.040848)
			(xy 432.276277 -404.03483) (xy 432.279874 -404.021561) (xy 432.28006 -404.014686) (xy 432.28006 -403.728682)
			(xy 432.28045 -403.718507) (xy 432.288245 -403.699707) (xy 432.302641 -403.685322) (xy 432.321446 -403.677542)
			(xy 432.331622 -403.67712) (xy 433.047902 -403.67712) (xy 433.058058 -403.677631) (xy 433.076823 -403.685403)
			(xy 433.091188 -403.699763) (xy 433.098965 -403.718526) (xy 433.099464 -403.728682) (xy 433.099464 -404.014686)
			(xy 433.099666 -404.021558) (xy 433.103268 -404.034821) (xy 433.106576 -404.040848) (xy 433.122916 -404.069199)
			(xy 433.148631 -404.129373) (xy 433.166037 -404.192454) (xy 433.174818 -404.2573) (xy 433.174816 -404.290022)
			(xy 436.603656 -404.290022) (xy 436.607647 -404.227855) (xy 436.619556 -404.166708) (xy 436.639185 -404.107587)
			(xy 436.666214 -404.051461) (xy 436.700198 -403.999252) (xy 436.74058 -403.951817) (xy 436.786696 -403.909936)
			(xy 436.837788 -403.874296) (xy 436.893019 -403.845482) (xy 436.951481 -403.823968) (xy 437.012215 -403.810106)
			(xy 437.074222 -403.804124) (xy 437.136485 -403.80612) (xy 437.197982 -403.816063) (xy 437.257703 -403.833787)
			(xy 437.314666 -403.859004) (xy 437.367937 -403.891297) (xy 437.416642 -403.930137) (xy 437.459979 -403.974887)
			(xy 437.497239 -404.024811) (xy 437.507272 -404.042626) (xy 446.93027 -404.042626) (xy 446.934341 -403.987004)
			(xy 446.946467 -403.932567) (xy 446.96639 -403.880476) (xy 446.993686 -403.831841) (xy 447.027772 -403.787698)
			(xy 447.067921 -403.748989) (xy 447.113279 -403.716538) (xy 447.162879 -403.691037) (xy 447.215663 -403.67303)
			(xy 447.270506 -403.6629) (xy 447.32624 -403.660863) (xy 447.381677 -403.666963) (xy 447.435634 -403.681069)
			(xy 447.486963 -403.702881) (xy 447.534569 -403.731935) (xy 447.577437 -403.76761) (xy 447.614654 -403.809147)
			(xy 447.645427 -403.85566) (xy 447.669099 -403.906157) (xy 447.685167 -403.959564) (xy 447.693287 -404.01474)
			(xy 447.693796 -404.042626) (xy 447.693287 -404.070512) (xy 447.685167 -404.125688) (xy 447.669099 -404.179095)
			(xy 447.645427 -404.229592) (xy 447.614654 -404.276105) (xy 447.577437 -404.317642) (xy 447.534569 -404.353317)
			(xy 447.486963 -404.382371) (xy 447.435634 -404.404183) (xy 447.381677 -404.418289) (xy 447.32624 -404.424389)
			(xy 447.270506 -404.422352) (xy 447.215663 -404.412222) (xy 447.162879 -404.394215) (xy 447.113279 -404.368714)
			(xy 447.067921 -404.336263) (xy 447.027772 -404.297554) (xy 446.993686 -404.253411) (xy 446.96639 -404.204776)
			(xy 446.946467 -404.152685) (xy 446.934341 -404.098248) (xy 446.93027 -404.042626) (xy 437.507272 -404.042626)
			(xy 437.527808 -404.07909) (xy 437.551186 -404.136833) (xy 437.566987 -404.197091) (xy 437.574953 -404.258874)
			(xy 437.575452 -404.290022) (xy 437.574953 -404.32117) (xy 437.566987 -404.382953) (xy 437.551186 -404.443211)
			(xy 437.527808 -404.500954) (xy 437.497239 -404.555233) (xy 437.459979 -404.605157) (xy 437.416642 -404.649907)
			(xy 437.367937 -404.688747) (xy 437.314666 -404.72104) (xy 437.257703 -404.746257) (xy 437.197982 -404.763981)
			(xy 437.136485 -404.773924) (xy 437.074222 -404.77592) (xy 437.012215 -404.769938) (xy 436.951481 -404.756076)
			(xy 436.893019 -404.734562) (xy 436.837788 -404.705748) (xy 436.786696 -404.670108) (xy 436.74058 -404.628227)
			(xy 436.700198 -404.580792) (xy 436.666214 -404.528583) (xy 436.639185 -404.472457) (xy 436.619556 -404.413336)
			(xy 436.607647 -404.352189) (xy 436.603656 -404.290022) (xy 433.174816 -404.290022) (xy 433.174815 -404.322738)
			(xy 433.166029 -404.387583) (xy 433.148619 -404.450663) (xy 433.122899 -404.510835) (xy 433.106576 -404.539196)
			(xy 433.103261 -404.54522) (xy 433.099656 -404.558484) (xy 433.099464 -404.565358) (xy 433.099464 -405.314658)
			(xy 433.099676 -405.32153) (xy 433.103271 -405.334792) (xy 433.106576 -405.34082) (xy 433.122893 -405.369184)
			(xy 433.14861 -405.429355) (xy 433.166018 -405.492433) (xy 433.174802 -405.557277) (xy 433.174803 -405.622713)
			(xy 433.16602 -405.687557) (xy 433.148613 -405.750635) (xy 433.122897 -405.810807) (xy 433.106576 -405.839168)
			(xy 433.103271 -405.845197) (xy 433.09966 -405.858457) (xy 433.099464 -405.86533) (xy 433.099464 -406.151334)
			(xy 433.098995 -406.161494) (xy 433.091209 -406.180263) (xy 433.076836 -406.194627) (xy 433.058062 -406.202401)
			(xy 433.047902 -406.202896) (xy 432.331622 -406.202896) (xy 432.32147 -406.20235) (xy 432.302708 -406.194589)
			(xy 432.288343 -406.180239) (xy 432.280561 -406.161486) (xy 432.28006 -406.151334) (xy 432.28006 -405.86533)
			(xy 432.279862 -405.858457) (xy 432.276258 -405.845194) (xy 432.272948 -405.839168) (xy 432.25662 -405.81081)
			(xy 432.230903 -405.750638) (xy 432.213495 -405.687559) (xy 432.204712 -405.622713) (xy 430.91599 -405.622713)
			(xy 430.906428 -405.63927) (xy 430.903126 -405.645301) (xy 430.899512 -405.65856) (xy 430.899316 -405.665432)
			(xy 430.899316 -406.414732) (xy 430.899494 -406.421606) (xy 430.903111 -406.434869) (xy 430.906428 -406.440894)
			(xy 430.922794 -406.469243) (xy 430.948595 -406.529403) (xy 430.966084 -406.592482) (xy 430.974945 -406.657339)
			(xy 430.975516 -406.690068) (xy 430.974956 -406.722792) (xy 434.404852 -406.722792) (xy 434.404856 -406.657353)
			(xy 434.413643 -406.592508) (xy 434.431053 -406.529428) (xy 434.456773 -406.469256) (xy 434.473096 -406.440894)
			(xy 434.476413 -406.43487) (xy 434.480017 -406.421606) (xy 434.480208 -406.414732) (xy 434.480208 -405.665432)
			(xy 434.480003 -405.65856) (xy 434.476404 -405.645297) (xy 434.473096 -405.63927) (xy 434.456772 -405.61091)
			(xy 434.431057 -405.550738) (xy 434.413651 -405.487659) (xy 434.404868 -405.422815) (xy 434.404869 -405.357378)
			(xy 434.413652 -405.292534) (xy 434.431059 -405.229455) (xy 434.456775 -405.169284) (xy 434.473096 -405.140922)
			(xy 434.476403 -405.134893) (xy 434.480013 -405.121633) (xy 434.480208 -405.11476) (xy 434.480208 -404.828756)
			(xy 434.480586 -404.818598) (xy 434.488397 -404.799843) (xy 434.502807 -404.785521) (xy 434.52161 -404.777824)
			(xy 434.53177 -404.777448) (xy 435.24805 -404.777448) (xy 435.258175 -404.777968) (xy 435.276896 -404.785681)
			(xy 435.291254 -404.799957) (xy 435.299074 -404.818634) (xy 435.299612 -404.828756) (xy 435.299612 -405.11476)
			(xy 435.299818 -405.121632) (xy 435.303417 -405.134895) (xy 435.306724 -405.140922) (xy 435.323044 -405.169285)
			(xy 435.348764 -405.229455) (xy 435.366174 -405.292534) (xy 435.374958 -405.357378) (xy 435.374959 -405.422815)
			(xy 435.366175 -405.48766) (xy 435.348766 -405.550738) (xy 435.331987 -405.589994) (xy 436.603656 -405.589994)
			(xy 436.607647 -405.527827) (xy 436.619556 -405.46668) (xy 436.639185 -405.407559) (xy 436.666214 -405.351433)
			(xy 436.700198 -405.299224) (xy 436.74058 -405.251789) (xy 436.786696 -405.209908) (xy 436.837788 -405.174268)
			(xy 436.893019 -405.145454) (xy 436.951481 -405.12394) (xy 437.012215 -405.110078) (xy 437.074222 -405.104096)
			(xy 437.136485 -405.106092) (xy 437.197982 -405.116035) (xy 437.257703 -405.133759) (xy 437.314666 -405.158976)
			(xy 437.367937 -405.191269) (xy 437.416642 -405.230109) (xy 437.459979 -405.274859) (xy 437.497239 -405.324783)
			(xy 437.527808 -405.379062) (xy 437.532275 -405.390096) (xy 438.803804 -405.390096) (xy 438.807795 -405.327929)
			(xy 438.819704 -405.266782) (xy 438.839333 -405.207661) (xy 438.866362 -405.151535) (xy 438.900346 -405.099326)
			(xy 438.940728 -405.051891) (xy 438.986844 -405.01001) (xy 439.037936 -404.97437) (xy 439.093167 -404.945556)
			(xy 439.151629 -404.924042) (xy 439.212363 -404.91018) (xy 439.27437 -404.904198) (xy 439.336633 -404.906194)
			(xy 439.39813 -404.916137) (xy 439.457851 -404.933861) (xy 439.514814 -404.959078) (xy 439.568085 -404.991371)
			(xy 439.61679 -405.030211) (xy 439.660127 -405.074961) (xy 439.697387 -405.124885) (xy 439.727956 -405.179164)
			(xy 439.751334 -405.236907) (xy 439.767135 -405.297165) (xy 439.775101 -405.358948) (xy 439.7756 -405.390096)
			(xy 439.775101 -405.421244) (xy 439.767135 -405.483027) (xy 439.751334 -405.543285) (xy 439.727956 -405.601028)
			(xy 439.697387 -405.655307) (xy 439.660127 -405.705231) (xy 439.61679 -405.749981) (xy 439.568085 -405.788821)
			(xy 439.514814 -405.821114) (xy 439.457851 -405.846331) (xy 439.39813 -405.864055) (xy 439.336633 -405.873998)
			(xy 439.27437 -405.875994) (xy 439.212363 -405.870012) (xy 439.151629 -405.85615) (xy 439.093167 -405.834636)
			(xy 439.037936 -405.805822) (xy 438.986844 -405.770182) (xy 438.940728 -405.728301) (xy 438.900346 -405.680866)
			(xy 438.866362 -405.628657) (xy 438.839333 -405.572531) (xy 438.819704 -405.51341) (xy 438.807795 -405.452263)
			(xy 438.803804 -405.390096) (xy 437.532275 -405.390096) (xy 437.551186 -405.436805) (xy 437.566987 -405.497063)
			(xy 437.574953 -405.558846) (xy 437.575452 -405.589994) (xy 437.574953 -405.621142) (xy 437.566987 -405.682925)
			(xy 437.551186 -405.743183) (xy 437.527808 -405.800926) (xy 437.497239 -405.855205) (xy 437.459979 -405.905129)
			(xy 437.416642 -405.949879) (xy 437.367937 -405.988719) (xy 437.314666 -406.021012) (xy 437.257703 -406.046229)
			(xy 437.197982 -406.063953) (xy 437.136485 -406.073896) (xy 437.074222 -406.075892) (xy 437.012215 -406.06991)
			(xy 436.951481 -406.056048) (xy 436.893019 -406.034534) (xy 436.837788 -406.00572) (xy 436.786696 -405.97008)
			(xy 436.74058 -405.928199) (xy 436.700198 -405.880764) (xy 436.666214 -405.828555) (xy 436.639185 -405.772429)
			(xy 436.619556 -405.713308) (xy 436.607647 -405.652161) (xy 436.603656 -405.589994) (xy 435.331987 -405.589994)
			(xy 435.323047 -405.610909) (xy 435.306724 -405.63927) (xy 435.303422 -405.645301) (xy 435.299808 -405.65856)
			(xy 435.299612 -405.665432) (xy 435.299612 -406.153366) (xy 446.64452 -406.153366) (xy 446.648591 -406.097744)
			(xy 446.660717 -406.043307) (xy 446.68064 -405.991216) (xy 446.707936 -405.942581) (xy 446.742022 -405.898438)
			(xy 446.782171 -405.859729) (xy 446.827529 -405.827278) (xy 446.877129 -405.801777) (xy 446.929913 -405.78377)
			(xy 446.984756 -405.77364) (xy 447.04049 -405.771603) (xy 447.095927 -405.777703) (xy 447.149884 -405.791809)
			(xy 447.201213 -405.813621) (xy 447.248819 -405.842675) (xy 447.291687 -405.87835) (xy 447.328904 -405.919887)
			(xy 447.359677 -405.9664) (xy 447.383349 -406.016897) (xy 447.399417 -406.070304) (xy 447.407537 -406.12548)
			(xy 447.408046 -406.153366) (xy 447.407537 -406.181252) (xy 447.399417 -406.236428) (xy 447.387573 -406.275794)
			(xy 447.938142 -406.275794) (xy 447.942213 -406.220172) (xy 447.954339 -406.165735) (xy 447.974262 -406.113644)
			(xy 448.001558 -406.065009) (xy 448.035644 -406.020866) (xy 448.075793 -405.982157) (xy 448.121151 -405.949706)
			(xy 448.170751 -405.924205) (xy 448.223535 -405.906198) (xy 448.278378 -405.896068) (xy 448.334112 -405.894031)
			(xy 448.389549 -405.900131) (xy 448.443506 -405.914237) (xy 448.494835 -405.936049) (xy 448.542441 -405.965103)
			(xy 448.585309 -406.000778) (xy 448.622526 -406.042315) (xy 448.653299 -406.088828) (xy 448.676971 -406.139325)
			(xy 448.693039 -406.192732) (xy 448.701159 -406.247908) (xy 448.701668 -406.275794) (xy 448.701159 -406.30368)
			(xy 448.693039 -406.358856) (xy 448.676971 -406.412263) (xy 448.653299 -406.46276) (xy 448.622526 -406.509273)
			(xy 448.585309 -406.55081) (xy 448.542441 -406.586485) (xy 448.494835 -406.615539) (xy 448.443506 -406.637351)
			(xy 448.389549 -406.651457) (xy 448.334112 -406.657557) (xy 448.278378 -406.65552) (xy 448.223535 -406.64539)
			(xy 448.170751 -406.627383) (xy 448.121151 -406.601882) (xy 448.075793 -406.569431) (xy 448.035644 -406.530722)
			(xy 448.001558 -406.486579) (xy 447.974262 -406.437944) (xy 447.954339 -406.385853) (xy 447.942213 -406.331416)
			(xy 447.938142 -406.275794) (xy 447.387573 -406.275794) (xy 447.383349 -406.289835) (xy 447.359677 -406.340332)
			(xy 447.328904 -406.386845) (xy 447.291687 -406.428382) (xy 447.248819 -406.464057) (xy 447.201213 -406.493111)
			(xy 447.149884 -406.514923) (xy 447.095927 -406.529029) (xy 447.04049 -406.535129) (xy 446.984756 -406.533092)
			(xy 446.929913 -406.522962) (xy 446.877129 -406.504955) (xy 446.827529 -406.479454) (xy 446.782171 -406.447003)
			(xy 446.742022 -406.408294) (xy 446.707936 -406.364151) (xy 446.68064 -406.315516) (xy 446.660717 -406.263425)
			(xy 446.648591 -406.208988) (xy 446.64452 -406.153366) (xy 435.299612 -406.153366) (xy 435.299612 -406.414732)
			(xy 435.29979 -406.421606) (xy 435.303408 -406.434869) (xy 435.306724 -406.440894) (xy 435.32302 -406.46927)
			(xy 435.348742 -406.529437) (xy 435.366155 -406.592513) (xy 435.374942 -406.657355) (xy 435.374944 -406.690068)
			(xy 438.803804 -406.690068) (xy 438.807795 -406.627901) (xy 438.819704 -406.566754) (xy 438.839333 -406.507633)
			(xy 438.866362 -406.451507) (xy 438.900346 -406.399298) (xy 438.940728 -406.351863) (xy 438.986844 -406.309982)
			(xy 439.037936 -406.274342) (xy 439.093167 -406.245528) (xy 439.151629 -406.224014) (xy 439.212363 -406.210152)
			(xy 439.27437 -406.20417) (xy 439.336633 -406.206166) (xy 439.39813 -406.216109) (xy 439.457851 -406.233833)
			(xy 439.514814 -406.25905) (xy 439.568085 -406.291343) (xy 439.61679 -406.330183) (xy 439.660127 -406.374933)
			(xy 439.697387 -406.424857) (xy 439.727956 -406.479136) (xy 439.751334 -406.536879) (xy 439.767135 -406.597137)
			(xy 439.775101 -406.65892) (xy 439.7756 -406.690068) (xy 439.775101 -406.721216) (xy 439.767135 -406.782999)
			(xy 439.751334 -406.843257) (xy 439.727956 -406.901) (xy 439.697387 -406.955279) (xy 439.660127 -407.005203)
			(xy 439.61679 -407.049953) (xy 439.568085 -407.088793) (xy 439.514814 -407.121086) (xy 439.457851 -407.146303)
			(xy 439.39813 -407.164027) (xy 439.336633 -407.17397) (xy 439.27437 -407.175966) (xy 439.212363 -407.169984)
			(xy 439.151629 -407.156122) (xy 439.093167 -407.134608) (xy 439.037936 -407.105794) (xy 438.986844 -407.070154)
			(xy 438.940728 -407.028273) (xy 438.900346 -406.980838) (xy 438.866362 -406.928629) (xy 438.839333 -406.872503)
			(xy 438.819704 -406.813382) (xy 438.807795 -406.752235) (xy 438.803804 -406.690068) (xy 435.374944 -406.690068)
			(xy 435.374946 -406.72279) (xy 435.366166 -406.787633) (xy 435.348761 -406.850711) (xy 435.323045 -406.910881)
			(xy 435.306724 -406.939242) (xy 435.303396 -406.94526) (xy 435.299798 -406.958529) (xy 435.299612 -406.965404)
			(xy 435.299612 -407.251408) (xy 435.299185 -407.261561) (xy 435.291389 -407.280311) (xy 435.276994 -407.294634)
			(xy 435.258205 -407.302335) (xy 435.24805 -407.302716) (xy 434.53177 -407.302716) (xy 434.521636 -407.302297)
			(xy 434.502906 -407.294551) (xy 434.488549 -407.280244) (xy 434.480739 -407.26154) (xy 434.480208 -407.251408)
			(xy 434.480208 -406.965404) (xy 434.480014 -406.958531) (xy 434.476407 -406.945268) (xy 434.473096 -406.939242)
			(xy 434.456748 -406.910895) (xy 434.431035 -406.85072) (xy 434.413632 -406.787639) (xy 434.404852 -406.722792)
			(xy 430.974956 -406.722792) (xy 430.974956 -406.722798) (xy 430.966099 -406.787656) (xy 430.948606 -406.850736)
			(xy 430.922797 -406.910894) (xy 430.906428 -406.939242) (xy 430.9031 -406.94526) (xy 430.899502 -406.958529)
			(xy 430.899316 -406.965404) (xy 430.899316 -407.251408) (xy 430.898822 -407.261515) (xy 430.891084 -407.28019)
			(xy 430.87679 -407.294484) (xy 430.858115 -407.302222) (xy 430.848008 -407.302716) (xy 430.131728 -407.302716)
			(xy 430.121609 -407.302262) (xy 430.102909 -407.294526) (xy 430.088595 -407.280221) (xy 430.080845 -407.261526)
			(xy 430.08042 -407.251408) (xy 430.08042 -406.965404) (xy 430.080224 -406.958531) (xy 430.076618 -406.945268)
			(xy 430.073308 -406.939242) (xy 430.05696 -406.910883) (xy 430.031154 -406.850727) (xy 430.013659 -406.787651)
			(xy 430.004793 -406.722796) (xy 430.00422 -406.690068) (xy 426.574858 -406.690068) (xy 426.57486 -406.72279)
			(xy 426.56608 -406.787633) (xy 426.548675 -406.850711) (xy 426.522961 -406.910881) (xy 426.50664 -406.939242)
			(xy 426.503314 -406.945261) (xy 426.499715 -406.958529) (xy 426.499528 -406.965404) (xy 426.499528 -407.251408)
			(xy 426.499085 -407.261559) (xy 426.491292 -407.280306) (xy 426.476903 -407.294628) (xy 426.458119 -407.302333)
			(xy 426.447966 -407.302716) (xy 425.731686 -407.302716) (xy 425.721553 -407.302283) (xy 425.702823 -407.294543)
			(xy 425.688466 -407.28024) (xy 425.680655 -407.261539) (xy 425.680124 -407.251408) (xy 425.680124 -406.965404)
			(xy 425.679928 -406.958531) (xy 425.676322 -406.945268) (xy 425.673012 -406.939242) (xy 425.656663 -406.910895)
			(xy 425.63095 -406.850721) (xy 425.613546 -406.787639) (xy 425.604766 -406.722792) (xy 422.17487 -406.722792)
			(xy 422.17487 -406.722798) (xy 422.166013 -406.787656) (xy 422.148521 -406.850736) (xy 422.122713 -406.910894)
			(xy 422.106344 -406.939242) (xy 422.103018 -406.945261) (xy 422.099419 -406.958529) (xy 422.099232 -406.965404)
			(xy 422.099232 -407.251408) (xy 422.098722 -407.261513) (xy 422.090988 -407.280185) (xy 422.076699 -407.294479)
			(xy 422.058029 -407.302219) (xy 422.047924 -407.302716) (xy 421.331644 -407.302716) (xy 421.321526 -407.302248)
			(xy 421.302827 -407.294518) (xy 421.288512 -407.280217) (xy 421.280762 -407.261525) (xy 421.280336 -407.251408)
			(xy 421.280336 -406.965404) (xy 421.280138 -406.958531) (xy 421.276533 -406.945269) (xy 421.273224 -406.939242)
			(xy 421.256877 -406.910882) (xy 421.23107 -406.850727) (xy 421.213575 -406.78765) (xy 421.204709 -406.722796)
			(xy 421.204136 -406.690068) (xy 414.52546 -406.690068) (xy 414.52546 -409.522889) (xy 419.004819 -409.522889)
			(xy 419.004823 -409.457449) (xy 419.013612 -409.392602) (xy 419.031026 -409.329522) (xy 419.05675 -409.269351)
			(xy 419.073076 -409.24099) (xy 419.076393 -409.234966) (xy 419.079998 -409.221702) (xy 419.080188 -409.214828)
			(xy 419.080188 -408.465528) (xy 419.079987 -408.458655) (xy 419.076385 -408.445393) (xy 419.073076 -408.439366)
			(xy 419.056746 -408.411009) (xy 419.031027 -408.350837) (xy 419.013618 -408.287758) (xy 419.004835 -408.222912)
			(xy 419.004836 -408.157474) (xy 419.013621 -408.092629) (xy 419.031031 -408.02955) (xy 419.056752 -407.969379)
			(xy 419.073076 -407.941018) (xy 419.076383 -407.934989) (xy 419.079994 -407.921729) (xy 419.080188 -407.914856)
			(xy 419.080188 -407.628852) (xy 419.080582 -407.618696) (xy 419.088391 -407.599945) (xy 419.102796 -407.585624)
			(xy 419.121592 -407.577924) (xy 419.13175 -407.577544) (xy 419.84803 -407.577544) (xy 419.858159 -407.578002)
			(xy 419.876882 -407.58574) (xy 419.891237 -407.600035) (xy 419.899055 -407.618725) (xy 419.899592 -407.628852)
			(xy 419.899592 -407.914856) (xy 419.899802 -407.921728) (xy 419.903398 -407.934991) (xy 419.906704 -407.941018)
			(xy 419.923018 -407.969383) (xy 419.948734 -408.029554) (xy 419.966141 -408.092632) (xy 419.974925 -408.157475)
			(xy 419.974926 -408.222911) (xy 419.966144 -408.287755) (xy 419.948739 -408.350833) (xy 419.923024 -408.411004)
			(xy 419.906704 -408.439366) (xy 419.903402 -408.445397) (xy 419.899788 -408.458656) (xy 419.899592 -408.465528)
			(xy 419.899592 -409.214828) (xy 419.899774 -409.221702) (xy 419.903389 -409.234965) (xy 419.906704 -409.24099)
			(xy 419.922994 -409.269369) (xy 419.948713 -409.329536) (xy 419.966122 -409.392611) (xy 419.974909 -409.457452)
			(xy 419.974913 -409.522886) (xy 419.966135 -409.587728) (xy 419.948733 -409.650805) (xy 419.923022 -409.710976)
			(xy 419.906704 -409.739338) (xy 419.903376 -409.745356) (xy 419.899779 -409.758625) (xy 419.899592 -409.7655)
			(xy 419.899592 -410.051504) (xy 419.899181 -410.061659) (xy 419.891383 -410.080413) (xy 419.876983 -410.094737)
			(xy 419.858187 -410.102435) (xy 419.84803 -410.102812) (xy 419.13175 -410.102812) (xy 419.121633 -410.102234)
			(xy 419.102923 -410.094532) (xy 419.088567 -410.080274) (xy 419.080736 -410.061618) (xy 419.080188 -410.051504)
			(xy 419.080188 -409.7655) (xy 419.079997 -409.758627) (xy 419.076388 -409.745364) (xy 419.073076 -409.739338)
			(xy 419.056722 -409.710994) (xy 419.031005 -409.650819) (xy 419.013599 -409.587737) (xy 419.004819 -409.522889)
			(xy 414.52546 -409.522889) (xy 414.52546 -410.589984) (xy 421.204136 -410.589984) (xy 421.204725 -410.557255)
			(xy 421.213576 -410.492398) (xy 421.231059 -410.429318) (xy 421.256859 -410.369159) (xy 421.273224 -410.34081)
			(xy 421.276537 -410.334785) (xy 421.280143 -410.321521) (xy 421.280336 -410.314648) (xy 421.280336 -409.565348)
			(xy 421.280121 -409.558476) (xy 421.276528 -409.545214) (xy 421.273224 -409.539186) (xy 421.256855 -409.510839)
			(xy 421.231054 -409.450679) (xy 421.213565 -409.387598) (xy 421.204706 -409.322741) (xy 421.204136 -409.290012)
			(xy 421.204693 -409.257282) (xy 421.213553 -409.192424) (xy 421.231046 -409.129344) (xy 421.256855 -409.069186)
			(xy 421.273224 -409.040838) (xy 421.276527 -409.034808) (xy 421.28014 -409.021548) (xy 421.280336 -409.014676)
			(xy 421.280336 -408.728672) (xy 421.280694 -408.718543) (xy 421.288458 -408.699832) (xy 421.302793 -408.685517)
			(xy 421.321515 -408.67778) (xy 421.331644 -408.677364) (xy 422.047924 -408.677364) (xy 422.05803 -408.677864)
			(xy 422.076702 -408.685603) (xy 422.090994 -408.699895) (xy 422.098735 -408.718566) (xy 422.099232 -408.728672)
			(xy 422.099232 -409.014676) (xy 422.099429 -409.021549) (xy 422.103033 -409.034812) (xy 422.106344 -409.040838)
			(xy 422.122719 -409.069182) (xy 422.14852 -409.129343) (xy 422.166007 -409.192424) (xy 422.174864 -409.257282)
			(xy 422.175432 -409.290012) (xy 422.174845 -409.322741) (xy 422.165995 -409.387598) (xy 422.14851 -409.450678)
			(xy 422.131575 -409.490164) (xy 423.404284 -409.490164) (xy 423.404858 -409.457435) (xy 423.413712 -409.392577)
			(xy 423.4312 -409.329497) (xy 423.457005 -409.269338) (xy 423.473372 -409.24099) (xy 423.476688 -409.234966)
			(xy 423.480293 -409.221702) (xy 423.480484 -409.214828) (xy 423.480484 -408.465528) (xy 423.480283 -408.458655)
			(xy 423.476681 -408.445393) (xy 423.473372 -408.439366) (xy 423.45699 -408.411026) (xy 423.431193 -408.350863)
			(xy 423.413708 -408.287781) (xy 423.404852 -408.222922) (xy 423.404284 -408.190192) (xy 423.404871 -408.157463)
			(xy 423.413721 -408.092606) (xy 423.431205 -408.029526) (xy 423.457006 -407.969367) (xy 423.473372 -407.941018)
			(xy 423.476678 -407.934989) (xy 423.48029 -407.921729) (xy 423.480484 -407.914856) (xy 423.480484 -407.628852)
			(xy 423.480946 -407.618742) (xy 423.488696 -407.600066) (xy 423.503 -407.585774) (xy 423.521682 -407.578038)
			(xy 423.531792 -407.577544) (xy 424.248072 -407.577544) (xy 424.258172 -407.578106) (xy 424.276839 -407.585825)
			(xy 424.291133 -407.600097) (xy 424.298879 -407.618753) (xy 424.29938 -407.628852) (xy 424.29938 -407.914856)
			(xy 424.299591 -407.921728) (xy 424.303186 -407.934991) (xy 424.306492 -407.941018) (xy 424.322864 -407.969364)
			(xy 424.348664 -408.029524) (xy 424.366152 -408.092605) (xy 424.375011 -408.157463) (xy 424.37558 -408.190192)
			(xy 424.375036 -408.222922) (xy 424.366174 -408.287781) (xy 424.348677 -408.350862) (xy 424.322864 -408.411019)
			(xy 424.306492 -408.439366) (xy 424.303189 -408.445396) (xy 424.299576 -408.458656) (xy 424.29938 -408.465528)
			(xy 424.29938 -409.214828) (xy 424.299564 -409.221702) (xy 424.303178 -409.234964) (xy 424.306492 -409.24099)
			(xy 424.322853 -409.269342) (xy 424.348656 -409.3295) (xy 424.366147 -409.392579) (xy 424.375009 -409.457435)
			(xy 424.37558 -409.490164) (xy 424.375023 -409.522894) (xy 424.366165 -409.587753) (xy 424.348672 -409.650833)
			(xy 424.322862 -409.71099) (xy 424.306492 -409.739338) (xy 424.303163 -409.745356) (xy 424.299567 -409.758625)
			(xy 424.29938 -409.7655) (xy 424.29938 -410.051504) (xy 424.298987 -410.061629) (xy 424.291234 -410.080337)
			(xy 424.27691 -410.094651) (xy 424.258197 -410.102393) (xy 424.248072 -410.102812) (xy 423.531792 -410.102812)
			(xy 423.521684 -410.102322) (xy 423.503008 -410.094584) (xy 423.488714 -410.080288) (xy 423.480978 -410.061612)
			(xy 423.480484 -410.051504) (xy 423.480484 -409.7655) (xy 423.480294 -409.758627) (xy 423.476684 -409.745364)
			(xy 423.473372 -409.739338) (xy 423.457019 -409.710982) (xy 423.431215 -409.650825) (xy 423.413722 -409.587747)
			(xy 423.404857 -409.522892) (xy 423.404284 -409.490164) (xy 422.131575 -409.490164) (xy 422.122709 -409.510837)
			(xy 422.106344 -409.539186) (xy 422.103038 -409.545215) (xy 422.099426 -409.558475) (xy 422.099232 -409.565348)
			(xy 422.099232 -410.314648) (xy 422.09944 -410.32152) (xy 422.103037 -410.334783) (xy 422.106344 -410.34081)
			(xy 422.122708 -410.36916) (xy 422.148512 -410.429319) (xy 422.166002 -410.492398) (xy 422.174862 -410.557255)
			(xy 422.175432 -410.589984) (xy 422.174877 -410.622705) (xy 425.604775 -410.622705) (xy 425.604777 -410.557268)
			(xy 425.613562 -410.492422) (xy 425.630971 -410.429343) (xy 425.65669 -410.369172) (xy 425.673012 -410.34081)
			(xy 425.676324 -410.334784) (xy 425.679931 -410.321521) (xy 425.680124 -410.314648) (xy 425.680124 -409.565348)
			(xy 425.679911 -409.558476) (xy 425.676317 -409.545214) (xy 425.673012 -409.539186) (xy 425.656701 -409.510819)
			(xy 425.630984 -409.450649) (xy 425.613575 -409.387571) (xy 425.604791 -409.322728) (xy 425.60479 -409.257293)
			(xy 425.613571 -409.192449) (xy 425.630977 -409.129371) (xy 425.656691 -409.0692) (xy 425.673012 -409.040838)
			(xy 425.676314 -409.034807) (xy 425.679927 -409.021548) (xy 425.680124 -409.014676) (xy 425.680124 -408.728672)
			(xy 425.680499 -408.718513) (xy 425.688308 -408.699755) (xy 425.70272 -408.685432) (xy 425.721525 -408.677738)
			(xy 425.731686 -408.677364) (xy 426.447966 -408.677364) (xy 426.458093 -408.677855) (xy 426.476818 -408.685576)
			(xy 426.491177 -408.699862) (xy 426.498993 -408.718547) (xy 426.499528 -408.728672) (xy 426.499528 -409.014676)
			(xy 426.499726 -409.021549) (xy 426.50333 -409.034812) (xy 426.50664 -409.040838) (xy 426.522973 -409.069193)
			(xy 426.548691 -409.129366) (xy 426.566099 -409.192446) (xy 426.574881 -409.257291) (xy 426.57488 -409.322729)
			(xy 426.566094 -409.387575) (xy 426.548684 -409.450654) (xy 426.522964 -409.510825) (xy 426.51602 -409.522889)
			(xy 427.804905 -409.522889) (xy 427.804909 -409.457449) (xy 427.813698 -409.392603) (xy 427.831111 -409.329523)
			(xy 427.856835 -409.269351) (xy 427.87316 -409.24099) (xy 427.876475 -409.234965) (xy 427.880081 -409.221702)
			(xy 427.880272 -409.214828) (xy 427.880272 -408.465528) (xy 427.880073 -408.458655) (xy 427.87647 -408.445392)
			(xy 427.87316 -408.439366) (xy 427.85683 -408.411009) (xy 427.831112 -408.350837) (xy 427.813704 -408.287757)
			(xy 427.804921 -408.222912) (xy 427.804922 -408.157474) (xy 427.813707 -408.092629) (xy 427.831117 -408.02955)
			(xy 427.856837 -407.969379) (xy 427.87316 -407.941018) (xy 427.876465 -407.934989) (xy 427.880077 -407.921729)
			(xy 427.880272 -407.914856) (xy 427.880272 -407.628852) (xy 427.880682 -407.618698) (xy 427.888488 -407.59995)
			(xy 427.902887 -407.58563) (xy 427.921678 -407.577927) (xy 427.931834 -407.577544) (xy 428.648114 -407.577544)
			(xy 428.658242 -407.578015) (xy 428.676964 -407.585749) (xy 428.69132 -407.600039) (xy 428.699138 -407.618726)
			(xy 428.699676 -407.628852) (xy 428.699676 -407.914856) (xy 428.699888 -407.921728) (xy 428.703483 -407.93499)
			(xy 428.706788 -407.941018) (xy 428.723103 -407.969383) (xy 428.748819 -408.029554) (xy 428.766227 -408.092632)
			(xy 428.775011 -408.157475) (xy 428.775012 -408.222911) (xy 428.76623 -408.287755) (xy 428.748824 -408.350833)
			(xy 428.723109 -408.411004) (xy 428.706788 -408.439366) (xy 428.703485 -408.445396) (xy 428.699872 -408.458656)
			(xy 428.699676 -408.465528) (xy 428.699676 -409.214828) (xy 428.69986 -409.221702) (xy 428.703474 -409.234964)
			(xy 428.706788 -409.24099) (xy 428.723079 -409.269368) (xy 428.748798 -409.329536) (xy 428.766208 -409.392611)
			(xy 428.774995 -409.457452) (xy 428.774999 -409.522886) (xy 428.766221 -409.587728) (xy 428.748818 -409.650806)
			(xy 428.723107 -409.710977) (xy 428.706788 -409.739338) (xy 428.703459 -409.745356) (xy 428.699863 -409.758625)
			(xy 428.699676 -409.7655) (xy 428.699676 -410.051504) (xy 428.699281 -410.061661) (xy 428.69148 -410.080418)
			(xy 428.677074 -410.094742) (xy 428.658274 -410.102438) (xy 428.648114 -410.102812) (xy 427.931834 -410.102812)
			(xy 427.921716 -410.102247) (xy 427.903005 -410.09454) (xy 427.88865 -410.080278) (xy 427.88082 -410.061619)
			(xy 427.880272 -410.051504) (xy 427.880272 -409.7655) (xy 427.880083 -409.758626) (xy 427.876473 -409.745364)
			(xy 427.87316 -409.739338) (xy 427.856807 -409.710994) (xy 427.831091 -409.650819) (xy 427.813685 -409.587737)
			(xy 427.804905 -409.522889) (xy 426.51602 -409.522889) (xy 426.50664 -409.539186) (xy 426.503334 -409.545215)
			(xy 426.499722 -409.558475) (xy 426.499528 -409.565348) (xy 426.499528 -410.314648) (xy 426.499736 -410.32152)
			(xy 426.503333 -410.334783) (xy 426.50664 -410.34081) (xy 426.522949 -410.369179) (xy 426.548669 -410.429348)
			(xy 426.56608 -410.492425) (xy 426.574865 -410.557268) (xy 426.574866 -410.589984) (xy 430.00422 -410.589984)
			(xy 430.004798 -410.557255) (xy 430.01365 -410.492397) (xy 430.031136 -410.429317) (xy 430.056941 -410.369158)
			(xy 430.073308 -410.34081) (xy 430.07662 -410.334784) (xy 430.080227 -410.321521) (xy 430.08042 -410.314648)
			(xy 430.08042 -409.565348) (xy 430.080207 -409.558476) (xy 430.076613 -409.545214) (xy 430.073308 -409.539186)
			(xy 430.056938 -409.510839) (xy 430.031137 -409.450679) (xy 430.013648 -409.387599) (xy 430.00479 -409.322741)
			(xy 430.00422 -409.290012) (xy 430.004766 -409.257282) (xy 430.013627 -409.192423) (xy 430.031123 -409.129343)
			(xy 430.056937 -409.069185) (xy 430.073308 -409.040838) (xy 430.07661 -409.034807) (xy 430.080223 -409.021548)
			(xy 430.08042 -409.014676) (xy 430.08042 -408.728672) (xy 430.080863 -408.718559) (xy 430.088613 -408.699876)
			(xy 430.102923 -408.685582) (xy 430.121614 -408.677852) (xy 430.131728 -408.677364) (xy 430.848008 -408.677364)
			(xy 430.858113 -408.677878) (xy 430.876784 -408.685611) (xy 430.891077 -408.699899) (xy 430.898818 -408.718567)
			(xy 430.899316 -408.728672) (xy 430.899316 -409.014676) (xy 430.899515 -409.021549) (xy 430.903118 -409.034812)
			(xy 430.906428 -409.040838) (xy 430.922811 -409.069177) (xy 430.948608 -409.129341) (xy 430.966093 -409.192423)
			(xy 430.974948 -409.257282) (xy 430.975516 -409.290012) (xy 430.974931 -409.322741) (xy 430.966081 -409.387598)
			(xy 430.948596 -409.450678) (xy 430.922794 -409.510837) (xy 430.915836 -409.522889) (xy 432.204695 -409.522889)
			(xy 432.204699 -409.457449) (xy 432.213487 -409.392603) (xy 432.2309 -409.329523) (xy 432.256623 -409.269351)
			(xy 432.272948 -409.24099) (xy 432.276262 -409.234965) (xy 432.279869 -409.221702) (xy 432.28006 -409.214828)
			(xy 432.28006 -408.465528) (xy 432.279862 -408.458655) (xy 432.276259 -408.445392) (xy 432.272948 -408.439366)
			(xy 432.256619 -408.411009) (xy 432.230901 -408.350837) (xy 432.213494 -408.287757) (xy 432.204711 -408.222912)
			(xy 432.204712 -408.157474) (xy 432.213496 -408.092629) (xy 432.230906 -408.02955) (xy 432.256625 -407.969379)
			(xy 432.272948 -407.941018) (xy 432.276252 -407.934988) (xy 432.279865 -407.921729) (xy 432.28006 -407.914856)
			(xy 432.28006 -407.628852) (xy 432.280482 -407.6187) (xy 432.288286 -407.599954) (xy 432.302681 -407.585634)
			(xy 432.321468 -407.577929) (xy 432.331622 -407.577544) (xy 433.047902 -407.577544) (xy 433.058029 -407.578025)
			(xy 433.076751 -407.585754) (xy 433.091108 -407.600042) (xy 433.098926 -407.618727) (xy 433.099464 -407.628852)
			(xy 433.099464 -407.914856) (xy 433.099677 -407.921728) (xy 433.103271 -407.93499) (xy 433.106576 -407.941018)
			(xy 433.122891 -407.969383) (xy 433.148608 -408.029554) (xy 433.166017 -408.092631) (xy 433.174801 -408.157475)
			(xy 433.174801 -408.190192) (xy 436.603656 -408.190192) (xy 436.607647 -408.128025) (xy 436.619556 -408.066878)
			(xy 436.639185 -408.007757) (xy 436.666214 -407.951631) (xy 436.700198 -407.899422) (xy 436.74058 -407.851987)
			(xy 436.786696 -407.810106) (xy 436.837788 -407.774466) (xy 436.893019 -407.745652) (xy 436.951481 -407.724138)
			(xy 437.012215 -407.710276) (xy 437.074222 -407.704294) (xy 437.136485 -407.70629) (xy 437.197982 -407.716233)
			(xy 437.257703 -407.733957) (xy 437.314666 -407.759174) (xy 437.367937 -407.791467) (xy 437.416642 -407.830307)
			(xy 437.459979 -407.875057) (xy 437.497239 -407.924981) (xy 437.527808 -407.97926) (xy 437.551186 -408.037003)
			(xy 437.566987 -408.097261) (xy 437.574953 -408.159044) (xy 437.575452 -408.190192) (xy 437.574953 -408.22134)
			(xy 437.566987 -408.283123) (xy 437.551186 -408.343381) (xy 437.527808 -408.401124) (xy 437.497239 -408.455403)
			(xy 437.459979 -408.505327) (xy 437.416642 -408.550077) (xy 437.367937 -408.588917) (xy 437.314666 -408.62121)
			(xy 437.257703 -408.646427) (xy 437.197982 -408.664151) (xy 437.136485 -408.674094) (xy 437.074222 -408.67609)
			(xy 437.012215 -408.670108) (xy 436.951481 -408.656246) (xy 436.893019 -408.634732) (xy 436.837788 -408.605918)
			(xy 436.786696 -408.570278) (xy 436.74058 -408.528397) (xy 436.700198 -408.480962) (xy 436.666214 -408.428753)
			(xy 436.639185 -408.372627) (xy 436.619556 -408.313506) (xy 436.607647 -408.252359) (xy 436.603656 -408.190192)
			(xy 433.174801 -408.190192) (xy 433.174802 -408.222911) (xy 433.16602 -408.287755) (xy 433.148613 -408.350833)
			(xy 433.122897 -408.411005) (xy 433.106576 -408.439366) (xy 433.103272 -408.445396) (xy 433.09966 -408.458656)
			(xy 433.099464 -408.465528) (xy 433.099464 -409.214828) (xy 433.09965 -409.221702) (xy 433.103263 -409.234964)
			(xy 433.106576 -409.24099) (xy 433.122867 -409.269368) (xy 433.148587 -409.329536) (xy 433.165998 -409.392611)
			(xy 433.174785 -409.457452) (xy 433.174789 -409.522886) (xy 433.16601 -409.587729) (xy 433.148607 -409.650806)
			(xy 433.122895 -409.710977) (xy 433.106576 -409.739338) (xy 433.103246 -409.745355) (xy 433.09965 -409.758625)
			(xy 433.099464 -409.7655) (xy 433.099464 -410.051504) (xy 433.099081 -410.061663) (xy 433.091277 -410.080422)
			(xy 433.076868 -410.094747) (xy 433.058063 -410.10244) (xy 433.047902 -410.102812) (xy 432.331622 -410.102812)
			(xy 432.321503 -410.102257) (xy 432.302792 -410.094546) (xy 432.288437 -410.080281) (xy 432.280608 -410.06162)
			(xy 432.28006 -410.051504) (xy 432.28006 -409.7655) (xy 432.279873 -409.758626) (xy 432.276262 -409.745363)
			(xy 432.272948 -409.739338) (xy 432.256595 -409.710994) (xy 432.23088 -409.650819) (xy 432.213475 -409.587736)
			(xy 432.204695 -409.522889) (xy 430.915836 -409.522889) (xy 430.906428 -409.539186) (xy 430.90312 -409.545214)
			(xy 430.89951 -409.558475) (xy 430.899316 -409.565348) (xy 430.899316 -410.314648) (xy 430.899526 -410.32152)
			(xy 430.903122 -410.334783) (xy 430.906428 -410.34081) (xy 430.9228 -410.369156) (xy 430.9486 -410.429317)
			(xy 430.966087 -410.492397) (xy 430.974946 -410.557255) (xy 430.975516 -410.589984) (xy 430.974964 -410.622705)
			(xy 434.404861 -410.622705) (xy 434.404863 -410.557268) (xy 434.413648 -410.492423) (xy 434.431057 -410.429344)
			(xy 434.456774 -410.369172) (xy 434.473096 -410.34081) (xy 434.476407 -410.334783) (xy 434.480015 -410.321521)
			(xy 434.480208 -410.314648) (xy 434.480208 -409.565348) (xy 434.479996 -409.558476) (xy 434.476401 -409.545214)
			(xy 434.473096 -409.539186) (xy 434.456785 -409.510819) (xy 434.431069 -409.450648) (xy 434.413661 -409.387571)
			(xy 434.404877 -409.322728) (xy 434.404876 -409.257293) (xy 434.413657 -409.192449) (xy 434.431062 -409.129371)
			(xy 434.456776 -409.0692) (xy 434.473096 -409.040838) (xy 434.476397 -409.034807) (xy 434.480011 -409.021548)
			(xy 434.480208 -409.014676) (xy 434.480208 -408.728672) (xy 434.480599 -408.718515) (xy 434.488405 -408.69976)
			(xy 434.502811 -408.685438) (xy 434.521611 -408.67774) (xy 434.53177 -408.677364) (xy 435.24805 -408.677364)
			(xy 435.258176 -408.677868) (xy 435.276901 -408.685584) (xy 435.29126 -408.699866) (xy 435.299077 -408.718548)
			(xy 435.299612 -408.728672) (xy 435.299612 -409.014676) (xy 435.299812 -409.021549) (xy 435.303415 -409.034811)
			(xy 435.306724 -409.040838) (xy 435.323058 -409.069193) (xy 435.348776 -409.129365) (xy 435.366185 -409.192445)
			(xy 435.374967 -409.257291) (xy 435.374966 -409.322729) (xy 435.36618 -409.387575) (xy 435.348769 -409.450654)
			(xy 435.33188 -409.490164) (xy 436.603656 -409.490164) (xy 436.607647 -409.427997) (xy 436.619556 -409.36685)
			(xy 436.639185 -409.307729) (xy 436.666214 -409.251603) (xy 436.700198 -409.199394) (xy 436.74058 -409.151959)
			(xy 436.786696 -409.110078) (xy 436.837788 -409.074438) (xy 436.893019 -409.045624) (xy 436.951481 -409.02411)
			(xy 437.012215 -409.010248) (xy 437.074222 -409.004266) (xy 437.136485 -409.006262) (xy 437.197982 -409.016205)
			(xy 437.257703 -409.033929) (xy 437.314666 -409.059146) (xy 437.367937 -409.091439) (xy 437.416642 -409.130279)
			(xy 437.459979 -409.175029) (xy 437.497239 -409.224953) (xy 437.527808 -409.279232) (xy 437.532172 -409.290012)
			(xy 438.803804 -409.290012) (xy 438.807795 -409.227845) (xy 438.819704 -409.166698) (xy 438.839333 -409.107577)
			(xy 438.866362 -409.051451) (xy 438.900346 -408.999242) (xy 438.940728 -408.951807) (xy 438.986844 -408.909926)
			(xy 439.037936 -408.874286) (xy 439.093167 -408.845472) (xy 439.151629 -408.823958) (xy 439.212363 -408.810096)
			(xy 439.27437 -408.804114) (xy 439.336633 -408.80611) (xy 439.39813 -408.816053) (xy 439.457851 -408.833777)
			(xy 439.514814 -408.858994) (xy 439.568085 -408.891287) (xy 439.61679 -408.930127) (xy 439.660127 -408.974877)
			(xy 439.697387 -409.024801) (xy 439.727956 -409.07908) (xy 439.751334 -409.136823) (xy 439.767135 -409.197081)
			(xy 439.775101 -409.258864) (xy 439.7756 -409.290012) (xy 439.775101 -409.32116) (xy 439.767135 -409.382943)
			(xy 439.751334 -409.443201) (xy 439.727956 -409.500944) (xy 439.697387 -409.555223) (xy 439.660127 -409.605147)
			(xy 439.61679 -409.649897) (xy 439.568085 -409.688737) (xy 439.514814 -409.72103) (xy 439.457851 -409.746247)
			(xy 439.39813 -409.763971) (xy 439.336633 -409.773914) (xy 439.27437 -409.77591) (xy 439.212363 -409.769928)
			(xy 439.151629 -409.756066) (xy 439.093167 -409.734552) (xy 439.037936 -409.705738) (xy 438.986844 -409.670098)
			(xy 438.940728 -409.628217) (xy 438.900346 -409.580782) (xy 438.866362 -409.528573) (xy 438.839333 -409.472447)
			(xy 438.819704 -409.413326) (xy 438.807795 -409.352179) (xy 438.803804 -409.290012) (xy 437.532172 -409.290012)
			(xy 437.551186 -409.336975) (xy 437.566987 -409.397233) (xy 437.574953 -409.459016) (xy 437.575452 -409.490164)
			(xy 437.574953 -409.521312) (xy 437.566987 -409.583095) (xy 437.551186 -409.643353) (xy 437.527808 -409.701096)
			(xy 437.497239 -409.755375) (xy 437.459979 -409.805299) (xy 437.416642 -409.850049) (xy 437.367937 -409.888889)
			(xy 437.314666 -409.921182) (xy 437.257703 -409.946399) (xy 437.197982 -409.964123) (xy 437.136485 -409.974066)
			(xy 437.074222 -409.976062) (xy 437.012215 -409.97008) (xy 436.951481 -409.956218) (xy 436.893019 -409.934704)
			(xy 436.837788 -409.90589) (xy 436.786696 -409.87025) (xy 436.74058 -409.828369) (xy 436.700198 -409.780934)
			(xy 436.666214 -409.728725) (xy 436.639185 -409.672599) (xy 436.619556 -409.613478) (xy 436.607647 -409.552331)
			(xy 436.603656 -409.490164) (xy 435.33188 -409.490164) (xy 435.323048 -409.510825) (xy 435.306724 -409.539186)
			(xy 435.303416 -409.545214) (xy 435.299806 -409.558475) (xy 435.299612 -409.565348) (xy 435.299612 -410.314648)
			(xy 435.299822 -410.32152) (xy 435.303418 -410.334783) (xy 435.306724 -410.34081) (xy 435.323034 -410.369178)
			(xy 435.348755 -410.429347) (xy 435.366166 -410.492425) (xy 435.374952 -410.557268) (xy 435.374952 -410.589984)
			(xy 438.803804 -410.589984) (xy 438.807795 -410.527817) (xy 438.819704 -410.46667) (xy 438.839333 -410.407549)
			(xy 438.866362 -410.351423) (xy 438.900346 -410.299214) (xy 438.940728 -410.251779) (xy 438.986844 -410.209898)
			(xy 439.037936 -410.174258) (xy 439.093167 -410.145444) (xy 439.151629 -410.12393) (xy 439.212363 -410.110068)
			(xy 439.27437 -410.104086) (xy 439.336633 -410.106082) (xy 439.39813 -410.116025) (xy 439.457851 -410.133749)
			(xy 439.514814 -410.158966) (xy 439.568085 -410.191259) (xy 439.61679 -410.230099) (xy 439.660127 -410.274849)
			(xy 439.697387 -410.324773) (xy 439.727956 -410.379052) (xy 439.751334 -410.436795) (xy 439.767135 -410.497053)
			(xy 439.775101 -410.558836) (xy 439.7756 -410.589984) (xy 439.775101 -410.621132) (xy 439.767135 -410.682915)
			(xy 439.751334 -410.743173) (xy 439.727956 -410.800916) (xy 439.697387 -410.855195) (xy 439.660127 -410.905119)
			(xy 439.61679 -410.949869) (xy 439.568085 -410.988709) (xy 439.514814 -411.021002) (xy 439.457851 -411.046219)
			(xy 439.39813 -411.063943) (xy 439.336633 -411.073886) (xy 439.27437 -411.075882) (xy 439.212363 -411.0699)
			(xy 439.151629 -411.056038) (xy 439.093167 -411.034524) (xy 439.037936 -411.00571) (xy 438.986844 -410.97007)
			(xy 438.940728 -410.928189) (xy 438.900346 -410.880754) (xy 438.866362 -410.828545) (xy 438.839333 -410.772419)
			(xy 438.819704 -410.713298) (xy 438.807795 -410.652151) (xy 438.803804 -410.589984) (xy 435.374952 -410.589984)
			(xy 435.374953 -410.622704) (xy 435.366171 -410.687548) (xy 435.348764 -410.750627) (xy 435.323046 -410.810797)
			(xy 435.306724 -410.839158) (xy 435.303426 -410.845191) (xy 435.299809 -410.858448) (xy 435.299612 -410.86532)
			(xy 435.299612 -411.151324) (xy 435.299198 -411.161478) (xy 435.291397 -411.180229) (xy 435.276998 -411.194551)
			(xy 435.258206 -411.202252) (xy 435.24805 -411.202632) (xy 434.53177 -411.202632) (xy 434.521638 -411.202197)
			(xy 434.502911 -411.194454) (xy 434.488554 -411.180152) (xy 434.480741 -411.161454) (xy 434.480208 -411.151324)
			(xy 434.480208 -410.86532) (xy 434.480008 -410.858447) (xy 434.476405 -410.845185) (xy 434.473096 -410.839158)
			(xy 434.456762 -410.810804) (xy 434.431047 -410.75063) (xy 434.413642 -410.68755) (xy 434.404861 -410.622705)
			(xy 430.974964 -410.622705) (xy 430.974964 -410.622714) (xy 430.966104 -410.687573) (xy 430.948609 -410.750653)
			(xy 430.922798 -410.81081) (xy 430.906428 -410.839158) (xy 430.90313 -410.845191) (xy 430.899513 -410.858448)
			(xy 430.899316 -410.86532) (xy 430.899316 -411.151324) (xy 430.898835 -411.161432) (xy 430.891092 -411.180108)
			(xy 430.876795 -411.194401) (xy 430.858116 -411.202138) (xy 430.848008 -411.202632) (xy 430.131728 -411.202632)
			(xy 430.121611 -411.202162) (xy 430.102914 -411.194429) (xy 430.0886 -411.180129) (xy 430.080848 -411.16144)
			(xy 430.08042 -411.151324) (xy 430.08042 -410.86532) (xy 430.080218 -410.858448) (xy 430.076616 -410.845185)
			(xy 430.073308 -410.839158) (xy 430.056926 -410.810818) (xy 430.031128 -410.750655) (xy 430.013643 -410.687573)
			(xy 430.004788 -410.622714) (xy 430.00422 -410.589984) (xy 426.574866 -410.589984) (xy 426.574867 -410.622704)
			(xy 426.566085 -410.687548) (xy 426.548678 -410.750626) (xy 426.522962 -410.810797) (xy 426.50664 -410.839158)
			(xy 426.503343 -410.845192) (xy 426.499726 -410.858448) (xy 426.499528 -410.86532) (xy 426.499528 -411.151324)
			(xy 426.499099 -411.161476) (xy 426.4913 -411.180224) (xy 426.476907 -411.194545) (xy 426.45812 -411.202249)
			(xy 426.447966 -411.202632) (xy 425.731686 -411.202632) (xy 425.721555 -411.202184) (xy 425.702828 -411.194446)
			(xy 425.688472 -411.180148) (xy 425.680658 -411.161453) (xy 425.680124 -411.151324) (xy 425.680124 -410.86532)
			(xy 425.679921 -410.858448) (xy 425.67632 -410.845185) (xy 425.673012 -410.839158) (xy 425.656677 -410.810804)
			(xy 425.630962 -410.750631) (xy 425.613557 -410.687551) (xy 425.604775 -410.622705) (xy 422.174877 -410.622705)
			(xy 422.174877 -410.622714) (xy 422.166018 -410.687572) (xy 422.148524 -410.750652) (xy 422.122714 -410.81081)
			(xy 422.106344 -410.839158) (xy 422.103048 -410.845192) (xy 422.09943 -410.858448) (xy 422.099232 -410.86532)
			(xy 422.099232 -411.151324) (xy 422.098735 -411.16143) (xy 422.090996 -411.180103) (xy 422.076703 -411.194396)
			(xy 422.05803 -411.202135) (xy 422.047924 -411.202632) (xy 421.331644 -411.202632) (xy 421.321528 -411.202149)
			(xy 421.302832 -411.194421) (xy 421.288517 -411.180125) (xy 421.280765 -411.161439) (xy 421.280336 -411.151324)
			(xy 421.280336 -410.86532) (xy 421.280132 -410.858448) (xy 421.276531 -410.845185) (xy 421.273224 -410.839158)
			(xy 421.256844 -410.810817) (xy 421.231045 -410.750654) (xy 421.213559 -410.687572) (xy 421.204704 -410.622714)
			(xy 421.204136 -410.589984) (xy 414.52546 -410.589984) (xy 414.52546 -412.090108) (xy 419.003742 -412.090108)
			(xy 419.007733 -412.027941) (xy 419.019642 -411.966794) (xy 419.039271 -411.907673) (xy 419.0663 -411.851547)
			(xy 419.100284 -411.799338) (xy 419.140666 -411.751903) (xy 419.186782 -411.710022) (xy 419.237874 -411.674382)
			(xy 419.293105 -411.645568) (xy 419.351567 -411.624054) (xy 419.412301 -411.610192) (xy 419.474308 -411.60421)
			(xy 419.536571 -411.606206) (xy 419.598068 -411.616149) (xy 419.657789 -411.633873) (xy 419.714752 -411.65909)
			(xy 419.768023 -411.691383) (xy 419.816728 -411.730223) (xy 419.860065 -411.774973) (xy 419.897325 -411.824897)
			(xy 419.927894 -411.879176) (xy 419.951272 -411.936919) (xy 419.967073 -411.997177) (xy 419.975039 -412.05896)
			(xy 419.975538 -412.090108) (xy 423.403784 -412.090108) (xy 423.407775 -412.027941) (xy 423.419684 -411.966794)
			(xy 423.439313 -411.907673) (xy 423.466342 -411.851547) (xy 423.500326 -411.799338) (xy 423.540708 -411.751903)
			(xy 423.586824 -411.710022) (xy 423.637916 -411.674382) (xy 423.693147 -411.645568) (xy 423.751609 -411.624054)
			(xy 423.812343 -411.610192) (xy 423.87435 -411.60421) (xy 423.936613 -411.606206) (xy 423.99811 -411.616149)
			(xy 424.057831 -411.633873) (xy 424.114794 -411.65909) (xy 424.168065 -411.691383) (xy 424.21677 -411.730223)
			(xy 424.260107 -411.774973) (xy 424.297367 -411.824897) (xy 424.327936 -411.879176) (xy 424.351314 -411.936919)
			(xy 424.367115 -411.997177) (xy 424.375081 -412.05896) (xy 424.37558 -412.090108) (xy 427.803826 -412.090108)
			(xy 427.807817 -412.027941) (xy 427.819726 -411.966794) (xy 427.839355 -411.907673) (xy 427.866384 -411.851547)
			(xy 427.900368 -411.799338) (xy 427.94075 -411.751903) (xy 427.986866 -411.710022) (xy 428.037958 -411.674382)
			(xy 428.093189 -411.645568) (xy 428.151651 -411.624054) (xy 428.212385 -411.610192) (xy 428.274392 -411.60421)
			(xy 428.336655 -411.606206) (xy 428.398152 -411.616149) (xy 428.457873 -411.633873) (xy 428.514836 -411.65909)
			(xy 428.568107 -411.691383) (xy 428.616812 -411.730223) (xy 428.660149 -411.774973) (xy 428.697409 -411.824897)
			(xy 428.727978 -411.879176) (xy 428.751356 -411.936919) (xy 428.767157 -411.997177) (xy 428.775123 -412.05896)
			(xy 428.775622 -412.090108) (xy 432.203614 -412.090108) (xy 432.207605 -412.027941) (xy 432.219514 -411.966794)
			(xy 432.239143 -411.907673) (xy 432.266172 -411.851547) (xy 432.300156 -411.799338) (xy 432.340538 -411.751903)
			(xy 432.386654 -411.710022) (xy 432.437746 -411.674382) (xy 432.492977 -411.645568) (xy 432.551439 -411.624054)
			(xy 432.612173 -411.610192) (xy 432.67418 -411.60421) (xy 432.736443 -411.606206) (xy 432.79794 -411.616149)
			(xy 432.857661 -411.633873) (xy 432.914624 -411.65909) (xy 432.967895 -411.691383) (xy 433.0166 -411.730223)
			(xy 433.059937 -411.774973) (xy 433.097197 -411.824897) (xy 433.127766 -411.879176) (xy 433.151144 -411.936919)
			(xy 433.166945 -411.997177) (xy 433.174911 -412.05896) (xy 433.17541 -412.090108) (xy 436.603656 -412.090108)
			(xy 436.607647 -412.027941) (xy 436.619556 -411.966794) (xy 436.639185 -411.907673) (xy 436.666214 -411.851547)
			(xy 436.700198 -411.799338) (xy 436.74058 -411.751903) (xy 436.786696 -411.710022) (xy 436.837788 -411.674382)
			(xy 436.893019 -411.645568) (xy 436.951481 -411.624054) (xy 437.012215 -411.610192) (xy 437.074222 -411.60421)
			(xy 437.136485 -411.606206) (xy 437.197982 -411.616149) (xy 437.257703 -411.633873) (xy 437.314666 -411.65909)
			(xy 437.367937 -411.691383) (xy 437.416642 -411.730223) (xy 437.459979 -411.774973) (xy 437.497239 -411.824897)
			(xy 437.527808 -411.879176) (xy 437.536286 -411.900116) (xy 444.291972 -411.900116) (xy 444.296043 -411.844494)
			(xy 444.308169 -411.790057) (xy 444.328092 -411.737966) (xy 444.355388 -411.689331) (xy 444.389474 -411.645188)
			(xy 444.429623 -411.606479) (xy 444.474981 -411.574028) (xy 444.524581 -411.548527) (xy 444.577365 -411.53052)
			(xy 444.632208 -411.52039) (xy 444.687942 -411.518353) (xy 444.743379 -411.524453) (xy 444.797336 -411.538559)
			(xy 444.848665 -411.560371) (xy 444.896271 -411.589425) (xy 444.939139 -411.6251) (xy 444.976356 -411.666637)
			(xy 445.007129 -411.71315) (xy 445.030801 -411.763647) (xy 445.046869 -411.817054) (xy 445.054989 -411.87223)
			(xy 445.055498 -411.900116) (xy 445.054989 -411.928002) (xy 445.046869 -411.983178) (xy 445.030801 -412.036585)
			(xy 445.007129 -412.087082) (xy 444.976356 -412.133595) (xy 444.939139 -412.175132) (xy 444.896271 -412.210807)
			(xy 444.848665 -412.239861) (xy 444.797336 -412.261673) (xy 444.743379 -412.275779) (xy 444.687942 -412.281879)
			(xy 444.632208 -412.279842) (xy 444.577365 -412.269712) (xy 444.524581 -412.251705) (xy 444.474981 -412.226204)
			(xy 444.429623 -412.193753) (xy 444.389474 -412.155044) (xy 444.355388 -412.110901) (xy 444.328092 -412.062266)
			(xy 444.308169 -412.010175) (xy 444.296043 -411.955738) (xy 444.291972 -411.900116) (xy 437.536286 -411.900116)
			(xy 437.551186 -411.936919) (xy 437.566987 -411.997177) (xy 437.574953 -412.05896) (xy 437.575452 -412.090108)
			(xy 437.574953 -412.121256) (xy 437.566987 -412.183039) (xy 437.551186 -412.243297) (xy 437.527808 -412.30104)
			(xy 437.497239 -412.355319) (xy 437.459979 -412.405243) (xy 437.416642 -412.449993) (xy 437.367937 -412.488833)
			(xy 437.314666 -412.521126) (xy 437.257703 -412.546343) (xy 437.197982 -412.564067) (xy 437.136485 -412.57401)
			(xy 437.074222 -412.576006) (xy 437.012215 -412.570024) (xy 436.951481 -412.556162) (xy 436.893019 -412.534648)
			(xy 436.837788 -412.505834) (xy 436.786696 -412.470194) (xy 436.74058 -412.428313) (xy 436.700198 -412.380878)
			(xy 436.666214 -412.328669) (xy 436.639185 -412.272543) (xy 436.619556 -412.213422) (xy 436.607647 -412.152275)
			(xy 436.603656 -412.090108) (xy 433.17541 -412.090108) (xy 433.174911 -412.121256) (xy 433.166945 -412.183039)
			(xy 433.151144 -412.243297) (xy 433.127766 -412.30104) (xy 433.097197 -412.355319) (xy 433.059937 -412.405243)
			(xy 433.0166 -412.449993) (xy 432.967895 -412.488833) (xy 432.914624 -412.521126) (xy 432.857661 -412.546343)
			(xy 432.79794 -412.564067) (xy 432.736443 -412.57401) (xy 432.67418 -412.576006) (xy 432.612173 -412.570024)
			(xy 432.551439 -412.556162) (xy 432.492977 -412.534648) (xy 432.437746 -412.505834) (xy 432.386654 -412.470194)
			(xy 432.340538 -412.428313) (xy 432.300156 -412.380878) (xy 432.266172 -412.328669) (xy 432.239143 -412.272543)
			(xy 432.219514 -412.213422) (xy 432.207605 -412.152275) (xy 432.203614 -412.090108) (xy 428.775622 -412.090108)
			(xy 428.775123 -412.121256) (xy 428.767157 -412.183039) (xy 428.751356 -412.243297) (xy 428.727978 -412.30104)
			(xy 428.697409 -412.355319) (xy 428.660149 -412.405243) (xy 428.616812 -412.449993) (xy 428.568107 -412.488833)
			(xy 428.514836 -412.521126) (xy 428.457873 -412.546343) (xy 428.398152 -412.564067) (xy 428.336655 -412.57401)
			(xy 428.274392 -412.576006) (xy 428.212385 -412.570024) (xy 428.151651 -412.556162) (xy 428.093189 -412.534648)
			(xy 428.037958 -412.505834) (xy 427.986866 -412.470194) (xy 427.94075 -412.428313) (xy 427.900368 -412.380878)
			(xy 427.866384 -412.328669) (xy 427.839355 -412.272543) (xy 427.819726 -412.213422) (xy 427.807817 -412.152275)
			(xy 427.803826 -412.090108) (xy 424.37558 -412.090108) (xy 424.375081 -412.121256) (xy 424.367115 -412.183039)
			(xy 424.351314 -412.243297) (xy 424.327936 -412.30104) (xy 424.297367 -412.355319) (xy 424.260107 -412.405243)
			(xy 424.21677 -412.449993) (xy 424.168065 -412.488833) (xy 424.114794 -412.521126) (xy 424.057831 -412.546343)
			(xy 423.99811 -412.564067) (xy 423.936613 -412.57401) (xy 423.87435 -412.576006) (xy 423.812343 -412.570024)
			(xy 423.751609 -412.556162) (xy 423.693147 -412.534648) (xy 423.637916 -412.505834) (xy 423.586824 -412.470194)
			(xy 423.540708 -412.428313) (xy 423.500326 -412.380878) (xy 423.466342 -412.328669) (xy 423.439313 -412.272543)
			(xy 423.419684 -412.213422) (xy 423.407775 -412.152275) (xy 423.403784 -412.090108) (xy 419.975538 -412.090108)
			(xy 419.975039 -412.121256) (xy 419.967073 -412.183039) (xy 419.951272 -412.243297) (xy 419.927894 -412.30104)
			(xy 419.897325 -412.355319) (xy 419.860065 -412.405243) (xy 419.816728 -412.449993) (xy 419.768023 -412.488833)
			(xy 419.714752 -412.521126) (xy 419.657789 -412.546343) (xy 419.598068 -412.564067) (xy 419.536571 -412.57401)
			(xy 419.474308 -412.576006) (xy 419.412301 -412.570024) (xy 419.351567 -412.556162) (xy 419.293105 -412.534648)
			(xy 419.237874 -412.505834) (xy 419.186782 -412.470194) (xy 419.140666 -412.428313) (xy 419.100284 -412.380878)
			(xy 419.0663 -412.328669) (xy 419.039271 -412.272543) (xy 419.019642 -412.213422) (xy 419.007733 -412.152275)
			(xy 419.003742 -412.090108) (xy 414.52546 -412.090108) (xy 414.52546 -414.403794) (xy 447.176396 -414.403794)
			(xy 447.180467 -414.348172) (xy 447.192593 -414.293735) (xy 447.212516 -414.241644) (xy 447.239812 -414.193009)
			(xy 447.273898 -414.148866) (xy 447.314047 -414.110157) (xy 447.359405 -414.077706) (xy 447.409005 -414.052205)
			(xy 447.461789 -414.034198) (xy 447.516632 -414.024068) (xy 447.572366 -414.022031) (xy 447.627803 -414.028131)
			(xy 447.68176 -414.042237) (xy 447.733089 -414.064049) (xy 447.780695 -414.093103) (xy 447.823563 -414.128778)
			(xy 447.86078 -414.170315) (xy 447.891553 -414.216828) (xy 447.915225 -414.267325) (xy 447.931293 -414.320732)
			(xy 447.939413 -414.375908) (xy 447.939922 -414.403794) (xy 447.939413 -414.43168) (xy 447.931293 -414.486856)
			(xy 447.915225 -414.540263) (xy 447.891801 -414.59023) (xy 448.79717 -414.59023) (xy 448.801241 -414.534608)
			(xy 448.813367 -414.480171) (xy 448.83329 -414.42808) (xy 448.860586 -414.379445) (xy 448.894672 -414.335302)
			(xy 448.934821 -414.296593) (xy 448.980179 -414.264142) (xy 449.029779 -414.238641) (xy 449.082563 -414.220634)
			(xy 449.137406 -414.210504) (xy 449.19314 -414.208467) (xy 449.248577 -414.214567) (xy 449.302534 -414.228673)
			(xy 449.353863 -414.250485) (xy 449.401469 -414.279539) (xy 449.444337 -414.315214) (xy 449.461574 -414.334452)
			(xy 450.168262 -414.334452) (xy 450.172333 -414.27883) (xy 450.184459 -414.224393) (xy 450.204382 -414.172302)
			(xy 450.231678 -414.123667) (xy 450.265764 -414.079524) (xy 450.305913 -414.040815) (xy 450.351271 -414.008364)
			(xy 450.400871 -413.982863) (xy 450.453655 -413.964856) (xy 450.508498 -413.954726) (xy 450.564232 -413.952689)
			(xy 450.619669 -413.958789) (xy 450.673626 -413.972895) (xy 450.724955 -413.994707) (xy 450.772561 -414.023761)
			(xy 450.815429 -414.059436) (xy 450.852646 -414.100973) (xy 450.883419 -414.147486) (xy 450.907091 -414.197983)
			(xy 450.923159 -414.25139) (xy 450.931279 -414.306566) (xy 450.931788 -414.334452) (xy 450.931279 -414.362338)
			(xy 450.923159 -414.417514) (xy 450.907091 -414.470921) (xy 450.883419 -414.521418) (xy 450.852646 -414.567931)
			(xy 450.815429 -414.609468) (xy 450.772561 -414.645143) (xy 450.724955 -414.674197) (xy 450.673626 -414.696009)
			(xy 450.619669 -414.710115) (xy 450.564232 -414.716215) (xy 450.508498 -414.714178) (xy 450.453655 -414.704048)
			(xy 450.400871 -414.686041) (xy 450.351271 -414.66054) (xy 450.305913 -414.628089) (xy 450.265764 -414.58938)
			(xy 450.231678 -414.545237) (xy 450.204382 -414.496602) (xy 450.184459 -414.444511) (xy 450.172333 -414.390074)
			(xy 450.168262 -414.334452) (xy 449.461574 -414.334452) (xy 449.481554 -414.356751) (xy 449.512327 -414.403264)
			(xy 449.535999 -414.453761) (xy 449.552067 -414.507168) (xy 449.560187 -414.562344) (xy 449.560696 -414.59023)
			(xy 449.560187 -414.618116) (xy 449.552067 -414.673292) (xy 449.535999 -414.726699) (xy 449.512327 -414.777196)
			(xy 449.481554 -414.823709) (xy 449.444337 -414.865246) (xy 449.401469 -414.900921) (xy 449.353863 -414.929975)
			(xy 449.302534 -414.951787) (xy 449.248577 -414.965893) (xy 449.19314 -414.971993) (xy 449.137406 -414.969956)
			(xy 449.082563 -414.959826) (xy 449.029779 -414.941819) (xy 448.980179 -414.916318) (xy 448.934821 -414.883867)
			(xy 448.894672 -414.845158) (xy 448.860586 -414.801015) (xy 448.83329 -414.75238) (xy 448.813367 -414.700289)
			(xy 448.801241 -414.645852) (xy 448.79717 -414.59023) (xy 447.891801 -414.59023) (xy 447.891553 -414.59076)
			(xy 447.86078 -414.637273) (xy 447.823563 -414.67881) (xy 447.780695 -414.714485) (xy 447.733089 -414.743539)
			(xy 447.68176 -414.765351) (xy 447.627803 -414.779457) (xy 447.572366 -414.785557) (xy 447.516632 -414.78352)
			(xy 447.461789 -414.77339) (xy 447.409005 -414.755383) (xy 447.359405 -414.729882) (xy 447.314047 -414.697431)
			(xy 447.273898 -414.658722) (xy 447.239812 -414.614579) (xy 447.212516 -414.565944) (xy 447.192593 -414.513853)
			(xy 447.180467 -414.459416) (xy 447.176396 -414.403794) (xy 414.52546 -414.403794) (xy 414.52546 -415.342578)
			(xy 414.525944 -415.352592) (xy 414.533598 -415.371098) (xy 414.54775 -415.385267) (xy 414.566247 -415.392944)
			(xy 414.57626 -415.393378) (xy 463.660998 -415.393378) (xy 463.669126 -415.392616) (xy 463.669634 -415.392616)
			(xy 463.677153 -415.391015) (xy 463.690842 -415.38404) (xy 463.696558 -415.3789) (xy 466.018372 -413.057086)
			(xy 466.023575 -413.051339) (xy 466.030563 -413.037508) (xy 466.032088 -413.029908) (xy 466.03285 -413.021526)
			(xy 466.03285 -326.257158) (xy 466.032755 -326.25228) (xy 466.030968 -326.24269) (xy 466.029294 -326.238108)
			(xy 466.025484 -326.228964) (xy 462.81213 -323.01561) (xy 462.808402 -323.012084) (xy 462.799832 -323.006446)
			(xy 462.795112 -323.004434) (xy 462.786476 -323.000878) (xy 449.302632 -323.000878) (xy 449.292568 -323.000442)
			(xy 449.273983 -322.992708) (xy 449.266564 -322.985892) (xy 446.684654 -320.403982) (xy 446.677804 -320.396585)
			(xy 446.670068 -320.377987) (xy 446.669668 -320.367914) (xy 446.669668 -313.619388) (xy 446.669576 -313.61451)
			(xy 446.667794 -313.604918) (xy 446.666112 -313.600338) (xy 446.662302 -313.591194) (xy 444.268606 -311.197498)
			(xy 444.264877 -311.193975) (xy 444.256304 -311.188341) (xy 444.251588 -311.186322) (xy 444.242952 -311.182766)
			(xy 439.714386 -311.182766) (xy 439.708597 -311.182894) (xy 439.69731 -311.18546) (xy 439.692034 -311.187846)
			(xy 439.681874 -311.192926) (xy 439.678572 -311.197244) (xy 439.674508 -311.202578) (xy 439.661554 -311.219342)
			(xy 439.624724 -311.267094) (xy 439.623708 -311.268618) (xy 439.631652 -311.291) (xy 439.642829 -311.337161)
			(xy 439.648489 -311.384317) (xy 439.648854 -311.408064) (xy 439.648597 -311.428983) (xy 439.644271 -311.470597)
			(xy 439.640218 -311.491122) (xy 439.638743 -311.499448) (xy 439.640771 -311.516225) (xy 439.648169 -311.531419)
			(xy 439.653934 -311.537604) (xy 439.696098 -311.579768) (xy 439.704359 -311.587292) (xy 439.72532 -311.594946)
			(xy 439.736484 -311.5945) (xy 439.74131 -311.593992) (xy 439.743088 -311.593738) (xy 439.759525 -311.591005)
			(xy 439.79272 -311.588081) (xy 439.809382 -311.587896) (xy 439.811922 -311.587896) (xy 439.839055 -311.588553)
			(xy 439.89273 -311.5966) (xy 439.944723 -311.612172) (xy 439.993983 -311.634956) (xy 440.039518 -311.664491)
			(xy 440.080407 -311.700181) (xy 440.115826 -311.741306) (xy 440.145059 -311.787035) (xy 440.167516 -311.836446)
			(xy 440.182744 -311.88854) (xy 440.190435 -311.942267) (xy 440.19089 -311.969404) (xy 440.190404 -311.996655)
			(xy 440.182648 -312.050603) (xy 440.167293 -312.102898) (xy 440.144651 -312.152475) (xy 440.115185 -312.198325)
			(xy 440.079494 -312.239516) (xy 440.038303 -312.275207) (xy 439.992453 -312.304673) (xy 439.942876 -312.327315)
			(xy 439.890581 -312.34267) (xy 439.836633 -312.350426) (xy 439.782131 -312.350426) (xy 439.728183 -312.34267)
			(xy 439.675888 -312.327315) (xy 439.626311 -312.304673) (xy 439.580461 -312.275207) (xy 439.53927 -312.239516)
			(xy 439.503579 -312.198325) (xy 439.474113 -312.152475) (xy 439.451471 -312.102898) (xy 439.436116 -312.050603)
			(xy 439.42836 -311.996655) (xy 439.427874 -311.969404) (xy 439.428056 -311.952355) (xy 439.43111 -311.918394)
			(xy 439.43397 -311.901586) (xy 439.436256 -311.88914) (xy 439.4327 -311.877456) (xy 439.430693 -311.871619)
			(xy 439.424279 -311.861076) (xy 439.42 -311.856628) (xy 439.361072 -311.7977) (xy 439.356754 -311.79389)
			(xy 439.330071 -311.800979) (xy 439.275392 -311.808622) (xy 439.247788 -311.80913) (xy 439.219139 -311.808642)
			(xy 439.162426 -311.800486) (xy 439.107451 -311.784342) (xy 439.055332 -311.760537) (xy 439.007133 -311.729557)
			(xy 438.963833 -311.692033) (xy 438.926314 -311.648729) (xy 438.89534 -311.600525) (xy 438.871542 -311.548404)
			(xy 438.855404 -311.493427) (xy 438.847254 -311.436713) (xy 438.846722 -311.408064) (xy 438.846722 -311.407302)
			(xy 438.847522 -311.371869) (xy 438.86004 -311.302116) (xy 438.871614 -311.268618) (xy 438.869836 -311.266332)
			(xy 438.855104 -311.246774) (xy 438.854596 -311.246266) (xy 438.819798 -311.201054) (xy 438.812242 -311.192845)
			(xy 438.792078 -311.18336) (xy 438.780936 -311.182766) (xy 431.544984 -311.182766) (xy 431.540158 -311.18302)
			(xy 431.528255 -311.184898) (xy 431.507999 -311.197895) (xy 431.501296 -311.207912) (xy 431.50028 -311.20969)
			(xy 431.473864 -311.268364) (xy 431.472134 -311.272872) (xy 431.470212 -311.282334) (xy 431.470054 -311.28716)
			(xy 431.470054 -311.333642) (xy 431.470377 -311.341922) (xy 431.475695 -311.357603) (xy 431.480468 -311.364376)
			(xy 431.48631 -311.371996) (xy 431.489612 -311.376314) (xy 431.492914 -311.38114) (xy 431.509916 -311.40572)
			(xy 431.535708 -311.459629) (xy 431.55142 -311.517288) (xy 431.554636 -311.547002) (xy 431.555398 -311.556146)
			(xy 431.555906 -311.574942) (xy 431.555394 -311.600936) (xy 431.54726 -311.652283) (xy 431.531199 -311.701727)
			(xy 431.507606 -311.748052) (xy 431.47706 -311.790119) (xy 431.440314 -311.826894) (xy 431.398271 -311.857472)
			(xy 431.351964 -311.881101) (xy 431.302532 -311.8972) (xy 431.251191 -311.905374) (xy 431.225198 -311.905904)
			(xy 431.17643 -311.905904) (xy 431.165708 -311.906328) (xy 431.146111 -311.915019) (xy 431.138584 -311.922668)
			(xy 431.088292 -311.978294) (xy 431.081567 -311.986558) (xy 431.074882 -312.006764) (xy 431.075338 -312.01741)
			(xy 431.075338 -312.017664) (xy 431.077116 -312.049668) (xy 431.077116 -312.050176) (xy 431.076593 -312.075871)
			(xy 431.068518 -312.126623) (xy 431.052608 -312.175488) (xy 431.029252 -312.221264) (xy 430.999026 -312.262825)
			(xy 430.962674 -312.29915) (xy 430.921089 -312.329343) (xy 430.875295 -312.352663) (xy 430.826417 -312.368536)
			(xy 430.775659 -312.376571) (xy 430.724269 -312.376571) (xy 430.673511 -312.368536) (xy 430.624633 -312.352663)
			(xy 430.578839 -312.329343) (xy 430.537254 -312.29915) (xy 430.500902 -312.262825) (xy 430.470676 -312.221264)
			(xy 430.44732 -312.175488) (xy 430.43141 -312.126623) (xy 430.423335 -312.075871) (xy 430.422812 -312.050176)
			(xy 430.422812 -312.049668) (xy 430.42459 -312.017664) (xy 430.42459 -312.01741) (xy 430.425193 -312.006748)
			(xy 430.418472 -311.986499) (xy 430.411636 -311.978294) (xy 430.361344 -311.922668) (xy 430.353752 -311.915111)
			(xy 430.334196 -311.906427) (xy 430.323498 -311.905904) (xy 430.274984 -311.905904) (xy 430.26563 -311.90586)
			(xy 430.24695 -311.904841) (xy 430.237646 -311.903872) (xy 430.226216 -311.902602) (xy 430.204372 -311.909968)
			(xy 430.131728 -311.982358) (xy 430.123854 -312.003948) (xy 430.125124 -312.015378) (xy 430.127156 -312.049668)
			(xy 430.127156 -312.050176) (xy 430.126631 -312.075851) (xy 430.118559 -312.126562) (xy 430.102655 -312.175387)
			(xy 430.079312 -312.221125) (xy 430.049104 -312.262649) (xy 430.012774 -312.298939) (xy 429.971216 -312.329101)
			(xy 429.925453 -312.352394) (xy 429.87661 -312.368243) (xy 429.82589 -312.37626) (xy 429.77454 -312.376247)
			(xy 429.723824 -312.368203) (xy 429.674989 -312.352328) (xy 429.629238 -312.329012) (xy 429.587696 -312.298828)
			(xy 429.551385 -312.262519) (xy 429.521199 -312.220979) (xy 429.497879 -312.175229) (xy 429.482001 -312.126396)
			(xy 429.473955 -312.07568) (xy 429.473939 -312.02433) (xy 429.481952 -311.973609) (xy 429.497799 -311.924766)
			(xy 429.521088 -311.879001) (xy 429.551248 -311.837441) (xy 429.587536 -311.801109) (xy 429.629058 -311.770898)
			(xy 429.674794 -311.747553) (xy 429.723619 -311.731646) (xy 429.77433 -311.72357) (xy 429.800004 -311.723024)
			(xy 429.800766 -311.723024) (xy 429.824877 -311.723497) (xy 429.872569 -311.730642) (xy 429.895762 -311.737248)
			(xy 429.906222 -311.739973) (xy 429.927657 -311.737339) (xy 429.946125 -311.726144) (xy 429.958375 -311.708359)
			(xy 429.962253 -311.687114) (xy 429.960024 -311.676542) (xy 429.958754 -311.672478) (xy 429.958754 -311.67197)
			(xy 429.951983 -311.648287) (xy 429.944718 -311.59957) (xy 429.944276 -311.574942) (xy 429.944276 -311.574434)
			(xy 429.946054 -311.540398) (xy 429.947324 -311.528968) (xy 429.939704 -311.507378) (xy 429.867314 -311.435242)
			(xy 429.845724 -311.427622) (xy 429.834548 -311.428892) (xy 429.800512 -311.43067) (xy 429.800004 -311.43067)
			(xy 429.774916 -311.430205) (xy 429.725315 -311.422628) (xy 429.677428 -311.407645) (xy 429.632354 -311.385602)
			(xy 429.591125 -311.357004) (xy 429.55469 -311.322506) (xy 429.523882 -311.282902) (xy 429.499409 -311.239098)
			(xy 429.490124 -311.215786) (xy 429.484536 -311.2008) (xy 429.458628 -311.182766) (xy 429.191166 -311.182766)
			(xy 429.165258 -311.2008) (xy 429.15967 -311.215786) (xy 429.150431 -311.239114) (xy 429.125933 -311.282899)
			(xy 429.095108 -311.322486) (xy 429.058662 -311.356968) (xy 429.01743 -311.385554) (xy 428.972356 -311.407592)
			(xy 428.924472 -311.422574) (xy 428.874876 -311.430159) (xy 428.84979 -311.43067) (xy 428.817278 -311.429146)
			(xy 428.80661 -311.42813) (xy 428.78629 -311.434734) (xy 428.722536 -311.492392) (xy 428.714988 -311.499988)
			(xy 428.706324 -311.519544) (xy 428.705772 -311.530238) (xy 428.705772 -311.574688) (xy 428.705289 -311.600698)
			(xy 428.697154 -311.652078) (xy 428.68108 -311.701553) (xy 428.657465 -311.747904) (xy 428.62689 -311.78999)
			(xy 428.590107 -311.826775) (xy 428.548023 -311.857354) (xy 428.501673 -311.880972) (xy 428.4522 -311.897048)
			(xy 428.40082 -311.905188) (xy 428.37481 -311.90565) (xy 428.365456 -311.905607) (xy 428.346776 -311.90459)
			(xy 428.337472 -311.903618) (xy 428.326042 -311.902348) (xy 428.304198 -311.909714) (xy 428.239682 -311.973976)
			(xy 428.232057 -311.982405) (xy 428.224397 -312.003772) (xy 428.22495 -312.015124) (xy 428.22495 -312.015378)
			(xy 428.226728 -312.049922) (xy 428.226249 -312.075614) (xy 428.218207 -312.126366) (xy 428.202325 -312.175234)
			(xy 428.178994 -312.221017) (xy 428.148787 -312.262586) (xy 428.11245 -312.298918) (xy 428.070877 -312.329118)
			(xy 428.025091 -312.352443) (xy 427.97622 -312.368318) (xy 427.925468 -312.376352) (xy 427.874083 -312.376349)
			(xy 427.823332 -312.368306) (xy 427.774463 -312.352424) (xy 427.728681 -312.329092) (xy 427.687112 -312.298886)
			(xy 427.65078 -312.262548) (xy 427.620581 -312.220975) (xy 427.597256 -312.175189) (xy 427.581381 -312.126318)
			(xy 427.573347 -312.075565) (xy 427.573352 -312.02418) (xy 427.581394 -311.973429) (xy 427.597277 -311.924561)
			(xy 427.620609 -311.878778) (xy 427.650816 -311.83721) (xy 427.687154 -311.800879) (xy 427.728727 -311.770679)
			(xy 427.774514 -311.747355) (xy 427.823385 -311.731481) (xy 427.874138 -311.723447) (xy 427.89983 -311.723024)
			(xy 427.934374 -311.724802) (xy 427.945804 -311.726072) (xy 427.967394 -311.718198) (xy 428.039784 -311.645554)
			(xy 428.04715 -311.62371) (xy 428.04588 -311.61228) (xy 428.044908 -311.602913) (xy 428.043894 -311.584105)
			(xy 428.043848 -311.574688) (xy 428.043848 -311.526428) (xy 428.043423 -311.515707) (xy 428.034725 -311.496116)
			(xy 428.027084 -311.488582) (xy 427.971458 -311.43829) (xy 427.963192 -311.431573) (xy 427.942987 -311.424907)
			(xy 427.932342 -311.425336) (xy 427.932088 -311.425336) (xy 427.89983 -311.42686) (xy 427.875108 -311.426401)
			(xy 427.826229 -311.418946) (xy 427.77903 -311.404216) (xy 427.734587 -311.382547) (xy 427.693914 -311.354433)
			(xy 427.657937 -311.320516) (xy 427.627477 -311.281568) (xy 427.603229 -311.238478) (xy 427.594014 -311.215532)
			(xy 427.588426 -311.200546) (xy 427.562518 -311.182766) (xy 427.291246 -311.182766) (xy 427.265338 -311.2008)
			(xy 427.25975 -311.215786) (xy 427.250512 -311.239117) (xy 427.226016 -311.282909) (xy 427.195193 -311.322503)
			(xy 427.158749 -311.356994) (xy 427.117517 -311.38559) (xy 427.072443 -311.407638) (xy 427.024558 -311.422631)
			(xy 426.974959 -311.430228) (xy 426.94987 -311.43067) (xy 426.917358 -311.429146) (xy 426.90669 -311.42813)
			(xy 426.88637 -311.434734) (xy 426.822616 -311.492392) (xy 426.815071 -311.49999) (xy 426.80641 -311.519545)
			(xy 426.805852 -311.530238) (xy 426.805852 -311.574688) (xy 426.805369 -311.600698) (xy 426.797233 -311.652076)
			(xy 426.78116 -311.70155) (xy 426.757544 -311.7479) (xy 426.726969 -311.789984) (xy 426.690186 -311.826767)
			(xy 426.648101 -311.857343) (xy 426.601752 -311.880959) (xy 426.552278 -311.897033) (xy 426.5009 -311.905169)
			(xy 426.47489 -311.90565) (xy 426.465536 -311.905606) (xy 426.446856 -311.904588) (xy 426.437552 -311.903618)
			(xy 426.426122 -311.902348) (xy 426.404278 -311.909714) (xy 426.339762 -311.973976) (xy 426.332139 -311.982406)
			(xy 426.324482 -312.003773) (xy 426.32503 -312.015124) (xy 426.32503 -312.015378) (xy 426.326808 -312.049922)
			(xy 426.326302 -312.07561) (xy 426.318262 -312.126354) (xy 426.302383 -312.175215) (xy 426.279055 -312.220991)
			(xy 426.248854 -312.262553) (xy 426.212523 -312.29888) (xy 426.170957 -312.329076) (xy 426.125178 -312.352398)
			(xy 426.076315 -312.368271) (xy 426.02557 -312.376306) (xy 425.974194 -312.376303) (xy 425.92345 -312.368263)
			(xy 425.874589 -312.352384) (xy 425.828813 -312.329057) (xy 425.78725 -312.298857) (xy 425.750923 -312.262526)
			(xy 425.720726 -312.22096) (xy 425.697404 -312.175182) (xy 425.68153 -312.126319) (xy 425.673495 -312.075574)
			(xy 425.673497 -312.024198) (xy 425.681536 -311.973454) (xy 425.697414 -311.924592) (xy 425.720741 -311.878816)
			(xy 425.750941 -311.837253) (xy 425.787271 -311.800925) (xy 425.828837 -311.770728) (xy 425.874614 -311.747405)
			(xy 425.923477 -311.73153) (xy 425.974222 -311.723495) (xy 425.99991 -311.723024) (xy 426.034454 -311.724802)
			(xy 426.045884 -311.726072) (xy 426.067474 -311.718198) (xy 426.139864 -311.645554) (xy 426.14723 -311.62371)
			(xy 426.14596 -311.61228) (xy 426.144988 -311.602913) (xy 426.143974 -311.584105) (xy 426.143928 -311.574688)
			(xy 426.143928 -311.526428) (xy 426.143505 -311.515705) (xy 426.134817 -311.496105) (xy 426.127164 -311.488582)
			(xy 426.071538 -311.43829) (xy 426.063275 -311.431559) (xy 426.043068 -311.424862) (xy 426.032422 -311.425336)
			(xy 426.032168 -311.425336) (xy 425.99991 -311.42686) (xy 425.975185 -311.426407) (xy 425.926298 -311.418962)
			(xy 425.87909 -311.404239) (xy 425.834637 -311.382576) (xy 425.793953 -311.354465) (xy 425.757967 -311.320549)
			(xy 425.727498 -311.2816) (xy 425.703242 -311.238507) (xy 425.694094 -311.215532) (xy 425.688506 -311.200546)
			(xy 425.662598 -311.182766) (xy 425.391326 -311.182766) (xy 425.365418 -311.2008) (xy 425.35983 -311.215786)
			(xy 425.350592 -311.239116) (xy 425.326096 -311.282906) (xy 425.295272 -311.322499) (xy 425.258827 -311.356987)
			(xy 425.217595 -311.385581) (xy 425.172521 -311.407626) (xy 425.124636 -311.422617) (xy 425.075038 -311.430211)
			(xy 425.04995 -311.43067) (xy 425.017438 -311.429146) (xy 425.00677 -311.42813) (xy 424.98645 -311.434734)
			(xy 424.922696 -311.492392) (xy 424.915153 -311.499991) (xy 424.906496 -311.519546) (xy 424.905932 -311.530238)
			(xy 424.905932 -311.574688) (xy 424.905449 -311.600697) (xy 424.897313 -311.652075) (xy 424.881239 -311.701547)
			(xy 424.857624 -311.747895) (xy 424.827048 -311.789978) (xy 424.790264 -311.826759) (xy 424.74818 -311.857333)
			(xy 424.70183 -311.880946) (xy 424.652357 -311.897017) (xy 424.600979 -311.905151) (xy 424.57497 -311.90565)
			(xy 424.565616 -311.905609) (xy 424.546935 -311.904595) (xy 424.537632 -311.903618) (xy 424.526202 -311.902348)
			(xy 424.504358 -311.909714) (xy 424.439842 -311.973976) (xy 424.432209 -311.982402) (xy 424.42454 -312.003771)
			(xy 424.42511 -312.015124) (xy 424.42511 -312.015378) (xy 424.426888 -312.049922) (xy 424.426383 -312.075608)
			(xy 424.418343 -312.126348) (xy 424.402465 -312.175206) (xy 424.379139 -312.220978) (xy 424.348941 -312.262538)
			(xy 424.312613 -312.298862) (xy 424.27105 -312.329057) (xy 424.225275 -312.352378) (xy 424.176416 -312.368251)
			(xy 424.125675 -312.376285) (xy 424.074302 -312.376283) (xy 424.023562 -312.368245) (xy 423.974704 -312.352369)
			(xy 423.928931 -312.329045) (xy 423.88737 -312.298848) (xy 423.851044 -312.262521) (xy 423.820849 -312.220959)
			(xy 423.797527 -312.175185) (xy 423.781652 -312.126326) (xy 423.773616 -312.075586) (xy 423.773616 -312.024213)
			(xy 423.781652 -311.973472) (xy 423.797527 -311.924614) (xy 423.82085 -311.87884) (xy 423.851045 -311.837278)
			(xy 423.887371 -311.800951) (xy 423.928932 -311.770754) (xy 423.974705 -311.747431) (xy 424.023563 -311.731554)
			(xy 424.074304 -311.723516) (xy 424.09999 -311.723024) (xy 424.134534 -311.724802) (xy 424.145964 -311.726072)
			(xy 424.167554 -311.718198) (xy 424.239944 -311.645554) (xy 424.24731 -311.62371) (xy 424.24604 -311.61228)
			(xy 424.245068 -311.602913) (xy 424.244055 -311.584105) (xy 424.244008 -311.574688) (xy 424.244008 -311.526428)
			(xy 424.243585 -311.515706) (xy 424.234894 -311.496108) (xy 424.227244 -311.488582) (xy 424.171618 -311.43829)
			(xy 424.163354 -311.431563) (xy 424.143148 -311.424873) (xy 424.132502 -311.425336) (xy 424.132248 -311.425336)
			(xy 424.09999 -311.42686) (xy 424.075266 -311.426405) (xy 424.026381 -311.418958) (xy 423.979175 -311.404233)
			(xy 423.934724 -311.382569) (xy 423.894043 -311.354457) (xy 423.858059 -311.320541) (xy 423.827593 -311.281592)
			(xy 423.803339 -311.2385) (xy 423.794174 -311.215532) (xy 423.788586 -311.200546) (xy 423.762678 -311.182766)
			(xy 423.491406 -311.182766) (xy 423.465498 -311.2008) (xy 423.45991 -311.215786) (xy 423.450672 -311.239115)
			(xy 423.426175 -311.282904) (xy 423.395351 -311.322495) (xy 423.358905 -311.356981) (xy 423.317673 -311.385572)
			(xy 423.272599 -311.407615) (xy 423.224715 -311.422603) (xy 423.175117 -311.430194) (xy 423.15003 -311.43067)
			(xy 423.117518 -311.429146) (xy 423.10685 -311.42813) (xy 423.08653 -311.434734) (xy 423.022776 -311.492392)
			(xy 423.015224 -311.499986) (xy 423.006552 -311.519542) (xy 423.006012 -311.530238) (xy 423.006012 -311.574688)
			(xy 423.005551 -311.599442) (xy 422.998174 -311.648398) (xy 422.983584 -311.695708) (xy 422.962107 -311.740315)
			(xy 422.934221 -311.781223) (xy 422.90055 -311.817519) (xy 422.861846 -311.848391) (xy 422.840658 -311.8612)
			(xy 422.824358 -311.870313) (xy 422.790113 -311.88521) (xy 422.772332 -311.890918) (xy 422.748588 -311.897708)
			(xy 422.699743 -311.904983) (xy 422.67505 -311.905396) (xy 422.655695 -311.905148) (xy 422.617242 -311.900688)
			(xy 422.598342 -311.896506) (xy 422.598088 -311.896506) (xy 422.58488 -311.89295) (xy 422.584626 -311.89295)
			(xy 422.583864 -311.892696) (xy 422.576244 -311.89041) (xy 422.561004 -311.888124) (xy 422.550984 -311.888543)
			(xy 422.53247 -311.896214) (xy 422.518302 -311.910387) (xy 422.51064 -311.928904) (xy 422.510204 -311.938924)
			(xy 422.511982 -311.950354) (xy 422.513506 -311.957212) (xy 422.519795 -311.979872) (xy 422.526547 -312.026409)
			(xy 422.526968 -312.049922) (xy 422.526524 -312.074578) (xy 422.519124 -312.12333) (xy 422.504481 -312.170416)
			(xy 422.482927 -312.214767) (xy 422.454952 -312.255374) (xy 422.421191 -312.291316) (xy 422.382412 -312.321774)
			(xy 422.339496 -312.346059) (xy 422.293417 -312.363617) (xy 422.245222 -312.37405) (xy 422.220644 -312.376058)
			(xy 422.211447 -312.377048) (xy 422.194639 -312.384732) (xy 422.187878 -312.391044) (xy 422.166288 -312.412634)
			(xy 422.159517 -312.420061) (xy 422.151937 -312.438658) (xy 422.151556 -312.448702) (xy 422.151556 -312.570876)
			(xy 422.151726 -312.577029) (xy 422.154683 -312.588974) (xy 422.157398 -312.594498) (xy 422.171368 -312.617866)
			(xy 422.174749 -312.623146) (xy 422.183619 -312.632002) (xy 422.188894 -312.635392) (xy 422.199308 -312.641488)
			(xy 422.200324 -312.641742) (xy 422.24325 -312.66765) (xy 422.247408 -312.670256) (xy 422.25649 -312.673969)
			(xy 422.261284 -312.675016) (xy 422.285537 -312.680021) (xy 422.332297 -312.696324) (xy 422.3761 -312.719424)
			(xy 422.415964 -312.748804) (xy 422.450997 -312.783804) (xy 422.480413 -312.823641) (xy 422.503553 -312.867422)
			(xy 422.5199 -312.914167) (xy 422.524936 -312.938414) (xy 422.525968 -312.943123) (xy 422.529551 -312.952071)
			(xy 422.532048 -312.956194) (xy 422.540503 -312.969612) (xy 422.556635 -312.996923) (xy 422.564306 -313.010804)
			(xy 422.576083 -313.032409) (xy 422.597684 -313.076627) (xy 422.607486 -313.099196) (xy 422.610534 -313.106054)
			(xy 422.614852 -313.111388) (xy 422.617299 -313.114286) (xy 422.622915 -313.119381) (xy 422.626028 -313.121548)
			(xy 422.647364 -313.135772) (xy 422.650448 -313.137777) (xy 422.657081 -313.140962) (xy 422.660572 -313.142122)
			(xy 422.66743 -313.144154) (xy 422.667938 -313.144154) (xy 422.679071 -313.144009) (xy 422.701315 -313.145027)
			(xy 422.712388 -313.146186) (xy 422.723818 -313.147456) (xy 422.745662 -313.14009) (xy 422.818306 -313.0677)
			(xy 422.82618 -313.04611) (xy 422.82491 -313.03468) (xy 422.823132 -312.999882) (xy 422.823637 -312.974197)
			(xy 422.831676 -312.923461) (xy 422.847552 -312.874607) (xy 422.870875 -312.828837) (xy 422.90107 -312.78728)
			(xy 422.937395 -312.750957) (xy 422.978954 -312.720764) (xy 423.024725 -312.697444) (xy 423.07358 -312.681571)
			(xy 423.124317 -312.673535) (xy 423.175687 -312.673536) (xy 423.226423 -312.681572) (xy 423.275279 -312.697446)
			(xy 423.321049 -312.720766) (xy 423.362608 -312.75096) (xy 423.398932 -312.787283) (xy 423.429127 -312.828841)
			(xy 423.45245 -312.87461) (xy 423.468325 -312.923465) (xy 423.476363 -312.974201) (xy 423.476365 -313.025571)
			(xy 423.476362 -313.02559) (xy 424.723302 -313.02559) (xy 424.723302 -312.974174) (xy 424.731345 -312.923392)
			(xy 424.747233 -312.874493) (xy 424.770576 -312.828681) (xy 424.800797 -312.787085) (xy 424.837153 -312.750729)
			(xy 424.878749 -312.720508) (xy 424.924561 -312.697165) (xy 424.97346 -312.681277) (xy 425.024242 -312.673234)
			(xy 425.075658 -312.673234) (xy 425.12644 -312.681277) (xy 425.175339 -312.697165) (xy 425.221151 -312.720508)
			(xy 425.262747 -312.750729) (xy 425.299103 -312.787085) (xy 425.329324 -312.828681) (xy 425.352667 -312.874493)
			(xy 425.368555 -312.923392) (xy 425.376598 -312.974174) (xy 425.377102 -312.999882) (xy 425.376598 -313.02559)
			(xy 426.623222 -313.02559) (xy 426.623222 -312.974174) (xy 426.631265 -312.923392) (xy 426.647153 -312.874493)
			(xy 426.670496 -312.828681) (xy 426.700717 -312.787085) (xy 426.737073 -312.750729) (xy 426.778669 -312.720508)
			(xy 426.824481 -312.697165) (xy 426.87338 -312.681277) (xy 426.924162 -312.673234) (xy 426.975578 -312.673234)
			(xy 427.02636 -312.681277) (xy 427.075259 -312.697165) (xy 427.121071 -312.720508) (xy 427.162667 -312.750729)
			(xy 427.199023 -312.787085) (xy 427.229244 -312.828681) (xy 427.252587 -312.874493) (xy 427.268475 -312.923392)
			(xy 427.276518 -312.974174) (xy 427.277022 -312.999882) (xy 427.276518 -313.02559) (xy 428.523142 -313.02559)
			(xy 428.523142 -312.974174) (xy 428.531185 -312.923392) (xy 428.547073 -312.874493) (xy 428.570416 -312.828681)
			(xy 428.600637 -312.787085) (xy 428.636993 -312.750729) (xy 428.678589 -312.720508) (xy 428.724401 -312.697165)
			(xy 428.7733 -312.681277) (xy 428.824082 -312.673234) (xy 428.875498 -312.673234) (xy 428.92628 -312.681277)
			(xy 428.975179 -312.697165) (xy 429.020991 -312.720508) (xy 429.062587 -312.750729) (xy 429.098943 -312.787085)
			(xy 429.129164 -312.828681) (xy 429.152507 -312.874493) (xy 429.153014 -312.876052) (xy 434.16853 -312.876052)
			(xy 434.16853 -312.821548) (xy 434.176286 -312.767597) (xy 434.19164 -312.7153) (xy 434.214281 -312.66572)
			(xy 434.243746 -312.619866) (xy 434.279437 -312.578672) (xy 434.320626 -312.542976) (xy 434.366476 -312.513505)
			(xy 434.416053 -312.490858) (xy 434.468349 -312.475497) (xy 434.522298 -312.467733) (xy 434.54955 -312.467244)
			(xy 434.561584 -312.467349) (xy 434.585605 -312.468874) (xy 434.597556 -312.470292) (xy 434.611702 -312.471595)
			(xy 434.639763 -312.467237) (xy 434.665541 -312.455327) (xy 434.687048 -312.436783) (xy 434.702622 -312.413038)
			(xy 434.711061 -312.385924) (xy 434.711856 -312.37174) (xy 434.712819 -312.344857) (xy 434.721495 -312.291768)
			(xy 434.73754 -312.240423) (xy 434.760634 -312.191838) (xy 434.790321 -312.146978) (xy 434.826013 -312.106731)
			(xy 434.867002 -312.071893) (xy 434.912477 -312.043156) (xy 434.961536 -312.021088) (xy 435.013207 -312.006127)
			(xy 435.066467 -311.998569) (xy 435.093364 -311.998106) (xy 435.12062 -311.998538) (xy 435.174576 -312.006292)
			(xy 435.226881 -312.021645) (xy 435.276467 -312.044286) (xy 435.322326 -312.073754) (xy 435.363525 -312.109449)
			(xy 435.399224 -312.150645) (xy 435.428696 -312.196501) (xy 435.451342 -312.246086) (xy 435.466701 -312.298388)
			(xy 435.474459 -312.352344) (xy 435.474459 -312.406856) (xy 435.466701 -312.460812) (xy 435.451342 -312.513114)
			(xy 435.428696 -312.562699) (xy 435.399224 -312.608555) (xy 435.363525 -312.649751) (xy 435.322326 -312.685446)
			(xy 435.276467 -312.714914) (xy 435.226881 -312.737555) (xy 435.174576 -312.752908) (xy 435.12062 -312.760662)
			(xy 435.093364 -312.761122) (xy 435.08133 -312.761016) (xy 435.057309 -312.759492) (xy 435.045358 -312.758074)
			(xy 435.031213 -312.756721) (xy 435.003142 -312.761078) (xy 434.977355 -312.772995) (xy 434.955845 -312.791549)
			(xy 434.940274 -312.815309) (xy 434.931845 -312.842437) (xy 434.931058 -312.856626) (xy 434.93005 -312.883506)
			(xy 434.921379 -312.936593) (xy 434.90534 -312.987937) (xy 434.88225 -313.036521) (xy 434.852568 -313.08138)
			(xy 434.816881 -313.121628) (xy 434.775896 -313.156466) (xy 434.730425 -313.185205) (xy 434.68137 -313.207274)
			(xy 434.629702 -313.222237) (xy 434.576445 -313.229796) (xy 434.54955 -313.23026) (xy 434.522298 -313.229867)
			(xy 434.468349 -313.222103) (xy 434.416053 -313.206742) (xy 434.366476 -313.184095) (xy 434.320626 -313.154624)
			(xy 434.279437 -313.118928) (xy 434.243746 -313.077734) (xy 434.214281 -313.03188) (xy 434.19164 -312.9823)
			(xy 434.176286 -312.930003) (xy 434.16853 -312.876052) (xy 429.153014 -312.876052) (xy 429.168395 -312.923392)
			(xy 429.176438 -312.974174) (xy 429.176942 -312.999882) (xy 429.176438 -313.02559) (xy 429.168395 -313.076372)
			(xy 429.152507 -313.125271) (xy 429.129164 -313.171083) (xy 429.098943 -313.212679) (xy 429.062587 -313.249035)
			(xy 429.020991 -313.279256) (xy 428.975179 -313.302599) (xy 428.92628 -313.318487) (xy 428.875498 -313.32653)
			(xy 428.824082 -313.32653) (xy 428.7733 -313.318487) (xy 428.724401 -313.302599) (xy 428.678589 -313.279256)
			(xy 428.636993 -313.249035) (xy 428.600637 -313.212679) (xy 428.570416 -313.171083) (xy 428.547073 -313.125271)
			(xy 428.531185 -313.076372) (xy 428.523142 -313.02559) (xy 427.276518 -313.02559) (xy 427.268475 -313.076372)
			(xy 427.252587 -313.125271) (xy 427.229244 -313.171083) (xy 427.199023 -313.212679) (xy 427.162667 -313.249035)
			(xy 427.121071 -313.279256) (xy 427.075259 -313.302599) (xy 427.02636 -313.318487) (xy 426.975578 -313.32653)
			(xy 426.924162 -313.32653) (xy 426.87338 -313.318487) (xy 426.824481 -313.302599) (xy 426.778669 -313.279256)
			(xy 426.737073 -313.249035) (xy 426.700717 -313.212679) (xy 426.670496 -313.171083) (xy 426.647153 -313.125271)
			(xy 426.631265 -313.076372) (xy 426.623222 -313.02559) (xy 425.376598 -313.02559) (xy 425.368555 -313.076372)
			(xy 425.352667 -313.125271) (xy 425.329324 -313.171083) (xy 425.299103 -313.212679) (xy 425.262747 -313.249035)
			(xy 425.221151 -313.279256) (xy 425.175339 -313.302599) (xy 425.12644 -313.318487) (xy 425.075658 -313.32653)
			(xy 425.024242 -313.32653) (xy 424.97346 -313.318487) (xy 424.924561 -313.302599) (xy 424.878749 -313.279256)
			(xy 424.837153 -313.249035) (xy 424.800797 -313.212679) (xy 424.770576 -313.171083) (xy 424.747233 -313.125271)
			(xy 424.731345 -313.076372) (xy 424.723302 -313.02559) (xy 423.476362 -313.02559) (xy 423.468332 -313.076308)
			(xy 423.452461 -313.125164) (xy 423.429142 -313.170935) (xy 423.398951 -313.212496) (xy 423.362629 -313.248822)
			(xy 423.321073 -313.279019) (xy 423.275304 -313.302344) (xy 423.226451 -313.318222) (xy 423.175715 -313.326262)
			(xy 423.15003 -313.32678) (xy 423.115232 -313.325002) (xy 423.114978 -313.325002) (xy 423.103628 -313.324476)
			(xy 423.082261 -313.332118) (xy 423.07383 -313.339734) (xy 423.009568 -313.40425) (xy 423.002202 -313.426094)
			(xy 423.003472 -313.437524) (xy 423.00444 -313.446828) (xy 423.005457 -313.465508) (xy 423.005504 -313.474862)
			(xy 423.005462 -313.484216) (xy 423.004448 -313.502897) (xy 423.003472 -313.5122) (xy 423.002202 -313.52363)
			(xy 423.009568 -313.545474) (xy 423.07383 -313.60999) (xy 423.08226 -313.617609) (xy 423.103627 -313.625251)
			(xy 423.114978 -313.624722) (xy 423.115232 -313.624722) (xy 423.15003 -313.622944) (xy 423.175713 -313.62345)
			(xy 423.226446 -313.631489) (xy 423.275297 -313.647366) (xy 423.321063 -313.670689) (xy 423.362617 -313.700883)
			(xy 423.398936 -313.737206) (xy 423.429127 -313.778763) (xy 423.452445 -313.824531) (xy 423.468318 -313.873383)
			(xy 423.476352 -313.924117) (xy 423.476352 -313.975483) (xy 423.476341 -313.97555) (xy 424.723302 -313.97555)
			(xy 424.723302 -313.924134) (xy 424.731345 -313.873352) (xy 424.747233 -313.824453) (xy 424.770576 -313.778641)
			(xy 424.800797 -313.737045) (xy 424.837153 -313.700689) (xy 424.878749 -313.670468) (xy 424.924561 -313.647125)
			(xy 424.97346 -313.631237) (xy 425.024242 -313.623194) (xy 425.075658 -313.623194) (xy 425.12644 -313.631237)
			(xy 425.175339 -313.647125) (xy 425.221151 -313.670468) (xy 425.262747 -313.700689) (xy 425.299103 -313.737045)
			(xy 425.329324 -313.778641) (xy 425.352667 -313.824453) (xy 425.368555 -313.873352) (xy 425.376598 -313.924134)
			(xy 425.377102 -313.949842) (xy 425.376598 -313.97555) (xy 426.623222 -313.97555) (xy 426.623222 -313.924134)
			(xy 426.631265 -313.873352) (xy 426.647153 -313.824453) (xy 426.670496 -313.778641) (xy 426.700717 -313.737045)
			(xy 426.737073 -313.700689) (xy 426.778669 -313.670468) (xy 426.824481 -313.647125) (xy 426.87338 -313.631237)
			(xy 426.924162 -313.623194) (xy 426.975578 -313.623194) (xy 427.02636 -313.631237) (xy 427.075259 -313.647125)
			(xy 427.121071 -313.670468) (xy 427.162667 -313.700689) (xy 427.199023 -313.737045) (xy 427.229244 -313.778641)
			(xy 427.252587 -313.824453) (xy 427.268475 -313.873352) (xy 427.276518 -313.924134) (xy 427.277022 -313.949842)
			(xy 427.276518 -313.97555) (xy 428.523142 -313.97555) (xy 428.523142 -313.924134) (xy 428.531185 -313.873352)
			(xy 428.547073 -313.824453) (xy 428.570416 -313.778641) (xy 428.600637 -313.737045) (xy 428.636993 -313.700689)
			(xy 428.678589 -313.670468) (xy 428.724401 -313.647125) (xy 428.7733 -313.631237) (xy 428.824082 -313.623194)
			(xy 428.875498 -313.623194) (xy 428.92628 -313.631237) (xy 428.975179 -313.647125) (xy 429.020991 -313.670468)
			(xy 429.062587 -313.700689) (xy 429.098943 -313.737045) (xy 429.129164 -313.778641) (xy 429.152507 -313.824453)
			(xy 429.168395 -313.873352) (xy 429.176438 -313.924134) (xy 429.176942 -313.949842) (xy 429.176438 -313.97555)
			(xy 429.168395 -314.026332) (xy 429.152507 -314.075231) (xy 429.129164 -314.121043) (xy 429.098943 -314.162639)
			(xy 429.062587 -314.198995) (xy 429.020991 -314.229216) (xy 428.975179 -314.252559) (xy 428.92628 -314.268447)
			(xy 428.875498 -314.27649) (xy 428.824082 -314.27649) (xy 428.7733 -314.268447) (xy 428.724401 -314.252559)
			(xy 428.678589 -314.229216) (xy 428.636993 -314.198995) (xy 428.600637 -314.162639) (xy 428.570416 -314.121043)
			(xy 428.547073 -314.075231) (xy 428.531185 -314.026332) (xy 428.523142 -313.97555) (xy 427.276518 -313.97555)
			(xy 427.268475 -314.026332) (xy 427.252587 -314.075231) (xy 427.229244 -314.121043) (xy 427.199023 -314.162639)
			(xy 427.162667 -314.198995) (xy 427.121071 -314.229216) (xy 427.075259 -314.252559) (xy 427.02636 -314.268447)
			(xy 426.975578 -314.27649) (xy 426.924162 -314.27649) (xy 426.87338 -314.268447) (xy 426.824481 -314.252559)
			(xy 426.778669 -314.229216) (xy 426.737073 -314.198995) (xy 426.700717 -314.162639) (xy 426.670496 -314.121043)
			(xy 426.647153 -314.075231) (xy 426.631265 -314.026332) (xy 426.623222 -313.97555) (xy 425.376598 -313.97555)
			(xy 425.368555 -314.026332) (xy 425.352667 -314.075231) (xy 425.329324 -314.121043) (xy 425.299103 -314.162639)
			(xy 425.262747 -314.198995) (xy 425.221151 -314.229216) (xy 425.175339 -314.252559) (xy 425.12644 -314.268447)
			(xy 425.075658 -314.27649) (xy 425.024242 -314.27649) (xy 424.97346 -314.268447) (xy 424.924561 -314.252559)
			(xy 424.878749 -314.229216) (xy 424.837153 -314.198995) (xy 424.800797 -314.162639) (xy 424.770576 -314.121043)
			(xy 424.747233 -314.075231) (xy 424.731345 -314.026332) (xy 424.723302 -313.97555) (xy 423.476341 -313.97555)
			(xy 423.468318 -314.026217) (xy 423.452445 -314.075069) (xy 423.429127 -314.120837) (xy 423.398936 -314.162394)
			(xy 423.362617 -314.198717) (xy 423.321063 -314.228911) (xy 423.275297 -314.252234) (xy 423.226446 -314.268111)
			(xy 423.175713 -314.27615) (xy 423.15003 -314.27674) (xy 423.115232 -314.274962) (xy 423.114978 -314.274962)
			(xy 423.103627 -314.274435) (xy 423.082257 -314.282073) (xy 423.07383 -314.289694) (xy 423.009568 -314.35421)
			(xy 423.002202 -314.376054) (xy 423.003472 -314.387484) (xy 423.004442 -314.396788) (xy 423.00546 -314.415468)
			(xy 423.005504 -314.424822) (xy 423.004995 -314.450783) (xy 422.996877 -314.502065) (xy 422.980845 -314.551449)
			(xy 422.957292 -314.597721) (xy 422.926798 -314.639744) (xy 422.890111 -314.676484) (xy 422.848133 -314.70704)
			(xy 422.801895 -314.73066) (xy 422.752535 -314.746764) (xy 422.701264 -314.754957) (xy 422.675304 -314.75553)
			(xy 422.66743 -314.75553) (xy 422.660572 -314.757562) (xy 422.657009 -314.758777) (xy 422.650253 -314.762094)
			(xy 422.64711 -314.764166) (xy 422.625774 -314.77839) (xy 422.622883 -314.7804) (xy 422.617652 -314.785115)
			(xy 422.61536 -314.787788) (xy 422.610534 -314.79363) (xy 422.607486 -314.800488) (xy 422.595703 -314.827531)
			(xy 422.569267 -314.880273) (xy 422.554654 -314.905898) (xy 422.542728 -314.92551) (xy 429.473356 -314.92551)
			(xy 429.473356 -314.874094) (xy 429.481399 -314.823312) (xy 429.497287 -314.774413) (xy 429.52063 -314.728601)
			(xy 429.550851 -314.687005) (xy 429.587207 -314.650649) (xy 429.628803 -314.620428) (xy 429.674615 -314.597085)
			(xy 429.723514 -314.581197) (xy 429.774296 -314.573154) (xy 429.825712 -314.573154) (xy 429.876494 -314.581197)
			(xy 429.925393 -314.597085) (xy 429.971205 -314.620428) (xy 430.012801 -314.650649) (xy 430.049157 -314.687005)
			(xy 430.079378 -314.728601) (xy 430.102721 -314.774413) (xy 430.118609 -314.823312) (xy 430.126652 -314.874094)
			(xy 430.127156 -314.899802) (xy 430.126652 -314.92551) (xy 430.423316 -314.92551) (xy 430.423316 -314.874094)
			(xy 430.431359 -314.823312) (xy 430.447247 -314.774413) (xy 430.47059 -314.728601) (xy 430.500811 -314.687005)
			(xy 430.537167 -314.650649) (xy 430.578763 -314.620428) (xy 430.624575 -314.597085) (xy 430.673474 -314.581197)
			(xy 430.724256 -314.573154) (xy 430.775672 -314.573154) (xy 430.826454 -314.581197) (xy 430.875353 -314.597085)
			(xy 430.921165 -314.620428) (xy 430.962761 -314.650649) (xy 430.999117 -314.687005) (xy 431.029338 -314.728601)
			(xy 431.052681 -314.774413) (xy 431.068569 -314.823312) (xy 431.076612 -314.874094) (xy 431.077116 -314.899802)
			(xy 431.076612 -314.92551) (xy 431.068569 -314.976292) (xy 431.052681 -315.025191) (xy 431.029338 -315.071003)
			(xy 430.999117 -315.112599) (xy 430.962761 -315.148955) (xy 430.921165 -315.179176) (xy 430.875353 -315.202519)
			(xy 430.826454 -315.218407) (xy 430.775672 -315.22645) (xy 430.724256 -315.22645) (xy 430.673474 -315.218407)
			(xy 430.624575 -315.202519) (xy 430.578763 -315.179176) (xy 430.537167 -315.148955) (xy 430.500811 -315.112599)
			(xy 430.47059 -315.071003) (xy 430.447247 -315.025191) (xy 430.431359 -314.976292) (xy 430.423316 -314.92551)
			(xy 430.126652 -314.92551) (xy 430.118609 -314.976292) (xy 430.102721 -315.025191) (xy 430.079378 -315.071003)
			(xy 430.049157 -315.112599) (xy 430.012801 -315.148955) (xy 429.971205 -315.179176) (xy 429.925393 -315.202519)
			(xy 429.876494 -315.218407) (xy 429.825712 -315.22645) (xy 429.774296 -315.22645) (xy 429.723514 -315.218407)
			(xy 429.674615 -315.202519) (xy 429.628803 -315.179176) (xy 429.587207 -315.148955) (xy 429.550851 -315.112599)
			(xy 429.52063 -315.071003) (xy 429.497287 -315.025191) (xy 429.481399 -314.976292) (xy 429.473356 -314.92551)
			(xy 422.542728 -314.92551) (xy 422.531794 -314.94349) (xy 422.529347 -314.947618) (xy 422.52589 -314.956568)
			(xy 422.524936 -314.96127) (xy 422.519481 -314.987301) (xy 422.501374 -315.037305) (xy 422.47549 -315.083762)
			(xy 422.442498 -315.125473) (xy 422.403251 -315.16136) (xy 422.358761 -315.190496) (xy 422.33469 -315.201808)
			(xy 422.3259 -315.206187) (xy 422.312255 -315.220285) (xy 422.30491 -315.238479) (xy 422.304464 -315.24829)
			(xy 422.304464 -315.505592) (xy 422.30494 -315.515258) (xy 422.312197 -315.533182) (xy 422.32557 -315.547149)
			(xy 422.334182 -315.551566) (xy 422.334436 -315.55182) (xy 422.358622 -315.563324) (xy 422.403194 -315.593014)
			(xy 422.442332 -315.62957) (xy 422.474991 -315.672014) (xy 422.500298 -315.719212) (xy 422.517577 -315.769903)
			(xy 422.526367 -315.822731) (xy 422.526968 -315.849508) (xy 422.526968 -315.850016) (xy 422.525448 -315.87547)
			(xy 423.773342 -315.87547) (xy 423.773342 -315.824054) (xy 423.781385 -315.773272) (xy 423.797273 -315.724373)
			(xy 423.820616 -315.678561) (xy 423.850837 -315.636965) (xy 423.887193 -315.600609) (xy 423.928789 -315.570388)
			(xy 423.974601 -315.547045) (xy 424.0235 -315.531157) (xy 424.074282 -315.523114) (xy 424.125698 -315.523114)
			(xy 424.17648 -315.531157) (xy 424.225379 -315.547045) (xy 424.271191 -315.570388) (xy 424.312787 -315.600609)
			(xy 424.349143 -315.636965) (xy 424.379364 -315.678561) (xy 424.402707 -315.724373) (xy 424.418595 -315.773272)
			(xy 424.426638 -315.824054) (xy 424.427142 -315.849762) (xy 424.426638 -315.87547) (xy 425.673262 -315.87547)
			(xy 425.673262 -315.824054) (xy 425.681305 -315.773272) (xy 425.697193 -315.724373) (xy 425.720536 -315.678561)
			(xy 425.750757 -315.636965) (xy 425.787113 -315.600609) (xy 425.828709 -315.570388) (xy 425.874521 -315.547045)
			(xy 425.92342 -315.531157) (xy 425.974202 -315.523114) (xy 426.025618 -315.523114) (xy 426.0764 -315.531157)
			(xy 426.125299 -315.547045) (xy 426.171111 -315.570388) (xy 426.212707 -315.600609) (xy 426.249063 -315.636965)
			(xy 426.279284 -315.678561) (xy 426.302627 -315.724373) (xy 426.318515 -315.773272) (xy 426.326558 -315.824054)
			(xy 426.327062 -315.849762) (xy 426.326558 -315.87547) (xy 427.573182 -315.87547) (xy 427.573182 -315.824054)
			(xy 427.581225 -315.773272) (xy 427.597113 -315.724373) (xy 427.620456 -315.678561) (xy 427.650677 -315.636965)
			(xy 427.687033 -315.600609) (xy 427.728629 -315.570388) (xy 427.774441 -315.547045) (xy 427.82334 -315.531157)
			(xy 427.874122 -315.523114) (xy 427.925538 -315.523114) (xy 427.97632 -315.531157) (xy 428.025219 -315.547045)
			(xy 428.071031 -315.570388) (xy 428.112627 -315.600609) (xy 428.148983 -315.636965) (xy 428.179204 -315.678561)
			(xy 428.202547 -315.724373) (xy 428.218435 -315.773272) (xy 428.226478 -315.824054) (xy 428.226982 -315.849762)
			(xy 428.226478 -315.87547) (xy 428.218435 -315.926252) (xy 428.202547 -315.975151) (xy 428.179204 -316.020963)
			(xy 428.148983 -316.062559) (xy 428.112627 -316.098915) (xy 428.071031 -316.129136) (xy 428.025219 -316.152479)
			(xy 427.97632 -316.168367) (xy 427.925538 -316.17641) (xy 427.874122 -316.17641) (xy 427.82334 -316.168367)
			(xy 427.774441 -316.152479) (xy 427.728629 -316.129136) (xy 427.687033 -316.098915) (xy 427.650677 -316.062559)
			(xy 427.620456 -316.020963) (xy 427.597113 -315.975151) (xy 427.581225 -315.926252) (xy 427.573182 -315.87547)
			(xy 426.326558 -315.87547) (xy 426.318515 -315.926252) (xy 426.302627 -315.975151) (xy 426.279284 -316.020963)
			(xy 426.249063 -316.062559) (xy 426.212707 -316.098915) (xy 426.171111 -316.129136) (xy 426.125299 -316.152479)
			(xy 426.0764 -316.168367) (xy 426.025618 -316.17641) (xy 425.974202 -316.17641) (xy 425.92342 -316.168367)
			(xy 425.874521 -316.152479) (xy 425.828709 -316.129136) (xy 425.787113 -316.098915) (xy 425.750757 -316.062559)
			(xy 425.720536 -316.020963) (xy 425.697193 -315.975151) (xy 425.681305 -315.926252) (xy 425.673262 -315.87547)
			(xy 424.426638 -315.87547) (xy 424.418595 -315.926252) (xy 424.402707 -315.975151) (xy 424.379364 -316.020963)
			(xy 424.349143 -316.062559) (xy 424.312787 -316.098915) (xy 424.271191 -316.129136) (xy 424.225379 -316.152479)
			(xy 424.17648 -316.168367) (xy 424.125698 -316.17641) (xy 424.074282 -316.17641) (xy 424.0235 -316.168367)
			(xy 423.974601 -316.152479) (xy 423.928789 -316.129136) (xy 423.887193 -316.098915) (xy 423.850837 -316.062559)
			(xy 423.820616 -316.020963) (xy 423.797273 -315.975151) (xy 423.781385 -315.926252) (xy 423.773342 -315.87547)
			(xy 422.525448 -315.87547) (xy 422.524936 -315.884052) (xy 422.524936 -315.88456) (xy 422.523666 -315.895736)
			(xy 422.53154 -315.917326) (xy 422.596056 -315.981334) (xy 422.604579 -315.988901) (xy 422.626073 -315.996393)
			(xy 422.637458 -315.995812) (xy 422.637712 -315.995812) (xy 422.647016 -315.994845) (xy 422.665696 -315.99383)
			(xy 422.67505 -315.99378) (xy 422.701053 -315.994294) (xy 422.752419 -316.002437) (xy 422.801878 -316.018516)
			(xy 422.848213 -316.042133) (xy 422.890283 -316.072708) (xy 422.927052 -316.109487) (xy 422.957615 -316.151566)
			(xy 422.98122 -316.197907) (xy 422.997284 -316.247371) (xy 423.005413 -316.298739) (xy 423.006012 -316.324742)
			(xy 423.006012 -316.82543) (xy 423.773342 -316.82543) (xy 423.773342 -316.774014) (xy 423.781385 -316.723232)
			(xy 423.797273 -316.674333) (xy 423.820616 -316.628521) (xy 423.850837 -316.586925) (xy 423.887193 -316.550569)
			(xy 423.928789 -316.520348) (xy 423.974601 -316.497005) (xy 424.0235 -316.481117) (xy 424.074282 -316.473074)
			(xy 424.125698 -316.473074) (xy 424.17648 -316.481117) (xy 424.225379 -316.497005) (xy 424.271191 -316.520348)
			(xy 424.312787 -316.550569) (xy 424.349143 -316.586925) (xy 424.379364 -316.628521) (xy 424.402707 -316.674333)
			(xy 424.418595 -316.723232) (xy 424.426638 -316.774014) (xy 424.427142 -316.799722) (xy 424.426638 -316.82543)
			(xy 425.673262 -316.82543) (xy 425.673262 -316.774014) (xy 425.681305 -316.723232) (xy 425.697193 -316.674333)
			(xy 425.720536 -316.628521) (xy 425.750757 -316.586925) (xy 425.787113 -316.550569) (xy 425.828709 -316.520348)
			(xy 425.874521 -316.497005) (xy 425.92342 -316.481117) (xy 425.974202 -316.473074) (xy 426.025618 -316.473074)
			(xy 426.0764 -316.481117) (xy 426.125299 -316.497005) (xy 426.171111 -316.520348) (xy 426.212707 -316.550569)
			(xy 426.249063 -316.586925) (xy 426.279284 -316.628521) (xy 426.302627 -316.674333) (xy 426.318515 -316.723232)
			(xy 426.326558 -316.774014) (xy 426.327062 -316.799722) (xy 426.326558 -316.82543) (xy 427.573182 -316.82543)
			(xy 427.573182 -316.774014) (xy 427.581225 -316.723232) (xy 427.597113 -316.674333) (xy 427.620456 -316.628521)
			(xy 427.650677 -316.586925) (xy 427.687033 -316.550569) (xy 427.728629 -316.520348) (xy 427.774441 -316.497005)
			(xy 427.82334 -316.481117) (xy 427.874122 -316.473074) (xy 427.925538 -316.473074) (xy 427.97632 -316.481117)
			(xy 428.025219 -316.497005) (xy 428.071031 -316.520348) (xy 428.112627 -316.550569) (xy 428.148983 -316.586925)
			(xy 428.179204 -316.628521) (xy 428.202547 -316.674333) (xy 428.218435 -316.723232) (xy 428.226478 -316.774014)
			(xy 428.226982 -316.799722) (xy 428.226478 -316.82543) (xy 429.473356 -316.82543) (xy 429.473356 -316.774014)
			(xy 429.481399 -316.723232) (xy 429.497287 -316.674333) (xy 429.52063 -316.628521) (xy 429.550851 -316.586925)
			(xy 429.587207 -316.550569) (xy 429.628803 -316.520348) (xy 429.674615 -316.497005) (xy 429.723514 -316.481117)
			(xy 429.774296 -316.473074) (xy 429.825712 -316.473074) (xy 429.876494 -316.481117) (xy 429.925393 -316.497005)
			(xy 429.971205 -316.520348) (xy 430.012801 -316.550569) (xy 430.049157 -316.586925) (xy 430.079378 -316.628521)
			(xy 430.102721 -316.674333) (xy 430.118609 -316.723232) (xy 430.126652 -316.774014) (xy 430.127156 -316.799722)
			(xy 430.126652 -316.82543) (xy 430.423316 -316.82543) (xy 430.423316 -316.774014) (xy 430.431359 -316.723232)
			(xy 430.447247 -316.674333) (xy 430.47059 -316.628521) (xy 430.500811 -316.586925) (xy 430.537167 -316.550569)
			(xy 430.578763 -316.520348) (xy 430.624575 -316.497005) (xy 430.673474 -316.481117) (xy 430.724256 -316.473074)
			(xy 430.775672 -316.473074) (xy 430.826454 -316.481117) (xy 430.875353 -316.497005) (xy 430.921165 -316.520348)
			(xy 430.962761 -316.550569) (xy 430.999117 -316.586925) (xy 431.029338 -316.628521) (xy 431.052681 -316.674333)
			(xy 431.068569 -316.723232) (xy 431.076612 -316.774014) (xy 431.077116 -316.799722) (xy 431.076612 -316.82543)
			(xy 431.068569 -316.876212) (xy 431.052681 -316.925111) (xy 431.029338 -316.970923) (xy 430.999117 -317.012519)
			(xy 430.962761 -317.048875) (xy 430.921165 -317.079096) (xy 430.875353 -317.102439) (xy 430.826454 -317.118327)
			(xy 430.775672 -317.12637) (xy 430.724256 -317.12637) (xy 430.673474 -317.118327) (xy 430.624575 -317.102439)
			(xy 430.578763 -317.079096) (xy 430.537167 -317.048875) (xy 430.500811 -317.012519) (xy 430.47059 -316.970923)
			(xy 430.447247 -316.925111) (xy 430.431359 -316.876212) (xy 430.423316 -316.82543) (xy 430.126652 -316.82543)
			(xy 430.118609 -316.876212) (xy 430.102721 -316.925111) (xy 430.079378 -316.970923) (xy 430.049157 -317.012519)
			(xy 430.012801 -317.048875) (xy 429.971205 -317.079096) (xy 429.925393 -317.102439) (xy 429.876494 -317.118327)
			(xy 429.825712 -317.12637) (xy 429.774296 -317.12637) (xy 429.723514 -317.118327) (xy 429.674615 -317.102439)
			(xy 429.628803 -317.079096) (xy 429.587207 -317.048875) (xy 429.550851 -317.012519) (xy 429.52063 -316.970923)
			(xy 429.497287 -316.925111) (xy 429.481399 -316.876212) (xy 429.473356 -316.82543) (xy 428.226478 -316.82543)
			(xy 428.218435 -316.876212) (xy 428.202547 -316.925111) (xy 428.179204 -316.970923) (xy 428.148983 -317.012519)
			(xy 428.112627 -317.048875) (xy 428.071031 -317.079096) (xy 428.025219 -317.102439) (xy 427.97632 -317.118327)
			(xy 427.925538 -317.12637) (xy 427.874122 -317.12637) (xy 427.82334 -317.118327) (xy 427.774441 -317.102439)
			(xy 427.728629 -317.079096) (xy 427.687033 -317.048875) (xy 427.650677 -317.012519) (xy 427.620456 -316.970923)
			(xy 427.597113 -316.925111) (xy 427.581225 -316.876212) (xy 427.573182 -316.82543) (xy 426.326558 -316.82543)
			(xy 426.318515 -316.876212) (xy 426.302627 -316.925111) (xy 426.279284 -316.970923) (xy 426.249063 -317.012519)
			(xy 426.212707 -317.048875) (xy 426.171111 -317.079096) (xy 426.125299 -317.102439) (xy 426.0764 -317.118327)
			(xy 426.025618 -317.12637) (xy 425.974202 -317.12637) (xy 425.92342 -317.118327) (xy 425.874521 -317.102439)
			(xy 425.828709 -317.079096) (xy 425.787113 -317.048875) (xy 425.750757 -317.012519) (xy 425.720536 -316.970923)
			(xy 425.697193 -316.925111) (xy 425.681305 -316.876212) (xy 425.673262 -316.82543) (xy 424.426638 -316.82543)
			(xy 424.418595 -316.876212) (xy 424.402707 -316.925111) (xy 424.379364 -316.970923) (xy 424.349143 -317.012519)
			(xy 424.312787 -317.048875) (xy 424.271191 -317.079096) (xy 424.225379 -317.102439) (xy 424.17648 -317.118327)
			(xy 424.125698 -317.12637) (xy 424.074282 -317.12637) (xy 424.0235 -317.118327) (xy 423.974601 -317.102439)
			(xy 423.928789 -317.079096) (xy 423.887193 -317.048875) (xy 423.850837 -317.012519) (xy 423.820616 -316.970923)
			(xy 423.797273 -316.925111) (xy 423.781385 -316.876212) (xy 423.773342 -316.82543) (xy 423.006012 -316.82543)
			(xy 423.006012 -317.274702) (xy 423.005977 -317.28412) (xy 423.004963 -317.302928) (xy 423.00398 -317.312294)
			(xy 423.00271 -317.323724) (xy 423.010076 -317.345568) (xy 423.082466 -317.418212) (xy 423.104056 -317.426086)
			(xy 423.115486 -317.424816) (xy 423.149776 -317.422784) (xy 423.150284 -317.422784) (xy 423.175964 -317.423309)
			(xy 423.226686 -317.431385) (xy 423.275521 -317.447294) (xy 423.321268 -317.470644) (xy 423.3628 -317.500861)
			(xy 423.399096 -317.5372) (xy 423.429262 -317.578769) (xy 423.452557 -317.624544) (xy 423.468407 -317.673398)
			(xy 423.476422 -317.72413) (xy 423.476404 -317.775491) (xy 423.47638 -317.775644) (xy 424.723302 -317.775644)
			(xy 424.723302 -317.724228) (xy 424.731345 -317.673446) (xy 424.747233 -317.624547) (xy 424.770576 -317.578735)
			(xy 424.800797 -317.537139) (xy 424.837153 -317.500783) (xy 424.878749 -317.470562) (xy 424.924561 -317.447219)
			(xy 424.97346 -317.431331) (xy 425.024242 -317.423288) (xy 425.075658 -317.423288) (xy 425.12644 -317.431331)
			(xy 425.175339 -317.447219) (xy 425.221151 -317.470562) (xy 425.262747 -317.500783) (xy 425.299103 -317.537139)
			(xy 425.329324 -317.578735) (xy 425.352667 -317.624547) (xy 425.368555 -317.673446) (xy 425.376598 -317.724228)
			(xy 425.377102 -317.749936) (xy 425.376598 -317.775644) (xy 426.623222 -317.775644) (xy 426.623222 -317.724228)
			(xy 426.631265 -317.673446) (xy 426.647153 -317.624547) (xy 426.670496 -317.578735) (xy 426.700717 -317.537139)
			(xy 426.737073 -317.500783) (xy 426.778669 -317.470562) (xy 426.824481 -317.447219) (xy 426.87338 -317.431331)
			(xy 426.924162 -317.423288) (xy 426.975578 -317.423288) (xy 427.02636 -317.431331) (xy 427.075259 -317.447219)
			(xy 427.121071 -317.470562) (xy 427.162667 -317.500783) (xy 427.199023 -317.537139) (xy 427.229244 -317.578735)
			(xy 427.252587 -317.624547) (xy 427.268475 -317.673446) (xy 427.276518 -317.724228) (xy 427.277022 -317.749936)
			(xy 427.276518 -317.775644) (xy 428.523142 -317.775644) (xy 428.523142 -317.724228) (xy 428.531185 -317.673446)
			(xy 428.547073 -317.624547) (xy 428.570416 -317.578735) (xy 428.600637 -317.537139) (xy 428.636993 -317.500783)
			(xy 428.678589 -317.470562) (xy 428.724401 -317.447219) (xy 428.7733 -317.431331) (xy 428.824082 -317.423288)
			(xy 428.875498 -317.423288) (xy 428.92628 -317.431331) (xy 428.975179 -317.447219) (xy 429.020991 -317.470562)
			(xy 429.062587 -317.500783) (xy 429.098943 -317.537139) (xy 429.129164 -317.578735) (xy 429.152507 -317.624547)
			(xy 429.168395 -317.673446) (xy 429.176438 -317.724228) (xy 429.176942 -317.749936) (xy 429.176438 -317.775644)
			(xy 429.168395 -317.826426) (xy 429.152507 -317.875325) (xy 429.129164 -317.921137) (xy 429.098943 -317.962733)
			(xy 429.062587 -317.999089) (xy 429.020991 -318.02931) (xy 428.975179 -318.052653) (xy 428.92628 -318.068541)
			(xy 428.875498 -318.076584) (xy 428.824082 -318.076584) (xy 428.7733 -318.068541) (xy 428.724401 -318.052653)
			(xy 428.678589 -318.02931) (xy 428.636993 -317.999089) (xy 428.600637 -317.962733) (xy 428.570416 -317.921137)
			(xy 428.547073 -317.875325) (xy 428.531185 -317.826426) (xy 428.523142 -317.775644) (xy 427.276518 -317.775644)
			(xy 427.268475 -317.826426) (xy 427.252587 -317.875325) (xy 427.229244 -317.921137) (xy 427.199023 -317.962733)
			(xy 427.162667 -317.999089) (xy 427.121071 -318.02931) (xy 427.075259 -318.052653) (xy 427.02636 -318.068541)
			(xy 426.975578 -318.076584) (xy 426.924162 -318.076584) (xy 426.87338 -318.068541) (xy 426.824481 -318.052653)
			(xy 426.778669 -318.02931) (xy 426.737073 -317.999089) (xy 426.700717 -317.962733) (xy 426.670496 -317.921137)
			(xy 426.647153 -317.875325) (xy 426.631265 -317.826426) (xy 426.623222 -317.775644) (xy 425.376598 -317.775644)
			(xy 425.368555 -317.826426) (xy 425.352667 -317.875325) (xy 425.329324 -317.921137) (xy 425.299103 -317.962733)
			(xy 425.262747 -317.999089) (xy 425.221151 -318.02931) (xy 425.175339 -318.052653) (xy 425.12644 -318.068541)
			(xy 425.075658 -318.076584) (xy 425.024242 -318.076584) (xy 424.97346 -318.068541) (xy 424.924561 -318.052653)
			(xy 424.878749 -318.02931) (xy 424.837153 -317.999089) (xy 424.800797 -317.962733) (xy 424.770576 -317.921137)
			(xy 424.747233 -317.875325) (xy 424.731345 -317.826426) (xy 424.723302 -317.775644) (xy 423.47638 -317.775644)
			(xy 423.468355 -317.826217) (xy 423.452472 -317.875061) (xy 423.429147 -317.92082) (xy 423.398952 -317.962368)
			(xy 423.362632 -317.998683) (xy 423.321079 -318.028872) (xy 423.275317 -318.052191) (xy 423.226471 -318.068066)
			(xy 423.175743 -318.076108) (xy 423.124382 -318.076118) (xy 423.073651 -318.068096) (xy 423.024799 -318.052239)
			(xy 422.979028 -318.028937) (xy 422.937464 -317.998765) (xy 422.901129 -317.962464) (xy 422.870919 -317.920927)
			(xy 422.847576 -317.875177) (xy 422.831674 -317.82634) (xy 422.823606 -317.775616) (xy 422.823132 -317.749936)
			(xy 422.82491 -317.715392) (xy 422.82491 -317.715138) (xy 422.825428 -317.703791) (xy 422.817775 -317.682435)
			(xy 422.810178 -317.67399) (xy 422.745662 -317.609728) (xy 422.723818 -317.602362) (xy 422.712388 -317.603632)
			(xy 422.703084 -317.604599) (xy 422.684404 -317.605614) (xy 422.67505 -317.605664) (xy 422.640506 -317.603886)
			(xy 422.629185 -317.603308) (xy 422.607836 -317.610837) (xy 422.599358 -317.618364) (xy 422.535096 -317.682372)
			(xy 422.527476 -317.703962) (xy 422.528746 -317.715392) (xy 422.530524 -317.749428) (xy 422.530524 -317.749936)
			(xy 422.52997 -317.777136) (xy 422.521064 -317.830802) (xy 422.503498 -317.882288) (xy 422.477746 -317.930207)
			(xy 422.444501 -317.973267) (xy 422.404659 -318.010307) (xy 422.359294 -318.040331) (xy 422.33469 -318.051942)
			(xy 422.325904 -318.056323) (xy 422.312268 -318.070423) (xy 422.304936 -318.088615) (xy 422.304464 -318.098424)
			(xy 422.304464 -318.351408) (xy 422.304911 -318.361219) (xy 422.312262 -318.379413) (xy 422.325892 -318.393529)
			(xy 422.33469 -318.39789) (xy 422.357683 -318.408667) (xy 422.400338 -318.436217) (xy 422.43828 -318.469963)
			(xy 422.47062 -318.509111) (xy 422.496597 -318.552742) (xy 422.515601 -318.59983) (xy 422.527184 -318.649269)
			(xy 422.531076 -318.699898) (xy 422.5291 -318.725604) (xy 422.823382 -318.725604) (xy 422.823382 -318.674188)
			(xy 422.831425 -318.623406) (xy 422.847313 -318.574507) (xy 422.870656 -318.528695) (xy 422.900877 -318.487099)
			(xy 422.937233 -318.450743) (xy 422.978829 -318.420522) (xy 423.024641 -318.397179) (xy 423.07354 -318.381291)
			(xy 423.124322 -318.373248) (xy 423.175738 -318.373248) (xy 423.22652 -318.381291) (xy 423.275419 -318.397179)
			(xy 423.321231 -318.420522) (xy 423.362827 -318.450743) (xy 423.399183 -318.487099) (xy 423.429404 -318.528695)
			(xy 423.452747 -318.574507) (xy 423.468635 -318.623406) (xy 423.476678 -318.674188) (xy 423.477182 -318.699896)
			(xy 423.476678 -318.725604) (xy 424.723302 -318.725604) (xy 424.723302 -318.674188) (xy 424.731345 -318.623406)
			(xy 424.747233 -318.574507) (xy 424.770576 -318.528695) (xy 424.800797 -318.487099) (xy 424.837153 -318.450743)
			(xy 424.878749 -318.420522) (xy 424.924561 -318.397179) (xy 424.97346 -318.381291) (xy 425.024242 -318.373248)
			(xy 425.075658 -318.373248) (xy 425.12644 -318.381291) (xy 425.175339 -318.397179) (xy 425.221151 -318.420522)
			(xy 425.262747 -318.450743) (xy 425.299103 -318.487099) (xy 425.329324 -318.528695) (xy 425.352667 -318.574507)
			(xy 425.368555 -318.623406) (xy 425.376598 -318.674188) (xy 425.377102 -318.699896) (xy 425.376598 -318.725604)
			(xy 426.623222 -318.725604) (xy 426.623222 -318.674188) (xy 426.631265 -318.623406) (xy 426.647153 -318.574507)
			(xy 426.670496 -318.528695) (xy 426.700717 -318.487099) (xy 426.737073 -318.450743) (xy 426.778669 -318.420522)
			(xy 426.824481 -318.397179) (xy 426.87338 -318.381291) (xy 426.924162 -318.373248) (xy 426.975578 -318.373248)
			(xy 427.02636 -318.381291) (xy 427.075259 -318.397179) (xy 427.121071 -318.420522) (xy 427.162667 -318.450743)
			(xy 427.199023 -318.487099) (xy 427.229244 -318.528695) (xy 427.252587 -318.574507) (xy 427.268475 -318.623406)
			(xy 427.276518 -318.674188) (xy 427.277022 -318.699896) (xy 427.276518 -318.725604) (xy 428.523142 -318.725604)
			(xy 428.523142 -318.674188) (xy 428.531185 -318.623406) (xy 428.547073 -318.574507) (xy 428.570416 -318.528695)
			(xy 428.600637 -318.487099) (xy 428.636993 -318.450743) (xy 428.678589 -318.420522) (xy 428.724401 -318.397179)
			(xy 428.7733 -318.381291) (xy 428.824082 -318.373248) (xy 428.875498 -318.373248) (xy 428.92628 -318.381291)
			(xy 428.975179 -318.397179) (xy 429.020991 -318.420522) (xy 429.062587 -318.450743) (xy 429.098943 -318.487099)
			(xy 429.129164 -318.528695) (xy 429.152507 -318.574507) (xy 429.168395 -318.623406) (xy 429.176438 -318.674188)
			(xy 429.176942 -318.699896) (xy 429.176438 -318.725604) (xy 429.168395 -318.776386) (xy 429.152507 -318.825285)
			(xy 429.129164 -318.871097) (xy 429.098943 -318.912693) (xy 429.062587 -318.949049) (xy 429.020991 -318.97927)
			(xy 428.975179 -319.002613) (xy 428.92628 -319.018501) (xy 428.875498 -319.026544) (xy 428.824082 -319.026544)
			(xy 428.7733 -319.018501) (xy 428.724401 -319.002613) (xy 428.678589 -318.97927) (xy 428.636993 -318.949049)
			(xy 428.600637 -318.912693) (xy 428.570416 -318.871097) (xy 428.547073 -318.825285) (xy 428.531185 -318.776386)
			(xy 428.523142 -318.725604) (xy 427.276518 -318.725604) (xy 427.268475 -318.776386) (xy 427.252587 -318.825285)
			(xy 427.229244 -318.871097) (xy 427.199023 -318.912693) (xy 427.162667 -318.949049) (xy 427.121071 -318.97927)
			(xy 427.075259 -319.002613) (xy 427.02636 -319.018501) (xy 426.975578 -319.026544) (xy 426.924162 -319.026544)
			(xy 426.87338 -319.018501) (xy 426.824481 -319.002613) (xy 426.778669 -318.97927) (xy 426.737073 -318.949049)
			(xy 426.700717 -318.912693) (xy 426.670496 -318.871097) (xy 426.647153 -318.825285) (xy 426.631265 -318.776386)
			(xy 426.623222 -318.725604) (xy 425.376598 -318.725604) (xy 425.368555 -318.776386) (xy 425.352667 -318.825285)
			(xy 425.329324 -318.871097) (xy 425.299103 -318.912693) (xy 425.262747 -318.949049) (xy 425.221151 -318.97927)
			(xy 425.175339 -319.002613) (xy 425.12644 -319.018501) (xy 425.075658 -319.026544) (xy 425.024242 -319.026544)
			(xy 424.97346 -319.018501) (xy 424.924561 -319.002613) (xy 424.878749 -318.97927) (xy 424.837153 -318.949049)
			(xy 424.800797 -318.912693) (xy 424.770576 -318.871097) (xy 424.747233 -318.825285) (xy 424.731345 -318.776386)
			(xy 424.723302 -318.725604) (xy 423.476678 -318.725604) (xy 423.468635 -318.776386) (xy 423.452747 -318.825285)
			(xy 423.429404 -318.871097) (xy 423.399183 -318.912693) (xy 423.362827 -318.949049) (xy 423.321231 -318.97927)
			(xy 423.275419 -319.002613) (xy 423.22652 -319.018501) (xy 423.175738 -319.026544) (xy 423.124322 -319.026544)
			(xy 423.07354 -319.018501) (xy 423.024641 -319.002613) (xy 422.978829 -318.97927) (xy 422.937233 -318.949049)
			(xy 422.900877 -318.912693) (xy 422.870656 -318.871097) (xy 422.847313 -318.825285) (xy 422.831425 -318.776386)
			(xy 422.823382 -318.725604) (xy 422.5291 -318.725604) (xy 422.527185 -318.750527) (xy 422.515602 -318.799967)
			(xy 422.496598 -318.847055) (xy 422.470622 -318.890686) (xy 422.438283 -318.929835) (xy 422.40034 -318.963581)
			(xy 422.357686 -318.991132) (xy 422.33469 -319.001902) (xy 422.325899 -319.006281) (xy 422.312252 -319.020379)
			(xy 422.304906 -319.038573) (xy 422.304464 -319.048384) (xy 422.304464 -319.680336) (xy 422.305226 -319.68948)
			(xy 422.307004 -319.698624) (xy 422.309544 -319.707768) (xy 422.32539 -319.750328) (xy 422.350127 -319.837718)
			(xy 422.366737 -319.927009) (xy 422.375079 -320.017448) (xy 422.375584 -320.06286) (xy 422.375584 -320.082164)
			(xy 422.376092 -320.086228) (xy 422.381746 -320.124459) (xy 422.38785 -320.201508) (xy 422.388284 -320.240152)
			(xy 422.388284 -320.900044) (xy 435.182527 -320.900044) (xy 435.186516 -320.751504) (xy 435.198473 -320.603391)
			(xy 435.218363 -320.456134) (xy 435.246128 -320.310158) (xy 435.281689 -320.165881) (xy 435.324943 -320.023722)
			(xy 435.375765 -319.884089) (xy 435.434009 -319.747386) (xy 435.499507 -319.614006) (xy 435.57207 -319.484334)
			(xy 435.651488 -319.358744) (xy 435.737533 -319.237597) (xy 435.829957 -319.121244) (xy 435.928493 -319.01002)
			(xy 436.032857 -318.904245) (xy 436.142749 -318.804225) (xy 436.25785 -318.710247) (xy 436.37783 -318.622583)
			(xy 436.502343 -318.541486) (xy 436.631029 -318.467189) (xy 436.763518 -318.399907) (xy 436.899427 -318.339833)
			(xy 437.038365 -318.287141) (xy 437.179931 -318.241982) (xy 437.323717 -318.204487) (xy 437.469308 -318.174765)
			(xy 437.616284 -318.1529) (xy 437.764223 -318.138956) (xy 437.912696 -318.132972) (xy 438.061277 -318.134967)
			(xy 438.209536 -318.144935) (xy 438.357047 -318.162846) (xy 438.503383 -318.188649) (xy 438.648124 -318.222269)
			(xy 438.790851 -318.263611) (xy 438.931154 -318.312554) (xy 439.068627 -318.368957) (xy 439.202874 -318.432658)
			(xy 439.333509 -318.503474) (xy 439.460154 -318.581199) (xy 439.582444 -318.66561) (xy 439.700027 -318.756463)
			(xy 439.812564 -318.853497) (xy 439.919731 -318.956432) (xy 440.021218 -319.064971) (xy 440.116732 -319.1788)
			(xy 440.205999 -319.297593) (xy 440.28876 -319.421005) (xy 440.364778 -319.548683) (xy 440.433833 -319.680256)
			(xy 440.495726 -319.815347) (xy 440.550279 -319.953564) (xy 440.597334 -320.094511) (xy 440.636756 -320.237781)
			(xy 440.66843 -320.38296) (xy 440.692266 -320.529629) (xy 440.708195 -320.677367) (xy 440.716171 -320.825747)
			(xy 440.71667 -320.900044) (xy 440.716171 -320.974341) (xy 440.708195 -321.122721) (xy 440.692266 -321.270459)
			(xy 440.66843 -321.417128) (xy 440.636756 -321.562307) (xy 440.597334 -321.705577) (xy 440.550279 -321.846524)
			(xy 440.495726 -321.984741) (xy 440.433833 -322.119832) (xy 440.364778 -322.251405) (xy 440.28876 -322.379083)
			(xy 440.205999 -322.502495) (xy 440.116732 -322.621288) (xy 440.021218 -322.735117) (xy 439.919731 -322.843656)
			(xy 439.812564 -322.946591) (xy 439.700027 -323.043625) (xy 439.582444 -323.134478) (xy 439.460154 -323.218889)
			(xy 439.333509 -323.296614) (xy 439.202874 -323.36743) (xy 439.068627 -323.431131) (xy 438.931154 -323.487534)
			(xy 438.790851 -323.536477) (xy 438.648124 -323.577819) (xy 438.503383 -323.611439) (xy 438.357047 -323.637242)
			(xy 438.209536 -323.655153) (xy 438.061277 -323.665121) (xy 437.912696 -323.667116) (xy 437.764223 -323.661132)
			(xy 437.616284 -323.647188) (xy 437.469308 -323.625323) (xy 437.323717 -323.595601) (xy 437.179931 -323.558106)
			(xy 437.038365 -323.512947) (xy 436.899427 -323.460255) (xy 436.763518 -323.400181) (xy 436.631029 -323.332899)
			(xy 436.502343 -323.258602) (xy 436.37783 -323.177505) (xy 436.25785 -323.089841) (xy 436.142749 -322.995863)
			(xy 436.032857 -322.895843) (xy 435.928493 -322.790068) (xy 435.829957 -322.678844) (xy 435.737533 -322.562491)
			(xy 435.651488 -322.441344) (xy 435.57207 -322.315754) (xy 435.499507 -322.186082) (xy 435.434009 -322.052702)
			(xy 435.375765 -321.915999) (xy 435.324943 -321.776366) (xy 435.281689 -321.634207) (xy 435.246128 -321.48993)
			(xy 435.218363 -321.343954) (xy 435.198473 -321.196697) (xy 435.186516 -321.048584) (xy 435.182527 -320.900044)
			(xy 422.388284 -320.900044) (xy 422.388284 -322.302632) (xy 422.387854 -322.341277) (xy 422.381755 -322.418326)
			(xy 422.376092 -322.456556) (xy 422.375584 -322.46062) (xy 422.375584 -323.306948) (xy 422.375092 -323.350954)
			(xy 422.367246 -323.438616) (xy 422.351638 -323.525233) (xy 422.328393 -323.610119) (xy 422.297693 -323.692604)
			(xy 422.259782 -323.772032) (xy 422.214961 -323.847776) (xy 422.189656 -323.883782) (xy 422.168574 -323.913246)
			(xy 422.165113 -323.918785) (xy 422.160874 -323.931134) (xy 422.160192 -323.93763) (xy 422.159938 -323.941694)
			(xy 422.159938 -329.720448) (xy 422.159504 -329.730513) (xy 422.151771 -329.749099) (xy 422.144952 -329.756516)
			(xy 422.020492 -329.880976) (xy 459.363064 -329.880976) (xy 459.363527 -329.854662) (xy 459.370764 -329.802534)
			(xy 459.385085 -329.751891) (xy 459.406218 -329.703693) (xy 459.433765 -329.658849) (xy 459.467203 -329.618209)
			(xy 459.486254 -329.600052) (xy 459.493672 -329.592544) (xy 459.502188 -329.573254) (xy 459.502764 -329.562714)
			(xy 459.502764 -329.488038) (xy 459.502238 -329.477488) (xy 459.493702 -329.458192) (xy 459.486254 -329.4507)
			(xy 459.467197 -329.432546) (xy 459.433741 -329.391915) (xy 459.406184 -329.347074) (xy 459.385046 -329.298873)
			(xy 459.370729 -329.248226) (xy 459.363503 -329.196092) (xy 459.363064 -329.169776) (xy 459.363555 -329.142525)
			(xy 459.371314 -329.088579) (xy 459.386671 -329.036286) (xy 459.409313 -328.986711) (xy 459.438779 -328.940862)
			(xy 459.47447 -328.899673) (xy 459.515659 -328.863982) (xy 459.561507 -328.834515) (xy 459.611083 -328.811873)
			(xy 459.663375 -328.796515) (xy 459.717321 -328.788756) (xy 459.744572 -328.788268) (xy 459.770887 -328.788698)
			(xy 459.823017 -328.795942) (xy 459.87366 -328.810269) (xy 459.921858 -328.831408) (xy 459.966701 -328.858961)
			(xy 460.00734 -328.892404) (xy 460.025496 -328.911458) (xy 460.033023 -328.918853) (xy 460.052299 -328.927383)
			(xy 460.062834 -328.927968) (xy 460.13751 -328.927968) (xy 460.148063 -328.927467) (xy 460.167359 -328.918913)
			(xy 460.174848 -328.911458) (xy 460.194668 -328.89067) (xy 460.23944 -328.854695) (xy 460.289098 -328.825835)
			(xy 460.34252 -328.804742) (xy 460.398499 -328.791893) (xy 460.455772 -328.787578) (xy 460.513045 -328.791893)
			(xy 460.569024 -328.804742) (xy 460.622446 -328.825835) (xy 460.672104 -328.854695) (xy 460.716876 -328.89067)
			(xy 460.736696 -328.911458) (xy 460.744223 -328.918853) (xy 460.763499 -328.927383) (xy 460.774034 -328.927968)
			(xy 460.84871 -328.927968) (xy 460.859263 -328.927467) (xy 460.878559 -328.918913) (xy 460.886048 -328.911458)
			(xy 460.904179 -328.892378) (xy 460.944815 -328.858925) (xy 460.989661 -328.83137) (xy 461.037866 -328.810236)
			(xy 461.088517 -328.795924) (xy 461.140655 -328.788704) (xy 461.166972 -328.788268) (xy 461.194223 -328.788781)
			(xy 461.248171 -328.796534) (xy 461.300466 -328.811885) (xy 461.350045 -328.834523) (xy 461.395897 -328.863985)
			(xy 461.437089 -328.899674) (xy 461.472783 -328.940861) (xy 461.502252 -328.986709) (xy 461.524897 -329.036285)
			(xy 461.540255 -329.088578) (xy 461.548015 -329.142525) (xy 461.54848 -329.169776) (xy 461.548003 -329.19609)
			(xy 461.540771 -329.248218) (xy 461.526454 -329.298861) (xy 461.505324 -329.34706) (xy 461.477779 -329.391904)
			(xy 461.444341 -329.432543) (xy 461.42529 -329.4507) (xy 461.417885 -329.458218) (xy 461.409363 -329.477501)
			(xy 461.40878 -329.488038) (xy 461.40878 -329.562714) (xy 461.409294 -329.573265) (xy 461.41784 -329.59256)
			(xy 461.42529 -329.600052) (xy 461.444362 -329.618191) (xy 461.477818 -329.658824) (xy 461.505375 -329.703668)
			(xy 461.526511 -329.751872) (xy 461.540824 -329.802522) (xy 461.548044 -329.854659) (xy 461.54848 -329.880976)
			(xy 461.548022 -329.90823) (xy 461.540268 -329.962182) (xy 461.524913 -330.014482) (xy 461.502272 -330.064064)
			(xy 461.472804 -330.109918) (xy 461.437109 -330.151112) (xy 461.395915 -330.186806) (xy 461.35006 -330.216274)
			(xy 461.300478 -330.238915) (xy 461.248178 -330.254269) (xy 461.194226 -330.262023) (xy 461.166972 -330.262484)
			(xy 461.140657 -330.26204) (xy 461.088527 -330.254801) (xy 461.037884 -330.240478) (xy 460.989685 -330.219341)
			(xy 460.944842 -330.191791) (xy 460.904204 -330.158348) (xy 460.886048 -330.139294) (xy 460.878548 -330.131867)
			(xy 460.859252 -330.123357) (xy 460.84871 -330.122784) (xy 460.774034 -330.122784) (xy 460.763486 -330.123323)
			(xy 460.74419 -330.131852) (xy 460.736696 -330.139294) (xy 460.716876 -330.160082) (xy 460.672104 -330.196057)
			(xy 460.622446 -330.224917) (xy 460.569024 -330.24601) (xy 460.513045 -330.258859) (xy 460.455772 -330.263174)
			(xy 460.398499 -330.258859) (xy 460.34252 -330.24601) (xy 460.289098 -330.224917) (xy 460.23944 -330.196057)
			(xy 460.194668 -330.160082) (xy 460.174848 -330.139294) (xy 460.167348 -330.131867) (xy 460.148052 -330.123357)
			(xy 460.13751 -330.122784) (xy 460.062834 -330.122784) (xy 460.052286 -330.123323) (xy 460.03299 -330.131852)
			(xy 460.025496 -330.139294) (xy 460.007334 -330.158343) (xy 459.966706 -330.191801) (xy 459.921867 -330.219361)
			(xy 459.873667 -330.240501) (xy 459.823021 -330.254819) (xy 459.770888 -330.262045) (xy 459.744572 -330.262484)
			(xy 459.717319 -330.262048) (xy 459.663368 -330.254287) (xy 459.611071 -330.238927) (xy 459.561492 -330.216281)
			(xy 459.515641 -330.18681) (xy 459.47445 -330.151113) (xy 459.438759 -330.109918) (xy 459.409294 -330.064062)
			(xy 459.386654 -330.01448) (xy 459.371302 -329.962181) (xy 459.363548 -329.908229) (xy 459.363064 -329.880976)
			(xy 422.020492 -329.880976) (xy 410.887672 -341.013796) (xy 410.88415 -341.017526) (xy 410.878519 -341.0261)
			(xy 410.876496 -341.030814) (xy 410.87294 -341.03945) (xy 410.87294 -342.098884) (xy 410.874718 -342.112346)
			(xy 410.879544 -342.12403) (xy 410.890974 -342.14435) (xy 410.898848 -342.155018) (xy 410.902404 -342.158574)
			(xy 410.903674 -342.159336) (xy 410.925176 -342.173439) (xy 410.96394 -342.207223) (xy 410.997013 -342.246595)
			(xy 411.0236 -342.290608) (xy 411.043062 -342.338202) (xy 411.054929 -342.388234) (xy 411.058917 -342.439499)
			(xy 411.056796 -342.466767) (xy 412.022822 -342.466767) (xy 412.022822 -342.412233) (xy 412.030583 -342.358253)
			(xy 412.045946 -342.305927) (xy 412.068599 -342.25632) (xy 412.09808 -342.210441) (xy 412.13379 -342.169224)
			(xy 412.175002 -342.133509) (xy 412.220878 -342.104022) (xy 412.270482 -342.081363) (xy 412.322806 -342.065993)
			(xy 412.376785 -342.058226) (xy 412.404052 -342.057736) (xy 413.267652 -342.057736) (xy 413.294925 -342.0582)
			(xy 413.348917 -342.065957) (xy 413.401255 -342.081319) (xy 413.450874 -342.103974) (xy 413.496763 -342.13346)
			(xy 413.537989 -342.169177) (xy 413.573712 -342.210398) (xy 413.603203 -342.256284) (xy 413.625864 -342.3059)
			(xy 413.641233 -342.358236) (xy 413.648996 -342.412227) (xy 413.648996 -342.466772) (xy 415.1317 -342.466772)
			(xy 415.1317 -342.412228) (xy 415.139462 -342.35824) (xy 415.154829 -342.305906) (xy 415.177488 -342.256292)
			(xy 415.206976 -342.210407) (xy 415.242695 -342.169187) (xy 415.283917 -342.133469) (xy 415.329803 -342.103982)
			(xy 415.379417 -342.081325) (xy 415.431752 -342.065959) (xy 415.48574 -342.058199) (xy 415.513012 -342.057736)
			(xy 416.376612 -342.057736) (xy 416.403881 -342.058227) (xy 416.457863 -342.06599) (xy 416.510191 -342.081357)
			(xy 416.559799 -342.104013) (xy 416.605678 -342.133499) (xy 416.646894 -342.169214) (xy 416.682608 -342.210432)
			(xy 416.712092 -342.256312) (xy 416.734748 -342.305921) (xy 416.750112 -342.358249) (xy 416.757874 -342.412231)
			(xy 416.757874 -342.466768) (xy 418.240722 -342.466768) (xy 418.240722 -342.412232) (xy 418.248483 -342.35825)
			(xy 418.263847 -342.305923) (xy 418.286502 -342.256314) (xy 418.315985 -342.210434) (xy 418.351697 -342.169217)
			(xy 418.392912 -342.133502) (xy 418.43879 -342.104015) (xy 418.488396 -342.081357) (xy 418.540723 -342.065989)
			(xy 418.594704 -342.058224) (xy 418.621972 -342.057736) (xy 419.485572 -342.057736) (xy 419.512844 -342.058202)
			(xy 419.566834 -342.06596) (xy 419.61917 -342.081324) (xy 419.668786 -342.10398) (xy 419.714673 -342.133467)
			(xy 419.755896 -342.169184) (xy 419.791616 -342.210405) (xy 419.821107 -342.256289) (xy 419.843766 -342.305904)
			(xy 419.859134 -342.358239) (xy 419.866896 -342.412228) (xy 419.866896 -342.466772) (xy 419.866896 -342.466773)
			(xy 421.3496 -342.466773) (xy 421.3496 -342.412227) (xy 421.357363 -342.358237) (xy 421.372731 -342.305902)
			(xy 421.395391 -342.256286) (xy 421.424881 -342.210401) (xy 421.460602 -342.16918) (xy 421.501827 -342.133462)
			(xy 421.547715 -342.103975) (xy 421.597332 -342.081319) (xy 421.649669 -342.065956) (xy 421.703659 -342.058197)
			(xy 421.730932 -342.057736) (xy 422.594532 -342.057736) (xy 422.6218 -342.058229) (xy 422.67578 -342.065994)
			(xy 422.728105 -342.081362) (xy 422.777711 -342.10402) (xy 422.823588 -342.133506) (xy 422.864801 -342.169222)
			(xy 422.900513 -342.210438) (xy 422.929995 -342.256317) (xy 422.952649 -342.305925) (xy 422.968013 -342.358252)
			(xy 422.975774 -342.412232) (xy 422.975774 -342.466768) (xy 422.975774 -342.466769) (xy 424.458622 -342.466769)
			(xy 424.458622 -342.412231) (xy 424.466384 -342.358248) (xy 424.481749 -342.305918) (xy 424.504405 -342.256309)
			(xy 424.53389 -342.210428) (xy 424.569605 -342.16921) (xy 424.610821 -342.133495) (xy 424.656702 -342.104009)
			(xy 424.706311 -342.081352) (xy 424.75864 -342.065986) (xy 424.812623 -342.058223) (xy 424.839892 -342.057736)
			(xy 425.703492 -342.057736) (xy 425.730763 -342.058203) (xy 425.784751 -342.065964) (xy 425.837084 -342.08133)
			(xy 425.886698 -342.103987) (xy 425.932582 -342.133474) (xy 425.973803 -342.169191) (xy 426.009521 -342.210411)
			(xy 426.03901 -342.256295) (xy 426.061668 -342.305908) (xy 426.077034 -342.358241) (xy 426.084796 -342.412229)
			(xy 426.084796 -342.466767) (xy 427.567622 -342.466767) (xy 427.567622 -342.412233) (xy 427.575383 -342.358253)
			(xy 427.590746 -342.305927) (xy 427.613399 -342.25632) (xy 427.64288 -342.210441) (xy 427.67859 -342.169224)
			(xy 427.719802 -342.133509) (xy 427.765678 -342.104022) (xy 427.815282 -342.081363) (xy 427.867606 -342.065993)
			(xy 427.921585 -342.058226) (xy 427.948852 -342.057736) (xy 428.812452 -342.057736) (xy 428.839725 -342.0582)
			(xy 428.893717 -342.065957) (xy 428.946055 -342.081319) (xy 428.995674 -342.103974) (xy 429.041563 -342.13346)
			(xy 429.082789 -342.169177) (xy 429.118512 -342.210398) (xy 429.148003 -342.256284) (xy 429.170664 -342.3059)
			(xy 429.186033 -342.358236) (xy 429.193796 -342.412227) (xy 429.193796 -342.466772) (xy 430.6765 -342.466772)
			(xy 430.6765 -342.412228) (xy 430.684262 -342.35824) (xy 430.699629 -342.305906) (xy 430.722288 -342.256292)
			(xy 430.751776 -342.210407) (xy 430.787495 -342.169187) (xy 430.828717 -342.133469) (xy 430.874603 -342.103982)
			(xy 430.924217 -342.081325) (xy 430.976552 -342.065959) (xy 431.03054 -342.058199) (xy 431.057812 -342.057736)
			(xy 431.921412 -342.057736) (xy 431.948681 -342.058227) (xy 432.002663 -342.06599) (xy 432.054991 -342.081357)
			(xy 432.104599 -342.104013) (xy 432.150478 -342.133499) (xy 432.191694 -342.169214) (xy 432.227408 -342.210432)
			(xy 432.256892 -342.256312) (xy 432.279548 -342.305921) (xy 432.294912 -342.358249) (xy 432.302674 -342.412231)
			(xy 432.302674 -342.466768) (xy 433.785522 -342.466768) (xy 433.785522 -342.412232) (xy 433.793283 -342.35825)
			(xy 433.808647 -342.305923) (xy 433.831302 -342.256314) (xy 433.860785 -342.210434) (xy 433.896497 -342.169217)
			(xy 433.937712 -342.133502) (xy 433.98359 -342.104015) (xy 434.033196 -342.081357) (xy 434.085523 -342.065989)
			(xy 434.139504 -342.058224) (xy 434.166772 -342.057736) (xy 435.030372 -342.057736) (xy 435.057644 -342.058202)
			(xy 435.111634 -342.06596) (xy 435.16397 -342.081324) (xy 435.213586 -342.10398) (xy 435.259473 -342.133467)
			(xy 435.300696 -342.169184) (xy 435.336416 -342.210405) (xy 435.365907 -342.256289) (xy 435.388566 -342.305904)
			(xy 435.403934 -342.358239) (xy 435.411696 -342.412228) (xy 435.411696 -342.466772) (xy 435.411696 -342.466773)
			(xy 436.8944 -342.466773) (xy 436.8944 -342.412227) (xy 436.902163 -342.358237) (xy 436.917531 -342.305902)
			(xy 436.940191 -342.256286) (xy 436.969681 -342.210401) (xy 437.005402 -342.16918) (xy 437.046627 -342.133462)
			(xy 437.092515 -342.103975) (xy 437.142132 -342.081319) (xy 437.194469 -342.065956) (xy 437.248459 -342.058197)
			(xy 437.275732 -342.057736) (xy 438.139332 -342.057736) (xy 438.1666 -342.058229) (xy 438.22058 -342.065994)
			(xy 438.272905 -342.081362) (xy 438.322511 -342.10402) (xy 438.368388 -342.133506) (xy 438.409601 -342.169222)
			(xy 438.445313 -342.210438) (xy 438.474795 -342.256317) (xy 438.497449 -342.305925) (xy 438.512813 -342.358252)
			(xy 438.520574 -342.412232) (xy 438.520574 -342.466768) (xy 438.520574 -342.466769) (xy 440.003422 -342.466769)
			(xy 440.003422 -342.412231) (xy 440.011184 -342.358248) (xy 440.026549 -342.305918) (xy 440.049205 -342.256309)
			(xy 440.07869 -342.210428) (xy 440.114405 -342.16921) (xy 440.155621 -342.133495) (xy 440.201502 -342.104009)
			(xy 440.251111 -342.081352) (xy 440.30344 -342.065986) (xy 440.357423 -342.058223) (xy 440.384692 -342.057736)
			(xy 441.248292 -342.057736) (xy 441.275563 -342.058203) (xy 441.329551 -342.065964) (xy 441.381884 -342.08133)
			(xy 441.431498 -342.103987) (xy 441.477382 -342.133474) (xy 441.518603 -342.169191) (xy 441.554321 -342.210411)
			(xy 441.58381 -342.256295) (xy 441.606468 -342.305908) (xy 441.621834 -342.358241) (xy 441.629596 -342.412229)
			(xy 441.629596 -342.466771) (xy 441.621834 -342.520759) (xy 441.606468 -342.573092) (xy 441.58381 -342.622705)
			(xy 441.554321 -342.668589) (xy 441.518603 -342.709809) (xy 441.477382 -342.745526) (xy 441.431498 -342.775013)
			(xy 441.381884 -342.79767) (xy 441.329551 -342.813036) (xy 441.275563 -342.820797) (xy 441.248292 -342.82126)
			(xy 440.384692 -342.82126) (xy 440.357423 -342.820777) (xy 440.30344 -342.813014) (xy 440.251111 -342.797648)
			(xy 440.201502 -342.774991) (xy 440.155621 -342.745505) (xy 440.114405 -342.70979) (xy 440.07869 -342.668572)
			(xy 440.049205 -342.622691) (xy 440.026549 -342.573082) (xy 440.011184 -342.520752) (xy 440.003422 -342.466769)
			(xy 438.520574 -342.466769) (xy 438.512813 -342.520748) (xy 438.497449 -342.573075) (xy 438.474795 -342.622683)
			(xy 438.445313 -342.668562) (xy 438.409601 -342.709778) (xy 438.368388 -342.745494) (xy 438.322511 -342.77498)
			(xy 438.272905 -342.797638) (xy 438.22058 -342.813006) (xy 438.1666 -342.820771) (xy 438.139332 -342.82126)
			(xy 437.275732 -342.82126) (xy 437.248459 -342.820803) (xy 437.194469 -342.813044) (xy 437.142132 -342.797681)
			(xy 437.092515 -342.775025) (xy 437.046627 -342.745538) (xy 437.005402 -342.70982) (xy 436.969681 -342.668599)
			(xy 436.940191 -342.622714) (xy 436.917531 -342.573098) (xy 436.902163 -342.520763) (xy 436.8944 -342.466773)
			(xy 435.411696 -342.466773) (xy 435.403934 -342.520761) (xy 435.388566 -342.573096) (xy 435.365907 -342.622711)
			(xy 435.336416 -342.668595) (xy 435.300696 -342.709816) (xy 435.259473 -342.745533) (xy 435.213586 -342.77502)
			(xy 435.16397 -342.797676) (xy 435.111634 -342.81304) (xy 435.057644 -342.820798) (xy 435.030372 -342.82126)
			(xy 434.166772 -342.82126) (xy 434.139504 -342.820776) (xy 434.085523 -342.813011) (xy 434.033196 -342.797643)
			(xy 433.98359 -342.774985) (xy 433.937712 -342.745498) (xy 433.896497 -342.709783) (xy 433.860785 -342.668566)
			(xy 433.831302 -342.622686) (xy 433.808647 -342.573077) (xy 433.793283 -342.52075) (xy 433.785522 -342.466768)
			(xy 432.302674 -342.466768) (xy 432.302674 -342.466769) (xy 432.294912 -342.520751) (xy 432.279548 -342.573079)
			(xy 432.256892 -342.622688) (xy 432.227408 -342.668568) (xy 432.191694 -342.709786) (xy 432.150478 -342.745501)
			(xy 432.104599 -342.774987) (xy 432.054991 -342.797643) (xy 432.002663 -342.81301) (xy 431.948681 -342.820773)
			(xy 431.921412 -342.82126) (xy 431.057812 -342.82126) (xy 431.03054 -342.820801) (xy 430.976552 -342.813041)
			(xy 430.924217 -342.797675) (xy 430.874603 -342.775018) (xy 430.828717 -342.745531) (xy 430.787495 -342.709813)
			(xy 430.751776 -342.668593) (xy 430.722288 -342.622708) (xy 430.699629 -342.573094) (xy 430.684262 -342.52076)
			(xy 430.6765 -342.466772) (xy 429.193796 -342.466772) (xy 429.193796 -342.466773) (xy 429.186033 -342.520764)
			(xy 429.170664 -342.5731) (xy 429.148003 -342.622716) (xy 429.118512 -342.668602) (xy 429.082789 -342.709823)
			(xy 429.041563 -342.74554) (xy 428.995674 -342.775026) (xy 428.946055 -342.797681) (xy 428.893717 -342.813043)
			(xy 428.839725 -342.8208) (xy 428.812452 -342.82126) (xy 427.948852 -342.82126) (xy 427.921585 -342.820774)
			(xy 427.867606 -342.813007) (xy 427.815282 -342.797637) (xy 427.765678 -342.774978) (xy 427.719802 -342.745491)
			(xy 427.67859 -342.709776) (xy 427.64288 -342.668559) (xy 427.613399 -342.62268) (xy 427.590746 -342.573073)
			(xy 427.575383 -342.520747) (xy 427.567622 -342.466767) (xy 426.084796 -342.466767) (xy 426.084796 -342.466771)
			(xy 426.077034 -342.520759) (xy 426.061668 -342.573092) (xy 426.03901 -342.622705) (xy 426.009521 -342.668589)
			(xy 425.973803 -342.709809) (xy 425.932582 -342.745526) (xy 425.886698 -342.775013) (xy 425.837084 -342.79767)
			(xy 425.784751 -342.813036) (xy 425.730763 -342.820797) (xy 425.703492 -342.82126) (xy 424.839892 -342.82126)
			(xy 424.812623 -342.820777) (xy 424.75864 -342.813014) (xy 424.706311 -342.797648) (xy 424.656702 -342.774991)
			(xy 424.610821 -342.745505) (xy 424.569605 -342.70979) (xy 424.53389 -342.668572) (xy 424.504405 -342.622691)
			(xy 424.481749 -342.573082) (xy 424.466384 -342.520752) (xy 424.458622 -342.466769) (xy 422.975774 -342.466769)
			(xy 422.968013 -342.520748) (xy 422.952649 -342.573075) (xy 422.929995 -342.622683) (xy 422.900513 -342.668562)
			(xy 422.864801 -342.709778) (xy 422.823588 -342.745494) (xy 422.777711 -342.77498) (xy 422.728105 -342.797638)
			(xy 422.67578 -342.813006) (xy 422.6218 -342.820771) (xy 422.594532 -342.82126) (xy 421.730932 -342.82126)
			(xy 421.703659 -342.820803) (xy 421.649669 -342.813044) (xy 421.597332 -342.797681) (xy 421.547715 -342.775025)
			(xy 421.501827 -342.745538) (xy 421.460602 -342.70982) (xy 421.424881 -342.668599) (xy 421.395391 -342.622714)
			(xy 421.372731 -342.573098) (xy 421.357363 -342.520763) (xy 421.3496 -342.466773) (xy 419.866896 -342.466773)
			(xy 419.859134 -342.520761) (xy 419.843766 -342.573096) (xy 419.821107 -342.622711) (xy 419.791616 -342.668595)
			(xy 419.755896 -342.709816) (xy 419.714673 -342.745533) (xy 419.668786 -342.77502) (xy 419.61917 -342.797676)
			(xy 419.566834 -342.81304) (xy 419.512844 -342.820798) (xy 419.485572 -342.82126) (xy 418.621972 -342.82126)
			(xy 418.594704 -342.820776) (xy 418.540723 -342.813011) (xy 418.488396 -342.797643) (xy 418.43879 -342.774985)
			(xy 418.392912 -342.745498) (xy 418.351697 -342.709783) (xy 418.315985 -342.668566) (xy 418.286502 -342.622686)
			(xy 418.263847 -342.573077) (xy 418.248483 -342.52075) (xy 418.240722 -342.466768) (xy 416.757874 -342.466768)
			(xy 416.757874 -342.466769) (xy 416.750112 -342.520751) (xy 416.734748 -342.573079) (xy 416.712092 -342.622688)
			(xy 416.682608 -342.668568) (xy 416.646894 -342.709786) (xy 416.605678 -342.745501) (xy 416.559799 -342.774987)
			(xy 416.510191 -342.797643) (xy 416.457863 -342.81301) (xy 416.403881 -342.820773) (xy 416.376612 -342.82126)
			(xy 415.513012 -342.82126) (xy 415.48574 -342.820801) (xy 415.431752 -342.813041) (xy 415.379417 -342.797675)
			(xy 415.329803 -342.775018) (xy 415.283917 -342.745531) (xy 415.242695 -342.709813) (xy 415.206976 -342.668593)
			(xy 415.177488 -342.622708) (xy 415.154829 -342.573094) (xy 415.139462 -342.52076) (xy 415.1317 -342.466772)
			(xy 413.648996 -342.466772) (xy 413.648996 -342.466773) (xy 413.641233 -342.520764) (xy 413.625864 -342.5731)
			(xy 413.603203 -342.622716) (xy 413.573712 -342.668602) (xy 413.537989 -342.709823) (xy 413.496763 -342.74554)
			(xy 413.450874 -342.775026) (xy 413.401255 -342.797681) (xy 413.348917 -342.813043) (xy 413.294925 -342.8208)
			(xy 413.267652 -342.82126) (xy 412.404052 -342.82126) (xy 412.376785 -342.820774) (xy 412.322806 -342.813007)
			(xy 412.270482 -342.797637) (xy 412.220878 -342.774978) (xy 412.175002 -342.745491) (xy 412.13379 -342.709776)
			(xy 412.09808 -342.668559) (xy 412.068599 -342.62268) (xy 412.045946 -342.573073) (xy 412.030583 -342.520747)
			(xy 412.022822 -342.466767) (xy 411.056796 -342.466767) (xy 411.05493 -342.490764) (xy 411.043062 -342.540796)
			(xy 411.023601 -342.58839) (xy 410.997014 -342.632403) (xy 410.963941 -342.671775) (xy 410.925178 -342.705559)
			(xy 410.903674 -342.71966) (xy 410.902404 -342.720422) (xy 410.898848 -342.723978) (xy 410.890974 -342.734646)
			(xy 410.879544 -342.754966) (xy 410.874718 -342.76665) (xy 410.87294 -342.780112) (xy 410.87294 -345.124532)
			(xy 410.874718 -345.137994) (xy 410.879544 -345.149678) (xy 410.890974 -345.169998) (xy 410.898848 -345.180666)
			(xy 410.902404 -345.184222) (xy 410.903674 -345.184984) (xy 410.925172 -345.199088) (xy 410.963928 -345.23287)
			(xy 410.996995 -345.27224) (xy 411.023575 -345.316249) (xy 411.043031 -345.363839) (xy 411.054893 -345.413866)
			(xy 411.058876 -345.465125) (xy 411.056755 -345.492364) (xy 412.02287 -345.492364) (xy 412.02287 -345.437836)
			(xy 412.03063 -345.383863) (xy 412.045991 -345.331544) (xy 412.068641 -345.281943) (xy 412.098119 -345.23607)
			(xy 412.133824 -345.194858) (xy 412.175031 -345.159147) (xy 412.220901 -345.129664) (xy 412.270499 -345.107008)
			(xy 412.322816 -345.09164) (xy 412.376788 -345.083874) (xy 412.404052 -345.083384) (xy 413.267652 -345.083384)
			(xy 413.294929 -345.083752) (xy 413.348927 -345.09151) (xy 413.401272 -345.106874) (xy 413.450897 -345.129531)
			(xy 413.496792 -345.159021) (xy 413.538023 -345.194743) (xy 413.57375 -345.235969) (xy 413.603246 -345.281861)
			(xy 413.625909 -345.331483) (xy 413.64128 -345.383826) (xy 413.649044 -345.437824) (xy 413.649044 -345.492368)
			(xy 415.131747 -345.492368) (xy 415.131747 -345.437832) (xy 415.139509 -345.38385) (xy 415.154874 -345.331523)
			(xy 415.17753 -345.281915) (xy 415.207015 -345.236036) (xy 415.242729 -345.194821) (xy 415.283946 -345.159108)
			(xy 415.329826 -345.129624) (xy 415.379434 -345.10697) (xy 415.431762 -345.091606) (xy 415.485744 -345.083847)
			(xy 415.513012 -345.083384) (xy 416.376612 -345.083384) (xy 416.403884 -345.083779) (xy 416.457873 -345.091543)
			(xy 416.510207 -345.106912) (xy 416.559822 -345.129571) (xy 416.605707 -345.159061) (xy 416.646928 -345.194781)
			(xy 416.682646 -345.236003) (xy 416.712135 -345.281889) (xy 416.734793 -345.331504) (xy 416.750159 -345.383839)
			(xy 416.757921 -345.437828) (xy 416.757921 -345.492365) (xy 418.24077 -345.492365) (xy 418.24077 -345.437835)
			(xy 418.24853 -345.383861) (xy 418.263892 -345.33154) (xy 418.286544 -345.281937) (xy 418.316023 -345.236063)
			(xy 418.351731 -345.194851) (xy 418.392941 -345.15914) (xy 418.438813 -345.129657) (xy 418.488413 -345.107002)
			(xy 418.540733 -345.091636) (xy 418.594707 -345.083872) (xy 418.621972 -345.083384) (xy 419.485572 -345.083384)
			(xy 419.512848 -345.083754) (xy 419.566844 -345.091514) (xy 419.619186 -345.106879) (xy 419.668809 -345.129538)
			(xy 419.714702 -345.159028) (xy 419.75593 -345.19475) (xy 419.791655 -345.235976) (xy 419.821149 -345.281866)
			(xy 419.843811 -345.331487) (xy 419.859181 -345.383829) (xy 419.866944 -345.437824) (xy 419.866944 -345.492369)
			(xy 421.349647 -345.492369) (xy 421.349647 -345.437831) (xy 421.35741 -345.383848) (xy 421.372776 -345.331519)
			(xy 421.395433 -345.281909) (xy 421.42492 -345.23603) (xy 421.460636 -345.194814) (xy 421.501855 -345.159101)
			(xy 421.547738 -345.129617) (xy 421.597349 -345.106964) (xy 421.649679 -345.091603) (xy 421.703663 -345.083845)
			(xy 421.730932 -345.083384) (xy 422.594532 -345.083384) (xy 422.621803 -345.083781) (xy 422.67579 -345.091547)
			(xy 422.728122 -345.106917) (xy 422.777734 -345.129578) (xy 422.823616 -345.159068) (xy 422.864835 -345.194788)
			(xy 422.900551 -345.236009) (xy 422.930038 -345.281894) (xy 422.952694 -345.331508) (xy 422.96806 -345.383842)
			(xy 422.975822 -345.437829) (xy 422.975822 -345.492366) (xy 424.45867 -345.492366) (xy 424.45867 -345.437834)
			(xy 424.466431 -345.383858) (xy 424.481794 -345.331535) (xy 424.504447 -345.281932) (xy 424.533928 -345.236057)
			(xy 424.569638 -345.194844) (xy 424.61085 -345.159133) (xy 424.656725 -345.129651) (xy 424.706328 -345.106997)
			(xy 424.75865 -345.091633) (xy 424.812626 -345.083871) (xy 424.839892 -345.083384) (xy 425.703492 -345.083384)
			(xy 425.730767 -345.083755) (xy 425.784761 -345.091517) (xy 425.837101 -345.106885) (xy 425.886721 -345.129544)
			(xy 425.932611 -345.159035) (xy 425.973837 -345.194757) (xy 426.00956 -345.235982) (xy 426.039052 -345.281872)
			(xy 426.061713 -345.331492) (xy 426.077081 -345.383831) (xy 426.084844 -345.437825) (xy 426.084844 -345.492364)
			(xy 427.56767 -345.492364) (xy 427.56767 -345.437836) (xy 427.57543 -345.383863) (xy 427.590791 -345.331544)
			(xy 427.613441 -345.281943) (xy 427.642919 -345.23607) (xy 427.678624 -345.194858) (xy 427.719831 -345.159147)
			(xy 427.765701 -345.129664) (xy 427.815299 -345.107008) (xy 427.867616 -345.09164) (xy 427.921588 -345.083874)
			(xy 427.948852 -345.083384) (xy 428.812452 -345.083384) (xy 428.839729 -345.083752) (xy 428.893727 -345.09151)
			(xy 428.946072 -345.106874) (xy 428.995697 -345.129531) (xy 429.041592 -345.159021) (xy 429.082823 -345.194743)
			(xy 429.11855 -345.235969) (xy 429.148046 -345.281861) (xy 429.170709 -345.331483) (xy 429.18608 -345.383826)
			(xy 429.193844 -345.437824) (xy 429.193844 -345.492368) (xy 430.676547 -345.492368) (xy 430.676547 -345.437832)
			(xy 430.684309 -345.38385) (xy 430.699674 -345.331523) (xy 430.72233 -345.281915) (xy 430.751815 -345.236036)
			(xy 430.787529 -345.194821) (xy 430.828746 -345.159108) (xy 430.874626 -345.129624) (xy 430.924234 -345.10697)
			(xy 430.976562 -345.091606) (xy 431.030544 -345.083847) (xy 431.057812 -345.083384) (xy 431.921412 -345.083384)
			(xy 431.948684 -345.083779) (xy 432.002673 -345.091543) (xy 432.055007 -345.106912) (xy 432.104622 -345.129571)
			(xy 432.150507 -345.159061) (xy 432.191728 -345.194781) (xy 432.227446 -345.236003) (xy 432.256935 -345.281889)
			(xy 432.279593 -345.331504) (xy 432.294959 -345.383839) (xy 432.302721 -345.437828) (xy 432.302721 -345.492365)
			(xy 433.78557 -345.492365) (xy 433.78557 -345.437835) (xy 433.79333 -345.383861) (xy 433.808692 -345.33154)
			(xy 433.831344 -345.281937) (xy 433.860823 -345.236063) (xy 433.896531 -345.194851) (xy 433.937741 -345.15914)
			(xy 433.983613 -345.129657) (xy 434.033213 -345.107002) (xy 434.085533 -345.091636) (xy 434.139507 -345.083872)
			(xy 434.166772 -345.083384) (xy 435.030372 -345.083384) (xy 435.057648 -345.083754) (xy 435.111644 -345.091514)
			(xy 435.163986 -345.106879) (xy 435.213609 -345.129538) (xy 435.259502 -345.159028) (xy 435.30073 -345.19475)
			(xy 435.336455 -345.235976) (xy 435.365949 -345.281866) (xy 435.388611 -345.331487) (xy 435.403981 -345.383829)
			(xy 435.411744 -345.437824) (xy 435.411744 -345.492369) (xy 436.894447 -345.492369) (xy 436.894447 -345.437831)
			(xy 436.90221 -345.383848) (xy 436.917576 -345.331519) (xy 436.940233 -345.281909) (xy 436.96972 -345.23603)
			(xy 437.005436 -345.194814) (xy 437.046655 -345.159101) (xy 437.092538 -345.129617) (xy 437.142149 -345.106964)
			(xy 437.194479 -345.091603) (xy 437.248463 -345.083845) (xy 437.275732 -345.083384) (xy 438.139332 -345.083384)
			(xy 438.166603 -345.083781) (xy 438.22059 -345.091547) (xy 438.272922 -345.106917) (xy 438.322534 -345.129578)
			(xy 438.368416 -345.159068) (xy 438.409635 -345.194788) (xy 438.445351 -345.236009) (xy 438.474838 -345.281894)
			(xy 438.497494 -345.331508) (xy 438.51286 -345.383842) (xy 438.520622 -345.437829) (xy 438.520622 -345.492366)
			(xy 440.00347 -345.492366) (xy 440.00347 -345.437834) (xy 440.011231 -345.383858) (xy 440.026594 -345.331535)
			(xy 440.049247 -345.281932) (xy 440.078728 -345.236057) (xy 440.114438 -345.194844) (xy 440.15565 -345.159133)
			(xy 440.201525 -345.129651) (xy 440.251128 -345.106997) (xy 440.30345 -345.091633) (xy 440.357426 -345.083871)
			(xy 440.384692 -345.083384) (xy 441.248292 -345.083384) (xy 441.275567 -345.083755) (xy 441.329561 -345.091517)
			(xy 441.381901 -345.106885) (xy 441.431521 -345.129544) (xy 441.477411 -345.159035) (xy 441.518637 -345.194757)
			(xy 441.55436 -345.235982) (xy 441.583852 -345.281872) (xy 441.606513 -345.331492) (xy 441.621881 -345.383831)
			(xy 441.629644 -345.437825) (xy 441.629644 -345.492375) (xy 441.621881 -345.546369) (xy 441.606513 -345.598708)
			(xy 441.583852 -345.648328) (xy 441.55436 -345.694218) (xy 441.518637 -345.735443) (xy 441.477411 -345.771165)
			(xy 441.431521 -345.800656) (xy 441.381901 -345.823315) (xy 441.329561 -345.838683) (xy 441.275567 -345.846445)
			(xy 441.248292 -345.846908) (xy 440.384692 -345.846908) (xy 440.357426 -345.846329) (xy 440.30345 -345.838567)
			(xy 440.251128 -345.823203) (xy 440.201525 -345.800549) (xy 440.15565 -345.771067) (xy 440.114438 -345.735356)
			(xy 440.078728 -345.694143) (xy 440.049247 -345.648268) (xy 440.026594 -345.598665) (xy 440.011231 -345.546342)
			(xy 440.00347 -345.492366) (xy 438.520622 -345.492366) (xy 438.520622 -345.492371) (xy 438.51286 -345.546358)
			(xy 438.497494 -345.598692) (xy 438.474838 -345.648306) (xy 438.445351 -345.694191) (xy 438.409635 -345.735412)
			(xy 438.368416 -345.771132) (xy 438.322534 -345.800622) (xy 438.272922 -345.823283) (xy 438.22059 -345.838653)
			(xy 438.166603 -345.846419) (xy 438.139332 -345.846908) (xy 437.275732 -345.846908) (xy 437.248463 -345.846355)
			(xy 437.194479 -345.838597) (xy 437.142149 -345.823236) (xy 437.092538 -345.800583) (xy 437.046655 -345.771099)
			(xy 437.005436 -345.735386) (xy 436.96972 -345.69417) (xy 436.940233 -345.648291) (xy 436.917576 -345.598681)
			(xy 436.90221 -345.546352) (xy 436.894447 -345.492369) (xy 435.411744 -345.492369) (xy 435.411744 -345.492376)
			(xy 435.403981 -345.546371) (xy 435.388611 -345.598713) (xy 435.365949 -345.648334) (xy 435.336455 -345.694224)
			(xy 435.30073 -345.73545) (xy 435.259502 -345.771172) (xy 435.213609 -345.800662) (xy 435.163986 -345.823321)
			(xy 435.111644 -345.838686) (xy 435.057648 -345.846446) (xy 435.030372 -345.846908) (xy 434.166772 -345.846908)
			(xy 434.139507 -345.846328) (xy 434.085533 -345.838564) (xy 434.033213 -345.823198) (xy 433.983613 -345.800543)
			(xy 433.937741 -345.77106) (xy 433.896531 -345.735349) (xy 433.860823 -345.694137) (xy 433.831344 -345.648263)
			(xy 433.808692 -345.59866) (xy 433.79333 -345.546339) (xy 433.78557 -345.492365) (xy 432.302721 -345.492365)
			(xy 432.302721 -345.492372) (xy 432.294959 -345.546361) (xy 432.279593 -345.598696) (xy 432.256935 -345.648311)
			(xy 432.227446 -345.694197) (xy 432.191728 -345.735419) (xy 432.150507 -345.771139) (xy 432.104622 -345.800629)
			(xy 432.055007 -345.823288) (xy 432.002673 -345.838657) (xy 431.948684 -345.846421) (xy 431.921412 -345.846908)
			(xy 431.057812 -345.846908) (xy 431.030544 -345.846353) (xy 430.976562 -345.838594) (xy 430.924234 -345.82323)
			(xy 430.874626 -345.800576) (xy 430.828746 -345.771092) (xy 430.787529 -345.735379) (xy 430.751815 -345.694164)
			(xy 430.72233 -345.648285) (xy 430.699674 -345.598677) (xy 430.684309 -345.54635) (xy 430.676547 -345.492368)
			(xy 429.193844 -345.492368) (xy 429.193844 -345.492376) (xy 429.18608 -345.546374) (xy 429.170709 -345.598717)
			(xy 429.148046 -345.648339) (xy 429.11855 -345.694231) (xy 429.082823 -345.735457) (xy 429.041592 -345.771179)
			(xy 428.995697 -345.800669) (xy 428.946072 -345.823326) (xy 428.893727 -345.83869) (xy 428.839729 -345.846448)
			(xy 428.812452 -345.846908) (xy 427.948852 -345.846908) (xy 427.921588 -345.846326) (xy 427.867616 -345.83856)
			(xy 427.815299 -345.823192) (xy 427.765701 -345.800536) (xy 427.719831 -345.771053) (xy 427.678624 -345.735342)
			(xy 427.642919 -345.69413) (xy 427.613441 -345.648257) (xy 427.590791 -345.598656) (xy 427.57543 -345.546337)
			(xy 427.56767 -345.492364) (xy 426.084844 -345.492364) (xy 426.084844 -345.492375) (xy 426.077081 -345.546369)
			(xy 426.061713 -345.598708) (xy 426.039052 -345.648328) (xy 426.00956 -345.694218) (xy 425.973837 -345.735443)
			(xy 425.932611 -345.771165) (xy 425.886721 -345.800656) (xy 425.837101 -345.823315) (xy 425.784761 -345.838683)
			(xy 425.730767 -345.846445) (xy 425.703492 -345.846908) (xy 424.839892 -345.846908) (xy 424.812626 -345.846329)
			(xy 424.75865 -345.838567) (xy 424.706328 -345.823203) (xy 424.656725 -345.800549) (xy 424.61085 -345.771067)
			(xy 424.569638 -345.735356) (xy 424.533928 -345.694143) (xy 424.504447 -345.648268) (xy 424.481794 -345.598665)
			(xy 424.466431 -345.546342) (xy 424.45867 -345.492366) (xy 422.975822 -345.492366) (xy 422.975822 -345.492371)
			(xy 422.96806 -345.546358) (xy 422.952694 -345.598692) (xy 422.930038 -345.648306) (xy 422.900551 -345.694191)
			(xy 422.864835 -345.735412) (xy 422.823616 -345.771132) (xy 422.777734 -345.800622) (xy 422.728122 -345.823283)
			(xy 422.67579 -345.838653) (xy 422.621803 -345.846419) (xy 422.594532 -345.846908) (xy 421.730932 -345.846908)
			(xy 421.703663 -345.846355) (xy 421.649679 -345.838597) (xy 421.597349 -345.823236) (xy 421.547738 -345.800583)
			(xy 421.501855 -345.771099) (xy 421.460636 -345.735386) (xy 421.42492 -345.69417) (xy 421.395433 -345.648291)
			(xy 421.372776 -345.598681) (xy 421.35741 -345.546352) (xy 421.349647 -345.492369) (xy 419.866944 -345.492369)
			(xy 419.866944 -345.492376) (xy 419.859181 -345.546371) (xy 419.843811 -345.598713) (xy 419.821149 -345.648334)
			(xy 419.791655 -345.694224) (xy 419.75593 -345.73545) (xy 419.714702 -345.771172) (xy 419.668809 -345.800662)
			(xy 419.619186 -345.823321) (xy 419.566844 -345.838686) (xy 419.512848 -345.846446) (xy 419.485572 -345.846908)
			(xy 418.621972 -345.846908) (xy 418.594707 -345.846328) (xy 418.540733 -345.838564) (xy 418.488413 -345.823198)
			(xy 418.438813 -345.800543) (xy 418.392941 -345.77106) (xy 418.351731 -345.735349) (xy 418.316023 -345.694137)
			(xy 418.286544 -345.648263) (xy 418.263892 -345.59866) (xy 418.24853 -345.546339) (xy 418.24077 -345.492365)
			(xy 416.757921 -345.492365) (xy 416.757921 -345.492372) (xy 416.750159 -345.546361) (xy 416.734793 -345.598696)
			(xy 416.712135 -345.648311) (xy 416.682646 -345.694197) (xy 416.646928 -345.735419) (xy 416.605707 -345.771139)
			(xy 416.559822 -345.800629) (xy 416.510207 -345.823288) (xy 416.457873 -345.838657) (xy 416.403884 -345.846421)
			(xy 416.376612 -345.846908) (xy 415.513012 -345.846908) (xy 415.485744 -345.846353) (xy 415.431762 -345.838594)
			(xy 415.379434 -345.82323) (xy 415.329826 -345.800576) (xy 415.283946 -345.771092) (xy 415.242729 -345.735379)
			(xy 415.207015 -345.694164) (xy 415.17753 -345.648285) (xy 415.154874 -345.598677) (xy 415.139509 -345.54635)
			(xy 415.131747 -345.492368) (xy 413.649044 -345.492368) (xy 413.649044 -345.492376) (xy 413.64128 -345.546374)
			(xy 413.625909 -345.598717) (xy 413.603246 -345.648339) (xy 413.57375 -345.694231) (xy 413.538023 -345.735457)
			(xy 413.496792 -345.771179) (xy 413.450897 -345.800669) (xy 413.401272 -345.823326) (xy 413.348927 -345.83869)
			(xy 413.294929 -345.846448) (xy 413.267652 -345.846908) (xy 412.404052 -345.846908) (xy 412.376788 -345.846326)
			(xy 412.322816 -345.83856) (xy 412.270499 -345.823192) (xy 412.220901 -345.800536) (xy 412.175031 -345.771053)
			(xy 412.133824 -345.735342) (xy 412.098119 -345.69413) (xy 412.068641 -345.648257) (xy 412.045991 -345.598656)
			(xy 412.03063 -345.546337) (xy 412.02287 -345.492364) (xy 411.056755 -345.492364) (xy 411.054885 -345.516383)
			(xy 411.043016 -345.566407) (xy 411.023553 -345.613995) (xy 410.996966 -345.658) (xy 410.963894 -345.697365)
			(xy 410.925133 -345.731142) (xy 410.903674 -345.745308) (xy 410.902404 -345.74607) (xy 410.898848 -345.749626)
			(xy 410.890974 -345.760294) (xy 410.879544 -345.780614) (xy 410.874718 -345.792298) (xy 410.87294 -345.80576)
			(xy 410.87294 -346.878148) (xy 410.872507 -346.888213) (xy 410.864773 -346.906799) (xy 410.857954 -346.914216)
			(xy 409.894786 -347.877384) (xy 409.891263 -347.881113) (xy 409.885628 -347.889685) (xy 409.88361 -347.894402)
			(xy 409.880054 -347.903038) (xy 409.880054 -348.177358) (xy 409.880308 -348.182438) (xy 409.88103 -348.188156)
			(xy 409.884745 -348.199064) (xy 409.887674 -348.204028) (xy 410.158692 -348.204028) (xy 410.185956 -348.204492)
			(xy 410.239928 -348.212254) (xy 410.292245 -348.227623) (xy 410.341841 -348.250284) (xy 410.387705 -348.279776)
			(xy 410.428902 -348.315498) (xy 410.464593 -348.356721) (xy 410.494051 -348.402607) (xy 410.516676 -348.45222)
			(xy 410.532006 -348.504548) (xy 410.539728 -348.558526) (xy 410.5402 -348.58579) (xy 410.5402 -348.595696)
			(xy 410.540454 -348.609666) (xy 410.540396 -348.613068) (xy 412.022814 -348.613068) (xy 412.022814 -348.558532)
			(xy 412.030575 -348.504551) (xy 412.045938 -348.452224) (xy 412.068592 -348.402616) (xy 412.098074 -348.356736)
			(xy 412.133785 -348.315519) (xy 412.174998 -348.279803) (xy 412.220874 -348.250315) (xy 412.270479 -348.227655)
			(xy 412.322804 -348.212285) (xy 412.376784 -348.204518) (xy 412.404052 -348.204028) (xy 413.267652 -348.204028)
			(xy 413.294925 -348.204508) (xy 413.348915 -348.212265) (xy 413.401252 -348.227626) (xy 413.45087 -348.250281)
			(xy 413.496759 -348.279766) (xy 413.537983 -348.315483) (xy 413.573705 -348.356703) (xy 413.603196 -348.402588)
			(xy 413.625857 -348.452203) (xy 413.641225 -348.504538) (xy 413.648988 -348.558528) (xy 413.648988 -348.613072)
			(xy 415.131692 -348.613072) (xy 415.131692 -348.558528) (xy 415.139454 -348.504538) (xy 415.154821 -348.452203)
			(xy 415.177481 -348.402588) (xy 415.20697 -348.356703) (xy 415.24269 -348.315481) (xy 415.283912 -348.279763)
			(xy 415.329799 -348.250275) (xy 415.379415 -348.227617) (xy 415.43175 -348.212252) (xy 415.48574 -348.204491)
			(xy 415.513012 -348.204028) (xy 416.376612 -348.204028) (xy 416.40388 -348.204535) (xy 416.457861 -348.212298)
			(xy 416.510188 -348.227664) (xy 416.559795 -348.25032) (xy 416.605673 -348.279806) (xy 416.646888 -348.31552)
			(xy 416.682601 -348.356736) (xy 416.712085 -348.402615) (xy 416.73474 -348.452224) (xy 416.750104 -348.504551)
			(xy 416.757866 -348.558532) (xy 416.757866 -348.613068) (xy 416.757866 -348.613069) (xy 418.240714 -348.613069)
			(xy 418.240714 -348.558531) (xy 418.248476 -348.504549) (xy 418.26384 -348.45222) (xy 418.286495 -348.40261)
			(xy 418.315979 -348.35673) (xy 418.351692 -348.315512) (xy 418.392907 -348.279795) (xy 418.438786 -348.250308)
			(xy 418.488394 -348.22765) (xy 418.540721 -348.212281) (xy 418.594703 -348.204516) (xy 418.621972 -348.204028)
			(xy 419.485572 -348.204028) (xy 419.512844 -348.20451) (xy 419.566832 -348.212268) (xy 419.619167 -348.227632)
			(xy 419.668782 -348.250287) (xy 419.714668 -348.279773) (xy 419.75589 -348.31549) (xy 419.79161 -348.356709)
			(xy 419.821099 -348.402593) (xy 419.843759 -348.452207) (xy 419.859126 -348.504541) (xy 419.866888 -348.558528)
			(xy 419.866888 -348.613072) (xy 419.866888 -348.613073) (xy 421.349592 -348.613073) (xy 421.349592 -348.558527)
			(xy 421.357355 -348.504536) (xy 421.372723 -348.452199) (xy 421.395384 -348.402583) (xy 421.424875 -348.356696)
			(xy 421.460597 -348.315474) (xy 421.501822 -348.279756) (xy 421.547711 -348.250268) (xy 421.597329 -348.227612)
			(xy 421.649667 -348.212248) (xy 421.703659 -348.204489) (xy 421.730932 -348.204028) (xy 422.594532 -348.204028)
			(xy 422.621799 -348.204537) (xy 422.675778 -348.212302) (xy 422.728102 -348.227669) (xy 422.777707 -348.250327)
			(xy 422.823583 -348.279813) (xy 422.864795 -348.315527) (xy 422.900506 -348.356743) (xy 422.929988 -348.402621)
			(xy 422.952642 -348.452228) (xy 422.968005 -348.504553) (xy 422.975766 -348.558533) (xy 422.975766 -348.613067)
			(xy 422.975766 -348.61307) (xy 424.458614 -348.61307) (xy 424.458614 -348.55853) (xy 424.466376 -348.504546)
			(xy 424.481741 -348.452216) (xy 424.504398 -348.402605) (xy 424.533884 -348.356723) (xy 424.569599 -348.315505)
			(xy 424.610817 -348.279788) (xy 424.656698 -348.250301) (xy 424.706308 -348.227644) (xy 424.758638 -348.212278)
			(xy 424.812622 -348.204515) (xy 424.839892 -348.204028) (xy 425.703492 -348.204028) (xy 425.730763 -348.204511)
			(xy 425.784749 -348.212272) (xy 425.837081 -348.227637) (xy 425.886694 -348.250294) (xy 425.932578 -348.27978)
			(xy 425.973798 -348.315497) (xy 426.009515 -348.356716) (xy 426.039003 -348.402599) (xy 426.06166 -348.452211)
			(xy 426.077026 -348.504543) (xy 426.084789 -348.558529) (xy 426.084789 -348.613068) (xy 427.567614 -348.613068)
			(xy 427.567614 -348.558532) (xy 427.575375 -348.504551) (xy 427.590738 -348.452224) (xy 427.613392 -348.402616)
			(xy 427.642874 -348.356736) (xy 427.678585 -348.315519) (xy 427.719798 -348.279803) (xy 427.765674 -348.250315)
			(xy 427.815279 -348.227655) (xy 427.867604 -348.212285) (xy 427.921584 -348.204518) (xy 427.948852 -348.204028)
			(xy 428.812452 -348.204028) (xy 428.839725 -348.204508) (xy 428.893715 -348.212265) (xy 428.946052 -348.227626)
			(xy 428.99567 -348.250281) (xy 429.041559 -348.279766) (xy 429.082783 -348.315483) (xy 429.118505 -348.356703)
			(xy 429.147996 -348.402588) (xy 429.170657 -348.452203) (xy 429.186025 -348.504538) (xy 429.193788 -348.558528)
			(xy 429.193788 -348.613072) (xy 430.676492 -348.613072) (xy 430.676492 -348.558528) (xy 430.684254 -348.504538)
			(xy 430.699621 -348.452203) (xy 430.722281 -348.402588) (xy 430.75177 -348.356703) (xy 430.78749 -348.315481)
			(xy 430.828712 -348.279763) (xy 430.874599 -348.250275) (xy 430.924215 -348.227617) (xy 430.97655 -348.212252)
			(xy 431.03054 -348.204491) (xy 431.057812 -348.204028) (xy 431.921412 -348.204028) (xy 431.94868 -348.204535)
			(xy 432.002661 -348.212298) (xy 432.054988 -348.227664) (xy 432.104595 -348.25032) (xy 432.150473 -348.279806)
			(xy 432.191688 -348.31552) (xy 432.227401 -348.356736) (xy 432.256885 -348.402615) (xy 432.27954 -348.452224)
			(xy 432.294904 -348.504551) (xy 432.302666 -348.558532) (xy 432.302666 -348.613068) (xy 432.302666 -348.613069)
			(xy 433.785514 -348.613069) (xy 433.785514 -348.558531) (xy 433.793276 -348.504549) (xy 433.80864 -348.45222)
			(xy 433.831295 -348.40261) (xy 433.860779 -348.35673) (xy 433.896492 -348.315512) (xy 433.937707 -348.279795)
			(xy 433.983586 -348.250308) (xy 434.033194 -348.22765) (xy 434.085521 -348.212281) (xy 434.139503 -348.204516)
			(xy 434.166772 -348.204028) (xy 435.030372 -348.204028) (xy 435.057644 -348.20451) (xy 435.111632 -348.212268)
			(xy 435.163967 -348.227632) (xy 435.213582 -348.250287) (xy 435.259468 -348.279773) (xy 435.30069 -348.31549)
			(xy 435.33641 -348.356709) (xy 435.365899 -348.402593) (xy 435.388559 -348.452207) (xy 435.403926 -348.504541)
			(xy 435.411688 -348.558528) (xy 435.411688 -348.613072) (xy 435.411688 -348.613073) (xy 436.894392 -348.613073)
			(xy 436.894392 -348.558527) (xy 436.902155 -348.504536) (xy 436.917523 -348.452199) (xy 436.940184 -348.402583)
			(xy 436.969675 -348.356696) (xy 437.005397 -348.315474) (xy 437.046622 -348.279756) (xy 437.092511 -348.250268)
			(xy 437.142129 -348.227612) (xy 437.194467 -348.212248) (xy 437.248459 -348.204489) (xy 437.275732 -348.204028)
			(xy 438.139332 -348.204028) (xy 438.166599 -348.204537) (xy 438.220578 -348.212302) (xy 438.272902 -348.227669)
			(xy 438.322507 -348.250327) (xy 438.368383 -348.279813) (xy 438.409595 -348.315527) (xy 438.445306 -348.356743)
			(xy 438.474788 -348.402621) (xy 438.497442 -348.452228) (xy 438.512805 -348.504553) (xy 438.520566 -348.558533)
			(xy 438.520566 -348.613067) (xy 438.520566 -348.61307) (xy 440.003414 -348.61307) (xy 440.003414 -348.55853)
			(xy 440.011176 -348.504546) (xy 440.026541 -348.452216) (xy 440.049198 -348.402605) (xy 440.078684 -348.356723)
			(xy 440.114399 -348.315505) (xy 440.155617 -348.279788) (xy 440.201498 -348.250301) (xy 440.251108 -348.227644)
			(xy 440.303438 -348.212278) (xy 440.357422 -348.204515) (xy 440.384692 -348.204028) (xy 441.248292 -348.204028)
			(xy 441.275563 -348.204511) (xy 441.329549 -348.212272) (xy 441.381881 -348.227637) (xy 441.431494 -348.250294)
			(xy 441.477378 -348.27978) (xy 441.518598 -348.315497) (xy 441.554315 -348.356716) (xy 441.583803 -348.402599)
			(xy 441.60646 -348.452211) (xy 441.621826 -348.504543) (xy 441.629589 -348.558529) (xy 441.629589 -348.613071)
			(xy 441.621826 -348.667057) (xy 441.60646 -348.719389) (xy 441.583803 -348.769001) (xy 441.554315 -348.814884)
			(xy 441.518598 -348.856103) (xy 441.477378 -348.89182) (xy 441.431494 -348.921306) (xy 441.381881 -348.943963)
			(xy 441.329549 -348.959328) (xy 441.275563 -348.967089) (xy 441.248292 -348.967552) (xy 440.384692 -348.967552)
			(xy 440.357422 -348.967085) (xy 440.303438 -348.959322) (xy 440.251108 -348.943956) (xy 440.201498 -348.921299)
			(xy 440.155617 -348.891812) (xy 440.114399 -348.856095) (xy 440.078684 -348.814877) (xy 440.049198 -348.768995)
			(xy 440.026541 -348.719384) (xy 440.011176 -348.667054) (xy 440.003414 -348.61307) (xy 438.520566 -348.61307)
			(xy 438.512805 -348.667047) (xy 438.497442 -348.719372) (xy 438.474788 -348.768979) (xy 438.445306 -348.814857)
			(xy 438.409595 -348.856073) (xy 438.368383 -348.891787) (xy 438.322507 -348.921273) (xy 438.272902 -348.943931)
			(xy 438.220578 -348.959298) (xy 438.166599 -348.967063) (xy 438.139332 -348.967552) (xy 437.275732 -348.967552)
			(xy 437.248459 -348.967111) (xy 437.194467 -348.959352) (xy 437.142129 -348.943988) (xy 437.092511 -348.921332)
			(xy 437.046622 -348.891844) (xy 437.005397 -348.856126) (xy 436.969675 -348.814904) (xy 436.940184 -348.769017)
			(xy 436.917523 -348.719401) (xy 436.902155 -348.667064) (xy 436.894392 -348.613073) (xy 435.411688 -348.613073)
			(xy 435.403926 -348.667059) (xy 435.388559 -348.719393) (xy 435.365899 -348.769007) (xy 435.33641 -348.814891)
			(xy 435.30069 -348.85611) (xy 435.259468 -348.891827) (xy 435.213582 -348.921313) (xy 435.163967 -348.943968)
			(xy 435.111632 -348.959332) (xy 435.057644 -348.96709) (xy 435.030372 -348.967552) (xy 434.166772 -348.967552)
			(xy 434.139503 -348.967084) (xy 434.085521 -348.959319) (xy 434.033194 -348.94395) (xy 433.983586 -348.921292)
			(xy 433.937707 -348.891805) (xy 433.896492 -348.856088) (xy 433.860779 -348.81487) (xy 433.831295 -348.76899)
			(xy 433.80864 -348.71938) (xy 433.793276 -348.667051) (xy 433.785514 -348.613069) (xy 432.302666 -348.613069)
			(xy 432.294904 -348.667049) (xy 432.27954 -348.719376) (xy 432.256885 -348.768985) (xy 432.227401 -348.814864)
			(xy 432.191688 -348.85608) (xy 432.150473 -348.891794) (xy 432.104595 -348.92128) (xy 432.054988 -348.943936)
			(xy 432.002661 -348.959302) (xy 431.94868 -348.967065) (xy 431.921412 -348.967552) (xy 431.057812 -348.967552)
			(xy 431.03054 -348.967109) (xy 430.97655 -348.959348) (xy 430.924215 -348.943983) (xy 430.874599 -348.921325)
			(xy 430.828712 -348.891837) (xy 430.78749 -348.856119) (xy 430.75177 -348.814897) (xy 430.722281 -348.769012)
			(xy 430.699621 -348.719397) (xy 430.684254 -348.667062) (xy 430.676492 -348.613072) (xy 429.193788 -348.613072)
			(xy 429.186025 -348.667062) (xy 429.170657 -348.719397) (xy 429.147996 -348.769012) (xy 429.118505 -348.814897)
			(xy 429.082783 -348.856117) (xy 429.041559 -348.891834) (xy 428.99567 -348.921319) (xy 428.946052 -348.943974)
			(xy 428.893715 -348.959335) (xy 428.839725 -348.967092) (xy 428.812452 -348.967552) (xy 427.948852 -348.967552)
			(xy 427.921584 -348.967082) (xy 427.867604 -348.959315) (xy 427.815279 -348.943945) (xy 427.765674 -348.921285)
			(xy 427.719798 -348.891797) (xy 427.678585 -348.856081) (xy 427.642874 -348.814864) (xy 427.613392 -348.768984)
			(xy 427.590738 -348.719376) (xy 427.575375 -348.667049) (xy 427.567614 -348.613068) (xy 426.084789 -348.613068)
			(xy 426.084789 -348.613071) (xy 426.077026 -348.667057) (xy 426.06166 -348.719389) (xy 426.039003 -348.769001)
			(xy 426.009515 -348.814884) (xy 425.973798 -348.856103) (xy 425.932578 -348.89182) (xy 425.886694 -348.921306)
			(xy 425.837081 -348.943963) (xy 425.784749 -348.959328) (xy 425.730763 -348.967089) (xy 425.703492 -348.967552)
			(xy 424.839892 -348.967552) (xy 424.812622 -348.967085) (xy 424.758638 -348.959322) (xy 424.706308 -348.943956)
			(xy 424.656698 -348.921299) (xy 424.610817 -348.891812) (xy 424.569599 -348.856095) (xy 424.533884 -348.814877)
			(xy 424.504398 -348.768995) (xy 424.481741 -348.719384) (xy 424.466376 -348.667054) (xy 424.458614 -348.61307)
			(xy 422.975766 -348.61307) (xy 422.968005 -348.667047) (xy 422.952642 -348.719372) (xy 422.929988 -348.768979)
			(xy 422.900506 -348.814857) (xy 422.864795 -348.856073) (xy 422.823583 -348.891787) (xy 422.777707 -348.921273)
			(xy 422.728102 -348.943931) (xy 422.675778 -348.959298) (xy 422.621799 -348.967063) (xy 422.594532 -348.967552)
			(xy 421.730932 -348.967552) (xy 421.703659 -348.967111) (xy 421.649667 -348.959352) (xy 421.597329 -348.943988)
			(xy 421.547711 -348.921332) (xy 421.501822 -348.891844) (xy 421.460597 -348.856126) (xy 421.424875 -348.814904)
			(xy 421.395384 -348.769017) (xy 421.372723 -348.719401) (xy 421.357355 -348.667064) (xy 421.349592 -348.613073)
			(xy 419.866888 -348.613073) (xy 419.859126 -348.667059) (xy 419.843759 -348.719393) (xy 419.821099 -348.769007)
			(xy 419.79161 -348.814891) (xy 419.75589 -348.85611) (xy 419.714668 -348.891827) (xy 419.668782 -348.921313)
			(xy 419.619167 -348.943968) (xy 419.566832 -348.959332) (xy 419.512844 -348.96709) (xy 419.485572 -348.967552)
			(xy 418.621972 -348.967552) (xy 418.594703 -348.967084) (xy 418.540721 -348.959319) (xy 418.488394 -348.94395)
			(xy 418.438786 -348.921292) (xy 418.392907 -348.891805) (xy 418.351692 -348.856088) (xy 418.315979 -348.81487)
			(xy 418.286495 -348.76899) (xy 418.26384 -348.71938) (xy 418.248476 -348.667051) (xy 418.240714 -348.613069)
			(xy 416.757866 -348.613069) (xy 416.750104 -348.667049) (xy 416.73474 -348.719376) (xy 416.712085 -348.768985)
			(xy 416.682601 -348.814864) (xy 416.646888 -348.85608) (xy 416.605673 -348.891794) (xy 416.559795 -348.92128)
			(xy 416.510188 -348.943936) (xy 416.457861 -348.959302) (xy 416.40388 -348.967065) (xy 416.376612 -348.967552)
			(xy 415.513012 -348.967552) (xy 415.48574 -348.967109) (xy 415.43175 -348.959348) (xy 415.379415 -348.943983)
			(xy 415.329799 -348.921325) (xy 415.283912 -348.891837) (xy 415.24269 -348.856119) (xy 415.20697 -348.814897)
			(xy 415.177481 -348.769012) (xy 415.154821 -348.719397) (xy 415.139454 -348.667062) (xy 415.131692 -348.613072)
			(xy 413.648988 -348.613072) (xy 413.641225 -348.667062) (xy 413.625857 -348.719397) (xy 413.603196 -348.769012)
			(xy 413.573705 -348.814897) (xy 413.537983 -348.856117) (xy 413.496759 -348.891834) (xy 413.45087 -348.921319)
			(xy 413.401252 -348.943974) (xy 413.348915 -348.959335) (xy 413.294925 -348.967092) (xy 413.267652 -348.967552)
			(xy 412.404052 -348.967552) (xy 412.376784 -348.967082) (xy 412.322804 -348.959315) (xy 412.270479 -348.943945)
			(xy 412.220874 -348.921285) (xy 412.174998 -348.891797) (xy 412.133785 -348.856081) (xy 412.098074 -348.814864)
			(xy 412.068592 -348.768984) (xy 412.045938 -348.719376) (xy 412.030575 -348.667049) (xy 412.022814 -348.613068)
			(xy 410.540396 -348.613068) (xy 410.539993 -348.636938) (xy 410.532235 -348.690929) (xy 410.516871 -348.743265)
			(xy 410.494215 -348.792882) (xy 410.464729 -348.838769) (xy 410.429011 -348.879993) (xy 410.38779 -348.915713)
			(xy 410.341905 -348.945203) (xy 410.292289 -348.967862) (xy 410.239954 -348.983229) (xy 410.185964 -348.990991)
			(xy 410.158692 -348.991428) (xy 409.930854 -348.991428) (xy 409.920854 -348.991924) (xy 409.902383 -348.999593)
			(xy 409.888251 -349.013745) (xy 409.88061 -349.032228) (xy 409.880054 -349.042228) (xy 409.880054 -351.203006)
			(xy 409.880308 -351.208086) (xy 409.881035 -351.213803) (xy 409.884759 -351.224705) (xy 409.887674 -351.229676)
			(xy 410.158692 -351.229676) (xy 410.185957 -351.230139) (xy 410.239932 -351.237902) (xy 410.292252 -351.25327)
			(xy 410.341851 -351.27593) (xy 410.387719 -351.305421) (xy 410.428921 -351.341142) (xy 410.464617 -351.382365)
			(xy 410.49408 -351.428251) (xy 410.516711 -351.477863) (xy 410.532047 -351.530193) (xy 410.539777 -351.584173)
			(xy 410.5402 -351.611438) (xy 410.5402 -351.621344) (xy 410.540454 -351.635314) (xy 410.540394 -351.638664)
			(xy 412.022862 -351.638664) (xy 412.022862 -351.584136) (xy 412.030622 -351.530162) (xy 412.045983 -351.477841)
			(xy 412.068634 -351.428239) (xy 412.098112 -351.382365) (xy 412.133819 -351.341153) (xy 412.175026 -351.305441)
			(xy 412.220897 -351.275957) (xy 412.270496 -351.2533) (xy 412.322815 -351.237932) (xy 412.376788 -351.230166)
			(xy 412.404052 -351.229676) (xy 413.267652 -351.229676) (xy 413.294928 -351.23006) (xy 413.348925 -351.237818)
			(xy 413.401269 -351.253181) (xy 413.450893 -351.275838) (xy 413.496787 -351.305328) (xy 413.538017 -351.341049)
			(xy 413.573744 -351.382274) (xy 413.603239 -351.428165) (xy 413.625902 -351.477786) (xy 413.641272 -351.530128)
			(xy 413.649036 -351.584124) (xy 413.649036 -351.638669) (xy 415.131739 -351.638669) (xy 415.131739 -351.584131)
			(xy 415.139501 -351.530149) (xy 415.154866 -351.47782) (xy 415.177523 -351.428211) (xy 415.207008 -351.382331)
			(xy 415.242724 -351.341115) (xy 415.283941 -351.305401) (xy 415.329822 -351.275917) (xy 415.379431 -351.253262)
			(xy 415.43176 -351.237899) (xy 415.485743 -351.230139) (xy 415.513012 -351.229676) (xy 416.376612 -351.229676)
			(xy 416.403884 -351.230087) (xy 416.457871 -351.237851) (xy 416.510204 -351.253219) (xy 416.559818 -351.275878)
			(xy 416.605702 -351.305367) (xy 416.646922 -351.341086) (xy 416.68264 -351.382308) (xy 416.712128 -351.428192)
			(xy 416.734785 -351.477807) (xy 416.750151 -351.530141) (xy 416.757914 -351.584128) (xy 416.757914 -351.638665)
			(xy 418.240762 -351.638665) (xy 418.240762 -351.584135) (xy 418.248522 -351.530159) (xy 418.263885 -351.477837)
			(xy 418.286537 -351.428233) (xy 418.316017 -351.382358) (xy 418.351726 -351.341146) (xy 418.392936 -351.305434)
			(xy 418.438809 -351.27595) (xy 418.48841 -351.253295) (xy 418.540731 -351.237928) (xy 418.594707 -351.230164)
			(xy 418.621972 -351.229676) (xy 419.485572 -351.229676) (xy 419.512847 -351.230062) (xy 419.566842 -351.237821)
			(xy 419.619184 -351.253187) (xy 419.668805 -351.275845) (xy 419.714697 -351.305335) (xy 419.755924 -351.341056)
			(xy 419.791648 -351.382281) (xy 419.821142 -351.42817) (xy 419.843803 -351.47779) (xy 419.859173 -351.53013)
			(xy 419.866936 -351.584125) (xy 419.866936 -351.63867) (xy 421.349639 -351.63867) (xy 421.349639 -351.58413)
			(xy 421.357402 -351.530146) (xy 421.372768 -351.477816) (xy 421.395426 -351.428206) (xy 421.424913 -351.382325)
			(xy 421.460631 -351.341108) (xy 421.501851 -351.305394) (xy 421.547734 -351.27591) (xy 421.597346 -351.253257)
			(xy 421.649677 -351.237895) (xy 421.703662 -351.230137) (xy 421.730932 -351.229676) (xy 422.594532 -351.229676)
			(xy 422.621803 -351.230089) (xy 422.675788 -351.237855) (xy 422.728119 -351.253224) (xy 422.77773 -351.275885)
			(xy 422.823612 -351.305374) (xy 422.864829 -351.341093) (xy 422.900545 -351.382314) (xy 422.930031 -351.428198)
			(xy 422.952687 -351.477811) (xy 422.968052 -351.530143) (xy 422.975814 -351.584129) (xy 422.975814 -351.638666)
			(xy 424.458662 -351.638666) (xy 424.458662 -351.584134) (xy 424.466423 -351.530156) (xy 424.481786 -351.477832)
			(xy 424.50444 -351.428228) (xy 424.533922 -351.382352) (xy 424.569633 -351.341138) (xy 424.610845 -351.305427)
			(xy 424.656721 -351.275944) (xy 424.706325 -351.253289) (xy 424.758648 -351.237925) (xy 424.812626 -351.230163)
			(xy 424.839892 -351.229676) (xy 425.703492 -351.229676) (xy 425.730766 -351.230063) (xy 425.784759 -351.237825)
			(xy 425.837098 -351.253192) (xy 425.886717 -351.275851) (xy 425.932606 -351.305342) (xy 425.973832 -351.341063)
			(xy 426.009553 -351.382287) (xy 426.039045 -351.428176) (xy 426.061705 -351.477794) (xy 426.077073 -351.530133)
			(xy 426.084836 -351.584126) (xy 426.084836 -351.638664) (xy 427.567662 -351.638664) (xy 427.567662 -351.584136)
			(xy 427.575422 -351.530162) (xy 427.590783 -351.477841) (xy 427.613434 -351.428239) (xy 427.642912 -351.382365)
			(xy 427.678619 -351.341153) (xy 427.719826 -351.305441) (xy 427.765697 -351.275957) (xy 427.815296 -351.2533)
			(xy 427.867615 -351.237932) (xy 427.921588 -351.230166) (xy 427.948852 -351.229676) (xy 428.812452 -351.229676)
			(xy 428.839728 -351.23006) (xy 428.893725 -351.237818) (xy 428.946069 -351.253181) (xy 428.995693 -351.275838)
			(xy 429.041587 -351.305328) (xy 429.082817 -351.341049) (xy 429.118544 -351.382274) (xy 429.148039 -351.428165)
			(xy 429.170702 -351.477786) (xy 429.186072 -351.530128) (xy 429.193836 -351.584124) (xy 429.193836 -351.638669)
			(xy 430.676539 -351.638669) (xy 430.676539 -351.584131) (xy 430.684301 -351.530149) (xy 430.699666 -351.47782)
			(xy 430.722323 -351.428211) (xy 430.751808 -351.382331) (xy 430.787524 -351.341115) (xy 430.828741 -351.305401)
			(xy 430.874622 -351.275917) (xy 430.924231 -351.253262) (xy 430.97656 -351.237899) (xy 431.030543 -351.230139)
			(xy 431.057812 -351.229676) (xy 431.921412 -351.229676) (xy 431.948684 -351.230087) (xy 432.002671 -351.237851)
			(xy 432.055004 -351.253219) (xy 432.104618 -351.275878) (xy 432.150502 -351.305367) (xy 432.191722 -351.341086)
			(xy 432.22744 -351.382308) (xy 432.256928 -351.428192) (xy 432.279585 -351.477807) (xy 432.294951 -351.530141)
			(xy 432.302714 -351.584128) (xy 432.302714 -351.638665) (xy 433.785562 -351.638665) (xy 433.785562 -351.584135)
			(xy 433.793322 -351.530159) (xy 433.808685 -351.477837) (xy 433.831337 -351.428233) (xy 433.860817 -351.382358)
			(xy 433.896526 -351.341146) (xy 433.937736 -351.305434) (xy 433.983609 -351.27595) (xy 434.03321 -351.253295)
			(xy 434.085531 -351.237928) (xy 434.139507 -351.230164) (xy 434.166772 -351.229676) (xy 435.030372 -351.229676)
			(xy 435.057647 -351.230062) (xy 435.111642 -351.237821) (xy 435.163984 -351.253187) (xy 435.213605 -351.275845)
			(xy 435.259497 -351.305335) (xy 435.300724 -351.341056) (xy 435.336448 -351.382281) (xy 435.365942 -351.42817)
			(xy 435.388603 -351.47779) (xy 435.403973 -351.53013) (xy 435.411736 -351.584125) (xy 435.411736 -351.63867)
			(xy 436.894439 -351.63867) (xy 436.894439 -351.58413) (xy 436.902202 -351.530146) (xy 436.917568 -351.477816)
			(xy 436.940226 -351.428206) (xy 436.969713 -351.382325) (xy 437.005431 -351.341108) (xy 437.046651 -351.305394)
			(xy 437.092534 -351.27591) (xy 437.142146 -351.253257) (xy 437.194477 -351.237895) (xy 437.248462 -351.230137)
			(xy 437.275732 -351.229676) (xy 438.139332 -351.229676) (xy 438.166603 -351.230089) (xy 438.220588 -351.237855)
			(xy 438.272919 -351.253224) (xy 438.32253 -351.275885) (xy 438.368412 -351.305374) (xy 438.409629 -351.341093)
			(xy 438.445345 -351.382314) (xy 438.474831 -351.428198) (xy 438.497487 -351.477811) (xy 438.512852 -351.530143)
			(xy 438.520614 -351.584129) (xy 438.520614 -351.638666) (xy 440.003462 -351.638666) (xy 440.003462 -351.584134)
			(xy 440.011223 -351.530156) (xy 440.026586 -351.477832) (xy 440.04924 -351.428228) (xy 440.078722 -351.382352)
			(xy 440.114433 -351.341138) (xy 440.155645 -351.305427) (xy 440.201521 -351.275944) (xy 440.251125 -351.253289)
			(xy 440.303448 -351.237925) (xy 440.357426 -351.230163) (xy 440.384692 -351.229676) (xy 441.248292 -351.229676)
			(xy 441.275566 -351.230063) (xy 441.329559 -351.237825) (xy 441.381898 -351.253192) (xy 441.431517 -351.275851)
			(xy 441.477406 -351.305342) (xy 441.518632 -351.341063) (xy 441.554353 -351.382287) (xy 441.583845 -351.428176)
			(xy 441.606505 -351.477794) (xy 441.621873 -351.530133) (xy 441.629636 -351.584126) (xy 441.629636 -351.638674)
			(xy 441.621873 -351.692667) (xy 441.606505 -351.745006) (xy 441.583845 -351.794624) (xy 441.554353 -351.840513)
			(xy 441.518632 -351.881737) (xy 441.477406 -351.917458) (xy 441.431517 -351.946949) (xy 441.381898 -351.969608)
			(xy 441.329559 -351.984975) (xy 441.275566 -351.992737) (xy 441.248292 -351.9932) (xy 440.384692 -351.9932)
			(xy 440.357426 -351.992637) (xy 440.303448 -351.984875) (xy 440.251125 -351.969511) (xy 440.201521 -351.946856)
			(xy 440.155645 -351.917373) (xy 440.114433 -351.881662) (xy 440.078722 -351.840448) (xy 440.04924 -351.794572)
			(xy 440.026586 -351.744968) (xy 440.011223 -351.692644) (xy 440.003462 -351.638666) (xy 438.520614 -351.638666)
			(xy 438.520614 -351.638671) (xy 438.512852 -351.692657) (xy 438.497487 -351.744989) (xy 438.474831 -351.794602)
			(xy 438.445345 -351.840486) (xy 438.409629 -351.881707) (xy 438.368412 -351.917426) (xy 438.32253 -351.946915)
			(xy 438.272919 -351.969576) (xy 438.220588 -351.984945) (xy 438.166603 -351.992711) (xy 438.139332 -351.9932)
			(xy 437.275732 -351.9932) (xy 437.248462 -351.992663) (xy 437.194477 -351.984905) (xy 437.142146 -351.969543)
			(xy 437.092534 -351.94689) (xy 437.046651 -351.917406) (xy 437.005431 -351.881692) (xy 436.969713 -351.840475)
			(xy 436.940226 -351.794594) (xy 436.917568 -351.744984) (xy 436.902202 -351.692654) (xy 436.894439 -351.63867)
			(xy 435.411736 -351.63867) (xy 435.411736 -351.638675) (xy 435.403973 -351.69267) (xy 435.388603 -351.74501)
			(xy 435.365942 -351.79463) (xy 435.336448 -351.840519) (xy 435.300724 -351.881744) (xy 435.259497 -351.917465)
			(xy 435.213605 -351.946955) (xy 435.163984 -351.969613) (xy 435.111642 -351.984979) (xy 435.057647 -351.992738)
			(xy 435.030372 -351.9932) (xy 434.166772 -351.9932) (xy 434.139507 -351.992636) (xy 434.085531 -351.984872)
			(xy 434.03321 -351.969505) (xy 433.983609 -351.94685) (xy 433.937736 -351.917366) (xy 433.896526 -351.881654)
			(xy 433.860817 -351.840442) (xy 433.831337 -351.794567) (xy 433.808685 -351.744963) (xy 433.793322 -351.692641)
			(xy 433.785562 -351.638665) (xy 432.302714 -351.638665) (xy 432.302714 -351.638672) (xy 432.294951 -351.692659)
			(xy 432.279585 -351.744993) (xy 432.256928 -351.794608) (xy 432.22744 -351.840492) (xy 432.191722 -351.881714)
			(xy 432.150502 -351.917433) (xy 432.104618 -351.946922) (xy 432.055004 -351.969581) (xy 432.002671 -351.984949)
			(xy 431.948684 -351.992713) (xy 431.921412 -351.9932) (xy 431.057812 -351.9932) (xy 431.030543 -351.992661)
			(xy 430.97656 -351.984901) (xy 430.924231 -351.969538) (xy 430.874622 -351.946883) (xy 430.828741 -351.917399)
			(xy 430.787524 -351.881685) (xy 430.751808 -351.840469) (xy 430.722323 -351.794589) (xy 430.699666 -351.74498)
			(xy 430.684301 -351.692651) (xy 430.676539 -351.638669) (xy 429.193836 -351.638669) (xy 429.193836 -351.638676)
			(xy 429.186072 -351.692672) (xy 429.170702 -351.745014) (xy 429.148039 -351.794635) (xy 429.118544 -351.840526)
			(xy 429.082817 -351.881751) (xy 429.041587 -351.917472) (xy 428.995693 -351.946962) (xy 428.946069 -351.969619)
			(xy 428.893725 -351.984982) (xy 428.839728 -351.99274) (xy 428.812452 -351.9932) (xy 427.948852 -351.9932)
			(xy 427.921588 -351.992634) (xy 427.867615 -351.984868) (xy 427.815296 -351.9695) (xy 427.765697 -351.946843)
			(xy 427.719826 -351.917359) (xy 427.678619 -351.881647) (xy 427.642912 -351.840435) (xy 427.613434 -351.794561)
			(xy 427.590783 -351.744959) (xy 427.575422 -351.692639) (xy 427.567662 -351.638664) (xy 426.084836 -351.638664)
			(xy 426.084836 -351.638674) (xy 426.077073 -351.692667) (xy 426.061705 -351.745006) (xy 426.039045 -351.794624)
			(xy 426.009553 -351.840513) (xy 425.973832 -351.881737) (xy 425.932606 -351.917458) (xy 425.886717 -351.946949)
			(xy 425.837098 -351.969608) (xy 425.784759 -351.984975) (xy 425.730766 -351.992737) (xy 425.703492 -351.9932)
			(xy 424.839892 -351.9932) (xy 424.812626 -351.992637) (xy 424.758648 -351.984875) (xy 424.706325 -351.969511)
			(xy 424.656721 -351.946856) (xy 424.610845 -351.917373) (xy 424.569633 -351.881662) (xy 424.533922 -351.840448)
			(xy 424.50444 -351.794572) (xy 424.481786 -351.744968) (xy 424.466423 -351.692644) (xy 424.458662 -351.638666)
			(xy 422.975814 -351.638666) (xy 422.975814 -351.638671) (xy 422.968052 -351.692657) (xy 422.952687 -351.744989)
			(xy 422.930031 -351.794602) (xy 422.900545 -351.840486) (xy 422.864829 -351.881707) (xy 422.823612 -351.917426)
			(xy 422.77773 -351.946915) (xy 422.728119 -351.969576) (xy 422.675788 -351.984945) (xy 422.621803 -351.992711)
			(xy 422.594532 -351.9932) (xy 421.730932 -351.9932) (xy 421.703662 -351.992663) (xy 421.649677 -351.984905)
			(xy 421.597346 -351.969543) (xy 421.547734 -351.94689) (xy 421.501851 -351.917406) (xy 421.460631 -351.881692)
			(xy 421.424913 -351.840475) (xy 421.395426 -351.794594) (xy 421.372768 -351.744984) (xy 421.357402 -351.692654)
			(xy 421.349639 -351.63867) (xy 419.866936 -351.63867) (xy 419.866936 -351.638675) (xy 419.859173 -351.69267)
			(xy 419.843803 -351.74501) (xy 419.821142 -351.79463) (xy 419.791648 -351.840519) (xy 419.755924 -351.881744)
			(xy 419.714697 -351.917465) (xy 419.668805 -351.946955) (xy 419.619184 -351.969613) (xy 419.566842 -351.984979)
			(xy 419.512847 -351.992738) (xy 419.485572 -351.9932) (xy 418.621972 -351.9932) (xy 418.594707 -351.992636)
			(xy 418.540731 -351.984872) (xy 418.48841 -351.969505) (xy 418.438809 -351.94685) (xy 418.392936 -351.917366)
			(xy 418.351726 -351.881654) (xy 418.316017 -351.840442) (xy 418.286537 -351.794567) (xy 418.263885 -351.744963)
			(xy 418.248522 -351.692641) (xy 418.240762 -351.638665) (xy 416.757914 -351.638665) (xy 416.757914 -351.638672)
			(xy 416.750151 -351.692659) (xy 416.734785 -351.744993) (xy 416.712128 -351.794608) (xy 416.68264 -351.840492)
			(xy 416.646922 -351.881714) (xy 416.605702 -351.917433) (xy 416.559818 -351.946922) (xy 416.510204 -351.969581)
			(xy 416.457871 -351.984949) (xy 416.403884 -351.992713) (xy 416.376612 -351.9932) (xy 415.513012 -351.9932)
			(xy 415.485743 -351.992661) (xy 415.43176 -351.984901) (xy 415.379431 -351.969538) (xy 415.329822 -351.946883)
			(xy 415.283941 -351.917399) (xy 415.242724 -351.881685) (xy 415.207008 -351.840469) (xy 415.177523 -351.794589)
			(xy 415.154866 -351.74498) (xy 415.139501 -351.692651) (xy 415.131739 -351.638669) (xy 413.649036 -351.638669)
			(xy 413.649036 -351.638676) (xy 413.641272 -351.692672) (xy 413.625902 -351.745014) (xy 413.603239 -351.794635)
			(xy 413.573744 -351.840526) (xy 413.538017 -351.881751) (xy 413.496787 -351.917472) (xy 413.450893 -351.946962)
			(xy 413.401269 -351.969619) (xy 413.348925 -351.984982) (xy 413.294928 -351.99274) (xy 413.267652 -351.9932)
			(xy 412.404052 -351.9932) (xy 412.376788 -351.992634) (xy 412.322815 -351.984868) (xy 412.270496 -351.9695)
			(xy 412.220897 -351.946843) (xy 412.175026 -351.917359) (xy 412.133819 -351.881647) (xy 412.098112 -351.840435)
			(xy 412.068634 -351.794561) (xy 412.045983 -351.744959) (xy 412.030622 -351.692639) (xy 412.022862 -351.638664)
			(xy 410.540394 -351.638664) (xy 410.539967 -351.662583) (xy 410.532203 -351.716564) (xy 410.516837 -351.768892)
			(xy 410.49418 -351.818499) (xy 410.464693 -351.864378) (xy 410.428978 -351.905593) (xy 410.38776 -351.941306)
			(xy 410.34188 -351.97079) (xy 410.292271 -351.993444) (xy 410.239943 -352.008808) (xy 410.185961 -352.016568)
			(xy 410.158692 -352.017076) (xy 409.930854 -352.017076) (xy 409.920851 -352.017571) (xy 409.90237 -352.025238)
			(xy 409.888226 -352.039389) (xy 409.880567 -352.057872) (xy 409.880054 -352.067876) (xy 409.880054 -354.759368)
			(xy 412.022806 -354.759368) (xy 412.022806 -354.704832) (xy 412.030567 -354.65085) (xy 412.045931 -354.598521)
			(xy 412.068585 -354.548912) (xy 412.098067 -354.503031) (xy 412.133779 -354.461813) (xy 412.174993 -354.426096)
			(xy 412.22087 -354.396608) (xy 412.270476 -354.373948) (xy 412.322803 -354.358577) (xy 412.376784 -354.35081)
			(xy 412.404052 -354.35032) (xy 413.267652 -354.35032) (xy 413.294924 -354.350816) (xy 413.348913 -354.358572)
			(xy 413.401249 -354.373934) (xy 413.450866 -354.396588) (xy 413.496754 -354.426072) (xy 413.537978 -354.461788)
			(xy 413.573699 -354.503008) (xy 413.603189 -354.548891) (xy 413.625849 -354.598506) (xy 413.641217 -354.65084)
			(xy 413.64898 -354.704828) (xy 413.64898 -354.759372) (xy 413.64898 -354.759373) (xy 415.131684 -354.759373)
			(xy 415.131684 -354.704827) (xy 415.139446 -354.650837) (xy 415.154814 -354.598501) (xy 415.177473 -354.548884)
			(xy 415.206964 -354.502998) (xy 415.242684 -354.461776) (xy 415.283908 -354.426056) (xy 415.329795 -354.396568)
			(xy 415.379412 -354.37391) (xy 415.431748 -354.358544) (xy 415.485739 -354.350783) (xy 415.513012 -354.35032)
			(xy 416.376612 -354.35032) (xy 416.40388 -354.350843) (xy 416.457859 -354.358606) (xy 416.510185 -354.373972)
			(xy 416.559791 -354.396627) (xy 416.605668 -354.426112) (xy 416.646883 -354.461826) (xy 416.682595 -354.503041)
			(xy 416.712078 -354.548919) (xy 416.734733 -354.598526) (xy 416.750097 -354.650852) (xy 416.757858 -354.704832)
			(xy 416.757858 -354.759368) (xy 416.757858 -354.759369) (xy 418.240706 -354.759369) (xy 418.240706 -354.704831)
			(xy 418.248468 -354.650847) (xy 418.263832 -354.598517) (xy 418.286488 -354.548907) (xy 418.315972 -354.503025)
			(xy 418.351686 -354.461806) (xy 418.392902 -354.426089) (xy 418.438782 -354.396601) (xy 418.488391 -354.373942)
			(xy 418.54072 -354.358574) (xy 418.594703 -354.350808) (xy 418.621972 -354.35032) (xy 419.485572 -354.35032)
			(xy 419.512843 -354.350818) (xy 419.56683 -354.358576) (xy 419.619164 -354.373939) (xy 419.668778 -354.396594)
			(xy 419.714663 -354.42608) (xy 419.755885 -354.461795) (xy 419.791604 -354.503014) (xy 419.821092 -354.548897)
			(xy 419.843751 -354.59851) (xy 419.859118 -354.650842) (xy 419.86688 -354.704829) (xy 419.86688 -354.759371)
			(xy 419.86688 -354.759374) (xy 421.349584 -354.759374) (xy 421.349584 -354.704826) (xy 421.357347 -354.650834)
			(xy 421.372716 -354.598496) (xy 421.395377 -354.548879) (xy 421.424869 -354.502991) (xy 421.460591 -354.461768)
			(xy 421.501817 -354.426049) (xy 421.547707 -354.396561) (xy 421.597326 -354.373904) (xy 421.649665 -354.35854)
			(xy 421.703658 -354.350781) (xy 421.730932 -354.35032) (xy 422.594532 -354.35032) (xy 422.621799 -354.350845)
			(xy 422.675776 -354.35861) (xy 422.728099 -354.373977) (xy 422.777703 -354.396634) (xy 422.823578 -354.426119)
			(xy 422.86479 -354.461833) (xy 422.9005 -354.503048) (xy 422.929981 -354.548925) (xy 422.952634 -354.598531)
			(xy 422.967997 -354.650855) (xy 422.975758 -354.704833) (xy 422.975758 -354.759367) (xy 422.975758 -354.75937)
			(xy 424.458606 -354.75937) (xy 424.458606 -354.70483) (xy 424.466368 -354.650844) (xy 424.481734 -354.598513)
			(xy 424.504391 -354.548901) (xy 424.533877 -354.503018) (xy 424.569593 -354.461799) (xy 424.610812 -354.426082)
			(xy 424.656694 -354.396594) (xy 424.706305 -354.373937) (xy 424.758636 -354.35857) (xy 424.812622 -354.350807)
			(xy 424.839892 -354.35032) (xy 425.703492 -354.35032) (xy 425.730762 -354.350819) (xy 425.784747 -354.35858)
			(xy 425.837078 -354.373945) (xy 425.88669 -354.396601) (xy 425.932573 -354.426087) (xy 425.973792 -354.461802)
			(xy 426.009509 -354.503021) (xy 426.038996 -354.548903) (xy 426.061653 -354.598514) (xy 426.077019 -354.650845)
			(xy 426.084781 -354.70483) (xy 426.084781 -354.759368) (xy 427.567606 -354.759368) (xy 427.567606 -354.704832)
			(xy 427.575367 -354.65085) (xy 427.590731 -354.598521) (xy 427.613385 -354.548912) (xy 427.642867 -354.503031)
			(xy 427.678579 -354.461813) (xy 427.719793 -354.426096) (xy 427.76567 -354.396608) (xy 427.815276 -354.373948)
			(xy 427.867603 -354.358577) (xy 427.921584 -354.35081) (xy 427.948852 -354.35032) (xy 428.812452 -354.35032)
			(xy 428.839724 -354.350816) (xy 428.893713 -354.358572) (xy 428.946049 -354.373934) (xy 428.995666 -354.396588)
			(xy 429.041554 -354.426072) (xy 429.082778 -354.461788) (xy 429.118499 -354.503008) (xy 429.147989 -354.548891)
			(xy 429.170649 -354.598506) (xy 429.186017 -354.65084) (xy 429.19378 -354.704828) (xy 429.19378 -354.759372)
			(xy 429.19378 -354.759373) (xy 430.676484 -354.759373) (xy 430.676484 -354.704827) (xy 430.684246 -354.650837)
			(xy 430.699614 -354.598501) (xy 430.722273 -354.548884) (xy 430.751764 -354.502998) (xy 430.787484 -354.461776)
			(xy 430.828708 -354.426056) (xy 430.874595 -354.396568) (xy 430.924212 -354.37391) (xy 430.976548 -354.358544)
			(xy 431.030539 -354.350783) (xy 431.057812 -354.35032) (xy 431.921412 -354.35032) (xy 431.94868 -354.350843)
			(xy 432.002659 -354.358606) (xy 432.054985 -354.373972) (xy 432.104591 -354.396627) (xy 432.150468 -354.426112)
			(xy 432.191683 -354.461826) (xy 432.227395 -354.503041) (xy 432.256878 -354.548919) (xy 432.279533 -354.598526)
			(xy 432.294897 -354.650852) (xy 432.302658 -354.704832) (xy 432.302658 -354.759368) (xy 432.302658 -354.759369)
			(xy 433.785506 -354.759369) (xy 433.785506 -354.704831) (xy 433.793268 -354.650847) (xy 433.808632 -354.598517)
			(xy 433.831288 -354.548907) (xy 433.860772 -354.503025) (xy 433.896486 -354.461806) (xy 433.937702 -354.426089)
			(xy 433.983582 -354.396601) (xy 434.033191 -354.373942) (xy 434.08552 -354.358574) (xy 434.139503 -354.350808)
			(xy 434.166772 -354.35032) (xy 435.030372 -354.35032) (xy 435.057643 -354.350818) (xy 435.11163 -354.358576)
			(xy 435.163964 -354.373939) (xy 435.213578 -354.396594) (xy 435.259463 -354.42608) (xy 435.300685 -354.461795)
			(xy 435.336404 -354.503014) (xy 435.365892 -354.548897) (xy 435.388551 -354.59851) (xy 435.403918 -354.650842)
			(xy 435.41168 -354.704829) (xy 435.41168 -354.759371) (xy 435.41168 -354.759374) (xy 436.894384 -354.759374)
			(xy 436.894384 -354.704826) (xy 436.902147 -354.650834) (xy 436.917516 -354.598496) (xy 436.940177 -354.548879)
			(xy 436.969669 -354.502991) (xy 437.005391 -354.461768) (xy 437.046617 -354.426049) (xy 437.092507 -354.396561)
			(xy 437.142126 -354.373904) (xy 437.194465 -354.35854) (xy 437.248458 -354.350781) (xy 437.275732 -354.35032)
			(xy 438.139332 -354.35032) (xy 438.166599 -354.350845) (xy 438.220576 -354.35861) (xy 438.272899 -354.373977)
			(xy 438.322503 -354.396634) (xy 438.368378 -354.426119) (xy 438.40959 -354.461833) (xy 438.4453 -354.503048)
			(xy 438.474781 -354.548925) (xy 438.497434 -354.598531) (xy 438.512797 -354.650855) (xy 438.520558 -354.704833)
			(xy 438.520558 -354.759367) (xy 438.520558 -354.75937) (xy 440.003406 -354.75937) (xy 440.003406 -354.70483)
			(xy 440.011168 -354.650844) (xy 440.026534 -354.598513) (xy 440.049191 -354.548901) (xy 440.078677 -354.503018)
			(xy 440.114393 -354.461799) (xy 440.155612 -354.426082) (xy 440.201494 -354.396594) (xy 440.251105 -354.373937)
			(xy 440.303436 -354.35857) (xy 440.357422 -354.350807) (xy 440.384692 -354.35032) (xy 441.248292 -354.35032)
			(xy 441.275562 -354.350819) (xy 441.329547 -354.35858) (xy 441.381878 -354.373945) (xy 441.43149 -354.396601)
			(xy 441.477373 -354.426087) (xy 441.518592 -354.461802) (xy 441.554309 -354.503021) (xy 441.583796 -354.548903)
			(xy 441.606453 -354.598514) (xy 441.621819 -354.650845) (xy 441.629581 -354.70483) (xy 441.629581 -354.75937)
			(xy 441.621819 -354.813355) (xy 441.606453 -354.865686) (xy 441.583796 -354.915297) (xy 441.554309 -354.961179)
			(xy 441.518592 -355.002398) (xy 441.477373 -355.038113) (xy 441.43149 -355.067599) (xy 441.381878 -355.090255)
			(xy 441.329547 -355.10562) (xy 441.275562 -355.113381) (xy 441.248292 -355.113844) (xy 440.384692 -355.113844)
			(xy 440.357422 -355.113393) (xy 440.303436 -355.10563) (xy 440.251105 -355.090263) (xy 440.201494 -355.067606)
			(xy 440.155612 -355.038118) (xy 440.114393 -355.002401) (xy 440.078677 -354.961182) (xy 440.049191 -354.915299)
			(xy 440.026534 -354.865687) (xy 440.011168 -354.813356) (xy 440.003406 -354.75937) (xy 438.520558 -354.75937)
			(xy 438.512797 -354.813345) (xy 438.497434 -354.865669) (xy 438.474781 -354.915275) (xy 438.4453 -354.961152)
			(xy 438.40959 -355.002367) (xy 438.368378 -355.038081) (xy 438.322503 -355.067566) (xy 438.272899 -355.090223)
			(xy 438.220576 -355.10559) (xy 438.166599 -355.113355) (xy 438.139332 -355.113844) (xy 437.275732 -355.113844)
			(xy 437.248458 -355.113419) (xy 437.194465 -355.10566) (xy 437.142126 -355.090296) (xy 437.092507 -355.067639)
			(xy 437.046617 -355.038151) (xy 437.005391 -355.002432) (xy 436.969669 -354.961209) (xy 436.940177 -354.915321)
			(xy 436.917516 -354.865704) (xy 436.902147 -354.813366) (xy 436.894384 -354.759374) (xy 435.41168 -354.759374)
			(xy 435.403918 -354.813358) (xy 435.388551 -354.86569) (xy 435.365892 -354.915303) (xy 435.336404 -354.961186)
			(xy 435.300685 -355.002405) (xy 435.259463 -355.03812) (xy 435.213578 -355.067606) (xy 435.163964 -355.090261)
			(xy 435.11163 -355.105624) (xy 435.057643 -355.113382) (xy 435.030372 -355.113844) (xy 434.166772 -355.113844)
			(xy 434.139503 -355.113392) (xy 434.08552 -355.105626) (xy 434.033191 -355.090258) (xy 433.983582 -355.067599)
			(xy 433.937702 -355.038111) (xy 433.896486 -355.002394) (xy 433.860772 -354.961175) (xy 433.831288 -354.915293)
			(xy 433.808632 -354.865683) (xy 433.793268 -354.813353) (xy 433.785506 -354.759369) (xy 432.302658 -354.759369)
			(xy 432.294897 -354.813348) (xy 432.279533 -354.865674) (xy 432.256878 -354.915281) (xy 432.227395 -354.961159)
			(xy 432.191683 -355.002374) (xy 432.150468 -355.038088) (xy 432.104591 -355.067573) (xy 432.054985 -355.090228)
			(xy 432.002659 -355.105594) (xy 431.94868 -355.113357) (xy 431.921412 -355.113844) (xy 431.057812 -355.113844)
			(xy 431.030539 -355.113417) (xy 430.976548 -355.105656) (xy 430.924212 -355.09029) (xy 430.874595 -355.067632)
			(xy 430.828708 -355.038144) (xy 430.787484 -355.002424) (xy 430.751764 -354.961202) (xy 430.722273 -354.915316)
			(xy 430.699614 -354.865699) (xy 430.684246 -354.813363) (xy 430.676484 -354.759373) (xy 429.19378 -354.759373)
			(xy 429.186017 -354.81336) (xy 429.170649 -354.865694) (xy 429.147989 -354.915309) (xy 429.118499 -354.961192)
			(xy 429.082778 -355.002412) (xy 429.041554 -355.038128) (xy 428.995666 -355.067612) (xy 428.946049 -355.090266)
			(xy 428.893713 -355.105628) (xy 428.839724 -355.113384) (xy 428.812452 -355.113844) (xy 427.948852 -355.113844)
			(xy 427.921584 -355.11339) (xy 427.867603 -355.105623) (xy 427.815276 -355.090252) (xy 427.76567 -355.067592)
			(xy 427.719793 -355.038104) (xy 427.678579 -355.002387) (xy 427.642867 -354.961169) (xy 427.613385 -354.915288)
			(xy 427.590731 -354.865679) (xy 427.575367 -354.81335) (xy 427.567606 -354.759368) (xy 426.084781 -354.759368)
			(xy 426.084781 -354.75937) (xy 426.077019 -354.813355) (xy 426.061653 -354.865686) (xy 426.038996 -354.915297)
			(xy 426.009509 -354.961179) (xy 425.973792 -355.002398) (xy 425.932573 -355.038113) (xy 425.88669 -355.067599)
			(xy 425.837078 -355.090255) (xy 425.784747 -355.10562) (xy 425.730762 -355.113381) (xy 425.703492 -355.113844)
			(xy 424.839892 -355.113844) (xy 424.812622 -355.113393) (xy 424.758636 -355.10563) (xy 424.706305 -355.090263)
			(xy 424.656694 -355.067606) (xy 424.610812 -355.038118) (xy 424.569593 -355.002401) (xy 424.533877 -354.961182)
			(xy 424.504391 -354.915299) (xy 424.481734 -354.865687) (xy 424.466368 -354.813356) (xy 424.458606 -354.75937)
			(xy 422.975758 -354.75937) (xy 422.967997 -354.813345) (xy 422.952634 -354.865669) (xy 422.929981 -354.915275)
			(xy 422.9005 -354.961152) (xy 422.86479 -355.002367) (xy 422.823578 -355.038081) (xy 422.777703 -355.067566)
			(xy 422.728099 -355.090223) (xy 422.675776 -355.10559) (xy 422.621799 -355.113355) (xy 422.594532 -355.113844)
			(xy 421.730932 -355.113844) (xy 421.703658 -355.113419) (xy 421.649665 -355.10566) (xy 421.597326 -355.090296)
			(xy 421.547707 -355.067639) (xy 421.501817 -355.038151) (xy 421.460591 -355.002432) (xy 421.424869 -354.961209)
			(xy 421.395377 -354.915321) (xy 421.372716 -354.865704) (xy 421.357347 -354.813366) (xy 421.349584 -354.759374)
			(xy 419.86688 -354.759374) (xy 419.859118 -354.813358) (xy 419.843751 -354.86569) (xy 419.821092 -354.915303)
			(xy 419.791604 -354.961186) (xy 419.755885 -355.002405) (xy 419.714663 -355.03812) (xy 419.668778 -355.067606)
			(xy 419.619164 -355.090261) (xy 419.56683 -355.105624) (xy 419.512843 -355.113382) (xy 419.485572 -355.113844)
			(xy 418.621972 -355.113844) (xy 418.594703 -355.113392) (xy 418.54072 -355.105626) (xy 418.488391 -355.090258)
			(xy 418.438782 -355.067599) (xy 418.392902 -355.038111) (xy 418.351686 -355.002394) (xy 418.315972 -354.961175)
			(xy 418.286488 -354.915293) (xy 418.263832 -354.865683) (xy 418.248468 -354.813353) (xy 418.240706 -354.759369)
			(xy 416.757858 -354.759369) (xy 416.750097 -354.813348) (xy 416.734733 -354.865674) (xy 416.712078 -354.915281)
			(xy 416.682595 -354.961159) (xy 416.646883 -355.002374) (xy 416.605668 -355.038088) (xy 416.559791 -355.067573)
			(xy 416.510185 -355.090228) (xy 416.457859 -355.105594) (xy 416.40388 -355.113357) (xy 416.376612 -355.113844)
			(xy 415.513012 -355.113844) (xy 415.485739 -355.113417) (xy 415.431748 -355.105656) (xy 415.379412 -355.09029)
			(xy 415.329795 -355.067632) (xy 415.283908 -355.038144) (xy 415.242684 -355.002424) (xy 415.206964 -354.961202)
			(xy 415.177473 -354.915316) (xy 415.154814 -354.865699) (xy 415.139446 -354.813363) (xy 415.131684 -354.759373)
			(xy 413.64898 -354.759373) (xy 413.641217 -354.81336) (xy 413.625849 -354.865694) (xy 413.603189 -354.915309)
			(xy 413.573699 -354.961192) (xy 413.537978 -355.002412) (xy 413.496754 -355.038128) (xy 413.450866 -355.067612)
			(xy 413.401249 -355.090266) (xy 413.348913 -355.105628) (xy 413.294924 -355.113384) (xy 413.267652 -355.113844)
			(xy 412.404052 -355.113844) (xy 412.376784 -355.11339) (xy 412.322803 -355.105623) (xy 412.270476 -355.090252)
			(xy 412.22087 -355.067592) (xy 412.174993 -355.038104) (xy 412.133779 -355.002387) (xy 412.098067 -354.961169)
			(xy 412.068585 -354.915288) (xy 412.045931 -354.865679) (xy 412.030567 -354.81335) (xy 412.022806 -354.759368)
			(xy 409.880054 -354.759368) (xy 409.880054 -355.175312) (xy 409.879627 -355.18538) (xy 409.871905 -355.203977)
			(xy 409.865068 -355.21138) (xy 407.291483 -357.784965) (xy 412.022854 -357.784965) (xy 412.022854 -357.730435)
			(xy 412.030614 -357.67646) (xy 412.045976 -357.624138) (xy 412.068627 -357.574535) (xy 412.098106 -357.52866)
			(xy 412.133813 -357.487447) (xy 412.175022 -357.451735) (xy 412.220893 -357.42225) (xy 412.270493 -357.399593)
			(xy 412.322813 -357.384224) (xy 412.376787 -357.376458) (xy 412.404052 -357.375968) (xy 413.267652 -357.375968)
			(xy 413.294927 -357.376368) (xy 413.348924 -357.384125) (xy 413.401266 -357.399489) (xy 413.450889 -357.422145)
			(xy 413.496783 -357.451634) (xy 413.538012 -357.487354) (xy 413.573737 -357.528579) (xy 413.603232 -357.574468)
			(xy 413.625894 -357.624089) (xy 413.641264 -357.676429) (xy 413.649028 -357.730425) (xy 413.649028 -357.784969)
			(xy 415.131731 -357.784969) (xy 415.131731 -357.730431) (xy 415.139493 -357.676447) (xy 415.154859 -357.624117)
			(xy 415.177516 -357.574507) (xy 415.207002 -357.528627) (xy 415.242718 -357.487409) (xy 415.283936 -357.451695)
			(xy 415.329818 -357.42221) (xy 415.379429 -357.399555) (xy 415.431759 -357.384191) (xy 415.485743 -357.376431)
			(xy 415.513012 -357.375968) (xy 416.376612 -357.375968) (xy 416.403883 -357.376395) (xy 416.457869 -357.384159)
			(xy 416.510202 -357.399527) (xy 416.559814 -357.422185) (xy 416.605697 -357.451674) (xy 416.646917 -357.487392)
			(xy 416.682633 -357.528612) (xy 416.712121 -357.574496) (xy 416.734778 -357.62411) (xy 416.750144 -357.676442)
			(xy 416.757906 -357.730429) (xy 416.757906 -357.784966) (xy 418.240754 -357.784966) (xy 418.240754 -357.730434)
			(xy 418.248515 -357.676457) (xy 418.263877 -357.624134) (xy 418.28653 -357.57453) (xy 418.316011 -357.528654)
			(xy 418.35172 -357.48744) (xy 418.392931 -357.451727) (xy 418.438805 -357.422243) (xy 418.488408 -357.399587)
			(xy 418.54073 -357.384221) (xy 418.594706 -357.376456) (xy 418.621972 -357.375968) (xy 419.485572 -357.375968)
			(xy 419.512846 -357.37637) (xy 419.566841 -357.384129) (xy 419.619181 -357.399494) (xy 419.668801 -357.422152)
			(xy 419.714692 -357.451641) (xy 419.755919 -357.487361) (xy 419.791642 -357.528585) (xy 419.821135 -357.574474)
			(xy 419.843796 -357.624093) (xy 419.859165 -357.676432) (xy 419.866928 -357.730426) (xy 419.866928 -357.78497)
			(xy 421.349632 -357.78497) (xy 421.349632 -357.73043) (xy 421.357394 -357.676444) (xy 421.372761 -357.624113)
			(xy 421.395419 -357.574502) (xy 421.424907 -357.52862) (xy 421.460625 -357.487402) (xy 421.501846 -357.451688)
			(xy 421.54773 -357.422203) (xy 421.597343 -357.399549) (xy 421.649676 -357.384187) (xy 421.703662 -357.376429)
			(xy 421.730932 -357.375968) (xy 422.594532 -357.375968) (xy 422.621802 -357.376397) (xy 422.675786 -357.384163)
			(xy 422.728116 -357.399532) (xy 422.777726 -357.422192) (xy 422.823607 -357.451681) (xy 422.864824 -357.487399)
			(xy 422.900538 -357.528619) (xy 422.930024 -357.574502) (xy 422.952679 -357.624114) (xy 422.968044 -357.676445)
			(xy 422.975806 -357.73043) (xy 422.975806 -357.784967) (xy 424.458654 -357.784967) (xy 424.458654 -357.730433)
			(xy 424.466415 -357.676454) (xy 424.481779 -357.62413) (xy 424.504433 -357.574524) (xy 424.533916 -357.528647)
			(xy 424.569627 -357.487433) (xy 424.610841 -357.45172) (xy 424.656717 -357.422237) (xy 424.706322 -357.399582)
			(xy 424.758647 -357.384217) (xy 424.812625 -357.376455) (xy 424.839892 -357.375968) (xy 425.703492 -357.375968)
			(xy 425.730766 -357.376371) (xy 425.784757 -357.384133) (xy 425.837095 -357.3995) (xy 425.886713 -357.422159)
			(xy 425.932602 -357.451648) (xy 425.973826 -357.487368) (xy 426.009547 -357.528592) (xy 426.039038 -357.57448)
			(xy 426.061698 -357.624097) (xy 426.077065 -357.676435) (xy 426.084828 -357.730426) (xy 426.084828 -357.784965)
			(xy 427.567654 -357.784965) (xy 427.567654 -357.730435) (xy 427.575414 -357.67646) (xy 427.590776 -357.624138)
			(xy 427.613427 -357.574535) (xy 427.642906 -357.52866) (xy 427.678613 -357.487447) (xy 427.719822 -357.451735)
			(xy 427.765693 -357.42225) (xy 427.815293 -357.399593) (xy 427.867613 -357.384224) (xy 427.921587 -357.376458)
			(xy 427.948852 -357.375968) (xy 428.812452 -357.375968) (xy 428.839727 -357.376368) (xy 428.893724 -357.384125)
			(xy 428.946066 -357.399489) (xy 428.995689 -357.422145) (xy 429.041583 -357.451634) (xy 429.082812 -357.487354)
			(xy 429.118537 -357.528579) (xy 429.148032 -357.574468) (xy 429.170694 -357.624089) (xy 429.186064 -357.676429)
			(xy 429.193828 -357.730425) (xy 429.193828 -357.784969) (xy 430.676531 -357.784969) (xy 430.676531 -357.730431)
			(xy 430.684293 -357.676447) (xy 430.699659 -357.624117) (xy 430.722316 -357.574507) (xy 430.751802 -357.528627)
			(xy 430.787518 -357.487409) (xy 430.828736 -357.451695) (xy 430.874618 -357.42221) (xy 430.924229 -357.399555)
			(xy 430.976559 -357.384191) (xy 431.030543 -357.376431) (xy 431.057812 -357.375968) (xy 431.921412 -357.375968)
			(xy 431.948683 -357.376395) (xy 432.002669 -357.384159) (xy 432.055002 -357.399527) (xy 432.104614 -357.422185)
			(xy 432.150497 -357.451674) (xy 432.191717 -357.487392) (xy 432.227433 -357.528612) (xy 432.256921 -357.574496)
			(xy 432.279578 -357.62411) (xy 432.294944 -357.676442) (xy 432.302706 -357.730429) (xy 432.302706 -357.784966)
			(xy 433.785554 -357.784966) (xy 433.785554 -357.730434) (xy 433.793315 -357.676457) (xy 433.808677 -357.624134)
			(xy 433.83133 -357.57453) (xy 433.860811 -357.528654) (xy 433.89652 -357.48744) (xy 433.937731 -357.451727)
			(xy 433.983605 -357.422243) (xy 434.033208 -357.399587) (xy 434.08553 -357.384221) (xy 434.139506 -357.376456)
			(xy 434.166772 -357.375968) (xy 435.030372 -357.375968) (xy 435.057646 -357.37637) (xy 435.111641 -357.384129)
			(xy 435.163981 -357.399494) (xy 435.213601 -357.422152) (xy 435.259492 -357.451641) (xy 435.300719 -357.487361)
			(xy 435.336442 -357.528585) (xy 435.365935 -357.574474) (xy 435.388596 -357.624093) (xy 435.403965 -357.676432)
			(xy 435.411728 -357.730426) (xy 435.411728 -357.78497) (xy 436.894432 -357.78497) (xy 436.894432 -357.73043)
			(xy 436.902194 -357.676444) (xy 436.917561 -357.624113) (xy 436.940219 -357.574502) (xy 436.969707 -357.52862)
			(xy 437.005425 -357.487402) (xy 437.046646 -357.451688) (xy 437.09253 -357.422203) (xy 437.142143 -357.399549)
			(xy 437.194476 -357.384187) (xy 437.248462 -357.376429) (xy 437.275732 -357.375968) (xy 438.139332 -357.375968)
			(xy 438.166602 -357.376397) (xy 438.220586 -357.384163) (xy 438.272916 -357.399532) (xy 438.322526 -357.422192)
			(xy 438.368407 -357.451681) (xy 438.409624 -357.487399) (xy 438.445338 -357.528619) (xy 438.474824 -357.574502)
			(xy 438.497479 -357.624114) (xy 438.512844 -357.676445) (xy 438.520606 -357.73043) (xy 438.520606 -357.784967)
			(xy 440.003454 -357.784967) (xy 440.003454 -357.730433) (xy 440.011215 -357.676454) (xy 440.026579 -357.62413)
			(xy 440.049233 -357.574524) (xy 440.078716 -357.528647) (xy 440.114427 -357.487433) (xy 440.155641 -357.45172)
			(xy 440.201517 -357.422237) (xy 440.251122 -357.399582) (xy 440.303447 -357.384217) (xy 440.357425 -357.376455)
			(xy 440.384692 -357.375968) (xy 441.248292 -357.375968) (xy 441.275566 -357.376371) (xy 441.329557 -357.384133)
			(xy 441.381895 -357.3995) (xy 441.431513 -357.422159) (xy 441.477402 -357.451648) (xy 441.518626 -357.487368)
			(xy 441.554347 -357.528592) (xy 441.583838 -357.57448) (xy 441.606498 -357.624097) (xy 441.621865 -357.676435)
			(xy 441.629628 -357.730426) (xy 441.629628 -357.784974) (xy 441.621865 -357.838965) (xy 441.606498 -357.891303)
			(xy 441.583838 -357.94092) (xy 441.554347 -357.986808) (xy 441.518626 -358.028032) (xy 441.477402 -358.063752)
			(xy 441.431513 -358.093241) (xy 441.381895 -358.1159) (xy 441.329557 -358.131267) (xy 441.275566 -358.139029)
			(xy 441.248292 -358.139492) (xy 440.384692 -358.139492) (xy 440.357425 -358.138945) (xy 440.303447 -358.131183)
			(xy 440.251122 -358.115818) (xy 440.201517 -358.093163) (xy 440.155641 -358.06368) (xy 440.114427 -358.027967)
			(xy 440.078716 -357.986753) (xy 440.049233 -357.940876) (xy 440.026579 -357.89127) (xy 440.011215 -357.838946)
			(xy 440.003454 -357.784967) (xy 438.520606 -357.784967) (xy 438.520606 -357.78497) (xy 438.512844 -357.838955)
			(xy 438.497479 -357.891286) (xy 438.474824 -357.940898) (xy 438.445338 -357.986781) (xy 438.409624 -358.028001)
			(xy 438.368407 -358.063719) (xy 438.322526 -358.093208) (xy 438.272916 -358.115868) (xy 438.220586 -358.131237)
			(xy 438.166602 -358.139003) (xy 438.139332 -358.139492) (xy 437.275732 -358.139492) (xy 437.248462 -358.138971)
			(xy 437.194476 -358.131213) (xy 437.142143 -358.115851) (xy 437.09253 -358.093197) (xy 437.046646 -358.063712)
			(xy 437.005425 -358.027998) (xy 436.969707 -357.98678) (xy 436.940219 -357.940898) (xy 436.917561 -357.891287)
			(xy 436.902194 -357.838956) (xy 436.894432 -357.78497) (xy 435.411728 -357.78497) (xy 435.411728 -357.784974)
			(xy 435.403965 -357.838968) (xy 435.388596 -357.891307) (xy 435.365935 -357.940926) (xy 435.336442 -357.986815)
			(xy 435.300719 -358.028039) (xy 435.259492 -358.063759) (xy 435.213601 -358.093248) (xy 435.163981 -358.115906)
			(xy 435.111641 -358.131271) (xy 435.057646 -358.13903) (xy 435.030372 -358.139492) (xy 434.166772 -358.139492)
			(xy 434.139506 -358.138944) (xy 434.08553 -358.131179) (xy 434.033208 -358.115813) (xy 433.983605 -358.093157)
			(xy 433.937731 -358.063673) (xy 433.89652 -358.02796) (xy 433.860811 -357.986746) (xy 433.83133 -357.94087)
			(xy 433.808677 -357.891266) (xy 433.793315 -357.838943) (xy 433.785554 -357.784966) (xy 432.302706 -357.784966)
			(xy 432.302706 -357.784971) (xy 432.294944 -357.838958) (xy 432.279578 -357.89129) (xy 432.256921 -357.940904)
			(xy 432.227433 -357.986788) (xy 432.191717 -358.028008) (xy 432.150497 -358.063726) (xy 432.104614 -358.093215)
			(xy 432.055002 -358.115873) (xy 432.002669 -358.131241) (xy 431.948683 -358.139005) (xy 431.921412 -358.139492)
			(xy 431.057812 -358.139492) (xy 431.030543 -358.138969) (xy 430.976559 -358.131209) (xy 430.924229 -358.115845)
			(xy 430.874618 -358.09319) (xy 430.828736 -358.063705) (xy 430.787518 -358.027991) (xy 430.751802 -357.986773)
			(xy 430.722316 -357.940893) (xy 430.699659 -357.891283) (xy 430.684293 -357.838953) (xy 430.676531 -357.784969)
			(xy 429.193828 -357.784969) (xy 429.193828 -357.784975) (xy 429.186064 -357.838971) (xy 429.170694 -357.891311)
			(xy 429.148032 -357.940932) (xy 429.118537 -357.986821) (xy 429.082812 -358.028046) (xy 429.041583 -358.063766)
			(xy 428.995689 -358.093255) (xy 428.946066 -358.115911) (xy 428.893724 -358.131275) (xy 428.839727 -358.139032)
			(xy 428.812452 -358.139492) (xy 427.948852 -358.139492) (xy 427.921587 -358.138942) (xy 427.867613 -358.131176)
			(xy 427.815293 -358.115807) (xy 427.765693 -358.09315) (xy 427.719822 -358.063665) (xy 427.678613 -358.027953)
			(xy 427.642906 -357.98674) (xy 427.613427 -357.940865) (xy 427.590776 -357.891262) (xy 427.575414 -357.83894)
			(xy 427.567654 -357.784965) (xy 426.084828 -357.784965) (xy 426.084828 -357.784974) (xy 426.077065 -357.838965)
			(xy 426.061698 -357.891303) (xy 426.039038 -357.94092) (xy 426.009547 -357.986808) (xy 425.973826 -358.028032)
			(xy 425.932602 -358.063752) (xy 425.886713 -358.093241) (xy 425.837095 -358.1159) (xy 425.784757 -358.131267)
			(xy 425.730766 -358.139029) (xy 425.703492 -358.139492) (xy 424.839892 -358.139492) (xy 424.812625 -358.138945)
			(xy 424.758647 -358.131183) (xy 424.706322 -358.115818) (xy 424.656717 -358.093163) (xy 424.610841 -358.06368)
			(xy 424.569627 -358.027967) (xy 424.533916 -357.986753) (xy 424.504433 -357.940876) (xy 424.481779 -357.89127)
			(xy 424.466415 -357.838946) (xy 424.458654 -357.784967) (xy 422.975806 -357.784967) (xy 422.975806 -357.78497)
			(xy 422.968044 -357.838955) (xy 422.952679 -357.891286) (xy 422.930024 -357.940898) (xy 422.900538 -357.986781)
			(xy 422.864824 -358.028001) (xy 422.823607 -358.063719) (xy 422.777726 -358.093208) (xy 422.728116 -358.115868)
			(xy 422.675786 -358.131237) (xy 422.621802 -358.139003) (xy 422.594532 -358.139492) (xy 421.730932 -358.139492)
			(xy 421.703662 -358.138971) (xy 421.649676 -358.131213) (xy 421.597343 -358.115851) (xy 421.54773 -358.093197)
			(xy 421.501846 -358.063712) (xy 421.460625 -358.027998) (xy 421.424907 -357.98678) (xy 421.395419 -357.940898)
			(xy 421.372761 -357.891287) (xy 421.357394 -357.838956) (xy 421.349632 -357.78497) (xy 419.866928 -357.78497)
			(xy 419.866928 -357.784974) (xy 419.859165 -357.838968) (xy 419.843796 -357.891307) (xy 419.821135 -357.940926)
			(xy 419.791642 -357.986815) (xy 419.755919 -358.028039) (xy 419.714692 -358.063759) (xy 419.668801 -358.093248)
			(xy 419.619181 -358.115906) (xy 419.566841 -358.131271) (xy 419.512846 -358.13903) (xy 419.485572 -358.139492)
			(xy 418.621972 -358.139492) (xy 418.594706 -358.138944) (xy 418.54073 -358.131179) (xy 418.488408 -358.115813)
			(xy 418.438805 -358.093157) (xy 418.392931 -358.063673) (xy 418.35172 -358.02796) (xy 418.316011 -357.986746)
			(xy 418.28653 -357.94087) (xy 418.263877 -357.891266) (xy 418.248515 -357.838943) (xy 418.240754 -357.784966)
			(xy 416.757906 -357.784966) (xy 416.757906 -357.784971) (xy 416.750144 -357.838958) (xy 416.734778 -357.89129)
			(xy 416.712121 -357.940904) (xy 416.682633 -357.986788) (xy 416.646917 -358.028008) (xy 416.605697 -358.063726)
			(xy 416.559814 -358.093215) (xy 416.510202 -358.115873) (xy 416.457869 -358.131241) (xy 416.403883 -358.139005)
			(xy 416.376612 -358.139492) (xy 415.513012 -358.139492) (xy 415.485743 -358.138969) (xy 415.431759 -358.131209)
			(xy 415.379429 -358.115845) (xy 415.329818 -358.09319) (xy 415.283936 -358.063705) (xy 415.242718 -358.027991)
			(xy 415.207002 -357.986773) (xy 415.177516 -357.940893) (xy 415.154859 -357.891283) (xy 415.139493 -357.838953)
			(xy 415.131731 -357.784969) (xy 413.649028 -357.784969) (xy 413.649028 -357.784975) (xy 413.641264 -357.838971)
			(xy 413.625894 -357.891311) (xy 413.603232 -357.940932) (xy 413.573737 -357.986821) (xy 413.538012 -358.028046)
			(xy 413.496783 -358.063766) (xy 413.450889 -358.093255) (xy 413.401266 -358.115911) (xy 413.348924 -358.131275)
			(xy 413.294927 -358.139032) (xy 413.267652 -358.139492) (xy 412.404052 -358.139492) (xy 412.376787 -358.138942)
			(xy 412.322813 -358.131176) (xy 412.270493 -358.115807) (xy 412.220893 -358.09315) (xy 412.175022 -358.063665)
			(xy 412.133813 -358.027953) (xy 412.098106 -357.98674) (xy 412.068627 -357.940865) (xy 412.045976 -357.891262)
			(xy 412.030614 -357.83894) (xy 412.022854 -357.784965) (xy 407.291483 -357.784965) (xy 402.270722 -362.805726)
			(xy 449.753734 -362.805726) (xy 449.757805 -362.750104) (xy 449.769931 -362.695667) (xy 449.789854 -362.643576)
			(xy 449.81715 -362.594941) (xy 449.851236 -362.550798) (xy 449.891385 -362.512089) (xy 449.936743 -362.479638)
			(xy 449.986343 -362.454137) (xy 450.039127 -362.43613) (xy 450.09397 -362.426) (xy 450.149704 -362.423963)
			(xy 450.205141 -362.430063) (xy 450.259098 -362.444169) (xy 450.310427 -362.465981) (xy 450.358033 -362.495035)
			(xy 450.400901 -362.53071) (xy 450.438118 -362.572247) (xy 450.468891 -362.61876) (xy 450.492563 -362.669257)
			(xy 450.508631 -362.722664) (xy 450.516751 -362.77784) (xy 450.51726 -362.805726) (xy 450.516751 -362.833612)
			(xy 450.508631 -362.888788) (xy 450.492563 -362.942195) (xy 450.468891 -362.992692) (xy 450.438118 -363.039205)
			(xy 450.400901 -363.080742) (xy 450.358033 -363.116417) (xy 450.310427 -363.145471) (xy 450.259098 -363.167283)
			(xy 450.205141 -363.181389) (xy 450.149704 -363.187489) (xy 450.09397 -363.185452) (xy 450.039127 -363.175322)
			(xy 449.986343 -363.157315) (xy 449.936743 -363.131814) (xy 449.891385 -363.099363) (xy 449.851236 -363.060654)
			(xy 449.81715 -363.016511) (xy 449.789854 -362.967876) (xy 449.769931 -362.915785) (xy 449.757805 -362.861348)
			(xy 449.753734 -362.805726) (xy 402.270722 -362.805726) (xy 401.189952 -363.886496) (xy 459.91729 -363.886496)
			(xy 459.921361 -363.830874) (xy 459.933487 -363.776437) (xy 459.95341 -363.724346) (xy 459.980706 -363.675711)
			(xy 460.014792 -363.631568) (xy 460.054941 -363.592859) (xy 460.100299 -363.560408) (xy 460.149899 -363.534907)
			(xy 460.202683 -363.5169) (xy 460.257526 -363.50677) (xy 460.31326 -363.504733) (xy 460.368697 -363.510833)
			(xy 460.422654 -363.524939) (xy 460.473983 -363.546751) (xy 460.521589 -363.575805) (xy 460.564457 -363.61148)
			(xy 460.601674 -363.653017) (xy 460.632447 -363.69953) (xy 460.656119 -363.750027) (xy 460.672187 -363.803434)
			(xy 460.680307 -363.85861) (xy 460.680816 -363.886496) (xy 460.680307 -363.914382) (xy 460.672187 -363.969558)
			(xy 460.656119 -364.022965) (xy 460.632447 -364.073462) (xy 460.601674 -364.119975) (xy 460.564457 -364.161512)
			(xy 460.521589 -364.197187) (xy 460.473983 -364.226241) (xy 460.422654 -364.248053) (xy 460.368697 -364.262159)
			(xy 460.31326 -364.268259) (xy 460.257526 -364.266222) (xy 460.202683 -364.256092) (xy 460.149899 -364.238085)
			(xy 460.100299 -364.212584) (xy 460.054941 -364.180133) (xy 460.014792 -364.141424) (xy 459.980706 -364.097281)
			(xy 459.95341 -364.048646) (xy 459.933487 -363.996555) (xy 459.921361 -363.942118) (xy 459.91729 -363.886496)
			(xy 401.189952 -363.886496) (xy 400.574764 -364.501684) (xy 457.804772 -364.501684) (xy 457.808843 -364.446062)
			(xy 457.820969 -364.391625) (xy 457.840892 -364.339534) (xy 457.868188 -364.290899) (xy 457.902274 -364.246756)
			(xy 457.942423 -364.208047) (xy 457.987781 -364.175596) (xy 458.037381 -364.150095) (xy 458.090165 -364.132088)
			(xy 458.145008 -364.121958) (xy 458.200742 -364.119921) (xy 458.256179 -364.126021) (xy 458.310136 -364.140127)
			(xy 458.361465 -364.161939) (xy 458.409071 -364.190993) (xy 458.451939 -364.226668) (xy 458.489156 -364.268205)
			(xy 458.519929 -364.314718) (xy 458.543601 -364.365215) (xy 458.559669 -364.418622) (xy 458.567789 -364.473798)
			(xy 458.568298 -364.501684) (xy 458.567789 -364.52957) (xy 458.559669 -364.584746) (xy 458.543601 -364.638153)
			(xy 458.519929 -364.68865) (xy 458.489156 -364.735163) (xy 458.451939 -364.7767) (xy 458.409071 -364.812375)
			(xy 458.361465 -364.841429) (xy 458.310136 -364.863241) (xy 458.256179 -364.877347) (xy 458.200742 -364.883447)
			(xy 458.145008 -364.88141) (xy 458.090165 -364.87128) (xy 458.037381 -364.853273) (xy 457.987781 -364.827772)
			(xy 457.942423 -364.795321) (xy 457.902274 -364.756612) (xy 457.868188 -364.712469) (xy 457.840892 -364.663834)
			(xy 457.820969 -364.611743) (xy 457.808843 -364.557306) (xy 457.804772 -364.501684) (xy 400.574764 -364.501684)
			(xy 399.799302 -365.277146) (xy 451.28764 -365.277146) (xy 451.291711 -365.221524) (xy 451.303837 -365.167087)
			(xy 451.32376 -365.114996) (xy 451.351056 -365.066361) (xy 451.385142 -365.022218) (xy 451.425291 -364.983509)
			(xy 451.470649 -364.951058) (xy 451.520249 -364.925557) (xy 451.573033 -364.90755) (xy 451.627876 -364.89742)
			(xy 451.68361 -364.895383) (xy 451.739047 -364.901483) (xy 451.793004 -364.915589) (xy 451.844333 -364.937401)
			(xy 451.891939 -364.966455) (xy 451.934807 -365.00213) (xy 451.972024 -365.043667) (xy 452.002797 -365.09018)
			(xy 452.025073 -365.1377) (xy 452.545194 -365.1377) (xy 452.549265 -365.082078) (xy 452.561391 -365.027641)
			(xy 452.581314 -364.97555) (xy 452.60861 -364.926915) (xy 452.642696 -364.882772) (xy 452.682845 -364.844063)
			(xy 452.728203 -364.811612) (xy 452.777803 -364.786111) (xy 452.830587 -364.768104) (xy 452.88543 -364.757974)
			(xy 452.941164 -364.755937) (xy 452.996601 -364.762037) (xy 453.050558 -364.776143) (xy 453.101887 -364.797955)
			(xy 453.149493 -364.827009) (xy 453.192361 -364.862684) (xy 453.229578 -364.904221) (xy 453.260351 -364.950734)
			(xy 453.284023 -365.001231) (xy 453.300091 -365.054638) (xy 453.308211 -365.109814) (xy 453.30872 -365.1377)
			(xy 453.308211 -365.165586) (xy 453.304278 -365.19231) (xy 453.705212 -365.19231) (xy 453.709283 -365.136688)
			(xy 453.721409 -365.082251) (xy 453.741332 -365.03016) (xy 453.768628 -364.981525) (xy 453.802714 -364.937382)
			(xy 453.842863 -364.898673) (xy 453.888221 -364.866222) (xy 453.937821 -364.840721) (xy 453.990605 -364.822714)
			(xy 454.045448 -364.812584) (xy 454.101182 -364.810547) (xy 454.156619 -364.816647) (xy 454.210576 -364.830753)
			(xy 454.261905 -364.852565) (xy 454.309511 -364.881619) (xy 454.352379 -364.917294) (xy 454.389596 -364.958831)
			(xy 454.420369 -365.005344) (xy 454.444041 -365.055841) (xy 454.460109 -365.109248) (xy 454.468229 -365.164424)
			(xy 454.468738 -365.19231) (xy 454.468229 -365.220196) (xy 454.460109 -365.275372) (xy 454.444041 -365.328779)
			(xy 454.420369 -365.379276) (xy 454.389596 -365.425789) (xy 454.352379 -365.467326) (xy 454.309511 -365.503001)
			(xy 454.261905 -365.532055) (xy 454.210576 -365.553867) (xy 454.156619 -365.567973) (xy 454.101182 -365.574073)
			(xy 454.045448 -365.572036) (xy 453.990605 -365.561906) (xy 453.937821 -365.543899) (xy 453.888221 -365.518398)
			(xy 453.842863 -365.485947) (xy 453.802714 -365.447238) (xy 453.768628 -365.403095) (xy 453.741332 -365.35446)
			(xy 453.721409 -365.302369) (xy 453.709283 -365.247932) (xy 453.705212 -365.19231) (xy 453.304278 -365.19231)
			(xy 453.300091 -365.220762) (xy 453.284023 -365.274169) (xy 453.260351 -365.324666) (xy 453.229578 -365.371179)
			(xy 453.192361 -365.412716) (xy 453.149493 -365.448391) (xy 453.101887 -365.477445) (xy 453.050558 -365.499257)
			(xy 452.996601 -365.513363) (xy 452.941164 -365.519463) (xy 452.88543 -365.517426) (xy 452.830587 -365.507296)
			(xy 452.777803 -365.489289) (xy 452.728203 -365.463788) (xy 452.682845 -365.431337) (xy 452.642696 -365.392628)
			(xy 452.60861 -365.348485) (xy 452.581314 -365.29985) (xy 452.561391 -365.247759) (xy 452.549265 -365.193322)
			(xy 452.545194 -365.1377) (xy 452.025073 -365.1377) (xy 452.026469 -365.140677) (xy 452.042537 -365.194084)
			(xy 452.050657 -365.24926) (xy 452.051166 -365.277146) (xy 452.050657 -365.305032) (xy 452.042537 -365.360208)
			(xy 452.026469 -365.413615) (xy 452.002797 -365.464112) (xy 451.972024 -365.510625) (xy 451.934807 -365.552162)
			(xy 451.891939 -365.587837) (xy 451.844333 -365.616891) (xy 451.793004 -365.638703) (xy 451.739047 -365.652809)
			(xy 451.68361 -365.658909) (xy 451.627876 -365.656872) (xy 451.573033 -365.646742) (xy 451.520249 -365.628735)
			(xy 451.470649 -365.603234) (xy 451.425291 -365.570783) (xy 451.385142 -365.532074) (xy 451.351056 -365.487931)
			(xy 451.32376 -365.439296) (xy 451.303837 -365.387205) (xy 451.291711 -365.332768) (xy 451.28764 -365.277146)
			(xy 399.799302 -365.277146) (xy 399.188432 -365.888016) (xy 406.102564 -365.888016) (xy 406.106635 -365.832394)
			(xy 406.118761 -365.777957) (xy 406.138684 -365.725866) (xy 406.16598 -365.677231) (xy 406.200066 -365.633088)
			(xy 406.240215 -365.594379) (xy 406.285573 -365.561928) (xy 406.335173 -365.536427) (xy 406.387957 -365.51842)
			(xy 406.4428 -365.50829) (xy 406.498534 -365.506253) (xy 406.553971 -365.512353) (xy 406.607928 -365.526459)
			(xy 406.659257 -365.548271) (xy 406.706863 -365.577325) (xy 406.749731 -365.613) (xy 406.786948 -365.654537)
			(xy 406.817721 -365.70105) (xy 406.841393 -365.751547) (xy 406.857461 -365.804954) (xy 406.865581 -365.86013)
			(xy 406.86609 -365.888016) (xy 406.865581 -365.915902) (xy 406.857461 -365.971078) (xy 406.841393 -366.024485)
			(xy 406.817721 -366.074982) (xy 406.786948 -366.121495) (xy 406.749731 -366.163032) (xy 406.706863 -366.198707)
			(xy 406.659257 -366.227761) (xy 406.607928 -366.249573) (xy 406.553971 -366.263679) (xy 406.498534 -366.269779)
			(xy 406.4428 -366.267742) (xy 406.387957 -366.257612) (xy 406.335173 -366.239605) (xy 406.285573 -366.214104)
			(xy 406.240215 -366.181653) (xy 406.200066 -366.142944) (xy 406.16598 -366.098801) (xy 406.138684 -366.050166)
			(xy 406.118761 -365.998075) (xy 406.106635 -365.943638) (xy 406.102564 -365.888016) (xy 399.188432 -365.888016)
			(xy 398.66697 -366.409478) (xy 405.202642 -366.409478) (xy 405.206713 -366.353856) (xy 405.218839 -366.299419)
			(xy 405.238762 -366.247328) (xy 405.266058 -366.198693) (xy 405.300144 -366.15455) (xy 405.340293 -366.115841)
			(xy 405.385651 -366.08339) (xy 405.435251 -366.057889) (xy 405.488035 -366.039882) (xy 405.542878 -366.029752)
			(xy 405.598612 -366.027715) (xy 405.654049 -366.033815) (xy 405.708006 -366.047921) (xy 405.759335 -366.069733)
			(xy 405.806941 -366.098787) (xy 405.849809 -366.134462) (xy 405.887026 -366.175999) (xy 405.917799 -366.222512)
			(xy 405.941471 -366.273009) (xy 405.957539 -366.326416) (xy 405.965659 -366.381592) (xy 405.966168 -366.409478)
			(xy 405.965659 -366.437364) (xy 405.957539 -366.49254) (xy 405.941471 -366.545947) (xy 405.917799 -366.596444)
			(xy 405.887026 -366.642957) (xy 405.849809 -366.684494) (xy 405.826839 -366.70361) (xy 453.285096 -366.70361)
			(xy 453.289167 -366.647988) (xy 453.301293 -366.593551) (xy 453.321216 -366.54146) (xy 453.348512 -366.492825)
			(xy 453.382598 -366.448682) (xy 453.422747 -366.409973) (xy 453.468105 -366.377522) (xy 453.517705 -366.352021)
			(xy 453.570489 -366.334014) (xy 453.625332 -366.323884) (xy 453.681066 -366.321847) (xy 453.736503 -366.327947)
			(xy 453.79046 -366.342053) (xy 453.841789 -366.363865) (xy 453.889395 -366.392919) (xy 453.932263 -366.428594)
			(xy 453.96948 -366.470131) (xy 454.000253 -366.516644) (xy 454.023925 -366.567141) (xy 454.039993 -366.620548)
			(xy 454.048113 -366.675724) (xy 454.048622 -366.70361) (xy 454.048113 -366.731496) (xy 454.039993 -366.786672)
			(xy 454.023925 -366.840079) (xy 454.000253 -366.890576) (xy 453.984807 -366.913922) (xy 455.642978 -366.913922)
			(xy 455.647049 -366.8583) (xy 455.659175 -366.803863) (xy 455.679098 -366.751772) (xy 455.706394 -366.703137)
			(xy 455.74048 -366.658994) (xy 455.780629 -366.620285) (xy 455.825987 -366.587834) (xy 455.875587 -366.562333)
			(xy 455.928371 -366.544326) (xy 455.983214 -366.534196) (xy 456.038948 -366.532159) (xy 456.094385 -366.538259)
			(xy 456.148342 -366.552365) (xy 456.199671 -366.574177) (xy 456.247277 -366.603231) (xy 456.290145 -366.638906)
			(xy 456.327362 -366.680443) (xy 456.358135 -366.726956) (xy 456.381807 -366.777453) (xy 456.397875 -366.83086)
			(xy 456.405995 -366.886036) (xy 456.406504 -366.913922) (xy 458.450694 -366.913922) (xy 458.454765 -366.8583)
			(xy 458.466891 -366.803863) (xy 458.486814 -366.751772) (xy 458.51411 -366.703137) (xy 458.548196 -366.658994)
			(xy 458.588345 -366.620285) (xy 458.633703 -366.587834) (xy 458.683303 -366.562333) (xy 458.736087 -366.544326)
			(xy 458.79093 -366.534196) (xy 458.846664 -366.532159) (xy 458.902101 -366.538259) (xy 458.956058 -366.552365)
			(xy 459.007387 -366.574177) (xy 459.054993 -366.603231) (xy 459.097861 -366.638906) (xy 459.135078 -366.680443)
			(xy 459.165851 -366.726956) (xy 459.189523 -366.777453) (xy 459.205591 -366.83086) (xy 459.213711 -366.886036)
			(xy 459.21422 -366.913922) (xy 459.213711 -366.941808) (xy 459.205591 -366.996984) (xy 459.189523 -367.050391)
			(xy 459.165851 -367.100888) (xy 459.135078 -367.147401) (xy 459.097861 -367.188938) (xy 459.054993 -367.224613)
			(xy 459.007387 -367.253667) (xy 458.956058 -367.275479) (xy 458.902101 -367.289585) (xy 458.846664 -367.295685)
			(xy 458.79093 -367.293648) (xy 458.736087 -367.283518) (xy 458.683303 -367.265511) (xy 458.633703 -367.24001)
			(xy 458.588345 -367.207559) (xy 458.548196 -367.16885) (xy 458.51411 -367.124707) (xy 458.486814 -367.076072)
			(xy 458.466891 -367.023981) (xy 458.454765 -366.969544) (xy 458.450694 -366.913922) (xy 456.406504 -366.913922)
			(xy 456.405995 -366.941808) (xy 456.397875 -366.996984) (xy 456.381807 -367.050391) (xy 456.358135 -367.100888)
			(xy 456.327362 -367.147401) (xy 456.290145 -367.188938) (xy 456.247277 -367.224613) (xy 456.199671 -367.253667)
			(xy 456.148342 -367.275479) (xy 456.094385 -367.289585) (xy 456.038948 -367.295685) (xy 455.983214 -367.293648)
			(xy 455.928371 -367.283518) (xy 455.875587 -367.265511) (xy 455.825987 -367.24001) (xy 455.780629 -367.207559)
			(xy 455.74048 -367.16885) (xy 455.706394 -367.124707) (xy 455.679098 -367.076072) (xy 455.659175 -367.023981)
			(xy 455.647049 -366.969544) (xy 455.642978 -366.913922) (xy 453.984807 -366.913922) (xy 453.96948 -366.937089)
			(xy 453.932263 -366.978626) (xy 453.889395 -367.014301) (xy 453.841789 -367.043355) (xy 453.79046 -367.065167)
			(xy 453.736503 -367.079273) (xy 453.681066 -367.085373) (xy 453.625332 -367.083336) (xy 453.570489 -367.073206)
			(xy 453.517705 -367.055199) (xy 453.468105 -367.029698) (xy 453.422747 -366.997247) (xy 453.382598 -366.958538)
			(xy 453.348512 -366.914395) (xy 453.321216 -366.86576) (xy 453.301293 -366.813669) (xy 453.289167 -366.759232)
			(xy 453.285096 -366.70361) (xy 405.826839 -366.70361) (xy 405.806941 -366.720169) (xy 405.759335 -366.749223)
			(xy 405.708006 -366.771035) (xy 405.654049 -366.785141) (xy 405.598612 -366.791241) (xy 405.542878 -366.789204)
			(xy 405.488035 -366.779074) (xy 405.435251 -366.761067) (xy 405.385651 -366.735566) (xy 405.340293 -366.703115)
			(xy 405.300144 -366.664406) (xy 405.266058 -366.620263) (xy 405.238762 -366.571628) (xy 405.218839 -366.519537)
			(xy 405.206713 -366.4651) (xy 405.202642 -366.409478) (xy 398.66697 -366.409478) (xy 397.668496 -367.407952)
			(xy 405.214326 -367.407952) (xy 405.218397 -367.35233) (xy 405.230523 -367.297893) (xy 405.250446 -367.245802)
			(xy 405.277742 -367.197167) (xy 405.311828 -367.153024) (xy 405.351977 -367.114315) (xy 405.397335 -367.081864)
			(xy 405.446935 -367.056363) (xy 405.499719 -367.038356) (xy 405.554562 -367.028226) (xy 405.610296 -367.026189)
			(xy 405.665733 -367.032289) (xy 405.71969 -367.046395) (xy 405.771019 -367.068207) (xy 405.818625 -367.097261)
			(xy 405.861493 -367.132936) (xy 405.89871 -367.174473) (xy 405.929483 -367.220986) (xy 405.953155 -367.271483)
			(xy 405.969223 -367.32489) (xy 405.977343 -367.380066) (xy 405.977852 -367.407952) (xy 405.977343 -367.435838)
			(xy 405.969223 -367.491014) (xy 405.953155 -367.544421) (xy 405.929483 -367.594918) (xy 405.89871 -367.641431)
			(xy 405.861493 -367.682968) (xy 405.818625 -367.718643) (xy 405.771019 -367.747697) (xy 405.71969 -367.769509)
			(xy 405.665733 -367.783615) (xy 405.610296 -367.789715) (xy 405.554562 -367.787678) (xy 405.499719 -367.777548)
			(xy 405.446935 -367.759541) (xy 405.397335 -367.73404) (xy 405.351977 -367.701589) (xy 405.311828 -367.66288)
			(xy 405.277742 -367.618737) (xy 405.250446 -367.570102) (xy 405.230523 -367.518011) (xy 405.218397 -367.463574)
			(xy 405.214326 -367.407952) (xy 397.668496 -367.407952) (xy 397.013176 -368.063272) (xy 406.102564 -368.063272)
			(xy 406.106635 -368.00765) (xy 406.118761 -367.953213) (xy 406.138684 -367.901122) (xy 406.16598 -367.852487)
			(xy 406.200066 -367.808344) (xy 406.240215 -367.769635) (xy 406.285573 -367.737184) (xy 406.335173 -367.711683)
			(xy 406.387957 -367.693676) (xy 406.4428 -367.683546) (xy 406.498534 -367.681509) (xy 406.553971 -367.687609)
			(xy 406.607928 -367.701715) (xy 406.659257 -367.723527) (xy 406.706863 -367.752581) (xy 406.749731 -367.788256)
			(xy 406.786948 -367.829793) (xy 406.817721 -367.876306) (xy 406.841393 -367.926803) (xy 406.857461 -367.98021)
			(xy 406.865581 -368.035386) (xy 406.86609 -368.063272) (xy 406.865581 -368.091158) (xy 406.857461 -368.146334)
			(xy 406.841393 -368.199741) (xy 406.817721 -368.250238) (xy 406.786948 -368.296751) (xy 406.749731 -368.338288)
			(xy 406.706863 -368.373963) (xy 406.659257 -368.403017) (xy 406.607928 -368.424829) (xy 406.553971 -368.438935)
			(xy 406.498534 -368.445035) (xy 406.4428 -368.442998) (xy 406.387957 -368.432868) (xy 406.335173 -368.414861)
			(xy 406.285573 -368.38936) (xy 406.240215 -368.356909) (xy 406.200066 -368.3182) (xy 406.16598 -368.274057)
			(xy 406.138684 -368.225422) (xy 406.118761 -368.173331) (xy 406.106635 -368.118894) (xy 406.102564 -368.063272)
			(xy 397.013176 -368.063272) (xy 396.211298 -368.86515) (xy 396.207778 -368.868881) (xy 396.202153 -368.877457)
			(xy 396.200122 -368.882168) (xy 396.196566 -368.890804) (xy 396.196566 -369.174268) (xy 406.517854 -369.174268)
			(xy 406.521925 -369.118646) (xy 406.534051 -369.064209) (xy 406.553974 -369.012118) (xy 406.58127 -368.963483)
			(xy 406.615356 -368.91934) (xy 406.655505 -368.880631) (xy 406.700863 -368.84818) (xy 406.750463 -368.822679)
			(xy 406.803247 -368.804672) (xy 406.85809 -368.794542) (xy 406.913824 -368.792505) (xy 406.969261 -368.798605)
			(xy 407.023218 -368.812711) (xy 407.074547 -368.834523) (xy 407.122153 -368.863577) (xy 407.165021 -368.899252)
			(xy 407.202238 -368.940789) (xy 407.233011 -368.987302) (xy 407.234331 -368.990118) (xy 421.203636 -368.990118)
			(xy 421.207627 -368.927951) (xy 421.219536 -368.866804) (xy 421.239165 -368.807683) (xy 421.266194 -368.751557)
			(xy 421.300178 -368.699348) (xy 421.34056 -368.651913) (xy 421.386676 -368.610032) (xy 421.437768 -368.574392)
			(xy 421.492999 -368.545578) (xy 421.551461 -368.524064) (xy 421.612195 -368.510202) (xy 421.674202 -368.50422)
			(xy 421.736465 -368.506216) (xy 421.797962 -368.516159) (xy 421.857683 -368.533883) (xy 421.914646 -368.5591)
			(xy 421.967917 -368.591393) (xy 422.016622 -368.630233) (xy 422.059959 -368.674983) (xy 422.097219 -368.724907)
			(xy 422.127788 -368.779186) (xy 422.151166 -368.836929) (xy 422.166967 -368.897187) (xy 422.174933 -368.95897)
			(xy 422.175432 -368.990118) (xy 425.603678 -368.990118) (xy 425.607669 -368.927951) (xy 425.619578 -368.866804)
			(xy 425.639207 -368.807683) (xy 425.666236 -368.751557) (xy 425.70022 -368.699348) (xy 425.740602 -368.651913)
			(xy 425.786718 -368.610032) (xy 425.83781 -368.574392) (xy 425.893041 -368.545578) (xy 425.951503 -368.524064)
			(xy 426.012237 -368.510202) (xy 426.074244 -368.50422) (xy 426.136507 -368.506216) (xy 426.198004 -368.516159)
			(xy 426.257725 -368.533883) (xy 426.314688 -368.5591) (xy 426.367959 -368.591393) (xy 426.416664 -368.630233)
			(xy 426.460001 -368.674983) (xy 426.497261 -368.724907) (xy 426.52783 -368.779186) (xy 426.551208 -368.836929)
			(xy 426.567009 -368.897187) (xy 426.574975 -368.95897) (xy 426.575474 -368.990118) (xy 430.00372 -368.990118)
			(xy 430.007711 -368.927951) (xy 430.01962 -368.866804) (xy 430.039249 -368.807683) (xy 430.066278 -368.751557)
			(xy 430.100262 -368.699348) (xy 430.140644 -368.651913) (xy 430.18676 -368.610032) (xy 430.237852 -368.574392)
			(xy 430.293083 -368.545578) (xy 430.351545 -368.524064) (xy 430.412279 -368.510202) (xy 430.474286 -368.50422)
			(xy 430.536549 -368.506216) (xy 430.598046 -368.516159) (xy 430.657767 -368.533883) (xy 430.71473 -368.5591)
			(xy 430.768001 -368.591393) (xy 430.816706 -368.630233) (xy 430.860043 -368.674983) (xy 430.897303 -368.724907)
			(xy 430.927872 -368.779186) (xy 430.95125 -368.836929) (xy 430.967051 -368.897187) (xy 430.975017 -368.95897)
			(xy 430.975516 -368.990118) (xy 434.403762 -368.990118) (xy 434.407753 -368.927951) (xy 434.419662 -368.866804)
			(xy 434.439291 -368.807683) (xy 434.46632 -368.751557) (xy 434.500304 -368.699348) (xy 434.540686 -368.651913)
			(xy 434.586802 -368.610032) (xy 434.637894 -368.574392) (xy 434.693125 -368.545578) (xy 434.751587 -368.524064)
			(xy 434.812321 -368.510202) (xy 434.874328 -368.50422) (xy 434.936591 -368.506216) (xy 434.998088 -368.516159)
			(xy 435.057809 -368.533883) (xy 435.114772 -368.5591) (xy 435.168043 -368.591393) (xy 435.216748 -368.630233)
			(xy 435.260085 -368.674983) (xy 435.297345 -368.724907) (xy 435.327914 -368.779186) (xy 435.351292 -368.836929)
			(xy 435.367093 -368.897187) (xy 435.375059 -368.95897) (xy 435.375558 -368.990118) (xy 438.803804 -368.990118)
			(xy 438.807795 -368.927951) (xy 438.819704 -368.866804) (xy 438.839333 -368.807683) (xy 438.866362 -368.751557)
			(xy 438.900346 -368.699348) (xy 438.940728 -368.651913) (xy 438.986844 -368.610032) (xy 439.037936 -368.574392)
			(xy 439.093167 -368.545578) (xy 439.151629 -368.524064) (xy 439.212363 -368.510202) (xy 439.27437 -368.50422)
			(xy 439.336633 -368.506216) (xy 439.39813 -368.516159) (xy 439.457851 -368.533883) (xy 439.514814 -368.5591)
			(xy 439.568085 -368.591393) (xy 439.61679 -368.630233) (xy 439.660127 -368.674983) (xy 439.697387 -368.724907)
			(xy 439.727956 -368.779186) (xy 439.751334 -368.836929) (xy 439.767135 -368.897187) (xy 439.775101 -368.95897)
			(xy 439.7756 -368.990118) (xy 439.775101 -369.021266) (xy 439.767135 -369.083049) (xy 439.751334 -369.143307)
			(xy 439.727956 -369.20105) (xy 439.697387 -369.255329) (xy 439.660127 -369.305253) (xy 439.61679 -369.350003)
			(xy 439.568085 -369.388843) (xy 439.514814 -369.421136) (xy 439.457851 -369.446353) (xy 439.39813 -369.464077)
			(xy 439.336633 -369.47402) (xy 439.27437 -369.476016) (xy 439.212363 -369.470034) (xy 439.151629 -369.456172)
			(xy 439.093167 -369.434658) (xy 439.037936 -369.405844) (xy 438.986844 -369.370204) (xy 438.940728 -369.328323)
			(xy 438.900346 -369.280888) (xy 438.866362 -369.228679) (xy 438.839333 -369.172553) (xy 438.819704 -369.113432)
			(xy 438.807795 -369.052285) (xy 438.803804 -368.990118) (xy 435.375558 -368.990118) (xy 435.375059 -369.021266)
			(xy 435.367093 -369.083049) (xy 435.351292 -369.143307) (xy 435.327914 -369.20105) (xy 435.297345 -369.255329)
			(xy 435.260085 -369.305253) (xy 435.216748 -369.350003) (xy 435.168043 -369.388843) (xy 435.114772 -369.421136)
			(xy 435.057809 -369.446353) (xy 434.998088 -369.464077) (xy 434.936591 -369.47402) (xy 434.874328 -369.476016)
			(xy 434.812321 -369.470034) (xy 434.751587 -369.456172) (xy 434.693125 -369.434658) (xy 434.637894 -369.405844)
			(xy 434.586802 -369.370204) (xy 434.540686 -369.328323) (xy 434.500304 -369.280888) (xy 434.46632 -369.228679)
			(xy 434.439291 -369.172553) (xy 434.419662 -369.113432) (xy 434.407753 -369.052285) (xy 434.403762 -368.990118)
			(xy 430.975516 -368.990118) (xy 430.975017 -369.021266) (xy 430.967051 -369.083049) (xy 430.95125 -369.143307)
			(xy 430.927872 -369.20105) (xy 430.897303 -369.255329) (xy 430.860043 -369.305253) (xy 430.816706 -369.350003)
			(xy 430.768001 -369.388843) (xy 430.71473 -369.421136) (xy 430.657767 -369.446353) (xy 430.598046 -369.464077)
			(xy 430.536549 -369.47402) (xy 430.474286 -369.476016) (xy 430.412279 -369.470034) (xy 430.351545 -369.456172)
			(xy 430.293083 -369.434658) (xy 430.237852 -369.405844) (xy 430.18676 -369.370204) (xy 430.140644 -369.328323)
			(xy 430.100262 -369.280888) (xy 430.066278 -369.228679) (xy 430.039249 -369.172553) (xy 430.01962 -369.113432)
			(xy 430.007711 -369.052285) (xy 430.00372 -368.990118) (xy 426.575474 -368.990118) (xy 426.574975 -369.021266)
			(xy 426.567009 -369.083049) (xy 426.551208 -369.143307) (xy 426.52783 -369.20105) (xy 426.497261 -369.255329)
			(xy 426.460001 -369.305253) (xy 426.416664 -369.350003) (xy 426.367959 -369.388843) (xy 426.314688 -369.421136)
			(xy 426.257725 -369.446353) (xy 426.198004 -369.464077) (xy 426.136507 -369.47402) (xy 426.074244 -369.476016)
			(xy 426.012237 -369.470034) (xy 425.951503 -369.456172) (xy 425.893041 -369.434658) (xy 425.83781 -369.405844)
			(xy 425.786718 -369.370204) (xy 425.740602 -369.328323) (xy 425.70022 -369.280888) (xy 425.666236 -369.228679)
			(xy 425.639207 -369.172553) (xy 425.619578 -369.113432) (xy 425.607669 -369.052285) (xy 425.603678 -368.990118)
			(xy 422.175432 -368.990118) (xy 422.174933 -369.021266) (xy 422.166967 -369.083049) (xy 422.151166 -369.143307)
			(xy 422.127788 -369.20105) (xy 422.097219 -369.255329) (xy 422.059959 -369.305253) (xy 422.016622 -369.350003)
			(xy 421.967917 -369.388843) (xy 421.914646 -369.421136) (xy 421.857683 -369.446353) (xy 421.797962 -369.464077)
			(xy 421.736465 -369.47402) (xy 421.674202 -369.476016) (xy 421.612195 -369.470034) (xy 421.551461 -369.456172)
			(xy 421.492999 -369.434658) (xy 421.437768 -369.405844) (xy 421.386676 -369.370204) (xy 421.34056 -369.328323)
			(xy 421.300178 -369.280888) (xy 421.266194 -369.228679) (xy 421.239165 -369.172553) (xy 421.219536 -369.113432)
			(xy 421.207627 -369.052285) (xy 421.203636 -368.990118) (xy 407.234331 -368.990118) (xy 407.256683 -369.037799)
			(xy 407.272751 -369.091206) (xy 407.280871 -369.146382) (xy 407.28138 -369.174268) (xy 407.280871 -369.202154)
			(xy 407.272751 -369.25733) (xy 407.256683 -369.310737) (xy 407.233011 -369.361234) (xy 407.202238 -369.407747)
			(xy 407.165021 -369.449284) (xy 407.122153 -369.484959) (xy 407.074547 -369.514013) (xy 407.023218 -369.535825)
			(xy 406.969261 -369.549931) (xy 406.913824 -369.556031) (xy 406.85809 -369.553994) (xy 406.803247 -369.543864)
			(xy 406.750463 -369.525857) (xy 406.700863 -369.500356) (xy 406.655505 -369.467905) (xy 406.615356 -369.429196)
			(xy 406.58127 -369.385053) (xy 406.553974 -369.336418) (xy 406.534051 -369.284327) (xy 406.521925 -369.22989)
			(xy 406.517854 -369.174268) (xy 396.196566 -369.174268) (xy 396.196566 -371.019578) (xy 404.149814 -371.019578)
			(xy 404.150207 -370.99322) (xy 404.157455 -370.941005) (xy 404.171825 -370.890286) (xy 404.193043 -370.842029)
			(xy 404.220703 -370.797153) (xy 404.25428 -370.756514) (xy 404.293133 -370.720885) (xy 404.336523 -370.690947)
			(xy 404.359872 -370.67871) (xy 404.372456 -370.671818) (xy 404.393539 -370.652384) (xy 404.408375 -370.627847)
			(xy 404.41579 -370.600149) (xy 404.415198 -370.571482) (xy 404.406645 -370.544113) (xy 404.390808 -370.52021)
			(xy 404.380192 -370.510562) (xy 404.359429 -370.492363) (xy 404.322896 -370.450966) (xy 404.292711 -370.404736)
			(xy 404.269504 -370.354639) (xy 404.253758 -370.30172) (xy 404.245804 -370.247084) (xy 404.245318 -370.219478)
			(xy 404.245804 -370.192227) (xy 404.25356 -370.138279) (xy 404.268915 -370.085984) (xy 404.291557 -370.036407)
			(xy 404.321023 -369.990557) (xy 404.356714 -369.949366) (xy 404.397905 -369.913675) (xy 404.443755 -369.884209)
			(xy 404.493332 -369.861567) (xy 404.545627 -369.846212) (xy 404.599575 -369.838456) (xy 404.654077 -369.838456)
			(xy 404.708025 -369.846212) (xy 404.76032 -369.861567) (xy 404.809897 -369.884209) (xy 404.855747 -369.913675)
			(xy 404.896938 -369.949366) (xy 404.932629 -369.990557) (xy 404.962095 -370.036407) (xy 404.984737 -370.085984)
			(xy 405.000092 -370.138279) (xy 405.007848 -370.192227) (xy 405.008334 -370.219478) (xy 405.007879 -370.245834)
			(xy 405.000637 -370.298045) (xy 404.986275 -370.348761) (xy 404.965066 -370.397017) (xy 404.937414 -370.441893)
			(xy 404.903846 -370.482533) (xy 404.865002 -370.518164) (xy 404.858417 -370.522709) (xy 419.004833 -370.522709)
			(xy 419.004834 -370.457271) (xy 419.01362 -370.392425) (xy 419.031031 -370.329346) (xy 419.056752 -370.269175)
			(xy 419.073076 -370.240814) (xy 419.076384 -370.234786) (xy 419.079994 -370.221525) (xy 419.080188 -370.214652)
			(xy 419.080188 -369.928902) (xy 419.080567 -369.918724) (xy 419.08836 -369.89992) (xy 419.10276 -369.885533)
			(xy 419.121572 -369.877757) (xy 419.13175 -369.87734) (xy 419.84803 -369.87734) (xy 419.85819 -369.877809)
			(xy 419.87696 -369.885593) (xy 419.891325 -369.899967) (xy 419.899098 -369.918742) (xy 419.899592 -369.928902)
			(xy 419.899592 -370.214652) (xy 419.899804 -370.221524) (xy 419.903399 -370.234786) (xy 419.906704 -370.240814)
			(xy 419.923015 -370.269181) (xy 419.948731 -370.329352) (xy 419.966139 -370.392429) (xy 419.974923 -370.457272)
			(xy 419.974924 -370.522707) (xy 419.966143 -370.587551) (xy 419.948738 -370.650629) (xy 419.923024 -370.7108)
			(xy 419.906704 -370.739162) (xy 419.903403 -370.745193) (xy 419.899789 -370.758452) (xy 419.899592 -370.765324)
			(xy 419.899592 -371.514878) (xy 419.899793 -371.521751) (xy 419.903395 -371.535013) (xy 419.906704 -371.54104)
			(xy 419.923037 -371.569395) (xy 419.948751 -371.629568) (xy 419.966156 -371.692648) (xy 419.974937 -371.757493)
			(xy 419.974936 -371.822931) (xy 419.966151 -371.887775) (xy 419.948743 -371.950854) (xy 419.923026 -372.011026)
			(xy 419.906704 -372.039388) (xy 419.903394 -372.045415) (xy 419.899785 -372.058677) (xy 419.899592 -372.06555)
			(xy 419.899592 -372.351554) (xy 419.899099 -372.361719) (xy 419.891335 -372.380507) (xy 419.876971 -372.394892)
			(xy 419.858194 -372.402684) (xy 419.84803 -372.403116) (xy 419.13175 -372.403116) (xy 419.121576 -372.402694)
			(xy 419.102773 -372.394917) (xy 419.088385 -372.38053) (xy 419.080607 -372.361728) (xy 419.080188 -372.351554)
			(xy 419.080188 -372.06555) (xy 419.079978 -372.058678) (xy 419.076382 -372.045415) (xy 419.073076 -372.039388)
			(xy 419.056764 -372.011021) (xy 419.031044 -371.950851) (xy 419.013633 -371.887774) (xy 419.004847 -371.82293)
			(xy 419.004846 -371.757494) (xy 419.013628 -371.69265) (xy 419.031036 -371.629571) (xy 419.056754 -371.569401)
			(xy 419.073076 -371.54104) (xy 419.076375 -371.535008) (xy 419.079991 -371.52175) (xy 419.080188 -371.514878)
			(xy 419.080188 -370.765324) (xy 419.079988 -370.758451) (xy 419.076385 -370.745189) (xy 419.073076 -370.739162)
			(xy 419.056742 -370.710807) (xy 419.031024 -370.650635) (xy 419.013615 -370.587555) (xy 419.004833 -370.522709)
			(xy 404.858417 -370.522709) (xy 404.821621 -370.548106) (xy 404.798276 -370.560346) (xy 404.785647 -370.567166)
			(xy 404.764551 -370.58661) (xy 404.749709 -370.611162) (xy 404.742295 -370.638877) (xy 404.742897 -370.66756)
			(xy 404.751468 -370.69494) (xy 404.767328 -370.718847) (xy 404.777956 -370.728494) (xy 404.798687 -370.746728)
			(xy 404.835224 -370.788116) (xy 404.865415 -370.834338) (xy 404.888629 -370.884429) (xy 404.90438 -370.937342)
			(xy 404.91234 -370.991974) (xy 404.912627 -371.008148) (xy 405.37206 -371.008148) (xy 405.376131 -370.952526)
			(xy 405.388257 -370.898089) (xy 405.40818 -370.845998) (xy 405.435476 -370.797363) (xy 405.469562 -370.75322)
			(xy 405.509711 -370.714511) (xy 405.555069 -370.68206) (xy 405.604669 -370.656559) (xy 405.657453 -370.638552)
			(xy 405.712296 -370.628422) (xy 405.76803 -370.626385) (xy 405.823467 -370.632485) (xy 405.877424 -370.646591)
			(xy 405.928753 -370.668403) (xy 405.976359 -370.697457) (xy 406.019227 -370.733132) (xy 406.056444 -370.774669)
			(xy 406.087217 -370.821182) (xy 406.110889 -370.871679) (xy 406.126957 -370.925086) (xy 406.135077 -370.980262)
			(xy 406.135586 -371.008148) (xy 406.135077 -371.036034) (xy 406.126957 -371.09121) (xy 406.110889 -371.144617)
			(xy 406.087217 -371.195114) (xy 406.056444 -371.241627) (xy 406.019227 -371.283164) (xy 405.976359 -371.318839)
			(xy 405.928753 -371.347893) (xy 405.877424 -371.369705) (xy 405.823467 -371.383811) (xy 405.76803 -371.389911)
			(xy 405.712296 -371.387874) (xy 405.657453 -371.377744) (xy 405.604669 -371.359737) (xy 405.555069 -371.334236)
			(xy 405.509711 -371.301785) (xy 405.469562 -371.263076) (xy 405.435476 -371.218933) (xy 405.40818 -371.170298)
			(xy 405.388257 -371.118207) (xy 405.376131 -371.06377) (xy 405.37206 -371.008148) (xy 404.912627 -371.008148)
			(xy 404.91283 -371.019578) (xy 404.912344 -371.046829) (xy 404.904588 -371.100777) (xy 404.889233 -371.153072)
			(xy 404.866591 -371.202649) (xy 404.837125 -371.248499) (xy 404.801434 -371.28969) (xy 404.760243 -371.325381)
			(xy 404.714393 -371.354847) (xy 404.664816 -371.377489) (xy 404.612521 -371.392844) (xy 404.558573 -371.4006)
			(xy 404.504071 -371.4006) (xy 404.450123 -371.392844) (xy 404.397828 -371.377489) (xy 404.348251 -371.354847)
			(xy 404.302401 -371.325381) (xy 404.26121 -371.28969) (xy 404.225519 -371.248499) (xy 404.196053 -371.202649)
			(xy 404.173411 -371.153072) (xy 404.158056 -371.100777) (xy 404.1503 -371.046829) (xy 404.149814 -371.019578)
			(xy 396.196566 -371.019578) (xy 396.196566 -372.877842) (xy 407.397202 -372.877842) (xy 407.401273 -372.82222)
			(xy 407.413399 -372.767783) (xy 407.433322 -372.715692) (xy 407.460618 -372.667057) (xy 407.494704 -372.622914)
			(xy 407.534853 -372.584205) (xy 407.580211 -372.551754) (xy 407.629811 -372.526253) (xy 407.682595 -372.508246)
			(xy 407.737438 -372.498116) (xy 407.793172 -372.496079) (xy 407.848609 -372.502179) (xy 407.902566 -372.516285)
			(xy 407.953895 -372.538097) (xy 408.001501 -372.567151) (xy 408.044369 -372.602826) (xy 408.081586 -372.644363)
			(xy 408.112359 -372.690876) (xy 408.136031 -372.741373) (xy 408.152099 -372.79478) (xy 408.160219 -372.849956)
			(xy 408.160728 -372.877842) (xy 408.160505 -372.890034) (xy 421.204136 -372.890034) (xy 421.204703 -372.857305)
			(xy 421.21356 -372.792447) (xy 421.23105 -372.729367) (xy 421.256856 -372.669208) (xy 421.273224 -372.64086)
			(xy 421.276555 -372.634843) (xy 421.28015 -372.621573) (xy 421.280336 -372.614698) (xy 421.280336 -371.865398)
			(xy 421.28014 -371.858525) (xy 421.276534 -371.845262) (xy 421.273224 -371.839236) (xy 421.256875 -371.810878)
			(xy 421.231069 -371.750722) (xy 421.213574 -371.687645) (xy 421.204709 -371.62279) (xy 421.204136 -371.590062)
			(xy 421.204716 -371.557333) (xy 421.213569 -371.492476) (xy 421.231055 -371.429396) (xy 421.256858 -371.369237)
			(xy 421.273224 -371.340888) (xy 421.276545 -371.334866) (xy 421.280146 -371.3216) (xy 421.280336 -371.314726)
			(xy 421.280336 -371.028722) (xy 421.280844 -371.018597) (xy 421.288564 -370.999877) (xy 421.302844 -370.98552)
			(xy 421.321522 -370.9777) (xy 421.331644 -370.97716) (xy 422.047924 -370.97716) (xy 422.058075 -370.977601)
			(xy 422.07682 -370.985397) (xy 422.091141 -370.999787) (xy 422.098847 -371.018569) (xy 422.099232 -371.028722)
			(xy 422.099232 -371.314726) (xy 422.09941 -371.3216) (xy 422.103028 -371.334863) (xy 422.106344 -371.340888)
			(xy 422.122699 -371.369243) (xy 422.148505 -371.4294) (xy 422.165998 -371.492478) (xy 422.174861 -371.557333)
			(xy 422.175432 -371.590062) (xy 422.174867 -371.622792) (xy 422.166011 -371.68765) (xy 422.14852 -371.75073)
			(xy 422.131582 -371.790214) (xy 423.404284 -371.790214) (xy 423.404836 -371.757484) (xy 423.413696 -371.692625)
			(xy 423.43119 -371.629545) (xy 423.457001 -371.569388) (xy 423.473372 -371.54104) (xy 423.476671 -371.535007)
			(xy 423.480287 -371.52175) (xy 423.480484 -371.514878) (xy 423.480484 -370.765324) (xy 423.480285 -370.758451)
			(xy 423.476682 -370.745188) (xy 423.473372 -370.739162) (xy 423.456989 -370.710823) (xy 423.431192 -370.650659)
			(xy 423.413707 -370.587577) (xy 423.404852 -370.522718) (xy 423.404284 -370.489988) (xy 423.404869 -370.457259)
			(xy 423.413719 -370.392402) (xy 423.431204 -370.329322) (xy 423.457006 -370.269163) (xy 423.473372 -370.240814)
			(xy 423.47668 -370.234786) (xy 423.48029 -370.221525) (xy 423.480484 -370.214652) (xy 423.480484 -369.928902)
			(xy 423.48093 -369.91877) (xy 423.488665 -369.900041) (xy 423.502964 -369.885683) (xy 423.521662 -369.877871)
			(xy 423.531792 -369.87734) (xy 424.248072 -369.87734) (xy 424.258229 -369.877745) (xy 424.276989 -369.885539)
			(xy 424.291315 -369.899942) (xy 424.299008 -369.918743) (xy 424.29938 -369.928902) (xy 424.29938 -370.214652)
			(xy 424.299593 -370.221524) (xy 424.303187 -370.234786) (xy 424.306492 -370.240814) (xy 424.322862 -370.269161)
			(xy 424.348663 -370.329321) (xy 424.366152 -370.392401) (xy 424.37501 -370.457259) (xy 424.37558 -370.489988)
			(xy 424.375034 -370.522709) (xy 427.804919 -370.522709) (xy 427.80492 -370.457271) (xy 427.813706 -370.392425)
			(xy 427.831116 -370.329346) (xy 427.856836 -370.269175) (xy 427.87316 -370.240814) (xy 427.876466 -370.234785)
			(xy 427.880078 -370.221525) (xy 427.880272 -370.214652) (xy 427.880272 -369.928902) (xy 427.880666 -369.918726)
			(xy 427.888457 -369.899925) (xy 427.902852 -369.885539) (xy 427.921658 -369.87776) (xy 427.931834 -369.87734)
			(xy 428.648114 -369.87734) (xy 428.658273 -369.877822) (xy 428.677043 -369.885602) (xy 428.691407 -369.899971)
			(xy 428.699181 -369.918743) (xy 428.699676 -369.928902) (xy 428.699676 -370.214652) (xy 428.699889 -370.221524)
			(xy 428.703483 -370.234786) (xy 428.706788 -370.240814) (xy 428.723099 -370.269181) (xy 428.748816 -370.329351)
			(xy 428.766225 -370.392429) (xy 428.775009 -370.457272) (xy 428.77501 -370.522707) (xy 428.77501 -370.522709)
			(xy 432.204708 -370.522709) (xy 432.20471 -370.457271) (xy 432.213495 -370.392426) (xy 432.230905 -370.329346)
			(xy 432.256625 -370.269175) (xy 432.272948 -370.240814) (xy 432.276254 -370.234785) (xy 432.279866 -370.221525)
			(xy 432.28006 -370.214652) (xy 432.28006 -369.928902) (xy 432.280466 -369.918728) (xy 432.288254 -369.899929)
			(xy 432.302646 -369.885543) (xy 432.321448 -369.877762) (xy 432.331622 -369.87734) (xy 433.047902 -369.87734)
			(xy 433.05806 -369.877832) (xy 433.07683 -369.885607) (xy 433.091195 -369.899974) (xy 433.098969 -369.918744)
			(xy 433.099464 -369.928902) (xy 433.099464 -370.214652) (xy 433.099679 -370.221524) (xy 433.103272 -370.234786)
			(xy 433.106576 -370.240814) (xy 433.122888 -370.269181) (xy 433.148605 -370.329351) (xy 433.166014 -370.392428)
			(xy 433.174799 -370.457272) (xy 433.174799 -370.489988) (xy 436.603656 -370.489988) (xy 436.607647 -370.427821)
			(xy 436.619556 -370.366674) (xy 436.639185 -370.307553) (xy 436.666214 -370.251427) (xy 436.700198 -370.199218)
			(xy 436.74058 -370.151783) (xy 436.786696 -370.109902) (xy 436.837788 -370.074262) (xy 436.893019 -370.045448)
			(xy 436.951481 -370.023934) (xy 437.012215 -370.010072) (xy 437.074222 -370.00409) (xy 437.136485 -370.006086)
			(xy 437.197982 -370.016029) (xy 437.257703 -370.033753) (xy 437.314666 -370.05897) (xy 437.367937 -370.091263)
			(xy 437.416642 -370.130103) (xy 437.459979 -370.174853) (xy 437.497239 -370.224777) (xy 437.527808 -370.279056)
			(xy 437.551186 -370.336799) (xy 437.566987 -370.397057) (xy 437.574953 -370.45884) (xy 437.575452 -370.489988)
			(xy 437.574953 -370.521136) (xy 437.566987 -370.582919) (xy 437.551186 -370.643177) (xy 437.527808 -370.70092)
			(xy 437.497239 -370.755199) (xy 437.459979 -370.805123) (xy 437.416642 -370.849873) (xy 437.367937 -370.888713)
			(xy 437.314666 -370.921006) (xy 437.257703 -370.946223) (xy 437.197982 -370.963947) (xy 437.136485 -370.97389)
			(xy 437.074222 -370.975886) (xy 437.012215 -370.969904) (xy 436.951481 -370.956042) (xy 436.893019 -370.934528)
			(xy 436.837788 -370.905714) (xy 436.786696 -370.870074) (xy 436.74058 -370.828193) (xy 436.700198 -370.780758)
			(xy 436.666214 -370.728549) (xy 436.639185 -370.672423) (xy 436.619556 -370.613302) (xy 436.607647 -370.552155)
			(xy 436.603656 -370.489988) (xy 433.174799 -370.489988) (xy 433.1748 -370.522708) (xy 433.166018 -370.587551)
			(xy 433.148612 -370.65063) (xy 433.122897 -370.710801) (xy 433.106576 -370.739162) (xy 433.103273 -370.745192)
			(xy 433.09966 -370.758452) (xy 433.099464 -370.765324) (xy 433.099464 -371.514878) (xy 433.099669 -371.52175)
			(xy 433.103269 -371.535013) (xy 433.106576 -371.54104) (xy 433.12291 -371.569395) (xy 433.145727 -371.622787)
			(xy 434.404849 -371.622787) (xy 434.404853 -371.557348) (xy 434.413641 -371.492502) (xy 434.431052 -371.429422)
			(xy 434.456773 -371.36925) (xy 434.473096 -371.340888) (xy 434.476415 -371.334865) (xy 434.480018 -371.3216)
			(xy 434.480208 -371.314726) (xy 434.480208 -371.028722) (xy 434.48075 -371.018569) (xy 434.488512 -370.999806)
			(xy 434.502863 -370.985441) (xy 434.521618 -370.977661) (xy 434.53177 -370.97716) (xy 435.24805 -370.97716)
			(xy 435.258221 -370.977605) (xy 435.277019 -370.985378) (xy 435.291406 -370.999758) (xy 435.299189 -371.018551)
			(xy 435.299612 -371.028722) (xy 435.299612 -371.314726) (xy 435.299792 -371.3216) (xy 435.303408 -371.334863)
			(xy 435.306724 -371.340888) (xy 435.323015 -371.369267) (xy 435.348738 -371.429433) (xy 435.366151 -371.492508)
			(xy 435.374939 -371.55735) (xy 435.374943 -371.622785) (xy 435.366164 -371.687628) (xy 435.348759 -371.750705)
			(xy 435.331875 -371.790214) (xy 436.603656 -371.790214) (xy 436.607647 -371.728047) (xy 436.619556 -371.6669)
			(xy 436.639185 -371.607779) (xy 436.666214 -371.551653) (xy 436.700198 -371.499444) (xy 436.74058 -371.452009)
			(xy 436.786696 -371.410128) (xy 436.837788 -371.374488) (xy 436.893019 -371.345674) (xy 436.951481 -371.32416)
			(xy 437.012215 -371.310298) (xy 437.074222 -371.304316) (xy 437.136485 -371.306312) (xy 437.197982 -371.316255)
			(xy 437.257703 -371.333979) (xy 437.314666 -371.359196) (xy 437.367937 -371.391489) (xy 437.416642 -371.430329)
			(xy 437.459979 -371.475079) (xy 437.497239 -371.525003) (xy 437.527808 -371.579282) (xy 437.532172 -371.590062)
			(xy 438.803804 -371.590062) (xy 438.807795 -371.527895) (xy 438.819704 -371.466748) (xy 438.839333 -371.407627)
			(xy 438.866362 -371.351501) (xy 438.900346 -371.299292) (xy 438.940728 -371.251857) (xy 438.986844 -371.209976)
			(xy 439.037936 -371.174336) (xy 439.093167 -371.145522) (xy 439.151629 -371.124008) (xy 439.212363 -371.110146)
			(xy 439.27437 -371.104164) (xy 439.336633 -371.10616) (xy 439.39813 -371.116103) (xy 439.457851 -371.133827)
			(xy 439.514814 -371.159044) (xy 439.568085 -371.191337) (xy 439.61679 -371.230177) (xy 439.660127 -371.274927)
			(xy 439.697387 -371.324851) (xy 439.727956 -371.37913) (xy 439.751334 -371.436873) (xy 439.767135 -371.497131)
			(xy 439.775101 -371.558914) (xy 439.7756 -371.590062) (xy 439.775101 -371.62121) (xy 439.767135 -371.682993)
			(xy 439.751334 -371.743251) (xy 439.727956 -371.800994) (xy 439.697387 -371.855273) (xy 439.694001 -371.85981)
			(xy 457.532994 -371.85981) (xy 457.53348 -371.832559) (xy 457.541236 -371.778611) (xy 457.556591 -371.726316)
			(xy 457.579233 -371.676739) (xy 457.608699 -371.630889) (xy 457.64439 -371.589698) (xy 457.685581 -371.554007)
			(xy 457.731431 -371.524541) (xy 457.781008 -371.501899) (xy 457.833303 -371.486544) (xy 457.887251 -371.478788)
			(xy 457.941753 -371.478788) (xy 457.995701 -371.486544) (xy 458.047996 -371.501899) (xy 458.097573 -371.524541)
			(xy 458.143423 -371.554007) (xy 458.184614 -371.589698) (xy 458.220305 -371.630889) (xy 458.249771 -371.676739)
			(xy 458.272413 -371.726316) (xy 458.287768 -371.778611) (xy 458.295524 -371.832559) (xy 458.29601 -371.85981)
			(xy 458.29539 -371.890148) (xy 458.285787 -371.950059) (xy 458.266823 -372.007696) (xy 458.238976 -372.061604)
			(xy 458.202949 -372.110427) (xy 458.18171 -372.132098) (xy 458.17212 -372.141991) (xy 458.1583 -372.165823)
			(xy 458.151349 -372.192479) (xy 458.151771 -372.220024) (xy 458.159536 -372.246455) (xy 458.174079 -372.269852)
			(xy 458.194344 -372.288513) (xy 458.218858 -372.301083) (xy 458.232256 -372.30431) (xy 458.260571 -372.310664)
			(xy 458.314998 -372.330791) (xy 458.365747 -372.358932) (xy 458.411647 -372.394436) (xy 458.451638 -372.436485)
			(xy 458.484797 -372.484106) (xy 458.510358 -372.536202) (xy 458.527732 -372.591569) (xy 458.536517 -372.648929)
			(xy 458.537056 -372.677944) (xy 458.53657 -372.705195) (xy 458.528814 -372.759143) (xy 458.513459 -372.811438)
			(xy 458.490817 -372.861015) (xy 458.461351 -372.906865) (xy 458.42566 -372.948056) (xy 458.384469 -372.983747)
			(xy 458.338619 -373.013213) (xy 458.289042 -373.035855) (xy 458.236747 -373.05121) (xy 458.182799 -373.058966)
			(xy 458.128297 -373.058966) (xy 458.074349 -373.05121) (xy 458.022054 -373.035855) (xy 457.972477 -373.013213)
			(xy 457.926627 -372.983747) (xy 457.885436 -372.948056) (xy 457.849745 -372.906865) (xy 457.820279 -372.861015)
			(xy 457.797637 -372.811438) (xy 457.782282 -372.759143) (xy 457.774526 -372.705195) (xy 457.77404 -372.677944)
			(xy 457.774616 -372.647604) (xy 457.784228 -372.58769) (xy 457.803202 -372.530053) (xy 457.831058 -372.476145)
			(xy 457.867095 -372.427325) (xy 457.88834 -372.405656) (xy 457.897843 -372.395687) (xy 457.911655 -372.371873)
			(xy 457.918606 -372.345236) (xy 457.918191 -372.317709) (xy 457.910439 -372.291294) (xy 457.895914 -372.267908)
			(xy 457.875672 -372.24925) (xy 457.851181 -372.236677) (xy 457.837794 -372.233444) (xy 457.809476 -372.227098)
			(xy 457.755046 -372.206974) (xy 457.704294 -372.178835) (xy 457.658391 -372.143331) (xy 457.618399 -372.101281)
			(xy 457.58524 -372.053657) (xy 457.55968 -372.001559) (xy 457.54231 -371.946188) (xy 457.53353 -371.888826)
			(xy 457.532994 -371.85981) (xy 439.694001 -371.85981) (xy 439.660127 -371.905197) (xy 439.61679 -371.949947)
			(xy 439.568085 -371.988787) (xy 439.514814 -372.02108) (xy 439.457851 -372.046297) (xy 439.39813 -372.064021)
			(xy 439.336633 -372.073964) (xy 439.27437 -372.07596) (xy 439.212363 -372.069978) (xy 439.151629 -372.056116)
			(xy 439.093167 -372.034602) (xy 439.037936 -372.005788) (xy 438.986844 -371.970148) (xy 438.940728 -371.928267)
			(xy 438.900346 -371.880832) (xy 438.866362 -371.828623) (xy 438.839333 -371.772497) (xy 438.819704 -371.713376)
			(xy 438.807795 -371.652229) (xy 438.803804 -371.590062) (xy 437.532172 -371.590062) (xy 437.551186 -371.637025)
			(xy 437.566987 -371.697283) (xy 437.574953 -371.759066) (xy 437.575452 -371.790214) (xy 437.574953 -371.821362)
			(xy 437.566987 -371.883145) (xy 437.551186 -371.943403) (xy 437.527808 -372.001146) (xy 437.497239 -372.055425)
			(xy 437.459979 -372.105349) (xy 437.416642 -372.150099) (xy 437.367937 -372.188939) (xy 437.314666 -372.221232)
			(xy 437.257703 -372.246449) (xy 437.197982 -372.264173) (xy 437.136485 -372.274116) (xy 437.074222 -372.276112)
			(xy 437.012215 -372.27013) (xy 436.951481 -372.256268) (xy 436.893019 -372.234754) (xy 436.837788 -372.20594)
			(xy 436.786696 -372.1703) (xy 436.74058 -372.128419) (xy 436.700198 -372.080984) (xy 436.666214 -372.028775)
			(xy 436.639185 -371.972649) (xy 436.619556 -371.913528) (xy 436.607647 -371.852381) (xy 436.603656 -371.790214)
			(xy 435.331875 -371.790214) (xy 435.323045 -371.810875) (xy 435.306724 -371.839236) (xy 435.303398 -371.845255)
			(xy 435.299799 -371.858523) (xy 435.299612 -371.865398) (xy 435.299612 -372.614698) (xy 435.299803 -372.621571)
			(xy 435.303412 -372.634834) (xy 435.306724 -372.64086) (xy 435.323076 -372.669205) (xy 435.348793 -372.72938)
			(xy 435.366199 -372.792462) (xy 435.37498 -372.857309) (xy 435.374978 -372.890034) (xy 438.803804 -372.890034)
			(xy 438.807795 -372.827867) (xy 438.819704 -372.76672) (xy 438.839333 -372.707599) (xy 438.866362 -372.651473)
			(xy 438.900346 -372.599264) (xy 438.940728 -372.551829) (xy 438.986844 -372.509948) (xy 439.037936 -372.474308)
			(xy 439.093167 -372.445494) (xy 439.151629 -372.42398) (xy 439.212363 -372.410118) (xy 439.27437 -372.404136)
			(xy 439.336633 -372.406132) (xy 439.39813 -372.416075) (xy 439.457851 -372.433799) (xy 439.514814 -372.459016)
			(xy 439.568085 -372.491309) (xy 439.61679 -372.530149) (xy 439.660127 -372.574899) (xy 439.697387 -372.624823)
			(xy 439.727956 -372.679102) (xy 439.751334 -372.736845) (xy 439.767135 -372.797103) (xy 439.775101 -372.858886)
			(xy 439.7756 -372.890034) (xy 439.775101 -372.921182) (xy 439.767135 -372.982965) (xy 439.751334 -373.043223)
			(xy 439.727956 -373.100966) (xy 439.697387 -373.155245) (xy 439.660127 -373.205169) (xy 439.61679 -373.249919)
			(xy 439.568085 -373.288759) (xy 439.514814 -373.321052) (xy 439.457851 -373.346269) (xy 439.39813 -373.363993)
			(xy 439.336633 -373.373936) (xy 439.27437 -373.375932) (xy 439.212363 -373.36995) (xy 439.151629 -373.356088)
			(xy 439.093167 -373.334574) (xy 439.037936 -373.30576) (xy 438.986844 -373.27012) (xy 438.940728 -373.228239)
			(xy 438.900346 -373.180804) (xy 438.866362 -373.128595) (xy 438.839333 -373.072469) (xy 438.819704 -373.013348)
			(xy 438.807795 -372.952201) (xy 438.803804 -372.890034) (xy 435.374978 -372.890034) (xy 435.374976 -372.922749)
			(xy 435.366188 -372.987596) (xy 435.348774 -373.050676) (xy 435.32305 -373.110847) (xy 435.306724 -373.139208)
			(xy 435.303408 -373.145232) (xy 435.299803 -373.158496) (xy 435.299612 -373.16537) (xy 435.299612 -373.451374)
			(xy 435.299532 -373.453406) (xy 451.256398 -373.453406) (xy 451.260469 -373.397784) (xy 451.272595 -373.343347)
			(xy 451.292518 -373.291256) (xy 451.319814 -373.242621) (xy 451.3539 -373.198478) (xy 451.394049 -373.159769)
			(xy 451.439407 -373.127318) (xy 451.489007 -373.101817) (xy 451.541791 -373.08381) (xy 451.596634 -373.07368)
			(xy 451.652368 -373.071643) (xy 451.707805 -373.077743) (xy 451.761762 -373.091849) (xy 451.813091 -373.113661)
			(xy 451.860697 -373.142715) (xy 451.903565 -373.17839) (xy 451.940782 -373.219927) (xy 451.971555 -373.26644)
			(xy 451.995227 -373.316937) (xy 452.011295 -373.370344) (xy 452.019415 -373.42552) (xy 452.019924 -373.453406)
			(xy 452.019415 -373.481292) (xy 452.011295 -373.536468) (xy 451.995227 -373.589875) (xy 451.971555 -373.640372)
			(xy 451.940782 -373.686885) (xy 451.903565 -373.728422) (xy 451.860697 -373.764097) (xy 451.813091 -373.793151)
			(xy 451.761762 -373.814963) (xy 451.707805 -373.829069) (xy 451.652368 -373.835169) (xy 451.596634 -373.833132)
			(xy 451.541791 -373.823002) (xy 451.489007 -373.804995) (xy 451.439407 -373.779494) (xy 451.394049 -373.747043)
			(xy 451.3539 -373.708334) (xy 451.319814 -373.664191) (xy 451.292518 -373.615556) (xy 451.272595 -373.563465)
			(xy 451.260469 -373.509028) (xy 451.256398 -373.453406) (xy 435.299532 -373.453406) (xy 435.299213 -373.46155)
			(xy 435.291428 -373.480354) (xy 435.277034 -373.494741) (xy 435.258226 -373.502518) (xy 435.24805 -373.502936)
			(xy 434.53177 -373.502936) (xy 434.521607 -373.502491) (xy 434.502832 -373.494701) (xy 434.488467 -373.480321)
			(xy 434.480698 -373.461537) (xy 434.480208 -373.451374) (xy 434.480208 -373.16537) (xy 434.480027 -373.158496)
			(xy 434.476411 -373.145233) (xy 434.473096 -373.139208) (xy 434.456804 -373.11083) (xy 434.431086 -373.050663)
			(xy 434.413676 -372.987587) (xy 434.40489 -372.922746) (xy 434.404886 -372.857312) (xy 434.413664 -372.79247)
			(xy 434.431067 -372.729393) (xy 434.456777 -372.669222) (xy 434.473096 -372.64086) (xy 434.476425 -372.634842)
			(xy 434.480022 -372.621573) (xy 434.480208 -372.614698) (xy 434.480208 -371.865398) (xy 434.480016 -371.858525)
			(xy 434.476408 -371.845262) (xy 434.473096 -371.839236) (xy 434.456743 -371.810892) (xy 434.431031 -371.750716)
			(xy 434.413628 -371.687634) (xy 434.404849 -371.622787) (xy 433.145727 -371.622787) (xy 433.148625 -371.629568)
			(xy 433.166032 -371.692648) (xy 433.174813 -371.757493) (xy 433.174812 -371.822931) (xy 433.166027 -371.887776)
			(xy 433.148617 -371.950855) (xy 433.122899 -372.011027) (xy 433.106576 -372.039388) (xy 433.103264 -372.045414)
			(xy 433.099657 -372.058677) (xy 433.099464 -372.06555) (xy 433.099464 -372.351554) (xy 433.098999 -372.361722)
			(xy 433.091229 -372.380516) (xy 433.076856 -372.394902) (xy 433.05807 -372.402689) (xy 433.047902 -372.403116)
			(xy 432.331622 -372.403116) (xy 432.321446 -372.402717) (xy 432.302643 -372.394931) (xy 432.288256 -372.380537)
			(xy 432.280478 -372.36173) (xy 432.28006 -372.351554) (xy 432.28006 -372.06555) (xy 432.279854 -372.058678)
			(xy 432.276256 -372.045415) (xy 432.272948 -372.039388) (xy 432.256637 -372.01102) (xy 432.230918 -371.950851)
			(xy 432.213508 -371.887773) (xy 432.204723 -371.82293) (xy 432.204722 -371.757494) (xy 432.213504 -371.69265)
			(xy 432.23091 -371.629572) (xy 432.256626 -371.569401) (xy 432.272948 -371.54104) (xy 432.276244 -371.535006)
			(xy 432.279862 -371.52175) (xy 432.28006 -371.514878) (xy 432.28006 -370.765324) (xy 432.279864 -370.758451)
			(xy 432.276259 -370.745188) (xy 432.272948 -370.739162) (xy 432.256615 -370.710806) (xy 432.230898 -370.650634)
			(xy 432.213491 -370.587554) (xy 432.204708 -370.522709) (xy 428.77501 -370.522709) (xy 428.766229 -370.587551)
			(xy 428.748823 -370.650629) (xy 428.723109 -370.7108) (xy 428.706788 -370.739162) (xy 428.703486 -370.745193)
			(xy 428.699873 -370.758452) (xy 428.699676 -370.765324) (xy 428.699676 -371.514878) (xy 428.699879 -371.52175)
			(xy 428.70348 -371.535013) (xy 428.706788 -371.54104) (xy 428.723121 -371.569395) (xy 428.748836 -371.629568)
			(xy 428.766242 -371.692648) (xy 428.775024 -371.757493) (xy 428.775022 -371.822931) (xy 428.766237 -371.887776)
			(xy 428.748828 -371.950855) (xy 428.72311 -372.011026) (xy 428.706788 -372.039388) (xy 428.703477 -372.045414)
			(xy 428.699869 -372.058677) (xy 428.699676 -372.06555) (xy 428.699676 -372.351554) (xy 428.699199 -372.361721)
			(xy 428.691432 -372.380512) (xy 428.677062 -372.394898) (xy 428.65828 -372.402687) (xy 428.648114 -372.403116)
			(xy 427.931834 -372.403116) (xy 427.921659 -372.402707) (xy 427.902856 -372.394925) (xy 427.888469 -372.380534)
			(xy 427.880691 -372.361729) (xy 427.880272 -372.351554) (xy 427.880272 -372.06555) (xy 427.880064 -372.058678)
			(xy 427.876467 -372.045415) (xy 427.87316 -372.039388) (xy 427.856849 -372.01102) (xy 427.831129 -371.950851)
			(xy 427.813719 -371.887774) (xy 427.804934 -371.82293) (xy 427.804932 -371.757494) (xy 427.813714 -371.69265)
			(xy 427.831121 -371.629572) (xy 427.856838 -371.569401) (xy 427.87316 -371.54104) (xy 427.876457 -371.535007)
			(xy 427.880074 -371.52175) (xy 427.880272 -371.514878) (xy 427.880272 -370.765324) (xy 427.880074 -370.758451)
			(xy 427.87647 -370.745188) (xy 427.87316 -370.739162) (xy 427.856827 -370.710807) (xy 427.831109 -370.650634)
			(xy 427.813701 -370.587554) (xy 427.804919 -370.522709) (xy 424.375034 -370.522709) (xy 424.375034 -370.522718)
			(xy 424.366173 -370.587577) (xy 424.348677 -370.650657) (xy 424.322863 -370.710815) (xy 424.306492 -370.739162)
			(xy 424.30319 -370.745193) (xy 424.299577 -370.758452) (xy 424.29938 -370.765324) (xy 424.29938 -371.514878)
			(xy 424.299583 -371.52175) (xy 424.303184 -371.535013) (xy 424.306492 -371.54104) (xy 424.322873 -371.569381)
			(xy 424.345774 -371.622787) (xy 425.604763 -371.622787) (xy 425.604767 -371.557348) (xy 425.613555 -371.492502)
			(xy 425.630967 -371.429422) (xy 425.656688 -371.36925) (xy 425.673012 -371.340888) (xy 425.676332 -371.334866)
			(xy 425.679934 -371.3216) (xy 425.680124 -371.314726) (xy 425.680124 -371.028722) (xy 425.680582 -371.018554)
			(xy 425.688357 -370.999762) (xy 425.702732 -370.985377) (xy 425.721518 -370.977589) (xy 425.731686 -370.97716)
			(xy 426.447966 -370.97716) (xy 426.458138 -370.977592) (xy 426.476936 -370.98537) (xy 426.491323 -370.999754)
			(xy 426.499105 -371.01855) (xy 426.499528 -371.028722) (xy 426.499528 -371.314726) (xy 426.499707 -371.3216)
			(xy 426.503324 -371.334863) (xy 426.50664 -371.340888) (xy 426.522931 -371.369267) (xy 426.548652 -371.429434)
			(xy 426.566065 -371.492509) (xy 426.574853 -371.55735) (xy 426.574857 -371.622785) (xy 426.566078 -371.687627)
			(xy 426.548674 -371.750705) (xy 426.52296 -371.810875) (xy 426.50664 -371.839236) (xy 426.503316 -371.845256)
			(xy 426.499716 -371.858523) (xy 426.499528 -371.865398) (xy 426.499528 -372.614698) (xy 426.499717 -372.621571)
			(xy 426.503327 -372.634834) (xy 426.50664 -372.64086) (xy 426.522992 -372.669205) (xy 426.548708 -372.72938)
			(xy 426.566113 -372.792462) (xy 426.574894 -372.857309) (xy 426.574892 -372.890034) (xy 430.00422 -372.890034)
			(xy 430.004776 -372.857304) (xy 430.013634 -372.792445) (xy 430.031127 -372.729365) (xy 430.056938 -372.669208)
			(xy 430.073308 -372.64086) (xy 430.076638 -372.634843) (xy 430.080234 -372.621573) (xy 430.08042 -372.614698)
			(xy 430.08042 -371.865398) (xy 430.080226 -371.858525) (xy 430.076619 -371.845262) (xy 430.073308 -371.839236)
			(xy 430.056958 -371.810878) (xy 430.031152 -371.750722) (xy 430.013658 -371.687645) (xy 430.004793 -371.62279)
			(xy 430.00422 -371.590062) (xy 430.004788 -371.557333) (xy 430.013643 -371.492474) (xy 430.031132 -371.429394)
			(xy 430.05694 -371.369236) (xy 430.073308 -371.340888) (xy 430.076628 -371.334866) (xy 430.08023 -371.3216)
			(xy 430.08042 -371.314726) (xy 430.08042 -371.028722) (xy 430.080944 -371.018599) (xy 430.088661 -370.999882)
			(xy 430.102935 -370.985526) (xy 430.121608 -370.977702) (xy 430.131728 -370.97716) (xy 430.848008 -370.97716)
			(xy 430.858158 -370.977614) (xy 430.876902 -370.985405) (xy 430.891224 -370.999791) (xy 430.898931 -371.018571)
			(xy 430.899316 -371.028722) (xy 430.899316 -371.314726) (xy 430.899496 -371.3216) (xy 430.903112 -371.334863)
			(xy 430.906428 -371.340888) (xy 430.922791 -371.369238) (xy 430.948593 -371.429398) (xy 430.966083 -371.492477)
			(xy 430.974945 -371.557333) (xy 430.975516 -371.590062) (xy 430.974954 -371.622792) (xy 430.966097 -371.68765)
			(xy 430.948605 -371.75073) (xy 430.922797 -371.810888) (xy 430.906428 -371.839236) (xy 430.903102 -371.845255)
			(xy 430.899503 -371.858523) (xy 430.899316 -371.865398) (xy 430.899316 -372.614698) (xy 430.899507 -372.621571)
			(xy 430.903116 -372.634834) (xy 430.906428 -372.64086) (xy 430.92278 -372.669216) (xy 430.948585 -372.729374)
			(xy 430.966078 -372.792451) (xy 430.974943 -372.857306) (xy 430.975516 -372.890034) (xy 430.974941 -372.922763)
			(xy 430.966087 -372.987621) (xy 430.9486 -373.050701) (xy 430.922795 -373.11086) (xy 430.906428 -373.139208)
			(xy 430.903112 -373.145232) (xy 430.899507 -373.158496) (xy 430.899316 -373.16537) (xy 430.899316 -373.451374)
			(xy 430.898851 -373.461504) (xy 430.891124 -373.480233) (xy 430.87683 -373.494592) (xy 430.858136 -373.502405)
			(xy 430.848008 -373.502936) (xy 430.131728 -373.502936) (xy 430.12158 -373.502456) (xy 430.102835 -373.494677)
			(xy 430.088512 -373.480298) (xy 430.080805 -373.461523) (xy 430.08042 -373.451374) (xy 430.08042 -373.16537)
			(xy 430.080237 -373.158496) (xy 430.076622 -373.145233) (xy 430.073308 -373.139208) (xy 430.056946 -373.110857)
			(xy 430.031143 -373.050698) (xy 430.013653 -372.987619) (xy 430.004791 -372.922763) (xy 430.00422 -372.890034)
			(xy 426.574892 -372.890034) (xy 426.57489 -372.922749) (xy 426.566102 -372.987595) (xy 426.548688 -373.050675)
			(xy 426.522965 -373.110847) (xy 426.50664 -373.139208) (xy 426.503326 -373.145233) (xy 426.499719 -373.158496)
			(xy 426.499528 -373.16537) (xy 426.499528 -373.451374) (xy 426.499114 -373.461548) (xy 426.491331 -373.480349)
			(xy 426.476942 -373.494736) (xy 426.45814 -373.502515) (xy 426.447966 -373.502936) (xy 425.731686 -373.502936)
			(xy 425.72151 -373.502547) (xy 425.70271 -373.494752) (xy 425.688325 -373.480356) (xy 425.680545 -373.46155)
			(xy 425.680124 -373.451374) (xy 425.680124 -373.16537) (xy 425.67994 -373.158496) (xy 425.676326 -373.145234)
			(xy 425.673012 -373.139208) (xy 425.656719 -373.110831) (xy 425.631001 -373.050663) (xy 425.61359 -372.987588)
			(xy 425.604804 -372.922746) (xy 425.6048 -372.857312) (xy 425.613579 -372.79247) (xy 425.630981 -372.729392)
			(xy 425.656693 -372.669221) (xy 425.673012 -372.64086) (xy 425.676342 -372.634843) (xy 425.679938 -372.621573)
			(xy 425.680124 -372.614698) (xy 425.680124 -371.865398) (xy 425.67993 -371.858525) (xy 425.676323 -371.845262)
			(xy 425.673012 -371.839236) (xy 425.656658 -371.810892) (xy 425.630945 -371.750717) (xy 425.613542 -371.687634)
			(xy 425.604763 -371.622787) (xy 424.345774 -371.622787) (xy 424.348671 -371.629543) (xy 424.366157 -371.692625)
			(xy 424.375012 -371.757484) (xy 424.37558 -371.790214) (xy 424.375001 -371.822943) (xy 424.366149 -371.887801)
			(xy 424.348663 -371.950881) (xy 424.322859 -372.01104) (xy 424.306492 -372.039388) (xy 424.303181 -372.045414)
			(xy 424.299573 -372.058677) (xy 424.29938 -372.06555) (xy 424.29938 -372.351554) (xy 424.298836 -372.361675)
			(xy 424.291127 -372.380392) (xy 424.276858 -372.394749) (xy 424.25819 -372.402573) (xy 424.248072 -372.403116)
			(xy 423.531792 -372.403116) (xy 423.521639 -372.402685) (xy 423.50289 -372.39489) (xy 423.488568 -372.380496)
			(xy 423.480865 -372.361709) (xy 423.480484 -372.351554) (xy 423.480484 -372.06555) (xy 423.480275 -372.058678)
			(xy 423.476678 -372.045415) (xy 423.473372 -372.039388) (xy 423.456999 -372.011043) (xy 423.4312 -371.950882)
			(xy 423.413712 -371.887801) (xy 423.404854 -371.822943) (xy 423.404284 -371.790214) (xy 422.131582 -371.790214)
			(xy 422.122713 -371.810888) (xy 422.106344 -371.839236) (xy 422.10302 -371.845256) (xy 422.09942 -371.858523)
			(xy 422.099232 -371.865398) (xy 422.099232 -372.614698) (xy 422.099421 -372.621572) (xy 422.103031 -372.634834)
			(xy 422.106344 -372.64086) (xy 422.122688 -372.669221) (xy 422.148497 -372.729376) (xy 422.165992 -372.792452)
			(xy 422.174859 -372.857306) (xy 422.175432 -372.890034) (xy 422.174855 -372.922763) (xy 422.166002 -372.987621)
			(xy 422.148515 -373.050701) (xy 422.122711 -373.11086) (xy 422.106344 -373.139208) (xy 422.10303 -373.145233)
			(xy 422.099423 -373.158496) (xy 422.099232 -373.16537) (xy 422.099232 -373.451374) (xy 422.098751 -373.461503)
			(xy 422.091027 -373.480228) (xy 422.076738 -373.494587) (xy 422.05805 -373.502402) (xy 422.047924 -373.502936)
			(xy 421.331644 -373.502936) (xy 421.321497 -373.502443) (xy 421.302753 -373.494669) (xy 421.288429 -373.480294)
			(xy 421.280721 -373.461522) (xy 421.280336 -373.451374) (xy 421.280336 -373.16537) (xy 421.280151 -373.158496)
			(xy 421.276537 -373.145234) (xy 421.273224 -373.139208) (xy 421.256864 -373.110856) (xy 421.23106 -373.050697)
			(xy 421.213569 -372.987619) (xy 421.204707 -372.922763) (xy 421.204136 -372.890034) (xy 408.160505 -372.890034)
			(xy 408.160219 -372.905728) (xy 408.152099 -372.960904) (xy 408.136031 -373.014311) (xy 408.112359 -373.064808)
			(xy 408.081586 -373.111321) (xy 408.044369 -373.152858) (xy 408.001501 -373.188533) (xy 407.953895 -373.217587)
			(xy 407.902566 -373.239399) (xy 407.848609 -373.253505) (xy 407.793172 -373.259605) (xy 407.737438 -373.257568)
			(xy 407.682595 -373.247438) (xy 407.629811 -373.229431) (xy 407.580211 -373.20393) (xy 407.534853 -373.171479)
			(xy 407.494704 -373.13277) (xy 407.460618 -373.088627) (xy 407.433322 -373.039992) (xy 407.413399 -372.987901)
			(xy 407.401273 -372.933464) (xy 407.397202 -372.877842) (xy 396.196566 -372.877842) (xy 396.196566 -374.16486)
			(xy 403.928832 -374.16486) (xy 403.932903 -374.109238) (xy 403.945029 -374.054801) (xy 403.964952 -374.00271)
			(xy 403.992248 -373.954075) (xy 404.026334 -373.909932) (xy 404.066483 -373.871223) (xy 404.111841 -373.838772)
			(xy 404.161441 -373.813271) (xy 404.214225 -373.795264) (xy 404.269068 -373.785134) (xy 404.324802 -373.783097)
			(xy 404.380239 -373.789197) (xy 404.434196 -373.803303) (xy 404.485525 -373.825115) (xy 404.533131 -373.854169)
			(xy 404.575999 -373.889844) (xy 404.613216 -373.931381) (xy 404.643989 -373.977894) (xy 404.667661 -374.028391)
			(xy 404.683729 -374.081798) (xy 404.691849 -374.136974) (xy 404.692358 -374.16486) (xy 404.691849 -374.192746)
			(xy 404.683729 -374.247922) (xy 404.667661 -374.301329) (xy 404.643989 -374.351826) (xy 404.613216 -374.398339)
			(xy 404.575999 -374.439876) (xy 404.533131 -374.475551) (xy 404.485525 -374.504605) (xy 404.434196 -374.526417)
			(xy 404.380239 -374.540523) (xy 404.324802 -374.546623) (xy 404.269068 -374.544586) (xy 404.214225 -374.534456)
			(xy 404.161441 -374.516449) (xy 404.111841 -374.490948) (xy 404.066483 -374.458497) (xy 404.026334 -374.419788)
			(xy 403.992248 -374.375645) (xy 403.964952 -374.32701) (xy 403.945029 -374.274919) (xy 403.932903 -374.220482)
			(xy 403.928832 -374.16486) (xy 396.196566 -374.16486) (xy 396.196566 -374.702653) (xy 405.266855 -374.702653)
			(xy 405.266855 -374.648147) (xy 405.274612 -374.594195) (xy 405.289969 -374.541897) (xy 405.312612 -374.492317)
			(xy 405.34208 -374.446463) (xy 405.377775 -374.40527) (xy 405.418968 -374.369577) (xy 405.464822 -374.340109)
			(xy 405.514403 -374.317467) (xy 405.566701 -374.302111) (xy 405.620653 -374.294355) (xy 405.647906 -374.293892)
			(xy 405.64816 -374.293892) (xy 405.676552 -374.294419) (xy 405.732706 -374.302865) (xy 405.78699 -374.319533)
			(xy 405.838208 -374.344055) (xy 405.885231 -374.375889) (xy 405.906478 -374.39473) (xy 405.913844 -374.401588)
			(xy 405.93264 -374.408446) (xy 406.014682 -374.405144) (xy 406.02457 -374.404284) (xy 406.042608 -374.396051)
			(xy 406.049734 -374.389142) (xy 406.049988 -374.388888) (xy 406.068094 -374.369853) (xy 406.108661 -374.336473)
			(xy 406.153427 -374.308978) (xy 406.201543 -374.287887) (xy 406.252098 -374.273602) (xy 406.304136 -374.266391)
			(xy 406.330404 -374.265952) (xy 406.357652 -374.266518) (xy 406.411594 -374.274275) (xy 406.463882 -374.289628)
			(xy 406.513454 -374.312267) (xy 406.559299 -374.341731) (xy 406.600484 -374.377418) (xy 406.636172 -374.418604)
			(xy 406.638922 -374.422884) (xy 419.004815 -374.422884) (xy 419.00482 -374.357444) (xy 419.01361 -374.292597)
			(xy 419.031025 -374.229517) (xy 419.05675 -374.169345) (xy 419.073076 -374.140984) (xy 419.076395 -374.134961)
			(xy 419.079998 -374.121696) (xy 419.080188 -374.114822) (xy 419.080188 -373.828818) (xy 419.08058 -373.818641)
			(xy 419.088368 -373.799837) (xy 419.102764 -373.78545) (xy 419.121573 -373.777673) (xy 419.13175 -373.777256)
			(xy 419.84803 -373.777256) (xy 419.858192 -373.777709) (xy 419.876965 -373.785497) (xy 419.89133 -373.799875)
			(xy 419.8991 -373.818656) (xy 419.899592 -373.828818) (xy 419.899592 -374.114822) (xy 419.899776 -374.121696)
			(xy 419.90339 -374.134959) (xy 419.906704 -374.140984) (xy 419.922989 -374.169365) (xy 419.948708 -374.229532)
			(xy 419.966118 -374.292607) (xy 419.974906 -374.357447) (xy 419.97491 -374.422881) (xy 419.966133 -374.487722)
			(xy 419.948732 -374.5508) (xy 419.923022 -374.61097) (xy 419.906704 -374.639332) (xy 419.903378 -374.645351)
			(xy 419.899779 -374.658619) (xy 419.899592 -374.665494) (xy 419.899592 -375.414794) (xy 419.899787 -375.421667)
			(xy 419.903393 -375.43493) (xy 419.906704 -375.440956) (xy 419.92305 -375.469304) (xy 419.948763 -375.529479)
			(xy 419.966167 -375.59256) (xy 419.974947 -375.657407) (xy 419.974943 -375.722845) (xy 419.966157 -375.787691)
			(xy 419.948746 -375.85077) (xy 419.923027 -375.910942) (xy 419.906704 -375.939304) (xy 419.903388 -375.945328)
			(xy 419.899783 -375.958592) (xy 419.899592 -375.965466) (xy 419.899592 -376.25147) (xy 419.899043 -376.261622)
			(xy 419.891284 -376.280385) (xy 419.876935 -376.29475) (xy 419.858182 -376.302531) (xy 419.84803 -376.303032)
			(xy 419.13175 -376.303032) (xy 419.121578 -376.302595) (xy 419.102779 -376.29482) (xy 419.088391 -376.280438)
			(xy 419.080609 -376.261642) (xy 419.080188 -376.25147) (xy 419.080188 -375.965466) (xy 419.080011 -375.958592)
			(xy 419.076393 -375.945329) (xy 419.073076 -375.939304) (xy 419.056778 -375.910929) (xy 419.031056 -375.850762)
			(xy 419.013644 -375.787686) (xy 419.004856 -375.722843) (xy 419.004853 -375.657408) (xy 419.013634 -375.592565)
			(xy 419.031039 -375.529487) (xy 419.056755 -375.469317) (xy 419.073076 -375.440956) (xy 419.076405 -375.434938)
			(xy 419.080002 -375.421669) (xy 419.080188 -375.414794) (xy 419.080188 -374.665494) (xy 419.08 -374.65862)
			(xy 419.076389 -374.645358) (xy 419.073076 -374.639332) (xy 419.056717 -374.610991) (xy 419.031001 -374.550815)
			(xy 419.013595 -374.487732) (xy 419.004815 -374.422884) (xy 406.638922 -374.422884) (xy 406.665634 -374.46445)
			(xy 406.688273 -374.514021) (xy 406.703626 -374.56631) (xy 406.711382 -374.620252) (xy 406.711382 -374.674748)
			(xy 406.703626 -374.72869) (xy 406.688273 -374.780979) (xy 406.665634 -374.83055) (xy 406.636172 -374.876396)
			(xy 406.600484 -374.917582) (xy 406.559299 -374.953269) (xy 406.513454 -374.982733) (xy 406.463882 -375.005372)
			(xy 406.411594 -375.020725) (xy 406.357652 -375.028482) (xy 406.330404 -375.028968) (xy 406.33015 -375.028968)
			(xy 406.301757 -375.028445) (xy 406.245603 -375.019999) (xy 406.191318 -375.003331) (xy 406.1401 -374.978809)
			(xy 406.093079 -374.946972) (xy 406.071832 -374.92813) (xy 406.064466 -374.921272) (xy 406.04567 -374.914414)
			(xy 405.963628 -374.917716) (xy 405.953738 -374.918564) (xy 405.935699 -374.926804) (xy 405.928576 -374.933718)
			(xy 405.928322 -374.933972) (xy 405.910204 -374.952995) (xy 405.86964 -374.986377) (xy 405.824877 -375.013875)
			(xy 405.776763 -375.034968) (xy 405.72621 -375.049256) (xy 405.674173 -375.056468) (xy 405.647906 -375.056908)
			(xy 405.620653 -375.056445) (xy 405.566701 -375.048689) (xy 405.514403 -375.033333) (xy 405.464822 -375.010691)
			(xy 405.418968 -374.981223) (xy 405.377775 -374.94553) (xy 405.34208 -374.904337) (xy 405.312612 -374.858483)
			(xy 405.289969 -374.808903) (xy 405.274612 -374.756605) (xy 405.266855 -374.702653) (xy 396.196566 -374.702653)
			(xy 396.196566 -376.790204) (xy 421.204136 -376.790204) (xy 421.20469 -376.757474) (xy 421.213551 -376.692616)
			(xy 421.231044 -376.629536) (xy 421.256854 -376.569378) (xy 421.273224 -376.54103) (xy 421.27653 -376.535001)
			(xy 421.280141 -376.521741) (xy 421.280336 -376.514868) (xy 421.280336 -375.765568) (xy 421.280152 -375.758694)
			(xy 421.276538 -375.745432) (xy 421.273224 -375.739406) (xy 421.256863 -375.711054) (xy 421.23106 -375.650896)
			(xy 421.213569 -375.587817) (xy 421.204707 -375.522961) (xy 421.204136 -375.490232) (xy 421.204702 -375.457503)
			(xy 421.213559 -375.392645) (xy 421.23105 -375.329565) (xy 421.256856 -375.269406) (xy 421.273224 -375.241058)
			(xy 421.276555 -375.235042) (xy 421.28015 -375.221771) (xy 421.280336 -375.214896) (xy 421.280336 -374.928638)
			(xy 421.280858 -374.918514) (xy 421.288572 -374.899795) (xy 421.302848 -374.885437) (xy 421.321523 -374.877616)
			(xy 421.331644 -374.877076) (xy 422.047924 -374.877076) (xy 422.058077 -374.877501) (xy 422.076825 -374.8853)
			(xy 422.091147 -374.899695) (xy 422.09885 -374.918483) (xy 422.099232 -374.928638) (xy 422.099232 -375.214896)
			(xy 422.099422 -375.221769) (xy 422.103031 -375.235032) (xy 422.106344 -375.241058) (xy 422.122688 -375.269419)
			(xy 422.148496 -375.329574) (xy 422.165992 -375.39265) (xy 422.174859 -375.457504) (xy 422.175432 -375.490232)
			(xy 422.174854 -375.522961) (xy 422.166001 -375.587819) (xy 422.148515 -375.650899) (xy 422.131688 -375.69013)
			(xy 423.404284 -375.69013) (xy 423.404843 -375.6574) (xy 423.413701 -375.592542) (xy 423.431193 -375.529462)
			(xy 423.457002 -375.469304) (xy 423.473372 -375.440956) (xy 423.4767 -375.434938) (xy 423.480298 -375.421669)
			(xy 423.480484 -375.414794) (xy 423.480484 -374.665494) (xy 423.480296 -374.65862) (xy 423.476685 -374.645358)
			(xy 423.473372 -374.639332) (xy 423.457016 -374.610977) (xy 423.431213 -374.55082) (xy 423.413721 -374.487742)
			(xy 423.404857 -374.422886) (xy 423.404284 -374.390158) (xy 423.404856 -374.357429) (xy 423.41371 -374.292571)
			(xy 423.431199 -374.229491) (xy 423.457004 -374.169332) (xy 423.473372 -374.140984) (xy 423.47669 -374.134961)
			(xy 423.480294 -374.121696) (xy 423.480484 -374.114822) (xy 423.480484 -373.828818) (xy 423.480942 -373.818687)
			(xy 423.488672 -373.799958) (xy 423.502968 -373.785599) (xy 423.521663 -373.777787) (xy 423.531792 -373.777256)
			(xy 424.248072 -373.777256) (xy 424.258219 -373.777743) (xy 424.276962 -373.785522) (xy 424.291285 -373.799898)
			(xy 424.298994 -373.81867) (xy 424.29938 -373.828818) (xy 424.29938 -374.114822) (xy 424.299566 -374.121696)
			(xy 424.303179 -374.134958) (xy 424.306492 -374.140984) (xy 424.32285 -374.169337) (xy 424.348654 -374.229495)
			(xy 424.366146 -374.292573) (xy 424.375008 -374.357429) (xy 424.37558 -374.390158) (xy 424.37502 -374.422884)
			(xy 427.804902 -374.422884) (xy 427.804907 -374.357444) (xy 427.813696 -374.292597) (xy 427.83111 -374.229517)
			(xy 427.856834 -374.169345) (xy 427.87316 -374.140984) (xy 427.876477 -374.13496) (xy 427.880082 -374.121696)
			(xy 427.880272 -374.114822) (xy 427.880272 -373.828818) (xy 427.880679 -373.818643) (xy 427.888465 -373.799842)
			(xy 427.902856 -373.785456) (xy 427.921659 -373.777676) (xy 427.931834 -373.777256) (xy 428.648114 -373.777256)
			(xy 428.658289 -373.777653) (xy 428.677087 -373.785446) (xy 428.691472 -373.79984) (xy 428.699253 -373.818643)
			(xy 428.699676 -373.828818) (xy 428.699676 -374.114822) (xy 428.699863 -374.121696) (xy 428.703475 -374.134958)
			(xy 428.706788 -374.140984) (xy 428.723074 -374.169365) (xy 428.748793 -374.229532) (xy 428.766204 -374.292607)
			(xy 428.774992 -374.357447) (xy 428.774997 -374.422881) (xy 428.774997 -374.422884) (xy 432.204691 -374.422884)
			(xy 432.204696 -374.357444) (xy 432.213485 -374.292597) (xy 432.230899 -374.229517) (xy 432.256623 -374.169345)
			(xy 432.272948 -374.140984) (xy 432.276264 -374.13496) (xy 432.27987 -374.121696) (xy 432.28006 -374.114822)
			(xy 432.28006 -373.828818) (xy 432.280479 -373.818645) (xy 432.288262 -373.799846) (xy 432.30265 -373.78546)
			(xy 432.321449 -373.777678) (xy 432.331622 -373.777256) (xy 433.047902 -373.777256) (xy 433.058076 -373.777663)
			(xy 433.076874 -373.785452) (xy 433.09126 -373.799843) (xy 433.099041 -373.818644) (xy 433.099464 -373.828818)
			(xy 433.099464 -374.114822) (xy 433.099652 -374.121695) (xy 433.103264 -374.134958) (xy 433.106576 -374.140984)
			(xy 433.122862 -374.169365) (xy 433.148582 -374.229532) (xy 433.165994 -374.292606) (xy 433.174781 -374.357447)
			(xy 433.174783 -374.390158) (xy 436.603656 -374.390158) (xy 436.607647 -374.327991) (xy 436.619556 -374.266844)
			(xy 436.639185 -374.207723) (xy 436.666214 -374.151597) (xy 436.700198 -374.099388) (xy 436.74058 -374.051953)
			(xy 436.786696 -374.010072) (xy 436.837788 -373.974432) (xy 436.893019 -373.945618) (xy 436.951481 -373.924104)
			(xy 437.012215 -373.910242) (xy 437.074222 -373.90426) (xy 437.136485 -373.906256) (xy 437.197982 -373.916199)
			(xy 437.257703 -373.933923) (xy 437.314666 -373.95914) (xy 437.367937 -373.991433) (xy 437.416642 -374.030273)
			(xy 437.459979 -374.075023) (xy 437.497239 -374.124947) (xy 437.527808 -374.179226) (xy 437.551186 -374.236969)
			(xy 437.566987 -374.297227) (xy 437.574953 -374.35901) (xy 437.575452 -374.390158) (xy 437.574953 -374.421306)
			(xy 437.566987 -374.483089) (xy 437.551186 -374.543347) (xy 437.527808 -374.60109) (xy 437.497239 -374.655369)
			(xy 437.459979 -374.705293) (xy 437.416642 -374.750043) (xy 437.367937 -374.788883) (xy 437.314666 -374.821176)
			(xy 437.257703 -374.846393) (xy 437.197982 -374.864117) (xy 437.136485 -374.87406) (xy 437.074222 -374.876056)
			(xy 437.012215 -374.870074) (xy 436.951481 -374.856212) (xy 436.893019 -374.834698) (xy 436.837788 -374.805884)
			(xy 436.786696 -374.770244) (xy 436.74058 -374.728363) (xy 436.700198 -374.680928) (xy 436.666214 -374.628719)
			(xy 436.639185 -374.572593) (xy 436.619556 -374.513472) (xy 436.607647 -374.452325) (xy 436.603656 -374.390158)
			(xy 433.174783 -374.390158) (xy 433.174786 -374.422881) (xy 433.166008 -374.487723) (xy 433.148606 -374.5508)
			(xy 433.122895 -374.610971) (xy 433.106576 -374.639332) (xy 433.103248 -374.64535) (xy 433.099651 -374.658619)
			(xy 433.099464 -374.665494) (xy 433.099464 -375.414794) (xy 433.099663 -375.421667) (xy 433.103267 -375.434929)
			(xy 433.106576 -375.440956) (xy 433.122923 -375.469303) (xy 433.148638 -375.529478) (xy 433.166042 -375.59256)
			(xy 433.174822 -375.657406) (xy 433.174819 -375.722845) (xy 433.166032 -375.787691) (xy 433.148621 -375.850771)
			(xy 433.1229 -375.910943) (xy 433.106576 -375.939304) (xy 433.103258 -375.945327) (xy 433.099655 -375.958592)
			(xy 433.099464 -375.965466) (xy 433.099464 -376.25147) (xy 433.099011 -376.261639) (xy 433.091237 -376.280433)
			(xy 433.07686 -376.294819) (xy 433.058071 -376.302605) (xy 433.047902 -376.303032) (xy 432.331622 -376.303032)
			(xy 432.321448 -376.302617) (xy 432.302648 -376.294834) (xy 432.288262 -376.280445) (xy 432.280481 -376.261644)
			(xy 432.28006 -376.25147) (xy 432.28006 -375.965466) (xy 432.279886 -375.958591) (xy 432.276266 -375.945328)
			(xy 432.272948 -375.939304) (xy 432.256651 -375.910929) (xy 432.23093 -375.850761) (xy 432.213519 -375.787685)
			(xy 432.204732 -375.722843) (xy 432.204729 -375.657408) (xy 432.213509 -375.592565) (xy 432.230913 -375.529488)
			(xy 432.256627 -375.469317) (xy 432.272948 -375.440956) (xy 432.276274 -375.434937) (xy 432.279873 -375.421669)
			(xy 432.28006 -375.414794) (xy 432.28006 -374.665494) (xy 432.279875 -374.65862) (xy 432.276263 -374.645357)
			(xy 432.272948 -374.639332) (xy 432.25659 -374.61099) (xy 432.230875 -374.550815) (xy 432.213471 -374.487732)
			(xy 432.204691 -374.422884) (xy 428.774997 -374.422884) (xy 428.766219 -374.487723) (xy 428.748817 -374.5508)
			(xy 428.723107 -374.610971) (xy 428.706788 -374.639332) (xy 428.703461 -374.645351) (xy 428.699863 -374.658619)
			(xy 428.699676 -374.665494) (xy 428.699676 -375.414794) (xy 428.699873 -375.421667) (xy 428.703478 -375.434929)
			(xy 428.706788 -375.440956) (xy 428.723135 -375.469304) (xy 428.748849 -375.529478) (xy 428.766253 -375.59256)
			(xy 428.775033 -375.657407) (xy 428.775029 -375.722845) (xy 428.766243 -375.787691) (xy 428.748832 -375.85077)
			(xy 428.723111 -375.910942) (xy 428.706788 -375.939304) (xy 428.703471 -375.945327) (xy 428.699867 -375.958592)
			(xy 428.699676 -375.965466) (xy 428.699676 -376.25147) (xy 428.699212 -376.261638) (xy 428.691439 -376.280429)
			(xy 428.677066 -376.294815) (xy 428.658282 -376.302603) (xy 428.648114 -376.303032) (xy 427.931834 -376.303032)
			(xy 427.921661 -376.302607) (xy 427.902861 -376.294828) (xy 427.888474 -376.280442) (xy 427.880693 -376.261643)
			(xy 427.880272 -376.25147) (xy 427.880272 -375.965466) (xy 427.880097 -375.958591) (xy 427.876478 -375.945328)
			(xy 427.87316 -375.939304) (xy 427.856863 -375.910929) (xy 427.831141 -375.850761) (xy 427.81373 -375.787685)
			(xy 427.804943 -375.722843) (xy 427.804939 -375.657408) (xy 427.813719 -375.592565) (xy 427.831124 -375.529487)
			(xy 427.856839 -375.469317) (xy 427.87316 -375.440956) (xy 427.876487 -375.434937) (xy 427.880085 -375.421669)
			(xy 427.880272 -375.414794) (xy 427.880272 -374.665494) (xy 427.880086 -374.65862) (xy 427.876474 -374.645357)
			(xy 427.87316 -374.639332) (xy 427.856802 -374.610991) (xy 427.831086 -374.550815) (xy 427.813681 -374.487732)
			(xy 427.804902 -374.422884) (xy 424.37502 -374.422884) (xy 424.37502 -374.422888) (xy 424.366163 -374.487746)
			(xy 424.348671 -374.550827) (xy 424.322862 -374.610984) (xy 424.306492 -374.639332) (xy 424.303165 -374.645351)
			(xy 424.299567 -374.658619) (xy 424.29938 -374.665494) (xy 424.29938 -375.414794) (xy 424.299577 -375.421667)
			(xy 424.303182 -375.43493) (xy 424.306492 -375.440956) (xy 424.322839 -375.469315) (xy 424.348646 -375.529471)
			(xy 424.366141 -375.592547) (xy 424.375007 -375.657402) (xy 424.37558 -375.69013) (xy 424.375008 -375.722859)
			(xy 424.366154 -375.787717) (xy 424.348666 -375.850798) (xy 424.32286 -375.910956) (xy 424.306492 -375.939304)
			(xy 424.303175 -375.945328) (xy 424.299571 -375.958592) (xy 424.29938 -375.965466) (xy 424.29938 -376.25147)
			(xy 424.29885 -376.261592) (xy 424.291135 -376.280309) (xy 424.276863 -376.294666) (xy 424.258191 -376.30249)
			(xy 424.248072 -376.303032) (xy 423.531792 -376.303032) (xy 423.521641 -376.302585) (xy 423.502895 -376.294793)
			(xy 423.488573 -376.280405) (xy 423.480868 -376.261622) (xy 423.480484 -376.25147) (xy 423.480484 -375.965466)
			(xy 423.480307 -375.958592) (xy 423.476689 -375.945329) (xy 423.473372 -375.939304) (xy 423.457005 -375.910955)
			(xy 423.431204 -375.850795) (xy 423.413715 -375.787716) (xy 423.404855 -375.722859) (xy 423.404284 -375.69013)
			(xy 422.131688 -375.69013) (xy 422.122711 -375.711058) (xy 422.106344 -375.739406) (xy 422.103031 -375.745431)
			(xy 422.099424 -375.758694) (xy 422.099232 -375.765568) (xy 422.099232 -376.514868) (xy 422.099432 -376.521741)
			(xy 422.103034 -376.535004) (xy 422.106344 -376.54103) (xy 422.122716 -376.569376) (xy 422.148518 -376.629536)
			(xy 422.166006 -376.692617) (xy 422.174863 -376.757475) (xy 422.174863 -376.757485) (xy 425.604786 -376.757485)
			(xy 425.613569 -376.692641) (xy 425.630975 -376.629563) (xy 425.656691 -376.569392) (xy 425.673012 -376.54103)
			(xy 425.676317 -376.535001) (xy 425.679929 -376.521741) (xy 425.680124 -376.514868) (xy 425.680124 -375.765568)
			(xy 425.679941 -375.758694) (xy 425.676326 -375.745431) (xy 425.673012 -375.739406) (xy 425.656718 -375.71103)
			(xy 425.630999 -375.650862) (xy 425.613589 -375.587786) (xy 425.604802 -375.522945) (xy 425.604799 -375.45751)
			(xy 425.613578 -375.392668) (xy 425.630981 -375.32959) (xy 425.656693 -375.26942) (xy 425.673012 -375.241058)
			(xy 425.676343 -375.235041) (xy 425.679938 -375.221771) (xy 425.680124 -375.214896) (xy 425.680124 -374.928638)
			(xy 425.680595 -374.918471) (xy 425.688365 -374.899679) (xy 425.702736 -374.885294) (xy 425.721519 -374.877505)
			(xy 425.731686 -374.877076) (xy 426.447966 -374.877076) (xy 426.45814 -374.877493) (xy 426.476941 -374.885274)
			(xy 426.491329 -374.899662) (xy 426.499108 -374.918464) (xy 426.499528 -374.928638) (xy 426.499528 -375.214896)
			(xy 426.499718 -375.221769) (xy 426.503327 -375.235032) (xy 426.50664 -375.241058) (xy 426.52299 -375.269404)
			(xy 426.548706 -375.329579) (xy 426.566112 -375.39266) (xy 426.574893 -375.457508) (xy 426.574889 -375.522947)
			(xy 426.566101 -375.587793) (xy 426.548688 -375.650873) (xy 426.522965 -375.711045) (xy 426.50664 -375.739406)
			(xy 426.503326 -375.745431) (xy 426.49972 -375.758694) (xy 426.499528 -375.765568) (xy 426.499528 -376.514868)
			(xy 426.499729 -376.521741) (xy 426.503331 -376.535004) (xy 426.50664 -376.54103) (xy 426.522966 -376.569389)
			(xy 426.548685 -376.629561) (xy 426.566093 -376.69264) (xy 426.574877 -376.757485) (xy 426.574876 -376.790204)
			(xy 430.00422 -376.790204) (xy 430.004763 -376.757474) (xy 430.013625 -376.692614) (xy 430.031122 -376.629534)
			(xy 430.056936 -376.569377) (xy 430.073308 -376.54103) (xy 430.076613 -376.535) (xy 430.080225 -376.52174)
			(xy 430.08042 -376.514868) (xy 430.08042 -375.765568) (xy 430.080238 -375.758694) (xy 430.076623 -375.745431)
			(xy 430.073308 -375.739406) (xy 430.056946 -375.711055) (xy 430.031143 -375.650896) (xy 430.013652 -375.587817)
			(xy 430.004791 -375.522961) (xy 430.00422 -375.490232) (xy 430.004775 -375.457502) (xy 430.013634 -375.392643)
			(xy 430.031127 -375.329563) (xy 430.056938 -375.269406) (xy 430.073308 -375.241058) (xy 430.076638 -375.235041)
			(xy 430.080234 -375.221771) (xy 430.08042 -375.214896) (xy 430.08042 -374.928638) (xy 430.080957 -374.918516)
			(xy 430.088669 -374.8998) (xy 430.10294 -374.885443) (xy 430.121609 -374.877619) (xy 430.131728 -374.877076)
			(xy 430.848008 -374.877076) (xy 430.85816 -374.877515) (xy 430.876907 -374.885308) (xy 430.89123 -374.899699)
			(xy 430.898933 -374.918484) (xy 430.899316 -374.928638) (xy 430.899316 -375.214896) (xy 430.899508 -375.221769)
			(xy 430.903116 -375.235032) (xy 430.906428 -375.241058) (xy 430.92278 -375.269415) (xy 430.948584 -375.329572)
			(xy 430.966078 -375.392649) (xy 430.974943 -375.457504) (xy 430.975516 -375.490232) (xy 430.97494 -375.522961)
			(xy 430.966087 -375.587819) (xy 430.948599 -375.650899) (xy 430.922795 -375.711057) (xy 430.906428 -375.739406)
			(xy 430.903113 -375.745431) (xy 430.899507 -375.758694) (xy 430.899316 -375.765568) (xy 430.899316 -376.514868)
			(xy 430.899518 -376.52174) (xy 430.903119 -376.535003) (xy 430.906428 -376.54103) (xy 430.922808 -376.569371)
			(xy 430.948606 -376.629534) (xy 430.966091 -376.692616) (xy 430.974948 -376.757474) (xy 430.974948 -376.757485)
			(xy 434.404872 -376.757485) (xy 434.413655 -376.692642) (xy 434.431061 -376.629563) (xy 434.456775 -376.569392)
			(xy 434.473096 -376.54103) (xy 434.4764 -376.535) (xy 434.480012 -376.52174) (xy 434.480208 -376.514868)
			(xy 434.480208 -375.765568) (xy 434.480027 -375.758694) (xy 434.476411 -375.745431) (xy 434.473096 -375.739406)
			(xy 434.456802 -375.711029) (xy 434.431084 -375.650861) (xy 434.413675 -375.587786) (xy 434.404889 -375.522944)
			(xy 434.404885 -375.45751) (xy 434.413664 -375.392668) (xy 434.431066 -375.329591) (xy 434.456777 -375.26942)
			(xy 434.473096 -375.241058) (xy 434.476425 -375.235041) (xy 434.480022 -375.221771) (xy 434.480208 -375.214896)
			(xy 434.480208 -374.928638) (xy 434.480694 -374.918473) (xy 434.488461 -374.899684) (xy 434.502827 -374.885299)
			(xy 434.521605 -374.877508) (xy 434.53177 -374.877076) (xy 435.24805 -374.877076) (xy 435.258223 -374.877506)
			(xy 435.277024 -374.885281) (xy 435.291412 -374.899666) (xy 435.299192 -374.918465) (xy 435.299612 -374.928638)
			(xy 435.299612 -375.214896) (xy 435.299804 -375.221769) (xy 435.303412 -375.235032) (xy 435.306724 -375.241058)
			(xy 435.323074 -375.269404) (xy 435.348792 -375.329578) (xy 435.366198 -375.39266) (xy 435.374979 -375.457508)
			(xy 435.374975 -375.522947) (xy 435.366187 -375.587794) (xy 435.348773 -375.650874) (xy 435.331991 -375.69013)
			(xy 436.603656 -375.69013) (xy 436.607647 -375.627963) (xy 436.619556 -375.566816) (xy 436.639185 -375.507695)
			(xy 436.666214 -375.451569) (xy 436.700198 -375.39936) (xy 436.74058 -375.351925) (xy 436.786696 -375.310044)
			(xy 436.837788 -375.274404) (xy 436.893019 -375.24559) (xy 436.951481 -375.224076) (xy 437.012215 -375.210214)
			(xy 437.074222 -375.204232) (xy 437.136485 -375.206228) (xy 437.197982 -375.216171) (xy 437.257703 -375.233895)
			(xy 437.314666 -375.259112) (xy 437.367937 -375.291405) (xy 437.416642 -375.330245) (xy 437.459979 -375.374995)
			(xy 437.497239 -375.424919) (xy 437.527808 -375.479198) (xy 437.532275 -375.490232) (xy 438.803804 -375.490232)
			(xy 438.807795 -375.428065) (xy 438.819704 -375.366918) (xy 438.839333 -375.307797) (xy 438.866362 -375.251671)
			(xy 438.900346 -375.199462) (xy 438.940728 -375.152027) (xy 438.986844 -375.110146) (xy 439.037936 -375.074506)
			(xy 439.093167 -375.045692) (xy 439.151629 -375.024178) (xy 439.212363 -375.010316) (xy 439.27437 -375.004334)
			(xy 439.336633 -375.00633) (xy 439.39813 -375.016273) (xy 439.457851 -375.033997) (xy 439.514814 -375.059214)
			(xy 439.565899 -375.090182) (xy 459.19085 -375.090182) (xy 459.194921 -375.03456) (xy 459.207047 -374.980123)
			(xy 459.22697 -374.928032) (xy 459.254266 -374.879397) (xy 459.288352 -374.835254) (xy 459.328501 -374.796545)
			(xy 459.373859 -374.764094) (xy 459.423459 -374.738593) (xy 459.476243 -374.720586) (xy 459.531086 -374.710456)
			(xy 459.58682 -374.708419) (xy 459.642257 -374.714519) (xy 459.696214 -374.728625) (xy 459.747543 -374.750437)
			(xy 459.795149 -374.779491) (xy 459.838017 -374.815166) (xy 459.875234 -374.856703) (xy 459.906007 -374.903216)
			(xy 459.929679 -374.953713) (xy 459.945747 -375.00712) (xy 459.953867 -375.062296) (xy 459.954376 -375.090182)
			(xy 459.953867 -375.118068) (xy 459.945747 -375.173244) (xy 459.929679 -375.226651) (xy 459.906007 -375.277148)
			(xy 459.875234 -375.323661) (xy 459.838017 -375.365198) (xy 459.795149 -375.400873) (xy 459.747543 -375.429927)
			(xy 459.696214 -375.451739) (xy 459.642257 -375.465845) (xy 459.58682 -375.471945) (xy 459.531086 -375.469908)
			(xy 459.476243 -375.459778) (xy 459.423459 -375.441771) (xy 459.373859 -375.41627) (xy 459.328501 -375.383819)
			(xy 459.288352 -375.34511) (xy 459.254266 -375.300967) (xy 459.22697 -375.252332) (xy 459.207047 -375.200241)
			(xy 459.194921 -375.145804) (xy 459.19085 -375.090182) (xy 439.565899 -375.090182) (xy 439.568085 -375.091507)
			(xy 439.61679 -375.130347) (xy 439.660127 -375.175097) (xy 439.697387 -375.225021) (xy 439.727956 -375.2793)
			(xy 439.751334 -375.337043) (xy 439.767135 -375.397301) (xy 439.775101 -375.459084) (xy 439.7756 -375.490232)
			(xy 439.775101 -375.52138) (xy 439.767135 -375.583163) (xy 439.751334 -375.643421) (xy 439.727956 -375.701164)
			(xy 439.697387 -375.755443) (xy 439.660127 -375.805367) (xy 439.61679 -375.850117) (xy 439.568085 -375.888957)
			(xy 439.514814 -375.92125) (xy 439.457851 -375.946467) (xy 439.39813 -375.964191) (xy 439.336633 -375.974134)
			(xy 439.27437 -375.97613) (xy 439.212363 -375.970148) (xy 439.151629 -375.956286) (xy 439.093167 -375.934772)
			(xy 439.037936 -375.905958) (xy 438.986844 -375.870318) (xy 438.940728 -375.828437) (xy 438.900346 -375.781002)
			(xy 438.866362 -375.728793) (xy 438.839333 -375.672667) (xy 438.819704 -375.613546) (xy 438.807795 -375.552399)
			(xy 438.803804 -375.490232) (xy 437.532275 -375.490232) (xy 437.551186 -375.536941) (xy 437.566987 -375.597199)
			(xy 437.574953 -375.658982) (xy 437.575452 -375.69013) (xy 437.574953 -375.721278) (xy 437.566987 -375.783061)
			(xy 437.551186 -375.843319) (xy 437.527808 -375.901062) (xy 437.497239 -375.955341) (xy 437.459979 -376.005265)
			(xy 437.416642 -376.050015) (xy 437.367937 -376.088855) (xy 437.314666 -376.121148) (xy 437.257703 -376.146365)
			(xy 437.197982 -376.164089) (xy 437.136485 -376.174032) (xy 437.074222 -376.176028) (xy 437.012215 -376.170046)
			(xy 436.951481 -376.156184) (xy 436.893019 -376.13467) (xy 436.837788 -376.105856) (xy 436.786696 -376.070216)
			(xy 436.74058 -376.028335) (xy 436.700198 -375.9809) (xy 436.666214 -375.928691) (xy 436.639185 -375.872565)
			(xy 436.619556 -375.813444) (xy 436.607647 -375.752297) (xy 436.603656 -375.69013) (xy 435.331991 -375.69013)
			(xy 435.32305 -375.711045) (xy 435.306724 -375.739406) (xy 435.303409 -375.74543) (xy 435.299803 -375.758694)
			(xy 435.299612 -375.765568) (xy 435.299612 -376.514868) (xy 435.299815 -376.52174) (xy 435.303416 -376.535003)
			(xy 435.306724 -376.54103) (xy 435.323051 -376.569389) (xy 435.34877 -376.62956) (xy 435.366179 -376.692639)
			(xy 435.374963 -376.757485) (xy 435.374962 -376.790204) (xy 438.803804 -376.790204) (xy 438.807795 -376.728037)
			(xy 438.819704 -376.66689) (xy 438.839333 -376.607769) (xy 438.866362 -376.551643) (xy 438.900346 -376.499434)
			(xy 438.940728 -376.451999) (xy 438.986844 -376.410118) (xy 439.037936 -376.374478) (xy 439.093167 -376.345664)
			(xy 439.151629 -376.32415) (xy 439.212363 -376.310288) (xy 439.27437 -376.304306) (xy 439.336633 -376.306302)
			(xy 439.39813 -376.316245) (xy 439.457851 -376.333969) (xy 439.514814 -376.359186) (xy 439.568085 -376.391479)
			(xy 439.61679 -376.430319) (xy 439.660127 -376.475069) (xy 439.697387 -376.524993) (xy 439.727956 -376.579272)
			(xy 439.751334 -376.637015) (xy 439.767135 -376.697273) (xy 439.775101 -376.759056) (xy 439.7756 -376.790204)
			(xy 439.775101 -376.821352) (xy 439.767135 -376.883135) (xy 439.751334 -376.943393) (xy 439.727956 -377.001136)
			(xy 439.697387 -377.055415) (xy 439.660127 -377.105339) (xy 439.61679 -377.150089) (xy 439.568085 -377.188929)
			(xy 439.514814 -377.221222) (xy 439.457851 -377.246439) (xy 439.39813 -377.264163) (xy 439.336633 -377.274106)
			(xy 439.27437 -377.276102) (xy 439.212363 -377.27012) (xy 439.151629 -377.256258) (xy 439.093167 -377.234744)
			(xy 439.037936 -377.20593) (xy 438.986844 -377.17029) (xy 438.940728 -377.128409) (xy 438.900346 -377.080974)
			(xy 438.866362 -377.028765) (xy 438.839333 -376.972639) (xy 438.819704 -376.913518) (xy 438.807795 -376.852371)
			(xy 438.803804 -376.790204) (xy 435.374962 -376.790204) (xy 435.374962 -376.822922) (xy 435.366178 -376.887767)
			(xy 435.348768 -376.950846) (xy 435.323048 -377.011017) (xy 435.306724 -377.039378) (xy 435.303419 -377.045407)
			(xy 435.299807 -377.058667) (xy 435.299612 -377.06554) (xy 435.299612 -377.35129) (xy 435.299227 -377.361467)
			(xy 435.291436 -377.380271) (xy 435.277038 -377.394658) (xy 435.258228 -377.402435) (xy 435.24805 -377.402852)
			(xy 434.53177 -377.402852) (xy 434.521609 -377.402391) (xy 434.502837 -377.394605) (xy 434.488473 -377.380229)
			(xy 434.480701 -377.361451) (xy 434.480208 -377.35129) (xy 434.480208 -377.06554) (xy 434.48 -377.058668)
			(xy 434.476402 -377.045405) (xy 434.473096 -377.039378) (xy 434.456778 -377.011014) (xy 434.431063 -376.950843)
			(xy 434.413656 -376.887765) (xy 434.404873 -376.822921) (xy 434.404872 -376.757485) (xy 430.974948 -376.757485)
			(xy 430.975516 -376.790204) (xy 430.974972 -376.822934) (xy 430.96611 -376.887793) (xy 430.948613 -376.950873)
			(xy 430.9228 -377.011031) (xy 430.906428 -377.039378) (xy 430.903123 -377.045407) (xy 430.899511 -377.058667)
			(xy 430.899316 -377.06554) (xy 430.899316 -377.35129) (xy 430.898864 -377.361421) (xy 430.891131 -377.380151)
			(xy 430.876834 -377.394509) (xy 430.858137 -377.402321) (xy 430.848008 -377.402852) (xy 430.131728 -377.402852)
			(xy 430.121582 -377.402357) (xy 430.10284 -377.39458) (xy 430.088518 -377.380207) (xy 430.080808 -377.361437)
			(xy 430.08042 -377.35129) (xy 430.08042 -377.06554) (xy 430.08021 -377.058668) (xy 430.076614 -377.045405)
			(xy 430.073308 -377.039378) (xy 430.056934 -377.011033) (xy 430.031134 -376.950872) (xy 430.013647 -376.887791)
			(xy 430.004789 -376.822933) (xy 430.00422 -376.790204) (xy 426.574876 -376.790204) (xy 426.574876 -376.822922)
			(xy 426.566092 -376.887767) (xy 426.548682 -376.950846) (xy 426.522963 -377.011017) (xy 426.50664 -377.039378)
			(xy 426.503336 -377.045408) (xy 426.499723 -377.058668) (xy 426.499528 -377.06554) (xy 426.499528 -377.35129)
			(xy 426.499127 -377.361465) (xy 426.491339 -377.380266) (xy 426.476946 -377.394653) (xy 426.458141 -377.402432)
			(xy 426.447966 -377.402852) (xy 425.731686 -377.402852) (xy 425.721526 -377.402378) (xy 425.702755 -377.394597)
			(xy 425.68839 -377.380225) (xy 425.680618 -377.36145) (xy 425.680124 -377.35129) (xy 425.680124 -377.06554)
			(xy 425.679914 -377.058668) (xy 425.676318 -377.045405) (xy 425.673012 -377.039378) (xy 425.656694 -377.011015)
			(xy 425.630977 -376.950844) (xy 425.61357 -376.887765) (xy 425.604787 -376.822921) (xy 425.604786 -376.757485)
			(xy 422.174863 -376.757485) (xy 422.175432 -376.790204) (xy 422.174886 -376.822934) (xy 422.166024 -376.887793)
			(xy 422.148528 -376.950873) (xy 422.122715 -377.011031) (xy 422.106344 -377.039378) (xy 422.103041 -377.045408)
			(xy 422.099427 -377.058668) (xy 422.099232 -377.06554) (xy 422.099232 -377.35129) (xy 422.098764 -377.36142)
			(xy 422.091035 -377.380146) (xy 422.076742 -377.394503) (xy 422.058051 -377.402318) (xy 422.047924 -377.402852)
			(xy 421.331644 -377.402852) (xy 421.321499 -377.402343) (xy 421.302758 -377.394572) (xy 421.288435 -377.380202)
			(xy 421.280724 -377.361436) (xy 421.280336 -377.35129) (xy 421.280336 -377.06554) (xy 421.280124 -377.058668)
			(xy 421.276529 -377.045406) (xy 421.273224 -377.039378) (xy 421.256852 -377.011032) (xy 421.231051 -376.950872)
			(xy 421.213563 -376.887791) (xy 421.204705 -376.822933) (xy 421.204136 -376.790204) (xy 396.196566 -376.790204)
			(xy 396.196566 -378.076968) (xy 406.020014 -378.076968) (xy 406.024085 -378.021346) (xy 406.036211 -377.966909)
			(xy 406.056134 -377.914818) (xy 406.08343 -377.866183) (xy 406.117516 -377.82204) (xy 406.157665 -377.783331)
			(xy 406.203023 -377.75088) (xy 406.252623 -377.725379) (xy 406.305407 -377.707372) (xy 406.36025 -377.697242)
			(xy 406.415984 -377.695205) (xy 406.471421 -377.701305) (xy 406.525378 -377.715411) (xy 406.576707 -377.737223)
			(xy 406.624313 -377.766277) (xy 406.667181 -377.801952) (xy 406.704398 -377.843489) (xy 406.735171 -377.890002)
			(xy 406.758843 -377.940499) (xy 406.774911 -377.993906) (xy 406.783031 -378.049082) (xy 406.78354 -378.076968)
			(xy 406.783031 -378.104854) (xy 406.774911 -378.16003) (xy 406.758843 -378.213437) (xy 406.735171 -378.263934)
			(xy 406.704398 -378.310447) (xy 406.693332 -378.322797) (xy 419.004825 -378.322797) (xy 419.004828 -378.257358)
			(xy 419.013615 -378.192512) (xy 419.031028 -378.129432) (xy 419.056751 -378.069261) (xy 419.073076 -378.0409)
			(xy 419.076389 -378.034874) (xy 419.079996 -378.021611) (xy 419.080188 -378.014738) (xy 419.080188 -377.728734)
			(xy 419.080593 -377.718558) (xy 419.088376 -377.699755) (xy 419.102768 -377.685367) (xy 419.121574 -377.67759)
			(xy 419.13175 -377.677172) (xy 419.84803 -377.677172) (xy 419.858208 -377.67754) (xy 419.87701 -377.685341)
			(xy 419.891395 -377.699744) (xy 419.899173 -377.718556) (xy 419.899592 -377.728734) (xy 419.899592 -378.014738)
			(xy 419.899809 -378.021609) (xy 419.9034 -378.034872) (xy 419.906704 -378.0409) (xy 419.923003 -378.069274)
			(xy 419.94872 -378.129443) (xy 419.966129 -378.192519) (xy 419.974915 -378.257361) (xy 419.974918 -378.322795)
			(xy 419.966138 -378.387638) (xy 419.948735 -378.450715) (xy 419.923023 -378.510886) (xy 419.906704 -378.539248)
			(xy 419.903372 -378.545264) (xy 419.899777 -378.558535) (xy 419.899592 -378.56541) (xy 419.899592 -379.31471)
			(xy 419.899781 -379.321583) (xy 419.903391 -379.334846) (xy 419.906704 -379.340872) (xy 419.923064 -379.369212)
			(xy 419.948776 -379.429389) (xy 419.966178 -379.492472) (xy 419.974956 -379.55732) (xy 419.97495 -379.622759)
			(xy 419.966162 -379.687606) (xy 419.948749 -379.750686) (xy 419.923028 -379.810858) (xy 419.906704 -379.83922)
			(xy 419.903382 -379.845241) (xy 419.899781 -379.858508) (xy 419.899592 -379.865382) (xy 419.899592 -380.151386)
			(xy 419.899056 -380.161539) (xy 419.891292 -380.180302) (xy 419.876939 -380.194667) (xy 419.858183 -380.202447)
			(xy 419.84803 -380.202948) (xy 419.13175 -380.202948) (xy 419.12158 -380.202495) (xy 419.102784 -380.194724)
			(xy 419.088396 -380.180347) (xy 419.080612 -380.161556) (xy 419.080188 -380.151386) (xy 419.080188 -379.865382)
			(xy 419.080005 -379.858508) (xy 419.076391 -379.845245) (xy 419.073076 -379.83922) (xy 419.056792 -379.810838)
			(xy 419.031068 -379.750672) (xy 419.013655 -379.687597) (xy 419.004866 -379.622756) (xy 419.00486 -379.557322)
			(xy 419.013639 -379.49248) (xy 419.031042 -379.429403) (xy 419.056756 -379.369233) (xy 419.073076 -379.340872)
			(xy 419.076399 -379.334851) (xy 419.08 -379.321585) (xy 419.080188 -379.31471) (xy 419.080188 -378.56541)
			(xy 419.079994 -378.558537) (xy 419.076387 -378.545274) (xy 419.073076 -378.539248) (xy 419.056731 -378.510899)
			(xy 419.031013 -378.450726) (xy 419.013606 -378.387644) (xy 419.004825 -378.322797) (xy 406.693332 -378.322797)
			(xy 406.667181 -378.351984) (xy 406.624313 -378.387659) (xy 406.576707 -378.416713) (xy 406.525378 -378.438525)
			(xy 406.471421 -378.452631) (xy 406.415984 -378.458731) (xy 406.36025 -378.456694) (xy 406.305407 -378.446564)
			(xy 406.252623 -378.428557) (xy 406.203023 -378.403056) (xy 406.157665 -378.370605) (xy 406.117516 -378.331896)
			(xy 406.08343 -378.287753) (xy 406.056134 -378.239118) (xy 406.036211 -378.187027) (xy 406.024085 -378.13259)
			(xy 406.020014 -378.076968) (xy 396.196566 -378.076968) (xy 396.196566 -378.968) (xy 405.011634 -378.968)
			(xy 405.015705 -378.912378) (xy 405.027831 -378.857941) (xy 405.047754 -378.80585) (xy 405.07505 -378.757215)
			(xy 405.109136 -378.713072) (xy 405.149285 -378.674363) (xy 405.194643 -378.641912) (xy 405.244243 -378.616411)
			(xy 405.297027 -378.598404) (xy 405.35187 -378.588274) (xy 405.407604 -378.586237) (xy 405.463041 -378.592337)
			(xy 405.516998 -378.606443) (xy 405.568327 -378.628255) (xy 405.615933 -378.657309) (xy 405.658801 -378.692984)
			(xy 405.696018 -378.734521) (xy 405.726791 -378.781034) (xy 405.750463 -378.831531) (xy 405.766531 -378.884938)
			(xy 405.774651 -378.940114) (xy 405.77516 -378.968) (xy 405.774651 -378.995886) (xy 405.766531 -379.051062)
			(xy 405.750463 -379.104469) (xy 405.726791 -379.154966) (xy 405.696018 -379.201479) (xy 405.658801 -379.243016)
			(xy 405.615933 -379.278691) (xy 405.568327 -379.307745) (xy 405.516998 -379.329557) (xy 405.463041 -379.343663)
			(xy 405.407604 -379.349763) (xy 405.35187 -379.347726) (xy 405.297027 -379.337596) (xy 405.244243 -379.319589)
			(xy 405.194643 -379.294088) (xy 405.149285 -379.261637) (xy 405.109136 -379.222928) (xy 405.07505 -379.178785)
			(xy 405.047754 -379.13015) (xy 405.027831 -379.078059) (xy 405.015705 -379.023622) (xy 405.011634 -378.968)
			(xy 396.196566 -378.968) (xy 396.196566 -380.69012) (xy 421.204136 -380.69012) (xy 421.204697 -380.65739)
			(xy 421.213556 -380.592532) (xy 421.231047 -380.529452) (xy 421.256855 -380.469294) (xy 421.273224 -380.440946)
			(xy 421.276524 -380.434914) (xy 421.280139 -380.421656) (xy 421.280336 -380.414784) (xy 421.280336 -379.665484)
			(xy 421.280146 -379.658611) (xy 421.276536 -379.645348) (xy 421.273224 -379.639322) (xy 421.256869 -379.610967)
			(xy 421.231064 -379.55081) (xy 421.213572 -379.487732) (xy 421.204708 -379.422877) (xy 421.204136 -379.390148)
			(xy 421.204709 -379.357419) (xy 421.213564 -379.292561) (xy 421.231052 -379.229481) (xy 421.256857 -379.169323)
			(xy 421.273224 -379.140974) (xy 421.27655 -379.134955) (xy 421.280148 -379.121687) (xy 421.280336 -379.114812)
			(xy 421.280336 -378.828554) (xy 421.280789 -378.818425) (xy 421.288531 -378.799703) (xy 421.302827 -378.785349)
			(xy 421.321517 -378.777531) (xy 421.331644 -378.776992) (xy 422.047924 -378.776992) (xy 422.058079 -378.777402)
			(xy 422.07683 -378.785204) (xy 422.091152 -378.799604) (xy 422.098853 -378.818397) (xy 422.099232 -378.828554)
			(xy 422.099232 -379.114812) (xy 422.099416 -379.121686) (xy 422.103029 -379.134949) (xy 422.106344 -379.140974)
			(xy 422.122694 -379.169332) (xy 422.148501 -379.229488) (xy 422.165995 -379.292565) (xy 422.17486 -379.35742)
			(xy 422.175432 -379.390148) (xy 422.174861 -379.422877) (xy 422.166006 -379.487735) (xy 422.148517 -379.550815)
			(xy 422.131689 -379.590046) (xy 423.404284 -379.590046) (xy 423.40485 -379.557317) (xy 423.413706 -379.492458)
			(xy 423.431197 -379.429378) (xy 423.457004 -379.36922) (xy 423.473372 -379.340872) (xy 423.476695 -379.334851)
			(xy 423.480296 -379.321585) (xy 423.480484 -379.31471) (xy 423.480484 -378.56541) (xy 423.48029 -378.558537)
			(xy 423.476683 -378.545274) (xy 423.473372 -378.539248) (xy 423.456983 -378.510912) (xy 423.431187 -378.450747)
			(xy 423.413705 -378.387664) (xy 423.404851 -378.322804) (xy 423.404284 -378.290074) (xy 423.404863 -378.257345)
			(xy 423.413715 -378.192487) (xy 423.431202 -378.129407) (xy 423.457005 -378.069249) (xy 423.473372 -378.0409)
			(xy 423.476685 -378.034874) (xy 423.480292 -378.021611) (xy 423.480484 -378.014738) (xy 423.480484 -377.728734)
			(xy 423.480956 -377.718604) (xy 423.488681 -377.699875) (xy 423.502972 -377.685516) (xy 423.521664 -377.677704)
			(xy 423.531792 -377.677172) (xy 424.248072 -377.677172) (xy 424.258221 -377.677644) (xy 424.276967 -377.685425)
			(xy 424.291291 -377.699806) (xy 424.298996 -377.718584) (xy 424.29938 -377.728734) (xy 424.29938 -378.014738)
			(xy 424.299598 -378.021609) (xy 424.303189 -378.034872) (xy 424.306492 -378.0409) (xy 424.322857 -378.06925)
			(xy 424.348659 -378.129409) (xy 424.366149 -378.192488) (xy 424.37501 -378.257345) (xy 424.37558 -378.290074)
			(xy 424.375028 -378.322797) (xy 427.804911 -378.322797) (xy 427.804914 -378.257358) (xy 427.813701 -378.192512)
			(xy 427.831113 -378.129433) (xy 427.856835 -378.069261) (xy 427.87316 -378.0409) (xy 427.876471 -378.034874)
			(xy 427.88008 -378.021611) (xy 427.880272 -378.014738) (xy 427.880272 -377.728734) (xy 427.880693 -377.71856)
			(xy 427.888473 -377.69976) (xy 427.90286 -377.685373) (xy 427.92166 -377.677593) (xy 427.931834 -377.677172)
			(xy 428.648114 -377.677172) (xy 428.658291 -377.677553) (xy 428.677092 -377.685349) (xy 428.691478 -377.699748)
			(xy 428.699256 -377.718557) (xy 428.699676 -377.728734) (xy 428.699676 -378.014738) (xy 428.699895 -378.021609)
			(xy 428.703485 -378.034872) (xy 428.706788 -378.0409) (xy 428.723087 -378.069274) (xy 428.748806 -378.129442)
			(xy 428.766215 -378.192518) (xy 428.775001 -378.25736) (xy 428.775004 -378.322795) (xy 428.775004 -378.322797)
			(xy 432.2047 -378.322797) (xy 432.204703 -378.257358) (xy 432.21349 -378.192512) (xy 432.230902 -378.129433)
			(xy 432.256624 -378.069261) (xy 432.272948 -378.0409) (xy 432.276259 -378.034873) (xy 432.279867 -378.021611)
			(xy 432.28006 -378.014738) (xy 432.28006 -377.728734) (xy 432.280492 -377.718562) (xy 432.28827 -377.699764)
			(xy 432.302654 -377.685377) (xy 432.32145 -377.677595) (xy 432.331622 -377.677172) (xy 433.047902 -377.677172)
			(xy 433.058078 -377.677563) (xy 433.076879 -377.685355) (xy 433.091265 -377.699751) (xy 433.099044 -377.718558)
			(xy 433.099464 -377.728734) (xy 433.099464 -378.014738) (xy 433.099684 -378.021609) (xy 433.103274 -378.034872)
			(xy 433.106576 -378.0409) (xy 433.122876 -378.069274) (xy 433.148595 -378.129442) (xy 433.166005 -378.192518)
			(xy 433.174791 -378.25736) (xy 433.174792 -378.290074) (xy 436.603656 -378.290074) (xy 436.607647 -378.227907)
			(xy 436.619556 -378.16676) (xy 436.639185 -378.107639) (xy 436.666214 -378.051513) (xy 436.700198 -377.999304)
			(xy 436.74058 -377.951869) (xy 436.786696 -377.909988) (xy 436.837788 -377.874348) (xy 436.893019 -377.845534)
			(xy 436.951481 -377.82402) (xy 437.012215 -377.810158) (xy 437.074222 -377.804176) (xy 437.136485 -377.806172)
			(xy 437.197982 -377.816115) (xy 437.257703 -377.833839) (xy 437.314666 -377.859056) (xy 437.367937 -377.891349)
			(xy 437.416642 -377.930189) (xy 437.459979 -377.974939) (xy 437.497239 -378.024863) (xy 437.527808 -378.079142)
			(xy 437.551186 -378.136885) (xy 437.566987 -378.197143) (xy 437.574953 -378.258926) (xy 437.575452 -378.290074)
			(xy 437.574953 -378.321222) (xy 437.566987 -378.383005) (xy 437.551186 -378.443263) (xy 437.527808 -378.501006)
			(xy 437.497239 -378.555285) (xy 437.459979 -378.605209) (xy 437.416642 -378.649959) (xy 437.367937 -378.688799)
			(xy 437.314666 -378.721092) (xy 437.257703 -378.746309) (xy 437.197982 -378.764033) (xy 437.136485 -378.773976)
			(xy 437.074222 -378.775972) (xy 437.012215 -378.76999) (xy 436.951481 -378.756128) (xy 436.893019 -378.734614)
			(xy 436.837788 -378.7058) (xy 436.786696 -378.67016) (xy 436.74058 -378.628279) (xy 436.700198 -378.580844)
			(xy 436.666214 -378.528635) (xy 436.639185 -378.472509) (xy 436.619556 -378.413388) (xy 436.607647 -378.352241)
			(xy 436.603656 -378.290074) (xy 433.174792 -378.290074) (xy 433.174794 -378.322795) (xy 433.166014 -378.387638)
			(xy 433.148609 -378.450716) (xy 433.122896 -378.510887) (xy 433.106576 -378.539248) (xy 433.103243 -378.545263)
			(xy 433.099649 -378.558534) (xy 433.099464 -378.56541) (xy 433.099464 -379.31471) (xy 433.099657 -379.321583)
			(xy 433.103265 -379.334846) (xy 433.106576 -379.340872) (xy 433.122937 -379.369212) (xy 433.14865 -379.429388)
			(xy 433.166053 -379.492471) (xy 433.174832 -379.55732) (xy 433.174826 -379.622759) (xy 433.166037 -379.687606)
			(xy 433.148624 -379.750686) (xy 433.122901 -379.810859) (xy 433.106576 -379.83922) (xy 433.103252 -379.84524)
			(xy 433.099653 -379.858507) (xy 433.099464 -379.865382) (xy 433.099464 -380.151386) (xy 433.099025 -380.161556)
			(xy 433.091245 -380.180351) (xy 433.076864 -380.194736) (xy 433.058072 -380.202522) (xy 433.047902 -380.202948)
			(xy 432.331622 -380.202948) (xy 432.32145 -380.202518) (xy 432.302653 -380.194737) (xy 432.288267 -380.180353)
			(xy 432.280484 -380.161558) (xy 432.28006 -380.151386) (xy 432.28006 -379.865382) (xy 432.27988 -379.858508)
			(xy 432.276264 -379.845245) (xy 432.272948 -379.83922) (xy 432.256664 -379.810837) (xy 432.230943 -379.750671)
			(xy 432.21353 -379.687597) (xy 432.204741 -379.622756) (xy 432.204736 -379.557323) (xy 432.213514 -379.49248)
			(xy 432.230917 -379.429403) (xy 432.256629 -379.369233) (xy 432.272948 -379.340872) (xy 432.276269 -379.33485)
			(xy 432.279871 -379.321584) (xy 432.28006 -379.31471) (xy 432.28006 -378.56541) (xy 432.279869 -378.558537)
			(xy 432.276261 -378.545274) (xy 432.272948 -378.539248) (xy 432.256603 -378.510899) (xy 432.230887 -378.450725)
			(xy 432.213481 -378.387644) (xy 432.2047 -378.322797) (xy 428.775004 -378.322797) (xy 428.766224 -378.387638)
			(xy 428.74882 -378.450716) (xy 428.723108 -378.510886) (xy 428.706788 -378.539248) (xy 428.703455 -378.545264)
			(xy 428.699861 -378.558534) (xy 428.699676 -378.56541) (xy 428.699676 -379.31471) (xy 428.699867 -379.321583)
			(xy 428.703476 -379.334846) (xy 428.706788 -379.340872) (xy 428.723148 -379.369212) (xy 428.748861 -379.429388)
			(xy 428.766264 -379.492472) (xy 428.775042 -379.55732) (xy 428.775037 -379.622759) (xy 428.766248 -379.687606)
			(xy 428.748835 -379.750686) (xy 428.723112 -379.810858) (xy 428.706788 -379.83922) (xy 428.703465 -379.845241)
			(xy 428.699865 -379.858508) (xy 428.699676 -379.865382) (xy 428.699676 -380.151386) (xy 428.699156 -380.161541)
			(xy 428.691388 -380.180307) (xy 428.677031 -380.194673) (xy 428.658269 -380.20245) (xy 428.648114 -380.202948)
			(xy 427.931834 -380.202948) (xy 427.921663 -380.202508) (xy 427.902866 -380.194731) (xy 427.88848 -380.180351)
			(xy 427.880696 -380.161557) (xy 427.880272 -380.151386) (xy 427.880272 -379.865382) (xy 427.88009 -379.858508)
			(xy 427.876475 -379.845245) (xy 427.87316 -379.83922) (xy 427.856876 -379.810837) (xy 427.831154 -379.750672)
			(xy 427.813741 -379.687597) (xy 427.804952 -379.622756) (xy 427.804946 -379.557323) (xy 427.813725 -379.49248)
			(xy 427.831128 -379.429403) (xy 427.85684 -379.369233) (xy 427.87316 -379.340872) (xy 427.876481 -379.334851)
			(xy 427.880083 -379.321584) (xy 427.880272 -379.31471) (xy 427.880272 -378.56541) (xy 427.88008 -378.558537)
			(xy 427.876472 -378.545274) (xy 427.87316 -378.539248) (xy 427.856815 -378.510899) (xy 427.831098 -378.450725)
			(xy 427.813692 -378.387644) (xy 427.804911 -378.322797) (xy 424.375028 -378.322797) (xy 424.375028 -378.322804)
			(xy 424.366168 -378.387663) (xy 424.348674 -378.450743) (xy 424.322863 -378.5109) (xy 424.306492 -378.539248)
			(xy 424.30316 -378.545264) (xy 424.299565 -378.558534) (xy 424.29938 -378.56541) (xy 424.29938 -379.31471)
			(xy 424.299571 -379.321583) (xy 424.30318 -379.334846) (xy 424.306492 -379.340872) (xy 424.322846 -379.369228)
			(xy 424.348651 -379.429385) (xy 424.366144 -379.492462) (xy 424.375008 -379.557318) (xy 424.37558 -379.590046)
			(xy 424.375015 -379.622776) (xy 424.366159 -379.687634) (xy 424.348669 -379.750714) (xy 424.322861 -379.810872)
			(xy 424.306492 -379.83922) (xy 424.30317 -379.845241) (xy 424.299569 -379.858508) (xy 424.29938 -379.865382)
			(xy 424.29938 -380.151386) (xy 424.298863 -380.161509) (xy 424.291143 -380.180226) (xy 424.276866 -380.194583)
			(xy 424.258193 -380.202406) (xy 424.248072 -380.202948) (xy 423.531792 -380.202948) (xy 423.521643 -380.202486)
			(xy 423.5029 -380.194697) (xy 423.488579 -380.180313) (xy 423.480871 -380.161536) (xy 423.480484 -380.151386)
			(xy 423.480484 -379.865382) (xy 423.480301 -379.858508) (xy 423.476687 -379.845245) (xy 423.473372 -379.83922)
			(xy 423.457012 -379.810868) (xy 423.431209 -379.750709) (xy 423.413718 -379.687631) (xy 423.404856 -379.622775)
			(xy 423.404284 -379.590046) (xy 422.131689 -379.590046) (xy 422.122712 -379.610974) (xy 422.106344 -379.639322)
			(xy 422.103025 -379.645345) (xy 422.099422 -379.65861) (xy 422.099232 -379.665484) (xy 422.099232 -380.414784)
			(xy 422.099426 -380.421657) (xy 422.103033 -380.43492) (xy 422.106344 -380.440946) (xy 422.122723 -380.469288)
			(xy 422.148523 -380.52945) (xy 422.166009 -380.592532) (xy 422.174864 -380.65739) (xy 422.174864 -380.6574)
			(xy 425.604793 -380.6574) (xy 425.613574 -380.592556) (xy 425.630978 -380.529479) (xy 425.656692 -380.469308)
			(xy 425.673012 -380.440946) (xy 425.676311 -380.434914) (xy 425.679926 -380.421656) (xy 425.680124 -380.414784)
			(xy 425.680124 -379.665484) (xy 425.679935 -379.658611) (xy 425.676324 -379.645348) (xy 425.673012 -379.639322)
			(xy 425.656731 -379.610938) (xy 425.631011 -379.550772) (xy 425.6136 -379.487698) (xy 425.604812 -379.422858)
			(xy 425.604806 -379.357425) (xy 425.613583 -379.292583) (xy 425.630984 -379.229506) (xy 425.656694 -379.169335)
			(xy 425.673012 -379.140974) (xy 425.676337 -379.134954) (xy 425.679936 -379.121687) (xy 425.680124 -379.114812)
			(xy 425.680124 -378.828554) (xy 425.680595 -378.818395) (xy 425.688382 -378.799628) (xy 425.702754 -378.785264)
			(xy 425.721527 -378.777489) (xy 425.731686 -378.776992) (xy 426.447966 -378.776992) (xy 426.458116 -378.77756)
			(xy 426.476875 -378.785315) (xy 426.49124 -378.799657) (xy 426.499024 -378.818405) (xy 426.499528 -378.828554)
			(xy 426.499528 -379.114812) (xy 426.499712 -379.121686) (xy 426.503325 -379.134949) (xy 426.50664 -379.140974)
			(xy 426.523004 -379.169313) (xy 426.548718 -379.229489) (xy 426.566123 -379.292572) (xy 426.574902 -379.357421)
			(xy 426.574896 -379.422861) (xy 426.566106 -379.487709) (xy 426.548691 -379.550789) (xy 426.522966 -379.610961)
			(xy 426.50664 -379.639322) (xy 426.503321 -379.645344) (xy 426.499718 -379.65861) (xy 426.499528 -379.665484)
			(xy 426.499528 -380.414784) (xy 426.499723 -380.421657) (xy 426.503329 -380.43492) (xy 426.50664 -380.440946)
			(xy 426.52298 -380.469298) (xy 426.548697 -380.529471) (xy 426.566104 -380.592552) (xy 426.574886 -380.657398)
			(xy 426.574884 -380.69012) (xy 430.00422 -380.69012) (xy 430.00477 -380.65739) (xy 430.01363 -380.592531)
			(xy 430.031125 -380.529451) (xy 430.056937 -380.469293) (xy 430.073308 -380.440946) (xy 430.076607 -380.434914)
			(xy 430.080222 -380.421656) (xy 430.08042 -380.414784) (xy 430.08042 -379.665484) (xy 430.080232 -379.658611)
			(xy 430.076621 -379.645348) (xy 430.073308 -379.639322) (xy 430.056952 -379.610968) (xy 430.031148 -379.55081)
			(xy 430.013655 -379.487732) (xy 430.004792 -379.422877) (xy 430.00422 -379.390148) (xy 430.004782 -379.357418)
			(xy 430.013639 -379.29256) (xy 430.03113 -379.22948) (xy 430.056939 -379.169322) (xy 430.073308 -379.140974)
			(xy 430.076633 -379.134954) (xy 430.080232 -379.121687) (xy 430.08042 -379.114812) (xy 430.08042 -378.828554)
			(xy 430.080888 -378.818427) (xy 430.088628 -378.799708) (xy 430.102919 -378.785354) (xy 430.121603 -378.777533)
			(xy 430.131728 -378.776992) (xy 430.848008 -378.776992) (xy 430.858162 -378.777415) (xy 430.876913 -378.785212)
			(xy 430.891235 -378.799608) (xy 430.898936 -378.818398) (xy 430.899316 -378.828554) (xy 430.899316 -379.114812)
			(xy 430.899501 -379.121686) (xy 430.903114 -379.134949) (xy 430.906428 -379.140974) (xy 430.922786 -379.169327)
			(xy 430.948589 -379.229486) (xy 430.966081 -379.292564) (xy 430.974944 -379.357419) (xy 430.975516 -379.390148)
			(xy 430.974947 -379.422877) (xy 430.966092 -379.487735) (xy 430.948602 -379.550816) (xy 430.922796 -379.610974)
			(xy 430.906428 -379.639322) (xy 430.903107 -379.645344) (xy 430.899505 -379.65861) (xy 430.899316 -379.665484)
			(xy 430.899316 -380.414784) (xy 430.899512 -380.421657) (xy 430.903117 -380.43492) (xy 430.906428 -380.440946)
			(xy 430.922815 -380.469284) (xy 430.948611 -380.529448) (xy 430.966094 -380.592531) (xy 430.974949 -380.65739)
			(xy 430.974949 -380.6574) (xy 434.40488 -380.6574) (xy 434.41366 -380.592557) (xy 434.431064 -380.529479)
			(xy 434.456776 -380.469308) (xy 434.473096 -380.440946) (xy 434.476394 -380.434913) (xy 434.48001 -380.421656)
			(xy 434.480208 -380.414784) (xy 434.480208 -379.665484) (xy 434.480021 -379.65861) (xy 434.476409 -379.645348)
			(xy 434.473096 -379.639322) (xy 434.456816 -379.610938) (xy 434.431097 -379.550772) (xy 434.413686 -379.487698)
			(xy 434.404898 -379.422858) (xy 434.404892 -379.357425) (xy 434.413669 -379.292583) (xy 434.431069 -379.229506)
			(xy 434.456778 -379.169336) (xy 434.473096 -379.140974) (xy 434.47642 -379.134954) (xy 434.48002 -379.121687)
			(xy 434.480208 -379.114812) (xy 434.480208 -378.828554) (xy 434.480695 -378.818397) (xy 434.488479 -378.799633)
			(xy 434.502846 -378.78527) (xy 434.521613 -378.777492) (xy 434.53177 -378.776992) (xy 435.24805 -378.776992)
			(xy 435.258213 -378.777504) (xy 435.276998 -378.785264) (xy 435.291383 -378.799622) (xy 435.299177 -378.818392)
			(xy 435.299612 -378.828554) (xy 435.299612 -379.114812) (xy 435.299798 -379.121686) (xy 435.30341 -379.134949)
			(xy 435.306724 -379.140974) (xy 435.323088 -379.169312) (xy 435.348804 -379.229489) (xy 435.366209 -379.292572)
			(xy 435.374988 -379.357421) (xy 435.374982 -379.422861) (xy 435.366192 -379.487709) (xy 435.348777 -379.550789)
			(xy 435.331993 -379.590046) (xy 436.603656 -379.590046) (xy 436.607647 -379.527879) (xy 436.619556 -379.466732)
			(xy 436.639185 -379.407611) (xy 436.666214 -379.351485) (xy 436.700198 -379.299276) (xy 436.74058 -379.251841)
			(xy 436.786696 -379.20996) (xy 436.837788 -379.17432) (xy 436.893019 -379.145506) (xy 436.951481 -379.123992)
			(xy 437.012215 -379.11013) (xy 437.074222 -379.104148) (xy 437.136485 -379.106144) (xy 437.197982 -379.116087)
			(xy 437.257703 -379.133811) (xy 437.314666 -379.159028) (xy 437.367937 -379.191321) (xy 437.416642 -379.230161)
			(xy 437.459979 -379.274911) (xy 437.497239 -379.324835) (xy 437.527808 -379.379114) (xy 437.532275 -379.390148)
			(xy 438.803804 -379.390148) (xy 438.807795 -379.327981) (xy 438.819704 -379.266834) (xy 438.839333 -379.207713)
			(xy 438.866362 -379.151587) (xy 438.900346 -379.099378) (xy 438.940728 -379.051943) (xy 438.986844 -379.010062)
			(xy 439.037936 -378.974422) (xy 439.093167 -378.945608) (xy 439.151629 -378.924094) (xy 439.212363 -378.910232)
			(xy 439.27437 -378.90425) (xy 439.336633 -378.906246) (xy 439.39813 -378.916189) (xy 439.457851 -378.933913)
			(xy 439.514814 -378.95913) (xy 439.568085 -378.991423) (xy 439.61679 -379.030263) (xy 439.660127 -379.075013)
			(xy 439.697387 -379.124937) (xy 439.727956 -379.179216) (xy 439.751334 -379.236959) (xy 439.767135 -379.297217)
			(xy 439.775101 -379.359) (xy 439.7756 -379.390148) (xy 439.775101 -379.421296) (xy 439.767135 -379.483079)
			(xy 439.751334 -379.543337) (xy 439.727956 -379.60108) (xy 439.697387 -379.655359) (xy 439.660127 -379.705283)
			(xy 439.61679 -379.750033) (xy 439.568085 -379.788873) (xy 439.514814 -379.821166) (xy 439.457851 -379.846383)
			(xy 439.39813 -379.864107) (xy 439.336633 -379.87405) (xy 439.27437 -379.876046) (xy 439.212363 -379.870064)
			(xy 439.151629 -379.856202) (xy 439.093167 -379.834688) (xy 439.037936 -379.805874) (xy 438.986844 -379.770234)
			(xy 438.940728 -379.728353) (xy 438.900346 -379.680918) (xy 438.866362 -379.628709) (xy 438.839333 -379.572583)
			(xy 438.819704 -379.513462) (xy 438.807795 -379.452315) (xy 438.803804 -379.390148) (xy 437.532275 -379.390148)
			(xy 437.551186 -379.436857) (xy 437.566987 -379.497115) (xy 437.574953 -379.558898) (xy 437.575452 -379.590046)
			(xy 437.574953 -379.621194) (xy 437.566987 -379.682977) (xy 437.551186 -379.743235) (xy 437.527808 -379.800978)
			(xy 437.497239 -379.855257) (xy 437.459979 -379.905181) (xy 437.416642 -379.949931) (xy 437.367937 -379.988771)
			(xy 437.314666 -380.021064) (xy 437.257703 -380.046281) (xy 437.197982 -380.064005) (xy 437.136485 -380.073948)
			(xy 437.074222 -380.075944) (xy 437.012215 -380.069962) (xy 436.951481 -380.0561) (xy 436.893019 -380.034586)
			(xy 436.837788 -380.005772) (xy 436.786696 -379.970132) (xy 436.74058 -379.928251) (xy 436.700198 -379.880816)
			(xy 436.666214 -379.828607) (xy 436.639185 -379.772481) (xy 436.619556 -379.71336) (xy 436.607647 -379.652213)
			(xy 436.603656 -379.590046) (xy 435.331993 -379.590046) (xy 435.323051 -379.610961) (xy 435.306724 -379.639322)
			(xy 435.303403 -379.645344) (xy 435.299801 -379.65861) (xy 435.299612 -379.665484) (xy 435.299612 -380.414784)
			(xy 435.299809 -380.421657) (xy 435.303414 -380.43492) (xy 435.306724 -380.440946) (xy 435.323064 -380.469298)
			(xy 435.348782 -380.529471) (xy 435.36619 -380.592551) (xy 435.374972 -380.657398) (xy 435.374971 -380.69012)
			(xy 438.803804 -380.69012) (xy 438.807795 -380.627953) (xy 438.819704 -380.566806) (xy 438.839333 -380.507685)
			(xy 438.866362 -380.451559) (xy 438.900346 -380.39935) (xy 438.940728 -380.351915) (xy 438.986844 -380.310034)
			(xy 439.037936 -380.274394) (xy 439.093167 -380.24558) (xy 439.151629 -380.224066) (xy 439.212363 -380.210204)
			(xy 439.27437 -380.204222) (xy 439.336633 -380.206218) (xy 439.39813 -380.216161) (xy 439.457851 -380.233885)
			(xy 439.514814 -380.259102) (xy 439.568085 -380.291395) (xy 439.61679 -380.330235) (xy 439.660127 -380.374985)
			(xy 439.697387 -380.424909) (xy 439.727956 -380.479188) (xy 439.751334 -380.536931) (xy 439.767135 -380.597189)
			(xy 439.775101 -380.658972) (xy 439.7756 -380.69012) (xy 439.775101 -380.721268) (xy 439.767135 -380.783051)
			(xy 439.751334 -380.843309) (xy 439.727956 -380.901052) (xy 439.697387 -380.955331) (xy 439.660127 -381.005255)
			(xy 439.61679 -381.050005) (xy 439.568085 -381.088845) (xy 439.514814 -381.121138) (xy 439.457851 -381.146355)
			(xy 439.39813 -381.164079) (xy 439.336633 -381.174022) (xy 439.27437 -381.176018) (xy 439.212363 -381.170036)
			(xy 439.151629 -381.156174) (xy 439.093167 -381.13466) (xy 439.037936 -381.105846) (xy 438.986844 -381.070206)
			(xy 438.940728 -381.028325) (xy 438.900346 -380.98089) (xy 438.866362 -380.928681) (xy 438.839333 -380.872555)
			(xy 438.819704 -380.813434) (xy 438.807795 -380.752287) (xy 438.803804 -380.69012) (xy 435.374971 -380.69012)
			(xy 435.37497 -380.722836) (xy 435.366183 -380.787682) (xy 435.348771 -380.850762) (xy 435.323049 -380.910933)
			(xy 435.306724 -380.939294) (xy 435.303413 -380.945321) (xy 435.299805 -380.958583) (xy 435.299612 -380.965456)
			(xy 435.299612 -381.251206) (xy 435.29924 -381.261384) (xy 435.291444 -381.280189) (xy 435.277041 -381.294575)
			(xy 435.258229 -381.302351) (xy 435.24805 -381.302768) (xy 434.53177 -381.302768) (xy 434.521611 -381.302291)
			(xy 434.502842 -381.294508) (xy 434.488478 -381.280138) (xy 434.480704 -381.261365) (xy 434.480208 -381.251206)
			(xy 434.480208 -380.965456) (xy 434.479993 -380.958584) (xy 434.4764 -380.945322) (xy 434.473096 -380.939294)
			(xy 434.456792 -380.910923) (xy 434.431075 -380.850754) (xy 434.413667 -380.787677) (xy 434.404882 -380.722835)
			(xy 434.40488 -380.6574) (xy 430.974949 -380.6574) (xy 430.975516 -380.69012) (xy 430.974935 -380.722849)
			(xy 430.966083 -380.787707) (xy 430.948597 -380.850787) (xy 430.922794 -380.910945) (xy 430.906428 -380.939294)
			(xy 430.903117 -380.945321) (xy 430.899509 -380.958583) (xy 430.899316 -380.965456) (xy 430.899316 -381.251206)
			(xy 430.898877 -381.261338) (xy 430.891139 -381.280068) (xy 430.876838 -381.294426) (xy 430.858138 -381.302237)
			(xy 430.848008 -381.302768) (xy 430.131728 -381.302768) (xy 430.121572 -381.302355) (xy 430.102814 -381.294563)
			(xy 430.088488 -381.280163) (xy 430.080793 -381.261364) (xy 430.08042 -381.251206) (xy 430.08042 -380.965456)
			(xy 430.080204 -380.958585) (xy 430.076612 -380.945322) (xy 430.073308 -380.939294) (xy 430.056941 -380.910946)
			(xy 430.031139 -380.850786) (xy 430.01365 -380.787706) (xy 430.00479 -380.722849) (xy 430.00422 -380.69012)
			(xy 426.574884 -380.69012) (xy 426.574883 -380.722836) (xy 426.566097 -380.787682) (xy 426.548686 -380.850762)
			(xy 426.522964 -380.910933) (xy 426.50664 -380.939294) (xy 426.503331 -380.945321) (xy 426.499721 -380.958583)
			(xy 426.499528 -380.965456) (xy 426.499528 -381.251206) (xy 426.49914 -381.261382) (xy 426.491347 -381.280184)
			(xy 426.47695 -381.294569) (xy 426.458143 -381.302348) (xy 426.447966 -381.302768) (xy 425.731686 -381.302768)
			(xy 425.721528 -381.302278) (xy 425.70276 -381.2945) (xy 425.688395 -381.280133) (xy 425.68062 -381.261364)
			(xy 425.680124 -381.251206) (xy 425.680124 -380.965456) (xy 425.679908 -380.958585) (xy 425.676316 -380.945322)
			(xy 425.673012 -380.939294) (xy 425.656708 -380.910923) (xy 425.63099 -380.850754) (xy 425.613581 -380.787677)
			(xy 425.604796 -380.722835) (xy 425.604793 -380.6574) (xy 422.174864 -380.6574) (xy 422.175432 -380.69012)
			(xy 422.174848 -380.722849) (xy 422.165997 -380.787706) (xy 422.148512 -380.850786) (xy 422.12271 -380.910945)
			(xy 422.106344 -380.939294) (xy 422.103035 -380.945321) (xy 422.099425 -380.958583) (xy 422.099232 -380.965456)
			(xy 422.099232 -381.251206) (xy 422.098777 -381.261337) (xy 422.091042 -381.280063) (xy 422.076746 -381.29442)
			(xy 422.058052 -381.302234) (xy 422.047924 -381.302768) (xy 421.331644 -381.302768) (xy 421.321489 -381.302342)
			(xy 421.302731 -381.294555) (xy 421.288405 -381.280159) (xy 421.28071 -381.261363) (xy 421.280336 -381.251206)
			(xy 421.280336 -380.965456) (xy 421.280118 -380.958585) (xy 421.276527 -380.945322) (xy 421.273224 -380.939294)
			(xy 421.256858 -380.910945) (xy 421.231056 -380.850785) (xy 421.213566 -380.787706) (xy 421.204706 -380.722849)
			(xy 421.204136 -380.69012) (xy 396.196566 -380.69012) (xy 396.196566 -381.50292) (xy 403.816564 -381.50292)
			(xy 403.820635 -381.447298) (xy 403.832761 -381.392861) (xy 403.852684 -381.34077) (xy 403.87998 -381.292135)
			(xy 403.914066 -381.247992) (xy 403.954215 -381.209283) (xy 403.999573 -381.176832) (xy 404.049173 -381.151331)
			(xy 404.101957 -381.133324) (xy 404.1568 -381.123194) (xy 404.212534 -381.121157) (xy 404.267971 -381.127257)
			(xy 404.321928 -381.141363) (xy 404.373257 -381.163175) (xy 404.420863 -381.192229) (xy 404.463731 -381.227904)
			(xy 404.500948 -381.269441) (xy 404.531721 -381.315954) (xy 404.555393 -381.366451) (xy 404.571461 -381.419858)
			(xy 404.579581 -381.475034) (xy 404.58009 -381.50292) (xy 404.579581 -381.530806) (xy 404.571461 -381.585982)
			(xy 404.555393 -381.639389) (xy 404.531721 -381.689886) (xy 404.500948 -381.736399) (xy 404.463731 -381.777936)
			(xy 404.420863 -381.813611) (xy 404.373257 -381.842665) (xy 404.321928 -381.864477) (xy 404.267971 -381.878583)
			(xy 404.212534 -381.884683) (xy 404.1568 -381.882646) (xy 404.101957 -381.872516) (xy 404.049173 -381.854509)
			(xy 403.999573 -381.829008) (xy 403.954215 -381.796557) (xy 403.914066 -381.757848) (xy 403.87998 -381.713705)
			(xy 403.852684 -381.66507) (xy 403.832761 -381.612979) (xy 403.820635 -381.558542) (xy 403.816564 -381.50292)
			(xy 396.196566 -381.50292) (xy 396.196566 -382.524) (xy 408.176982 -382.524) (xy 408.181053 -382.468378)
			(xy 408.193179 -382.413941) (xy 408.213102 -382.36185) (xy 408.240398 -382.313215) (xy 408.274484 -382.269072)
			(xy 408.314633 -382.230363) (xy 408.359991 -382.197912) (xy 408.409591 -382.172411) (xy 408.462375 -382.154404)
			(xy 408.517218 -382.144274) (xy 408.572952 -382.142237) (xy 408.628389 -382.148337) (xy 408.682346 -382.162443)
			(xy 408.733675 -382.184255) (xy 408.781281 -382.213309) (xy 408.792577 -382.22271) (xy 419.004834 -382.22271)
			(xy 419.004835 -382.157272) (xy 419.01362 -382.092427) (xy 419.031031 -382.029348) (xy 419.056752 -381.969177)
			(xy 419.073076 -381.940816) (xy 419.076383 -381.934788) (xy 419.079994 -381.921527) (xy 419.080188 -381.914654)
			(xy 419.080188 -381.628904) (xy 419.080625 -381.618752) (xy 419.088417 -381.600002) (xy 419.102809 -381.585679)
			(xy 419.121596 -381.577977) (xy 419.13175 -381.577596) (xy 419.84803 -381.577596) (xy 419.858153 -381.578101)
			(xy 419.876867 -381.58583) (xy 419.89122 -381.60011) (xy 419.899046 -381.618783) (xy 419.899592 -381.628904)
			(xy 419.899592 -381.914654) (xy 419.899803 -381.921526) (xy 419.903398 -381.934789) (xy 419.906704 -381.940816)
			(xy 419.923016 -381.969182) (xy 419.948733 -382.029353) (xy 419.96614 -382.09243) (xy 419.974924 -382.157274)
			(xy 419.974925 -382.222709) (xy 419.966143 -382.287553) (xy 419.948738 -382.350631) (xy 419.923024 -382.410802)
			(xy 419.906704 -382.439164) (xy 419.903402 -382.445195) (xy 419.899788 -382.458454) (xy 419.899592 -382.465326)
			(xy 419.899592 -383.21488) (xy 419.899792 -383.221753) (xy 419.903395 -383.235015) (xy 419.906704 -383.241042)
			(xy 419.923038 -383.269396) (xy 419.948753 -383.32957) (xy 419.966158 -383.39265) (xy 419.974939 -383.457495)
			(xy 419.974937 -383.522932) (xy 419.966152 -383.587777) (xy 419.948743 -383.650856) (xy 419.923026 -383.711028)
			(xy 419.906704 -383.73939) (xy 419.903393 -383.745417) (xy 419.899785 -383.758679) (xy 419.899592 -383.765552)
			(xy 419.899592 -384.051556) (xy 419.899142 -384.061708) (xy 419.89136 -384.080461) (xy 419.876971 -384.094786)
			(xy 419.858184 -384.102486) (xy 419.84803 -384.102864) (xy 419.13175 -384.102864) (xy 419.121627 -384.102333)
			(xy 419.102908 -384.094622) (xy 419.08855 -384.080349) (xy 419.080728 -384.061676) (xy 419.080188 -384.051556)
			(xy 419.080188 -383.765552) (xy 419.079978 -383.75868) (xy 419.076382 -383.745417) (xy 419.073076 -383.73939)
			(xy 419.056766 -383.711022) (xy 419.031045 -383.650853) (xy 419.013634 -383.587775) (xy 419.004848 -383.522932)
			(xy 419.004847 -383.457496) (xy 419.013629 -383.392652) (xy 419.031036 -383.329573) (xy 419.056754 -383.269403)
			(xy 419.073076 -383.241042) (xy 419.076374 -383.235009) (xy 419.079991 -383.221752) (xy 419.080188 -383.21488)
			(xy 419.080188 -382.465326) (xy 419.079987 -382.458453) (xy 419.076385 -382.445191) (xy 419.073076 -382.439164)
			(xy 419.056744 -382.410808) (xy 419.031025 -382.350636) (xy 419.013617 -382.287556) (xy 419.004834 -382.22271)
			(xy 408.792577 -382.22271) (xy 408.824149 -382.248984) (xy 408.861366 -382.290521) (xy 408.892139 -382.337034)
			(xy 408.915811 -382.387531) (xy 408.931879 -382.440938) (xy 408.939999 -382.496114) (xy 408.940508 -382.524)
			(xy 408.939999 -382.551886) (xy 408.931879 -382.607062) (xy 408.915811 -382.660469) (xy 408.892139 -382.710966)
			(xy 408.861366 -382.757479) (xy 408.824149 -382.799016) (xy 408.781281 -382.834691) (xy 408.733675 -382.863745)
			(xy 408.682346 -382.885557) (xy 408.628389 -382.899663) (xy 408.572952 -382.905763) (xy 408.517218 -382.903726)
			(xy 408.462375 -382.893596) (xy 408.409591 -382.875589) (xy 408.359991 -382.850088) (xy 408.314633 -382.817637)
			(xy 408.274484 -382.778928) (xy 408.240398 -382.734785) (xy 408.213102 -382.68615) (xy 408.193179 -382.634059)
			(xy 408.181053 -382.579622) (xy 408.176982 -382.524) (xy 396.196566 -382.524) (xy 396.196566 -384.06705)
			(xy 403.966932 -384.06705) (xy 403.971003 -384.011428) (xy 403.983129 -383.956991) (xy 404.003052 -383.9049)
			(xy 404.030348 -383.856265) (xy 404.064434 -383.812122) (xy 404.104583 -383.773413) (xy 404.149941 -383.740962)
			(xy 404.199541 -383.715461) (xy 404.252325 -383.697454) (xy 404.307168 -383.687324) (xy 404.362902 -383.685287)
			(xy 404.418339 -383.691387) (xy 404.472296 -383.705493) (xy 404.523625 -383.727305) (xy 404.571231 -383.756359)
			(xy 404.614099 -383.792034) (xy 404.651316 -383.833571) (xy 404.682089 -383.880084) (xy 404.705761 -383.930581)
			(xy 404.721829 -383.983988) (xy 404.729949 -384.039164) (xy 404.730458 -384.06705) (xy 404.729949 -384.094936)
			(xy 404.721829 -384.150112) (xy 404.705761 -384.203519) (xy 404.682089 -384.254016) (xy 404.651316 -384.300529)
			(xy 404.614099 -384.342066) (xy 404.571231 -384.377741) (xy 404.523625 -384.406795) (xy 404.472296 -384.428607)
			(xy 404.418339 -384.442713) (xy 404.362902 -384.448813) (xy 404.307168 -384.446776) (xy 404.252325 -384.436646)
			(xy 404.199541 -384.418639) (xy 404.149941 -384.393138) (xy 404.104583 -384.360687) (xy 404.064434 -384.321978)
			(xy 404.030348 -384.277835) (xy 404.003052 -384.2292) (xy 403.983129 -384.177109) (xy 403.971003 -384.122672)
			(xy 403.966932 -384.06705) (xy 396.196566 -384.06705) (xy 396.196566 -384.683) (xy 406.398982 -384.683)
			(xy 406.403053 -384.627378) (xy 406.415179 -384.572941) (xy 406.435102 -384.52085) (xy 406.462398 -384.472215)
			(xy 406.496484 -384.428072) (xy 406.536633 -384.389363) (xy 406.581991 -384.356912) (xy 406.631591 -384.331411)
			(xy 406.684375 -384.313404) (xy 406.739218 -384.303274) (xy 406.794952 -384.301237) (xy 406.850389 -384.307337)
			(xy 406.904346 -384.321443) (xy 406.955675 -384.343255) (xy 407.003281 -384.372309) (xy 407.046149 -384.407984)
			(xy 407.083366 -384.449521) (xy 407.114139 -384.496034) (xy 407.137811 -384.546531) (xy 407.153879 -384.599938)
			(xy 407.161999 -384.655114) (xy 407.162508 -384.683) (xy 407.161999 -384.710886) (xy 407.153879 -384.766062)
			(xy 407.14066 -384.81) (xy 408.176982 -384.81) (xy 408.181053 -384.754378) (xy 408.193179 -384.699941)
			(xy 408.213102 -384.64785) (xy 408.240398 -384.599215) (xy 408.274484 -384.555072) (xy 408.314633 -384.516363)
			(xy 408.359991 -384.483912) (xy 408.409591 -384.458411) (xy 408.462375 -384.440404) (xy 408.517218 -384.430274)
			(xy 408.572952 -384.428237) (xy 408.628389 -384.434337) (xy 408.682346 -384.448443) (xy 408.733675 -384.470255)
			(xy 408.781281 -384.499309) (xy 408.824149 -384.534984) (xy 408.861366 -384.576521) (xy 408.870308 -384.590036)
			(xy 421.204136 -384.590036) (xy 421.204704 -384.557307) (xy 421.213561 -384.492449) (xy 421.23105 -384.429369)
			(xy 421.256856 -384.36921) (xy 421.273224 -384.340862) (xy 421.276554 -384.334845) (xy 421.28015 -384.321575)
			(xy 421.280336 -384.3147) (xy 421.280336 -383.5654) (xy 421.28014 -383.558527) (xy 421.276534 -383.545265)
			(xy 421.273224 -383.539238) (xy 421.256876 -383.510879) (xy 421.231069 -383.450723) (xy 421.213575 -383.387647)
			(xy 421.204709 -383.322792) (xy 421.204136 -383.290064) (xy 421.204717 -383.257335) (xy 421.213569 -383.192478)
			(xy 421.231055 -383.129398) (xy 421.256858 -383.069239) (xy 421.273224 -383.04089) (xy 421.276544 -383.034868)
			(xy 421.280146 -383.021602) (xy 421.280336 -383.014728) (xy 421.280336 -382.728724) (xy 421.280736 -382.718599)
			(xy 421.288483 -382.699889) (xy 421.302805 -382.685572) (xy 421.321518 -382.677832) (xy 421.331644 -382.677416)
			(xy 422.047924 -382.677416) (xy 422.058036 -382.677866) (xy 422.076718 -382.685614) (xy 422.091013 -382.699922)
			(xy 422.098744 -382.718611) (xy 422.099232 -382.728724) (xy 422.099232 -383.014728) (xy 422.099409 -383.021602)
			(xy 422.103027 -383.034865) (xy 422.106344 -383.04089) (xy 422.1227 -383.069244) (xy 422.148506 -383.129402)
			(xy 422.165998 -383.19248) (xy 422.174861 -383.257335) (xy 422.175432 -383.290064) (xy 422.174868 -383.322794)
			(xy 422.166011 -383.387652) (xy 422.14852 -383.450732) (xy 422.131582 -383.490216) (xy 423.404284 -383.490216)
			(xy 423.404836 -383.457486) (xy 423.413696 -383.392627) (xy 423.431191 -383.329547) (xy 423.457002 -383.26939)
			(xy 423.473372 -383.241042) (xy 423.47667 -383.235009) (xy 423.480287 -383.221752) (xy 423.480484 -383.21488)
			(xy 423.480484 -382.465326) (xy 423.480284 -382.458453) (xy 423.476681 -382.445191) (xy 423.473372 -382.439164)
			(xy 423.456989 -382.410824) (xy 423.431192 -382.350661) (xy 423.413708 -382.287579) (xy 423.404852 -382.22272)
			(xy 423.404284 -382.18999) (xy 423.40487 -382.157261) (xy 423.41372 -382.092404) (xy 423.431205 -382.029324)
			(xy 423.457006 -381.969165) (xy 423.473372 -381.940816) (xy 423.476679 -381.934788) (xy 423.48029 -381.921527)
			(xy 423.480484 -381.914654) (xy 423.480484 -381.628904) (xy 423.480988 -381.618798) (xy 423.488721 -381.600122)
			(xy 423.503012 -381.585828) (xy 423.521686 -381.57809) (xy 423.531792 -381.577596) (xy 424.248072 -381.577596)
			(xy 424.258192 -381.578039) (xy 424.276895 -381.585777) (xy 424.29121 -381.600085) (xy 424.298957 -381.618784)
			(xy 424.29938 -381.628904) (xy 424.29938 -381.914654) (xy 424.299592 -381.921526) (xy 424.303187 -381.934788)
			(xy 424.306492 -381.940816) (xy 424.322863 -381.969162) (xy 424.348664 -382.029323) (xy 424.366152 -382.092403)
			(xy 424.375011 -382.157261) (xy 424.37558 -382.18999) (xy 424.375035 -382.22271) (xy 427.80492 -382.22271)
			(xy 427.804921 -382.157273) (xy 427.813706 -382.092427) (xy 427.831116 -382.029348) (xy 427.856836 -381.969177)
			(xy 427.87316 -381.940816) (xy 427.876466 -381.934787) (xy 427.880077 -381.921527) (xy 427.880272 -381.914654)
			(xy 427.880272 -381.628904) (xy 427.880724 -381.618754) (xy 427.888513 -381.600007) (xy 427.9029 -381.585684)
			(xy 427.921682 -381.577979) (xy 427.931834 -381.577596) (xy 428.648114 -381.577596) (xy 428.658236 -381.578114)
			(xy 428.676949 -381.585838) (xy 428.691303 -381.600114) (xy 428.69913 -381.618785) (xy 428.699676 -381.628904)
			(xy 428.699676 -381.914654) (xy 428.699888 -381.921526) (xy 428.703483 -381.934788) (xy 428.706788 -381.940816)
			(xy 428.723101 -381.969182) (xy 428.748818 -382.029353) (xy 428.766226 -382.09243) (xy 428.77501 -382.157274)
			(xy 428.775011 -382.222709) (xy 428.775011 -382.22271) (xy 432.20471 -382.22271) (xy 432.204711 -382.157273)
			(xy 432.213496 -382.092428) (xy 432.230905 -382.029348) (xy 432.256625 -381.969177) (xy 432.272948 -381.940816)
			(xy 432.276253 -381.934786) (xy 432.279865 -381.921527) (xy 432.28006 -381.914654) (xy 432.28006 -381.628904)
			(xy 432.280524 -381.618755) (xy 432.288311 -381.600011) (xy 432.302694 -381.585689) (xy 432.321471 -381.577981)
			(xy 432.331622 -381.577596) (xy 433.047902 -381.577596) (xy 433.058023 -381.578124) (xy 433.076736 -381.585844)
			(xy 433.091091 -381.600117) (xy 433.098918 -381.618786) (xy 433.099464 -381.628904) (xy 433.099464 -381.914654)
			(xy 433.099678 -381.921526) (xy 433.103272 -381.934788) (xy 433.106576 -381.940816) (xy 433.122889 -381.969182)
			(xy 433.148607 -382.029352) (xy 433.166015 -382.09243) (xy 433.1748 -382.157274) (xy 433.1748 -382.18999)
			(xy 436.603656 -382.18999) (xy 436.607647 -382.127823) (xy 436.619556 -382.066676) (xy 436.639185 -382.007555)
			(xy 436.666214 -381.951429) (xy 436.700198 -381.89922) (xy 436.74058 -381.851785) (xy 436.786696 -381.809904)
			(xy 436.837788 -381.774264) (xy 436.893019 -381.74545) (xy 436.951481 -381.723936) (xy 437.012215 -381.710074)
			(xy 437.074222 -381.704092) (xy 437.136485 -381.706088) (xy 437.197982 -381.716031) (xy 437.257703 -381.733755)
			(xy 437.314666 -381.758972) (xy 437.367937 -381.791265) (xy 437.416642 -381.830105) (xy 437.459979 -381.874855)
			(xy 437.497239 -381.924779) (xy 437.527808 -381.979058) (xy 437.551186 -382.036801) (xy 437.566987 -382.097059)
			(xy 437.574953 -382.158842) (xy 437.575452 -382.18999) (xy 437.574953 -382.221138) (xy 437.566987 -382.282921)
			(xy 437.551186 -382.343179) (xy 437.527808 -382.400922) (xy 437.497239 -382.455201) (xy 437.459979 -382.505125)
			(xy 437.416642 -382.549875) (xy 437.367937 -382.588715) (xy 437.314666 -382.621008) (xy 437.257703 -382.646225)
			(xy 437.197982 -382.663949) (xy 437.136485 -382.673892) (xy 437.074222 -382.675888) (xy 437.012215 -382.669906)
			(xy 436.951481 -382.656044) (xy 436.893019 -382.63453) (xy 436.837788 -382.605716) (xy 436.786696 -382.570076)
			(xy 436.74058 -382.528195) (xy 436.700198 -382.48076) (xy 436.666214 -382.428551) (xy 436.639185 -382.372425)
			(xy 436.619556 -382.313304) (xy 436.607647 -382.252157) (xy 436.603656 -382.18999) (xy 433.1748 -382.18999)
			(xy 433.174801 -382.222709) (xy 433.166019 -382.287553) (xy 433.148613 -382.350631) (xy 433.122897 -382.410803)
			(xy 433.106576 -382.439164) (xy 433.103272 -382.445194) (xy 433.09966 -382.458454) (xy 433.099464 -382.465326)
			(xy 433.099464 -383.21488) (xy 433.099668 -383.221752) (xy 433.103269 -383.235015) (xy 433.106576 -383.241042)
			(xy 433.122911 -383.269396) (xy 433.145729 -383.322788) (xy 434.40485 -383.322788) (xy 434.404854 -383.25735)
			(xy 434.413641 -383.192504) (xy 434.431053 -383.129424) (xy 434.456773 -383.069252) (xy 434.473096 -383.04089)
			(xy 434.476414 -383.034867) (xy 434.480018 -383.021602) (xy 434.480208 -383.014728) (xy 434.480208 -382.728724)
			(xy 434.480641 -382.71857) (xy 434.48843 -382.699817) (xy 434.502824 -382.685492) (xy 434.521614 -382.677793)
			(xy 434.53177 -382.677416) (xy 435.24805 -382.677416) (xy 435.258171 -382.677967) (xy 435.276886 -382.685674)
			(xy 435.291243 -382.69994) (xy 435.299068 -382.718607) (xy 435.299612 -382.728724) (xy 435.299612 -383.014728)
			(xy 435.299792 -383.021602) (xy 435.303408 -383.034865) (xy 435.306724 -383.04089) (xy 435.323017 -383.069268)
			(xy 435.348739 -383.129435) (xy 435.366152 -383.19251) (xy 435.37494 -383.257352) (xy 435.374944 -383.322786)
			(xy 435.366165 -383.387629) (xy 435.34876 -383.450707) (xy 435.331875 -383.490216) (xy 436.603656 -383.490216)
			(xy 436.607647 -383.428049) (xy 436.619556 -383.366902) (xy 436.639185 -383.307781) (xy 436.666214 -383.251655)
			(xy 436.700198 -383.199446) (xy 436.74058 -383.152011) (xy 436.786696 -383.11013) (xy 436.837788 -383.07449)
			(xy 436.893019 -383.045676) (xy 436.951481 -383.024162) (xy 437.012215 -383.0103) (xy 437.074222 -383.004318)
			(xy 437.136485 -383.006314) (xy 437.197982 -383.016257) (xy 437.257703 -383.033981) (xy 437.314666 -383.059198)
			(xy 437.367937 -383.091491) (xy 437.416642 -383.130331) (xy 437.459979 -383.175081) (xy 437.497239 -383.225005)
			(xy 437.527808 -383.279284) (xy 437.532172 -383.290064) (xy 438.803804 -383.290064) (xy 438.807795 -383.227897)
			(xy 438.819704 -383.16675) (xy 438.839333 -383.107629) (xy 438.866362 -383.051503) (xy 438.900346 -382.999294)
			(xy 438.940728 -382.951859) (xy 438.986844 -382.909978) (xy 439.037936 -382.874338) (xy 439.093167 -382.845524)
			(xy 439.151629 -382.82401) (xy 439.212363 -382.810148) (xy 439.27437 -382.804166) (xy 439.336633 -382.806162)
			(xy 439.39813 -382.816105) (xy 439.457851 -382.833829) (xy 439.514814 -382.859046) (xy 439.568085 -382.891339)
			(xy 439.61679 -382.930179) (xy 439.660127 -382.974929) (xy 439.697387 -383.024853) (xy 439.727956 -383.079132)
			(xy 439.751334 -383.136875) (xy 439.767135 -383.197133) (xy 439.775101 -383.258916) (xy 439.7756 -383.290064)
			(xy 439.775101 -383.321212) (xy 439.767135 -383.382995) (xy 439.751334 -383.443253) (xy 439.727956 -383.500996)
			(xy 439.697387 -383.555275) (xy 439.660127 -383.605199) (xy 439.61679 -383.649949) (xy 439.568085 -383.688789)
			(xy 439.514814 -383.721082) (xy 439.457851 -383.746299) (xy 439.39813 -383.764023) (xy 439.336633 -383.773966)
			(xy 439.27437 -383.775962) (xy 439.212363 -383.76998) (xy 439.151629 -383.756118) (xy 439.093167 -383.734604)
			(xy 439.037936 -383.70579) (xy 438.986844 -383.67015) (xy 438.940728 -383.628269) (xy 438.900346 -383.580834)
			(xy 438.866362 -383.528625) (xy 438.839333 -383.472499) (xy 438.819704 -383.413378) (xy 438.807795 -383.352231)
			(xy 438.803804 -383.290064) (xy 437.532172 -383.290064) (xy 437.551186 -383.337027) (xy 437.566987 -383.397285)
			(xy 437.574953 -383.459068) (xy 437.575452 -383.490216) (xy 437.574953 -383.521364) (xy 437.566987 -383.583147)
			(xy 437.551186 -383.643405) (xy 437.527808 -383.701148) (xy 437.497239 -383.755427) (xy 437.459979 -383.805351)
			(xy 437.416642 -383.850101) (xy 437.367937 -383.888941) (xy 437.314666 -383.921234) (xy 437.257703 -383.946451)
			(xy 437.197982 -383.964175) (xy 437.136485 -383.974118) (xy 437.074222 -383.976114) (xy 437.012215 -383.970132)
			(xy 436.951481 -383.95627) (xy 436.893019 -383.934756) (xy 436.837788 -383.905942) (xy 436.786696 -383.870302)
			(xy 436.74058 -383.828421) (xy 436.700198 -383.780986) (xy 436.666214 -383.728777) (xy 436.639185 -383.672651)
			(xy 436.619556 -383.61353) (xy 436.607647 -383.552383) (xy 436.603656 -383.490216) (xy 435.331875 -383.490216)
			(xy 435.323045 -383.510877) (xy 435.306724 -383.539238) (xy 435.303397 -383.545257) (xy 435.299799 -383.558525)
			(xy 435.299612 -383.5654) (xy 435.299612 -384.3147) (xy 435.299803 -384.321573) (xy 435.303412 -384.334836)
			(xy 435.306724 -384.340862) (xy 435.323078 -384.369206) (xy 435.348795 -384.429381) (xy 435.366201 -384.492463)
			(xy 435.374981 -384.557311) (xy 435.374979 -384.590036) (xy 438.803804 -384.590036) (xy 438.807795 -384.527869)
			(xy 438.819704 -384.466722) (xy 438.839333 -384.407601) (xy 438.866362 -384.351475) (xy 438.900346 -384.299266)
			(xy 438.940728 -384.251831) (xy 438.986844 -384.20995) (xy 439.037936 -384.17431) (xy 439.093167 -384.145496)
			(xy 439.151629 -384.123982) (xy 439.212363 -384.11012) (xy 439.27437 -384.104138) (xy 439.336633 -384.106134)
			(xy 439.39813 -384.116077) (xy 439.457851 -384.133801) (xy 439.514814 -384.159018) (xy 439.568085 -384.191311)
			(xy 439.61679 -384.230151) (xy 439.660127 -384.274901) (xy 439.697387 -384.324825) (xy 439.727956 -384.379104)
			(xy 439.751334 -384.436847) (xy 439.767135 -384.497105) (xy 439.775101 -384.558888) (xy 439.7756 -384.590036)
			(xy 439.775101 -384.621184) (xy 439.767135 -384.682967) (xy 439.751334 -384.743225) (xy 439.727956 -384.800968)
			(xy 439.697387 -384.855247) (xy 439.660127 -384.905171) (xy 439.61679 -384.949921) (xy 439.568085 -384.988761)
			(xy 439.514814 -385.021054) (xy 439.457851 -385.046271) (xy 439.39813 -385.063995) (xy 439.336633 -385.073938)
			(xy 439.27437 -385.075934) (xy 439.212363 -385.069952) (xy 439.151629 -385.05609) (xy 439.093167 -385.034576)
			(xy 439.037936 -385.005762) (xy 438.986844 -384.970122) (xy 438.940728 -384.928241) (xy 438.900346 -384.880806)
			(xy 438.866362 -384.828597) (xy 438.839333 -384.772471) (xy 438.819704 -384.71335) (xy 438.807795 -384.652203)
			(xy 438.803804 -384.590036) (xy 435.374979 -384.590036) (xy 435.374977 -384.622751) (xy 435.366188 -384.687598)
			(xy 435.348774 -384.750678) (xy 435.32305 -384.810849) (xy 435.306724 -384.83921) (xy 435.303407 -384.845234)
			(xy 435.299802 -384.858498) (xy 435.299612 -384.865372) (xy 435.299612 -385.151376) (xy 435.299159 -385.161527)
			(xy 435.291374 -385.180277) (xy 435.276987 -385.194601) (xy 435.258203 -385.202303) (xy 435.24805 -385.202684)
			(xy 434.53177 -385.202684) (xy 434.521644 -385.202199) (xy 434.502927 -385.194466) (xy 434.488573 -385.180179)
			(xy 434.48075 -385.161499) (xy 434.480208 -385.151376) (xy 434.480208 -384.865372) (xy 434.480026 -384.858498)
			(xy 434.476411 -384.845235) (xy 434.473096 -384.83921) (xy 434.456806 -384.810831) (xy 434.431087 -384.750664)
			(xy 434.413678 -384.687589) (xy 434.404891 -384.622748) (xy 434.404887 -384.557314) (xy 434.413665 -384.492472)
			(xy 434.431067 -384.429395) (xy 434.456778 -384.369224) (xy 434.473096 -384.340862) (xy 434.476424 -384.334844)
			(xy 434.480021 -384.321575) (xy 434.480208 -384.3147) (xy 434.480208 -383.5654) (xy 434.480015 -383.558527)
			(xy 434.476408 -383.545264) (xy 434.473096 -383.539238) (xy 434.456745 -383.510893) (xy 434.431032 -383.450718)
			(xy 434.413629 -383.387636) (xy 434.40485 -383.322788) (xy 433.145729 -383.322788) (xy 433.148627 -383.329569)
			(xy 433.166033 -383.392649) (xy 433.174815 -383.457495) (xy 433.174813 -383.522933) (xy 433.166027 -383.587778)
			(xy 433.148618 -383.650857) (xy 433.122899 -383.711029) (xy 433.106576 -383.73939) (xy 433.103263 -383.745415)
			(xy 433.099657 -383.758679) (xy 433.099464 -383.765552) (xy 433.099464 -384.051556) (xy 433.099042 -384.061712)
			(xy 433.091254 -384.08047) (xy 433.076856 -384.094796) (xy 433.05806 -384.102491) (xy 433.047902 -384.102864)
			(xy 432.331622 -384.102864) (xy 432.321497 -384.102356) (xy 432.302777 -384.094636) (xy 432.28842 -384.080356)
			(xy 432.2806 -384.061678) (xy 432.28006 -384.051556) (xy 432.28006 -383.765552) (xy 432.279853 -383.75868)
			(xy 432.276256 -383.745417) (xy 432.272948 -383.73939) (xy 432.256639 -383.711021) (xy 432.23092 -383.650852)
			(xy 432.21351 -383.587775) (xy 432.204724 -383.522932) (xy 432.204723 -383.457496) (xy 432.213504 -383.392652)
			(xy 432.230911 -383.329574) (xy 432.256627 -383.269403) (xy 432.272948 -383.241042) (xy 432.276244 -383.235008)
			(xy 432.279862 -383.221752) (xy 432.28006 -383.21488) (xy 432.28006 -382.465326) (xy 432.279863 -382.458453)
			(xy 432.276259 -382.44519) (xy 432.272948 -382.439164) (xy 432.256617 -382.410808) (xy 432.2309 -382.350635)
			(xy 432.213492 -382.287556) (xy 432.20471 -382.22271) (xy 428.775011 -382.22271) (xy 428.766229 -382.287553)
			(xy 428.748824 -382.350631) (xy 428.723109 -382.410802) (xy 428.706788 -382.439164) (xy 428.703485 -382.445194)
			(xy 428.699872 -382.458454) (xy 428.699676 -382.465326) (xy 428.699676 -383.21488) (xy 428.699879 -383.221752)
			(xy 428.70348 -383.235015) (xy 428.706788 -383.241042) (xy 428.723123 -383.269396) (xy 428.748838 -383.329569)
			(xy 428.766243 -383.392649) (xy 428.775025 -383.457495) (xy 428.775023 -383.522932) (xy 428.766238 -383.587778)
			(xy 428.748829 -383.650857) (xy 428.72311 -383.711028) (xy 428.706788 -383.73939) (xy 428.703476 -383.745416)
			(xy 428.699869 -383.758679) (xy 428.699676 -383.765552) (xy 428.699676 -384.051556) (xy 428.699242 -384.06171)
			(xy 428.691456 -384.080466) (xy 428.677063 -384.094792) (xy 428.65827 -384.102489) (xy 428.648114 -384.102864)
			(xy 427.931834 -384.102864) (xy 427.92171 -384.102345) (xy 427.90299 -384.09463) (xy 427.888633 -384.080353)
			(xy 427.880812 -384.061677) (xy 427.880272 -384.051556) (xy 427.880272 -383.765552) (xy 427.880064 -383.75868)
			(xy 427.876467 -383.745417) (xy 427.87316 -383.73939) (xy 427.856851 -383.711021) (xy 427.831131 -383.650852)
			(xy 427.81372 -383.587775) (xy 427.804935 -383.522932) (xy 427.804933 -383.457496) (xy 427.813715 -383.392652)
			(xy 427.831122 -383.329574) (xy 427.856838 -383.269403) (xy 427.87316 -383.241042) (xy 427.876457 -383.235008)
			(xy 427.880074 -383.221752) (xy 427.880272 -383.21488) (xy 427.880272 -382.465326) (xy 427.880074 -382.458453)
			(xy 427.87647 -382.44519) (xy 427.87316 -382.439164) (xy 427.856829 -382.410808) (xy 427.831111 -382.350636)
			(xy 427.813703 -382.287556) (xy 427.80492 -382.22271) (xy 424.375035 -382.22271) (xy 424.375035 -382.22272)
			(xy 424.366173 -382.287579) (xy 424.348677 -382.35066) (xy 424.322863 -382.410817) (xy 424.306492 -382.439164)
			(xy 424.303189 -382.445195) (xy 424.299576 -382.458454) (xy 424.29938 -382.465326) (xy 424.29938 -383.21488)
			(xy 424.299582 -383.221752) (xy 424.303184 -383.235015) (xy 424.306492 -383.241042) (xy 424.322874 -383.269382)
			(xy 424.345775 -383.322789) (xy 425.604764 -383.322789) (xy 425.604768 -383.25735) (xy 425.613555 -383.192504)
			(xy 425.630967 -383.129424) (xy 425.656688 -383.069252) (xy 425.673012 -383.04089) (xy 425.676331 -383.034868)
			(xy 425.679934 -383.021602) (xy 425.680124 -383.014728) (xy 425.680124 -382.728724) (xy 425.680542 -382.718568)
			(xy 425.688334 -382.699812) (xy 425.702732 -382.685487) (xy 425.721528 -382.67779) (xy 425.731686 -382.677416)
			(xy 426.447966 -382.677416) (xy 426.458088 -382.677954) (xy 426.476803 -382.685666) (xy 426.49116 -382.699937)
			(xy 426.498984 -382.718606) (xy 426.499528 -382.728724) (xy 426.499528 -383.014728) (xy 426.499705 -383.021602)
			(xy 426.503323 -383.034865) (xy 426.50664 -383.04089) (xy 426.522932 -383.069268) (xy 426.548654 -383.129435)
			(xy 426.566066 -383.19251) (xy 426.574854 -383.257352) (xy 426.574858 -383.322786) (xy 426.566079 -383.387629)
			(xy 426.548674 -383.450707) (xy 426.52296 -383.510877) (xy 426.50664 -383.539238) (xy 426.503315 -383.545258)
			(xy 426.499715 -383.558525) (xy 426.499528 -383.5654) (xy 426.499528 -384.3147) (xy 426.499717 -384.321574)
			(xy 426.503327 -384.334836) (xy 426.50664 -384.340862) (xy 426.522993 -384.369206) (xy 426.548709 -384.429381)
			(xy 426.566115 -384.492463) (xy 426.574895 -384.557311) (xy 426.574893 -384.590036) (xy 430.00422 -384.590036)
			(xy 430.004777 -384.557306) (xy 430.013635 -384.492447) (xy 430.031128 -384.429367) (xy 430.056938 -384.36921)
			(xy 430.073308 -384.340862) (xy 430.076637 -384.334844) (xy 430.080233 -384.321575) (xy 430.08042 -384.3147)
			(xy 430.08042 -383.5654) (xy 430.080226 -383.558527) (xy 430.076619 -383.545264) (xy 430.073308 -383.539238)
			(xy 430.056958 -383.51088) (xy 430.031152 -383.450724) (xy 430.013658 -383.387647) (xy 430.004793 -383.322792)
			(xy 430.00422 -383.290064) (xy 430.004789 -383.257335) (xy 430.013644 -383.192476) (xy 430.031133 -383.129396)
			(xy 430.05694 -383.069238) (xy 430.073308 -383.04089) (xy 430.076627 -383.034867) (xy 430.08023 -383.021602)
			(xy 430.08042 -383.014728) (xy 430.08042 -382.728724) (xy 430.080836 -382.718601) (xy 430.08858 -382.699894)
			(xy 430.102897 -382.685578) (xy 430.121605 -382.677835) (xy 430.131728 -382.677416) (xy 430.848008 -382.677416)
			(xy 430.858133 -382.67781) (xy 430.87684 -382.685564) (xy 430.891154 -382.699887) (xy 430.898896 -382.718599)
			(xy 430.899316 -382.728724) (xy 430.899316 -383.014728) (xy 430.899495 -383.021602) (xy 430.903112 -383.034865)
			(xy 430.906428 -383.04089) (xy 430.922792 -383.06924) (xy 430.948594 -383.129399) (xy 430.966084 -383.192479)
			(xy 430.974945 -383.257335) (xy 430.975516 -383.290064) (xy 430.974955 -383.322794) (xy 430.966097 -383.387652)
			(xy 430.948606 -383.450732) (xy 430.922797 -383.51089) (xy 430.906428 -383.539238) (xy 430.903102 -383.545257)
			(xy 430.899503 -383.558525) (xy 430.899316 -383.5654) (xy 430.899316 -384.3147) (xy 430.899506 -384.321573)
			(xy 430.903116 -384.334836) (xy 430.906428 -384.340862) (xy 430.922781 -384.369218) (xy 430.948585 -384.429375)
			(xy 430.966078 -384.492453) (xy 430.974943 -384.557308) (xy 430.975516 -384.590036) (xy 430.974942 -384.622765)
			(xy 430.966088 -384.687623) (xy 430.9486 -384.750703) (xy 430.922795 -384.810862) (xy 430.906428 -384.83921)
			(xy 430.903112 -384.845234) (xy 430.899507 -384.858498) (xy 430.899316 -384.865372) (xy 430.899316 -385.151376)
			(xy 430.898865 -385.161495) (xy 430.891128 -385.180195) (xy 430.876822 -385.19451) (xy 430.858127 -385.202259)
			(xy 430.848008 -385.202684) (xy 430.131728 -385.202684) (xy 430.121605 -385.202261) (xy 430.102899 -385.194519)
			(xy 430.088583 -385.180204) (xy 430.08084 -385.161499) (xy 430.08042 -385.151376) (xy 430.08042 -384.865372)
			(xy 430.080236 -384.858498) (xy 430.076622 -384.845236) (xy 430.073308 -384.83921) (xy 430.056947 -384.810858)
			(xy 430.031144 -384.7507) (xy 430.013653 -384.687621) (xy 430.004791 -384.622765) (xy 430.00422 -384.590036)
			(xy 426.574893 -384.590036) (xy 426.574891 -384.622751) (xy 426.566102 -384.687597) (xy 426.548689 -384.750677)
			(xy 426.522965 -384.810849) (xy 426.50664 -384.83921) (xy 426.503325 -384.845235) (xy 426.499719 -384.858498)
			(xy 426.499528 -384.865372) (xy 426.499528 -385.151376) (xy 426.499059 -385.161525) (xy 426.491277 -385.180272)
			(xy 426.476895 -385.194595) (xy 426.458117 -385.202301) (xy 426.447966 -385.202684) (xy 425.731686 -385.202684)
			(xy 425.721561 -385.202185) (xy 425.702845 -385.194457) (xy 425.68849 -385.180175) (xy 425.680667 -385.161498)
			(xy 425.680124 -385.151376) (xy 425.680124 -384.865372) (xy 425.67994 -384.858498) (xy 425.676326 -384.845236)
			(xy 425.673012 -384.83921) (xy 425.656721 -384.810832) (xy 425.631002 -384.750664) (xy 425.613592 -384.687589)
			(xy 425.604805 -384.622748) (xy 425.604801 -384.557314) (xy 425.613579 -384.492472) (xy 425.630982 -384.429394)
			(xy 425.656693 -384.369223) (xy 425.673012 -384.340862) (xy 425.676341 -384.334844) (xy 425.679937 -384.321575)
			(xy 425.680124 -384.3147) (xy 425.680124 -383.5654) (xy 425.679929 -383.558527) (xy 425.676323 -383.545264)
			(xy 425.673012 -383.539238) (xy 425.65666 -383.510893) (xy 425.630947 -383.450718) (xy 425.613543 -383.387636)
			(xy 425.604764 -383.322789) (xy 424.345775 -383.322789) (xy 424.348672 -383.329545) (xy 424.366157 -383.392627)
			(xy 424.375012 -383.457486) (xy 424.37558 -383.490216) (xy 424.375002 -383.522945) (xy 424.36615 -383.587803)
			(xy 424.348664 -383.650883) (xy 424.322859 -383.711042) (xy 424.306492 -383.73939) (xy 424.30318 -383.745416)
			(xy 424.299573 -383.758679) (xy 424.29938 -383.765552) (xy 424.29938 -384.051556) (xy 424.298947 -384.061678)
			(xy 424.29121 -384.080385) (xy 424.276898 -384.094701) (xy 424.258194 -384.102444) (xy 424.248072 -384.102864)
			(xy 423.531792 -384.102864) (xy 423.521665 -384.10249) (xy 423.502954 -384.094732) (xy 423.488639 -384.080402)
			(xy 423.4809 -384.061684) (xy 423.480484 -384.051556) (xy 423.480484 -383.765552) (xy 423.480274 -383.75868)
			(xy 423.476678 -383.745417) (xy 423.473372 -383.73939) (xy 423.457 -383.711044) (xy 423.4312 -383.650883)
			(xy 423.413713 -383.587803) (xy 423.404854 -383.522945) (xy 423.404284 -383.490216) (xy 422.131582 -383.490216)
			(xy 422.122713 -383.51089) (xy 422.106344 -383.539238) (xy 422.103019 -383.545258) (xy 422.099419 -383.558525)
			(xy 422.099232 -383.5654) (xy 422.099232 -384.3147) (xy 422.09942 -384.321574) (xy 422.103031 -384.334836)
			(xy 422.106344 -384.340862) (xy 422.122689 -384.369223) (xy 422.148497 -384.429378) (xy 422.165993 -384.492454)
			(xy 422.174859 -384.557308) (xy 422.175432 -384.590036) (xy 422.174856 -384.622765) (xy 422.166003 -384.687623)
			(xy 422.148515 -384.750703) (xy 422.122711 -384.810862) (xy 422.106344 -384.83921) (xy 422.103029 -384.845235)
			(xy 422.099423 -384.858498) (xy 422.099232 -384.865372) (xy 422.099232 -385.151376) (xy 422.098696 -385.161479)
			(xy 422.090972 -385.180151) (xy 422.076691 -385.194445) (xy 422.058027 -385.202187) (xy 422.047924 -385.202684)
			(xy 421.331644 -385.202684) (xy 421.321522 -385.202247) (xy 421.302817 -385.194511) (xy 421.2885 -385.1802)
			(xy 421.280756 -385.161497) (xy 421.280336 -385.151376) (xy 421.280336 -384.865372) (xy 421.28015 -384.858498)
			(xy 421.276537 -384.845236) (xy 421.273224 -384.83921) (xy 421.256865 -384.810857) (xy 421.231061 -384.750699)
			(xy 421.213569 -384.687621) (xy 421.204707 -384.622765) (xy 421.204136 -384.590036) (xy 408.870308 -384.590036)
			(xy 408.892139 -384.623034) (xy 408.915811 -384.673531) (xy 408.931879 -384.726938) (xy 408.939999 -384.782114)
			(xy 408.940508 -384.81) (xy 408.939999 -384.837886) (xy 408.931879 -384.893062) (xy 408.915811 -384.946469)
			(xy 408.892139 -384.996966) (xy 408.861366 -385.043479) (xy 408.824149 -385.085016) (xy 408.781281 -385.120691)
			(xy 408.733675 -385.149745) (xy 408.682346 -385.171557) (xy 408.628389 -385.185663) (xy 408.572952 -385.191763)
			(xy 408.517218 -385.189726) (xy 408.462375 -385.179596) (xy 408.409591 -385.161589) (xy 408.359991 -385.136088)
			(xy 408.314633 -385.103637) (xy 408.274484 -385.064928) (xy 408.240398 -385.020785) (xy 408.213102 -384.97215)
			(xy 408.193179 -384.920059) (xy 408.181053 -384.865622) (xy 408.176982 -384.81) (xy 407.14066 -384.81)
			(xy 407.137811 -384.819469) (xy 407.114139 -384.869966) (xy 407.083366 -384.916479) (xy 407.046149 -384.958016)
			(xy 407.003281 -384.993691) (xy 406.955675 -385.022745) (xy 406.904346 -385.044557) (xy 406.850389 -385.058663)
			(xy 406.794952 -385.064763) (xy 406.739218 -385.062726) (xy 406.684375 -385.052596) (xy 406.631591 -385.034589)
			(xy 406.581991 -385.009088) (xy 406.536633 -384.976637) (xy 406.496484 -384.937928) (xy 406.462398 -384.893785)
			(xy 406.435102 -384.84515) (xy 406.415179 -384.793059) (xy 406.403053 -384.738622) (xy 406.398982 -384.683)
			(xy 396.196566 -384.683) (xy 396.196566 -385.826) (xy 407.033982 -385.826) (xy 407.038053 -385.770378)
			(xy 407.050179 -385.715941) (xy 407.070102 -385.66385) (xy 407.097398 -385.615215) (xy 407.131484 -385.571072)
			(xy 407.171633 -385.532363) (xy 407.216991 -385.499912) (xy 407.266591 -385.474411) (xy 407.319375 -385.456404)
			(xy 407.374218 -385.446274) (xy 407.429952 -385.444237) (xy 407.485389 -385.450337) (xy 407.539346 -385.464443)
			(xy 407.590675 -385.486255) (xy 407.638281 -385.515309) (xy 407.681149 -385.550984) (xy 407.718366 -385.592521)
			(xy 407.728856 -385.608376) (xy 454.303373 -385.608376) (xy 454.303373 -385.479236) (xy 454.311323 -385.350341)
			(xy 454.327193 -385.222181) (xy 454.350922 -385.09524) (xy 454.382421 -384.970001) (xy 454.42157 -384.846938)
			(xy 454.468221 -384.726519) (xy 454.522196 -384.6092) (xy 454.583291 -384.495426) (xy 454.651274 -384.385629)
			(xy 454.725888 -384.280226) (xy 454.806849 -384.179616) (xy 454.893849 -384.084181) (xy 454.98656 -383.994282)
			(xy 455.08463 -383.910261) (xy 455.187685 -383.832437) (xy 455.295336 -383.761105) (xy 455.407175 -383.696535)
			(xy 455.522776 -383.638973) (xy 455.641701 -383.588636) (xy 455.7635 -383.545716) (xy 455.88771 -383.510375)
			(xy 456.013859 -383.482748) (xy 456.141471 -383.462939) (xy 456.27006 -383.451023) (xy 456.399138 -383.447047)
			(xy 456.528216 -383.451023) (xy 456.656805 -383.462939) (xy 456.784417 -383.482748) (xy 456.910566 -383.510375)
			(xy 457.034776 -383.545716) (xy 457.156575 -383.588636) (xy 457.2755 -383.638973) (xy 457.391101 -383.696535)
			(xy 457.50294 -383.761105) (xy 457.610591 -383.832437) (xy 457.713646 -383.910261) (xy 457.811716 -383.994282)
			(xy 457.904427 -384.084181) (xy 457.991427 -384.179616) (xy 458.072388 -384.280226) (xy 458.147002 -384.385629)
			(xy 458.214985 -384.495426) (xy 458.27608 -384.6092) (xy 458.330055 -384.726519) (xy 458.376706 -384.846938)
			(xy 458.415855 -384.970001) (xy 458.447354 -385.09524) (xy 458.471083 -385.222181) (xy 458.486953 -385.350341)
			(xy 458.494903 -385.479236) (xy 458.4954 -385.543806) (xy 458.494903 -385.608376) (xy 458.486953 -385.737271)
			(xy 458.471083 -385.865431) (xy 458.447354 -385.992372) (xy 458.415855 -386.117611) (xy 458.376706 -386.240674)
			(xy 458.330055 -386.361093) (xy 458.27608 -386.478412) (xy 458.214985 -386.592186) (xy 458.147002 -386.701983)
			(xy 458.072388 -386.807386) (xy 457.991427 -386.907996) (xy 457.904427 -387.003431) (xy 457.811716 -387.09333)
			(xy 457.713646 -387.177351) (xy 457.610591 -387.255175) (xy 457.50294 -387.326507) (xy 457.391101 -387.391077)
			(xy 457.2755 -387.448639) (xy 457.156575 -387.498976) (xy 457.034776 -387.541896) (xy 456.910566 -387.577237)
			(xy 456.784417 -387.604864) (xy 456.656805 -387.624673) (xy 456.528216 -387.636589) (xy 456.399138 -387.640566)
			(xy 456.27006 -387.636589) (xy 456.141471 -387.624673) (xy 456.013859 -387.604864) (xy 455.88771 -387.577237)
			(xy 455.7635 -387.541896) (xy 455.641701 -387.498976) (xy 455.522776 -387.448639) (xy 455.407175 -387.391077)
			(xy 455.295336 -387.326507) (xy 455.187685 -387.255175) (xy 455.08463 -387.177351) (xy 454.98656 -387.09333)
			(xy 454.893849 -387.003431) (xy 454.806849 -386.907996) (xy 454.725888 -386.807386) (xy 454.651274 -386.701983)
			(xy 454.583291 -386.592186) (xy 454.522196 -386.478412) (xy 454.468221 -386.361093) (xy 454.42157 -386.240674)
			(xy 454.382421 -386.117611) (xy 454.350922 -385.992372) (xy 454.327193 -385.865431) (xy 454.311323 -385.737271)
			(xy 454.303373 -385.608376) (xy 407.728856 -385.608376) (xy 407.749139 -385.639034) (xy 407.772811 -385.689531)
			(xy 407.788879 -385.742938) (xy 407.796999 -385.798114) (xy 407.797508 -385.826) (xy 407.796999 -385.853886)
			(xy 407.788879 -385.909062) (xy 407.772811 -385.962469) (xy 407.749139 -386.012966) (xy 407.718366 -386.059479)
			(xy 407.681149 -386.101016) (xy 407.638281 -386.136691) (xy 407.590675 -386.165745) (xy 407.539346 -386.187557)
			(xy 407.485389 -386.201663) (xy 407.429952 -386.207763) (xy 407.374218 -386.205726) (xy 407.319375 -386.195596)
			(xy 407.266591 -386.177589) (xy 407.216991 -386.152088) (xy 407.171633 -386.119637) (xy 407.131484 -386.080928)
			(xy 407.097398 -386.036785) (xy 407.070102 -385.98815) (xy 407.050179 -385.936059) (xy 407.038053 -385.881622)
			(xy 407.033982 -385.826) (xy 396.196566 -385.826) (xy 396.196566 -386.937758) (xy 403.667974 -386.937758)
			(xy 403.672045 -386.882136) (xy 403.684171 -386.827699) (xy 403.704094 -386.775608) (xy 403.73139 -386.726973)
			(xy 403.765476 -386.68283) (xy 403.805625 -386.644121) (xy 403.850983 -386.61167) (xy 403.900583 -386.586169)
			(xy 403.953367 -386.568162) (xy 404.00821 -386.558032) (xy 404.063944 -386.555995) (xy 404.119381 -386.562095)
			(xy 404.173338 -386.576201) (xy 404.224667 -386.598013) (xy 404.272273 -386.627067) (xy 404.315141 -386.662742)
			(xy 404.352358 -386.704279) (xy 404.383131 -386.750792) (xy 404.406803 -386.801289) (xy 404.422871 -386.854696)
			(xy 404.430991 -386.909872) (xy 404.431301 -386.926836) (xy 409.520642 -386.926836) (xy 409.524713 -386.871214)
			(xy 409.536839 -386.816777) (xy 409.556762 -386.764686) (xy 409.584058 -386.716051) (xy 409.618144 -386.671908)
			(xy 409.658293 -386.633199) (xy 409.703651 -386.600748) (xy 409.753251 -386.575247) (xy 409.806035 -386.55724)
			(xy 409.860878 -386.54711) (xy 409.916612 -386.545073) (xy 409.972049 -386.551173) (xy 410.026006 -386.565279)
			(xy 410.077335 -386.587091) (xy 410.124941 -386.616145) (xy 410.167809 -386.65182) (xy 410.205026 -386.693357)
			(xy 410.235799 -386.73987) (xy 410.259471 -386.790367) (xy 410.275539 -386.843774) (xy 410.283659 -386.89895)
			(xy 410.284168 -386.926836) (xy 410.283659 -386.954722) (xy 410.275539 -387.009898) (xy 410.259471 -387.063305)
			(xy 410.235799 -387.113802) (xy 410.205026 -387.160315) (xy 410.167809 -387.201852) (xy 410.124941 -387.237527)
			(xy 410.077335 -387.266581) (xy 410.026006 -387.288393) (xy 409.972049 -387.302499) (xy 409.916612 -387.308599)
			(xy 409.860878 -387.306562) (xy 409.806035 -387.296432) (xy 409.753251 -387.278425) (xy 409.703651 -387.252924)
			(xy 409.658293 -387.220473) (xy 409.618144 -387.181764) (xy 409.584058 -387.137621) (xy 409.556762 -387.088986)
			(xy 409.536839 -387.036895) (xy 409.524713 -386.982458) (xy 409.520642 -386.926836) (xy 404.431301 -386.926836)
			(xy 404.4315 -386.937758) (xy 404.430991 -386.965644) (xy 404.422871 -387.02082) (xy 404.406803 -387.074227)
			(xy 404.383131 -387.124724) (xy 404.352358 -387.171237) (xy 404.315141 -387.212774) (xy 404.272273 -387.248449)
			(xy 404.224667 -387.277503) (xy 404.173338 -387.299315) (xy 404.119381 -387.313421) (xy 404.063944 -387.319521)
			(xy 404.00821 -387.317484) (xy 403.953367 -387.307354) (xy 403.900583 -387.289347) (xy 403.850983 -387.263846)
			(xy 403.805625 -387.231395) (xy 403.765476 -387.192686) (xy 403.73139 -387.148543) (xy 403.704094 -387.099908)
			(xy 403.684171 -387.047817) (xy 403.672045 -386.99338) (xy 403.667974 -386.937758) (xy 396.196566 -386.937758)
			(xy 396.196566 -387.942836) (xy 408.392374 -387.942836) (xy 408.396445 -387.887214) (xy 408.408571 -387.832777)
			(xy 408.428494 -387.780686) (xy 408.45579 -387.732051) (xy 408.489876 -387.687908) (xy 408.530025 -387.649199)
			(xy 408.575383 -387.616748) (xy 408.624983 -387.591247) (xy 408.677767 -387.57324) (xy 408.73261 -387.56311)
			(xy 408.788344 -387.561073) (xy 408.843781 -387.567173) (xy 408.897738 -387.581279) (xy 408.949067 -387.603091)
			(xy 408.996673 -387.632145) (xy 409.039541 -387.66782) (xy 409.076758 -387.709357) (xy 409.107531 -387.75587)
			(xy 409.131203 -387.806367) (xy 409.147271 -387.859774) (xy 409.155391 -387.91495) (xy 409.1559 -387.942836)
			(xy 409.155391 -387.970722) (xy 409.147271 -388.025898) (xy 409.131203 -388.079305) (xy 409.107531 -388.129802)
			(xy 409.076758 -388.176315) (xy 409.039541 -388.217852) (xy 408.996673 -388.253527) (xy 408.949067 -388.282581)
			(xy 408.897738 -388.304393) (xy 408.843781 -388.318499) (xy 408.788344 -388.324599) (xy 408.73261 -388.322562)
			(xy 408.677767 -388.312432) (xy 408.624983 -388.294425) (xy 408.575383 -388.268924) (xy 408.530025 -388.236473)
			(xy 408.489876 -388.197764) (xy 408.45579 -388.153621) (xy 408.428494 -388.104986) (xy 408.408571 -388.052895)
			(xy 408.396445 -387.998458) (xy 408.392374 -387.942836) (xy 396.196566 -387.942836) (xy 396.196566 -388.958836)
			(xy 409.520642 -388.958836) (xy 409.524713 -388.903214) (xy 409.536839 -388.848777) (xy 409.556762 -388.796686)
			(xy 409.584058 -388.748051) (xy 409.618144 -388.703908) (xy 409.658293 -388.665199) (xy 409.703651 -388.632748)
			(xy 409.753251 -388.607247) (xy 409.806035 -388.58924) (xy 409.860878 -388.57911) (xy 409.916612 -388.577073)
			(xy 409.972049 -388.583173) (xy 410.026006 -388.597279) (xy 410.077335 -388.619091) (xy 410.124941 -388.648145)
			(xy 410.167809 -388.68382) (xy 410.205026 -388.725357) (xy 410.235799 -388.77187) (xy 410.259471 -388.822367)
			(xy 410.275539 -388.875774) (xy 410.283659 -388.93095) (xy 410.284168 -388.958836) (xy 410.283659 -388.986722)
			(xy 410.275539 -389.041898) (xy 410.259471 -389.095305) (xy 410.235799 -389.145802) (xy 410.205026 -389.192315)
			(xy 410.167809 -389.233852) (xy 410.124941 -389.269527) (xy 410.077335 -389.298581) (xy 410.026006 -389.320393)
			(xy 409.972049 -389.334499) (xy 409.916612 -389.340599) (xy 409.860878 -389.338562) (xy 409.806035 -389.328432)
			(xy 409.753251 -389.310425) (xy 409.703651 -389.284924) (xy 409.658293 -389.252473) (xy 409.618144 -389.213764)
			(xy 409.584058 -389.169621) (xy 409.556762 -389.120986) (xy 409.536839 -389.068895) (xy 409.524713 -389.014458)
			(xy 409.520642 -388.958836) (xy 396.196566 -388.958836) (xy 396.196566 -389.974836) (xy 408.392374 -389.974836)
			(xy 408.396445 -389.919214) (xy 408.408571 -389.864777) (xy 408.428494 -389.812686) (xy 408.45579 -389.764051)
			(xy 408.489876 -389.719908) (xy 408.530025 -389.681199) (xy 408.575383 -389.648748) (xy 408.624983 -389.623247)
			(xy 408.677767 -389.60524) (xy 408.73261 -389.59511) (xy 408.788344 -389.593073) (xy 408.843781 -389.599173)
			(xy 408.897738 -389.613279) (xy 408.949067 -389.635091) (xy 408.996673 -389.664145) (xy 409.039541 -389.69982)
			(xy 409.076758 -389.741357) (xy 409.107531 -389.78787) (xy 409.131203 -389.838367) (xy 409.147271 -389.891774)
			(xy 409.155391 -389.94695) (xy 409.1559 -389.974836) (xy 409.155391 -390.002722) (xy 409.147271 -390.057898)
			(xy 409.131203 -390.111305) (xy 409.107531 -390.161802) (xy 409.076758 -390.208315) (xy 409.039541 -390.249852)
			(xy 408.996673 -390.285527) (xy 408.949067 -390.314581) (xy 408.897738 -390.336393) (xy 408.843781 -390.350499)
			(xy 408.788344 -390.356599) (xy 408.73261 -390.354562) (xy 408.677767 -390.344432) (xy 408.624983 -390.326425)
			(xy 408.575383 -390.300924) (xy 408.530025 -390.268473) (xy 408.489876 -390.229764) (xy 408.45579 -390.185621)
			(xy 408.428494 -390.136986) (xy 408.408571 -390.084895) (xy 408.396445 -390.030458) (xy 408.392374 -389.974836)
			(xy 396.196566 -389.974836) (xy 396.196566 -390.990836) (xy 406.20391 -390.990836) (xy 406.207981 -390.935214)
			(xy 406.220107 -390.880777) (xy 406.24003 -390.828686) (xy 406.267326 -390.780051) (xy 406.301412 -390.735908)
			(xy 406.341561 -390.697199) (xy 406.386919 -390.664748) (xy 406.436519 -390.639247) (xy 406.489303 -390.62124)
			(xy 406.544146 -390.61111) (xy 406.59988 -390.609073) (xy 406.655317 -390.615173) (xy 406.709274 -390.629279)
			(xy 406.760603 -390.651091) (xy 406.808209 -390.680145) (xy 406.851077 -390.71582) (xy 406.888294 -390.757357)
			(xy 406.919067 -390.80387) (xy 406.942739 -390.854367) (xy 406.958807 -390.907774) (xy 406.966927 -390.96295)
			(xy 406.967436 -390.990836) (xy 406.966927 -391.018722) (xy 406.958807 -391.073898) (xy 406.942739 -391.127305)
			(xy 406.919067 -391.177802) (xy 406.888294 -391.224315) (xy 406.851077 -391.265852) (xy 406.808209 -391.301527)
			(xy 406.760603 -391.330581) (xy 406.709274 -391.352393) (xy 406.655317 -391.366499) (xy 406.59988 -391.372599)
			(xy 406.544146 -391.370562) (xy 406.489303 -391.360432) (xy 406.436519 -391.342425) (xy 406.386919 -391.316924)
			(xy 406.341561 -391.284473) (xy 406.301412 -391.245764) (xy 406.267326 -391.201621) (xy 406.24003 -391.152986)
			(xy 406.220107 -391.100895) (xy 406.207981 -391.046458) (xy 406.20391 -390.990836) (xy 396.196566 -390.990836)
			(xy 396.196566 -392.016742) (xy 405.655778 -392.016742) (xy 405.659849 -391.96112) (xy 405.671975 -391.906683)
			(xy 405.691898 -391.854592) (xy 405.719194 -391.805957) (xy 405.75328 -391.761814) (xy 405.793429 -391.723105)
			(xy 405.838787 -391.690654) (xy 405.888387 -391.665153) (xy 405.941171 -391.647146) (xy 405.996014 -391.637016)
			(xy 406.051748 -391.634979) (xy 406.107185 -391.641079) (xy 406.161142 -391.655185) (xy 406.212471 -391.676997)
			(xy 406.260077 -391.706051) (xy 406.302945 -391.741726) (xy 406.340162 -391.783263) (xy 406.370935 -391.829776)
			(xy 406.394607 -391.880273) (xy 406.410675 -391.93368) (xy 406.418795 -391.988856) (xy 406.419304 -392.016742)
			(xy 406.418795 -392.044628) (xy 406.410675 -392.099804) (xy 406.394607 -392.153211) (xy 406.370935 -392.203708)
			(xy 406.340162 -392.250221) (xy 406.302945 -392.291758) (xy 406.260077 -392.327433) (xy 406.212471 -392.356487)
			(xy 406.161142 -392.378299) (xy 406.107185 -392.392405) (xy 406.051748 -392.398505) (xy 405.996014 -392.396468)
			(xy 405.941171 -392.386338) (xy 405.888387 -392.368331) (xy 405.838787 -392.34283) (xy 405.793429 -392.310379)
			(xy 405.75328 -392.27167) (xy 405.719194 -392.227527) (xy 405.691898 -392.178892) (xy 405.671975 -392.126801)
			(xy 405.659849 -392.072364) (xy 405.655778 -392.016742) (xy 396.196566 -392.016742) (xy 396.196566 -410.308552)
			(xy 396.197328 -410.316934) (xy 396.198848 -410.324536) (xy 396.205844 -410.33836) (xy 396.211044 -410.344112)
			(xy 396.381732 -410.5148) (xy 396.388586 -410.522195) (xy 396.396331 -410.540794) (xy 396.396718 -410.550868)
			(xy 396.396718 -412.676594) (xy 396.396297 -412.686665) (xy 396.388586 -412.705273) (xy 396.381732 -412.712662)
			(xy 395.829536 -413.264858) (xy 395.822136 -413.271699) (xy 395.803537 -413.279417) (xy 395.793468 -413.279844)
			(xy 375.459498 -413.279844) (xy 375.449429 -413.279419) (xy 375.430831 -413.271698) (xy 375.42343 -413.264858)
			(xy 374.289066 -412.130494) (xy 374.282213 -412.123098) (xy 374.27447 -412.1045) (xy 374.27408 -412.094426)
			(xy 374.27408 -396.840964) (xy 374.273985 -396.836086) (xy 374.272201 -396.826496) (xy 374.270524 -396.821914)
			(xy 374.266714 -396.81277) (xy 373.441976 -395.988032) (xy 373.438247 -395.984509) (xy 373.429674 -395.978876)
			(xy 373.424958 -395.976856) (xy 373.416322 -395.9733) (xy 372.919244 -395.9733) (xy 372.909178 -395.972866)
			(xy 372.890589 -395.965138) (xy 372.883176 -395.958314) (xy 369.102386 -392.177524) (xy 369.095542 -392.170126)
			(xy 369.087822 -392.151526) (xy 369.0874 -392.141456) (xy 369.0874 -391.341102) (xy 369.086816 -391.32934)
			(xy 369.076371 -391.308263) (xy 369.067334 -391.300716) (xy 368.26063 -390.68756) (xy 368.227113 -390.661561)
			(xy 368.164149 -390.604711) (xy 368.10624 -390.542719) (xy 368.053805 -390.476033) (xy 368.007223 -390.405134)
			(xy 367.966831 -390.330535) (xy 367.94948 -390.291828) (xy 367.892838 -390.162034) (xy 367.8301 -390.017762)
			(xy 367.829592 -390.016492) (xy 367.82745 -390.012081) (xy 367.821697 -390.004142) (xy 367.818162 -390.000744)
			(xy 367.526316 -389.762746) (xy 367.494298 -389.73609) (xy 367.434379 -389.678194) (xy 367.37955 -389.615457)
			(xy 367.330202 -389.548323) (xy 367.286686 -389.47727) (xy 367.24931 -389.402804) (xy 367.218342 -389.325453)
			(xy 367.205768 -389.285734) (xy 367.185702 -389.220202) (xy 367.18399 -389.215119) (xy 367.178733 -389.205771)
			(xy 367.175288 -389.20166) (xy 367.16843 -389.193786) (xy 367.15827 -389.189214) (xy 367.133809 -389.177372)
			(xy 367.088216 -389.147798) (xy 367.047272 -389.112063) (xy 367.011805 -389.070887) (xy 366.982529 -389.025101)
			(xy 366.960035 -388.97563) (xy 366.944777 -388.923471) (xy 366.937063 -388.869676) (xy 366.936528 -388.842504)
			(xy 366.936528 -388.84225) (xy 366.936971 -388.816204) (xy 366.944048 -388.764596) (xy 366.958064 -388.714425)
			(xy 366.978759 -388.666621) (xy 366.9919 -388.64413) (xy 366.992408 -388.643622) (xy 366.994969 -388.639071)
			(xy 366.998423 -388.629218) (xy 366.999266 -388.624064) (xy 367.000536 -388.613904) (xy 366.901222 -388.289546)
			(xy 366.901222 -388.289292) (xy 366.897553 -388.279108) (xy 366.883199 -388.262933) (xy 366.873536 -388.25805)
			(xy 366.794796 -388.228332) (xy 366.789282 -388.226471) (xy 366.777735 -388.22505) (xy 366.771936 -388.225538)
			(xy 366.760506 -388.226554) (xy 366.750346 -388.232904) (xy 366.727494 -388.24661) (xy 366.678801 -388.268253)
			(xy 366.627574 -388.282922) (xy 366.574805 -388.290333) (xy 366.548162 -388.290816) (xy 366.520898 -388.290327)
			(xy 366.466925 -388.282562) (xy 366.414606 -388.267195) (xy 366.365007 -388.24454) (xy 366.319136 -388.215056)
			(xy 366.277928 -388.179345) (xy 366.242221 -388.138134) (xy 366.212742 -388.09226) (xy 366.190092 -388.042658)
			(xy 366.17473 -387.990338) (xy 366.16697 -387.936364) (xy 366.16697 -387.881836) (xy 366.17473 -387.827862)
			(xy 366.190092 -387.775542) (xy 366.212742 -387.72594) (xy 366.242221 -387.680066) (xy 366.277928 -387.638855)
			(xy 366.319136 -387.603144) (xy 366.365007 -387.57366) (xy 366.414606 -387.551005) (xy 366.466925 -387.535638)
			(xy 366.520898 -387.527873) (xy 366.548162 -387.527292) (xy 366.548416 -387.527292) (xy 366.559427 -387.527371)
			(xy 366.581411 -387.528644) (xy 366.592358 -387.529832) (xy 366.592612 -387.529832) (xy 366.59439 -387.530086)
			(xy 366.596676 -387.53034) (xy 366.606454 -387.530691) (xy 366.625114 -387.524864) (xy 366.64023 -387.512468)
			(xy 366.649599 -387.495311) (xy 366.651855 -387.475893) (xy 366.649762 -387.466332) (xy 366.649254 -387.464808)
			(xy 366.485932 -386.931916) (xy 366.485678 -386.9309) (xy 366.273588 -386.443474) (xy 366.255517 -386.400637)
			(xy 366.226483 -386.312307) (xy 366.205785 -386.221661) (xy 366.193603 -386.129483) (xy 366.191292 -386.083048)
			(xy 366.18672 -385.958334) (xy 366.184434 -385.94538) (xy 366.003332 -385.353052) (xy 366.00257 -385.350766)
			(xy 365.510318 -383.977134) (xy 365.496779 -383.938091) (xy 365.475488 -383.858237) (xy 365.460941 -383.776884)
			(xy 365.453239 -383.6946) (xy 365.452406 -383.653284) (xy 365.442246 -382.618996) (xy 365.44123 -382.609344)
			(xy 364.084362 -375.90222) (xy 362.92917 -370.191538) (xy 362.928359 -370.187895) (xy 362.925806 -370.180882)
			(xy 362.92409 -370.177568) (xy 362.920788 -370.171472) (xy 358.99344 -366.244124) (xy 358.989709 -366.240603)
			(xy 358.981134 -366.234977) (xy 358.976422 -366.232948) (xy 358.967786 -366.229392) (xy 352.701352 -366.229392)
			(xy 352.696474 -366.229488) (xy 352.686885 -366.231277) (xy 352.682302 -366.232948) (xy 352.673158 -366.236758)
			(xy 350.366584 -368.543332) (xy 350.363064 -368.547063) (xy 350.357437 -368.555638) (xy 350.355408 -368.56035)
			(xy 350.351852 -368.568986) (xy 350.351852 -368.990118) (xy 350.80398 -368.990118) (xy 350.807971 -368.927951)
			(xy 350.81988 -368.866804) (xy 350.839509 -368.807683) (xy 350.866538 -368.751557) (xy 350.900522 -368.699348)
			(xy 350.940904 -368.651913) (xy 350.98702 -368.610032) (xy 351.038112 -368.574392) (xy 351.093343 -368.545578)
			(xy 351.151805 -368.524064) (xy 351.212539 -368.510202) (xy 351.274546 -368.50422) (xy 351.336809 -368.506216)
			(xy 351.398306 -368.516159) (xy 351.458027 -368.533883) (xy 351.51499 -368.5591) (xy 351.568261 -368.591393)
			(xy 351.616966 -368.630233) (xy 351.660303 -368.674983) (xy 351.697563 -368.724907) (xy 351.728132 -368.779186)
			(xy 351.75151 -368.836929) (xy 351.767311 -368.897187) (xy 351.775277 -368.95897) (xy 351.775776 -368.990118)
			(xy 351.775277 -369.021266) (xy 351.767311 -369.083049) (xy 351.75151 -369.143307) (xy 351.728132 -369.20105)
			(xy 351.697563 -369.255329) (xy 351.660303 -369.305253) (xy 351.616966 -369.350003) (xy 351.568261 -369.388843)
			(xy 351.51499 -369.421136) (xy 351.458027 -369.446353) (xy 351.398306 -369.464077) (xy 351.336809 -369.47402)
			(xy 351.274546 -369.476016) (xy 351.212539 -369.470034) (xy 351.151805 -369.456172) (xy 351.093343 -369.434658)
			(xy 351.038112 -369.405844) (xy 350.98702 -369.370204) (xy 350.940904 -369.328323) (xy 350.900522 -369.280888)
			(xy 350.866538 -369.228679) (xy 350.839509 -369.172553) (xy 350.81988 -369.113432) (xy 350.807971 -369.052285)
			(xy 350.80398 -368.990118) (xy 350.351852 -368.990118) (xy 350.351852 -371.590062) (xy 350.80398 -371.590062)
			(xy 350.807971 -371.527895) (xy 350.81988 -371.466748) (xy 350.839509 -371.407627) (xy 350.866538 -371.351501)
			(xy 350.900522 -371.299292) (xy 350.940904 -371.251857) (xy 350.98702 -371.209976) (xy 351.038112 -371.174336)
			(xy 351.093343 -371.145522) (xy 351.151805 -371.124008) (xy 351.212539 -371.110146) (xy 351.274546 -371.104164)
			(xy 351.336809 -371.10616) (xy 351.398306 -371.116103) (xy 351.458027 -371.133827) (xy 351.51499 -371.159044)
			(xy 351.568261 -371.191337) (xy 351.616966 -371.230177) (xy 351.660303 -371.274927) (xy 351.697563 -371.324851)
			(xy 351.728132 -371.37913) (xy 351.75151 -371.436873) (xy 351.767311 -371.497131) (xy 351.775277 -371.558914)
			(xy 351.775776 -371.590062) (xy 351.775277 -371.62121) (xy 351.767311 -371.682993) (xy 351.75151 -371.743251)
			(xy 351.728132 -371.800994) (xy 351.697563 -371.855273) (xy 351.660303 -371.905197) (xy 351.616966 -371.949947)
			(xy 351.568261 -371.988787) (xy 351.51499 -372.02108) (xy 351.458027 -372.046297) (xy 351.398306 -372.064021)
			(xy 351.336809 -372.073964) (xy 351.274546 -372.07596) (xy 351.212539 -372.069978) (xy 351.151805 -372.056116)
			(xy 351.093343 -372.034602) (xy 351.038112 -372.005788) (xy 350.98702 -371.970148) (xy 350.940904 -371.928267)
			(xy 350.900522 -371.880832) (xy 350.866538 -371.828623) (xy 350.839509 -371.772497) (xy 350.81988 -371.713376)
			(xy 350.807971 -371.652229) (xy 350.80398 -371.590062) (xy 350.351852 -371.590062) (xy 350.351852 -372.890034)
			(xy 350.80398 -372.890034) (xy 350.807971 -372.827867) (xy 350.81988 -372.76672) (xy 350.839509 -372.707599)
			(xy 350.866538 -372.651473) (xy 350.900522 -372.599264) (xy 350.940904 -372.551829) (xy 350.98702 -372.509948)
			(xy 351.038112 -372.474308) (xy 351.093343 -372.445494) (xy 351.151805 -372.42398) (xy 351.212539 -372.410118)
			(xy 351.274546 -372.404136) (xy 351.336809 -372.406132) (xy 351.398306 -372.416075) (xy 351.458027 -372.433799)
			(xy 351.51499 -372.459016) (xy 351.568261 -372.491309) (xy 351.616966 -372.530149) (xy 351.660303 -372.574899)
			(xy 351.697563 -372.624823) (xy 351.728132 -372.679102) (xy 351.75151 -372.736845) (xy 351.767311 -372.797103)
			(xy 351.775277 -372.858886) (xy 351.775776 -372.890034) (xy 351.775277 -372.921182) (xy 351.767311 -372.982965)
			(xy 351.75151 -373.043223) (xy 351.728132 -373.100966) (xy 351.697563 -373.155245) (xy 351.660303 -373.205169)
			(xy 351.616966 -373.249919) (xy 351.568261 -373.288759) (xy 351.51499 -373.321052) (xy 351.458027 -373.346269)
			(xy 351.398306 -373.363993) (xy 351.336809 -373.373936) (xy 351.274546 -373.375932) (xy 351.212539 -373.36995)
			(xy 351.151805 -373.356088) (xy 351.093343 -373.334574) (xy 351.038112 -373.30576) (xy 350.98702 -373.27012)
			(xy 350.940904 -373.228239) (xy 350.900522 -373.180804) (xy 350.866538 -373.128595) (xy 350.839509 -373.072469)
			(xy 350.81988 -373.013348) (xy 350.807971 -372.952201) (xy 350.80398 -372.890034) (xy 350.351852 -372.890034)
			(xy 350.351852 -375.490232) (xy 350.80398 -375.490232) (xy 350.807971 -375.428065) (xy 350.81988 -375.366918)
			(xy 350.839509 -375.307797) (xy 350.866538 -375.251671) (xy 350.900522 -375.199462) (xy 350.940904 -375.152027)
			(xy 350.98702 -375.110146) (xy 351.038112 -375.074506) (xy 351.093343 -375.045692) (xy 351.151805 -375.024178)
			(xy 351.212539 -375.010316) (xy 351.274546 -375.004334) (xy 351.336809 -375.00633) (xy 351.398306 -375.016273)
			(xy 351.458027 -375.033997) (xy 351.51499 -375.059214) (xy 351.568261 -375.091507) (xy 351.616966 -375.130347)
			(xy 351.660303 -375.175097) (xy 351.697563 -375.225021) (xy 351.728132 -375.2793) (xy 351.75151 -375.337043)
			(xy 351.767311 -375.397301) (xy 351.775277 -375.459084) (xy 351.775776 -375.490232) (xy 351.775277 -375.52138)
			(xy 351.767311 -375.583163) (xy 351.75151 -375.643421) (xy 351.728132 -375.701164) (xy 351.697563 -375.755443)
			(xy 351.660303 -375.805367) (xy 351.616966 -375.850117) (xy 351.568261 -375.888957) (xy 351.51499 -375.92125)
			(xy 351.458027 -375.946467) (xy 351.398306 -375.964191) (xy 351.336809 -375.974134) (xy 351.274546 -375.97613)
			(xy 351.212539 -375.970148) (xy 351.151805 -375.956286) (xy 351.093343 -375.934772) (xy 351.038112 -375.905958)
			(xy 350.98702 -375.870318) (xy 350.940904 -375.828437) (xy 350.900522 -375.781002) (xy 350.866538 -375.728793)
			(xy 350.839509 -375.672667) (xy 350.81988 -375.613546) (xy 350.807971 -375.552399) (xy 350.80398 -375.490232)
			(xy 350.351852 -375.490232) (xy 350.351852 -376.790204) (xy 350.80398 -376.790204) (xy 350.807971 -376.728037)
			(xy 350.81988 -376.66689) (xy 350.839509 -376.607769) (xy 350.866538 -376.551643) (xy 350.900522 -376.499434)
			(xy 350.940904 -376.451999) (xy 350.98702 -376.410118) (xy 351.038112 -376.374478) (xy 351.093343 -376.345664)
			(xy 351.151805 -376.32415) (xy 351.212539 -376.310288) (xy 351.274546 -376.304306) (xy 351.336809 -376.306302)
			(xy 351.398306 -376.316245) (xy 351.458027 -376.333969) (xy 351.51499 -376.359186) (xy 351.568261 -376.391479)
			(xy 351.616966 -376.430319) (xy 351.660303 -376.475069) (xy 351.697563 -376.524993) (xy 351.728132 -376.579272)
			(xy 351.75151 -376.637015) (xy 351.767311 -376.697273) (xy 351.775277 -376.759056) (xy 351.775776 -376.790204)
			(xy 351.775277 -376.821352) (xy 351.767311 -376.883135) (xy 351.75151 -376.943393) (xy 351.728132 -377.001136)
			(xy 351.697563 -377.055415) (xy 351.660303 -377.105339) (xy 351.616966 -377.150089) (xy 351.568261 -377.188929)
			(xy 351.51499 -377.221222) (xy 351.458027 -377.246439) (xy 351.398306 -377.264163) (xy 351.336809 -377.274106)
			(xy 351.274546 -377.276102) (xy 351.212539 -377.27012) (xy 351.151805 -377.256258) (xy 351.093343 -377.234744)
			(xy 351.038112 -377.20593) (xy 350.98702 -377.17029) (xy 350.940904 -377.128409) (xy 350.900522 -377.080974)
			(xy 350.866538 -377.028765) (xy 350.839509 -376.972639) (xy 350.81988 -376.913518) (xy 350.807971 -376.852371)
			(xy 350.80398 -376.790204) (xy 350.351852 -376.790204) (xy 350.351852 -379.390148) (xy 350.80398 -379.390148)
			(xy 350.807971 -379.327981) (xy 350.81988 -379.266834) (xy 350.839509 -379.207713) (xy 350.866538 -379.151587)
			(xy 350.900522 -379.099378) (xy 350.940904 -379.051943) (xy 350.98702 -379.010062) (xy 351.038112 -378.974422)
			(xy 351.093343 -378.945608) (xy 351.151805 -378.924094) (xy 351.212539 -378.910232) (xy 351.274546 -378.90425)
			(xy 351.336809 -378.906246) (xy 351.398306 -378.916189) (xy 351.458027 -378.933913) (xy 351.51499 -378.95913)
			(xy 351.568261 -378.991423) (xy 351.616966 -379.030263) (xy 351.660303 -379.075013) (xy 351.670291 -379.088396)
			(xy 362.932978 -379.088396) (xy 362.937049 -379.032774) (xy 362.949175 -378.978337) (xy 362.969098 -378.926246)
			(xy 362.996394 -378.877611) (xy 363.03048 -378.833468) (xy 363.070629 -378.794759) (xy 363.115987 -378.762308)
			(xy 363.165587 -378.736807) (xy 363.218371 -378.7188) (xy 363.273214 -378.70867) (xy 363.328948 -378.706633)
			(xy 363.384385 -378.712733) (xy 363.438342 -378.726839) (xy 363.489671 -378.748651) (xy 363.537277 -378.777705)
			(xy 363.580145 -378.81338) (xy 363.617362 -378.854917) (xy 363.648135 -378.90143) (xy 363.671807 -378.951927)
			(xy 363.687875 -379.005334) (xy 363.695995 -379.06051) (xy 363.696504 -379.088396) (xy 363.695995 -379.116282)
			(xy 363.687875 -379.171458) (xy 363.671807 -379.224865) (xy 363.648135 -379.275362) (xy 363.617362 -379.321875)
			(xy 363.580145 -379.363412) (xy 363.537277 -379.399087) (xy 363.489671 -379.428141) (xy 363.438342 -379.449953)
			(xy 363.384385 -379.464059) (xy 363.328948 -379.470159) (xy 363.273214 -379.468122) (xy 363.218371 -379.457992)
			(xy 363.165587 -379.439985) (xy 363.115987 -379.414484) (xy 363.070629 -379.382033) (xy 363.03048 -379.343324)
			(xy 362.996394 -379.299181) (xy 362.969098 -379.250546) (xy 362.949175 -379.198455) (xy 362.937049 -379.144018)
			(xy 362.932978 -379.088396) (xy 351.670291 -379.088396) (xy 351.697563 -379.124937) (xy 351.728132 -379.179216)
			(xy 351.75151 -379.236959) (xy 351.767311 -379.297217) (xy 351.775277 -379.359) (xy 351.775776 -379.390148)
			(xy 351.775277 -379.421296) (xy 351.767311 -379.483079) (xy 351.75151 -379.543337) (xy 351.728132 -379.60108)
			(xy 351.697583 -379.655324) (xy 360.52074 -379.655324) (xy 360.524811 -379.599702) (xy 360.536937 -379.545265)
			(xy 360.55686 -379.493174) (xy 360.584156 -379.444539) (xy 360.618242 -379.400396) (xy 360.658391 -379.361687)
			(xy 360.703749 -379.329236) (xy 360.753349 -379.303735) (xy 360.806133 -379.285728) (xy 360.860976 -379.275598)
			(xy 360.91671 -379.273561) (xy 360.972147 -379.279661) (xy 361.026104 -379.293767) (xy 361.077433 -379.315579)
			(xy 361.125039 -379.344633) (xy 361.167907 -379.380308) (xy 361.205124 -379.421845) (xy 361.235897 -379.468358)
			(xy 361.259569 -379.518855) (xy 361.275637 -379.572262) (xy 361.283757 -379.627438) (xy 361.284266 -379.655324)
			(xy 361.283757 -379.68321) (xy 361.275637 -379.738386) (xy 361.259569 -379.791793) (xy 361.235897 -379.84229)
			(xy 361.205124 -379.888803) (xy 361.167907 -379.93034) (xy 361.125039 -379.966015) (xy 361.077433 -379.995069)
			(xy 361.026104 -380.016881) (xy 360.972147 -380.030987) (xy 360.91671 -380.037087) (xy 360.860976 -380.03505)
			(xy 360.806133 -380.02492) (xy 360.753349 -380.006913) (xy 360.703749 -379.981412) (xy 360.658391 -379.948961)
			(xy 360.618242 -379.910252) (xy 360.584156 -379.866109) (xy 360.55686 -379.817474) (xy 360.536937 -379.765383)
			(xy 360.524811 -379.710946) (xy 360.52074 -379.655324) (xy 351.697583 -379.655324) (xy 351.697563 -379.655359)
			(xy 351.660303 -379.705283) (xy 351.616966 -379.750033) (xy 351.568261 -379.788873) (xy 351.51499 -379.821166)
			(xy 351.458027 -379.846383) (xy 351.398306 -379.864107) (xy 351.336809 -379.87405) (xy 351.274546 -379.876046)
			(xy 351.212539 -379.870064) (xy 351.151805 -379.856202) (xy 351.093343 -379.834688) (xy 351.038112 -379.805874)
			(xy 350.98702 -379.770234) (xy 350.940904 -379.728353) (xy 350.900522 -379.680918) (xy 350.866538 -379.628709)
			(xy 350.839509 -379.572583) (xy 350.81988 -379.513462) (xy 350.807971 -379.452315) (xy 350.80398 -379.390148)
			(xy 350.351852 -379.390148) (xy 350.351852 -380.69012) (xy 350.80398 -380.69012) (xy 350.807971 -380.627953)
			(xy 350.81988 -380.566806) (xy 350.839509 -380.507685) (xy 350.866538 -380.451559) (xy 350.900522 -380.39935)
			(xy 350.940904 -380.351915) (xy 350.98702 -380.310034) (xy 351.038112 -380.274394) (xy 351.093343 -380.24558)
			(xy 351.151805 -380.224066) (xy 351.212539 -380.210204) (xy 351.274546 -380.204222) (xy 351.336809 -380.206218)
			(xy 351.398306 -380.216161) (xy 351.458027 -380.233885) (xy 351.51499 -380.259102) (xy 351.568261 -380.291395)
			(xy 351.616966 -380.330235) (xy 351.660303 -380.374985) (xy 351.697563 -380.424909) (xy 351.728132 -380.479188)
			(xy 351.75151 -380.536931) (xy 351.767311 -380.597189) (xy 351.775277 -380.658972) (xy 351.775776 -380.69012)
			(xy 351.775277 -380.721268) (xy 351.767311 -380.783051) (xy 351.75151 -380.843309) (xy 351.728132 -380.901052)
			(xy 351.697563 -380.955331) (xy 351.660303 -381.005255) (xy 351.616966 -381.050005) (xy 351.568261 -381.088845)
			(xy 351.51499 -381.121138) (xy 351.458027 -381.146355) (xy 351.398306 -381.164079) (xy 351.336809 -381.174022)
			(xy 351.274546 -381.176018) (xy 351.212539 -381.170036) (xy 351.151805 -381.156174) (xy 351.093343 -381.13466)
			(xy 351.038112 -381.105846) (xy 350.98702 -381.070206) (xy 350.940904 -381.028325) (xy 350.900522 -380.98089)
			(xy 350.866538 -380.928681) (xy 350.839509 -380.872555) (xy 350.81988 -380.813434) (xy 350.807971 -380.752287)
			(xy 350.80398 -380.69012) (xy 350.351852 -380.69012) (xy 350.351852 -381.714502) (xy 360.796838 -381.714502)
			(xy 360.800909 -381.65888) (xy 360.813035 -381.604443) (xy 360.832958 -381.552352) (xy 360.860254 -381.503717)
			(xy 360.89434 -381.459574) (xy 360.934489 -381.420865) (xy 360.979847 -381.388414) (xy 361.029447 -381.362913)
			(xy 361.082231 -381.344906) (xy 361.137074 -381.334776) (xy 361.192808 -381.332739) (xy 361.248245 -381.338839)
			(xy 361.302202 -381.352945) (xy 361.353531 -381.374757) (xy 361.401137 -381.403811) (xy 361.444005 -381.439486)
			(xy 361.481222 -381.481023) (xy 361.511995 -381.527536) (xy 361.535667 -381.578033) (xy 361.551735 -381.63144)
			(xy 361.559855 -381.686616) (xy 361.560364 -381.714502) (xy 361.559855 -381.742388) (xy 361.551735 -381.797564)
			(xy 361.535667 -381.850971) (xy 361.511995 -381.901468) (xy 361.481222 -381.947981) (xy 361.444005 -381.989518)
			(xy 361.401137 -382.025193) (xy 361.353531 -382.054247) (xy 361.302202 -382.076059) (xy 361.248245 -382.090165)
			(xy 361.192808 -382.096265) (xy 361.137074 -382.094228) (xy 361.082231 -382.084098) (xy 361.029447 -382.066091)
			(xy 360.979847 -382.04059) (xy 360.934489 -382.008139) (xy 360.89434 -381.96943) (xy 360.860254 -381.925287)
			(xy 360.832958 -381.876652) (xy 360.813035 -381.824561) (xy 360.800909 -381.770124) (xy 360.796838 -381.714502)
			(xy 350.351852 -381.714502) (xy 350.351852 -383.290064) (xy 350.80398 -383.290064) (xy 350.807971 -383.227897)
			(xy 350.81988 -383.16675) (xy 350.839509 -383.107629) (xy 350.866538 -383.051503) (xy 350.900522 -382.999294)
			(xy 350.940904 -382.951859) (xy 350.98702 -382.909978) (xy 351.038112 -382.874338) (xy 351.093343 -382.845524)
			(xy 351.151805 -382.82401) (xy 351.212539 -382.810148) (xy 351.274546 -382.804166) (xy 351.336809 -382.806162)
			(xy 351.398306 -382.816105) (xy 351.458027 -382.833829) (xy 351.51499 -382.859046) (xy 351.568261 -382.891339)
			(xy 351.616966 -382.930179) (xy 351.660303 -382.974929) (xy 351.697563 -383.024853) (xy 351.728132 -383.079132)
			(xy 351.75151 -383.136875) (xy 351.767311 -383.197133) (xy 351.775277 -383.258916) (xy 351.775776 -383.290064)
			(xy 351.775277 -383.321212) (xy 351.767311 -383.382995) (xy 351.75151 -383.443253) (xy 351.728132 -383.500996)
			(xy 351.697563 -383.555275) (xy 351.660303 -383.605199) (xy 351.616966 -383.649949) (xy 351.568261 -383.688789)
			(xy 351.51499 -383.721082) (xy 351.458027 -383.746299) (xy 351.398306 -383.764023) (xy 351.336809 -383.773966)
			(xy 351.274546 -383.775962) (xy 351.212539 -383.76998) (xy 351.151805 -383.756118) (xy 351.093343 -383.734604)
			(xy 351.038112 -383.70579) (xy 350.98702 -383.67015) (xy 350.940904 -383.628269) (xy 350.900522 -383.580834)
			(xy 350.866538 -383.528625) (xy 350.839509 -383.472499) (xy 350.81988 -383.413378) (xy 350.807971 -383.352231)
			(xy 350.80398 -383.290064) (xy 350.351852 -383.290064) (xy 350.351852 -384.590036) (xy 350.80398 -384.590036)
			(xy 350.807971 -384.527869) (xy 350.81988 -384.466722) (xy 350.839509 -384.407601) (xy 350.866538 -384.351475)
			(xy 350.900522 -384.299266) (xy 350.940904 -384.251831) (xy 350.98702 -384.20995) (xy 351.038112 -384.17431)
			(xy 351.093343 -384.145496) (xy 351.151805 -384.123982) (xy 351.212539 -384.11012) (xy 351.274546 -384.104138)
			(xy 351.336809 -384.106134) (xy 351.398306 -384.116077) (xy 351.458027 -384.133801) (xy 351.51499 -384.159018)
			(xy 351.568261 -384.191311) (xy 351.616966 -384.230151) (xy 351.660303 -384.274901) (xy 351.697563 -384.324825)
			(xy 351.728132 -384.379104) (xy 351.75151 -384.436847) (xy 351.767311 -384.497105) (xy 351.775277 -384.558888)
			(xy 351.775776 -384.590036) (xy 351.775277 -384.621184) (xy 351.767311 -384.682967) (xy 351.75151 -384.743225)
			(xy 351.728132 -384.800968) (xy 351.697563 -384.855247) (xy 351.660303 -384.905171) (xy 351.616966 -384.949921)
			(xy 351.568261 -384.988761) (xy 351.51499 -385.021054) (xy 351.458027 -385.046271) (xy 351.398306 -385.063995)
			(xy 351.336809 -385.073938) (xy 351.274546 -385.075934) (xy 351.212539 -385.069952) (xy 351.151805 -385.05609)
			(xy 351.093343 -385.034576) (xy 351.038112 -385.005762) (xy 350.98702 -384.970122) (xy 350.940904 -384.928241)
			(xy 350.900522 -384.880806) (xy 350.866538 -384.828597) (xy 350.839509 -384.772471) (xy 350.81988 -384.71335)
			(xy 350.807971 -384.652203) (xy 350.80398 -384.590036) (xy 350.351852 -384.590036) (xy 350.351852 -386.172456)
			(xy 361.296202 -386.172456) (xy 361.300273 -386.116834) (xy 361.312399 -386.062397) (xy 361.332322 -386.010306)
			(xy 361.359618 -385.961671) (xy 361.393704 -385.917528) (xy 361.433853 -385.878819) (xy 361.479211 -385.846368)
			(xy 361.528811 -385.820867) (xy 361.581595 -385.80286) (xy 361.636438 -385.79273) (xy 361.692172 -385.790693)
			(xy 361.747609 -385.796793) (xy 361.801566 -385.810899) (xy 361.852895 -385.832711) (xy 361.900501 -385.861765)
			(xy 361.943369 -385.89744) (xy 361.980586 -385.938977) (xy 362.011359 -385.98549) (xy 362.035031 -386.035987)
			(xy 362.051099 -386.089394) (xy 362.059219 -386.14457) (xy 362.059728 -386.172456) (xy 362.059219 -386.200342)
			(xy 362.051099 -386.255518) (xy 362.035031 -386.308925) (xy 362.011359 -386.359422) (xy 361.980586 -386.405935)
			(xy 361.943369 -386.447472) (xy 361.900501 -386.483147) (xy 361.852895 -386.512201) (xy 361.801566 -386.534013)
			(xy 361.747609 -386.548119) (xy 361.692172 -386.554219) (xy 361.636438 -386.552182) (xy 361.581595 -386.542052)
			(xy 361.528811 -386.524045) (xy 361.479211 -386.498544) (xy 361.433853 -386.466093) (xy 361.393704 -386.427384)
			(xy 361.359618 -386.383241) (xy 361.332322 -386.334606) (xy 361.312399 -386.282515) (xy 361.300273 -386.228078)
			(xy 361.296202 -386.172456) (xy 350.351852 -386.172456) (xy 350.351852 -387.9723) (xy 362.73308 -387.9723)
			(xy 362.737151 -387.916678) (xy 362.749277 -387.862241) (xy 362.7692 -387.81015) (xy 362.796496 -387.761515)
			(xy 362.830582 -387.717372) (xy 362.870731 -387.678663) (xy 362.916089 -387.646212) (xy 362.965689 -387.620711)
			(xy 363.018473 -387.602704) (xy 363.073316 -387.592574) (xy 363.12905 -387.590537) (xy 363.184487 -387.596637)
			(xy 363.238444 -387.610743) (xy 363.289773 -387.632555) (xy 363.337379 -387.661609) (xy 363.380247 -387.697284)
			(xy 363.417464 -387.738821) (xy 363.448237 -387.785334) (xy 363.471909 -387.835831) (xy 363.487977 -387.889238)
			(xy 363.496097 -387.944414) (xy 363.496606 -387.9723) (xy 363.496097 -388.000186) (xy 363.487977 -388.055362)
			(xy 363.471909 -388.108769) (xy 363.448237 -388.159266) (xy 363.417464 -388.205779) (xy 363.380247 -388.247316)
			(xy 363.337379 -388.282991) (xy 363.289773 -388.312045) (xy 363.238444 -388.333857) (xy 363.184487 -388.347963)
			(xy 363.12905 -388.354063) (xy 363.073316 -388.352026) (xy 363.018473 -388.341896) (xy 362.965689 -388.323889)
			(xy 362.916089 -388.298388) (xy 362.870731 -388.265937) (xy 362.830582 -388.227228) (xy 362.796496 -388.183085)
			(xy 362.7692 -388.13445) (xy 362.749277 -388.082359) (xy 362.737151 -388.027922) (xy 362.73308 -387.9723)
			(xy 350.351852 -387.9723) (xy 350.351852 -390.28878) (xy 357.386126 -390.28878) (xy 357.390197 -390.233158)
			(xy 357.402323 -390.178721) (xy 357.422246 -390.12663) (xy 357.449542 -390.077995) (xy 357.483628 -390.033852)
			(xy 357.523777 -389.995143) (xy 357.569135 -389.962692) (xy 357.618735 -389.937191) (xy 357.671519 -389.919184)
			(xy 357.726362 -389.909054) (xy 357.782096 -389.907017) (xy 357.837533 -389.913117) (xy 357.89149 -389.927223)
			(xy 357.942819 -389.949035) (xy 357.990425 -389.978089) (xy 358.033293 -390.013764) (xy 358.07051 -390.055301)
			(xy 358.101283 -390.101814) (xy 358.124955 -390.152311) (xy 358.141023 -390.205718) (xy 358.149143 -390.260894)
			(xy 358.149652 -390.28878) (xy 358.149143 -390.316666) (xy 358.141023 -390.371842) (xy 358.124955 -390.425249)
			(xy 358.101283 -390.475746) (xy 358.07051 -390.522259) (xy 358.033293 -390.563796) (xy 357.990425 -390.599471)
			(xy 357.942819 -390.628525) (xy 357.89149 -390.650337) (xy 357.837533 -390.664443) (xy 357.782096 -390.670543)
			(xy 357.726362 -390.668506) (xy 357.671519 -390.658376) (xy 357.618735 -390.640369) (xy 357.569135 -390.614868)
			(xy 357.523777 -390.582417) (xy 357.483628 -390.543708) (xy 357.449542 -390.499565) (xy 357.422246 -390.45093)
			(xy 357.402323 -390.398839) (xy 357.390197 -390.344402) (xy 357.386126 -390.28878) (xy 350.351852 -390.28878)
			(xy 350.351852 -391.26541) (xy 365.668812 -391.26541) (xy 365.672883 -391.209788) (xy 365.685009 -391.155351)
			(xy 365.704932 -391.10326) (xy 365.732228 -391.054625) (xy 365.766314 -391.010482) (xy 365.806463 -390.971773)
			(xy 365.851821 -390.939322) (xy 365.901421 -390.913821) (xy 365.954205 -390.895814) (xy 366.009048 -390.885684)
			(xy 366.064782 -390.883647) (xy 366.120219 -390.889747) (xy 366.174176 -390.903853) (xy 366.225505 -390.925665)
			(xy 366.273111 -390.954719) (xy 366.315979 -390.990394) (xy 366.353196 -391.031931) (xy 366.383969 -391.078444)
			(xy 366.407641 -391.128941) (xy 366.423709 -391.182348) (xy 366.431829 -391.237524) (xy 366.432338 -391.26541)
			(xy 366.431829 -391.293296) (xy 366.423709 -391.348472) (xy 366.407641 -391.401879) (xy 366.383969 -391.452376)
			(xy 366.353196 -391.498889) (xy 366.315979 -391.540426) (xy 366.273111 -391.576101) (xy 366.225505 -391.605155)
			(xy 366.174176 -391.626967) (xy 366.120219 -391.641073) (xy 366.064782 -391.647173) (xy 366.009048 -391.645136)
			(xy 365.954205 -391.635006) (xy 365.901421 -391.616999) (xy 365.851821 -391.591498) (xy 365.806463 -391.559047)
			(xy 365.766314 -391.520338) (xy 365.732228 -391.476195) (xy 365.704932 -391.42756) (xy 365.685009 -391.375469)
			(xy 365.672883 -391.321032) (xy 365.668812 -391.26541) (xy 350.351852 -391.26541) (xy 350.351852 -392.684254)
			(xy 363.702852 -392.684254) (xy 363.706923 -392.628632) (xy 363.719049 -392.574195) (xy 363.738972 -392.522104)
			(xy 363.766268 -392.473469) (xy 363.800354 -392.429326) (xy 363.840503 -392.390617) (xy 363.885861 -392.358166)
			(xy 363.935461 -392.332665) (xy 363.988245 -392.314658) (xy 364.043088 -392.304528) (xy 364.098822 -392.302491)
			(xy 364.154259 -392.308591) (xy 364.208216 -392.322697) (xy 364.259545 -392.344509) (xy 364.307151 -392.373563)
			(xy 364.350019 -392.409238) (xy 364.387236 -392.450775) (xy 364.418009 -392.497288) (xy 364.441681 -392.547785)
			(xy 364.457749 -392.601192) (xy 364.465869 -392.656368) (xy 364.466378 -392.684254) (xy 364.465869 -392.71214)
			(xy 364.457749 -392.767316) (xy 364.441681 -392.820723) (xy 364.418009 -392.87122) (xy 364.387236 -392.917733)
			(xy 364.350019 -392.95927) (xy 364.307151 -392.994945) (xy 364.259545 -393.023999) (xy 364.208216 -393.045811)
			(xy 364.154259 -393.059917) (xy 364.098822 -393.066017) (xy 364.043088 -393.06398) (xy 363.988245 -393.05385)
			(xy 363.935461 -393.035843) (xy 363.885861 -393.010342) (xy 363.840503 -392.977891) (xy 363.800354 -392.939182)
			(xy 363.766268 -392.895039) (xy 363.738972 -392.846404) (xy 363.719049 -392.794313) (xy 363.706923 -392.739876)
			(xy 363.702852 -392.684254) (xy 350.351852 -392.684254) (xy 350.351852 -393.459716) (xy 357.18572 -393.459716)
			(xy 357.189791 -393.404094) (xy 357.201917 -393.349657) (xy 357.22184 -393.297566) (xy 357.249136 -393.248931)
			(xy 357.283222 -393.204788) (xy 357.323371 -393.166079) (xy 357.368729 -393.133628) (xy 357.418329 -393.108127)
			(xy 357.471113 -393.09012) (xy 357.525956 -393.07999) (xy 357.58169 -393.077953) (xy 357.637127 -393.084053)
			(xy 357.691084 -393.098159) (xy 357.742413 -393.119971) (xy 357.790019 -393.149025) (xy 357.832887 -393.1847)
			(xy 357.870104 -393.226237) (xy 357.900877 -393.27275) (xy 357.924549 -393.323247) (xy 357.940617 -393.376654)
			(xy 357.948737 -393.43183) (xy 357.949246 -393.459716) (xy 357.948737 -393.487602) (xy 357.940617 -393.542778)
			(xy 357.924549 -393.596185) (xy 357.900877 -393.646682) (xy 357.870104 -393.693195) (xy 357.832887 -393.734732)
			(xy 357.790019 -393.770407) (xy 357.742413 -393.799461) (xy 357.691084 -393.821273) (xy 357.637127 -393.835379)
			(xy 357.58169 -393.841479) (xy 357.525956 -393.839442) (xy 357.471113 -393.829312) (xy 357.418329 -393.811305)
			(xy 357.368729 -393.785804) (xy 357.323371 -393.753353) (xy 357.283222 -393.714644) (xy 357.249136 -393.670501)
			(xy 357.22184 -393.621866) (xy 357.201917 -393.569775) (xy 357.189791 -393.515338) (xy 357.18572 -393.459716)
			(xy 350.351852 -393.459716) (xy 350.351852 -396.063724) (xy 357.261158 -396.063724) (xy 357.265229 -396.008102)
			(xy 357.277355 -395.953665) (xy 357.297278 -395.901574) (xy 357.324574 -395.852939) (xy 357.35866 -395.808796)
			(xy 357.398809 -395.770087) (xy 357.444167 -395.737636) (xy 357.493767 -395.712135) (xy 357.546551 -395.694128)
			(xy 357.601394 -395.683998) (xy 357.657128 -395.681961) (xy 357.712565 -395.688061) (xy 357.766522 -395.702167)
			(xy 357.817851 -395.723979) (xy 357.865457 -395.753033) (xy 357.908325 -395.788708) (xy 357.945542 -395.830245)
			(xy 357.976315 -395.876758) (xy 357.999987 -395.927255) (xy 358.016055 -395.980662) (xy 358.024175 -396.035838)
			(xy 358.024684 -396.063724) (xy 358.024175 -396.09161) (xy 358.016055 -396.146786) (xy 357.999987 -396.200193)
			(xy 357.976315 -396.25069) (xy 357.945542 -396.297203) (xy 357.908325 -396.33874) (xy 357.865457 -396.374415)
			(xy 357.817851 -396.403469) (xy 357.766522 -396.425281) (xy 357.712565 -396.439387) (xy 357.657128 -396.445487)
			(xy 357.601394 -396.44345) (xy 357.546551 -396.43332) (xy 357.493767 -396.415313) (xy 357.444167 -396.389812)
			(xy 357.398809 -396.357361) (xy 357.35866 -396.318652) (xy 357.324574 -396.274509) (xy 357.297278 -396.225874)
			(xy 357.277355 -396.173783) (xy 357.265229 -396.119346) (xy 357.261158 -396.063724) (xy 350.351852 -396.063724)
			(xy 350.351852 -397.025622) (xy 365.416844 -397.025622) (xy 365.420915 -396.97) (xy 365.433041 -396.915563)
			(xy 365.452964 -396.863472) (xy 365.48026 -396.814837) (xy 365.514346 -396.770694) (xy 365.554495 -396.731985)
			(xy 365.599853 -396.699534) (xy 365.649453 -396.674033) (xy 365.702237 -396.656026) (xy 365.75708 -396.645896)
			(xy 365.812814 -396.643859) (xy 365.868251 -396.649959) (xy 365.922208 -396.664065) (xy 365.973537 -396.685877)
			(xy 366.021143 -396.714931) (xy 366.064011 -396.750606) (xy 366.101048 -396.791942) (xy 366.335308 -396.791942)
			(xy 366.339379 -396.73632) (xy 366.351505 -396.681883) (xy 366.371428 -396.629792) (xy 366.398724 -396.581157)
			(xy 366.43281 -396.537014) (xy 366.472959 -396.498305) (xy 366.518317 -396.465854) (xy 366.567917 -396.440353)
			(xy 366.620701 -396.422346) (xy 366.675544 -396.412216) (xy 366.731278 -396.410179) (xy 366.786715 -396.416279)
			(xy 366.840672 -396.430385) (xy 366.892001 -396.452197) (xy 366.939607 -396.481251) (xy 366.982475 -396.516926)
			(xy 367.019692 -396.558463) (xy 367.050465 -396.604976) (xy 367.074137 -396.655473) (xy 367.090205 -396.70888)
			(xy 367.098325 -396.764056) (xy 367.098834 -396.791942) (xy 367.098325 -396.819828) (xy 367.090205 -396.875004)
			(xy 367.074137 -396.928411) (xy 367.050465 -396.978908) (xy 367.019692 -397.025421) (xy 366.982475 -397.066958)
			(xy 366.939607 -397.102633) (xy 366.892001 -397.131687) (xy 366.840672 -397.153499) (xy 366.786715 -397.167605)
			(xy 366.731278 -397.173705) (xy 366.675544 -397.171668) (xy 366.620701 -397.161538) (xy 366.567917 -397.143531)
			(xy 366.518317 -397.11803) (xy 366.472959 -397.085579) (xy 366.43281 -397.04687) (xy 366.398724 -397.002727)
			(xy 366.371428 -396.954092) (xy 366.351505 -396.902001) (xy 366.339379 -396.847564) (xy 366.335308 -396.791942)
			(xy 366.101048 -396.791942) (xy 366.101228 -396.792143) (xy 366.132001 -396.838656) (xy 366.155673 -396.889153)
			(xy 366.171741 -396.94256) (xy 366.179861 -396.997736) (xy 366.18037 -397.025622) (xy 366.179861 -397.053508)
			(xy 366.171741 -397.108684) (xy 366.155673 -397.162091) (xy 366.132001 -397.212588) (xy 366.101228 -397.259101)
			(xy 366.064011 -397.300638) (xy 366.021143 -397.336313) (xy 365.973537 -397.365367) (xy 365.922208 -397.387179)
			(xy 365.868251 -397.401285) (xy 365.812814 -397.407385) (xy 365.75708 -397.405348) (xy 365.702237 -397.395218)
			(xy 365.649453 -397.377211) (xy 365.599853 -397.35171) (xy 365.554495 -397.319259) (xy 365.514346 -397.28055)
			(xy 365.48026 -397.236407) (xy 365.452964 -397.187772) (xy 365.433041 -397.135681) (xy 365.420915 -397.081244)
			(xy 365.416844 -397.025622) (xy 350.351852 -397.025622) (xy 350.351852 -397.59001) (xy 350.80398 -397.59001)
			(xy 350.807971 -397.527843) (xy 350.81988 -397.466696) (xy 350.839509 -397.407575) (xy 350.866538 -397.351449)
			(xy 350.900522 -397.29924) (xy 350.940904 -397.251805) (xy 350.98702 -397.209924) (xy 351.038112 -397.174284)
			(xy 351.093343 -397.14547) (xy 351.151805 -397.123956) (xy 351.212539 -397.110094) (xy 351.274546 -397.104112)
			(xy 351.336809 -397.106108) (xy 351.398306 -397.116051) (xy 351.458027 -397.133775) (xy 351.51499 -397.158992)
			(xy 351.568261 -397.191285) (xy 351.616966 -397.230125) (xy 351.660303 -397.274875) (xy 351.697563 -397.324799)
			(xy 351.728132 -397.379078) (xy 351.75151 -397.436821) (xy 351.767311 -397.497079) (xy 351.775277 -397.558862)
			(xy 351.775776 -397.59001) (xy 351.775277 -397.621158) (xy 351.767311 -397.682941) (xy 351.75151 -397.743199)
			(xy 351.728132 -397.800942) (xy 351.697563 -397.855221) (xy 351.660303 -397.905145) (xy 351.616966 -397.949895)
			(xy 351.568261 -397.988735) (xy 351.51499 -398.021028) (xy 351.458027 -398.046245) (xy 351.398306 -398.063969)
			(xy 351.336809 -398.073912) (xy 351.274546 -398.075908) (xy 351.212539 -398.069926) (xy 351.151805 -398.056064)
			(xy 351.093343 -398.03455) (xy 351.038112 -398.005736) (xy 350.98702 -397.970096) (xy 350.940904 -397.928215)
			(xy 350.900522 -397.88078) (xy 350.866538 -397.828571) (xy 350.839509 -397.772445) (xy 350.81988 -397.713324)
			(xy 350.807971 -397.652177) (xy 350.80398 -397.59001) (xy 350.351852 -397.59001) (xy 350.351852 -398.890236)
			(xy 350.80398 -398.890236) (xy 350.807971 -398.828069) (xy 350.81988 -398.766922) (xy 350.839509 -398.707801)
			(xy 350.866538 -398.651675) (xy 350.900522 -398.599466) (xy 350.940904 -398.552031) (xy 350.98702 -398.51015)
			(xy 351.038112 -398.47451) (xy 351.093343 -398.445696) (xy 351.151805 -398.424182) (xy 351.212539 -398.41032)
			(xy 351.274546 -398.404338) (xy 351.336809 -398.406334) (xy 351.398306 -398.416277) (xy 351.458027 -398.434001)
			(xy 351.481667 -398.444466) (xy 363.577884 -398.444466) (xy 363.581955 -398.388844) (xy 363.594081 -398.334407)
			(xy 363.614004 -398.282316) (xy 363.6413 -398.233681) (xy 363.675386 -398.189538) (xy 363.715535 -398.150829)
			(xy 363.760893 -398.118378) (xy 363.810493 -398.092877) (xy 363.863277 -398.07487) (xy 363.91812 -398.06474)
			(xy 363.973854 -398.062703) (xy 364.029291 -398.068803) (xy 364.083248 -398.082909) (xy 364.134577 -398.104721)
			(xy 364.182183 -398.133775) (xy 364.225051 -398.16945) (xy 364.262268 -398.210987) (xy 364.293041 -398.2575)
			(xy 364.316713 -398.307997) (xy 364.332781 -398.361404) (xy 364.340901 -398.41658) (xy 364.34141 -398.444466)
			(xy 364.340901 -398.472352) (xy 364.332781 -398.527528) (xy 364.316713 -398.580935) (xy 364.293041 -398.631432)
			(xy 364.262268 -398.677945) (xy 364.225051 -398.719482) (xy 364.182183 -398.755157) (xy 364.134577 -398.784211)
			(xy 364.083248 -398.806023) (xy 364.029291 -398.820129) (xy 363.973854 -398.826229) (xy 363.91812 -398.824192)
			(xy 363.863277 -398.814062) (xy 363.810493 -398.796055) (xy 363.760893 -398.770554) (xy 363.715535 -398.738103)
			(xy 363.675386 -398.699394) (xy 363.6413 -398.655251) (xy 363.614004 -398.606616) (xy 363.594081 -398.554525)
			(xy 363.581955 -398.500088) (xy 363.577884 -398.444466) (xy 351.481667 -398.444466) (xy 351.51499 -398.459218)
			(xy 351.568261 -398.491511) (xy 351.616966 -398.530351) (xy 351.660303 -398.575101) (xy 351.697563 -398.625025)
			(xy 351.728132 -398.679304) (xy 351.75151 -398.737047) (xy 351.767311 -398.797305) (xy 351.775277 -398.859088)
			(xy 351.775776 -398.890236) (xy 351.775277 -398.921384) (xy 351.767311 -398.983167) (xy 351.75151 -399.043425)
			(xy 351.728132 -399.101168) (xy 351.697563 -399.155447) (xy 351.660303 -399.205371) (xy 351.646206 -399.219928)
			(xy 357.060752 -399.219928) (xy 357.064823 -399.164306) (xy 357.076949 -399.109869) (xy 357.096872 -399.057778)
			(xy 357.124168 -399.009143) (xy 357.158254 -398.965) (xy 357.198403 -398.926291) (xy 357.243761 -398.89384)
			(xy 357.293361 -398.868339) (xy 357.346145 -398.850332) (xy 357.400988 -398.840202) (xy 357.456722 -398.838165)
			(xy 357.512159 -398.844265) (xy 357.566116 -398.858371) (xy 357.617445 -398.880183) (xy 357.665051 -398.909237)
			(xy 357.707919 -398.944912) (xy 357.745136 -398.986449) (xy 357.775909 -399.032962) (xy 357.799581 -399.083459)
			(xy 357.815649 -399.136866) (xy 357.823769 -399.192042) (xy 357.824278 -399.219928) (xy 357.823769 -399.247814)
			(xy 357.815649 -399.30299) (xy 357.799581 -399.356397) (xy 357.775909 -399.406894) (xy 357.745136 -399.453407)
			(xy 357.707919 -399.494944) (xy 357.665051 -399.530619) (xy 357.617445 -399.559673) (xy 357.566116 -399.581485)
			(xy 357.512159 -399.595591) (xy 357.456722 -399.601691) (xy 357.400988 -399.599654) (xy 357.346145 -399.589524)
			(xy 357.293361 -399.571517) (xy 357.243761 -399.546016) (xy 357.198403 -399.513565) (xy 357.158254 -399.474856)
			(xy 357.124168 -399.430713) (xy 357.096872 -399.382078) (xy 357.076949 -399.329987) (xy 357.064823 -399.27555)
			(xy 357.060752 -399.219928) (xy 351.646206 -399.219928) (xy 351.616966 -399.250121) (xy 351.568261 -399.288961)
			(xy 351.51499 -399.321254) (xy 351.458027 -399.346471) (xy 351.398306 -399.364195) (xy 351.336809 -399.374138)
			(xy 351.274546 -399.376134) (xy 351.212539 -399.370152) (xy 351.151805 -399.35629) (xy 351.093343 -399.334776)
			(xy 351.038112 -399.305962) (xy 350.98702 -399.270322) (xy 350.940904 -399.228441) (xy 350.900522 -399.181006)
			(xy 350.866538 -399.128797) (xy 350.839509 -399.072671) (xy 350.81988 -399.01355) (xy 350.807971 -398.952403)
			(xy 350.80398 -398.890236) (xy 350.351852 -398.890236) (xy 350.351852 -401.49018) (xy 350.80398 -401.49018)
			(xy 350.807971 -401.428013) (xy 350.81988 -401.366866) (xy 350.839509 -401.307745) (xy 350.866538 -401.251619)
			(xy 350.900522 -401.19941) (xy 350.940904 -401.151975) (xy 350.98702 -401.110094) (xy 351.038112 -401.074454)
			(xy 351.093343 -401.04564) (xy 351.151805 -401.024126) (xy 351.212539 -401.010264) (xy 351.274546 -401.004282)
			(xy 351.336809 -401.006278) (xy 351.398306 -401.016221) (xy 351.458027 -401.033945) (xy 351.51499 -401.059162)
			(xy 351.568261 -401.091455) (xy 351.616966 -401.130295) (xy 351.660303 -401.175045) (xy 351.697563 -401.224969)
			(xy 351.728132 -401.279248) (xy 351.75151 -401.336991) (xy 351.767311 -401.397249) (xy 351.775277 -401.459032)
			(xy 351.775776 -401.49018) (xy 351.775277 -401.521328) (xy 351.767311 -401.583111) (xy 351.75151 -401.643369)
			(xy 351.728132 -401.701112) (xy 351.697563 -401.755391) (xy 351.660303 -401.805315) (xy 351.616966 -401.850065)
			(xy 351.568261 -401.888905) (xy 351.51499 -401.921198) (xy 351.458027 -401.946415) (xy 351.398306 -401.964139)
			(xy 351.336809 -401.974082) (xy 351.274546 -401.976078) (xy 351.212539 -401.970096) (xy 351.151805 -401.956234)
			(xy 351.093343 -401.93472) (xy 351.038112 -401.905906) (xy 350.98702 -401.870266) (xy 350.940904 -401.828385)
			(xy 350.900522 -401.78095) (xy 350.866538 -401.728741) (xy 350.839509 -401.672615) (xy 350.81988 -401.613494)
			(xy 350.807971 -401.552347) (xy 350.80398 -401.49018) (xy 350.351852 -401.49018) (xy 350.351852 -402.790152)
			(xy 350.80398 -402.790152) (xy 350.807971 -402.727985) (xy 350.81988 -402.666838) (xy 350.839509 -402.607717)
			(xy 350.866538 -402.551591) (xy 350.900522 -402.499382) (xy 350.940904 -402.451947) (xy 350.98702 -402.410066)
			(xy 351.038112 -402.374426) (xy 351.093343 -402.345612) (xy 351.151805 -402.324098) (xy 351.212539 -402.310236)
			(xy 351.274546 -402.304254) (xy 351.336809 -402.30625) (xy 351.398306 -402.316193) (xy 351.458027 -402.333917)
			(xy 351.51499 -402.359134) (xy 351.568261 -402.391427) (xy 351.616966 -402.430267) (xy 351.660303 -402.475017)
			(xy 351.697563 -402.524941) (xy 351.728132 -402.57922) (xy 351.75151 -402.636963) (xy 351.767311 -402.697221)
			(xy 351.775277 -402.759004) (xy 351.775776 -402.790152) (xy 351.775277 -402.8213) (xy 351.767311 -402.883083)
			(xy 351.75151 -402.943341) (xy 351.728132 -403.001084) (xy 351.697563 -403.055363) (xy 351.660303 -403.105287)
			(xy 351.616966 -403.150037) (xy 351.568261 -403.188877) (xy 351.51499 -403.22117) (xy 351.458027 -403.246387)
			(xy 351.398306 -403.264111) (xy 351.336809 -403.274054) (xy 351.274546 -403.27605) (xy 351.212539 -403.270068)
			(xy 351.151805 -403.256206) (xy 351.093343 -403.234692) (xy 351.038112 -403.205878) (xy 350.98702 -403.170238)
			(xy 350.940904 -403.128357) (xy 350.900522 -403.080922) (xy 350.866538 -403.028713) (xy 350.839509 -402.972587)
			(xy 350.81988 -402.913466) (xy 350.807971 -402.852319) (xy 350.80398 -402.790152) (xy 350.351852 -402.790152)
			(xy 350.351852 -405.390096) (xy 350.80398 -405.390096) (xy 350.807971 -405.327929) (xy 350.81988 -405.266782)
			(xy 350.839509 -405.207661) (xy 350.866538 -405.151535) (xy 350.900522 -405.099326) (xy 350.940904 -405.051891)
			(xy 350.98702 -405.01001) (xy 351.038112 -404.97437) (xy 351.093343 -404.945556) (xy 351.151805 -404.924042)
			(xy 351.212539 -404.91018) (xy 351.274546 -404.904198) (xy 351.336809 -404.906194) (xy 351.398306 -404.916137)
			(xy 351.458027 -404.933861) (xy 351.51499 -404.959078) (xy 351.568261 -404.991371) (xy 351.616966 -405.030211)
			(xy 351.660303 -405.074961) (xy 351.697563 -405.124885) (xy 351.728132 -405.179164) (xy 351.75151 -405.236907)
			(xy 351.767311 -405.297165) (xy 351.775277 -405.358948) (xy 351.775776 -405.390096) (xy 351.775277 -405.421244)
			(xy 351.767311 -405.483027) (xy 351.75151 -405.543285) (xy 351.728132 -405.601028) (xy 351.697563 -405.655307)
			(xy 351.660303 -405.705231) (xy 351.616966 -405.749981) (xy 351.568261 -405.788821) (xy 351.51499 -405.821114)
			(xy 351.458027 -405.846331) (xy 351.398306 -405.864055) (xy 351.336809 -405.873998) (xy 351.274546 -405.875994)
			(xy 351.212539 -405.870012) (xy 351.151805 -405.85615) (xy 351.093343 -405.834636) (xy 351.038112 -405.805822)
			(xy 350.98702 -405.770182) (xy 350.940904 -405.728301) (xy 350.900522 -405.680866) (xy 350.866538 -405.628657)
			(xy 350.839509 -405.572531) (xy 350.81988 -405.51341) (xy 350.807971 -405.452263) (xy 350.80398 -405.390096)
			(xy 350.351852 -405.390096) (xy 350.351852 -406.690068) (xy 350.80398 -406.690068) (xy 350.807971 -406.627901)
			(xy 350.81988 -406.566754) (xy 350.839509 -406.507633) (xy 350.866538 -406.451507) (xy 350.900522 -406.399298)
			(xy 350.940904 -406.351863) (xy 350.98702 -406.309982) (xy 351.038112 -406.274342) (xy 351.093343 -406.245528)
			(xy 351.151805 -406.224014) (xy 351.212539 -406.210152) (xy 351.274546 -406.20417) (xy 351.336809 -406.206166)
			(xy 351.398306 -406.216109) (xy 351.458027 -406.233833) (xy 351.51499 -406.25905) (xy 351.568261 -406.291343)
			(xy 351.616966 -406.330183) (xy 351.660303 -406.374933) (xy 351.697563 -406.424857) (xy 351.728132 -406.479136)
			(xy 351.75151 -406.536879) (xy 351.767311 -406.597137) (xy 351.775277 -406.65892) (xy 351.775776 -406.690068)
			(xy 351.775277 -406.721216) (xy 351.767311 -406.782999) (xy 351.75151 -406.843257) (xy 351.728132 -406.901)
			(xy 351.697563 -406.955279) (xy 351.660303 -407.005203) (xy 351.616966 -407.049953) (xy 351.568261 -407.088793)
			(xy 351.51499 -407.121086) (xy 351.458027 -407.146303) (xy 351.398306 -407.164027) (xy 351.336809 -407.17397)
			(xy 351.274546 -407.175966) (xy 351.212539 -407.169984) (xy 351.151805 -407.156122) (xy 351.093343 -407.134608)
			(xy 351.038112 -407.105794) (xy 350.98702 -407.070154) (xy 350.940904 -407.028273) (xy 350.900522 -406.980838)
			(xy 350.866538 -406.928629) (xy 350.839509 -406.872503) (xy 350.81988 -406.813382) (xy 350.807971 -406.752235)
			(xy 350.80398 -406.690068) (xy 350.351852 -406.690068) (xy 350.351852 -409.290012) (xy 350.80398 -409.290012)
			(xy 350.807971 -409.227845) (xy 350.81988 -409.166698) (xy 350.839509 -409.107577) (xy 350.866538 -409.051451)
			(xy 350.900522 -408.999242) (xy 350.940904 -408.951807) (xy 350.98702 -408.909926) (xy 351.038112 -408.874286)
			(xy 351.093343 -408.845472) (xy 351.151805 -408.823958) (xy 351.212539 -408.810096) (xy 351.274546 -408.804114)
			(xy 351.336809 -408.80611) (xy 351.398306 -408.816053) (xy 351.458027 -408.833777) (xy 351.51499 -408.858994)
			(xy 351.568261 -408.891287) (xy 351.616966 -408.930127) (xy 351.660303 -408.974877) (xy 351.697563 -409.024801)
			(xy 351.728132 -409.07908) (xy 351.75151 -409.136823) (xy 351.767311 -409.197081) (xy 351.775277 -409.258864)
			(xy 351.775776 -409.290012) (xy 351.775277 -409.32116) (xy 351.767311 -409.382943) (xy 351.75151 -409.443201)
			(xy 351.728132 -409.500944) (xy 351.697563 -409.555223) (xy 351.660303 -409.605147) (xy 351.616966 -409.649897)
			(xy 351.568261 -409.688737) (xy 351.51499 -409.72103) (xy 351.458027 -409.746247) (xy 351.398306 -409.763971)
			(xy 351.336809 -409.773914) (xy 351.274546 -409.77591) (xy 351.212539 -409.769928) (xy 351.151805 -409.756066)
			(xy 351.093343 -409.734552) (xy 351.038112 -409.705738) (xy 350.98702 -409.670098) (xy 350.940904 -409.628217)
			(xy 350.900522 -409.580782) (xy 350.866538 -409.528573) (xy 350.839509 -409.472447) (xy 350.81988 -409.413326)
			(xy 350.807971 -409.352179) (xy 350.80398 -409.290012) (xy 350.351852 -409.290012) (xy 350.351852 -410.589984)
			(xy 350.80398 -410.589984) (xy 350.807971 -410.527817) (xy 350.81988 -410.46667) (xy 350.839509 -410.407549)
			(xy 350.866538 -410.351423) (xy 350.900522 -410.299214) (xy 350.940904 -410.251779) (xy 350.98702 -410.209898)
			(xy 351.038112 -410.174258) (xy 351.093343 -410.145444) (xy 351.151805 -410.12393) (xy 351.212539 -410.110068)
			(xy 351.274546 -410.104086) (xy 351.336809 -410.106082) (xy 351.398306 -410.116025) (xy 351.458027 -410.133749)
			(xy 351.51499 -410.158966) (xy 351.568261 -410.191259) (xy 351.616966 -410.230099) (xy 351.660303 -410.274849)
			(xy 351.697563 -410.324773) (xy 351.728132 -410.379052) (xy 351.75151 -410.436795) (xy 351.767311 -410.497053)
			(xy 351.775277 -410.558836) (xy 351.775776 -410.589984) (xy 351.775277 -410.621132) (xy 351.767311 -410.682915)
			(xy 351.75151 -410.743173) (xy 351.728132 -410.800916) (xy 351.697563 -410.855195) (xy 351.660303 -410.905119)
			(xy 351.616966 -410.949869) (xy 351.568261 -410.988709) (xy 351.51499 -411.021002) (xy 351.458027 -411.046219)
			(xy 351.398306 -411.063943) (xy 351.336809 -411.073886) (xy 351.274546 -411.075882) (xy 351.212539 -411.0699)
			(xy 351.151805 -411.056038) (xy 351.093343 -411.034524) (xy 351.038112 -411.00571) (xy 350.98702 -410.97007)
			(xy 350.940904 -410.928189) (xy 350.900522 -410.880754) (xy 350.866538 -410.828545) (xy 350.839509 -410.772419)
			(xy 350.81988 -410.713298) (xy 350.807971 -410.652151) (xy 350.80398 -410.589984) (xy 350.351852 -410.589984)
			(xy 350.351852 -412.25343) (xy 350.352614 -412.261812) (xy 350.354131 -412.269416) (xy 350.361121 -412.283246)
			(xy 350.36633 -412.28899) (xy 354.676964 -416.599624) (xy 354.682716 -416.604817) (xy 354.69655 -416.611785)
			(xy 354.704142 -416.61334) (xy 354.712524 -416.614102)
		)
		(stroke
			(width 0)
			(type solid)
		)
		(fill yes)
		(layer "In13.Cu")
		(net "GND")
	)
	(gr_poly
		(pts
			(xy 131.79044 -328.671428) (xy 131.798043 -328.669909) (xy 131.811871 -328.662917) (xy 131.817618 -328.657712)
			(xy 135.545068 -324.930262) (xy 135.552467 -324.923419) (xy 135.571066 -324.9157) (xy 135.581136 -324.915276)
			(xy 142.838932 -324.915276) (xy 142.853095 -324.914821) (xy 142.880335 -324.907057) (xy 142.904394 -324.892107)
			(xy 142.92342 -324.871123) (xy 142.935948 -324.845719) (xy 142.941014 -324.817851) (xy 142.938229 -324.789663)
			(xy 142.927806 -324.763325) (xy 142.910548 -324.740864) (xy 142.899384 -324.732142) (xy 142.822104 -324.674049)
			(xy 142.671758 -324.552462) (xy 142.526458 -324.424888) (xy 142.38644 -324.291538) (xy 142.251935 -324.15263)
			(xy 142.123162 -324.008391) (xy 142.000333 -323.859058) (xy 141.883649 -323.704876) (xy 141.773302 -323.546098)
			(xy 141.669472 -323.382983) (xy 141.572329 -323.215799) (xy 141.482033 -323.04482) (xy 141.398732 -322.870326)
			(xy 141.322561 -322.692603) (xy 141.253647 -322.511943) (xy 141.192102 -322.328642) (xy 141.138027 -322.142999)
			(xy 141.09151 -321.955321) (xy 141.052627 -321.765913) (xy 141.021444 -321.575086) (xy 140.99801 -321.383154)
			(xy 140.982363 -321.19043) (xy 140.974531 -320.997231) (xy 140.974064 -320.900552) (xy 140.974064 -320.900044)
			(xy 140.974561 -320.802616) (xy 140.982509 -320.607923) (xy 140.998391 -320.413717) (xy 141.022182 -320.220319)
			(xy 141.053841 -320.028053) (xy 141.093316 -319.837238) (xy 141.140542 -319.648193) (xy 141.195439 -319.46123)
			(xy 141.257916 -319.276663) (xy 141.32787 -319.094798) (xy 141.405183 -318.915937) (xy 141.489728 -318.740378)
			(xy 141.581363 -318.568414) (xy 141.679935 -318.400331) (xy 141.785282 -318.236409) (xy 141.897227 -318.076919)
			(xy 142.015585 -317.922129) (xy 142.140157 -317.772295) (xy 142.270737 -317.627667) (xy 142.407108 -317.488485)
			(xy 142.549043 -317.354982) (xy 142.696305 -317.227379) (xy 142.848648 -317.105888) (xy 143.005821 -316.990713)
			(xy 143.167561 -316.882045) (xy 143.333598 -316.780064) (xy 143.503657 -316.68494) (xy 143.677454 -316.596832)
			(xy 143.854701 -316.515886) (xy 144.035102 -316.442237) (xy 144.218356 -316.376008) (xy 144.40416 -316.317309)
			(xy 144.592203 -316.266237) (xy 144.782172 -316.222878) (xy 144.973753 -316.187303) (xy 145.166625 -316.159572)
			(xy 145.360467 -316.139731) (xy 145.554957 -316.127814) (xy 145.749772 -316.123839) (xy 145.944587 -316.127814)
			(xy 146.139077 -316.139731) (xy 146.332919 -316.159572) (xy 146.525791 -316.187303) (xy 146.717372 -316.222878)
			(xy 146.907341 -316.266237) (xy 147.095384 -316.317309) (xy 147.281188 -316.376008) (xy 147.464442 -316.442237)
			(xy 147.644843 -316.515886) (xy 147.82209 -316.596832) (xy 147.995887 -316.68494) (xy 148.165946 -316.780064)
			(xy 148.197538 -316.799468) (xy 151.693638 -316.799468) (xy 151.697598 -316.750414) (xy 151.709375 -316.70263)
			(xy 151.728666 -316.657354) (xy 151.754969 -316.615758) (xy 151.787604 -316.578921) (xy 151.825725 -316.547796)
			(xy 151.868346 -316.523189) (xy 151.914362 -316.505737) (xy 151.962581 -316.495893) (xy 152.011756 -316.493912)
			(xy 152.060611 -316.499844) (xy 152.107882 -316.513536) (xy 152.152344 -316.534634) (xy 152.192847 -316.56259)
			(xy 152.22834 -316.596682) (xy 152.257905 -316.636026) (xy 152.280776 -316.679603) (xy 152.29636 -316.726284)
			(xy 152.304255 -316.774861) (xy 152.30475 -316.799468) (xy 152.304255 -316.824075) (xy 152.304035 -316.82543)
			(xy 152.623262 -316.82543) (xy 152.623262 -316.774014) (xy 152.631305 -316.723232) (xy 152.647193 -316.674333)
			(xy 152.670536 -316.628521) (xy 152.700757 -316.586925) (xy 152.737113 -316.550569) (xy 152.778709 -316.520348)
			(xy 152.824521 -316.497005) (xy 152.87342 -316.481117) (xy 152.924202 -316.473074) (xy 152.975618 -316.473074)
			(xy 153.0264 -316.481117) (xy 153.075299 -316.497005) (xy 153.121111 -316.520348) (xy 153.162707 -316.550569)
			(xy 153.199063 -316.586925) (xy 153.229284 -316.628521) (xy 153.252627 -316.674333) (xy 153.268515 -316.723232)
			(xy 153.276558 -316.774014) (xy 153.277062 -316.799722) (xy 153.276558 -316.82543) (xy 153.573222 -316.82543)
			(xy 153.573222 -316.774014) (xy 153.581265 -316.723232) (xy 153.597153 -316.674333) (xy 153.620496 -316.628521)
			(xy 153.650717 -316.586925) (xy 153.687073 -316.550569) (xy 153.728669 -316.520348) (xy 153.774481 -316.497005)
			(xy 153.82338 -316.481117) (xy 153.874162 -316.473074) (xy 153.925578 -316.473074) (xy 153.97636 -316.481117)
			(xy 154.025259 -316.497005) (xy 154.071071 -316.520348) (xy 154.112667 -316.550569) (xy 154.149023 -316.586925)
			(xy 154.179244 -316.628521) (xy 154.202587 -316.674333) (xy 154.218475 -316.723232) (xy 154.226518 -316.774014)
			(xy 154.227022 -316.799722) (xy 154.54428 -316.799722) (xy 154.54824 -316.750668) (xy 154.560017 -316.702884)
			(xy 154.579308 -316.657608) (xy 154.605611 -316.616012) (xy 154.638246 -316.579175) (xy 154.676367 -316.54805)
			(xy 154.718988 -316.523443) (xy 154.765004 -316.505991) (xy 154.813223 -316.496147) (xy 154.862398 -316.494166)
			(xy 154.911253 -316.500098) (xy 154.958524 -316.51379) (xy 155.002986 -316.534888) (xy 155.043489 -316.562844)
			(xy 155.078982 -316.596936) (xy 155.108547 -316.63628) (xy 155.131418 -316.679857) (xy 155.147002 -316.726538)
			(xy 155.154897 -316.775115) (xy 155.155392 -316.799722) (xy 155.154897 -316.824329) (xy 155.154718 -316.82543)
			(xy 155.473396 -316.82543) (xy 155.473396 -316.774014) (xy 155.481439 -316.723232) (xy 155.497327 -316.674333)
			(xy 155.52067 -316.628521) (xy 155.550891 -316.586925) (xy 155.587247 -316.550569) (xy 155.628843 -316.520348)
			(xy 155.674655 -316.497005) (xy 155.723554 -316.481117) (xy 155.774336 -316.473074) (xy 155.825752 -316.473074)
			(xy 155.876534 -316.481117) (xy 155.925433 -316.497005) (xy 155.971245 -316.520348) (xy 156.012841 -316.550569)
			(xy 156.049197 -316.586925) (xy 156.079418 -316.628521) (xy 156.102761 -316.674333) (xy 156.118649 -316.723232)
			(xy 156.126692 -316.774014) (xy 156.127196 -316.799722) (xy 156.126692 -316.82543) (xy 156.118649 -316.876212)
			(xy 156.102761 -316.925111) (xy 156.079418 -316.970923) (xy 156.049197 -317.012519) (xy 156.012841 -317.048875)
			(xy 155.971245 -317.079096) (xy 155.925433 -317.102439) (xy 155.876534 -317.118327) (xy 155.825752 -317.12637)
			(xy 155.774336 -317.12637) (xy 155.723554 -317.118327) (xy 155.674655 -317.102439) (xy 155.628843 -317.079096)
			(xy 155.587247 -317.048875) (xy 155.550891 -317.012519) (xy 155.52067 -316.970923) (xy 155.497327 -316.925111)
			(xy 155.481439 -316.876212) (xy 155.473396 -316.82543) (xy 155.154718 -316.82543) (xy 155.147002 -316.872906)
			(xy 155.131418 -316.919587) (xy 155.108547 -316.963164) (xy 155.078982 -317.002508) (xy 155.043489 -317.0366)
			(xy 155.002986 -317.064556) (xy 154.958524 -317.085654) (xy 154.911253 -317.099346) (xy 154.862398 -317.105278)
			(xy 154.813223 -317.103297) (xy 154.765004 -317.093453) (xy 154.718988 -317.076001) (xy 154.676367 -317.051394)
			(xy 154.638246 -317.020269) (xy 154.605611 -316.983432) (xy 154.579308 -316.941836) (xy 154.560017 -316.89656)
			(xy 154.54824 -316.848776) (xy 154.54428 -316.799722) (xy 154.227022 -316.799722) (xy 154.226518 -316.82543)
			(xy 154.218475 -316.876212) (xy 154.202587 -316.925111) (xy 154.179244 -316.970923) (xy 154.149023 -317.012519)
			(xy 154.112667 -317.048875) (xy 154.071071 -317.079096) (xy 154.025259 -317.102439) (xy 153.97636 -317.118327)
			(xy 153.925578 -317.12637) (xy 153.874162 -317.12637) (xy 153.82338 -317.118327) (xy 153.774481 -317.102439)
			(xy 153.728669 -317.079096) (xy 153.687073 -317.048875) (xy 153.650717 -317.012519) (xy 153.620496 -316.970923)
			(xy 153.597153 -316.925111) (xy 153.581265 -316.876212) (xy 153.573222 -316.82543) (xy 153.276558 -316.82543)
			(xy 153.268515 -316.876212) (xy 153.252627 -316.925111) (xy 153.229284 -316.970923) (xy 153.199063 -317.012519)
			(xy 153.162707 -317.048875) (xy 153.121111 -317.079096) (xy 153.075299 -317.102439) (xy 153.0264 -317.118327)
			(xy 152.975618 -317.12637) (xy 152.924202 -317.12637) (xy 152.87342 -317.118327) (xy 152.824521 -317.102439)
			(xy 152.778709 -317.079096) (xy 152.737113 -317.048875) (xy 152.700757 -317.012519) (xy 152.670536 -316.970923)
			(xy 152.647193 -316.925111) (xy 152.631305 -316.876212) (xy 152.623262 -316.82543) (xy 152.304035 -316.82543)
			(xy 152.29636 -316.872652) (xy 152.280776 -316.919333) (xy 152.257905 -316.96291) (xy 152.22834 -317.002254)
			(xy 152.192847 -317.036346) (xy 152.152344 -317.064302) (xy 152.107882 -317.0854) (xy 152.060611 -317.099092)
			(xy 152.011756 -317.105024) (xy 151.962581 -317.103043) (xy 151.914362 -317.093199) (xy 151.868346 -317.075747)
			(xy 151.825725 -317.05114) (xy 151.787604 -317.020015) (xy 151.754969 -316.983178) (xy 151.728666 -316.941582)
			(xy 151.709375 -316.896306) (xy 151.697598 -316.848522) (xy 151.693638 -316.799468) (xy 148.197538 -316.799468)
			(xy 148.331983 -316.882045) (xy 148.493723 -316.990713) (xy 148.650896 -317.105888) (xy 148.803239 -317.227379)
			(xy 148.950501 -317.354982) (xy 149.092436 -317.488485) (xy 149.228807 -317.627667) (xy 149.3392 -317.749936)
			(xy 152.644106 -317.749936) (xy 152.648066 -317.700882) (xy 152.659843 -317.653098) (xy 152.679134 -317.607822)
			(xy 152.705437 -317.566226) (xy 152.738072 -317.529389) (xy 152.776193 -317.498264) (xy 152.818814 -317.473657)
			(xy 152.86483 -317.456205) (xy 152.913049 -317.446361) (xy 152.962224 -317.44438) (xy 153.011079 -317.450312)
			(xy 153.05835 -317.464004) (xy 153.102812 -317.485102) (xy 153.143315 -317.513058) (xy 153.178808 -317.54715)
			(xy 153.208373 -317.586494) (xy 153.231244 -317.630071) (xy 153.246828 -317.676752) (xy 153.254723 -317.725329)
			(xy 153.255218 -317.749936) (xy 153.594066 -317.749936) (xy 153.598026 -317.700882) (xy 153.609803 -317.653098)
			(xy 153.629094 -317.607822) (xy 153.655397 -317.566226) (xy 153.688032 -317.529389) (xy 153.726153 -317.498264)
			(xy 153.768774 -317.473657) (xy 153.81479 -317.456205) (xy 153.863009 -317.446361) (xy 153.912184 -317.44438)
			(xy 153.961039 -317.450312) (xy 154.00831 -317.464004) (xy 154.052772 -317.485102) (xy 154.093275 -317.513058)
			(xy 154.128768 -317.54715) (xy 154.158333 -317.586494) (xy 154.181204 -317.630071) (xy 154.196788 -317.676752)
			(xy 154.204683 -317.725329) (xy 154.205178 -317.749936) (xy 154.204683 -317.774543) (xy 154.204504 -317.775644)
			(xy 154.523436 -317.775644) (xy 154.523436 -317.724228) (xy 154.531479 -317.673446) (xy 154.547367 -317.624547)
			(xy 154.57071 -317.578735) (xy 154.600931 -317.537139) (xy 154.637287 -317.500783) (xy 154.678883 -317.470562)
			(xy 154.724695 -317.447219) (xy 154.773594 -317.431331) (xy 154.824376 -317.423288) (xy 154.875792 -317.423288)
			(xy 154.926574 -317.431331) (xy 154.975473 -317.447219) (xy 155.021285 -317.470562) (xy 155.062881 -317.500783)
			(xy 155.099237 -317.537139) (xy 155.129458 -317.578735) (xy 155.152801 -317.624547) (xy 155.168689 -317.673446)
			(xy 155.176732 -317.724228) (xy 155.177236 -317.749936) (xy 155.49424 -317.749936) (xy 155.4982 -317.700882)
			(xy 155.509977 -317.653098) (xy 155.529268 -317.607822) (xy 155.555571 -317.566226) (xy 155.588206 -317.529389)
			(xy 155.626327 -317.498264) (xy 155.668948 -317.473657) (xy 155.714964 -317.456205) (xy 155.763183 -317.446361)
			(xy 155.812358 -317.44438) (xy 155.861213 -317.450312) (xy 155.908484 -317.464004) (xy 155.952946 -317.485102)
			(xy 155.993449 -317.513058) (xy 156.028942 -317.54715) (xy 156.058507 -317.586494) (xy 156.081378 -317.630071)
			(xy 156.096962 -317.676752) (xy 156.104857 -317.725329) (xy 156.105352 -317.749936) (xy 156.104857 -317.774543)
			(xy 156.096962 -317.82312) (xy 156.081378 -317.869801) (xy 156.058507 -317.913378) (xy 156.028942 -317.952722)
			(xy 155.993449 -317.986814) (xy 155.952946 -318.01477) (xy 155.908484 -318.035868) (xy 155.861213 -318.04956)
			(xy 155.812358 -318.055492) (xy 155.763183 -318.053511) (xy 155.714964 -318.043667) (xy 155.668948 -318.026215)
			(xy 155.626327 -318.001608) (xy 155.588206 -317.970483) (xy 155.555571 -317.933646) (xy 155.529268 -317.89205)
			(xy 155.509977 -317.846774) (xy 155.4982 -317.79899) (xy 155.49424 -317.749936) (xy 155.177236 -317.749936)
			(xy 155.176732 -317.775644) (xy 155.168689 -317.826426) (xy 155.152801 -317.875325) (xy 155.129458 -317.921137)
			(xy 155.099237 -317.962733) (xy 155.062881 -317.999089) (xy 155.021285 -318.02931) (xy 154.975473 -318.052653)
			(xy 154.926574 -318.068541) (xy 154.875792 -318.076584) (xy 154.824376 -318.076584) (xy 154.773594 -318.068541)
			(xy 154.724695 -318.052653) (xy 154.678883 -318.02931) (xy 154.637287 -317.999089) (xy 154.600931 -317.962733)
			(xy 154.57071 -317.921137) (xy 154.547367 -317.875325) (xy 154.531479 -317.826426) (xy 154.523436 -317.775644)
			(xy 154.204504 -317.775644) (xy 154.196788 -317.82312) (xy 154.181204 -317.869801) (xy 154.158333 -317.913378)
			(xy 154.128768 -317.952722) (xy 154.093275 -317.986814) (xy 154.052772 -318.01477) (xy 154.00831 -318.035868)
			(xy 153.961039 -318.04956) (xy 153.912184 -318.055492) (xy 153.863009 -318.053511) (xy 153.81479 -318.043667)
			(xy 153.768774 -318.026215) (xy 153.726153 -318.001608) (xy 153.688032 -317.970483) (xy 153.655397 -317.933646)
			(xy 153.629094 -317.89205) (xy 153.609803 -317.846774) (xy 153.598026 -317.79899) (xy 153.594066 -317.749936)
			(xy 153.255218 -317.749936) (xy 153.254723 -317.774543) (xy 153.246828 -317.82312) (xy 153.231244 -317.869801)
			(xy 153.208373 -317.913378) (xy 153.178808 -317.952722) (xy 153.143315 -317.986814) (xy 153.102812 -318.01477)
			(xy 153.05835 -318.035868) (xy 153.011079 -318.04956) (xy 152.962224 -318.055492) (xy 152.913049 -318.053511)
			(xy 152.86483 -318.043667) (xy 152.818814 -318.026215) (xy 152.776193 -318.001608) (xy 152.738072 -317.970483)
			(xy 152.705437 -317.933646) (xy 152.679134 -317.89205) (xy 152.659843 -317.846774) (xy 152.648066 -317.79899)
			(xy 152.644106 -317.749936) (xy 149.3392 -317.749936) (xy 149.359387 -317.772295) (xy 149.483959 -317.922129)
			(xy 149.602317 -318.076919) (xy 149.714262 -318.236409) (xy 149.819609 -318.400331) (xy 149.918181 -318.568414)
			(xy 149.988244 -318.699896) (xy 153.594066 -318.699896) (xy 153.598026 -318.650842) (xy 153.609803 -318.603058)
			(xy 153.629094 -318.557782) (xy 153.655397 -318.516186) (xy 153.688032 -318.479349) (xy 153.726153 -318.448224)
			(xy 153.768774 -318.423617) (xy 153.81479 -318.406165) (xy 153.863009 -318.396321) (xy 153.912184 -318.39434)
			(xy 153.961039 -318.400272) (xy 154.00831 -318.413964) (xy 154.052772 -318.435062) (xy 154.093275 -318.463018)
			(xy 154.128768 -318.49711) (xy 154.158333 -318.536454) (xy 154.181204 -318.580031) (xy 154.196788 -318.626712)
			(xy 154.204683 -318.675289) (xy 154.205178 -318.699896) (xy 154.204683 -318.724503) (xy 154.204504 -318.725604)
			(xy 154.523436 -318.725604) (xy 154.523436 -318.674188) (xy 154.531479 -318.623406) (xy 154.547367 -318.574507)
			(xy 154.57071 -318.528695) (xy 154.600931 -318.487099) (xy 154.637287 -318.450743) (xy 154.678883 -318.420522)
			(xy 154.724695 -318.397179) (xy 154.773594 -318.381291) (xy 154.824376 -318.373248) (xy 154.875792 -318.373248)
			(xy 154.926574 -318.381291) (xy 154.975473 -318.397179) (xy 155.021285 -318.420522) (xy 155.062881 -318.450743)
			(xy 155.099237 -318.487099) (xy 155.129458 -318.528695) (xy 155.152801 -318.574507) (xy 155.168689 -318.623406)
			(xy 155.176732 -318.674188) (xy 155.177236 -318.699896) (xy 155.49424 -318.699896) (xy 155.4982 -318.650842)
			(xy 155.509977 -318.603058) (xy 155.529268 -318.557782) (xy 155.555571 -318.516186) (xy 155.588206 -318.479349)
			(xy 155.626327 -318.448224) (xy 155.668948 -318.423617) (xy 155.714964 -318.406165) (xy 155.763183 -318.396321)
			(xy 155.812358 -318.39434) (xy 155.861213 -318.400272) (xy 155.908484 -318.413964) (xy 155.952946 -318.435062)
			(xy 155.993449 -318.463018) (xy 156.028942 -318.49711) (xy 156.058507 -318.536454) (xy 156.081378 -318.580031)
			(xy 156.096962 -318.626712) (xy 156.104857 -318.675289) (xy 156.105352 -318.699896) (xy 156.104857 -318.724503)
			(xy 156.096962 -318.77308) (xy 156.081378 -318.819761) (xy 156.058507 -318.863338) (xy 156.028942 -318.902682)
			(xy 155.993449 -318.936774) (xy 155.952946 -318.96473) (xy 155.908484 -318.985828) (xy 155.861213 -318.99952)
			(xy 155.812358 -319.005452) (xy 155.763183 -319.003471) (xy 155.714964 -318.993627) (xy 155.668948 -318.976175)
			(xy 155.626327 -318.951568) (xy 155.588206 -318.920443) (xy 155.555571 -318.883606) (xy 155.529268 -318.84201)
			(xy 155.509977 -318.796734) (xy 155.4982 -318.74895) (xy 155.49424 -318.699896) (xy 155.177236 -318.699896)
			(xy 155.176732 -318.725604) (xy 155.168689 -318.776386) (xy 155.152801 -318.825285) (xy 155.129458 -318.871097)
			(xy 155.099237 -318.912693) (xy 155.062881 -318.949049) (xy 155.021285 -318.97927) (xy 154.975473 -319.002613)
			(xy 154.926574 -319.018501) (xy 154.875792 -319.026544) (xy 154.824376 -319.026544) (xy 154.773594 -319.018501)
			(xy 154.724695 -319.002613) (xy 154.678883 -318.97927) (xy 154.637287 -318.949049) (xy 154.600931 -318.912693)
			(xy 154.57071 -318.871097) (xy 154.547367 -318.825285) (xy 154.531479 -318.776386) (xy 154.523436 -318.725604)
			(xy 154.204504 -318.725604) (xy 154.196788 -318.77308) (xy 154.181204 -318.819761) (xy 154.158333 -318.863338)
			(xy 154.128768 -318.902682) (xy 154.093275 -318.936774) (xy 154.052772 -318.96473) (xy 154.00831 -318.985828)
			(xy 153.961039 -318.99952) (xy 153.912184 -319.005452) (xy 153.863009 -319.003471) (xy 153.81479 -318.993627)
			(xy 153.768774 -318.976175) (xy 153.726153 -318.951568) (xy 153.688032 -318.920443) (xy 153.655397 -318.883606)
			(xy 153.629094 -318.84201) (xy 153.609803 -318.796734) (xy 153.598026 -318.74895) (xy 153.594066 -318.699896)
			(xy 149.988244 -318.699896) (xy 150.009816 -318.740378) (xy 150.094361 -318.915937) (xy 150.171674 -319.094798)
			(xy 150.241628 -319.276663) (xy 150.304105 -319.46123) (xy 150.359002 -319.648193) (xy 150.359481 -319.65011)
			(xy 154.54428 -319.65011) (xy 154.54824 -319.601056) (xy 154.560017 -319.553272) (xy 154.579308 -319.507996)
			(xy 154.605611 -319.4664) (xy 154.638246 -319.429563) (xy 154.676367 -319.398438) (xy 154.718988 -319.373831)
			(xy 154.765004 -319.356379) (xy 154.813223 -319.346535) (xy 154.862398 -319.344554) (xy 154.911253 -319.350486)
			(xy 154.958524 -319.364178) (xy 155.002986 -319.385276) (xy 155.043489 -319.413232) (xy 155.078982 -319.447324)
			(xy 155.108547 -319.486668) (xy 155.131418 -319.530245) (xy 155.147002 -319.576926) (xy 155.154897 -319.625503)
			(xy 155.155392 -319.65011) (xy 155.154897 -319.674717) (xy 155.147002 -319.723294) (xy 155.131418 -319.769975)
			(xy 155.108547 -319.813552) (xy 155.078982 -319.852896) (xy 155.043489 -319.886988) (xy 155.002986 -319.914944)
			(xy 154.958524 -319.936042) (xy 154.911253 -319.949734) (xy 154.862398 -319.955666) (xy 154.813223 -319.953685)
			(xy 154.765004 -319.943841) (xy 154.718988 -319.926389) (xy 154.676367 -319.901782) (xy 154.638246 -319.870657)
			(xy 154.605611 -319.83382) (xy 154.579308 -319.792224) (xy 154.560017 -319.746948) (xy 154.54824 -319.699164)
			(xy 154.54428 -319.65011) (xy 150.359481 -319.65011) (xy 150.406228 -319.837238) (xy 150.445703 -320.028053)
			(xy 150.477362 -320.220319) (xy 150.501153 -320.413717) (xy 150.517035 -320.607923) (xy 150.524983 -320.802616)
			(xy 150.52548 -320.900044) (xy 150.52548 -320.900298) (xy 150.524966 -320.999415) (xy 150.516735 -321.197479)
			(xy 150.50029 -321.395031) (xy 150.475661 -321.59173) (xy 150.44289 -321.787237) (xy 150.402032 -321.981215)
			(xy 150.353159 -322.173331) (xy 150.296355 -322.363253) (xy 150.231718 -322.550654) (xy 150.159359 -322.73521)
			(xy 150.079402 -322.916605) (xy 149.991986 -323.094525) (xy 149.897261 -323.268663) (xy 149.795391 -323.43872)
			(xy 149.741382 -323.521832) (xy 149.737223 -323.528791) (xy 149.733086 -323.54446) (xy 149.733254 -323.552566)
			(xy 149.733508 -323.560694) (xy 149.73935 -323.575426) (xy 149.80666 -323.657214) (xy 149.812057 -323.663287)
			(xy 149.825781 -323.671968) (xy 149.833584 -323.674232) (xy 149.849586 -323.678296) (xy 149.86 -323.673978)
			(xy 149.865334 -323.671692) (xy 155.495498 -321.339464) (xy 155.500832 -321.337432) (xy 156.240226 -320.823082)
			(xy 156.247084 -320.817494) (xy 157.210252 -319.854326) (xy 157.215241 -319.848827) (xy 157.222091 -319.835662)
			(xy 157.223714 -319.828418) (xy 157.22473 -319.818766) (xy 157.22473 -319.527428) (xy 157.224376 -319.518409)
			(xy 157.218138 -319.501485) (xy 157.212538 -319.494408) (xy 157.206442 -319.487296) (xy 157.190694 -319.478406)
			(xy 157.184344 -319.477644) (xy 157.181042 -319.477136) (xy 157.174438 -319.47612) (xy 157.168596 -319.475104)
			(xy 157.15615 -319.472818) (xy 157.13202 -319.480184) (xy 157.063948 -319.54851) (xy 157.055808 -319.557752)
			(xy 157.04852 -319.581237) (xy 157.049978 -319.593468) (xy 157.049978 -319.593722) (xy 157.052463 -319.607687)
			(xy 157.055134 -319.635927) (xy 157.055312 -319.65011) (xy 157.054825 -319.674931) (xy 157.046793 -319.723919)
			(xy 157.03094 -319.770962) (xy 157.007686 -319.814821) (xy 156.977643 -319.85434) (xy 156.941602 -319.888477)
			(xy 156.900513 -319.916335) (xy 156.855458 -319.937178) (xy 156.807625 -319.950457) (xy 156.758274 -319.955823)
			(xy 156.708705 -319.953134) (xy 156.660223 -319.942461) (xy 156.614107 -319.924086) (xy 156.571572 -319.898492)
			(xy 156.533737 -319.866353) (xy 156.5016 -319.828517) (xy 156.476008 -319.78598) (xy 156.457635 -319.739863)
			(xy 156.446964 -319.691382) (xy 156.444277 -319.641812) (xy 156.449646 -319.592461) (xy 156.462927 -319.544629)
			(xy 156.483772 -319.499575) (xy 156.511631 -319.458487) (xy 156.545771 -319.422448) (xy 156.585291 -319.392406)
			(xy 156.629151 -319.369154) (xy 156.676195 -319.353304) (xy 156.725183 -319.345274) (xy 156.750004 -319.344802)
			(xy 156.764118 -319.344922) (xy 156.792232 -319.347462) (xy 156.806138 -319.349882) (xy 156.818584 -319.352168)
			(xy 156.842714 -319.344802) (xy 156.919676 -319.267586) (xy 156.927042 -319.243964) (xy 156.92628 -319.238884)
			(xy 156.921149 -319.212072) (xy 156.919362 -319.157517) (xy 156.922724 -319.130426) (xy 156.922724 -319.12941)
			(xy 156.923486 -319.123822) (xy 156.915612 -319.100962) (xy 156.839158 -319.027556) (xy 156.816298 -319.020444)
			(xy 156.80436 -319.022476) (xy 156.790874 -319.02462) (xy 156.763659 -319.026907) (xy 156.750004 -319.027048)
			(xy 156.724294 -319.02657) (xy 156.673508 -319.018527) (xy 156.624605 -319.002638) (xy 156.57879 -318.979294)
			(xy 156.537191 -318.949071) (xy 156.500831 -318.912713) (xy 156.470608 -318.871114) (xy 156.447264 -318.825299)
			(xy 156.431374 -318.776396) (xy 156.42333 -318.72561) (xy 156.42333 -318.67419) (xy 156.431374 -318.623404)
			(xy 156.447264 -318.574501) (xy 156.470608 -318.528686) (xy 156.500831 -318.487087) (xy 156.537191 -318.450729)
			(xy 156.57879 -318.420506) (xy 156.624605 -318.397162) (xy 156.673508 -318.381273) (xy 156.724294 -318.37323)
			(xy 156.750004 -318.372744) (xy 156.763658 -318.372898) (xy 156.790871 -318.37519) (xy 156.80436 -318.377316)
			(xy 156.816298 -318.379348) (xy 156.839158 -318.372236) (xy 156.915612 -318.29883) (xy 156.923486 -318.27597)
			(xy 156.922724 -318.270128) (xy 156.919827 -318.247804) (xy 156.919828 -318.20279) (xy 156.922724 -318.180466)
			(xy 156.922724 -318.17945) (xy 156.923486 -318.173862) (xy 156.915612 -318.151002) (xy 156.839158 -318.077596)
			(xy 156.816298 -318.070484) (xy 156.80436 -318.072516) (xy 156.790874 -318.07466) (xy 156.763659 -318.076947)
			(xy 156.750004 -318.077088) (xy 156.724291 -318.07661) (xy 156.673499 -318.068566) (xy 156.62459 -318.052675)
			(xy 156.578769 -318.029329) (xy 156.537165 -317.999102) (xy 156.500801 -317.962738) (xy 156.470573 -317.921134)
			(xy 156.447227 -317.875314) (xy 156.431335 -317.826405) (xy 156.42329 -317.775613) (xy 156.42329 -317.724187)
			(xy 156.431335 -317.673395) (xy 156.447227 -317.624486) (xy 156.470573 -317.578666) (xy 156.500801 -317.537062)
			(xy 156.537165 -317.500698) (xy 156.578769 -317.470471) (xy 156.62459 -317.447125) (xy 156.673499 -317.431234)
			(xy 156.724291 -317.42319) (xy 156.750004 -317.422784) (xy 156.783786 -317.424562) (xy 156.78404 -317.424562)
			(xy 156.795388 -317.425084) (xy 156.816746 -317.417432) (xy 156.825188 -317.40983) (xy 156.880814 -317.353696)
			(xy 156.888393 -317.345176) (xy 156.89591 -317.32368) (xy 156.895292 -317.312294) (xy 156.895292 -317.31204)
			(xy 156.894325 -317.302736) (xy 156.893311 -317.284056) (xy 156.89326 -317.274702) (xy 156.89326 -317.204598)
			(xy 156.892699 -317.193905) (xy 156.884041 -317.174349) (xy 156.876496 -317.166752) (xy 156.820616 -317.11646)
			(xy 156.812355 -317.109726) (xy 156.792147 -317.103027) (xy 156.7815 -317.103506) (xy 156.781246 -317.103506)
			(xy 156.750004 -317.10503) (xy 156.724744 -317.104538) (xy 156.674914 -317.096223) (xy 156.627131 -317.07982)
			(xy 156.582701 -317.055776) (xy 156.542833 -317.024746) (xy 156.508617 -316.987578) (xy 156.480985 -316.945285)
			(xy 156.460692 -316.899021) (xy 156.44829 -316.850047) (xy 156.444118 -316.7997) (xy 156.44829 -316.749353)
			(xy 156.460692 -316.700379) (xy 156.480985 -316.654115) (xy 156.508617 -316.611822) (xy 156.542833 -316.574654)
			(xy 156.582701 -316.543624) (xy 156.627131 -316.51958) (xy 156.674914 -316.503177) (xy 156.724744 -316.494862)
			(xy 156.750004 -316.494414) (xy 156.781246 -316.495938) (xy 156.7815 -316.495938) (xy 156.792162 -316.496539)
			(xy 156.812411 -316.489821) (xy 156.820616 -316.482984) (xy 156.876496 -316.432692) (xy 156.88415 -316.425172)
			(xy 156.892825 -316.405568) (xy 156.89326 -316.394846) (xy 156.89326 -316.324742) (xy 156.893418 -316.309476)
			(xy 156.896217 -316.279074) (xy 156.898848 -316.264036) (xy 156.899102 -316.262512) (xy 156.899864 -316.258448)
			(xy 156.892752 -316.235842) (xy 156.82849 -316.168532) (xy 156.81985 -316.160321) (xy 156.797458 -316.152247)
			(xy 156.785564 -316.153038) (xy 156.776705 -316.153993) (xy 156.758914 -316.155007) (xy 156.750004 -316.15507)
			(xy 156.724749 -316.154578) (xy 156.674928 -316.146265) (xy 156.627155 -316.129865) (xy 156.582733 -316.105825)
			(xy 156.542874 -316.074802) (xy 156.508665 -316.037641) (xy 156.481038 -315.995356) (xy 156.460749 -315.949101)
			(xy 156.448349 -315.900137) (xy 156.444178 -315.8498) (xy 156.448349 -315.799463) (xy 156.460749 -315.750499)
			(xy 156.481038 -315.704244) (xy 156.508665 -315.661959) (xy 156.542874 -315.624798) (xy 156.582733 -315.593775)
			(xy 156.627155 -315.569735) (xy 156.674928 -315.553335) (xy 156.724749 -315.545022) (xy 156.750004 -315.544454)
			(xy 156.764059 -315.544663) (xy 156.792043 -315.547335) (xy 156.805884 -315.549788) (xy 156.806392 -315.549788)
			(xy 156.818621 -315.551277) (xy 156.842104 -315.543963) (xy 156.85135 -315.535818) (xy 156.919676 -315.467238)
			(xy 156.927042 -315.443616) (xy 156.925518 -315.435488) (xy 156.920232 -315.40575) (xy 156.920103 -315.345359)
			(xy 156.925264 -315.3156) (xy 156.925264 -315.315092) (xy 156.927042 -315.305948) (xy 156.919676 -315.282326)
			(xy 156.85135 -315.213746) (xy 156.84211 -315.205594) (xy 156.818621 -315.19828) (xy 156.806392 -315.199776)
			(xy 156.806138 -315.199776) (xy 156.792236 -315.20225) (xy 156.764123 -315.204917) (xy 156.750004 -315.20511)
			(xy 156.724746 -315.204618) (xy 156.674919 -315.196304) (xy 156.627139 -315.179901) (xy 156.582711 -315.155859)
			(xy 156.542847 -315.124831) (xy 156.508633 -315.087666) (xy 156.481003 -315.045375) (xy 156.460711 -314.999114)
			(xy 156.44831 -314.950144) (xy 156.444138 -314.8998) (xy 156.44831 -314.849456) (xy 156.460711 -314.800486)
			(xy 156.481003 -314.754225) (xy 156.508633 -314.711934) (xy 156.542847 -314.674769) (xy 156.582711 -314.643741)
			(xy 156.627139 -314.619699) (xy 156.674919 -314.603296) (xy 156.724746 -314.594982) (xy 156.750004 -314.594494)
			(xy 156.759105 -314.594533) (xy 156.777278 -314.59555) (xy 156.786326 -314.596526) (xy 156.798264 -314.59805)
			(xy 156.820616 -314.589922) (xy 156.893514 -314.513722) (xy 156.900626 -314.491116) (xy 156.89961 -314.48502)
			(xy 156.897015 -314.470105) (xy 156.894215 -314.43996) (xy 156.894022 -314.424822) (xy 156.894064 -314.415468)
			(xy 156.895079 -314.396787) (xy 156.896054 -314.387484) (xy 156.897324 -314.376054) (xy 156.889958 -314.35421)
			(xy 156.817568 -314.281566) (xy 156.795978 -314.273692) (xy 156.784548 -314.274962) (xy 156.750004 -314.27674)
			(xy 156.724311 -314.276263) (xy 156.673556 -314.268225) (xy 156.624685 -314.252346) (xy 156.578899 -314.229017)
			(xy 156.537326 -314.198813) (xy 156.50099 -314.162477) (xy 156.470785 -314.120905) (xy 156.447456 -314.075119)
			(xy 156.431576 -314.026247) (xy 156.423538 -313.975493) (xy 156.423538 -313.924107) (xy 156.431576 -313.873353)
			(xy 156.447456 -313.824481) (xy 156.470785 -313.778695) (xy 156.50099 -313.737123) (xy 156.537326 -313.700787)
			(xy 156.578899 -313.670583) (xy 156.624685 -313.647254) (xy 156.673556 -313.631375) (xy 156.724311 -313.623337)
			(xy 156.750004 -313.622944) (xy 156.784548 -313.624722) (xy 156.795978 -313.625992) (xy 156.817568 -313.618118)
			(xy 156.889958 -313.545474) (xy 156.897324 -313.52363) (xy 156.896054 -313.5122) (xy 156.895085 -313.502896)
			(xy 156.894068 -313.484216) (xy 156.894022 -313.474862) (xy 156.894066 -313.465508) (xy 156.895084 -313.446828)
			(xy 156.896054 -313.437524) (xy 156.897324 -313.426094) (xy 156.889958 -313.40425) (xy 156.817568 -313.331606)
			(xy 156.795978 -313.323732) (xy 156.784548 -313.325002) (xy 156.750004 -313.32678) (xy 156.724315 -313.326302)
			(xy 156.673571 -313.318266) (xy 156.624708 -313.30239) (xy 156.57893 -313.279066) (xy 156.537365 -313.248867)
			(xy 156.501036 -313.212538) (xy 156.470837 -313.170973) (xy 156.447512 -313.125196) (xy 156.431635 -313.076333)
			(xy 156.423598 -313.025589) (xy 156.423598 -312.974211) (xy 156.431635 -312.923467) (xy 156.447512 -312.874604)
			(xy 156.470837 -312.828827) (xy 156.501036 -312.787262) (xy 156.537365 -312.750933) (xy 156.57893 -312.720734)
			(xy 156.624708 -312.69741) (xy 156.673571 -312.681534) (xy 156.724315 -312.673498) (xy 156.750004 -312.672984)
			(xy 156.784548 -312.674762) (xy 156.795978 -312.676032) (xy 156.817568 -312.668158) (xy 156.889958 -312.595514)
			(xy 156.897324 -312.57367) (xy 156.896054 -312.56224) (xy 156.895087 -312.552936) (xy 156.894073 -312.534256)
			(xy 156.894022 -312.524902) (xy 156.894221 -312.509891) (xy 156.897024 -312.48) (xy 156.89961 -312.465212)
			(xy 156.89961 -312.464196) (xy 156.900626 -312.458608) (xy 156.893514 -312.436002) (xy 156.820616 -312.359802)
			(xy 156.798264 -312.351674) (xy 156.786326 -312.353198) (xy 156.777279 -312.354186) (xy 156.759105 -312.355202)
			(xy 156.750004 -312.35523) (xy 156.724744 -312.354738) (xy 156.674914 -312.346423) (xy 156.627131 -312.33002)
			(xy 156.582701 -312.305976) (xy 156.542833 -312.274946) (xy 156.508617 -312.237778) (xy 156.480985 -312.195485)
			(xy 156.460692 -312.149221) (xy 156.44829 -312.100247) (xy 156.444118 -312.0499) (xy 156.44829 -311.999553)
			(xy 156.460692 -311.950579) (xy 156.480985 -311.904315) (xy 156.508617 -311.862022) (xy 156.542833 -311.824854)
			(xy 156.582701 -311.793824) (xy 156.627131 -311.76978) (xy 156.674914 -311.753377) (xy 156.724744 -311.745062)
			(xy 156.750004 -311.744614) (xy 156.759041 -311.744661) (xy 156.777086 -311.74568) (xy 156.786072 -311.746646)
			(xy 156.79801 -311.74817) (xy 156.820362 -311.740042) (xy 156.89326 -311.663842) (xy 156.900372 -311.641236)
			(xy 156.899356 -311.634632) (xy 156.89677 -311.61978) (xy 156.893968 -311.589762) (xy 156.893768 -311.574688)
			(xy 156.893768 -311.504584) (xy 156.893205 -311.493892) (xy 156.884545 -311.474339) (xy 156.877004 -311.466738)
			(xy 156.812996 -311.40908) (xy 156.792168 -311.402476) (xy 156.781754 -311.403746) (xy 156.750004 -311.40527)
			(xy 156.724749 -311.404778) (xy 156.674928 -311.396465) (xy 156.627155 -311.380065) (xy 156.582733 -311.356025)
			(xy 156.542874 -311.325002) (xy 156.508665 -311.287841) (xy 156.481038 -311.245556) (xy 156.460749 -311.199301)
			(xy 156.448349 -311.150337) (xy 156.444178 -311.1) (xy 156.448349 -311.049663) (xy 156.460749 -311.000699)
			(xy 156.481038 -310.954444) (xy 156.508665 -310.912159) (xy 156.542874 -310.874998) (xy 156.582733 -310.843975)
			(xy 156.627155 -310.819935) (xy 156.674928 -310.803535) (xy 156.724749 -310.795222) (xy 156.750004 -310.794654)
			(xy 156.781754 -310.796178) (xy 156.792168 -310.797448) (xy 156.812996 -310.790844) (xy 156.877004 -310.733186)
			(xy 156.884657 -310.725666) (xy 156.893327 -310.706061) (xy 156.893768 -310.69534) (xy 156.893768 -310.624728)
			(xy 156.893955 -310.609653) (xy 156.896752 -310.579633) (xy 156.899356 -310.564784) (xy 156.899356 -310.563768)
			(xy 156.900372 -310.558434) (xy 156.89326 -310.535828) (xy 156.820362 -310.459628) (xy 156.79801 -310.4515)
			(xy 156.786072 -310.453024) (xy 156.777088 -310.454008) (xy 156.759042 -310.455028) (xy 156.750004 -310.455056)
			(xy 156.725178 -310.454571) (xy 156.676181 -310.446538) (xy 156.629129 -310.430685) (xy 156.585261 -310.407427)
			(xy 156.545734 -310.377379) (xy 156.51159 -310.341332) (xy 156.483727 -310.300235) (xy 156.46288 -310.255173)
			(xy 156.449599 -310.207331) (xy 156.444232 -310.15797) (xy 156.446923 -310.108392) (xy 156.457599 -310.059902)
			(xy 156.475979 -310.013778) (xy 156.50158 -309.971235) (xy 156.533726 -309.933395) (xy 156.571571 -309.901254)
			(xy 156.614117 -309.87566) (xy 156.660244 -309.857286) (xy 156.708735 -309.846617) (xy 156.758314 -309.843934)
			(xy 156.807674 -309.849307) (xy 156.855514 -309.862595) (xy 156.900574 -309.883449) (xy 156.941666 -309.911317)
			(xy 156.977709 -309.945467) (xy 157.007751 -309.984998) (xy 157.031002 -310.028869) (xy 157.046849 -310.075924)
			(xy 157.054874 -310.124922) (xy 157.055312 -310.149748) (xy 157.054775 -310.175931) (xy 157.045841 -310.227529)
			(xy 157.037532 -310.252364) (xy 157.036262 -310.256936) (xy 157.034084 -310.26771) (xy 157.038063 -310.289306)
			(xy 157.050686 -310.307274) (xy 157.069651 -310.318342) (xy 157.091505 -310.320492) (xy 157.102048 -310.317388)
			(xy 157.127194 -310.308498) (xy 157.127448 -310.308498) (xy 157.129988 -310.307736) (xy 157.13837 -310.305196)
			(xy 157.141926 -310.30418) (xy 157.14599 -310.303164) (xy 157.165381 -310.298813) (xy 157.204858 -310.294225)
			(xy 157.22473 -310.29402) (xy 157.224984 -310.29402) (xy 157.249549 -310.294468) (xy 157.298138 -310.301737)
			(xy 157.321758 -310.308498) (xy 157.342332 -310.315356) (xy 157.35046 -310.317642) (xy 157.364684 -310.320436)
			(xy 157.374696 -310.319951) (xy 157.3932 -310.312296) (xy 157.407367 -310.298144) (xy 157.415041 -310.279648)
			(xy 157.415484 -310.269636) (xy 157.413198 -310.256682) (xy 157.411166 -310.249062) (xy 157.403489 -310.225084)
			(xy 157.3952 -310.175427) (xy 157.394656 -310.150256) (xy 157.394656 -310.149748) (xy 157.395099 -310.125751)
			(xy 157.402599 -310.078348) (xy 157.417423 -310.032702) (xy 157.439205 -309.989936) (xy 157.467409 -309.951105)
			(xy 157.501341 -309.917164) (xy 157.540164 -309.888949) (xy 157.582924 -309.867155) (xy 157.628566 -309.852319)
			(xy 157.675967 -309.844805) (xy 157.699964 -309.84444) (xy 157.709065 -309.844478) (xy 157.727238 -309.845493)
			(xy 157.736286 -309.846472) (xy 157.748224 -309.847996) (xy 157.770576 -309.839868) (xy 157.843474 -309.763668)
			(xy 157.850586 -309.741062) (xy 157.84957 -309.734966) (xy 157.846977 -309.720051) (xy 157.844183 -309.689905)
			(xy 157.843982 -309.674768) (xy 157.844026 -309.665414) (xy 157.845044 -309.646734) (xy 157.846014 -309.63743)
			(xy 157.847284 -309.626) (xy 157.839918 -309.604156) (xy 157.767528 -309.531512) (xy 157.745938 -309.523638)
			(xy 157.734508 -309.524908) (xy 157.700218 -309.52694) (xy 157.69971 -309.52694) (xy 157.674018 -309.526414)
			(xy 157.623271 -309.518335) (xy 157.574411 -309.502421) (xy 157.528641 -309.479063) (xy 157.487085 -309.448837)
			(xy 157.450767 -309.412485) (xy 157.420579 -309.370901) (xy 157.397263 -309.325109) (xy 157.381394 -309.276235)
			(xy 157.373362 -309.225481) (xy 157.372812 -309.199788) (xy 157.373317 -309.17408) (xy 157.381361 -309.123297)
			(xy 157.39725 -309.074397) (xy 157.420592 -309.028584) (xy 157.450813 -308.986987) (xy 157.487169 -308.950629)
			(xy 157.528764 -308.920405) (xy 157.574575 -308.897059) (xy 157.623473 -308.881167) (xy 157.674256 -308.873119)
			(xy 157.699964 -308.872636) (xy 157.725661 -308.873136) (xy 157.776424 -308.881167) (xy 157.825307 -308.897037)
			(xy 157.871108 -308.920354) (xy 157.912698 -308.950547) (xy 157.949056 -308.986872) (xy 157.979287 -309.028434)
			(xy 158.002648 -309.074213) (xy 158.018562 -309.123081) (xy 158.02664 -309.173837) (xy 158.027116 -309.199534)
			(xy 158.027116 -309.200042) (xy 158.025084 -309.234078) (xy 158.025084 -309.234586) (xy 158.023814 -309.246016)
			(xy 158.031688 -309.267606) (xy 158.104332 -309.339996) (xy 158.126176 -309.347362) (xy 158.137606 -309.346092)
			(xy 158.146847 -309.345129) (xy 158.1654 -309.344111) (xy 158.17469 -309.34406) (xy 158.184108 -309.344095)
			(xy 158.202916 -309.345109) (xy 158.212282 -309.346092) (xy 158.223712 -309.347362) (xy 158.245556 -309.339996)
			(xy 158.3182 -309.267606) (xy 158.326074 -309.246016) (xy 158.324804 -309.234586) (xy 158.322772 -309.200042)
			(xy 158.322772 -309.199534) (xy 158.323295 -309.173839) (xy 158.33137 -309.123087) (xy 158.34728 -309.074222)
			(xy 158.370636 -309.028446) (xy 158.400862 -308.986885) (xy 158.437214 -308.95056) (xy 158.478799 -308.920367)
			(xy 158.524593 -308.897047) (xy 158.573471 -308.881174) (xy 158.624229 -308.873139) (xy 158.675619 -308.873139)
			(xy 158.726377 -308.881174) (xy 158.775255 -308.897047) (xy 158.821049 -308.920367) (xy 158.862634 -308.95056)
			(xy 158.898986 -308.986885) (xy 158.929212 -309.028446) (xy 158.952568 -309.074222) (xy 158.968478 -309.123087)
			(xy 158.976553 -309.173839) (xy 158.977076 -309.199534) (xy 158.977076 -309.200042) (xy 158.975044 -309.234078)
			(xy 158.975044 -309.234586) (xy 158.973774 -309.246016) (xy 158.981648 -309.267606) (xy 159.054292 -309.339996)
			(xy 159.076136 -309.347362) (xy 159.087566 -309.346092) (xy 159.096807 -309.345131) (xy 159.11536 -309.344116)
			(xy 159.12465 -309.34406) (xy 159.124904 -309.34406) (xy 159.139332 -309.344224) (xy 159.168075 -309.346771)
			(xy 159.182308 -309.34914) (xy 159.182816 -309.34914) (xy 159.191198 -309.350664) (xy 159.213804 -309.343552)
			(xy 159.290258 -309.270908) (xy 159.298386 -309.248048) (xy 159.296862 -309.236364) (xy 159.295809 -309.227256)
			(xy 159.294668 -309.208956) (xy 159.294576 -309.199788) (xy 159.295098 -309.174533) (xy 159.303411 -309.124711)
			(xy 159.319812 -309.076937) (xy 159.343853 -309.032514) (xy 159.374877 -308.992654) (xy 159.412039 -308.958444)
			(xy 159.454325 -308.930818) (xy 159.500581 -308.910528) (xy 159.549546 -308.898128) (xy 159.599884 -308.893957)
			(xy 159.650222 -308.898128) (xy 159.699187 -308.910528) (xy 159.745443 -308.930818) (xy 159.787729 -308.958444)
			(xy 159.824891 -308.992654) (xy 159.855915 -309.032514) (xy 159.879956 -309.076937) (xy 159.896357 -309.124711)
			(xy 159.90467 -309.174533) (xy 159.905192 -309.199788) (xy 159.905087 -309.208829) (xy 159.903944 -309.226874)
			(xy 159.902906 -309.235856) (xy 159.902906 -309.236618) (xy 159.902199 -309.24829) (xy 159.910141 -309.270258)
			(xy 159.918146 -309.278782) (xy 159.98571 -309.343552) (xy 160.008316 -309.350664) (xy 160.013142 -309.349902)
			(xy 160.028362 -309.347172) (xy 160.059148 -309.344242) (xy 160.07461 -309.34406) (xy 160.074864 -309.34406)
			(xy 160.089292 -309.344223) (xy 160.118036 -309.346766) (xy 160.132268 -309.34914) (xy 160.132776 -309.34914)
			(xy 160.141158 -309.350664) (xy 160.163764 -309.343552) (xy 160.240218 -309.270908) (xy 160.248346 -309.248048)
			(xy 160.246822 -309.236364) (xy 160.245769 -309.227256) (xy 160.244628 -309.208956) (xy 160.244536 -309.199788)
			(xy 160.245058 -309.174533) (xy 160.253371 -309.124711) (xy 160.269772 -309.076937) (xy 160.293813 -309.032514)
			(xy 160.324837 -308.992654) (xy 160.361999 -308.958444) (xy 160.404285 -308.930818) (xy 160.450541 -308.910528)
			(xy 160.499506 -308.898128) (xy 160.549844 -308.893957) (xy 160.600182 -308.898128) (xy 160.649147 -308.910528)
			(xy 160.695403 -308.930818) (xy 160.737689 -308.958444) (xy 160.774851 -308.992654) (xy 160.805875 -309.032514)
			(xy 160.829916 -309.076937) (xy 160.846317 -309.124711) (xy 160.85463 -309.174533) (xy 160.855152 -309.199788)
			(xy 160.855053 -309.208892) (xy 160.853906 -309.227065) (xy 160.852866 -309.23611) (xy 160.852069 -309.248003)
			(xy 160.860151 -309.270394) (xy 160.86836 -309.279036) (xy 160.935924 -309.343552) (xy 160.95853 -309.350664)
			(xy 160.964626 -309.349648) (xy 160.979541 -309.347054) (xy 161.009687 -309.344258) (xy 161.024824 -309.34406)
			(xy 161.025078 -309.34406) (xy 161.039506 -309.344223) (xy 161.06825 -309.346767) (xy 161.082482 -309.34914)
			(xy 161.08299 -309.34914) (xy 161.091372 -309.350664) (xy 161.113978 -309.343552) (xy 161.190432 -309.270908)
			(xy 161.19856 -309.248048) (xy 161.197036 -309.236364) (xy 161.195983 -309.227256) (xy 161.194842 -309.208956)
			(xy 161.19475 -309.199788) (xy 161.195272 -309.174533) (xy 161.203585 -309.124711) (xy 161.219986 -309.076937)
			(xy 161.244027 -309.032514) (xy 161.275051 -308.992654) (xy 161.312213 -308.958444) (xy 161.354499 -308.930818)
			(xy 161.400755 -308.910528) (xy 161.44972 -308.898128) (xy 161.500058 -308.893957) (xy 161.550396 -308.898128)
			(xy 161.599361 -308.910528) (xy 161.645617 -308.930818) (xy 161.687903 -308.958444) (xy 161.725065 -308.992654)
			(xy 161.756089 -309.032514) (xy 161.78013 -309.076937) (xy 161.796531 -309.124711) (xy 161.804844 -309.174533)
			(xy 161.805366 -309.199788) (xy 161.805261 -309.208829) (xy 161.804117 -309.226874) (xy 161.80308 -309.235856)
			(xy 161.80308 -309.236618) (xy 161.802374 -309.248289) (xy 161.810324 -309.270249) (xy 161.81832 -309.278782)
			(xy 161.885884 -309.343552) (xy 161.90849 -309.350664) (xy 161.913316 -309.349902) (xy 161.928537 -309.347175)
			(xy 161.959322 -309.344252) (xy 161.974784 -309.34406) (xy 162.000773 -309.344568) (xy 162.052111 -309.352697)
			(xy 162.101546 -309.368756) (xy 162.14786 -309.39235) (xy 162.189913 -309.422899) (xy 162.226669 -309.45965)
			(xy 162.257225 -309.501699) (xy 162.280826 -309.54801) (xy 162.296892 -309.597442) (xy 162.305028 -309.648779)
			(xy 162.305492 -309.674768) (xy 162.305238 -309.688738) (xy 162.304984 -309.69204) (xy 162.30473 -309.702454)
			(xy 162.31108 -309.714138) (xy 162.314376 -309.719858) (xy 162.323382 -309.729503) (xy 162.32886 -309.733188)
			(xy 162.37712 -309.763414) (xy 162.404552 -309.780686) (xy 162.410494 -309.784085) (xy 162.423624 -309.787938)
			(xy 162.43046 -309.788306) (xy 162.44443 -309.78856) (xy 162.47139 -309.773356) (xy 162.526932 -309.746032)
			(xy 162.555428 -309.73395) (xy 162.562286 -309.731156) (xy 162.576256 -309.719726) (xy 162.584277 -309.712152)
			(xy 162.593497 -309.692136) (xy 162.594036 -309.681118) (xy 162.594036 -309.674768) (xy 162.594546 -309.648781)
			(xy 162.602676 -309.597446) (xy 162.618737 -309.548016) (xy 162.642333 -309.501706) (xy 162.672883 -309.459658)
			(xy 162.709634 -309.422907) (xy 162.751682 -309.392357) (xy 162.797992 -309.368761) (xy 162.847422 -309.3527)
			(xy 162.898757 -309.34457) (xy 162.950731 -309.34457) (xy 163.002066 -309.3527) (xy 163.051496 -309.368761)
			(xy 163.097806 -309.392357) (xy 163.139854 -309.422907) (xy 163.176605 -309.459658) (xy 163.207155 -309.501706)
			(xy 163.230751 -309.548016) (xy 163.246812 -309.597446) (xy 163.254942 -309.648781) (xy 163.255452 -309.674768)
			(xy 163.255452 -309.682642) (xy 163.255198 -309.690008) (xy 163.259262 -309.704486) (xy 163.26358 -309.711344)
			(xy 163.267898 -309.717948) (xy 163.279836 -309.727854) (xy 163.287202 -309.730902) (xy 163.314472 -309.742235)
			(xy 163.367723 -309.767778) (xy 163.393628 -309.781956) (xy 163.393882 -309.78221) (xy 163.399915 -309.785232)
			(xy 163.413043 -309.788329) (xy 163.41979 -309.788306) (xy 163.433252 -309.788052) (xy 163.520628 -309.733188)
			(xy 163.526107 -309.729505) (xy 163.535118 -309.719861) (xy 163.538408 -309.714138) (xy 163.544758 -309.702454)
			(xy 163.544504 -309.69204) (xy 163.54425 -309.688738) (xy 163.543996 -309.674768) (xy 163.544506 -309.648781)
			(xy 163.552636 -309.597446) (xy 163.568697 -309.548016) (xy 163.592293 -309.501706) (xy 163.622843 -309.459658)
			(xy 163.659594 -309.422907) (xy 163.701642 -309.392357) (xy 163.747952 -309.368761) (xy 163.797382 -309.3527)
			(xy 163.848717 -309.34457) (xy 163.900691 -309.34457) (xy 163.952026 -309.3527) (xy 164.001456 -309.368761)
			(xy 164.047766 -309.392357) (xy 164.089814 -309.422907) (xy 164.126565 -309.459658) (xy 164.157115 -309.501706)
			(xy 164.180711 -309.548016) (xy 164.196772 -309.597446) (xy 164.204902 -309.648781) (xy 164.205412 -309.674768)
			(xy 164.205158 -309.688738) (xy 164.204904 -309.69204) (xy 164.20465 -309.702454) (xy 164.211 -309.714138)
			(xy 164.214297 -309.719857) (xy 164.223305 -309.729499) (xy 164.22878 -309.733188) (xy 164.27704 -309.763414)
			(xy 164.304472 -309.780686) (xy 164.310411 -309.784095) (xy 164.323541 -309.787968) (xy 164.33038 -309.788306)
			(xy 164.34435 -309.78856) (xy 164.371309 -309.773354) (xy 164.42685 -309.746026) (xy 164.455348 -309.73395)
			(xy 164.462206 -309.731156) (xy 164.476176 -309.719726) (xy 164.484207 -309.712157) (xy 164.493442 -309.69214)
			(xy 164.493956 -309.681118) (xy 164.493956 -309.674768) (xy 164.494468 -309.648781) (xy 164.502602 -309.597449)
			(xy 164.518666 -309.54802) (xy 164.542263 -309.501712) (xy 164.572812 -309.459666) (xy 164.609563 -309.422915)
			(xy 164.651609 -309.392365) (xy 164.697916 -309.368767) (xy 164.747345 -309.352703) (xy 164.798677 -309.344568)
			(xy 164.824664 -309.34406) (xy 164.850061 -309.344521) (xy 164.900257 -309.352281) (xy 164.948678 -309.367624)
			(xy 164.994183 -309.39019) (xy 165.035703 -309.419447) (xy 165.05428 -309.43677) (xy 165.054534 -309.437024)
			(xy 165.061996 -309.443569) (xy 165.080428 -309.450878) (xy 165.090348 -309.451248) (xy 165.141148 -309.45074)
			(xy 165.157658 -309.450486) (xy 165.159182 -309.450486) (xy 165.163754 -309.450232) (xy 165.168956 -309.449856)
			(xy 165.179063 -309.447291) (xy 165.18382 -309.445152) (xy 165.19144 -309.441342) (xy 165.198044 -309.43423)
			(xy 165.534594 -309.09768) (xy 165.53815 -309.093616) (xy 165.541706 -309.089044) (xy 165.545331 -309.083289)
			(xy 165.549714 -309.070417) (xy 165.550342 -309.063644) (xy 165.551104 -308.999636) (xy 165.551104 -308.990492)
			(xy 165.550736 -308.980573) (xy 165.543422 -308.962142) (xy 165.53688 -308.954678) (xy 165.536626 -308.954424)
			(xy 165.519326 -308.935827) (xy 165.490061 -308.894314) (xy 165.467488 -308.848814) (xy 165.452137 -308.800398)
			(xy 165.44437 -308.750204) (xy 165.443916 -308.724808) (xy 165.444399 -308.699483) (xy 165.452122 -308.649424)
			(xy 165.467388 -308.601129) (xy 165.489841 -308.555726) (xy 165.518954 -308.514279) (xy 165.554048 -308.477756)
			(xy 165.594302 -308.447012) (xy 165.638772 -308.422766) (xy 165.68642 -308.405585) (xy 165.736131 -308.395871)
			(xy 165.761416 -308.394354) (xy 165.771068 -308.3941) (xy 165.779704 -308.39029) (xy 165.78391 -308.388317)
			(xy 165.79158 -308.383079) (xy 165.794944 -308.379876) (xy 165.816788 -308.358286) (xy 165.823734 -308.35086)
			(xy 165.831588 -308.332123) (xy 165.832028 -308.321964) (xy 165.832028 -308.177692) (xy 165.831977 -308.17362)
			(xy 165.830706 -308.165576) (xy 165.829488 -308.16169) (xy 165.827419 -308.155996) (xy 165.821002 -308.145723)
			(xy 165.816788 -308.14137) (xy 165.808914 -308.13375) (xy 165.808406 -308.133242) (xy 165.795198 -308.120034)
			(xy 165.792374 -308.117243) (xy 165.785992 -308.112522) (xy 165.782498 -308.110636) (xy 165.778942 -308.109112)
			(xy 165.77056 -308.105556) (xy 165.765988 -308.105556) (xy 165.740535 -308.104462) (xy 165.690401 -308.095419)
			(xy 165.642246 -308.078795) (xy 165.59721 -308.054985) (xy 165.556357 -308.024551) (xy 165.520653 -307.988213)
			(xy 165.490943 -307.94683) (xy 165.467929 -307.901381) (xy 165.452157 -307.852941) (xy 165.443998 -307.802655)
			(xy 165.443645 -307.751713) (xy 165.451108 -307.701319) (xy 165.46621 -307.652666) (xy 165.488592 -307.606903)
			(xy 165.517727 -307.565113) (xy 165.552925 -307.528284) (xy 165.593353 -307.497288) (xy 165.638056 -307.472857)
			(xy 165.685976 -307.455569) (xy 165.735981 -307.445834) (xy 165.761416 -307.444394) (xy 165.771068 -307.44414)
			(xy 165.779704 -307.44033) (xy 165.783911 -307.438359) (xy 165.791584 -307.433123) (xy 165.794944 -307.429916)
			(xy 165.816788 -307.408326) (xy 165.82374 -307.400902) (xy 165.831609 -307.382166) (xy 165.832028 -307.372004)
			(xy 165.832028 -307.227732) (xy 165.831972 -307.223661) (xy 165.830692 -307.21562) (xy 165.829488 -307.21173)
			(xy 165.827422 -307.206033) (xy 165.821011 -307.195755) (xy 165.816788 -307.19141) (xy 165.808914 -307.18379)
			(xy 165.808406 -307.183282) (xy 165.795198 -307.170074) (xy 165.792372 -307.167286) (xy 165.785987 -307.16257)
			(xy 165.782498 -307.160676) (xy 165.778942 -307.159152) (xy 165.77056 -307.155596) (xy 165.765988 -307.155596)
			(xy 165.740532 -307.154502) (xy 165.690392 -307.145458) (xy 165.642231 -307.128833) (xy 165.597189 -307.10502)
			(xy 165.556331 -307.074582) (xy 165.520623 -307.038239) (xy 165.490909 -306.996852) (xy 165.467893 -306.951397)
			(xy 165.452118 -306.902951) (xy 165.443958 -306.85266) (xy 165.443606 -306.801711) (xy 165.451069 -306.751312)
			(xy 165.466172 -306.702652) (xy 165.488557 -306.656884) (xy 165.517695 -306.615089) (xy 165.552897 -306.578255)
			(xy 165.59333 -306.547255) (xy 165.638038 -306.522821) (xy 165.685964 -306.505531) (xy 165.735975 -306.495794)
			(xy 165.761416 -306.494434) (xy 165.771068 -306.49418) (xy 165.779704 -306.49037) (xy 165.783909 -306.488397)
			(xy 165.791578 -306.483157) (xy 165.794944 -306.479956) (xy 165.816788 -306.458366) (xy 165.823731 -306.450939)
			(xy 165.831577 -306.432202) (xy 165.832028 -306.422044) (xy 165.832028 -306.277772) (xy 165.831975 -306.2737)
			(xy 165.830701 -306.265657) (xy 165.829488 -306.26177) (xy 165.827417 -306.256077) (xy 165.820997 -306.245807)
			(xy 165.816788 -306.24145) (xy 165.808914 -306.23383) (xy 165.808406 -306.233322) (xy 165.795198 -306.220114)
			(xy 165.792373 -306.217324) (xy 165.78599 -306.212605) (xy 165.782498 -306.210716) (xy 165.778942 -306.209192)
			(xy 165.77056 -306.205636) (xy 165.765988 -306.205636) (xy 165.740537 -306.204542) (xy 165.690406 -306.195499)
			(xy 165.642254 -306.178877) (xy 165.59722 -306.155068) (xy 165.556369 -306.124636) (xy 165.520668 -306.088299)
			(xy 165.49096 -306.046919) (xy 165.467948 -306.001473) (xy 165.452176 -305.953036) (xy 165.444018 -305.902753)
			(xy 165.443665 -305.851814) (xy 165.451128 -305.801423) (xy 165.466228 -305.752772) (xy 165.48861 -305.707012)
			(xy 165.517743 -305.665225) (xy 165.552939 -305.628399) (xy 165.593365 -305.597404) (xy 165.638065 -305.572975)
			(xy 165.685982 -305.555688) (xy 165.735984 -305.545953) (xy 165.761416 -305.544474) (xy 165.771068 -305.54422)
			(xy 165.779704 -305.54041) (xy 165.78391 -305.538438) (xy 165.791582 -305.533201) (xy 165.794944 -305.529996)
			(xy 165.816788 -305.508406) (xy 165.823737 -305.500981) (xy 165.831598 -305.482244) (xy 165.832028 -305.472084)
			(xy 165.832028 -305.327558) (xy 165.831974 -305.323486) (xy 165.830698 -305.315444) (xy 165.829488 -305.311556)
			(xy 165.827415 -305.305864) (xy 165.820994 -305.295596) (xy 165.816788 -305.291236) (xy 165.808914 -305.283616)
			(xy 165.808406 -305.283108) (xy 165.795198 -305.2699) (xy 165.792373 -305.267111) (xy 165.785989 -305.262393)
			(xy 165.782498 -305.260502) (xy 165.778942 -305.258978) (xy 165.77056 -305.255422) (xy 165.765988 -305.255422)
			(xy 165.740538 -305.254328) (xy 165.690409 -305.245286) (xy 165.642259 -305.228664) (xy 165.597227 -305.204856)
			(xy 165.556378 -305.174425) (xy 165.520678 -305.13809) (xy 165.490971 -305.096711) (xy 165.467961 -305.051267)
			(xy 165.45219 -305.002832) (xy 165.444032 -304.952551) (xy 165.443679 -304.901614) (xy 165.451142 -304.851226)
			(xy 165.466242 -304.802577) (xy 165.488622 -304.756819) (xy 165.517754 -304.715033) (xy 165.552948 -304.678209)
			(xy 165.593373 -304.647216) (xy 165.638071 -304.622788) (xy 165.685987 -304.605502) (xy 165.735986 -304.595767)
			(xy 165.761416 -304.59426) (xy 165.771068 -304.594006) (xy 165.779704 -304.590196) (xy 165.78391 -304.588224)
			(xy 165.79158 -304.582986) (xy 165.794944 -304.579782) (xy 165.816788 -304.558192) (xy 165.823735 -304.550766)
			(xy 165.831591 -304.53203) (xy 165.832028 -304.52187) (xy 165.832028 -304.377598) (xy 165.831978 -304.373526)
			(xy 165.830707 -304.365482) (xy 165.829488 -304.361596) (xy 165.827419 -304.355901) (xy 165.821003 -304.345628)
			(xy 165.816788 -304.341276) (xy 165.808914 -304.333656) (xy 165.808406 -304.333148) (xy 165.795198 -304.31994)
			(xy 165.792374 -304.317149) (xy 165.785992 -304.312427) (xy 165.782498 -304.310542) (xy 165.778942 -304.309018)
			(xy 165.77056 -304.305462) (xy 165.765988 -304.305462) (xy 165.740535 -304.304368) (xy 165.6904 -304.295325)
			(xy 165.642244 -304.278701) (xy 165.597207 -304.25489) (xy 165.556353 -304.224456) (xy 165.520648 -304.188117)
			(xy 165.490938 -304.146733) (xy 165.467924 -304.101283) (xy 165.452151 -304.052842) (xy 165.443992 -304.002556)
			(xy 165.443639 -303.951613) (xy 165.451102 -303.901218) (xy 165.466204 -303.852564) (xy 165.488587 -303.8068)
			(xy 165.517722 -303.765009) (xy 165.552921 -303.72818) (xy 165.59335 -303.697183) (xy 165.638053 -303.672752)
			(xy 165.685975 -303.655464) (xy 165.73598 -303.645728) (xy 165.761416 -303.6443) (xy 165.771068 -303.644046)
			(xy 165.779704 -303.640236) (xy 165.783908 -303.638262) (xy 165.791575 -303.633019) (xy 165.794944 -303.629822)
			(xy 165.816788 -303.608232) (xy 165.823741 -303.600808) (xy 165.831612 -303.582072) (xy 165.832028 -303.57191)
			(xy 165.832028 -303.427638) (xy 165.831973 -303.423566) (xy 165.830693 -303.415526) (xy 165.829488 -303.411636)
			(xy 165.827423 -303.405939) (xy 165.821013 -303.395659) (xy 165.816788 -303.391316) (xy 165.808914 -303.383696)
			(xy 165.808406 -303.383188) (xy 165.795198 -303.36998) (xy 165.792372 -303.367192) (xy 165.785988 -303.362475)
			(xy 165.782498 -303.360582) (xy 165.778942 -303.359058) (xy 165.77056 -303.355502) (xy 165.765988 -303.355502)
			(xy 165.740532 -303.354408) (xy 165.690391 -303.345364) (xy 165.642229 -303.328738) (xy 165.597186 -303.304925)
			(xy 165.556327 -303.274487) (xy 165.520618 -303.238143) (xy 165.490904 -303.196755) (xy 165.467887 -303.1513)
			(xy 165.452112 -303.102853) (xy 165.443952 -303.05256) (xy 165.4436 -303.001611) (xy 165.451063 -302.95121)
			(xy 165.466166 -302.90255) (xy 165.488552 -302.856781) (xy 165.51769 -302.814985) (xy 165.552893 -302.778151)
			(xy 165.593327 -302.74715) (xy 165.638036 -302.722716) (xy 165.685963 -302.705425) (xy 165.735974 -302.695688)
			(xy 165.761416 -302.69434) (xy 165.771068 -302.694086) (xy 165.779704 -302.690276) (xy 165.783909 -302.688303)
			(xy 165.791579 -302.683064) (xy 165.794944 -302.679862) (xy 165.816788 -302.658272) (xy 165.823732 -302.650845)
			(xy 165.831581 -302.632109) (xy 165.832028 -302.62195) (xy 165.832028 -302.477678) (xy 165.831976 -302.473606)
			(xy 165.830703 -302.465563) (xy 165.829488 -302.461676) (xy 165.827417 -302.455983) (xy 165.820999 -302.445712)
			(xy 165.816788 -302.441356) (xy 165.808914 -302.433736) (xy 165.808406 -302.433228) (xy 165.795198 -302.42002)
			(xy 165.792374 -302.41723) (xy 165.785991 -302.41251) (xy 165.782498 -302.410622) (xy 165.778942 -302.409098)
			(xy 165.770306 -302.405542) (xy 165.744542 -302.404714) (xy 165.693728 -302.396055) (xy 165.644873 -302.379616)
			(xy 165.599161 -302.355795) (xy 165.5577 -302.32517) (xy 165.521492 -302.288482) (xy 165.491416 -302.24662)
			(xy 165.4682 -302.200598) (xy 165.452407 -302.151531) (xy 165.444418 -302.100607) (xy 165.443916 -302.074834)
			(xy 165.444397 -302.048844) (xy 165.452524 -301.997502) (xy 165.468583 -301.948065) (xy 165.49218 -301.901749)
			(xy 165.522732 -301.859695) (xy 165.559487 -301.822938) (xy 165.60154 -301.792385) (xy 165.647856 -301.768787)
			(xy 165.697293 -301.752726) (xy 165.748634 -301.744597) (xy 165.774624 -301.744126) (xy 165.785129 -301.744174)
			(xy 165.8061 -301.745442) (xy 165.816534 -301.746666) (xy 165.81755 -301.74692) (xy 165.818312 -301.74692)
			(xy 165.823392 -301.747174) (xy 165.832376 -301.746719) (xy 165.849181 -301.740336) (xy 165.862762 -301.728557)
			(xy 165.871458 -301.712824) (xy 165.873176 -301.703994) (xy 165.873176 -301.702216) (xy 165.87343 -301.697136)
			(xy 165.87343 -301.502572) (xy 165.873176 -301.497492) (xy 165.873176 -301.495714) (xy 165.871479 -301.486875)
			(xy 165.862803 -301.471117) (xy 165.849211 -301.459335) (xy 165.832383 -301.452982) (xy 165.823392 -301.452534)
			(xy 165.818312 -301.452788) (xy 165.81755 -301.452788) (xy 165.816534 -301.453042) (xy 165.8061 -301.454258)
			(xy 165.785129 -301.455531) (xy 165.774624 -301.455582) (xy 165.748636 -301.455101) (xy 165.697298 -301.446973)
			(xy 165.647864 -301.430914) (xy 165.601551 -301.40732) (xy 165.5595 -301.37677) (xy 165.522745 -301.340018)
			(xy 165.492193 -301.297969) (xy 165.468595 -301.251658) (xy 165.452532 -301.202225) (xy 165.444401 -301.150888)
			(xy 165.444401 -301.098912) (xy 165.452532 -301.047575) (xy 165.468595 -300.998142) (xy 165.492193 -300.951831)
			(xy 165.522745 -300.909782) (xy 165.5595 -300.87303) (xy 165.601551 -300.84248) (xy 165.647864 -300.818886)
			(xy 165.697298 -300.802827) (xy 165.748636 -300.794699) (xy 165.774624 -300.794166) (xy 165.785129 -300.794215)
			(xy 165.8061 -300.795484) (xy 165.816534 -300.796706) (xy 165.81755 -300.79696) (xy 165.818312 -300.79696)
			(xy 165.823392 -300.797214) (xy 165.832372 -300.796758) (xy 165.84917 -300.790372) (xy 165.862738 -300.77859)
			(xy 165.871417 -300.762854) (xy 165.873176 -300.754034) (xy 165.873176 -300.752256) (xy 165.87343 -300.747176)
			(xy 165.87343 -299.68825) (xy 165.874446 -299.67809) (xy 165.876478 -299.668438) (xy 165.876926 -299.658774)
			(xy 165.871444 -299.640235) (xy 165.86581 -299.63237) (xy 165.814502 -299.573442) (xy 165.814502 -299.572934)
			(xy 165.814248 -299.572934) (xy 165.810667 -299.569025) (xy 165.802211 -299.562634) (xy 165.797484 -299.560234)
			(xy 165.787324 -299.555662) (xy 165.774624 -299.555662) (xy 165.748637 -299.555181) (xy 165.697303 -299.547054)
			(xy 165.647872 -299.530996) (xy 165.601562 -299.507403) (xy 165.559513 -299.476855) (xy 165.522761 -299.440105)
			(xy 165.49221 -299.398059) (xy 165.468613 -299.35175) (xy 165.452552 -299.302321) (xy 165.444421 -299.250987)
			(xy 165.444421 -299.199013) (xy 165.452552 -299.147679) (xy 165.468613 -299.09825) (xy 165.49221 -299.051941)
			(xy 165.522761 -299.009895) (xy 165.559513 -298.973145) (xy 165.601562 -298.942597) (xy 165.647872 -298.919004)
			(xy 165.697303 -298.902946) (xy 165.748637 -298.894819) (xy 165.774624 -298.894246) (xy 165.775132 -298.894246)
			(xy 165.801861 -298.894754) (xy 165.854623 -298.903343) (xy 165.905317 -298.920307) (xy 165.952621 -298.945206)
			(xy 165.995304 -298.97739) (xy 166.014146 -298.996354) (xy 166.0144 -298.996862) (xy 166.015162 -298.997624)
			(xy 166.020634 -299.00295) (xy 166.033933 -299.010437) (xy 166.041324 -299.012356) (xy 166.04869 -299.01388)
			(xy 166.063168 -299.01261) (xy 166.15283 -298.976796) (xy 166.159434 -298.974256) (xy 166.165276 -298.9707)
			(xy 166.172552 -298.965883) (xy 166.183594 -298.952389) (xy 166.189499 -298.935982) (xy 166.189914 -298.927266)
			(xy 166.189914 -298.772072) (xy 166.190343 -298.762004) (xy 166.198066 -298.743409) (xy 166.2049 -298.736004)
			(xy 166.35984 -298.581064) (xy 166.372794 -298.581064) (xy 166.446962 -298.456858) (xy 166.450994 -298.448029)
			(xy 166.452789 -298.42872) (xy 166.447306 -298.410118) (xy 166.441628 -298.402248) (xy 166.438326 -298.39793)
			(xy 166.408862 -298.372784) (xy 166.401998 -298.348985) (xy 166.394594 -298.300012) (xy 166.39413 -298.275248)
			(xy 166.39413 -298.27474) (xy 166.39464 -298.248753) (xy 166.40277 -298.197418) (xy 166.418831 -298.147988)
			(xy 166.442427 -298.101678) (xy 166.472977 -298.05963) (xy 166.509728 -298.022879) (xy 166.551776 -297.992329)
			(xy 166.598086 -297.968733) (xy 166.647516 -297.952672) (xy 166.698851 -297.944542) (xy 166.750825 -297.944542)
			(xy 166.80216 -297.952672) (xy 166.85159 -297.968733) (xy 166.8979 -297.992329) (xy 166.939948 -298.022879)
			(xy 166.976699 -298.05963) (xy 167.007249 -298.101678) (xy 167.030845 -298.147988) (xy 167.046906 -298.197418)
			(xy 167.055036 -298.248753) (xy 167.055546 -298.27474) (xy 167.055546 -298.275248) (xy 167.055036 -298.301614)
			(xy 167.046672 -298.353678) (xy 167.030149 -298.403754) (xy 167.018462 -298.427394) (xy 167.016176 -298.431712)
			(xy 167.010842 -298.441364) (xy 167.01008 -298.451778) (xy 167.009841 -298.459493) (xy 167.013449 -298.474493)
			(xy 167.017192 -298.481242) (xy 167.054276 -298.543726) (xy 167.061642 -298.556172) (xy 167.06723 -298.563792)
			(xy 167.072564 -298.569634) (xy 167.078914 -298.573444) (xy 167.082197 -298.575364) (xy 167.089211 -298.578301)
			(xy 167.092884 -298.579286) (xy 167.099488 -298.581064) (xy 167.84828 -298.581064) (xy 167.858342 -298.581503)
			(xy 167.87692 -298.589245) (xy 167.884348 -298.59605) (xy 167.954198 -298.6659) (xy 167.959695 -298.670891)
			(xy 167.972861 -298.677742) (xy 167.980106 -298.679362) (xy 167.989758 -298.680378) (xy 168.297352 -298.680378)
			(xy 168.30294 -298.680632) (xy 168.305734 -298.68114) (xy 168.305988 -298.68114) (xy 168.313354 -298.682156)
			(xy 168.319958 -298.681394) (xy 168.323613 -298.680962) (xy 168.330754 -298.679178) (xy 168.334182 -298.677838)
			(xy 168.343072 -298.673266) (xy 168.349959 -298.668859) (xy 168.360703 -298.656548) (xy 168.364154 -298.649136)
			(xy 168.400222 -298.562522) (xy 168.402254 -298.556426) (xy 168.404221 -298.547844) (xy 168.402853 -298.530304)
			(xy 168.395634 -298.51426) (xy 168.389808 -298.507658) (xy 168.389046 -298.506896) (xy 168.37136 -298.488221)
			(xy 168.341399 -298.446416) (xy 168.318265 -298.40048) (xy 168.302516 -298.351518) (xy 168.29453 -298.30071)
			(xy 168.29405 -298.274994) (xy 168.29405 -298.27474) (xy 168.29456 -298.248753) (xy 168.30269 -298.197418)
			(xy 168.318751 -298.147988) (xy 168.342347 -298.101678) (xy 168.372897 -298.05963) (xy 168.409648 -298.022879)
			(xy 168.451696 -297.992329) (xy 168.498006 -297.968733) (xy 168.547436 -297.952672) (xy 168.598771 -297.944542)
			(xy 168.650745 -297.944542) (xy 168.70208 -297.952672) (xy 168.75151 -297.968733) (xy 168.79782 -297.992329)
			(xy 168.839868 -298.022879) (xy 168.876619 -298.05963) (xy 168.907169 -298.101678) (xy 168.930765 -298.147988)
			(xy 168.946826 -298.197418) (xy 168.954956 -298.248753) (xy 168.955466 -298.27474) (xy 168.955466 -298.274994)
			(xy 168.954979 -298.300784) (xy 168.946979 -298.351741) (xy 168.931156 -298.400835) (xy 168.907896 -298.446873)
			(xy 168.877764 -298.488737) (xy 168.859962 -298.507404) (xy 168.859708 -298.507658) (xy 168.854635 -298.513125)
			(xy 168.847656 -298.526296) (xy 168.845992 -298.533566) (xy 168.844722 -298.540678) (xy 168.846246 -298.555664)
			(xy 168.870122 -298.61256) (xy 168.870122 -298.613068) (xy 168.88587 -298.651168) (xy 168.888717 -298.656736)
			(xy 168.896688 -298.666369) (xy 168.901618 -298.670218) (xy 168.905682 -298.673012) (xy 168.909365 -298.675168)
			(xy 168.917282 -298.678354) (xy 168.92143 -298.679362) (xy 168.932098 -298.680378) (xy 170.197272 -298.680378)
			(xy 170.20286 -298.680632) (xy 170.205654 -298.68114) (xy 170.205908 -298.68114) (xy 170.213274 -298.682156)
			(xy 170.219878 -298.681394) (xy 170.223533 -298.680961) (xy 170.230673 -298.679174) (xy 170.234102 -298.677838)
			(xy 170.242992 -298.673266) (xy 170.249877 -298.668858) (xy 170.260617 -298.656545) (xy 170.264074 -298.649136)
			(xy 170.300142 -298.562522) (xy 170.302174 -298.556426) (xy 170.304143 -298.547845) (xy 170.302773 -298.530307)
			(xy 170.295545 -298.514269) (xy 170.289728 -298.507658) (xy 170.288966 -298.506896) (xy 170.271279 -298.488221)
			(xy 170.241316 -298.446417) (xy 170.218181 -298.400481) (xy 170.202431 -298.351519) (xy 170.194444 -298.30071)
			(xy 170.19397 -298.274994) (xy 170.19397 -298.27474) (xy 170.19448 -298.248753) (xy 170.20261 -298.197418)
			(xy 170.218671 -298.147988) (xy 170.242267 -298.101678) (xy 170.272817 -298.05963) (xy 170.309568 -298.022879)
			(xy 170.351616 -297.992329) (xy 170.397926 -297.968733) (xy 170.447356 -297.952672) (xy 170.498691 -297.944542)
			(xy 170.550665 -297.944542) (xy 170.602 -297.952672) (xy 170.65143 -297.968733) (xy 170.69774 -297.992329)
			(xy 170.739788 -298.022879) (xy 170.776539 -298.05963) (xy 170.807089 -298.101678) (xy 170.830685 -298.147988)
			(xy 170.846746 -298.197418) (xy 170.854876 -298.248753) (xy 170.855386 -298.27474) (xy 170.855386 -298.274994)
			(xy 170.854899 -298.300785) (xy 170.846899 -298.351741) (xy 170.831077 -298.400836) (xy 170.807818 -298.446875)
			(xy 170.777687 -298.48874) (xy 170.759882 -298.507404) (xy 170.759628 -298.507658) (xy 170.754561 -298.513128)
			(xy 170.747593 -298.526301) (xy 170.745912 -298.533566) (xy 170.744642 -298.540678) (xy 170.746166 -298.555664)
			(xy 170.770042 -298.61256) (xy 170.770042 -298.613068) (xy 170.78579 -298.651168) (xy 170.788639 -298.656735)
			(xy 170.796611 -298.666366) (xy 170.801538 -298.670218) (xy 170.805602 -298.673012) (xy 170.809283 -298.675174)
			(xy 170.817198 -298.678372) (xy 170.82135 -298.679362) (xy 170.832018 -298.680378) (xy 172.097192 -298.680378)
			(xy 172.10278 -298.680632) (xy 172.105574 -298.68114) (xy 172.105828 -298.68114) (xy 172.113194 -298.682156)
			(xy 172.119798 -298.681394) (xy 172.123453 -298.680959) (xy 172.130591 -298.67917) (xy 172.134022 -298.677838)
			(xy 172.142912 -298.673266) (xy 172.149805 -298.668865) (xy 172.160561 -298.656558) (xy 172.163994 -298.649136)
			(xy 172.200062 -298.562522) (xy 172.202094 -298.556426) (xy 172.204062 -298.547845) (xy 172.202694 -298.530306)
			(xy 172.195468 -298.514266) (xy 172.189648 -298.507658) (xy 172.188886 -298.506896) (xy 172.171198 -298.488222)
			(xy 172.141234 -298.446418) (xy 172.118097 -298.400482) (xy 172.102346 -298.35152) (xy 172.094359 -298.30071)
			(xy 172.09389 -298.274994) (xy 172.09389 -298.27474) (xy 172.0944 -298.248753) (xy 172.10253 -298.197418)
			(xy 172.118591 -298.147988) (xy 172.142187 -298.101678) (xy 172.172737 -298.05963) (xy 172.209488 -298.022879)
			(xy 172.251536 -297.992329) (xy 172.297846 -297.968733) (xy 172.347276 -297.952672) (xy 172.398611 -297.944542)
			(xy 172.450585 -297.944542) (xy 172.50192 -297.952672) (xy 172.55135 -297.968733) (xy 172.59766 -297.992329)
			(xy 172.639708 -298.022879) (xy 172.676459 -298.05963) (xy 172.707009 -298.101678) (xy 172.730605 -298.147988)
			(xy 172.746666 -298.197418) (xy 172.754796 -298.248753) (xy 172.755306 -298.27474) (xy 172.755306 -298.274994)
			(xy 172.754819 -298.300785) (xy 172.746819 -298.351742) (xy 172.730999 -298.400837) (xy 172.707741 -298.446877)
			(xy 172.677611 -298.488743) (xy 172.659802 -298.507404) (xy 172.659548 -298.507658) (xy 172.65448 -298.513127)
			(xy 172.647509 -298.5263) (xy 172.645832 -298.533566) (xy 172.644562 -298.540678) (xy 172.646086 -298.555664)
			(xy 172.669962 -298.61256) (xy 172.669962 -298.613068) (xy 172.68571 -298.651168) (xy 172.68856 -298.656734)
			(xy 172.696534 -298.666362) (xy 172.701458 -298.670218) (xy 172.705522 -298.673012) (xy 172.709204 -298.675173)
			(xy 172.717119 -298.678367) (xy 172.72127 -298.679362) (xy 172.731938 -298.680378) (xy 173.997366 -298.680378)
			(xy 174.002954 -298.680632) (xy 174.005748 -298.68114) (xy 174.006002 -298.68114) (xy 174.013368 -298.682156)
			(xy 174.019972 -298.681394) (xy 174.023627 -298.680961) (xy 174.030767 -298.679175) (xy 174.034196 -298.677838)
			(xy 174.043086 -298.673266) (xy 174.049971 -298.668858) (xy 174.060713 -298.656546) (xy 174.064168 -298.649136)
			(xy 174.100236 -298.562522) (xy 174.102268 -298.556426) (xy 174.104235 -298.547844) (xy 174.102867 -298.530304)
			(xy 174.09565 -298.514259) (xy 174.089822 -298.507658) (xy 174.08906 -298.506896) (xy 174.071373 -298.488221)
			(xy 174.041411 -298.446417) (xy 174.018276 -298.400481) (xy 174.002526 -298.351519) (xy 173.99454 -298.30071)
			(xy 173.994064 -298.274994) (xy 173.994064 -298.27474) (xy 173.994574 -298.248753) (xy 174.002704 -298.197418)
			(xy 174.018765 -298.147988) (xy 174.042361 -298.101678) (xy 174.072911 -298.05963) (xy 174.109662 -298.022879)
			(xy 174.15171 -297.992329) (xy 174.19802 -297.968733) (xy 174.24745 -297.952672) (xy 174.298785 -297.944542)
			(xy 174.350759 -297.944542) (xy 174.402094 -297.952672) (xy 174.451524 -297.968733) (xy 174.497834 -297.992329)
			(xy 174.539882 -298.022879) (xy 174.576633 -298.05963) (xy 174.607183 -298.101678) (xy 174.630779 -298.147988)
			(xy 174.64684 -298.197418) (xy 174.65497 -298.248753) (xy 174.65548 -298.27474) (xy 174.65548 -298.274994)
			(xy 174.654993 -298.300785) (xy 174.646993 -298.351741) (xy 174.631171 -298.400835) (xy 174.607912 -298.446874)
			(xy 174.57778 -298.488739) (xy 174.559976 -298.507404) (xy 174.559722 -298.507658) (xy 174.554647 -298.513124)
			(xy 174.547666 -298.526295) (xy 174.546006 -298.533566) (xy 174.544736 -298.540678) (xy 174.54626 -298.555664)
			(xy 174.570136 -298.61256) (xy 174.570136 -298.613068) (xy 174.585884 -298.651168) (xy 174.588732 -298.656736)
			(xy 174.596704 -298.666367) (xy 174.601632 -298.670218) (xy 174.605696 -298.673012) (xy 174.609377 -298.675174)
			(xy 174.617291 -298.678373) (xy 174.621444 -298.679362) (xy 174.632112 -298.680378) (xy 176.847246 -298.680378)
			(xy 176.852834 -298.680632) (xy 176.855628 -298.68114) (xy 176.855882 -298.68114) (xy 176.863248 -298.682156)
			(xy 176.869852 -298.681394) (xy 176.873507 -298.680963) (xy 176.880648 -298.679179) (xy 176.884076 -298.677838)
			(xy 176.892966 -298.673266) (xy 176.899853 -298.66886) (xy 176.910599 -298.656549) (xy 176.914048 -298.649136)
			(xy 176.950116 -298.562522) (xy 176.952148 -298.556426) (xy 176.954115 -298.547844) (xy 176.952747 -298.530305)
			(xy 176.945527 -298.514261) (xy 176.939702 -298.507658) (xy 176.93894 -298.506896) (xy 176.921254 -298.488221)
			(xy 176.891294 -298.446416) (xy 176.868161 -298.40048) (xy 176.852411 -298.351518) (xy 176.844426 -298.30071)
			(xy 176.843944 -298.274994) (xy 176.843944 -298.27474) (xy 176.844454 -298.248753) (xy 176.852584 -298.197418)
			(xy 176.868645 -298.147988) (xy 176.892241 -298.101678) (xy 176.922791 -298.05963) (xy 176.959542 -298.022879)
			(xy 177.00159 -297.992329) (xy 177.0479 -297.968733) (xy 177.09733 -297.952672) (xy 177.148665 -297.944542)
			(xy 177.200639 -297.944542) (xy 177.251974 -297.952672) (xy 177.301404 -297.968733) (xy 177.347714 -297.992329)
			(xy 177.389762 -298.022879) (xy 177.426513 -298.05963) (xy 177.457063 -298.101678) (xy 177.480659 -298.147988)
			(xy 177.49672 -298.197418) (xy 177.50485 -298.248753) (xy 177.50536 -298.27474) (xy 177.50536 -298.274994)
			(xy 177.504873 -298.300784) (xy 177.496872 -298.351741) (xy 177.48105 -298.400834) (xy 177.457789 -298.446872)
			(xy 177.427657 -298.488736) (xy 177.409856 -298.507404) (xy 177.409602 -298.507658) (xy 177.404529 -298.513125)
			(xy 177.397551 -298.526297) (xy 177.395886 -298.533566) (xy 177.394616 -298.540678) (xy 177.39614 -298.555664)
			(xy 177.420016 -298.61256) (xy 177.420016 -298.613068) (xy 177.435764 -298.651168) (xy 177.438611 -298.656737)
			(xy 177.446581 -298.66637) (xy 177.451512 -298.670218) (xy 177.455576 -298.673012) (xy 177.459259 -298.675169)
			(xy 177.467176 -298.678356) (xy 177.471324 -298.679362) (xy 177.481992 -298.680378) (xy 178.74742 -298.680378)
			(xy 178.753008 -298.680632) (xy 178.755802 -298.68114) (xy 178.756056 -298.68114) (xy 178.763422 -298.682156)
			(xy 178.770026 -298.681394) (xy 178.77368 -298.680957) (xy 178.780817 -298.679165) (xy 178.78425 -298.677838)
			(xy 178.79314 -298.673266) (xy 178.80003 -298.668862) (xy 178.81078 -298.656554) (xy 178.814222 -298.649136)
			(xy 178.85029 -298.562522) (xy 178.852322 -298.556426) (xy 178.85429 -298.547845) (xy 178.852921 -298.530305)
			(xy 178.845699 -298.514264) (xy 178.839876 -298.507658) (xy 178.839114 -298.506896) (xy 178.821429 -298.48822)
			(xy 178.791471 -298.446415) (xy 178.768339 -298.400479) (xy 178.752592 -298.351517) (xy 178.744607 -298.300709)
			(xy 178.744118 -298.274994) (xy 178.744118 -298.27474) (xy 178.744628 -298.248753) (xy 178.752758 -298.197418)
			(xy 178.768819 -298.147988) (xy 178.792415 -298.101678) (xy 178.822965 -298.05963) (xy 178.859716 -298.022879)
			(xy 178.901764 -297.992329) (xy 178.948074 -297.968733) (xy 178.997504 -297.952672) (xy 179.048839 -297.944542)
			(xy 179.100813 -297.944542) (xy 179.152148 -297.952672) (xy 179.201578 -297.968733) (xy 179.247888 -297.992329)
			(xy 179.289936 -298.022879) (xy 179.326687 -298.05963) (xy 179.357237 -298.101678) (xy 179.380833 -298.147988)
			(xy 179.396894 -298.197418) (xy 179.405024 -298.248753) (xy 179.405534 -298.27474) (xy 179.405534 -298.274994)
			(xy 179.405046 -298.300784) (xy 179.397045 -298.35174) (xy 179.381222 -298.400833) (xy 179.35796 -298.44687)
			(xy 179.327826 -298.488731) (xy 179.31003 -298.507404) (xy 179.309776 -298.507658) (xy 179.304705 -298.513126)
			(xy 179.297731 -298.526298) (xy 179.29606 -298.533566) (xy 179.29479 -298.540678) (xy 179.296314 -298.555664)
			(xy 179.32019 -298.61256) (xy 179.32019 -298.613068) (xy 179.335938 -298.651168) (xy 179.338789 -298.656733)
			(xy 179.346766 -298.666358) (xy 179.351686 -298.670218) (xy 179.35575 -298.673012) (xy 179.359432 -298.675171)
			(xy 179.367349 -298.678361) (xy 179.371498 -298.679362) (xy 179.382166 -298.680378) (xy 180.64734 -298.680378)
			(xy 180.652928 -298.680632) (xy 180.655722 -298.68114) (xy 180.655976 -298.68114) (xy 180.663342 -298.682156)
			(xy 180.669946 -298.681394) (xy 180.673601 -298.680963) (xy 180.680743 -298.679181) (xy 180.68417 -298.677838)
			(xy 180.69306 -298.673266) (xy 180.699948 -298.66886) (xy 180.710694 -298.65655) (xy 180.714142 -298.649136)
			(xy 180.75021 -298.562522) (xy 180.752242 -298.556426) (xy 180.754209 -298.547844) (xy 180.752841 -298.530305)
			(xy 180.745621 -298.514262) (xy 180.739796 -298.507658) (xy 180.739034 -298.506896) (xy 180.721349 -298.48822)
			(xy 180.691389 -298.446416) (xy 180.668256 -298.400479) (xy 180.652507 -298.351518) (xy 180.644521 -298.30071)
			(xy 180.644038 -298.274994) (xy 180.644038 -298.27474) (xy 180.644548 -298.248753) (xy 180.652678 -298.197418)
			(xy 180.668739 -298.147988) (xy 180.692335 -298.101678) (xy 180.722885 -298.05963) (xy 180.759636 -298.022879)
			(xy 180.801684 -297.992329) (xy 180.847994 -297.968733) (xy 180.897424 -297.952672) (xy 180.948759 -297.944542)
			(xy 181.000733 -297.944542) (xy 181.052068 -297.952672) (xy 181.101498 -297.968733) (xy 181.147808 -297.992329)
			(xy 181.189856 -298.022879) (xy 181.226607 -298.05963) (xy 181.257157 -298.101678) (xy 181.280753 -298.147988)
			(xy 181.296814 -298.197418) (xy 181.304944 -298.248753) (xy 181.305454 -298.27474) (xy 181.305454 -298.274994)
			(xy 181.304967 -298.300784) (xy 181.296966 -298.35174) (xy 181.281143 -298.400834) (xy 181.257883 -298.446872)
			(xy 181.22775 -298.488735) (xy 181.20995 -298.507404) (xy 181.209696 -298.507658) (xy 181.204624 -298.513125)
			(xy 181.197646 -298.526297) (xy 181.19598 -298.533566) (xy 181.19471 -298.540678) (xy 181.196234 -298.555664)
			(xy 181.22011 -298.61256) (xy 181.22011 -298.613068) (xy 181.235858 -298.651168) (xy 181.238705 -298.656737)
			(xy 181.246674 -298.666371) (xy 181.251606 -298.670218) (xy 181.25567 -298.673012) (xy 181.259353 -298.675169)
			(xy 181.26727 -298.678357) (xy 181.271418 -298.679362) (xy 181.282086 -298.680378) (xy 182.54726 -298.680378)
			(xy 182.552848 -298.680632) (xy 182.555642 -298.68114) (xy 182.555896 -298.68114) (xy 182.563262 -298.682156)
			(xy 182.569866 -298.681394) (xy 182.573521 -298.680962) (xy 182.580661 -298.679177) (xy 182.58409 -298.677838)
			(xy 182.59298 -298.673266) (xy 182.599866 -298.668859) (xy 182.610608 -298.656547) (xy 182.614062 -298.649136)
			(xy 182.65013 -298.562522) (xy 182.652162 -298.556426) (xy 182.654129 -298.547844) (xy 182.652761 -298.530304)
			(xy 182.645543 -298.51426) (xy 182.639716 -298.507658) (xy 182.638954 -298.506896) (xy 182.621268 -298.488221)
			(xy 182.591306 -298.446417) (xy 182.568172 -298.400481) (xy 182.552422 -298.351519) (xy 182.544436 -298.30071)
			(xy 182.543958 -298.274994) (xy 182.543958 -298.27474) (xy 182.544468 -298.248753) (xy 182.552598 -298.197418)
			(xy 182.568659 -298.147988) (xy 182.592255 -298.101678) (xy 182.622805 -298.05963) (xy 182.659556 -298.022879)
			(xy 182.701604 -297.992329) (xy 182.747914 -297.968733) (xy 182.797344 -297.952672) (xy 182.848679 -297.944542)
			(xy 182.900653 -297.944542) (xy 182.951988 -297.952672) (xy 183.001418 -297.968733) (xy 183.047728 -297.992329)
			(xy 183.089776 -298.022879) (xy 183.126527 -298.05963) (xy 183.157077 -298.101678) (xy 183.180673 -298.147988)
			(xy 183.196734 -298.197418) (xy 183.204864 -298.248753) (xy 183.205374 -298.27474) (xy 183.205374 -298.274994)
			(xy 183.204887 -298.300784) (xy 183.196887 -298.351741) (xy 183.181065 -298.400835) (xy 183.157805 -298.446874)
			(xy 183.127673 -298.488738) (xy 183.10987 -298.507404) (xy 183.109616 -298.507658) (xy 183.104542 -298.513124)
			(xy 183.097562 -298.526296) (xy 183.0959 -298.533566) (xy 183.09463 -298.540678) (xy 183.096154 -298.555664)
			(xy 183.12003 -298.61256) (xy 183.12003 -298.613068) (xy 183.135778 -298.651168) (xy 183.138626 -298.656736)
			(xy 183.146597 -298.666368) (xy 183.151526 -298.670218) (xy 183.15559 -298.673012) (xy 183.159273 -298.675168)
			(xy 183.167191 -298.678352) (xy 183.171338 -298.679362) (xy 183.182006 -298.680378) (xy 184.02046 -298.680378)
			(xy 184.030112 -298.679362) (xy 184.037359 -298.677739) (xy 184.050535 -298.670905) (xy 184.05602 -298.6659)
			(xy 184.125616 -298.596304) (xy 184.130606 -298.590806) (xy 184.137455 -298.577641) (xy 184.139078 -298.570396)
			(xy 184.140094 -298.560744) (xy 184.140094 -298.242736) (xy 184.140528 -298.232671) (xy 184.148258 -298.214083)
			(xy 184.15508 -298.206668) (xy 184.60593 -297.755818) (xy 184.611518 -297.749214) (xy 184.615836 -297.741848)
			(xy 184.617868 -297.73626) (xy 184.619651 -297.730861) (xy 184.621058 -297.71958) (xy 184.620662 -297.713908)
			(xy 184.612788 -297.636692) (xy 184.612037 -297.631188) (xy 184.608449 -297.620678) (xy 184.605676 -297.615864)
			(xy 184.600088 -297.606466) (xy 184.59069 -297.599862) (xy 184.590182 -297.599862) (xy 184.568055 -297.584303)
			(xy 184.528705 -297.547194) (xy 184.495895 -297.504193) (xy 184.470497 -297.456439) (xy 184.453183 -297.405196)
			(xy 184.444411 -297.351824) (xy 184.443878 -297.32478) (xy 184.444389 -297.298793) (xy 184.452522 -297.247461)
			(xy 184.468585 -297.198032) (xy 184.492181 -297.151724) (xy 184.522731 -297.109677) (xy 184.559482 -297.072927)
			(xy 184.601529 -297.042378) (xy 184.647837 -297.018782) (xy 184.697266 -297.002721) (xy 184.748599 -296.994589)
			(xy 184.774586 -296.994072) (xy 184.804304 -296.995342) (xy 184.815226 -296.996358) (xy 184.825132 -296.993056)
			(xy 184.830101 -296.99117) (xy 184.839186 -296.985657) (xy 184.843166 -296.982134) (xy 184.89803 -296.931588)
			(xy 184.905467 -296.924091) (xy 184.913985 -296.904796) (xy 184.91454 -296.89425) (xy 184.91454 -296.80535)
			(xy 184.914268 -296.798233) (xy 184.910273 -296.784567) (xy 184.906666 -296.778426) (xy 184.89803 -296.768012)
			(xy 184.829958 -296.705782) (xy 184.827926 -296.704004) (xy 184.827418 -296.704004) (xy 184.816719 -296.697286)
			(xy 184.791672 -296.694229) (xy 184.779666 -296.698162) (xy 184.761632 -296.705274) (xy 184.736332 -296.703797)
			(xy 184.686591 -296.694108) (xy 184.638909 -296.676944) (xy 184.594404 -296.652708) (xy 184.554117 -296.621965)
			(xy 184.518992 -296.585437) (xy 184.489851 -296.543978) (xy 184.467375 -296.498558) (xy 184.452091 -296.450241)
			(xy 184.444357 -296.400158) (xy 184.443878 -296.37482) (xy 184.44436 -296.348829) (xy 184.452488 -296.297487)
			(xy 184.468549 -296.248049) (xy 184.492145 -296.201732) (xy 184.522697 -296.159677) (xy 184.559451 -296.122919)
			(xy 184.601503 -296.092363) (xy 184.647818 -296.068762) (xy 184.697254 -296.052696) (xy 184.748595 -296.044562)
			(xy 184.774586 -296.044112) (xy 184.804304 -296.045382) (xy 184.815226 -296.046398) (xy 184.825132 -296.043096)
			(xy 184.830102 -296.041212) (xy 184.83919 -296.035702) (xy 184.843166 -296.032174) (xy 184.89803 -295.981628)
			(xy 184.905473 -295.974134) (xy 184.914007 -295.954839) (xy 184.91454 -295.94429) (xy 184.91454 -294.90543)
			(xy 184.914266 -294.898314) (xy 184.910266 -294.884651) (xy 184.906666 -294.878506) (xy 184.89803 -294.868092)
			(xy 184.829958 -294.805862) (xy 184.827926 -294.804084) (xy 184.827418 -294.804084) (xy 184.816718 -294.797368)
			(xy 184.791673 -294.794312) (xy 184.779666 -294.798242) (xy 184.761632 -294.805354) (xy 184.736333 -294.803877)
			(xy 184.686592 -294.794188) (xy 184.638912 -294.777024) (xy 184.594409 -294.752787) (xy 184.554124 -294.722044)
			(xy 184.519 -294.685515) (xy 184.489861 -294.644056) (xy 184.467388 -294.598636) (xy 184.452107 -294.55032)
			(xy 184.444376 -294.500238) (xy 184.443878 -294.4749) (xy 184.444388 -294.448912) (xy 184.452518 -294.397577)
			(xy 184.468579 -294.348146) (xy 184.492174 -294.301835) (xy 184.522724 -294.259786) (xy 184.559475 -294.223033)
			(xy 184.601523 -294.192482) (xy 184.647833 -294.168884) (xy 184.697263 -294.152821) (xy 184.748598 -294.144689)
			(xy 184.774586 -294.144192) (xy 184.804304 -294.145462) (xy 184.815226 -294.146478) (xy 184.825132 -294.143176)
			(xy 184.830102 -294.141291) (xy 184.839188 -294.13578) (xy 184.843166 -294.132254) (xy 184.89803 -294.081708)
			(xy 184.90547 -294.074213) (xy 184.913997 -294.054918) (xy 184.91454 -294.04437) (xy 184.91454 -293.95547)
			(xy 184.914271 -293.948352) (xy 184.91028 -293.934684) (xy 184.906666 -293.928546) (xy 184.89803 -293.918132)
			(xy 184.829958 -293.855902) (xy 184.827926 -293.854124) (xy 184.827418 -293.854124) (xy 184.816717 -293.847414)
			(xy 184.791674 -293.844362) (xy 184.779666 -293.848282) (xy 184.761632 -293.855394) (xy 184.736332 -293.853917)
			(xy 184.686589 -293.844228) (xy 184.638906 -293.827065) (xy 184.5944 -293.802829) (xy 184.554111 -293.772087)
			(xy 184.518984 -293.735558) (xy 184.48984 -293.694099) (xy 184.467362 -293.64868) (xy 184.452076 -293.600362)
			(xy 184.444339 -293.550279) (xy 184.443878 -293.52494) (xy 184.444358 -293.498948) (xy 184.452484 -293.447604)
			(xy 184.468543 -293.398163) (xy 184.492138 -293.351844) (xy 184.52269 -293.309785) (xy 184.559444 -293.273025)
			(xy 184.601497 -293.242467) (xy 184.647813 -293.218864) (xy 184.697251 -293.202797) (xy 184.748594 -293.194662)
			(xy 184.774586 -293.194232) (xy 184.804304 -293.195502) (xy 184.815226 -293.196518) (xy 184.825132 -293.193216)
			(xy 184.830103 -293.191333) (xy 184.839192 -293.185825) (xy 184.843166 -293.182294) (xy 184.89803 -293.131748)
			(xy 184.905476 -293.124255) (xy 184.914018 -293.10496) (xy 184.91454 -293.09441) (xy 184.91454 -293.005256)
			(xy 184.914269 -292.998138) (xy 184.910275 -292.984472) (xy 184.906666 -292.978332) (xy 184.89803 -292.967918)
			(xy 184.829958 -292.905688) (xy 184.827926 -292.90391) (xy 184.827418 -292.90391) (xy 184.816717 -292.897201)
			(xy 184.791675 -292.89415) (xy 184.779666 -292.898068) (xy 184.761632 -292.90518) (xy 184.736332 -292.903703)
			(xy 184.68659 -292.894014) (xy 184.638908 -292.876851) (xy 184.594403 -292.852614) (xy 184.554116 -292.821872)
			(xy 184.51899 -292.785343) (xy 184.489848 -292.743884) (xy 184.467371 -292.698464) (xy 184.452087 -292.650147)
			(xy 184.444352 -292.600064) (xy 184.443878 -292.574726) (xy 184.444359 -292.548735) (xy 184.452487 -292.497392)
			(xy 184.468547 -292.447954) (xy 184.492143 -292.401636) (xy 184.522695 -292.35958) (xy 184.559449 -292.322821)
			(xy 184.601502 -292.292264) (xy 184.647817 -292.268662) (xy 184.697253 -292.252596) (xy 184.748595 -292.244462)
			(xy 184.774586 -292.244018) (xy 184.804304 -292.245288) (xy 184.815226 -292.246304) (xy 184.825132 -292.243002)
			(xy 184.830102 -292.241118) (xy 184.839191 -292.235609) (xy 184.843166 -292.23208) (xy 184.89803 -292.181534)
			(xy 184.905474 -292.17404) (xy 184.91401 -292.154745) (xy 184.91454 -292.144196) (xy 184.91454 -292.055296)
			(xy 184.914261 -292.048181) (xy 184.910254 -292.034524) (xy 184.906666 -292.028372) (xy 184.89803 -292.017958)
			(xy 184.829958 -291.955728) (xy 184.827926 -291.95395) (xy 184.827418 -291.95395) (xy 184.816718 -291.947237)
			(xy 184.791674 -291.944184) (xy 184.779666 -291.948108) (xy 184.761632 -291.95522) (xy 184.736334 -291.953743)
			(xy 184.686595 -291.944053) (xy 184.638917 -291.926889) (xy 184.594416 -291.902651) (xy 184.554134 -291.871908)
			(xy 184.519014 -291.835379) (xy 184.489879 -291.793919) (xy 184.46741 -291.7485) (xy 184.452133 -291.700184)
			(xy 184.444407 -291.650103) (xy 184.443878 -291.624766) (xy 184.44439 -291.59878) (xy 184.452525 -291.547449)
			(xy 184.468589 -291.498022) (xy 184.492186 -291.451716) (xy 184.522736 -291.409672) (xy 184.559487 -291.372923)
			(xy 184.601533 -291.342376) (xy 184.647841 -291.318781) (xy 184.697268 -291.30272) (xy 184.7486 -291.294588)
			(xy 184.774586 -291.294058) (xy 184.804304 -291.295328) (xy 184.815226 -291.296344) (xy 184.825132 -291.293042)
			(xy 184.830103 -291.291159) (xy 184.839194 -291.285654) (xy 184.843166 -291.28212) (xy 184.89803 -291.231574)
			(xy 184.905465 -291.224077) (xy 184.913978 -291.204782) (xy 184.91454 -291.194236) (xy 184.91454 -291.105336)
			(xy 184.914266 -291.098219) (xy 184.910268 -291.084556) (xy 184.906666 -291.078412) (xy 184.89803 -291.067998)
			(xy 184.829958 -291.005768) (xy 184.827926 -291.00399) (xy 184.827418 -291.00399) (xy 184.816718 -290.997274)
			(xy 184.791673 -290.994218) (xy 184.779666 -290.998148) (xy 184.761632 -291.00526) (xy 184.736333 -291.003783)
			(xy 184.686592 -290.994094) (xy 184.638911 -290.97693) (xy 184.594407 -290.952693) (xy 184.554122 -290.921951)
			(xy 184.518998 -290.885422) (xy 184.489858 -290.843962) (xy 184.467384 -290.798543) (xy 184.452102 -290.750226)
			(xy 184.44437 -290.700144) (xy 184.443878 -290.674806) (xy 184.444387 -290.648818) (xy 184.452517 -290.597482)
			(xy 184.468577 -290.54805) (xy 184.492172 -290.501738) (xy 184.522722 -290.459688) (xy 184.559473 -290.422935)
			(xy 184.601521 -290.392383) (xy 184.647831 -290.368785) (xy 184.697263 -290.352722) (xy 184.748598 -290.344589)
			(xy 184.774586 -290.344098) (xy 184.804304 -290.345368) (xy 184.815226 -290.346384) (xy 184.825132 -290.343082)
			(xy 184.830102 -290.341197) (xy 184.839189 -290.335687) (xy 184.843166 -290.33216) (xy 184.89803 -290.281614)
			(xy 184.905471 -290.274119) (xy 184.914 -290.254824) (xy 184.91454 -290.244276) (xy 184.91454 -290.155376)
			(xy 184.914272 -290.148258) (xy 184.910283 -290.134589) (xy 184.906666 -290.128452) (xy 184.89803 -290.118038)
			(xy 184.829958 -290.055808) (xy 184.827926 -290.05403) (xy 184.827418 -290.05403) (xy 184.816717 -290.04732)
			(xy 184.791674 -290.044267) (xy 184.779666 -290.048188) (xy 184.761632 -290.0553) (xy 184.736331 -290.053823)
			(xy 184.686588 -290.044134) (xy 184.638905 -290.026971) (xy 184.594398 -290.002735) (xy 184.554109 -289.971993)
			(xy 184.518982 -289.935465) (xy 184.489837 -289.894006) (xy 184.467358 -289.848586) (xy 184.452071 -289.800269)
			(xy 184.444333 -289.750185) (xy 184.443878 -289.724846) (xy 184.443878 -289.724592) (xy 184.444415 -289.697505)
			(xy 184.453243 -289.644056) (xy 184.470675 -289.592765) (xy 184.482994 -289.568636) (xy 184.483248 -289.568382)
			(xy 184.486087 -289.562564) (xy 184.489046 -289.549964) (xy 184.48909 -289.54349) (xy 184.488836 -289.530536)
			(xy 184.459372 -289.48126) (xy 184.43702 -289.443922) (xy 184.432702 -289.437826) (xy 184.426083 -289.430369)
			(xy 184.408539 -289.420926) (xy 184.398666 -289.419538) (xy 184.097676 -289.419538) (xy 184.094882 -289.41903)
			(xy 184.081166 -289.418014) (xy 184.080658 -289.418014) (xy 184.07477 -289.417653) (xy 184.063096 -289.419323)
			(xy 184.057544 -289.421316) (xy 184.053226 -289.423348) (xy 184.047895 -289.426227) (xy 184.038656 -289.434059)
			(xy 184.034938 -289.438842) (xy 184.031128 -289.444176) (xy 184.026302 -289.456622) (xy 184.025794 -289.463226)
			(xy 184.025305 -289.469854) (xy 184.027354 -289.482979) (xy 184.029858 -289.489134) (xy 184.030874 -289.49142)
			(xy 184.034938 -289.49904) (xy 184.043574 -289.51174) (xy 184.046622 -289.515042) (xy 184.062227 -289.532141)
			(xy 184.088615 -289.570173) (xy 184.108951 -289.611758) (xy 184.122765 -289.655939) (xy 184.129741 -289.701701)
			(xy 184.130188 -289.724846) (xy 184.129714 -289.748834) (xy 184.122202 -289.796219) (xy 184.10737 -289.841846)
			(xy 184.085584 -289.884591) (xy 184.057379 -289.923401) (xy 184.023451 -289.957322) (xy 183.984634 -289.985518)
			(xy 183.941885 -290.007296) (xy 183.896255 -290.022117) (xy 183.848868 -290.029619) (xy 183.82488 -290.030154)
			(xy 183.801215 -290.029708) (xy 183.754453 -290.022405) (xy 183.709377 -290.007976) (xy 183.667065 -289.986767)
			(xy 183.628532 -289.959286) (xy 183.594698 -289.92619) (xy 183.566374 -289.888271) (xy 183.544238 -289.846438)
			(xy 183.52882 -289.80169) (xy 183.520488 -289.7551) (xy 183.519572 -289.73145) (xy 183.519572 -289.724592)
			(xy 183.519998 -289.70141) (xy 183.527003 -289.655578) (xy 183.540865 -289.611335) (xy 183.561266 -289.569701)
			(xy 183.587735 -289.531635) (xy 183.603392 -289.514534) (xy 183.60644 -289.511486) (xy 183.616854 -289.495992)
			(xy 183.621426 -289.485578) (xy 183.623944 -289.477318) (xy 183.62394 -289.460058) (xy 183.621426 -289.451796)
			(xy 183.60771 -289.431222) (xy 183.606694 -289.430206) (xy 183.601868 -289.425888) (xy 183.58485 -289.419538)
			(xy 183.147716 -289.419538) (xy 183.144922 -289.41903) (xy 183.131206 -289.418014) (xy 183.130698 -289.418014)
			(xy 183.124809 -289.417649) (xy 183.113132 -289.41931) (xy 183.107584 -289.421316) (xy 183.103266 -289.423348)
			(xy 183.097933 -289.426224) (xy 183.088688 -289.434051) (xy 183.084978 -289.438842) (xy 183.081168 -289.444176)
			(xy 183.076342 -289.456622) (xy 183.075834 -289.463226) (xy 183.075345 -289.469854) (xy 183.077392 -289.48298)
			(xy 183.079898 -289.489134) (xy 183.080914 -289.49142) (xy 183.084978 -289.49904) (xy 183.093614 -289.51174)
			(xy 183.096662 -289.515042) (xy 183.112265 -289.532142) (xy 183.13865 -289.570175) (xy 183.158983 -289.61176)
			(xy 183.172795 -289.65594) (xy 183.179771 -289.701701) (xy 183.180228 -289.724846) (xy 183.179754 -289.748835)
			(xy 183.172242 -289.796223) (xy 183.157411 -289.841852) (xy 183.135625 -289.8846) (xy 183.107422 -289.923414)
			(xy 183.073494 -289.957338) (xy 183.034677 -289.985539) (xy 182.991928 -290.007321) (xy 182.946297 -290.022148)
			(xy 182.898909 -290.029656) (xy 182.87492 -290.030154) (xy 182.851258 -290.029704) (xy 182.804503 -290.022393)
			(xy 182.759435 -290.007959) (xy 182.717132 -289.986747) (xy 182.678606 -289.959264) (xy 182.64478 -289.926169)
			(xy 182.616463 -289.888253) (xy 182.594332 -289.846423) (xy 182.578917 -289.80168) (xy 182.570587 -289.755096)
			(xy 182.569612 -289.73145) (xy 182.569612 -289.724592) (xy 182.570037 -289.701409) (xy 182.577041 -289.655577)
			(xy 182.590902 -289.611332) (xy 182.611299 -289.569695) (xy 182.637764 -289.531625) (xy 182.653432 -289.514534)
			(xy 182.65648 -289.511486) (xy 182.666894 -289.495992) (xy 182.671466 -289.485578) (xy 182.673983 -289.477317)
			(xy 182.673979 -289.460058) (xy 182.671466 -289.451796) (xy 182.65775 -289.431222) (xy 182.656734 -289.430206)
			(xy 182.651908 -289.425888) (xy 182.63489 -289.419538) (xy 182.197756 -289.419538) (xy 182.194962 -289.41903)
			(xy 182.181246 -289.418014) (xy 182.180738 -289.418014) (xy 182.174851 -289.417656) (xy 182.163178 -289.41933)
			(xy 182.157624 -289.421316) (xy 182.153306 -289.423348) (xy 182.14797 -289.42622) (xy 182.138719 -289.434044)
			(xy 182.135018 -289.438842) (xy 182.131208 -289.444176) (xy 182.126382 -289.456622) (xy 182.125874 -289.463226)
			(xy 182.125385 -289.469854) (xy 182.127434 -289.482979) (xy 182.129938 -289.489134) (xy 182.130954 -289.49142)
			(xy 182.135018 -289.49904) (xy 182.143654 -289.51174) (xy 182.146702 -289.515042) (xy 182.162308 -289.53214)
			(xy 182.188698 -289.570172) (xy 182.209035 -289.611757) (xy 182.22285 -289.655938) (xy 182.229827 -289.7017)
			(xy 182.230268 -289.724846) (xy 182.229794 -289.748834) (xy 182.222282 -289.796218) (xy 182.20745 -289.841843)
			(xy 182.185663 -289.884586) (xy 182.157458 -289.923395) (xy 182.12353 -289.957314) (xy 182.084713 -289.985508)
			(xy 182.041963 -290.007283) (xy 181.996334 -290.022102) (xy 181.948948 -290.029601) (xy 181.92496 -290.030154)
			(xy 181.901296 -290.029707) (xy 181.854536 -290.022401) (xy 181.809463 -290.00797) (xy 181.767154 -289.986761)
			(xy 181.728623 -289.959279) (xy 181.694792 -289.926183) (xy 181.666471 -289.888265) (xy 181.644336 -289.846433)
			(xy 181.628919 -289.801687) (xy 181.620588 -289.755099) (xy 181.619652 -289.73145) (xy 181.619652 -289.724592)
			(xy 181.620078 -289.70141) (xy 181.627082 -289.655578) (xy 181.640944 -289.611334) (xy 181.661344 -289.569699)
			(xy 181.687811 -289.531632) (xy 181.703472 -289.514534) (xy 181.70652 -289.511486) (xy 181.716934 -289.495992)
			(xy 181.721506 -289.485578) (xy 181.724025 -289.477318) (xy 181.724021 -289.460058) (xy 181.721506 -289.451796)
			(xy 181.70779 -289.431222) (xy 181.706774 -289.430206) (xy 181.701948 -289.425888) (xy 181.68493 -289.419538)
			(xy 181.247796 -289.419538) (xy 181.245002 -289.41903) (xy 181.231286 -289.418014) (xy 181.230778 -289.418014)
			(xy 181.22489 -289.417651) (xy 181.213214 -289.419316) (xy 181.207664 -289.421316) (xy 181.203346 -289.423348)
			(xy 181.198014 -289.426225) (xy 181.188772 -289.434055) (xy 181.185058 -289.438842) (xy 181.181248 -289.444176)
			(xy 181.176422 -289.456622) (xy 181.175914 -289.463226) (xy 181.175425 -289.469854) (xy 181.177475 -289.482979)
			(xy 181.179978 -289.489134) (xy 181.180994 -289.49142) (xy 181.185058 -289.49904) (xy 181.193694 -289.51174)
			(xy 181.196742 -289.515042) (xy 181.212346 -289.532141) (xy 181.238733 -289.570174) (xy 181.259067 -289.611759)
			(xy 181.27288 -289.65594) (xy 181.279856 -289.701701) (xy 181.280308 -289.724846) (xy 181.279834 -289.748835)
			(xy 181.272322 -289.796221) (xy 181.257491 -289.841849) (xy 181.235705 -289.884595) (xy 181.2075 -289.923407)
			(xy 181.173572 -289.95733) (xy 181.134756 -289.985529) (xy 181.092006 -290.007308) (xy 181.046376 -290.022133)
			(xy 180.998989 -290.029638) (xy 180.975 -290.030154) (xy 180.951339 -290.029702) (xy 180.904586 -290.022389)
			(xy 180.859521 -290.007953) (xy 180.81722 -289.98674) (xy 180.778697 -289.959257) (xy 180.744874 -289.926162)
			(xy 180.716559 -289.888247) (xy 180.69443 -289.846418) (xy 180.679016 -289.801677) (xy 180.670687 -289.755095)
			(xy 180.669692 -289.73145) (xy 180.669692 -289.724592) (xy 180.670118 -289.70141) (xy 180.677123 -289.655579)
			(xy 180.690987 -289.611336) (xy 180.711388 -289.569703) (xy 180.737858 -289.531638) (xy 180.753512 -289.514534)
			(xy 180.75656 -289.511486) (xy 180.766974 -289.495992) (xy 180.771546 -289.485578) (xy 180.774064 -289.477317)
			(xy 180.77406 -289.460058) (xy 180.771546 -289.451796) (xy 180.75783 -289.431222) (xy 180.756814 -289.430206)
			(xy 180.751988 -289.425888) (xy 180.73497 -289.419538) (xy 180.297836 -289.419538) (xy 180.295042 -289.41903)
			(xy 180.281326 -289.418014) (xy 180.280818 -289.418014) (xy 180.274929 -289.417646) (xy 180.26325 -289.419303)
			(xy 180.257704 -289.421316) (xy 180.253386 -289.423348) (xy 180.248051 -289.426222) (xy 180.238803 -289.434048)
			(xy 180.235098 -289.438842) (xy 180.231288 -289.444176) (xy 180.226462 -289.456622) (xy 180.225954 -289.463226)
			(xy 180.225466 -289.469854) (xy 180.227513 -289.482979) (xy 180.230018 -289.489134) (xy 180.231034 -289.49142)
			(xy 180.235098 -289.49904) (xy 180.243734 -289.51174) (xy 180.246782 -289.515042) (xy 180.262389 -289.53214)
			(xy 180.288781 -289.570171) (xy 180.309118 -289.611756) (xy 180.322935 -289.655937) (xy 180.329912 -289.7017)
			(xy 180.330348 -289.724846) (xy 180.329874 -289.748836) (xy 180.322362 -289.796224) (xy 180.307531 -289.841855)
			(xy 180.285746 -289.884604) (xy 180.257543 -289.92342) (xy 180.223615 -289.957347) (xy 180.184799 -289.985549)
			(xy 180.142049 -290.007334) (xy 180.096419 -290.022164) (xy 180.04903 -290.029674) (xy 180.02504 -290.030154)
			(xy 180.001377 -290.029705) (xy 179.95462 -290.022397) (xy 179.909549 -290.007965) (xy 179.867243 -289.986754)
			(xy 179.828715 -289.959272) (xy 179.794886 -289.926176) (xy 179.766567 -289.888259) (xy 179.744434 -289.846428)
			(xy 179.729018 -289.801684) (xy 179.720687 -289.755097) (xy 179.719732 -289.73145) (xy 179.719732 -289.724592)
			(xy 179.720158 -289.70141) (xy 179.727162 -289.655577) (xy 179.741023 -289.611333) (xy 179.761422 -289.569697)
			(xy 179.787888 -289.531629) (xy 179.803552 -289.514534) (xy 179.8066 -289.511486) (xy 179.817014 -289.495992)
			(xy 179.821586 -289.485578) (xy 179.824102 -289.477317) (xy 179.824098 -289.460058) (xy 179.821586 -289.451796)
			(xy 179.80787 -289.431222) (xy 179.806854 -289.430206) (xy 179.802028 -289.425888) (xy 179.78501 -289.419538)
			(xy 179.347876 -289.419538) (xy 179.345082 -289.41903) (xy 179.331366 -289.418014) (xy 179.330858 -289.418014)
			(xy 179.32497 -289.417653) (xy 179.313296 -289.419323) (xy 179.307744 -289.421316) (xy 179.303426 -289.423348)
			(xy 179.298095 -289.426227) (xy 179.288856 -289.434059) (xy 179.285138 -289.438842) (xy 179.281328 -289.444176)
			(xy 179.276502 -289.456622) (xy 179.275994 -289.463226) (xy 179.275505 -289.469854) (xy 179.277554 -289.482979)
			(xy 179.280058 -289.489134) (xy 179.281074 -289.49142) (xy 179.285138 -289.49904) (xy 179.293774 -289.51174)
			(xy 179.296822 -289.515042) (xy 179.312427 -289.532141) (xy 179.338815 -289.570173) (xy 179.359151 -289.611758)
			(xy 179.372965 -289.655939) (xy 179.379941 -289.701701) (xy 179.380388 -289.724846) (xy 179.379914 -289.748834)
			(xy 179.372402 -289.796219) (xy 179.35757 -289.841846) (xy 179.335784 -289.884591) (xy 179.307579 -289.923401)
			(xy 179.273651 -289.957322) (xy 179.234834 -289.985518) (xy 179.192085 -290.007296) (xy 179.146455 -290.022117)
			(xy 179.099068 -290.029619) (xy 179.07508 -290.030154) (xy 179.051415 -290.029708) (xy 179.004653 -290.022405)
			(xy 178.959577 -290.007976) (xy 178.917265 -289.986767) (xy 178.878732 -289.959286) (xy 178.844898 -289.92619)
			(xy 178.816574 -289.888271) (xy 178.794438 -289.846438) (xy 178.77902 -289.80169) (xy 178.770688 -289.7551)
			(xy 178.769772 -289.73145) (xy 178.769772 -289.724592) (xy 178.770198 -289.70141) (xy 178.777203 -289.655578)
			(xy 178.791065 -289.611335) (xy 178.811466 -289.569701) (xy 178.837935 -289.531635) (xy 178.853592 -289.514534)
			(xy 178.85664 -289.511486) (xy 178.867054 -289.495992) (xy 178.871626 -289.485578) (xy 178.874144 -289.477318)
			(xy 178.87414 -289.460058) (xy 178.871626 -289.451796) (xy 178.85791 -289.431222) (xy 178.856894 -289.430206)
			(xy 178.852068 -289.425888) (xy 178.83505 -289.419538) (xy 178.397662 -289.419538) (xy 178.394868 -289.41903)
			(xy 178.381152 -289.418014) (xy 178.380644 -289.418014) (xy 178.374756 -289.417655) (xy 178.363084 -289.419328)
			(xy 178.35753 -289.421316) (xy 178.353212 -289.423348) (xy 178.347875 -289.42622) (xy 178.338624 -289.434043)
			(xy 178.334924 -289.438842) (xy 178.331114 -289.444176) (xy 178.326288 -289.456622) (xy 178.32578 -289.463226)
			(xy 178.325291 -289.469854) (xy 178.32734 -289.482979) (xy 178.329844 -289.489134) (xy 178.33086 -289.49142)
			(xy 178.334924 -289.49904) (xy 178.34356 -289.51174) (xy 178.346608 -289.515042) (xy 178.362214 -289.53214)
			(xy 178.388603 -289.570172) (xy 178.408939 -289.611757) (xy 178.422755 -289.655938) (xy 178.429731 -289.7017)
			(xy 178.430174 -289.724846) (xy 178.4297 -289.748834) (xy 178.422188 -289.796218) (xy 178.407356 -289.841844)
			(xy 178.385569 -289.884588) (xy 178.357365 -289.923397) (xy 178.323436 -289.957317) (xy 178.284619 -289.985511)
			(xy 178.24187 -290.007287) (xy 178.19624 -290.022107) (xy 178.148854 -290.029606) (xy 178.124866 -290.030154)
			(xy 178.101202 -290.029707) (xy 178.054441 -290.022402) (xy 178.009367 -290.007972) (xy 177.967058 -289.986763)
			(xy 177.928526 -289.959281) (xy 177.894694 -289.926185) (xy 177.866372 -289.888267) (xy 177.844237 -289.846434)
			(xy 177.828819 -289.801688) (xy 177.820488 -289.755099) (xy 177.819558 -289.73145) (xy 177.819558 -289.724592)
			(xy 177.819984 -289.70141) (xy 177.826988 -289.655578) (xy 177.840851 -289.611335) (xy 177.861251 -289.5697)
			(xy 177.887718 -289.531633) (xy 177.903378 -289.514534) (xy 177.906426 -289.511486) (xy 177.91684 -289.495992)
			(xy 177.921412 -289.485578) (xy 177.923931 -289.477318) (xy 177.923927 -289.460058) (xy 177.921412 -289.451796)
			(xy 177.907696 -289.431222) (xy 177.90668 -289.430206) (xy 177.901854 -289.425888) (xy 177.884836 -289.419538)
			(xy 177.447702 -289.419538) (xy 177.444908 -289.41903) (xy 177.431192 -289.418014) (xy 177.430684 -289.418014)
			(xy 177.424796 -289.41765) (xy 177.413119 -289.419314) (xy 177.40757 -289.421316) (xy 177.403252 -289.423348)
			(xy 177.397919 -289.426225) (xy 177.388677 -289.434054) (xy 177.384964 -289.438842) (xy 177.381154 -289.444176)
			(xy 177.376328 -289.456622) (xy 177.37582 -289.463226) (xy 177.375331 -289.469853) (xy 177.377381 -289.482978)
			(xy 177.379884 -289.489134) (xy 177.3809 -289.49142) (xy 177.384964 -289.49904) (xy 177.3936 -289.51174)
			(xy 177.396648 -289.515042) (xy 177.412252 -289.532141) (xy 177.438638 -289.570174) (xy 177.458971 -289.611759)
			(xy 177.472785 -289.65594) (xy 177.47976 -289.701701) (xy 177.480214 -289.724846) (xy 177.47974 -289.748835)
			(xy 177.472228 -289.796222) (xy 177.457397 -289.84185) (xy 177.435611 -289.884596) (xy 177.407407 -289.923409)
			(xy 177.373479 -289.957333) (xy 177.334662 -289.985532) (xy 177.291913 -290.007312) (xy 177.246283 -290.022138)
			(xy 177.198895 -290.029643) (xy 177.174906 -290.030154) (xy 177.151245 -290.029703) (xy 177.104491 -290.02239)
			(xy 177.059425 -290.007955) (xy 177.017124 -289.986742) (xy 176.9786 -289.959259) (xy 176.944776 -289.926164)
			(xy 176.91646 -289.888248) (xy 176.89433 -289.84642) (xy 176.878917 -289.801678) (xy 176.870587 -289.755095)
			(xy 176.869598 -289.73145) (xy 176.869598 -289.724592) (xy 176.870024 -289.70141) (xy 176.877029 -289.655579)
			(xy 176.890893 -289.611337) (xy 176.911295 -289.569703) (xy 176.937765 -289.531639) (xy 176.953418 -289.514534)
			(xy 176.956466 -289.511486) (xy 176.96688 -289.495992) (xy 176.971452 -289.485578) (xy 176.97397 -289.477317)
			(xy 176.973966 -289.460058) (xy 176.971452 -289.451796) (xy 176.957736 -289.431222) (xy 176.95672 -289.430206)
			(xy 176.951894 -289.425888) (xy 176.934876 -289.419538) (xy 176.497742 -289.419538) (xy 176.494948 -289.41903)
			(xy 176.481232 -289.418014) (xy 176.480724 -289.418014) (xy 176.474837 -289.417657) (xy 176.463166 -289.419334)
			(xy 176.45761 -289.421316) (xy 176.453292 -289.423348) (xy 176.447957 -289.426221) (xy 176.438708 -289.434047)
			(xy 176.435004 -289.438842) (xy 176.431194 -289.444176) (xy 176.426368 -289.456622) (xy 176.42586 -289.463226)
			(xy 176.425372 -289.469854) (xy 176.427419 -289.482979) (xy 176.429924 -289.489134) (xy 176.43094 -289.49142)
			(xy 176.435004 -289.49904) (xy 176.44364 -289.51174) (xy 176.446688 -289.515042) (xy 176.462295 -289.53214)
			(xy 176.488686 -289.570171) (xy 176.509023 -289.611756) (xy 176.522839 -289.655938) (xy 176.529817 -289.7017)
			(xy 176.530254 -289.724846) (xy 176.52978 -289.748836) (xy 176.522268 -289.796225) (xy 176.507438 -289.841856)
			(xy 176.485652 -289.884605) (xy 176.457449 -289.923422) (xy 176.423522 -289.957349) (xy 176.384705 -289.985552)
			(xy 176.341956 -290.007338) (xy 176.296325 -290.022168) (xy 176.248936 -290.02968) (xy 176.224946 -290.030154)
			(xy 176.201283 -290.029706) (xy 176.154525 -290.022398) (xy 176.109453 -290.007966) (xy 176.067146 -289.986756)
			(xy 176.028617 -289.959274) (xy 175.994788 -289.926178) (xy 175.966468 -289.888261) (xy 175.944335 -289.846429)
			(xy 175.928918 -289.801685) (xy 175.920587 -289.755098) (xy 175.919638 -289.73145) (xy 175.919638 -289.724592)
			(xy 175.920064 -289.70141) (xy 175.927068 -289.655577) (xy 175.94093 -289.611334) (xy 175.961329 -289.569698)
			(xy 175.987795 -289.53163) (xy 176.003458 -289.514534) (xy 176.006506 -289.511486) (xy 176.01692 -289.495992)
			(xy 176.021492 -289.485578) (xy 176.024008 -289.477317) (xy 176.024004 -289.460058) (xy 176.021492 -289.451796)
			(xy 176.007776 -289.431222) (xy 176.00676 -289.430206) (xy 176.001934 -289.425888) (xy 175.984916 -289.419538)
			(xy 174.597822 -289.419538) (xy 174.595028 -289.41903) (xy 174.581312 -289.418014) (xy 174.580804 -289.418014)
			(xy 174.574915 -289.417648) (xy 174.563237 -289.419308) (xy 174.55769 -289.421316) (xy 174.553372 -289.423348)
			(xy 174.548038 -289.426223) (xy 174.538792 -289.43405) (xy 174.535084 -289.438842) (xy 174.531274 -289.444176)
			(xy 174.526448 -289.456622) (xy 174.52594 -289.463226) (xy 174.525451 -289.469854) (xy 174.527498 -289.48298)
			(xy 174.530004 -289.489134) (xy 174.53102 -289.49142) (xy 174.535084 -289.49904) (xy 174.54372 -289.51174)
			(xy 174.546768 -289.515042) (xy 174.562376 -289.532139) (xy 174.588768 -289.570171) (xy 174.609107 -289.611755)
			(xy 174.622924 -289.655937) (xy 174.629902 -289.7017) (xy 174.630334 -289.724846) (xy 174.62986 -289.748836)
			(xy 174.622348 -289.796223) (xy 174.607517 -289.841853) (xy 174.585732 -289.884601) (xy 174.557528 -289.923415)
			(xy 174.5236 -289.957341) (xy 174.484784 -289.985542) (xy 174.442034 -290.007325) (xy 174.396404 -290.022153)
			(xy 174.349016 -290.029662) (xy 174.325026 -290.030154) (xy 174.301364 -290.029704) (xy 174.254608 -290.022394)
			(xy 174.209539 -290.007961) (xy 174.167235 -289.986749) (xy 174.128709 -289.959267) (xy 174.094882 -289.926171)
			(xy 174.066564 -289.888255) (xy 174.044433 -289.846424) (xy 174.029017 -289.801681) (xy 174.020687 -289.755096)
			(xy 174.019718 -289.73145) (xy 174.019718 -289.724592) (xy 174.020143 -289.701409) (xy 174.027147 -289.655577)
			(xy 174.041008 -289.611332) (xy 174.061406 -289.569696) (xy 174.087871 -289.531626) (xy 174.103538 -289.514534)
			(xy 174.106586 -289.511486) (xy 174.117 -289.495992) (xy 174.121572 -289.485578) (xy 174.124089 -289.477317)
			(xy 174.124085 -289.460058) (xy 174.121572 -289.451796) (xy 174.107856 -289.431222) (xy 174.10684 -289.430206)
			(xy 174.102014 -289.425888) (xy 174.084996 -289.419538) (xy 173.647862 -289.419538) (xy 173.645068 -289.41903)
			(xy 173.631352 -289.418014) (xy 173.630844 -289.418014) (xy 173.624956 -289.417655) (xy 173.613284 -289.419328)
			(xy 173.60773 -289.421316) (xy 173.603412 -289.423348) (xy 173.598075 -289.42622) (xy 173.588824 -289.434043)
			(xy 173.585124 -289.438842) (xy 173.581314 -289.444176) (xy 173.576488 -289.456622) (xy 173.57598 -289.463226)
			(xy 173.575491 -289.469854) (xy 173.57754 -289.482979) (xy 173.580044 -289.489134) (xy 173.58106 -289.49142)
			(xy 173.585124 -289.49904) (xy 173.59376 -289.51174) (xy 173.596808 -289.515042) (xy 173.612414 -289.53214)
			(xy 173.638803 -289.570172) (xy 173.659139 -289.611757) (xy 173.672955 -289.655938) (xy 173.679931 -289.7017)
			(xy 173.680374 -289.724846) (xy 173.6799 -289.748834) (xy 173.672388 -289.796218) (xy 173.657556 -289.841844)
			(xy 173.635769 -289.884588) (xy 173.607565 -289.923397) (xy 173.573636 -289.957317) (xy 173.534819 -289.985511)
			(xy 173.49207 -290.007287) (xy 173.44644 -290.022107) (xy 173.399054 -290.029606) (xy 173.375066 -290.030154)
			(xy 173.351402 -290.029707) (xy 173.304641 -290.022402) (xy 173.259567 -290.007972) (xy 173.217258 -289.986763)
			(xy 173.178726 -289.959281) (xy 173.144894 -289.926185) (xy 173.116572 -289.888267) (xy 173.094437 -289.846434)
			(xy 173.079019 -289.801688) (xy 173.070688 -289.755099) (xy 173.069758 -289.73145) (xy 173.069758 -289.724592)
			(xy 173.070184 -289.70141) (xy 173.077188 -289.655578) (xy 173.091051 -289.611335) (xy 173.111451 -289.5697)
			(xy 173.137918 -289.531633) (xy 173.153578 -289.514534) (xy 173.156626 -289.511486) (xy 173.16704 -289.495992)
			(xy 173.171612 -289.485578) (xy 173.174131 -289.477318) (xy 173.174127 -289.460058) (xy 173.171612 -289.451796)
			(xy 173.157896 -289.431222) (xy 173.15688 -289.430206) (xy 173.152054 -289.425888) (xy 173.135036 -289.419538)
			(xy 172.697648 -289.419538) (xy 172.694854 -289.41903) (xy 172.681138 -289.418014) (xy 172.68063 -289.418014)
			(xy 172.674743 -289.417657) (xy 172.663071 -289.419332) (xy 172.657516 -289.421316) (xy 172.653198 -289.423348)
			(xy 172.647862 -289.426221) (xy 172.638613 -289.434045) (xy 172.63491 -289.438842) (xy 172.6311 -289.444176)
			(xy 172.626274 -289.456622) (xy 172.625766 -289.463226) (xy 172.625277 -289.469854) (xy 172.627325 -289.482979)
			(xy 172.62983 -289.489134) (xy 172.630846 -289.49142) (xy 172.63491 -289.49904) (xy 172.643546 -289.51174)
			(xy 172.646594 -289.515042) (xy 172.6622 -289.53214) (xy 172.688591 -289.570172) (xy 172.708928 -289.611756)
			(xy 172.722744 -289.655938) (xy 172.729721 -289.7017) (xy 172.73016 -289.724846) (xy 172.72971 -289.748835)
			(xy 172.722198 -289.796223) (xy 172.707364 -289.841851) (xy 172.685576 -289.884597) (xy 172.657369 -289.923409)
			(xy 172.623437 -289.95733) (xy 172.584617 -289.985525) (xy 172.541864 -290.0073) (xy 172.496231 -290.02212)
			(xy 172.448842 -290.029618) (xy 172.424852 -290.030154) (xy 172.401189 -290.029706) (xy 172.35443 -290.022399)
			(xy 172.309357 -290.007968) (xy 172.26705 -289.986758) (xy 172.22852 -289.959276) (xy 172.19469 -289.92618)
			(xy 172.166369 -289.888263) (xy 172.144235 -289.846431) (xy 172.128819 -289.801686) (xy 172.120487 -289.755098)
			(xy 172.119544 -289.73145) (xy 172.119544 -289.724592) (xy 172.11997 -289.70141) (xy 172.126974 -289.655578)
			(xy 172.140836 -289.611334) (xy 172.161235 -289.569698) (xy 172.187702 -289.53163) (xy 172.203364 -289.514534)
			(xy 172.206412 -289.511486) (xy 172.216826 -289.495992) (xy 172.221398 -289.485578) (xy 172.223914 -289.477317)
			(xy 172.22391 -289.460058) (xy 172.221398 -289.451796) (xy 172.207682 -289.431222) (xy 172.206666 -289.430206)
			(xy 172.20184 -289.425888) (xy 172.184822 -289.419538) (xy 171.747688 -289.419538) (xy 171.744894 -289.41903)
			(xy 171.731178 -289.418014) (xy 171.73067 -289.418014) (xy 171.724782 -289.417652) (xy 171.713107 -289.419319)
			(xy 171.707556 -289.421316) (xy 171.703238 -289.423348) (xy 171.697906 -289.426226) (xy 171.688666 -289.434056)
			(xy 171.68495 -289.438842) (xy 171.68114 -289.444176) (xy 171.676314 -289.456622) (xy 171.675806 -289.463226)
			(xy 171.675317 -289.469854) (xy 171.677367 -289.482979) (xy 171.67987 -289.489134) (xy 171.680886 -289.49142)
			(xy 171.68495 -289.49904) (xy 171.693586 -289.51174) (xy 171.696634 -289.515042) (xy 171.712239 -289.532141)
			(xy 171.738626 -289.570174) (xy 171.75896 -289.611758) (xy 171.772774 -289.655939) (xy 171.77975 -289.701701)
			(xy 171.7802 -289.724846) (xy 171.779726 -289.748835) (xy 171.772214 -289.79622) (xy 171.757383 -289.841848)
			(xy 171.735596 -289.884593) (xy 171.707392 -289.923405) (xy 171.673464 -289.957327) (xy 171.634647 -289.985525)
			(xy 171.591898 -290.007303) (xy 171.546268 -290.022127) (xy 171.498881 -290.02963) (xy 171.474892 -290.030154)
			(xy 171.451227 -290.029709) (xy 171.404463 -290.022407) (xy 171.359385 -290.00798) (xy 171.317072 -289.986771)
			(xy 171.278537 -289.95929) (xy 171.244702 -289.926194) (xy 171.216377 -289.888275) (xy 171.19424 -289.846441)
			(xy 171.17882 -289.801692) (xy 171.170488 -289.755101) (xy 171.169584 -289.73145) (xy 171.169584 -289.724592)
			(xy 171.17001 -289.70141) (xy 171.177015 -289.655578) (xy 171.190878 -289.611336) (xy 171.211279 -289.569702)
			(xy 171.237749 -289.531636) (xy 171.253404 -289.514534) (xy 171.256452 -289.511486) (xy 171.266866 -289.495992)
			(xy 171.271438 -289.485578) (xy 171.273956 -289.477318) (xy 171.273952 -289.460058) (xy 171.271438 -289.451796)
			(xy 171.257722 -289.431222) (xy 171.256706 -289.430206) (xy 171.25188 -289.425888) (xy 171.234862 -289.419538)
			(xy 170.797728 -289.419538) (xy 170.794934 -289.41903) (xy 170.781218 -289.418014) (xy 170.78071 -289.418014)
			(xy 170.774821 -289.417647) (xy 170.763143 -289.419306) (xy 170.757596 -289.421316) (xy 170.753278 -289.423348)
			(xy 170.747944 -289.426223) (xy 170.738697 -289.434049) (xy 170.73499 -289.438842) (xy 170.73118 -289.444176)
			(xy 170.726354 -289.456622) (xy 170.725846 -289.463226) (xy 170.725357 -289.469854) (xy 170.727404 -289.48298)
			(xy 170.72991 -289.489134) (xy 170.730926 -289.49142) (xy 170.73499 -289.49904) (xy 170.743626 -289.51174)
			(xy 170.746674 -289.515042) (xy 170.762281 -289.53214) (xy 170.788674 -289.570171) (xy 170.809012 -289.611755)
			(xy 170.822829 -289.655937) (xy 170.829806 -289.7017) (xy 170.83024 -289.724846) (xy 170.829766 -289.748836)
			(xy 170.822254 -289.796224) (xy 170.807423 -289.841854) (xy 170.785638 -289.884602) (xy 170.757434 -289.923417)
			(xy 170.723507 -289.957343) (xy 170.68469 -289.985545) (xy 170.641941 -290.007329) (xy 170.59631 -290.022158)
			(xy 170.548922 -290.029667) (xy 170.524932 -290.030154) (xy 170.50127 -290.029705) (xy 170.454513 -290.022396)
			(xy 170.409443 -290.007962) (xy 170.367138 -289.986751) (xy 170.328611 -289.959269) (xy 170.294784 -289.926173)
			(xy 170.266465 -289.888256) (xy 170.244333 -289.846426) (xy 170.228918 -289.801682) (xy 170.220587 -289.755097)
			(xy 170.219624 -289.73145) (xy 170.219624 -289.724592) (xy 170.22005 -289.70141) (xy 170.227054 -289.655577)
			(xy 170.240915 -289.611333) (xy 170.261313 -289.569696) (xy 170.287779 -289.531627) (xy 170.303444 -289.514534)
			(xy 170.306492 -289.511486) (xy 170.316906 -289.495992) (xy 170.321478 -289.485578) (xy 170.323995 -289.477317)
			(xy 170.323991 -289.460058) (xy 170.321478 -289.451796) (xy 170.307762 -289.431222) (xy 170.306746 -289.430206)
			(xy 170.30192 -289.425888) (xy 170.284902 -289.419538) (xy 169.847768 -289.419538) (xy 169.844974 -289.41903)
			(xy 169.831258 -289.418014) (xy 169.83075 -289.418014) (xy 169.824862 -289.417654) (xy 169.813189 -289.419326)
			(xy 169.807636 -289.421316) (xy 169.803318 -289.423348) (xy 169.797981 -289.426219) (xy 169.788728 -289.434042)
			(xy 169.78503 -289.438842) (xy 169.78122 -289.444176) (xy 169.776394 -289.456622) (xy 169.775886 -289.463226)
			(xy 169.775397 -289.469854) (xy 169.777446 -289.482979) (xy 169.77995 -289.489134) (xy 169.780966 -289.49142)
			(xy 169.78503 -289.49904) (xy 169.793666 -289.51174) (xy 169.796714 -289.515042) (xy 169.81232 -289.532141)
			(xy 169.838708 -289.570173) (xy 169.859044 -289.611757) (xy 169.872859 -289.655939) (xy 169.879836 -289.7017)
			(xy 169.88028 -289.724846) (xy 169.879806 -289.748834) (xy 169.872294 -289.796219) (xy 169.857462 -289.841845)
			(xy 169.835676 -289.884589) (xy 169.807471 -289.923399) (xy 169.773543 -289.957319) (xy 169.734726 -289.985514)
			(xy 169.691976 -290.00729) (xy 169.646346 -290.022111) (xy 169.59896 -290.029612) (xy 169.574972 -290.030154)
			(xy 169.551308 -290.029708) (xy 169.504546 -290.022403) (xy 169.459471 -290.007974) (xy 169.417161 -289.986765)
			(xy 169.378628 -289.959283) (xy 169.344796 -289.926187) (xy 169.316473 -289.888269) (xy 169.294337 -289.846436)
			(xy 169.278919 -289.801689) (xy 169.270588 -289.7551) (xy 169.269664 -289.73145) (xy 169.269664 -289.724592)
			(xy 169.27009 -289.70141) (xy 169.277095 -289.655578) (xy 169.290957 -289.611335) (xy 169.311357 -289.5697)
			(xy 169.337825 -289.531633) (xy 169.353484 -289.514534) (xy 169.356532 -289.511486) (xy 169.366946 -289.495992)
			(xy 169.371518 -289.485578) (xy 169.374037 -289.477318) (xy 169.374033 -289.460058) (xy 169.371518 -289.451796)
			(xy 169.357802 -289.431222) (xy 169.356786 -289.430206) (xy 169.35196 -289.425888) (xy 169.334942 -289.419538)
			(xy 168.897808 -289.419538) (xy 168.895014 -289.41903) (xy 168.881298 -289.418014) (xy 168.88079 -289.418014)
			(xy 168.874902 -289.41765) (xy 168.863225 -289.419312) (xy 168.857676 -289.421316) (xy 168.853358 -289.423348)
			(xy 168.848025 -289.426224) (xy 168.838781 -289.434053) (xy 168.83507 -289.438842) (xy 168.83126 -289.444176)
			(xy 168.826434 -289.456622) (xy 168.825926 -289.463226) (xy 168.825437 -289.469854) (xy 168.827484 -289.48298)
			(xy 168.82999 -289.489134) (xy 168.831006 -289.49142) (xy 168.83507 -289.49904) (xy 168.843706 -289.51174)
			(xy 168.846754 -289.515042) (xy 168.862358 -289.532141) (xy 168.888743 -289.570175) (xy 168.909076 -289.611759)
			(xy 168.922889 -289.65594) (xy 168.929865 -289.701701) (xy 168.93032 -289.724846) (xy 168.929846 -289.748835)
			(xy 168.922334 -289.796222) (xy 168.907503 -289.841851) (xy 168.885717 -289.884598) (xy 168.857513 -289.923411)
			(xy 168.823585 -289.957335) (xy 168.784769 -289.985535) (xy 168.742019 -290.007316) (xy 168.696389 -290.022142)
			(xy 168.649001 -290.029649) (xy 168.625012 -290.030154) (xy 168.601351 -290.029703) (xy 168.554596 -290.022392)
			(xy 168.509529 -290.007957) (xy 168.467227 -289.986744) (xy 168.428703 -289.959261) (xy 168.394878 -289.926166)
			(xy 168.366561 -289.88825) (xy 168.344431 -289.846421) (xy 168.329017 -289.801679) (xy 168.320687 -289.755095)
			(xy 168.319704 -289.73145) (xy 168.319704 -289.724592) (xy 168.32013 -289.70141) (xy 168.327135 -289.655579)
			(xy 168.340999 -289.611337) (xy 168.361402 -289.569704) (xy 168.387872 -289.531639) (xy 168.403524 -289.514534)
			(xy 168.406572 -289.511486) (xy 168.416986 -289.495992) (xy 168.421558 -289.485578) (xy 168.424076 -289.477317)
			(xy 168.424071 -289.460058) (xy 168.421558 -289.451796) (xy 168.407842 -289.431222) (xy 168.406826 -289.430206)
			(xy 168.402 -289.425888) (xy 168.384982 -289.419538) (xy 167.947848 -289.419538) (xy 167.945054 -289.41903)
			(xy 167.931338 -289.418014) (xy 167.93083 -289.418014) (xy 167.924943 -289.417657) (xy 167.913271 -289.419332)
			(xy 167.907716 -289.421316) (xy 167.903398 -289.423348) (xy 167.898062 -289.426221) (xy 167.888813 -289.434045)
			(xy 167.88511 -289.438842) (xy 167.8813 -289.444176) (xy 167.876474 -289.456622) (xy 167.875966 -289.463226)
			(xy 167.875477 -289.469854) (xy 167.877525 -289.482979) (xy 167.88003 -289.489134) (xy 167.881046 -289.49142)
			(xy 167.88511 -289.49904) (xy 167.893746 -289.51174) (xy 167.896794 -289.515042) (xy 167.9124 -289.53214)
			(xy 167.938791 -289.570172) (xy 167.959128 -289.611756) (xy 167.972944 -289.655938) (xy 167.979921 -289.7017)
			(xy 167.98036 -289.724846) (xy 167.97991 -289.748835) (xy 167.972398 -289.796223) (xy 167.957564 -289.841851)
			(xy 167.935776 -289.884597) (xy 167.907569 -289.923409) (xy 167.873637 -289.95733) (xy 167.834817 -289.985525)
			(xy 167.792064 -290.0073) (xy 167.746431 -290.02212) (xy 167.699042 -290.029618) (xy 167.675052 -290.030154)
			(xy 167.651389 -290.029706) (xy 167.60463 -290.022399) (xy 167.559557 -290.007968) (xy 167.51725 -289.986758)
			(xy 167.47872 -289.959276) (xy 167.44489 -289.92618) (xy 167.416569 -289.888263) (xy 167.394435 -289.846431)
			(xy 167.379019 -289.801686) (xy 167.370687 -289.755098) (xy 167.369744 -289.73145) (xy 167.369744 -289.724592)
			(xy 167.37017 -289.70141) (xy 167.377174 -289.655578) (xy 167.391036 -289.611334) (xy 167.411435 -289.569698)
			(xy 167.437902 -289.53163) (xy 167.453564 -289.514534) (xy 167.456612 -289.511486) (xy 167.467026 -289.495992)
			(xy 167.471598 -289.485578) (xy 167.474114 -289.477317) (xy 167.47411 -289.460058) (xy 167.471598 -289.451796)
			(xy 167.457882 -289.431222) (xy 167.456866 -289.430206) (xy 167.45204 -289.425888) (xy 167.435022 -289.419538)
			(xy 166.997888 -289.419538) (xy 166.995094 -289.41903) (xy 166.981378 -289.418014) (xy 166.98087 -289.418014)
			(xy 166.974982 -289.417652) (xy 166.963307 -289.419319) (xy 166.957756 -289.421316) (xy 166.953438 -289.423348)
			(xy 166.948106 -289.426226) (xy 166.938866 -289.434056) (xy 166.93515 -289.438842) (xy 166.93134 -289.444176)
			(xy 166.926514 -289.456622) (xy 166.926006 -289.463226) (xy 166.925517 -289.469854) (xy 166.927567 -289.482979)
			(xy 166.93007 -289.489134) (xy 166.931086 -289.49142) (xy 166.93515 -289.49904) (xy 166.943786 -289.51174)
			(xy 166.946834 -289.515042) (xy 166.962439 -289.532141) (xy 166.988826 -289.570174) (xy 167.00916 -289.611758)
			(xy 167.022974 -289.655939) (xy 167.02995 -289.701701) (xy 167.0304 -289.724846) (xy 167.029926 -289.748835)
			(xy 167.022414 -289.79622) (xy 167.007583 -289.841848) (xy 166.985796 -289.884593) (xy 166.957592 -289.923405)
			(xy 166.923664 -289.957327) (xy 166.884847 -289.985525) (xy 166.842098 -290.007303) (xy 166.796468 -290.022127)
			(xy 166.749081 -290.02963) (xy 166.725092 -290.030154) (xy 166.701427 -290.029709) (xy 166.654663 -290.022407)
			(xy 166.609585 -290.00798) (xy 166.567272 -289.986771) (xy 166.528737 -289.95929) (xy 166.494902 -289.926194)
			(xy 166.466577 -289.888275) (xy 166.44444 -289.846441) (xy 166.42902 -289.801692) (xy 166.420688 -289.755101)
			(xy 166.419784 -289.73145) (xy 166.419784 -289.724592) (xy 166.42021 -289.70141) (xy 166.427215 -289.655578)
			(xy 166.441078 -289.611336) (xy 166.461479 -289.569702) (xy 166.487949 -289.531636) (xy 166.503604 -289.514534)
			(xy 166.506652 -289.511486) (xy 166.517066 -289.495992) (xy 166.521638 -289.485578) (xy 166.524156 -289.477318)
			(xy 166.524152 -289.460058) (xy 166.521638 -289.451796) (xy 166.507922 -289.431222) (xy 166.506906 -289.430206)
			(xy 166.50208 -289.425888) (xy 166.485062 -289.419538) (xy 166.12616 -289.419538) (xy 166.119048 -289.419792)
			(xy 166.108484 -289.421993) (xy 166.090468 -289.433833) (xy 166.08425 -289.442652) (xy 166.060882 -289.482784)
			(xy 166.060882 -289.483292) (xy 166.039038 -289.521392) (xy 166.03589 -289.527326) (xy 166.032539 -289.54033)
			(xy 166.032434 -289.547046) (xy 166.032434 -289.560254) (xy 166.035482 -289.565588) (xy 166.039038 -289.571938)
			(xy 166.05197 -289.595325) (xy 166.070327 -289.64551) (xy 166.079652 -289.698128) (xy 166.080186 -289.724846)
			(xy 166.079664 -289.750101) (xy 166.071351 -289.799923) (xy 166.05495 -289.847697) (xy 166.030909 -289.89212)
			(xy 165.999885 -289.93198) (xy 165.962723 -289.96619) (xy 165.920437 -289.993816) (xy 165.874181 -290.014106)
			(xy 165.825216 -290.026506) (xy 165.774878 -290.030677) (xy 165.72454 -290.026506) (xy 165.675575 -290.014106)
			(xy 165.629319 -289.993816) (xy 165.587033 -289.96619) (xy 165.549871 -289.93198) (xy 165.518847 -289.89212)
			(xy 165.494806 -289.847697) (xy 165.478405 -289.799923) (xy 165.470092 -289.750101) (xy 165.46957 -289.724846)
			(xy 165.469709 -289.712083) (xy 165.471873 -289.686649) (xy 165.473888 -289.674046) (xy 165.473634 -289.674046)
			(xy 165.478349 -289.64908) (xy 165.49496 -289.601068) (xy 165.519292 -289.55647) (xy 165.550674 -289.516516)
			(xy 165.588238 -289.482311) (xy 165.630947 -289.454798) (xy 165.677623 -289.434737) (xy 165.726976 -289.422681)
			(xy 165.752272 -289.4203) (xy 165.76167 -289.419538) (xy 165.769798 -289.415728) (xy 165.773876 -289.413733)
			(xy 165.781287 -289.408491) (xy 165.78453 -289.405314) (xy 165.795706 -289.394138) (xy 165.80236 -289.386783)
			(xy 165.809953 -289.368483) (xy 165.810438 -289.358578) (xy 165.810438 -289.348672) (xy 165.803072 -289.330384)
			(xy 165.79596 -289.323272) (xy 165.777094 -289.303069) (xy 165.746252 -289.257202) (xy 165.724161 -289.206537)
			(xy 165.711538 -289.152726) (xy 165.7096 -289.125152) (xy 165.709346 -289.117786) (xy 165.707314 -289.11169)
			(xy 165.706035 -289.108179) (xy 165.70259 -289.101549) (xy 165.700456 -289.098482) (xy 165.6842 -289.07613)
			(xy 165.682013 -289.073148) (xy 165.676906 -289.0678) (xy 165.67404 -289.065462) (xy 165.668706 -289.061398)
			(xy 165.661848 -289.058604) (xy 165.638983 -289.048966) (xy 165.596465 -289.023389) (xy 165.558631 -288.991287)
			(xy 165.526473 -288.9535) (xy 165.500834 -288.91102) (xy 165.49116 -288.88817) (xy 165.49116 -288.887916)
			(xy 165.488366 -288.881058) (xy 165.484302 -288.875724) (xy 165.481967 -288.872857) (xy 165.476609 -288.86776)
			(xy 165.473634 -288.865564) (xy 165.451282 -288.849308) (xy 165.448211 -288.84718) (xy 165.441579 -288.843743)
			(xy 165.438074 -288.84245) (xy 165.431978 -288.840418) (xy 165.424612 -288.840164) (xy 165.401465 -288.838511)
			(xy 165.356024 -288.829099) (xy 165.312523 -288.812943) (xy 165.292024 -288.802064) (xy 165.282995 -288.797006)
			(xy 165.265579 -288.785823) (xy 165.257226 -288.779712) (xy 165.246812 -288.771584) (xy 165.226746 -288.753804)
			(xy 165.226238 -288.753296) (xy 165.218883 -288.746823) (xy 165.200721 -288.739523) (xy 165.190932 -288.739072)
			(xy 165.18128 -288.739072) (xy 165.162992 -288.746692) (xy 165.14445 -288.765234) (xy 165.14129 -288.768491)
			(xy 165.136049 -288.775899) (xy 165.134036 -288.779966) (xy 165.130226 -288.788094) (xy 165.129464 -288.797492)
			(xy 165.129464 -288.797746) (xy 165.127068 -288.823034) (xy 165.11495 -288.872361) (xy 165.094833 -288.919001)
			(xy 165.067272 -288.961667) (xy 165.033029 -288.999182) (xy 164.993048 -289.030511) (xy 164.948432 -289.054788)
			(xy 164.900413 -289.071345) (xy 164.850315 -289.079723) (xy 164.824918 -289.080194) (xy 164.800924 -289.079749)
			(xy 164.753527 -289.072245) (xy 164.707888 -289.057417) (xy 164.665131 -289.035633) (xy 164.626308 -289.007427)
			(xy 164.592375 -288.973495) (xy 164.564169 -288.934673) (xy 164.542384 -288.891915) (xy 164.527556 -288.846276)
			(xy 164.520051 -288.79888) (xy 164.51961 -288.774886) (xy 164.520073 -288.75101) (xy 164.52751 -288.703841)
			(xy 164.5422 -288.658405) (xy 164.563785 -288.61581) (xy 164.591739 -288.577096) (xy 164.62538 -288.543206)
			(xy 164.663887 -288.514967) (xy 164.706321 -288.493068) (xy 164.751648 -288.478042) (xy 164.79876 -288.470257)
			(xy 164.822632 -288.469578) (xy 164.826188 -288.469578) (xy 164.847764 -288.47002) (xy 164.89047 -288.476235)
			(xy 164.931875 -288.488402) (xy 164.951664 -288.49701) (xy 164.952172 -288.497264) (xy 164.95776 -288.499804)
			(xy 164.96919 -288.50209) (xy 164.978762 -288.503468) (xy 164.997727 -288.499759) (xy 165.013963 -288.489281)
			(xy 165.025156 -288.473529) (xy 165.027864 -288.464244) (xy 165.02888 -288.459926) (xy 165.029388 -288.452306)
			(xy 165.029134 -288.449004) (xy 165.028626 -288.4297) (xy 165.028626 -288.239708) (xy 165.028372 -288.234628)
			(xy 165.026467 -288.220237) (xy 165.015565 -288.193344) (xy 164.997528 -288.170612) (xy 164.973816 -288.153883)
			(xy 164.946352 -288.144512) (xy 164.91736 -288.143259) (xy 164.90315 -288.146236) (xy 164.883953 -288.150616)
			(xy 164.84486 -288.155326) (xy 164.825172 -288.155634) (xy 164.824664 -288.155634) (xy 164.798678 -288.155122)
			(xy 164.747346 -288.146987) (xy 164.697919 -288.130923) (xy 164.651612 -288.107326) (xy 164.609567 -288.076776)
			(xy 164.572818 -288.040025) (xy 164.542269 -287.997979) (xy 164.518673 -287.951672) (xy 164.502611 -287.902244)
			(xy 164.494477 -287.850912) (xy 164.493956 -287.824926) (xy 164.494459 -287.799103) (xy 164.502501 -287.748087)
			(xy 164.518377 -287.698941) (xy 164.541701 -287.652862) (xy 164.571906 -287.610969) (xy 164.589714 -287.592262)
			(xy 164.595048 -287.586928) (xy 164.601906 -287.573974) (xy 164.603684 -287.566354) (xy 164.604922 -287.558711)
			(xy 164.603232 -287.543328) (xy 164.600382 -287.536128) (xy 164.590476 -287.51276) (xy 164.590476 -287.512252)
			(xy 164.564568 -287.450276) (xy 164.560368 -287.441208) (xy 164.546259 -287.427077) (xy 164.527816 -287.419422)
			(xy 164.517832 -287.419034) (xy 164.193474 -287.419034) (xy 164.187632 -287.41878) (xy 164.18052 -287.418018)
			(xy 164.173408 -287.419288) (xy 164.169643 -287.420006) (xy 164.16237 -287.422425) (xy 164.15893 -287.424114)
			(xy 164.150294 -287.428686) (xy 164.137848 -287.442656) (xy 164.135562 -287.448244) (xy 164.134546 -287.451038)
			(xy 164.132768 -287.455356) (xy 164.132006 -287.45688) (xy 164.09797 -287.538922) (xy 164.096558 -287.5431)
			(xy 164.095021 -287.551785) (xy 164.094922 -287.556194) (xy 164.101526 -287.57245) (xy 164.106098 -287.583372)
			(xy 164.107932 -287.587621) (xy 164.112919 -287.595416) (xy 164.116004 -287.598866) (xy 164.132713 -287.617343)
			(xy 164.16095 -287.658382) (xy 164.182707 -287.703196) (xy 164.19749 -287.750767) (xy 164.204965 -287.800018)
			(xy 164.205412 -287.824926) (xy 164.204902 -287.850913) (xy 164.196772 -287.902248) (xy 164.180711 -287.951678)
			(xy 164.157115 -287.997988) (xy 164.126565 -288.040036) (xy 164.089814 -288.076787) (xy 164.047766 -288.107337)
			(xy 164.001456 -288.130933) (xy 163.952026 -288.146994) (xy 163.900691 -288.155124) (xy 163.848717 -288.155124)
			(xy 163.797382 -288.146994) (xy 163.747952 -288.130933) (xy 163.701642 -288.107337) (xy 163.659594 -288.076787)
			(xy 163.622843 -288.040036) (xy 163.592293 -287.997988) (xy 163.568697 -287.951678) (xy 163.552636 -287.902248)
			(xy 163.544506 -287.850913) (xy 163.543996 -287.824926) (xy 163.544499 -287.799103) (xy 163.552542 -287.748088)
			(xy 163.568419 -287.698943) (xy 163.591745 -287.652866) (xy 163.621953 -287.610976) (xy 163.639754 -287.592262)
			(xy 163.645088 -287.586928) (xy 163.651946 -287.573974) (xy 163.653724 -287.566354) (xy 163.654963 -287.558711)
			(xy 163.65327 -287.543329) (xy 163.650422 -287.536128) (xy 163.640516 -287.51276) (xy 163.640516 -287.512252)
			(xy 163.614608 -287.450276) (xy 163.610405 -287.441215) (xy 163.596294 -287.4271) (xy 163.577852 -287.419466)
			(xy 163.567872 -287.419034) (xy 163.243514 -287.419034) (xy 163.237672 -287.41878) (xy 163.23056 -287.418018)
			(xy 163.223448 -287.419288) (xy 163.219685 -287.42001) (xy 163.212416 -287.422437) (xy 163.20897 -287.424114)
			(xy 163.200334 -287.428686) (xy 163.187888 -287.442656) (xy 163.185602 -287.448244) (xy 163.184586 -287.451038)
			(xy 163.182808 -287.455356) (xy 163.182046 -287.45688) (xy 163.14801 -287.538922) (xy 163.146597 -287.5431)
			(xy 163.145059 -287.551785) (xy 163.144962 -287.556194) (xy 163.151566 -287.57245) (xy 163.156138 -287.583372)
			(xy 163.157967 -287.587623) (xy 163.162958 -287.595417) (xy 163.166044 -287.598866) (xy 163.182756 -287.617342)
			(xy 163.210998 -287.65838) (xy 163.232759 -287.703193) (xy 163.247545 -287.750765) (xy 163.255021 -287.800017)
			(xy 163.255452 -287.824926) (xy 163.254942 -287.850913) (xy 163.246812 -287.902248) (xy 163.230751 -287.951678)
			(xy 163.207155 -287.997988) (xy 163.176605 -288.040036) (xy 163.139854 -288.076787) (xy 163.097806 -288.107337)
			(xy 163.051496 -288.130933) (xy 163.002066 -288.146994) (xy 162.950731 -288.155124) (xy 162.898757 -288.155124)
			(xy 162.847422 -288.146994) (xy 162.797992 -288.130933) (xy 162.751682 -288.107337) (xy 162.709634 -288.076787)
			(xy 162.672883 -288.040036) (xy 162.642333 -287.997988) (xy 162.618737 -287.951678) (xy 162.602676 -287.902248)
			(xy 162.594546 -287.850913) (xy 162.594036 -287.824926) (xy 162.594539 -287.799104) (xy 162.602582 -287.748089)
			(xy 162.618461 -287.698946) (xy 162.641789 -287.65287) (xy 162.671999 -287.610982) (xy 162.689794 -287.592262)
			(xy 162.695128 -287.586928) (xy 162.701986 -287.573974) (xy 162.703764 -287.566354) (xy 162.705002 -287.558711)
			(xy 162.703311 -287.543328) (xy 162.700462 -287.536128) (xy 162.690556 -287.51276) (xy 162.690556 -287.512252)
			(xy 162.664648 -287.450276) (xy 162.660448 -287.44121) (xy 162.646338 -287.427084) (xy 162.627895 -287.419436)
			(xy 162.617912 -287.419034) (xy 162.293554 -287.419034) (xy 162.287712 -287.41878) (xy 162.2806 -287.418018)
			(xy 162.273488 -287.419288) (xy 162.269724 -287.420007) (xy 162.262452 -287.422429) (xy 162.25901 -287.424114)
			(xy 162.250374 -287.428686) (xy 162.237928 -287.442656) (xy 162.235642 -287.448244) (xy 162.234626 -287.451038)
			(xy 162.232848 -287.455356) (xy 162.232086 -287.45688) (xy 162.19805 -287.538922) (xy 162.196639 -287.543101)
			(xy 162.195102 -287.551785) (xy 162.195002 -287.556194) (xy 162.201606 -287.57245) (xy 162.206178 -287.583372)
			(xy 162.208009 -287.587622) (xy 162.213002 -287.595413) (xy 162.216084 -287.598866) (xy 162.232794 -287.617343)
			(xy 162.261033 -287.658382) (xy 162.282791 -287.703195) (xy 162.297575 -287.750766) (xy 162.30505 -287.800018)
			(xy 162.305492 -287.824926) (xy 162.304982 -287.850913) (xy 162.296852 -287.902248) (xy 162.280791 -287.951678)
			(xy 162.257195 -287.997988) (xy 162.226645 -288.040036) (xy 162.189894 -288.076787) (xy 162.147846 -288.107337)
			(xy 162.101536 -288.130933) (xy 162.052106 -288.146994) (xy 162.000771 -288.155124) (xy 161.948797 -288.155124)
			(xy 161.897462 -288.146994) (xy 161.848032 -288.130933) (xy 161.801722 -288.107337) (xy 161.759674 -288.076787)
			(xy 161.722923 -288.040036) (xy 161.692373 -287.997988) (xy 161.668777 -287.951678) (xy 161.652716 -287.902248)
			(xy 161.644586 -287.850913) (xy 161.644076 -287.824926) (xy 161.644579 -287.799103) (xy 161.652621 -287.748087)
			(xy 161.668498 -287.698942) (xy 161.691823 -287.652864) (xy 161.722029 -287.610972) (xy 161.739834 -287.592262)
			(xy 161.745168 -287.586928) (xy 161.752026 -287.573974) (xy 161.753804 -287.566354) (xy 161.755043 -287.558711)
			(xy 161.75335 -287.543329) (xy 161.750502 -287.536128) (xy 161.740596 -287.51276) (xy 161.740596 -287.512252)
			(xy 161.714688 -287.450276) (xy 161.710432 -287.441244) (xy 161.696343 -287.427127) (xy 161.677924 -287.419475)
			(xy 161.667952 -287.419034) (xy 161.343594 -287.419034) (xy 161.337752 -287.41878) (xy 161.33064 -287.418018)
			(xy 161.323528 -287.419288) (xy 161.319765 -287.420012) (xy 161.312498 -287.422441) (xy 161.30905 -287.424114)
			(xy 161.300414 -287.428686) (xy 161.287968 -287.442656) (xy 161.285682 -287.448244) (xy 161.284666 -287.451038)
			(xy 161.282888 -287.455356) (xy 161.282126 -287.45688) (xy 161.24809 -287.538922) (xy 161.246678 -287.5431)
			(xy 161.24514 -287.551785) (xy 161.245042 -287.556194) (xy 161.251646 -287.57245) (xy 161.256218 -287.583372)
			(xy 161.258053 -287.587621) (xy 161.263041 -287.595414) (xy 161.266124 -287.598866) (xy 161.282832 -287.617344)
			(xy 161.311068 -287.658383) (xy 161.332823 -287.703197) (xy 161.347605 -287.750768) (xy 161.355079 -287.800019)
			(xy 161.355532 -287.824926) (xy 161.355022 -287.850913) (xy 161.346892 -287.902248) (xy 161.330831 -287.951678)
			(xy 161.307235 -287.997988) (xy 161.276685 -288.040036) (xy 161.239934 -288.076787) (xy 161.197886 -288.107337)
			(xy 161.151576 -288.130933) (xy 161.102146 -288.146994) (xy 161.050811 -288.155124) (xy 160.998837 -288.155124)
			(xy 160.947502 -288.146994) (xy 160.898072 -288.130933) (xy 160.851762 -288.107337) (xy 160.809714 -288.076787)
			(xy 160.772963 -288.040036) (xy 160.742413 -287.997988) (xy 160.718817 -287.951678) (xy 160.702756 -287.902248)
			(xy 160.694626 -287.850913) (xy 160.694116 -287.824926) (xy 160.694619 -287.799103) (xy 160.702662 -287.748088)
			(xy 160.71854 -287.698944) (xy 160.741867 -287.652868) (xy 160.772076 -287.610979) (xy 160.789874 -287.592262)
			(xy 160.795208 -287.586928) (xy 160.802066 -287.573974) (xy 160.803844 -287.566354) (xy 160.805082 -287.558711)
			(xy 160.803391 -287.543329) (xy 160.800542 -287.536128) (xy 160.790636 -287.51276) (xy 160.790636 -287.512252)
			(xy 160.764728 -287.450276) (xy 160.760527 -287.441212) (xy 160.746416 -287.427092) (xy 160.727973 -287.419451)
			(xy 160.717992 -287.419034) (xy 157.5435 -287.419034) (xy 157.537658 -287.41878) (xy 157.530546 -287.418018)
			(xy 157.523434 -287.419288) (xy 157.519671 -287.420011) (xy 157.512403 -287.42244) (xy 157.508956 -287.424114)
			(xy 157.50032 -287.428686) (xy 157.487874 -287.442656) (xy 157.485588 -287.448244) (xy 157.484572 -287.451038)
			(xy 157.482794 -287.455356) (xy 157.482032 -287.45688) (xy 157.447996 -287.538922) (xy 157.446583 -287.5431)
			(xy 157.445046 -287.551785) (xy 157.444948 -287.556194) (xy 157.451552 -287.57245) (xy 157.456124 -287.583372)
			(xy 157.457953 -287.587624) (xy 157.462942 -287.595418) (xy 157.46603 -287.598866) (xy 157.482738 -287.617344)
			(xy 157.510973 -287.658384) (xy 157.532728 -287.703197) (xy 157.54751 -287.750768) (xy 157.554984 -287.800019)
			(xy 157.555438 -287.824926) (xy 157.554928 -287.850913) (xy 157.546798 -287.902248) (xy 157.530737 -287.951678)
			(xy 157.507141 -287.997988) (xy 157.476591 -288.040036) (xy 157.43984 -288.076787) (xy 157.397792 -288.107337)
			(xy 157.351482 -288.130933) (xy 157.302052 -288.146994) (xy 157.250717 -288.155124) (xy 157.198743 -288.155124)
			(xy 157.147408 -288.146994) (xy 157.097978 -288.130933) (xy 157.051668 -288.107337) (xy 157.00962 -288.076787)
			(xy 156.972869 -288.040036) (xy 156.942319 -287.997988) (xy 156.918723 -287.951678) (xy 156.902662 -287.902248)
			(xy 156.894532 -287.850913) (xy 156.894022 -287.824926) (xy 156.894525 -287.799104) (xy 156.902568 -287.748088)
			(xy 156.918446 -287.698945) (xy 156.941774 -287.652868) (xy 156.971983 -287.61098) (xy 156.98978 -287.592262)
			(xy 156.995114 -287.586928) (xy 157.001972 -287.573974) (xy 157.00375 -287.566354) (xy 157.004989 -287.558711)
			(xy 157.003297 -287.543328) (xy 157.000448 -287.536128) (xy 156.990542 -287.51276) (xy 156.990542 -287.512252)
			(xy 156.964634 -287.450276) (xy 156.960433 -287.441212) (xy 156.946322 -287.42709) (xy 156.92788 -287.419447)
			(xy 156.917898 -287.419034) (xy 154.69362 -287.419034) (xy 154.687778 -287.41878) (xy 154.680666 -287.418018)
			(xy 154.673554 -287.419288) (xy 154.66979 -287.42001) (xy 154.662521 -287.422436) (xy 154.659076 -287.424114)
			(xy 154.65044 -287.428686) (xy 154.637994 -287.442656) (xy 154.635708 -287.448244) (xy 154.634692 -287.451038)
			(xy 154.632914 -287.455356) (xy 154.632152 -287.45688) (xy 154.598116 -287.538922) (xy 154.596703 -287.5431)
			(xy 154.595164 -287.551785) (xy 154.595068 -287.556194) (xy 154.601672 -287.57245) (xy 154.606244 -287.583372)
			(xy 154.608074 -287.587623) (xy 154.613065 -287.595416) (xy 154.61615 -287.598866) (xy 154.632861 -287.617342)
			(xy 154.661103 -287.65838) (xy 154.682864 -287.703193) (xy 154.697649 -287.750765) (xy 154.705125 -287.800018)
			(xy 154.705558 -287.824926) (xy 154.705048 -287.850913) (xy 154.696918 -287.902248) (xy 154.680857 -287.951678)
			(xy 154.657261 -287.997988) (xy 154.626711 -288.040036) (xy 154.58996 -288.076787) (xy 154.547912 -288.107337)
			(xy 154.501602 -288.130933) (xy 154.452172 -288.146994) (xy 154.400837 -288.155124) (xy 154.348863 -288.155124)
			(xy 154.297528 -288.146994) (xy 154.248098 -288.130933) (xy 154.201788 -288.107337) (xy 154.15974 -288.076787)
			(xy 154.122989 -288.040036) (xy 154.092439 -287.997988) (xy 154.068843 -287.951678) (xy 154.052782 -287.902248)
			(xy 154.044652 -287.850913) (xy 154.044142 -287.824926) (xy 154.044645 -287.799104) (xy 154.052689 -287.748089)
			(xy 154.068568 -287.698946) (xy 154.091896 -287.65287) (xy 154.122106 -287.610983) (xy 154.1399 -287.592262)
			(xy 154.145234 -287.586928) (xy 154.152092 -287.573974) (xy 154.15387 -287.566354) (xy 154.155108 -287.558711)
			(xy 154.153417 -287.543328) (xy 154.150568 -287.536128) (xy 154.140662 -287.51276) (xy 154.140662 -287.512252)
			(xy 154.114754 -287.450276) (xy 154.110554 -287.44121) (xy 154.096444 -287.427082) (xy 154.078001 -287.419432)
			(xy 154.068018 -287.419034) (xy 153.743406 -287.419034) (xy 153.737564 -287.41878) (xy 153.730452 -287.418018)
			(xy 153.72334 -287.419288) (xy 153.719577 -287.420011) (xy 153.712309 -287.422438) (xy 153.708862 -287.424114)
			(xy 153.700226 -287.428686) (xy 153.68778 -287.442656) (xy 153.685494 -287.448244) (xy 153.684478 -287.451038)
			(xy 153.6827 -287.455356) (xy 153.681938 -287.45688) (xy 153.647902 -287.538922) (xy 153.646489 -287.5431)
			(xy 153.644951 -287.551785) (xy 153.644854 -287.556194) (xy 153.651458 -287.57245) (xy 153.65603 -287.583372)
			(xy 153.657859 -287.587624) (xy 153.662849 -287.595417) (xy 153.665936 -287.598866) (xy 153.682643 -287.617344)
			(xy 153.710878 -287.658384) (xy 153.732633 -287.703197) (xy 153.747414 -287.750768) (xy 153.754888 -287.800019)
			(xy 153.755344 -287.824926) (xy 153.754834 -287.850913) (xy 153.746704 -287.902248) (xy 153.730643 -287.951678)
			(xy 153.707047 -287.997988) (xy 153.676497 -288.040036) (xy 153.639746 -288.076787) (xy 153.597698 -288.107337)
			(xy 153.551388 -288.130933) (xy 153.501958 -288.146994) (xy 153.450623 -288.155124) (xy 153.398649 -288.155124)
			(xy 153.347314 -288.146994) (xy 153.297884 -288.130933) (xy 153.251574 -288.107337) (xy 153.209526 -288.076787)
			(xy 153.172775 -288.040036) (xy 153.142225 -287.997988) (xy 153.118629 -287.951678) (xy 153.102568 -287.902248)
			(xy 153.094438 -287.850913) (xy 153.093928 -287.824926) (xy 153.094431 -287.799104) (xy 153.102474 -287.748089)
			(xy 153.118353 -287.698945) (xy 153.141681 -287.652869) (xy 153.17189 -287.610981) (xy 153.189686 -287.592262)
			(xy 153.19502 -287.586928) (xy 153.201878 -287.573974) (xy 153.203656 -287.566354) (xy 153.204894 -287.558711)
			(xy 153.203203 -287.543328) (xy 153.200354 -287.536128) (xy 153.190448 -287.51276) (xy 153.190448 -287.512252)
			(xy 153.16454 -287.450276) (xy 153.160339 -287.441211) (xy 153.146229 -287.427087) (xy 153.127786 -287.419442)
			(xy 153.117804 -287.419034) (xy 152.793446 -287.419034) (xy 152.787604 -287.41878) (xy 152.780492 -287.418018)
			(xy 152.77338 -287.419288) (xy 152.769616 -287.420008) (xy 152.762345 -287.422431) (xy 152.758902 -287.424114)
			(xy 152.750266 -287.428686) (xy 152.73782 -287.442656) (xy 152.735534 -287.448244) (xy 152.734518 -287.451038)
			(xy 152.73274 -287.455356) (xy 152.731978 -287.45688) (xy 152.697942 -287.538922) (xy 152.696531 -287.543101)
			(xy 152.694995 -287.551785) (xy 152.694894 -287.556194) (xy 152.701498 -287.57245) (xy 152.70607 -287.583372)
			(xy 152.707901 -287.587622) (xy 152.712894 -287.595413) (xy 152.715976 -287.598866) (xy 152.732686 -287.617343)
			(xy 152.760926 -287.658381) (xy 152.782685 -287.703194) (xy 152.797469 -287.750766) (xy 152.804944 -287.800018)
			(xy 152.805384 -287.824926) (xy 152.804874 -287.850913) (xy 152.796744 -287.902248) (xy 152.780683 -287.951678)
			(xy 152.757087 -287.997988) (xy 152.726537 -288.040036) (xy 152.689786 -288.076787) (xy 152.647738 -288.107337)
			(xy 152.601428 -288.130933) (xy 152.551998 -288.146994) (xy 152.500663 -288.155124) (xy 152.448689 -288.155124)
			(xy 152.397354 -288.146994) (xy 152.347924 -288.130933) (xy 152.301614 -288.107337) (xy 152.259566 -288.076787)
			(xy 152.222815 -288.040036) (xy 152.192265 -287.997988) (xy 152.168669 -287.951678) (xy 152.152608 -287.902248)
			(xy 152.144478 -287.850913) (xy 152.143968 -287.824926) (xy 152.144471 -287.799103) (xy 152.152513 -287.748087)
			(xy 152.168389 -287.698942) (xy 152.191714 -287.652863) (xy 152.22192 -287.610971) (xy 152.239726 -287.592262)
			(xy 152.24506 -287.586928) (xy 152.251918 -287.573974) (xy 152.253696 -287.566354) (xy 152.254934 -287.558711)
			(xy 152.253244 -287.543328) (xy 152.250394 -287.536128) (xy 152.240488 -287.51276) (xy 152.240488 -287.512252)
			(xy 152.21458 -287.450276) (xy 152.210381 -287.441207) (xy 152.196273 -287.427072) (xy 152.177829 -287.419413)
			(xy 152.167844 -287.419034) (xy 150.316946 -287.419034) (xy 150.308818 -287.421066) (xy 150.292308 -287.425384)
			(xy 150.28672 -287.428432) (xy 150.258394 -287.443221) (xy 150.198033 -287.464176) (xy 150.135026 -287.474791)
			(xy 150.103078 -287.475422) (xy 150.10257 -287.475422) (xy 150.071145 -287.474756) (xy 150.009151 -287.464409)
			(xy 149.949689 -287.444049) (xy 149.921722 -287.429702) (xy 149.918928 -287.428178) (xy 149.9108 -287.42513)
			(xy 149.908006 -287.424114) (xy 149.895052 -287.420558) (xy 149.88286 -287.419034) (xy 149.430486 -287.419034)
			(xy 149.422358 -287.421066) (xy 149.405848 -287.425384) (xy 149.40026 -287.428432) (xy 149.371933 -287.443216)
			(xy 149.311571 -287.464162) (xy 149.248565 -287.474767) (xy 149.216618 -287.475422) (xy 149.21611 -287.475422)
			(xy 149.184684 -287.474759) (xy 149.122688 -287.464418) (xy 149.063222 -287.444064) (xy 149.035262 -287.429702)
			(xy 149.032468 -287.428178) (xy 149.02434 -287.42513) (xy 149.021546 -287.424114) (xy 149.008592 -287.420558)
			(xy 148.9964 -287.419034) (xy 148.033486 -287.419034) (xy 148.025358 -287.421066) (xy 148.008848 -287.425384)
			(xy 148.00326 -287.428432) (xy 147.974933 -287.443216) (xy 147.914571 -287.464162) (xy 147.851565 -287.474767)
			(xy 147.819618 -287.475422) (xy 147.81911 -287.475422) (xy 147.787684 -287.474759) (xy 147.725688 -287.464418)
			(xy 147.666222 -287.444064) (xy 147.638262 -287.429702) (xy 147.635468 -287.428178) (xy 147.62734 -287.42513)
			(xy 147.624546 -287.424114) (xy 147.611592 -287.420558) (xy 147.5994 -287.419034) (xy 136.907524 -287.419034)
			(xy 136.901515 -287.419204) (xy 136.889837 -287.422035) (xy 136.88441 -287.424622) (xy 136.880935 -287.426461)
			(xy 136.874555 -287.431053) (xy 136.87171 -287.433766) (xy 136.364726 -287.94075) (xy 136.362018 -287.9436)
			(xy 136.35742 -287.949976) (xy 136.355582 -287.95345) (xy 136.353 -287.958877) (xy 136.350179 -287.970557)
			(xy 136.349994 -287.976564) (xy 136.349994 -288.230056) (xy 141.911576 -288.230056) (xy 141.915647 -288.174434)
			(xy 141.927773 -288.119997) (xy 141.947696 -288.067906) (xy 141.974992 -288.019271) (xy 142.009078 -287.975128)
			(xy 142.049227 -287.936419) (xy 142.094585 -287.903968) (xy 142.144185 -287.878467) (xy 142.196969 -287.86046)
			(xy 142.251812 -287.85033) (xy 142.307546 -287.848293) (xy 142.362983 -287.854393) (xy 142.41694 -287.868499)
			(xy 142.468269 -287.890311) (xy 142.515875 -287.919365) (xy 142.558743 -287.95504) (xy 142.59596 -287.996577)
			(xy 142.626733 -288.04309) (xy 142.650405 -288.093587) (xy 142.666473 -288.146994) (xy 142.674593 -288.20217)
			(xy 142.675102 -288.230056) (xy 143.396714 -288.230056) (xy 143.400785 -288.174434) (xy 143.412911 -288.119997)
			(xy 143.432834 -288.067906) (xy 143.46013 -288.019271) (xy 143.494216 -287.975128) (xy 143.534365 -287.936419)
			(xy 143.579723 -287.903968) (xy 143.629323 -287.878467) (xy 143.682107 -287.86046) (xy 143.73695 -287.85033)
			(xy 143.792684 -287.848293) (xy 143.848121 -287.854393) (xy 143.902078 -287.868499) (xy 143.953407 -287.890311)
			(xy 144.001013 -287.919365) (xy 144.043881 -287.95504) (xy 144.081098 -287.996577) (xy 144.111871 -288.04309)
			(xy 144.135543 -288.093587) (xy 144.151611 -288.146994) (xy 144.159731 -288.20217) (xy 144.16024 -288.230056)
			(xy 144.159731 -288.257942) (xy 144.151611 -288.313118) (xy 144.135543 -288.366525) (xy 144.111871 -288.417022)
			(xy 144.081098 -288.463535) (xy 144.043881 -288.505072) (xy 144.001013 -288.540747) (xy 143.953407 -288.569801)
			(xy 143.902078 -288.591613) (xy 143.848121 -288.605719) (xy 143.792684 -288.611819) (xy 143.73695 -288.609782)
			(xy 143.682107 -288.599652) (xy 143.629323 -288.581645) (xy 143.579723 -288.556144) (xy 143.534365 -288.523693)
			(xy 143.494216 -288.484984) (xy 143.46013 -288.440841) (xy 143.432834 -288.392206) (xy 143.412911 -288.340115)
			(xy 143.400785 -288.285678) (xy 143.396714 -288.230056) (xy 142.675102 -288.230056) (xy 142.674593 -288.257942)
			(xy 142.666473 -288.313118) (xy 142.650405 -288.366525) (xy 142.626733 -288.417022) (xy 142.59596 -288.463535)
			(xy 142.558743 -288.505072) (xy 142.515875 -288.540747) (xy 142.468269 -288.569801) (xy 142.41694 -288.591613)
			(xy 142.362983 -288.605719) (xy 142.307546 -288.611819) (xy 142.251812 -288.609782) (xy 142.196969 -288.599652)
			(xy 142.144185 -288.581645) (xy 142.094585 -288.556144) (xy 142.049227 -288.523693) (xy 142.009078 -288.484984)
			(xy 141.974992 -288.440841) (xy 141.947696 -288.392206) (xy 141.927773 -288.340115) (xy 141.915647 -288.285678)
			(xy 141.911576 -288.230056) (xy 136.349994 -288.230056) (xy 136.349994 -288.774886) (xy 152.169126 -288.774886)
			(xy 152.173086 -288.725832) (xy 152.184863 -288.678048) (xy 152.204154 -288.632772) (xy 152.230457 -288.591176)
			(xy 152.263092 -288.554339) (xy 152.301213 -288.523214) (xy 152.343834 -288.498607) (xy 152.38985 -288.481155)
			(xy 152.438069 -288.471311) (xy 152.487244 -288.46933) (xy 152.536099 -288.475262) (xy 152.58337 -288.488954)
			(xy 152.627832 -288.510052) (xy 152.668335 -288.538008) (xy 152.703828 -288.5721) (xy 152.733393 -288.611444)
			(xy 152.756264 -288.655021) (xy 152.771848 -288.701702) (xy 152.779743 -288.750279) (xy 152.780238 -288.774886)
			(xy 153.119086 -288.774886) (xy 153.123046 -288.725832) (xy 153.134823 -288.678048) (xy 153.154114 -288.632772)
			(xy 153.180417 -288.591176) (xy 153.213052 -288.554339) (xy 153.251173 -288.523214) (xy 153.293794 -288.498607)
			(xy 153.33981 -288.481155) (xy 153.388029 -288.471311) (xy 153.437204 -288.46933) (xy 153.486059 -288.475262)
			(xy 153.53333 -288.488954) (xy 153.577792 -288.510052) (xy 153.618295 -288.538008) (xy 153.653788 -288.5721)
			(xy 153.683353 -288.611444) (xy 153.706224 -288.655021) (xy 153.721808 -288.701702) (xy 153.729703 -288.750279)
			(xy 153.730198 -288.774886) (xy 154.0693 -288.774886) (xy 154.07326 -288.725832) (xy 154.085037 -288.678048)
			(xy 154.104328 -288.632772) (xy 154.130631 -288.591176) (xy 154.163266 -288.554339) (xy 154.201387 -288.523214)
			(xy 154.244008 -288.498607) (xy 154.290024 -288.481155) (xy 154.338243 -288.471311) (xy 154.387418 -288.46933)
			(xy 154.436273 -288.475262) (xy 154.483544 -288.488954) (xy 154.528006 -288.510052) (xy 154.568509 -288.538008)
			(xy 154.604002 -288.5721) (xy 154.633567 -288.611444) (xy 154.656438 -288.655021) (xy 154.672022 -288.701702)
			(xy 154.679917 -288.750279) (xy 154.680412 -288.774886) (xy 158.8191 -288.774886) (xy 158.82306 -288.725832)
			(xy 158.834837 -288.678048) (xy 158.854128 -288.632772) (xy 158.880431 -288.591176) (xy 158.913066 -288.554339)
			(xy 158.951187 -288.523214) (xy 158.993808 -288.498607) (xy 159.039824 -288.481155) (xy 159.088043 -288.471311)
			(xy 159.137218 -288.46933) (xy 159.186073 -288.475262) (xy 159.233344 -288.488954) (xy 159.277806 -288.510052)
			(xy 159.318309 -288.538008) (xy 159.353802 -288.5721) (xy 159.383367 -288.611444) (xy 159.406238 -288.655021)
			(xy 159.421822 -288.701702) (xy 159.429717 -288.750279) (xy 159.430212 -288.774886) (xy 159.76906 -288.774886)
			(xy 159.77302 -288.725832) (xy 159.784797 -288.678048) (xy 159.804088 -288.632772) (xy 159.830391 -288.591176)
			(xy 159.863026 -288.554339) (xy 159.901147 -288.523214) (xy 159.943768 -288.498607) (xy 159.989784 -288.481155)
			(xy 160.038003 -288.471311) (xy 160.087178 -288.46933) (xy 160.136033 -288.475262) (xy 160.183304 -288.488954)
			(xy 160.227766 -288.510052) (xy 160.268269 -288.538008) (xy 160.303762 -288.5721) (xy 160.333327 -288.611444)
			(xy 160.356198 -288.655021) (xy 160.371782 -288.701702) (xy 160.379677 -288.750279) (xy 160.380172 -288.774886)
			(xy 160.719274 -288.774886) (xy 160.723234 -288.725832) (xy 160.735011 -288.678048) (xy 160.754302 -288.632772)
			(xy 160.780605 -288.591176) (xy 160.81324 -288.554339) (xy 160.851361 -288.523214) (xy 160.893982 -288.498607)
			(xy 160.939998 -288.481155) (xy 160.988217 -288.471311) (xy 161.037392 -288.46933) (xy 161.086247 -288.475262)
			(xy 161.133518 -288.488954) (xy 161.17798 -288.510052) (xy 161.218483 -288.538008) (xy 161.253976 -288.5721)
			(xy 161.283541 -288.611444) (xy 161.306412 -288.655021) (xy 161.321996 -288.701702) (xy 161.329891 -288.750279)
			(xy 161.330386 -288.774886) (xy 161.669234 -288.774886) (xy 161.673194 -288.725832) (xy 161.684971 -288.678048)
			(xy 161.704262 -288.632772) (xy 161.730565 -288.591176) (xy 161.7632 -288.554339) (xy 161.801321 -288.523214)
			(xy 161.843942 -288.498607) (xy 161.889958 -288.481155) (xy 161.938177 -288.471311) (xy 161.987352 -288.46933)
			(xy 162.036207 -288.475262) (xy 162.083478 -288.488954) (xy 162.12794 -288.510052) (xy 162.168443 -288.538008)
			(xy 162.203936 -288.5721) (xy 162.233501 -288.611444) (xy 162.256372 -288.655021) (xy 162.271956 -288.701702)
			(xy 162.279851 -288.750279) (xy 162.280346 -288.774886) (xy 162.619194 -288.774886) (xy 162.623154 -288.725832)
			(xy 162.634931 -288.678048) (xy 162.654222 -288.632772) (xy 162.680525 -288.591176) (xy 162.71316 -288.554339)
			(xy 162.751281 -288.523214) (xy 162.793902 -288.498607) (xy 162.839918 -288.481155) (xy 162.888137 -288.471311)
			(xy 162.937312 -288.46933) (xy 162.986167 -288.475262) (xy 163.033438 -288.488954) (xy 163.0779 -288.510052)
			(xy 163.118403 -288.538008) (xy 163.153896 -288.5721) (xy 163.183461 -288.611444) (xy 163.206332 -288.655021)
			(xy 163.221916 -288.701702) (xy 163.229811 -288.750279) (xy 163.230306 -288.774886) (xy 163.569154 -288.774886)
			(xy 163.573114 -288.725832) (xy 163.584891 -288.678048) (xy 163.604182 -288.632772) (xy 163.630485 -288.591176)
			(xy 163.66312 -288.554339) (xy 163.701241 -288.523214) (xy 163.743862 -288.498607) (xy 163.789878 -288.481155)
			(xy 163.838097 -288.471311) (xy 163.887272 -288.46933) (xy 163.936127 -288.475262) (xy 163.983398 -288.488954)
			(xy 164.02786 -288.510052) (xy 164.068363 -288.538008) (xy 164.103856 -288.5721) (xy 164.133421 -288.611444)
			(xy 164.156292 -288.655021) (xy 164.171876 -288.701702) (xy 164.179771 -288.750279) (xy 164.180266 -288.774886)
			(xy 164.179771 -288.799493) (xy 164.171876 -288.84807) (xy 164.156292 -288.894751) (xy 164.133421 -288.938328)
			(xy 164.103856 -288.977672) (xy 164.068363 -289.011764) (xy 164.02786 -289.03972) (xy 163.983398 -289.060818)
			(xy 163.936127 -289.07451) (xy 163.887272 -289.080442) (xy 163.838097 -289.078461) (xy 163.789878 -289.068617)
			(xy 163.743862 -289.051165) (xy 163.701241 -289.026558) (xy 163.66312 -288.995433) (xy 163.630485 -288.958596)
			(xy 163.604182 -288.917) (xy 163.584891 -288.871724) (xy 163.573114 -288.82394) (xy 163.569154 -288.774886)
			(xy 163.230306 -288.774886) (xy 163.229811 -288.799493) (xy 163.221916 -288.84807) (xy 163.206332 -288.894751)
			(xy 163.183461 -288.938328) (xy 163.153896 -288.977672) (xy 163.118403 -289.011764) (xy 163.0779 -289.03972)
			(xy 163.033438 -289.060818) (xy 162.986167 -289.07451) (xy 162.937312 -289.080442) (xy 162.888137 -289.078461)
			(xy 162.839918 -289.068617) (xy 162.793902 -289.051165) (xy 162.751281 -289.026558) (xy 162.71316 -288.995433)
			(xy 162.680525 -288.958596) (xy 162.654222 -288.917) (xy 162.634931 -288.871724) (xy 162.623154 -288.82394)
			(xy 162.619194 -288.774886) (xy 162.280346 -288.774886) (xy 162.279851 -288.799493) (xy 162.271956 -288.84807)
			(xy 162.256372 -288.894751) (xy 162.233501 -288.938328) (xy 162.203936 -288.977672) (xy 162.168443 -289.011764)
			(xy 162.12794 -289.03972) (xy 162.083478 -289.060818) (xy 162.036207 -289.07451) (xy 161.987352 -289.080442)
			(xy 161.938177 -289.078461) (xy 161.889958 -289.068617) (xy 161.843942 -289.051165) (xy 161.801321 -289.026558)
			(xy 161.7632 -288.995433) (xy 161.730565 -288.958596) (xy 161.704262 -288.917) (xy 161.684971 -288.871724)
			(xy 161.673194 -288.82394) (xy 161.669234 -288.774886) (xy 161.330386 -288.774886) (xy 161.329891 -288.799493)
			(xy 161.321996 -288.84807) (xy 161.306412 -288.894751) (xy 161.283541 -288.938328) (xy 161.253976 -288.977672)
			(xy 161.218483 -289.011764) (xy 161.17798 -289.03972) (xy 161.133518 -289.060818) (xy 161.086247 -289.07451)
			(xy 161.037392 -289.080442) (xy 160.988217 -289.078461) (xy 160.939998 -289.068617) (xy 160.893982 -289.051165)
			(xy 160.851361 -289.026558) (xy 160.81324 -288.995433) (xy 160.780605 -288.958596) (xy 160.754302 -288.917)
			(xy 160.735011 -288.871724) (xy 160.723234 -288.82394) (xy 160.719274 -288.774886) (xy 160.380172 -288.774886)
			(xy 160.379677 -288.799493) (xy 160.371782 -288.84807) (xy 160.356198 -288.894751) (xy 160.333327 -288.938328)
			(xy 160.303762 -288.977672) (xy 160.268269 -289.011764) (xy 160.227766 -289.03972) (xy 160.183304 -289.060818)
			(xy 160.136033 -289.07451) (xy 160.087178 -289.080442) (xy 160.038003 -289.078461) (xy 159.989784 -289.068617)
			(xy 159.943768 -289.051165) (xy 159.901147 -289.026558) (xy 159.863026 -288.995433) (xy 159.830391 -288.958596)
			(xy 159.804088 -288.917) (xy 159.784797 -288.871724) (xy 159.77302 -288.82394) (xy 159.76906 -288.774886)
			(xy 159.430212 -288.774886) (xy 159.429717 -288.799493) (xy 159.421822 -288.84807) (xy 159.406238 -288.894751)
			(xy 159.383367 -288.938328) (xy 159.353802 -288.977672) (xy 159.318309 -289.011764) (xy 159.277806 -289.03972)
			(xy 159.233344 -289.060818) (xy 159.186073 -289.07451) (xy 159.137218 -289.080442) (xy 159.088043 -289.078461)
			(xy 159.039824 -289.068617) (xy 158.993808 -289.051165) (xy 158.951187 -289.026558) (xy 158.913066 -288.995433)
			(xy 158.880431 -288.958596) (xy 158.854128 -288.917) (xy 158.834837 -288.871724) (xy 158.82306 -288.82394)
			(xy 158.8191 -288.774886) (xy 154.680412 -288.774886) (xy 154.679917 -288.799493) (xy 154.672022 -288.84807)
			(xy 154.656438 -288.894751) (xy 154.633567 -288.938328) (xy 154.604002 -288.977672) (xy 154.568509 -289.011764)
			(xy 154.528006 -289.03972) (xy 154.483544 -289.060818) (xy 154.436273 -289.07451) (xy 154.387418 -289.080442)
			(xy 154.338243 -289.078461) (xy 154.290024 -289.068617) (xy 154.244008 -289.051165) (xy 154.201387 -289.026558)
			(xy 154.163266 -288.995433) (xy 154.130631 -288.958596) (xy 154.104328 -288.917) (xy 154.085037 -288.871724)
			(xy 154.07326 -288.82394) (xy 154.0693 -288.774886) (xy 153.730198 -288.774886) (xy 153.729703 -288.799493)
			(xy 153.721808 -288.84807) (xy 153.706224 -288.894751) (xy 153.683353 -288.938328) (xy 153.653788 -288.977672)
			(xy 153.618295 -289.011764) (xy 153.577792 -289.03972) (xy 153.53333 -289.060818) (xy 153.486059 -289.07451)
			(xy 153.437204 -289.080442) (xy 153.388029 -289.078461) (xy 153.33981 -289.068617) (xy 153.293794 -289.051165)
			(xy 153.251173 -289.026558) (xy 153.213052 -288.995433) (xy 153.180417 -288.958596) (xy 153.154114 -288.917)
			(xy 153.134823 -288.871724) (xy 153.123046 -288.82394) (xy 153.119086 -288.774886) (xy 152.780238 -288.774886)
			(xy 152.779743 -288.799493) (xy 152.771848 -288.84807) (xy 152.756264 -288.894751) (xy 152.733393 -288.938328)
			(xy 152.703828 -288.977672) (xy 152.668335 -289.011764) (xy 152.627832 -289.03972) (xy 152.58337 -289.060818)
			(xy 152.536099 -289.07451) (xy 152.487244 -289.080442) (xy 152.438069 -289.078461) (xy 152.38985 -289.068617)
			(xy 152.343834 -289.051165) (xy 152.301213 -289.026558) (xy 152.263092 -288.995433) (xy 152.230457 -288.958596)
			(xy 152.204154 -288.917) (xy 152.184863 -288.871724) (xy 152.173086 -288.82394) (xy 152.169126 -288.774886)
			(xy 136.349994 -288.774886) (xy 136.349994 -289.532314) (xy 141.911576 -289.532314) (xy 141.915647 -289.476692)
			(xy 141.927773 -289.422255) (xy 141.947696 -289.370164) (xy 141.974992 -289.321529) (xy 142.009078 -289.277386)
			(xy 142.049227 -289.238677) (xy 142.094585 -289.206226) (xy 142.144185 -289.180725) (xy 142.196969 -289.162718)
			(xy 142.251812 -289.152588) (xy 142.307546 -289.150551) (xy 142.362983 -289.156651) (xy 142.41694 -289.170757)
			(xy 142.468269 -289.192569) (xy 142.515875 -289.221623) (xy 142.558743 -289.257298) (xy 142.59596 -289.298835)
			(xy 142.626733 -289.345348) (xy 142.650405 -289.395845) (xy 142.666473 -289.449252) (xy 142.674593 -289.504428)
			(xy 142.675102 -289.532314) (xy 143.387062 -289.532314) (xy 143.391133 -289.476692) (xy 143.403259 -289.422255)
			(xy 143.423182 -289.370164) (xy 143.450478 -289.321529) (xy 143.484564 -289.277386) (xy 143.524713 -289.238677)
			(xy 143.570071 -289.206226) (xy 143.619671 -289.180725) (xy 143.672455 -289.162718) (xy 143.727298 -289.152588)
			(xy 143.783032 -289.150551) (xy 143.838469 -289.156651) (xy 143.892426 -289.170757) (xy 143.943755 -289.192569)
			(xy 143.991361 -289.221623) (xy 144.034229 -289.257298) (xy 144.071446 -289.298835) (xy 144.102219 -289.345348)
			(xy 144.125891 -289.395845) (xy 144.141959 -289.449252) (xy 144.150079 -289.504428) (xy 144.150588 -289.532314)
			(xy 144.276062 -289.532314) (xy 144.280133 -289.476692) (xy 144.292259 -289.422255) (xy 144.312182 -289.370164)
			(xy 144.339478 -289.321529) (xy 144.373564 -289.277386) (xy 144.413713 -289.238677) (xy 144.459071 -289.206226)
			(xy 144.508671 -289.180725) (xy 144.561455 -289.162718) (xy 144.616298 -289.152588) (xy 144.672032 -289.150551)
			(xy 144.727469 -289.156651) (xy 144.781426 -289.170757) (xy 144.832755 -289.192569) (xy 144.880361 -289.221623)
			(xy 144.923229 -289.257298) (xy 144.960446 -289.298835) (xy 144.991219 -289.345348) (xy 145.014891 -289.395845)
			(xy 145.030959 -289.449252) (xy 145.039079 -289.504428) (xy 145.039588 -289.532314) (xy 145.039079 -289.5602)
			(xy 145.030959 -289.615376) (xy 145.014891 -289.668783) (xy 144.991219 -289.71928) (xy 144.960446 -289.765793)
			(xy 144.923229 -289.80733) (xy 144.880361 -289.843005) (xy 144.832755 -289.872059) (xy 144.781426 -289.893871)
			(xy 144.727469 -289.907977) (xy 144.672032 -289.914077) (xy 144.616298 -289.91204) (xy 144.561455 -289.90191)
			(xy 144.508671 -289.883903) (xy 144.459071 -289.858402) (xy 144.413713 -289.825951) (xy 144.373564 -289.787242)
			(xy 144.339478 -289.743099) (xy 144.312182 -289.694464) (xy 144.292259 -289.642373) (xy 144.280133 -289.587936)
			(xy 144.276062 -289.532314) (xy 144.150588 -289.532314) (xy 144.150079 -289.5602) (xy 144.141959 -289.615376)
			(xy 144.125891 -289.668783) (xy 144.102219 -289.71928) (xy 144.071446 -289.765793) (xy 144.034229 -289.80733)
			(xy 143.991361 -289.843005) (xy 143.943755 -289.872059) (xy 143.892426 -289.893871) (xy 143.838469 -289.907977)
			(xy 143.783032 -289.914077) (xy 143.727298 -289.91204) (xy 143.672455 -289.90191) (xy 143.619671 -289.883903)
			(xy 143.570071 -289.858402) (xy 143.524713 -289.825951) (xy 143.484564 -289.787242) (xy 143.450478 -289.743099)
			(xy 143.423182 -289.694464) (xy 143.403259 -289.642373) (xy 143.391133 -289.587936) (xy 143.387062 -289.532314)
			(xy 142.675102 -289.532314) (xy 142.674593 -289.5602) (xy 142.666473 -289.615376) (xy 142.650405 -289.668783)
			(xy 142.626733 -289.71928) (xy 142.59596 -289.765793) (xy 142.558743 -289.80733) (xy 142.515875 -289.843005)
			(xy 142.468269 -289.872059) (xy 142.41694 -289.893871) (xy 142.362983 -289.907977) (xy 142.307546 -289.914077)
			(xy 142.251812 -289.91204) (xy 142.196969 -289.90191) (xy 142.144185 -289.883903) (xy 142.094585 -289.858402)
			(xy 142.049227 -289.825951) (xy 142.009078 -289.787242) (xy 141.974992 -289.743099) (xy 141.947696 -289.694464)
			(xy 141.927773 -289.642373) (xy 141.915647 -289.587936) (xy 141.911576 -289.532314) (xy 136.349994 -289.532314)
			(xy 136.349994 -290.294314) (xy 147.43811 -290.294314) (xy 147.438654 -290.264932) (xy 147.447683 -290.206865)
			(xy 147.465514 -290.150871) (xy 147.491725 -290.098275) (xy 147.525695 -290.050324) (xy 147.56662 -290.008152)
			(xy 147.589748 -289.990022) (xy 147.598672 -289.982542) (xy 147.609132 -289.961768) (xy 147.609814 -289.950144)
			(xy 147.611084 -289.858196) (xy 147.601178 -289.837114) (xy 147.592034 -289.829748) (xy 147.570186 -289.811542)
			(xy 147.531644 -289.769724) (xy 147.499736 -289.722649) (xy 147.475169 -289.671359) (xy 147.458486 -289.616991)
			(xy 147.450058 -289.560749) (xy 147.44954 -289.532314) (xy 147.450026 -289.505063) (xy 147.457782 -289.451115)
			(xy 147.473137 -289.39882) (xy 147.495779 -289.349243) (xy 147.525245 -289.303393) (xy 147.560936 -289.262202)
			(xy 147.602127 -289.226511) (xy 147.647977 -289.197045) (xy 147.697554 -289.174403) (xy 147.749849 -289.159048)
			(xy 147.803797 -289.151292) (xy 147.858299 -289.151292) (xy 147.912247 -289.159048) (xy 147.964542 -289.174403)
			(xy 148.014119 -289.197045) (xy 148.059969 -289.226511) (xy 148.10116 -289.262202) (xy 148.136851 -289.303393)
			(xy 148.166317 -289.349243) (xy 148.188959 -289.39882) (xy 148.204314 -289.451115) (xy 148.21207 -289.505063)
			(xy 148.212556 -289.532314) (xy 148.212006 -289.561696) (xy 148.202975 -289.619761) (xy 148.185143 -289.675754)
			(xy 148.160679 -289.724846) (xy 152.169126 -289.724846) (xy 152.173086 -289.675792) (xy 152.184863 -289.628008)
			(xy 152.204154 -289.582732) (xy 152.230457 -289.541136) (xy 152.263092 -289.504299) (xy 152.301213 -289.473174)
			(xy 152.343834 -289.448567) (xy 152.38985 -289.431115) (xy 152.438069 -289.421271) (xy 152.487244 -289.41929)
			(xy 152.536099 -289.425222) (xy 152.58337 -289.438914) (xy 152.627832 -289.460012) (xy 152.668335 -289.487968)
			(xy 152.703828 -289.52206) (xy 152.733393 -289.561404) (xy 152.756264 -289.604981) (xy 152.771848 -289.651662)
			(xy 152.779743 -289.700239) (xy 152.780238 -289.724846) (xy 153.119086 -289.724846) (xy 153.123046 -289.675792)
			(xy 153.134823 -289.628008) (xy 153.154114 -289.582732) (xy 153.180417 -289.541136) (xy 153.213052 -289.504299)
			(xy 153.251173 -289.473174) (xy 153.293794 -289.448567) (xy 153.33981 -289.431115) (xy 153.388029 -289.421271)
			(xy 153.437204 -289.41929) (xy 153.486059 -289.425222) (xy 153.53333 -289.438914) (xy 153.577792 -289.460012)
			(xy 153.618295 -289.487968) (xy 153.653788 -289.52206) (xy 153.683353 -289.561404) (xy 153.706224 -289.604981)
			(xy 153.721808 -289.651662) (xy 153.729703 -289.700239) (xy 153.730198 -289.724846) (xy 154.0693 -289.724846)
			(xy 154.07326 -289.675792) (xy 154.085037 -289.628008) (xy 154.104328 -289.582732) (xy 154.130631 -289.541136)
			(xy 154.163266 -289.504299) (xy 154.201387 -289.473174) (xy 154.244008 -289.448567) (xy 154.290024 -289.431115)
			(xy 154.338243 -289.421271) (xy 154.387418 -289.41929) (xy 154.436273 -289.425222) (xy 154.483544 -289.438914)
			(xy 154.528006 -289.460012) (xy 154.568509 -289.487968) (xy 154.604002 -289.52206) (xy 154.633567 -289.561404)
			(xy 154.656438 -289.604981) (xy 154.672022 -289.651662) (xy 154.679917 -289.700239) (xy 154.680412 -289.724846)
			(xy 155.01926 -289.724846) (xy 155.02322 -289.675792) (xy 155.034997 -289.628008) (xy 155.054288 -289.582732)
			(xy 155.080591 -289.541136) (xy 155.113226 -289.504299) (xy 155.151347 -289.473174) (xy 155.193968 -289.448567)
			(xy 155.239984 -289.431115) (xy 155.288203 -289.421271) (xy 155.337378 -289.41929) (xy 155.386233 -289.425222)
			(xy 155.433504 -289.438914) (xy 155.477966 -289.460012) (xy 155.518469 -289.487968) (xy 155.553962 -289.52206)
			(xy 155.583527 -289.561404) (xy 155.606398 -289.604981) (xy 155.621982 -289.651662) (xy 155.629877 -289.700239)
			(xy 155.630372 -289.724846) (xy 155.96922 -289.724846) (xy 155.97318 -289.675792) (xy 155.984957 -289.628008)
			(xy 156.004248 -289.582732) (xy 156.030551 -289.541136) (xy 156.063186 -289.504299) (xy 156.101307 -289.473174)
			(xy 156.143928 -289.448567) (xy 156.189944 -289.431115) (xy 156.238163 -289.421271) (xy 156.287338 -289.41929)
			(xy 156.336193 -289.425222) (xy 156.383464 -289.438914) (xy 156.427926 -289.460012) (xy 156.468429 -289.487968)
			(xy 156.503922 -289.52206) (xy 156.533487 -289.561404) (xy 156.556358 -289.604981) (xy 156.571942 -289.651662)
			(xy 156.579837 -289.700239) (xy 156.580332 -289.724846) (xy 156.91918 -289.724846) (xy 156.92314 -289.675792)
			(xy 156.934917 -289.628008) (xy 156.954208 -289.582732) (xy 156.980511 -289.541136) (xy 157.013146 -289.504299)
			(xy 157.051267 -289.473174) (xy 157.093888 -289.448567) (xy 157.139904 -289.431115) (xy 157.188123 -289.421271)
			(xy 157.237298 -289.41929) (xy 157.286153 -289.425222) (xy 157.333424 -289.438914) (xy 157.377886 -289.460012)
			(xy 157.418389 -289.487968) (xy 157.453882 -289.52206) (xy 157.483447 -289.561404) (xy 157.506318 -289.604981)
			(xy 157.521902 -289.651662) (xy 157.529797 -289.700239) (xy 157.530292 -289.724846) (xy 157.86914 -289.724846)
			(xy 157.8731 -289.675792) (xy 157.884877 -289.628008) (xy 157.904168 -289.582732) (xy 157.930471 -289.541136)
			(xy 157.963106 -289.504299) (xy 158.001227 -289.473174) (xy 158.043848 -289.448567) (xy 158.089864 -289.431115)
			(xy 158.138083 -289.421271) (xy 158.187258 -289.41929) (xy 158.236113 -289.425222) (xy 158.283384 -289.438914)
			(xy 158.327846 -289.460012) (xy 158.368349 -289.487968) (xy 158.403842 -289.52206) (xy 158.433407 -289.561404)
			(xy 158.456278 -289.604981) (xy 158.471862 -289.651662) (xy 158.479757 -289.700239) (xy 158.480252 -289.724846)
			(xy 158.8191 -289.724846) (xy 158.82306 -289.675792) (xy 158.834837 -289.628008) (xy 158.854128 -289.582732)
			(xy 158.880431 -289.541136) (xy 158.913066 -289.504299) (xy 158.951187 -289.473174) (xy 158.993808 -289.448567)
			(xy 159.039824 -289.431115) (xy 159.088043 -289.421271) (xy 159.137218 -289.41929) (xy 159.186073 -289.425222)
			(xy 159.233344 -289.438914) (xy 159.277806 -289.460012) (xy 159.318309 -289.487968) (xy 159.353802 -289.52206)
			(xy 159.383367 -289.561404) (xy 159.406238 -289.604981) (xy 159.421822 -289.651662) (xy 159.429717 -289.700239)
			(xy 159.430212 -289.724846) (xy 159.76906 -289.724846) (xy 159.77302 -289.675792) (xy 159.784797 -289.628008)
			(xy 159.804088 -289.582732) (xy 159.830391 -289.541136) (xy 159.863026 -289.504299) (xy 159.901147 -289.473174)
			(xy 159.943768 -289.448567) (xy 159.989784 -289.431115) (xy 160.038003 -289.421271) (xy 160.087178 -289.41929)
			(xy 160.136033 -289.425222) (xy 160.183304 -289.438914) (xy 160.227766 -289.460012) (xy 160.268269 -289.487968)
			(xy 160.303762 -289.52206) (xy 160.333327 -289.561404) (xy 160.356198 -289.604981) (xy 160.371782 -289.651662)
			(xy 160.379677 -289.700239) (xy 160.380172 -289.724846) (xy 160.719274 -289.724846) (xy 160.723234 -289.675792)
			(xy 160.735011 -289.628008) (xy 160.754302 -289.582732) (xy 160.780605 -289.541136) (xy 160.81324 -289.504299)
			(xy 160.851361 -289.473174) (xy 160.893982 -289.448567) (xy 160.939998 -289.431115) (xy 160.988217 -289.421271)
			(xy 161.037392 -289.41929) (xy 161.086247 -289.425222) (xy 161.133518 -289.438914) (xy 161.17798 -289.460012)
			(xy 161.218483 -289.487968) (xy 161.253976 -289.52206) (xy 161.283541 -289.561404) (xy 161.306412 -289.604981)
			(xy 161.321996 -289.651662) (xy 161.329891 -289.700239) (xy 161.330386 -289.724846) (xy 161.669234 -289.724846)
			(xy 161.673194 -289.675792) (xy 161.684971 -289.628008) (xy 161.704262 -289.582732) (xy 161.730565 -289.541136)
			(xy 161.7632 -289.504299) (xy 161.801321 -289.473174) (xy 161.843942 -289.448567) (xy 161.889958 -289.431115)
			(xy 161.938177 -289.421271) (xy 161.987352 -289.41929) (xy 162.036207 -289.425222) (xy 162.083478 -289.438914)
			(xy 162.12794 -289.460012) (xy 162.168443 -289.487968) (xy 162.203936 -289.52206) (xy 162.233501 -289.561404)
			(xy 162.256372 -289.604981) (xy 162.271956 -289.651662) (xy 162.279851 -289.700239) (xy 162.280346 -289.724846)
			(xy 162.619194 -289.724846) (xy 162.623154 -289.675792) (xy 162.634931 -289.628008) (xy 162.654222 -289.582732)
			(xy 162.680525 -289.541136) (xy 162.71316 -289.504299) (xy 162.751281 -289.473174) (xy 162.793902 -289.448567)
			(xy 162.839918 -289.431115) (xy 162.888137 -289.421271) (xy 162.937312 -289.41929) (xy 162.986167 -289.425222)
			(xy 163.033438 -289.438914) (xy 163.0779 -289.460012) (xy 163.118403 -289.487968) (xy 163.153896 -289.52206)
			(xy 163.183461 -289.561404) (xy 163.206332 -289.604981) (xy 163.221916 -289.651662) (xy 163.229811 -289.700239)
			(xy 163.230306 -289.724846) (xy 163.569154 -289.724846) (xy 163.573114 -289.675792) (xy 163.584891 -289.628008)
			(xy 163.604182 -289.582732) (xy 163.630485 -289.541136) (xy 163.66312 -289.504299) (xy 163.701241 -289.473174)
			(xy 163.743862 -289.448567) (xy 163.789878 -289.431115) (xy 163.838097 -289.421271) (xy 163.887272 -289.41929)
			(xy 163.936127 -289.425222) (xy 163.983398 -289.438914) (xy 164.02786 -289.460012) (xy 164.068363 -289.487968)
			(xy 164.103856 -289.52206) (xy 164.133421 -289.561404) (xy 164.156292 -289.604981) (xy 164.171876 -289.651662)
			(xy 164.179771 -289.700239) (xy 164.180266 -289.724846) (xy 164.519114 -289.724846) (xy 164.523074 -289.675792)
			(xy 164.534851 -289.628008) (xy 164.554142 -289.582732) (xy 164.580445 -289.541136) (xy 164.61308 -289.504299)
			(xy 164.651201 -289.473174) (xy 164.693822 -289.448567) (xy 164.739838 -289.431115) (xy 164.788057 -289.421271)
			(xy 164.837232 -289.41929) (xy 164.886087 -289.425222) (xy 164.933358 -289.438914) (xy 164.97782 -289.460012)
			(xy 165.018323 -289.487968) (xy 165.053816 -289.52206) (xy 165.083381 -289.561404) (xy 165.106252 -289.604981)
			(xy 165.121836 -289.651662) (xy 165.129731 -289.700239) (xy 165.130226 -289.724846) (xy 165.129731 -289.749453)
			(xy 165.121836 -289.79803) (xy 165.106252 -289.844711) (xy 165.083381 -289.888288) (xy 165.053816 -289.927632)
			(xy 165.018323 -289.961724) (xy 164.97782 -289.98968) (xy 164.933358 -290.010778) (xy 164.886087 -290.02447)
			(xy 164.837232 -290.030402) (xy 164.788057 -290.028421) (xy 164.739838 -290.018577) (xy 164.693822 -290.001125)
			(xy 164.651201 -289.976518) (xy 164.61308 -289.945393) (xy 164.580445 -289.908556) (xy 164.554142 -289.86696)
			(xy 164.534851 -289.821684) (xy 164.523074 -289.7739) (xy 164.519114 -289.724846) (xy 164.180266 -289.724846)
			(xy 164.179771 -289.749453) (xy 164.171876 -289.79803) (xy 164.156292 -289.844711) (xy 164.133421 -289.888288)
			(xy 164.103856 -289.927632) (xy 164.068363 -289.961724) (xy 164.02786 -289.98968) (xy 163.983398 -290.010778)
			(xy 163.936127 -290.02447) (xy 163.887272 -290.030402) (xy 163.838097 -290.028421) (xy 163.789878 -290.018577)
			(xy 163.743862 -290.001125) (xy 163.701241 -289.976518) (xy 163.66312 -289.945393) (xy 163.630485 -289.908556)
			(xy 163.604182 -289.86696) (xy 163.584891 -289.821684) (xy 163.573114 -289.7739) (xy 163.569154 -289.724846)
			(xy 163.230306 -289.724846) (xy 163.229811 -289.749453) (xy 163.221916 -289.79803) (xy 163.206332 -289.844711)
			(xy 163.183461 -289.888288) (xy 163.153896 -289.927632) (xy 163.118403 -289.961724) (xy 163.0779 -289.98968)
			(xy 163.033438 -290.010778) (xy 162.986167 -290.02447) (xy 162.937312 -290.030402) (xy 162.888137 -290.028421)
			(xy 162.839918 -290.018577) (xy 162.793902 -290.001125) (xy 162.751281 -289.976518) (xy 162.71316 -289.945393)
			(xy 162.680525 -289.908556) (xy 162.654222 -289.86696) (xy 162.634931 -289.821684) (xy 162.623154 -289.7739)
			(xy 162.619194 -289.724846) (xy 162.280346 -289.724846) (xy 162.279851 -289.749453) (xy 162.271956 -289.79803)
			(xy 162.256372 -289.844711) (xy 162.233501 -289.888288) (xy 162.203936 -289.927632) (xy 162.168443 -289.961724)
			(xy 162.12794 -289.98968) (xy 162.083478 -290.010778) (xy 162.036207 -290.02447) (xy 161.987352 -290.030402)
			(xy 161.938177 -290.028421) (xy 161.889958 -290.018577) (xy 161.843942 -290.001125) (xy 161.801321 -289.976518)
			(xy 161.7632 -289.945393) (xy 161.730565 -289.908556) (xy 161.704262 -289.86696) (xy 161.684971 -289.821684)
			(xy 161.673194 -289.7739) (xy 161.669234 -289.724846) (xy 161.330386 -289.724846) (xy 161.329891 -289.749453)
			(xy 161.321996 -289.79803) (xy 161.306412 -289.844711) (xy 161.283541 -289.888288) (xy 161.253976 -289.927632)
			(xy 161.218483 -289.961724) (xy 161.17798 -289.98968) (xy 161.133518 -290.010778) (xy 161.086247 -290.02447)
			(xy 161.037392 -290.030402) (xy 160.988217 -290.028421) (xy 160.939998 -290.018577) (xy 160.893982 -290.001125)
			(xy 160.851361 -289.976518) (xy 160.81324 -289.945393) (xy 160.780605 -289.908556) (xy 160.754302 -289.86696)
			(xy 160.735011 -289.821684) (xy 160.723234 -289.7739) (xy 160.719274 -289.724846) (xy 160.380172 -289.724846)
			(xy 160.379677 -289.749453) (xy 160.371782 -289.79803) (xy 160.356198 -289.844711) (xy 160.333327 -289.888288)
			(xy 160.303762 -289.927632) (xy 160.268269 -289.961724) (xy 160.227766 -289.98968) (xy 160.183304 -290.010778)
			(xy 160.136033 -290.02447) (xy 160.087178 -290.030402) (xy 160.038003 -290.028421) (xy 159.989784 -290.018577)
			(xy 159.943768 -290.001125) (xy 159.901147 -289.976518) (xy 159.863026 -289.945393) (xy 159.830391 -289.908556)
			(xy 159.804088 -289.86696) (xy 159.784797 -289.821684) (xy 159.77302 -289.7739) (xy 159.76906 -289.724846)
			(xy 159.430212 -289.724846) (xy 159.429717 -289.749453) (xy 159.421822 -289.79803) (xy 159.406238 -289.844711)
			(xy 159.383367 -289.888288) (xy 159.353802 -289.927632) (xy 159.318309 -289.961724) (xy 159.277806 -289.98968)
			(xy 159.233344 -290.010778) (xy 159.186073 -290.02447) (xy 159.137218 -290.030402) (xy 159.088043 -290.028421)
			(xy 159.039824 -290.018577) (xy 158.993808 -290.001125) (xy 158.951187 -289.976518) (xy 158.913066 -289.945393)
			(xy 158.880431 -289.908556) (xy 158.854128 -289.86696) (xy 158.834837 -289.821684) (xy 158.82306 -289.7739)
			(xy 158.8191 -289.724846) (xy 158.480252 -289.724846) (xy 158.479757 -289.749453) (xy 158.471862 -289.79803)
			(xy 158.456278 -289.844711) (xy 158.433407 -289.888288) (xy 158.403842 -289.927632) (xy 158.368349 -289.961724)
			(xy 158.327846 -289.98968) (xy 158.283384 -290.010778) (xy 158.236113 -290.02447) (xy 158.187258 -290.030402)
			(xy 158.138083 -290.028421) (xy 158.089864 -290.018577) (xy 158.043848 -290.001125) (xy 158.001227 -289.976518)
			(xy 157.963106 -289.945393) (xy 157.930471 -289.908556) (xy 157.904168 -289.86696) (xy 157.884877 -289.821684)
			(xy 157.8731 -289.7739) (xy 157.86914 -289.724846) (xy 157.530292 -289.724846) (xy 157.529797 -289.749453)
			(xy 157.521902 -289.79803) (xy 157.506318 -289.844711) (xy 157.483447 -289.888288) (xy 157.453882 -289.927632)
			(xy 157.418389 -289.961724) (xy 157.377886 -289.98968) (xy 157.333424 -290.010778) (xy 157.286153 -290.02447)
			(xy 157.237298 -290.030402) (xy 157.188123 -290.028421) (xy 157.139904 -290.018577) (xy 157.093888 -290.001125)
			(xy 157.051267 -289.976518) (xy 157.013146 -289.945393) (xy 156.980511 -289.908556) (xy 156.954208 -289.86696)
			(xy 156.934917 -289.821684) (xy 156.92314 -289.7739) (xy 156.91918 -289.724846) (xy 156.580332 -289.724846)
			(xy 156.579837 -289.749453) (xy 156.571942 -289.79803) (xy 156.556358 -289.844711) (xy 156.533487 -289.888288)
			(xy 156.503922 -289.927632) (xy 156.468429 -289.961724) (xy 156.427926 -289.98968) (xy 156.383464 -290.010778)
			(xy 156.336193 -290.02447) (xy 156.287338 -290.030402) (xy 156.238163 -290.028421) (xy 156.189944 -290.018577)
			(xy 156.143928 -290.001125) (xy 156.101307 -289.976518) (xy 156.063186 -289.945393) (xy 156.030551 -289.908556)
			(xy 156.004248 -289.86696) (xy 155.984957 -289.821684) (xy 155.97318 -289.7739) (xy 155.96922 -289.724846)
			(xy 155.630372 -289.724846) (xy 155.629877 -289.749453) (xy 155.621982 -289.79803) (xy 155.606398 -289.844711)
			(xy 155.583527 -289.888288) (xy 155.553962 -289.927632) (xy 155.518469 -289.961724) (xy 155.477966 -289.98968)
			(xy 155.433504 -290.010778) (xy 155.386233 -290.02447) (xy 155.337378 -290.030402) (xy 155.288203 -290.028421)
			(xy 155.239984 -290.018577) (xy 155.193968 -290.001125) (xy 155.151347 -289.976518) (xy 155.113226 -289.945393)
			(xy 155.080591 -289.908556) (xy 155.054288 -289.86696) (xy 155.034997 -289.821684) (xy 155.02322 -289.7739)
			(xy 155.01926 -289.724846) (xy 154.680412 -289.724846) (xy 154.679917 -289.749453) (xy 154.672022 -289.79803)
			(xy 154.656438 -289.844711) (xy 154.633567 -289.888288) (xy 154.604002 -289.927632) (xy 154.568509 -289.961724)
			(xy 154.528006 -289.98968) (xy 154.483544 -290.010778) (xy 154.436273 -290.02447) (xy 154.387418 -290.030402)
			(xy 154.338243 -290.028421) (xy 154.290024 -290.018577) (xy 154.244008 -290.001125) (xy 154.201387 -289.976518)
			(xy 154.163266 -289.945393) (xy 154.130631 -289.908556) (xy 154.104328 -289.86696) (xy 154.085037 -289.821684)
			(xy 154.07326 -289.7739) (xy 154.0693 -289.724846) (xy 153.730198 -289.724846) (xy 153.729703 -289.749453)
			(xy 153.721808 -289.79803) (xy 153.706224 -289.844711) (xy 153.683353 -289.888288) (xy 153.653788 -289.927632)
			(xy 153.618295 -289.961724) (xy 153.577792 -289.98968) (xy 153.53333 -290.010778) (xy 153.486059 -290.02447)
			(xy 153.437204 -290.030402) (xy 153.388029 -290.028421) (xy 153.33981 -290.018577) (xy 153.293794 -290.001125)
			(xy 153.251173 -289.976518) (xy 153.213052 -289.945393) (xy 153.180417 -289.908556) (xy 153.154114 -289.86696)
			(xy 153.134823 -289.821684) (xy 153.123046 -289.7739) (xy 153.119086 -289.724846) (xy 152.780238 -289.724846)
			(xy 152.779743 -289.749453) (xy 152.771848 -289.79803) (xy 152.756264 -289.844711) (xy 152.733393 -289.888288)
			(xy 152.703828 -289.927632) (xy 152.668335 -289.961724) (xy 152.627832 -289.98968) (xy 152.58337 -290.010778)
			(xy 152.536099 -290.02447) (xy 152.487244 -290.030402) (xy 152.438069 -290.028421) (xy 152.38985 -290.018577)
			(xy 152.343834 -290.001125) (xy 152.301213 -289.976518) (xy 152.263092 -289.945393) (xy 152.230457 -289.908556)
			(xy 152.204154 -289.86696) (xy 152.184863 -289.821684) (xy 152.173086 -289.7739) (xy 152.169126 -289.724846)
			(xy 148.160679 -289.724846) (xy 148.158933 -289.728349) (xy 148.124966 -289.776301) (xy 148.084044 -289.818474)
			(xy 148.060918 -289.836606) (xy 148.051975 -289.844067) (xy 148.041527 -289.864856) (xy 148.040852 -289.876484)
			(xy 148.039582 -289.968432) (xy 148.049488 -289.989514) (xy 148.058632 -289.99688) (xy 148.080459 -290.015109)
			(xy 148.118999 -290.056924) (xy 148.150908 -290.103995) (xy 148.175478 -290.15528) (xy 148.192166 -290.209643)
			(xy 148.200603 -290.265881) (xy 148.201126 -290.294314) (xy 148.8346 -290.294314) (xy 148.838671 -290.238692)
			(xy 148.850797 -290.184255) (xy 148.87072 -290.132164) (xy 148.898016 -290.083529) (xy 148.932102 -290.039386)
			(xy 148.972251 -290.000677) (xy 149.017609 -289.968226) (xy 149.067209 -289.942725) (xy 149.119993 -289.924718)
			(xy 149.174836 -289.914588) (xy 149.23057 -289.912551) (xy 149.286007 -289.918651) (xy 149.339964 -289.932757)
			(xy 149.391293 -289.954569) (xy 149.438899 -289.983623) (xy 149.481767 -290.019298) (xy 149.518984 -290.060835)
			(xy 149.549757 -290.107348) (xy 149.573429 -290.157845) (xy 149.589497 -290.211252) (xy 149.597617 -290.266428)
			(xy 149.598126 -290.294314) (xy 149.72106 -290.294314) (xy 149.725131 -290.238692) (xy 149.737257 -290.184255)
			(xy 149.75718 -290.132164) (xy 149.784476 -290.083529) (xy 149.818562 -290.039386) (xy 149.858711 -290.000677)
			(xy 149.904069 -289.968226) (xy 149.953669 -289.942725) (xy 150.006453 -289.924718) (xy 150.061296 -289.914588)
			(xy 150.11703 -289.912551) (xy 150.172467 -289.918651) (xy 150.226424 -289.932757) (xy 150.277753 -289.954569)
			(xy 150.325359 -289.983623) (xy 150.368227 -290.019298) (xy 150.405444 -290.060835) (xy 150.436217 -290.107348)
			(xy 150.459889 -290.157845) (xy 150.475957 -290.211252) (xy 150.484077 -290.266428) (xy 150.484586 -290.294314)
			(xy 150.484077 -290.3222) (xy 150.475957 -290.377376) (xy 150.459889 -290.430783) (xy 150.436217 -290.48128)
			(xy 150.405444 -290.527793) (xy 150.368227 -290.56933) (xy 150.325359 -290.605005) (xy 150.277753 -290.634059)
			(xy 150.226424 -290.655871) (xy 150.172467 -290.669977) (xy 150.128581 -290.674806) (xy 152.169126 -290.674806)
			(xy 152.173086 -290.625752) (xy 152.184863 -290.577968) (xy 152.204154 -290.532692) (xy 152.230457 -290.491096)
			(xy 152.263092 -290.454259) (xy 152.301213 -290.423134) (xy 152.343834 -290.398527) (xy 152.38985 -290.381075)
			(xy 152.438069 -290.371231) (xy 152.487244 -290.36925) (xy 152.536099 -290.375182) (xy 152.58337 -290.388874)
			(xy 152.627832 -290.409972) (xy 152.668335 -290.437928) (xy 152.703828 -290.47202) (xy 152.733393 -290.511364)
			(xy 152.756264 -290.554941) (xy 152.771848 -290.601622) (xy 152.779743 -290.650199) (xy 152.780238 -290.674806)
			(xy 153.119086 -290.674806) (xy 153.123046 -290.625752) (xy 153.134823 -290.577968) (xy 153.154114 -290.532692)
			(xy 153.180417 -290.491096) (xy 153.213052 -290.454259) (xy 153.251173 -290.423134) (xy 153.293794 -290.398527)
			(xy 153.33981 -290.381075) (xy 153.388029 -290.371231) (xy 153.437204 -290.36925) (xy 153.486059 -290.375182)
			(xy 153.53333 -290.388874) (xy 153.577792 -290.409972) (xy 153.618295 -290.437928) (xy 153.653788 -290.47202)
			(xy 153.683353 -290.511364) (xy 153.706224 -290.554941) (xy 153.721808 -290.601622) (xy 153.729703 -290.650199)
			(xy 153.730198 -290.674806) (xy 154.0693 -290.674806) (xy 154.07326 -290.625752) (xy 154.085037 -290.577968)
			(xy 154.104328 -290.532692) (xy 154.130631 -290.491096) (xy 154.163266 -290.454259) (xy 154.201387 -290.423134)
			(xy 154.244008 -290.398527) (xy 154.290024 -290.381075) (xy 154.338243 -290.371231) (xy 154.387418 -290.36925)
			(xy 154.436273 -290.375182) (xy 154.483544 -290.388874) (xy 154.528006 -290.409972) (xy 154.568509 -290.437928)
			(xy 154.604002 -290.47202) (xy 154.633567 -290.511364) (xy 154.656438 -290.554941) (xy 154.672022 -290.601622)
			(xy 154.679917 -290.650199) (xy 154.680412 -290.674806) (xy 156.91918 -290.674806) (xy 156.92314 -290.625752)
			(xy 156.934917 -290.577968) (xy 156.954208 -290.532692) (xy 156.980511 -290.491096) (xy 157.013146 -290.454259)
			(xy 157.051267 -290.423134) (xy 157.093888 -290.398527) (xy 157.139904 -290.381075) (xy 157.188123 -290.371231)
			(xy 157.237298 -290.36925) (xy 157.286153 -290.375182) (xy 157.333424 -290.388874) (xy 157.377886 -290.409972)
			(xy 157.418389 -290.437928) (xy 157.453882 -290.47202) (xy 157.483447 -290.511364) (xy 157.506318 -290.554941)
			(xy 157.521902 -290.601622) (xy 157.529797 -290.650199) (xy 157.530292 -290.674806) (xy 157.86914 -290.674806)
			(xy 157.8731 -290.625752) (xy 157.884877 -290.577968) (xy 157.904168 -290.532692) (xy 157.930471 -290.491096)
			(xy 157.963106 -290.454259) (xy 158.001227 -290.423134) (xy 158.043848 -290.398527) (xy 158.089864 -290.381075)
			(xy 158.138083 -290.371231) (xy 158.187258 -290.36925) (xy 158.236113 -290.375182) (xy 158.283384 -290.388874)
			(xy 158.327846 -290.409972) (xy 158.368349 -290.437928) (xy 158.403842 -290.47202) (xy 158.433407 -290.511364)
			(xy 158.456278 -290.554941) (xy 158.471862 -290.601622) (xy 158.479757 -290.650199) (xy 158.480252 -290.674806)
			(xy 158.8191 -290.674806) (xy 158.82306 -290.625752) (xy 158.834837 -290.577968) (xy 158.854128 -290.532692)
			(xy 158.880431 -290.491096) (xy 158.913066 -290.454259) (xy 158.951187 -290.423134) (xy 158.993808 -290.398527)
			(xy 159.039824 -290.381075) (xy 159.088043 -290.371231) (xy 159.137218 -290.36925) (xy 159.186073 -290.375182)
			(xy 159.233344 -290.388874) (xy 159.277806 -290.409972) (xy 159.318309 -290.437928) (xy 159.353802 -290.47202)
			(xy 159.383367 -290.511364) (xy 159.406238 -290.554941) (xy 159.421822 -290.601622) (xy 159.429717 -290.650199)
			(xy 159.430212 -290.674806) (xy 159.76906 -290.674806) (xy 159.77302 -290.625752) (xy 159.784797 -290.577968)
			(xy 159.804088 -290.532692) (xy 159.830391 -290.491096) (xy 159.863026 -290.454259) (xy 159.901147 -290.423134)
			(xy 159.943768 -290.398527) (xy 159.989784 -290.381075) (xy 160.038003 -290.371231) (xy 160.087178 -290.36925)
			(xy 160.136033 -290.375182) (xy 160.183304 -290.388874) (xy 160.227766 -290.409972) (xy 160.268269 -290.437928)
			(xy 160.303762 -290.47202) (xy 160.333327 -290.511364) (xy 160.356198 -290.554941) (xy 160.371782 -290.601622)
			(xy 160.379677 -290.650199) (xy 160.380172 -290.674806) (xy 160.719274 -290.674806) (xy 160.723234 -290.625752)
			(xy 160.735011 -290.577968) (xy 160.754302 -290.532692) (xy 160.780605 -290.491096) (xy 160.81324 -290.454259)
			(xy 160.851361 -290.423134) (xy 160.893982 -290.398527) (xy 160.939998 -290.381075) (xy 160.988217 -290.371231)
			(xy 161.037392 -290.36925) (xy 161.086247 -290.375182) (xy 161.133518 -290.388874) (xy 161.17798 -290.409972)
			(xy 161.218483 -290.437928) (xy 161.253976 -290.47202) (xy 161.283541 -290.511364) (xy 161.306412 -290.554941)
			(xy 161.321996 -290.601622) (xy 161.329891 -290.650199) (xy 161.330386 -290.674806) (xy 161.669234 -290.674806)
			(xy 161.673194 -290.625752) (xy 161.684971 -290.577968) (xy 161.704262 -290.532692) (xy 161.730565 -290.491096)
			(xy 161.7632 -290.454259) (xy 161.801321 -290.423134) (xy 161.843942 -290.398527) (xy 161.889958 -290.381075)
			(xy 161.938177 -290.371231) (xy 161.987352 -290.36925) (xy 162.036207 -290.375182) (xy 162.083478 -290.388874)
			(xy 162.12794 -290.409972) (xy 162.168443 -290.437928) (xy 162.203936 -290.47202) (xy 162.233501 -290.511364)
			(xy 162.256372 -290.554941) (xy 162.271956 -290.601622) (xy 162.279851 -290.650199) (xy 162.280346 -290.674806)
			(xy 162.619194 -290.674806) (xy 162.623154 -290.625752) (xy 162.634931 -290.577968) (xy 162.654222 -290.532692)
			(xy 162.680525 -290.491096) (xy 162.71316 -290.454259) (xy 162.751281 -290.423134) (xy 162.793902 -290.398527)
			(xy 162.839918 -290.381075) (xy 162.888137 -290.371231) (xy 162.937312 -290.36925) (xy 162.986167 -290.375182)
			(xy 163.033438 -290.388874) (xy 163.0779 -290.409972) (xy 163.118403 -290.437928) (xy 163.153896 -290.47202)
			(xy 163.183461 -290.511364) (xy 163.206332 -290.554941) (xy 163.221916 -290.601622) (xy 163.229811 -290.650199)
			(xy 163.230306 -290.674806) (xy 163.569154 -290.674806) (xy 163.573114 -290.625752) (xy 163.584891 -290.577968)
			(xy 163.604182 -290.532692) (xy 163.630485 -290.491096) (xy 163.66312 -290.454259) (xy 163.701241 -290.423134)
			(xy 163.743862 -290.398527) (xy 163.789878 -290.381075) (xy 163.838097 -290.371231) (xy 163.887272 -290.36925)
			(xy 163.936127 -290.375182) (xy 163.983398 -290.388874) (xy 164.02786 -290.409972) (xy 164.068363 -290.437928)
			(xy 164.103856 -290.47202) (xy 164.133421 -290.511364) (xy 164.156292 -290.554941) (xy 164.171876 -290.601622)
			(xy 164.179771 -290.650199) (xy 164.180266 -290.674806) (xy 165.469074 -290.674806) (xy 165.473034 -290.625752)
			(xy 165.484811 -290.577968) (xy 165.504102 -290.532692) (xy 165.530405 -290.491096) (xy 165.56304 -290.454259)
			(xy 165.601161 -290.423134) (xy 165.643782 -290.398527) (xy 165.689798 -290.381075) (xy 165.738017 -290.371231)
			(xy 165.787192 -290.36925) (xy 165.836047 -290.375182) (xy 165.883318 -290.388874) (xy 165.92778 -290.409972)
			(xy 165.968283 -290.437928) (xy 166.003776 -290.47202) (xy 166.033341 -290.511364) (xy 166.056212 -290.554941)
			(xy 166.071796 -290.601622) (xy 166.079691 -290.650199) (xy 166.080186 -290.674806) (xy 166.419288 -290.674806)
			(xy 166.423248 -290.625752) (xy 166.435025 -290.577968) (xy 166.454316 -290.532692) (xy 166.480619 -290.491096)
			(xy 166.513254 -290.454259) (xy 166.551375 -290.423134) (xy 166.593996 -290.398527) (xy 166.640012 -290.381075)
			(xy 166.688231 -290.371231) (xy 166.737406 -290.36925) (xy 166.786261 -290.375182) (xy 166.833532 -290.388874)
			(xy 166.877994 -290.409972) (xy 166.918497 -290.437928) (xy 166.95399 -290.47202) (xy 166.983555 -290.511364)
			(xy 167.006426 -290.554941) (xy 167.02201 -290.601622) (xy 167.029905 -290.650199) (xy 167.0304 -290.674806)
			(xy 167.369248 -290.674806) (xy 167.373208 -290.625752) (xy 167.384985 -290.577968) (xy 167.404276 -290.532692)
			(xy 167.430579 -290.491096) (xy 167.463214 -290.454259) (xy 167.501335 -290.423134) (xy 167.543956 -290.398527)
			(xy 167.589972 -290.381075) (xy 167.638191 -290.371231) (xy 167.687366 -290.36925) (xy 167.736221 -290.375182)
			(xy 167.783492 -290.388874) (xy 167.827954 -290.409972) (xy 167.868457 -290.437928) (xy 167.90395 -290.47202)
			(xy 167.933515 -290.511364) (xy 167.956386 -290.554941) (xy 167.97197 -290.601622) (xy 167.979865 -290.650199)
			(xy 167.98036 -290.674806) (xy 168.319208 -290.674806) (xy 168.323168 -290.625752) (xy 168.334945 -290.577968)
			(xy 168.354236 -290.532692) (xy 168.380539 -290.491096) (xy 168.413174 -290.454259) (xy 168.451295 -290.423134)
			(xy 168.493916 -290.398527) (xy 168.539932 -290.381075) (xy 168.588151 -290.371231) (xy 168.637326 -290.36925)
			(xy 168.686181 -290.375182) (xy 168.733452 -290.388874) (xy 168.777914 -290.409972) (xy 168.818417 -290.437928)
			(xy 168.85391 -290.47202) (xy 168.883475 -290.511364) (xy 168.906346 -290.554941) (xy 168.92193 -290.601622)
			(xy 168.929825 -290.650199) (xy 168.93032 -290.674806) (xy 169.269168 -290.674806) (xy 169.273128 -290.625752)
			(xy 169.284905 -290.577968) (xy 169.304196 -290.532692) (xy 169.330499 -290.491096) (xy 169.363134 -290.454259)
			(xy 169.401255 -290.423134) (xy 169.443876 -290.398527) (xy 169.489892 -290.381075) (xy 169.538111 -290.371231)
			(xy 169.587286 -290.36925) (xy 169.636141 -290.375182) (xy 169.683412 -290.388874) (xy 169.727874 -290.409972)
			(xy 169.768377 -290.437928) (xy 169.80387 -290.47202) (xy 169.833435 -290.511364) (xy 169.856306 -290.554941)
			(xy 169.87189 -290.601622) (xy 169.879785 -290.650199) (xy 169.88028 -290.674806) (xy 170.219128 -290.674806)
			(xy 170.223088 -290.625752) (xy 170.234865 -290.577968) (xy 170.254156 -290.532692) (xy 170.280459 -290.491096)
			(xy 170.313094 -290.454259) (xy 170.351215 -290.423134) (xy 170.393836 -290.398527) (xy 170.439852 -290.381075)
			(xy 170.488071 -290.371231) (xy 170.537246 -290.36925) (xy 170.586101 -290.375182) (xy 170.633372 -290.388874)
			(xy 170.677834 -290.409972) (xy 170.718337 -290.437928) (xy 170.75383 -290.47202) (xy 170.783395 -290.511364)
			(xy 170.806266 -290.554941) (xy 170.82185 -290.601622) (xy 170.829745 -290.650199) (xy 170.83024 -290.674806)
			(xy 171.169088 -290.674806) (xy 171.173048 -290.625752) (xy 171.184825 -290.577968) (xy 171.204116 -290.532692)
			(xy 171.230419 -290.491096) (xy 171.263054 -290.454259) (xy 171.301175 -290.423134) (xy 171.343796 -290.398527)
			(xy 171.389812 -290.381075) (xy 171.438031 -290.371231) (xy 171.487206 -290.36925) (xy 171.536061 -290.375182)
			(xy 171.583332 -290.388874) (xy 171.627794 -290.409972) (xy 171.668297 -290.437928) (xy 171.70379 -290.47202)
			(xy 171.733355 -290.511364) (xy 171.756226 -290.554941) (xy 171.77181 -290.601622) (xy 171.779705 -290.650199)
			(xy 171.7802 -290.674806) (xy 172.119048 -290.674806) (xy 172.123008 -290.625752) (xy 172.134785 -290.577968)
			(xy 172.154076 -290.532692) (xy 172.180379 -290.491096) (xy 172.213014 -290.454259) (xy 172.251135 -290.423134)
			(xy 172.293756 -290.398527) (xy 172.339772 -290.381075) (xy 172.387991 -290.371231) (xy 172.437166 -290.36925)
			(xy 172.486021 -290.375182) (xy 172.533292 -290.388874) (xy 172.577754 -290.409972) (xy 172.618257 -290.437928)
			(xy 172.65375 -290.47202) (xy 172.683315 -290.511364) (xy 172.706186 -290.554941) (xy 172.72177 -290.601622)
			(xy 172.729665 -290.650199) (xy 172.73016 -290.674806) (xy 173.069262 -290.674806) (xy 173.073222 -290.625752)
			(xy 173.084999 -290.577968) (xy 173.10429 -290.532692) (xy 173.130593 -290.491096) (xy 173.163228 -290.454259)
			(xy 173.201349 -290.423134) (xy 173.24397 -290.398527) (xy 173.289986 -290.381075) (xy 173.338205 -290.371231)
			(xy 173.38738 -290.36925) (xy 173.436235 -290.375182) (xy 173.483506 -290.388874) (xy 173.527968 -290.409972)
			(xy 173.568471 -290.437928) (xy 173.603964 -290.47202) (xy 173.633529 -290.511364) (xy 173.6564 -290.554941)
			(xy 173.671984 -290.601622) (xy 173.679879 -290.650199) (xy 173.680374 -290.674806) (xy 174.019222 -290.674806)
			(xy 174.023182 -290.625752) (xy 174.034959 -290.577968) (xy 174.05425 -290.532692) (xy 174.080553 -290.491096)
			(xy 174.113188 -290.454259) (xy 174.151309 -290.423134) (xy 174.19393 -290.398527) (xy 174.239946 -290.381075)
			(xy 174.288165 -290.371231) (xy 174.33734 -290.36925) (xy 174.386195 -290.375182) (xy 174.433466 -290.388874)
			(xy 174.477928 -290.409972) (xy 174.518431 -290.437928) (xy 174.553924 -290.47202) (xy 174.583489 -290.511364)
			(xy 174.60636 -290.554941) (xy 174.621944 -290.601622) (xy 174.629839 -290.650199) (xy 174.630334 -290.674806)
			(xy 175.919142 -290.674806) (xy 175.923102 -290.625752) (xy 175.934879 -290.577968) (xy 175.95417 -290.532692)
			(xy 175.980473 -290.491096) (xy 176.013108 -290.454259) (xy 176.051229 -290.423134) (xy 176.09385 -290.398527)
			(xy 176.139866 -290.381075) (xy 176.188085 -290.371231) (xy 176.23726 -290.36925) (xy 176.286115 -290.375182)
			(xy 176.333386 -290.388874) (xy 176.377848 -290.409972) (xy 176.418351 -290.437928) (xy 176.453844 -290.47202)
			(xy 176.483409 -290.511364) (xy 176.50628 -290.554941) (xy 176.521864 -290.601622) (xy 176.529759 -290.650199)
			(xy 176.530254 -290.674806) (xy 176.869102 -290.674806) (xy 176.873062 -290.625752) (xy 176.884839 -290.577968)
			(xy 176.90413 -290.532692) (xy 176.930433 -290.491096) (xy 176.963068 -290.454259) (xy 177.001189 -290.423134)
			(xy 177.04381 -290.398527) (xy 177.089826 -290.381075) (xy 177.138045 -290.371231) (xy 177.18722 -290.36925)
			(xy 177.236075 -290.375182) (xy 177.283346 -290.388874) (xy 177.327808 -290.409972) (xy 177.368311 -290.437928)
			(xy 177.403804 -290.47202) (xy 177.433369 -290.511364) (xy 177.45624 -290.554941) (xy 177.471824 -290.601622)
			(xy 177.479719 -290.650199) (xy 177.480214 -290.674806) (xy 177.819062 -290.674806) (xy 177.823022 -290.625752)
			(xy 177.834799 -290.577968) (xy 177.85409 -290.532692) (xy 177.880393 -290.491096) (xy 177.913028 -290.454259)
			(xy 177.951149 -290.423134) (xy 177.99377 -290.398527) (xy 178.039786 -290.381075) (xy 178.088005 -290.371231)
			(xy 178.13718 -290.36925) (xy 178.186035 -290.375182) (xy 178.233306 -290.388874) (xy 178.277768 -290.409972)
			(xy 178.318271 -290.437928) (xy 178.353764 -290.47202) (xy 178.383329 -290.511364) (xy 178.4062 -290.554941)
			(xy 178.421784 -290.601622) (xy 178.429679 -290.650199) (xy 178.430174 -290.674806) (xy 178.769276 -290.674806)
			(xy 178.773236 -290.625752) (xy 178.785013 -290.577968) (xy 178.804304 -290.532692) (xy 178.830607 -290.491096)
			(xy 178.863242 -290.454259) (xy 178.901363 -290.423134) (xy 178.943984 -290.398527) (xy 178.99 -290.381075)
			(xy 179.038219 -290.371231) (xy 179.087394 -290.36925) (xy 179.136249 -290.375182) (xy 179.18352 -290.388874)
			(xy 179.227982 -290.409972) (xy 179.268485 -290.437928) (xy 179.303978 -290.47202) (xy 179.333543 -290.511364)
			(xy 179.356414 -290.554941) (xy 179.371998 -290.601622) (xy 179.379893 -290.650199) (xy 179.380388 -290.674806)
			(xy 179.719236 -290.674806) (xy 179.723196 -290.625752) (xy 179.734973 -290.577968) (xy 179.754264 -290.532692)
			(xy 179.780567 -290.491096) (xy 179.813202 -290.454259) (xy 179.851323 -290.423134) (xy 179.893944 -290.398527)
			(xy 179.93996 -290.381075) (xy 179.988179 -290.371231) (xy 180.037354 -290.36925) (xy 180.086209 -290.375182)
			(xy 180.13348 -290.388874) (xy 180.177942 -290.409972) (xy 180.218445 -290.437928) (xy 180.253938 -290.47202)
			(xy 180.283503 -290.511364) (xy 180.306374 -290.554941) (xy 180.321958 -290.601622) (xy 180.329853 -290.650199)
			(xy 180.330348 -290.674806) (xy 180.669196 -290.674806) (xy 180.673156 -290.625752) (xy 180.684933 -290.577968)
			(xy 180.704224 -290.532692) (xy 180.730527 -290.491096) (xy 180.763162 -290.454259) (xy 180.801283 -290.423134)
			(xy 180.843904 -290.398527) (xy 180.88992 -290.381075) (xy 180.938139 -290.371231) (xy 180.987314 -290.36925)
			(xy 181.036169 -290.375182) (xy 181.08344 -290.388874) (xy 181.127902 -290.409972) (xy 181.168405 -290.437928)
			(xy 181.203898 -290.47202) (xy 181.233463 -290.511364) (xy 181.256334 -290.554941) (xy 181.271918 -290.601622)
			(xy 181.279813 -290.650199) (xy 181.280308 -290.674806) (xy 181.619156 -290.674806) (xy 181.623116 -290.625752)
			(xy 181.634893 -290.577968) (xy 181.654184 -290.532692) (xy 181.680487 -290.491096) (xy 181.713122 -290.454259)
			(xy 181.751243 -290.423134) (xy 181.793864 -290.398527) (xy 181.83988 -290.381075) (xy 181.888099 -290.371231)
			(xy 181.937274 -290.36925) (xy 181.986129 -290.375182) (xy 182.0334 -290.388874) (xy 182.077862 -290.409972)
			(xy 182.118365 -290.437928) (xy 182.153858 -290.47202) (xy 182.183423 -290.511364) (xy 182.206294 -290.554941)
			(xy 182.221878 -290.601622) (xy 182.229773 -290.650199) (xy 182.230268 -290.674806) (xy 182.569116 -290.674806)
			(xy 182.573076 -290.625752) (xy 182.584853 -290.577968) (xy 182.604144 -290.532692) (xy 182.630447 -290.491096)
			(xy 182.663082 -290.454259) (xy 182.701203 -290.423134) (xy 182.743824 -290.398527) (xy 182.78984 -290.381075)
			(xy 182.838059 -290.371231) (xy 182.887234 -290.36925) (xy 182.936089 -290.375182) (xy 182.98336 -290.388874)
			(xy 183.027822 -290.409972) (xy 183.068325 -290.437928) (xy 183.103818 -290.47202) (xy 183.133383 -290.511364)
			(xy 183.156254 -290.554941) (xy 183.171838 -290.601622) (xy 183.179733 -290.650199) (xy 183.180228 -290.674806)
			(xy 183.519076 -290.674806) (xy 183.523036 -290.625752) (xy 183.534813 -290.577968) (xy 183.554104 -290.532692)
			(xy 183.580407 -290.491096) (xy 183.613042 -290.454259) (xy 183.651163 -290.423134) (xy 183.693784 -290.398527)
			(xy 183.7398 -290.381075) (xy 183.788019 -290.371231) (xy 183.837194 -290.36925) (xy 183.886049 -290.375182)
			(xy 183.93332 -290.388874) (xy 183.977782 -290.409972) (xy 184.018285 -290.437928) (xy 184.053778 -290.47202)
			(xy 184.083343 -290.511364) (xy 184.106214 -290.554941) (xy 184.121798 -290.601622) (xy 184.129693 -290.650199)
			(xy 184.130188 -290.674806) (xy 184.129693 -290.699413) (xy 184.121798 -290.74799) (xy 184.106214 -290.794671)
			(xy 184.083343 -290.838248) (xy 184.053778 -290.877592) (xy 184.018285 -290.911684) (xy 183.977782 -290.93964)
			(xy 183.93332 -290.960738) (xy 183.886049 -290.97443) (xy 183.837194 -290.980362) (xy 183.788019 -290.978381)
			(xy 183.7398 -290.968537) (xy 183.693784 -290.951085) (xy 183.651163 -290.926478) (xy 183.613042 -290.895353)
			(xy 183.580407 -290.858516) (xy 183.554104 -290.81692) (xy 183.534813 -290.771644) (xy 183.523036 -290.72386)
			(xy 183.519076 -290.674806) (xy 183.180228 -290.674806) (xy 183.179733 -290.699413) (xy 183.171838 -290.74799)
			(xy 183.156254 -290.794671) (xy 183.133383 -290.838248) (xy 183.103818 -290.877592) (xy 183.068325 -290.911684)
			(xy 183.027822 -290.93964) (xy 182.98336 -290.960738) (xy 182.936089 -290.97443) (xy 182.887234 -290.980362)
			(xy 182.838059 -290.978381) (xy 182.78984 -290.968537) (xy 182.743824 -290.951085) (xy 182.701203 -290.926478)
			(xy 182.663082 -290.895353) (xy 182.630447 -290.858516) (xy 182.604144 -290.81692) (xy 182.584853 -290.771644)
			(xy 182.573076 -290.72386) (xy 182.569116 -290.674806) (xy 182.230268 -290.674806) (xy 182.229773 -290.699413)
			(xy 182.221878 -290.74799) (xy 182.206294 -290.794671) (xy 182.183423 -290.838248) (xy 182.153858 -290.877592)
			(xy 182.118365 -290.911684) (xy 182.077862 -290.93964) (xy 182.0334 -290.960738) (xy 181.986129 -290.97443)
			(xy 181.937274 -290.980362) (xy 181.888099 -290.978381) (xy 181.83988 -290.968537) (xy 181.793864 -290.951085)
			(xy 181.751243 -290.926478) (xy 181.713122 -290.895353) (xy 181.680487 -290.858516) (xy 181.654184 -290.81692)
			(xy 181.634893 -290.771644) (xy 181.623116 -290.72386) (xy 181.619156 -290.674806) (xy 181.280308 -290.674806)
			(xy 181.279813 -290.699413) (xy 181.271918 -290.74799) (xy 181.256334 -290.794671) (xy 181.233463 -290.838248)
			(xy 181.203898 -290.877592) (xy 181.168405 -290.911684) (xy 181.127902 -290.93964) (xy 181.08344 -290.960738)
			(xy 181.036169 -290.97443) (xy 180.987314 -290.980362) (xy 180.938139 -290.978381) (xy 180.88992 -290.968537)
			(xy 180.843904 -290.951085) (xy 180.801283 -290.926478) (xy 180.763162 -290.895353) (xy 180.730527 -290.858516)
			(xy 180.704224 -290.81692) (xy 180.684933 -290.771644) (xy 180.673156 -290.72386) (xy 180.669196 -290.674806)
			(xy 180.330348 -290.674806) (xy 180.329853 -290.699413) (xy 180.321958 -290.74799) (xy 180.306374 -290.794671)
			(xy 180.283503 -290.838248) (xy 180.253938 -290.877592) (xy 180.218445 -290.911684) (xy 180.177942 -290.93964)
			(xy 180.13348 -290.960738) (xy 180.086209 -290.97443) (xy 180.037354 -290.980362) (xy 179.988179 -290.978381)
			(xy 179.93996 -290.968537) (xy 179.893944 -290.951085) (xy 179.851323 -290.926478) (xy 179.813202 -290.895353)
			(xy 179.780567 -290.858516) (xy 179.754264 -290.81692) (xy 179.734973 -290.771644) (xy 179.723196 -290.72386)
			(xy 179.719236 -290.674806) (xy 179.380388 -290.674806) (xy 179.379893 -290.699413) (xy 179.371998 -290.74799)
			(xy 179.356414 -290.794671) (xy 179.333543 -290.838248) (xy 179.303978 -290.877592) (xy 179.268485 -290.911684)
			(xy 179.227982 -290.93964) (xy 179.18352 -290.960738) (xy 179.136249 -290.97443) (xy 179.087394 -290.980362)
			(xy 179.038219 -290.978381) (xy 178.99 -290.968537) (xy 178.943984 -290.951085) (xy 178.901363 -290.926478)
			(xy 178.863242 -290.895353) (xy 178.830607 -290.858516) (xy 178.804304 -290.81692) (xy 178.785013 -290.771644)
			(xy 178.773236 -290.72386) (xy 178.769276 -290.674806) (xy 178.430174 -290.674806) (xy 178.429679 -290.699413)
			(xy 178.421784 -290.74799) (xy 178.4062 -290.794671) (xy 178.383329 -290.838248) (xy 178.353764 -290.877592)
			(xy 178.318271 -290.911684) (xy 178.277768 -290.93964) (xy 178.233306 -290.960738) (xy 178.186035 -290.97443)
			(xy 178.13718 -290.980362) (xy 178.088005 -290.978381) (xy 178.039786 -290.968537) (xy 177.99377 -290.951085)
			(xy 177.951149 -290.926478) (xy 177.913028 -290.895353) (xy 177.880393 -290.858516) (xy 177.85409 -290.81692)
			(xy 177.834799 -290.771644) (xy 177.823022 -290.72386) (xy 177.819062 -290.674806) (xy 177.480214 -290.674806)
			(xy 177.479719 -290.699413) (xy 177.471824 -290.74799) (xy 177.45624 -290.794671) (xy 177.433369 -290.838248)
			(xy 177.403804 -290.877592) (xy 177.368311 -290.911684) (xy 177.327808 -290.93964) (xy 177.283346 -290.960738)
			(xy 177.236075 -290.97443) (xy 177.18722 -290.980362) (xy 177.138045 -290.978381) (xy 177.089826 -290.968537)
			(xy 177.04381 -290.951085) (xy 177.001189 -290.926478) (xy 176.963068 -290.895353) (xy 176.930433 -290.858516)
			(xy 176.90413 -290.81692) (xy 176.884839 -290.771644) (xy 176.873062 -290.72386) (xy 176.869102 -290.674806)
			(xy 176.530254 -290.674806) (xy 176.529759 -290.699413) (xy 176.521864 -290.74799) (xy 176.50628 -290.794671)
			(xy 176.483409 -290.838248) (xy 176.453844 -290.877592) (xy 176.418351 -290.911684) (xy 176.377848 -290.93964)
			(xy 176.333386 -290.960738) (xy 176.286115 -290.97443) (xy 176.23726 -290.980362) (xy 176.188085 -290.978381)
			(xy 176.139866 -290.968537) (xy 176.09385 -290.951085) (xy 176.051229 -290.926478) (xy 176.013108 -290.895353)
			(xy 175.980473 -290.858516) (xy 175.95417 -290.81692) (xy 175.934879 -290.771644) (xy 175.923102 -290.72386)
			(xy 175.919142 -290.674806) (xy 174.630334 -290.674806) (xy 174.629839 -290.699413) (xy 174.621944 -290.74799)
			(xy 174.60636 -290.794671) (xy 174.583489 -290.838248) (xy 174.553924 -290.877592) (xy 174.518431 -290.911684)
			(xy 174.477928 -290.93964) (xy 174.433466 -290.960738) (xy 174.386195 -290.97443) (xy 174.33734 -290.980362)
			(xy 174.288165 -290.978381) (xy 174.239946 -290.968537) (xy 174.19393 -290.951085) (xy 174.151309 -290.926478)
			(xy 174.113188 -290.895353) (xy 174.080553 -290.858516) (xy 174.05425 -290.81692) (xy 174.034959 -290.771644)
			(xy 174.023182 -290.72386) (xy 174.019222 -290.674806) (xy 173.680374 -290.674806) (xy 173.679879 -290.699413)
			(xy 173.671984 -290.74799) (xy 173.6564 -290.794671) (xy 173.633529 -290.838248) (xy 173.603964 -290.877592)
			(xy 173.568471 -290.911684) (xy 173.527968 -290.93964) (xy 173.483506 -290.960738) (xy 173.436235 -290.97443)
			(xy 173.38738 -290.980362) (xy 173.338205 -290.978381) (xy 173.289986 -290.968537) (xy 173.24397 -290.951085)
			(xy 173.201349 -290.926478) (xy 173.163228 -290.895353) (xy 173.130593 -290.858516) (xy 173.10429 -290.81692)
			(xy 173.084999 -290.771644) (xy 173.073222 -290.72386) (xy 173.069262 -290.674806) (xy 172.73016 -290.674806)
			(xy 172.729665 -290.699413) (xy 172.72177 -290.74799) (xy 172.706186 -290.794671) (xy 172.683315 -290.838248)
			(xy 172.65375 -290.877592) (xy 172.618257 -290.911684) (xy 172.577754 -290.93964) (xy 172.533292 -290.960738)
			(xy 172.486021 -290.97443) (xy 172.437166 -290.980362) (xy 172.387991 -290.978381) (xy 172.339772 -290.968537)
			(xy 172.293756 -290.951085) (xy 172.251135 -290.926478) (xy 172.213014 -290.895353) (xy 172.180379 -290.858516)
			(xy 172.154076 -290.81692) (xy 172.134785 -290.771644) (xy 172.123008 -290.72386) (xy 172.119048 -290.674806)
			(xy 171.7802 -290.674806) (xy 171.779705 -290.699413) (xy 171.77181 -290.74799) (xy 171.756226 -290.794671)
			(xy 171.733355 -290.838248) (xy 171.70379 -290.877592) (xy 171.668297 -290.911684) (xy 171.627794 -290.93964)
			(xy 171.583332 -290.960738) (xy 171.536061 -290.97443) (xy 171.487206 -290.980362) (xy 171.438031 -290.978381)
			(xy 171.389812 -290.968537) (xy 171.343796 -290.951085) (xy 171.301175 -290.926478) (xy 171.263054 -290.895353)
			(xy 171.230419 -290.858516) (xy 171.204116 -290.81692) (xy 171.184825 -290.771644) (xy 171.173048 -290.72386)
			(xy 171.169088 -290.674806) (xy 170.83024 -290.674806) (xy 170.829745 -290.699413) (xy 170.82185 -290.74799)
			(xy 170.806266 -290.794671) (xy 170.783395 -290.838248) (xy 170.75383 -290.877592) (xy 170.718337 -290.911684)
			(xy 170.677834 -290.93964) (xy 170.633372 -290.960738) (xy 170.586101 -290.97443) (xy 170.537246 -290.980362)
			(xy 170.488071 -290.978381) (xy 170.439852 -290.968537) (xy 170.393836 -290.951085) (xy 170.351215 -290.926478)
			(xy 170.313094 -290.895353) (xy 170.280459 -290.858516) (xy 170.254156 -290.81692) (xy 170.234865 -290.771644)
			(xy 170.223088 -290.72386) (xy 170.219128 -290.674806) (xy 169.88028 -290.674806) (xy 169.879785 -290.699413)
			(xy 169.87189 -290.74799) (xy 169.856306 -290.794671) (xy 169.833435 -290.838248) (xy 169.80387 -290.877592)
			(xy 169.768377 -290.911684) (xy 169.727874 -290.93964) (xy 169.683412 -290.960738) (xy 169.636141 -290.97443)
			(xy 169.587286 -290.980362) (xy 169.538111 -290.978381) (xy 169.489892 -290.968537) (xy 169.443876 -290.951085)
			(xy 169.401255 -290.926478) (xy 169.363134 -290.895353) (xy 169.330499 -290.858516) (xy 169.304196 -290.81692)
			(xy 169.284905 -290.771644) (xy 169.273128 -290.72386) (xy 169.269168 -290.674806) (xy 168.93032 -290.674806)
			(xy 168.929825 -290.699413) (xy 168.92193 -290.74799) (xy 168.906346 -290.794671) (xy 168.883475 -290.838248)
			(xy 168.85391 -290.877592) (xy 168.818417 -290.911684) (xy 168.777914 -290.93964) (xy 168.733452 -290.960738)
			(xy 168.686181 -290.97443) (xy 168.637326 -290.980362) (xy 168.588151 -290.978381) (xy 168.539932 -290.968537)
			(xy 168.493916 -290.951085) (xy 168.451295 -290.926478) (xy 168.413174 -290.895353) (xy 168.380539 -290.858516)
			(xy 168.354236 -290.81692) (xy 168.334945 -290.771644) (xy 168.323168 -290.72386) (xy 168.319208 -290.674806)
			(xy 167.98036 -290.674806) (xy 167.979865 -290.699413) (xy 167.97197 -290.74799) (xy 167.956386 -290.794671)
			(xy 167.933515 -290.838248) (xy 167.90395 -290.877592) (xy 167.868457 -290.911684) (xy 167.827954 -290.93964)
			(xy 167.783492 -290.960738) (xy 167.736221 -290.97443) (xy 167.687366 -290.980362) (xy 167.638191 -290.978381)
			(xy 167.589972 -290.968537) (xy 167.543956 -290.951085) (xy 167.501335 -290.926478) (xy 167.463214 -290.895353)
			(xy 167.430579 -290.858516) (xy 167.404276 -290.81692) (xy 167.384985 -290.771644) (xy 167.373208 -290.72386)
			(xy 167.369248 -290.674806) (xy 167.0304 -290.674806) (xy 167.029905 -290.699413) (xy 167.02201 -290.74799)
			(xy 167.006426 -290.794671) (xy 166.983555 -290.838248) (xy 166.95399 -290.877592) (xy 166.918497 -290.911684)
			(xy 166.877994 -290.93964) (xy 166.833532 -290.960738) (xy 166.786261 -290.97443) (xy 166.737406 -290.980362)
			(xy 166.688231 -290.978381) (xy 166.640012 -290.968537) (xy 166.593996 -290.951085) (xy 166.551375 -290.926478)
			(xy 166.513254 -290.895353) (xy 166.480619 -290.858516) (xy 166.454316 -290.81692) (xy 166.435025 -290.771644)
			(xy 166.423248 -290.72386) (xy 166.419288 -290.674806) (xy 166.080186 -290.674806) (xy 166.079691 -290.699413)
			(xy 166.071796 -290.74799) (xy 166.056212 -290.794671) (xy 166.033341 -290.838248) (xy 166.003776 -290.877592)
			(xy 165.968283 -290.911684) (xy 165.92778 -290.93964) (xy 165.883318 -290.960738) (xy 165.836047 -290.97443)
			(xy 165.787192 -290.980362) (xy 165.738017 -290.978381) (xy 165.689798 -290.968537) (xy 165.643782 -290.951085)
			(xy 165.601161 -290.926478) (xy 165.56304 -290.895353) (xy 165.530405 -290.858516) (xy 165.504102 -290.81692)
			(xy 165.484811 -290.771644) (xy 165.473034 -290.72386) (xy 165.469074 -290.674806) (xy 164.180266 -290.674806)
			(xy 164.179771 -290.699413) (xy 164.171876 -290.74799) (xy 164.156292 -290.794671) (xy 164.133421 -290.838248)
			(xy 164.103856 -290.877592) (xy 164.068363 -290.911684) (xy 164.02786 -290.93964) (xy 163.983398 -290.960738)
			(xy 163.936127 -290.97443) (xy 163.887272 -290.980362) (xy 163.838097 -290.978381) (xy 163.789878 -290.968537)
			(xy 163.743862 -290.951085) (xy 163.701241 -290.926478) (xy 163.66312 -290.895353) (xy 163.630485 -290.858516)
			(xy 163.604182 -290.81692) (xy 163.584891 -290.771644) (xy 163.573114 -290.72386) (xy 163.569154 -290.674806)
			(xy 163.230306 -290.674806) (xy 163.229811 -290.699413) (xy 163.221916 -290.74799) (xy 163.206332 -290.794671)
			(xy 163.183461 -290.838248) (xy 163.153896 -290.877592) (xy 163.118403 -290.911684) (xy 163.0779 -290.93964)
			(xy 163.033438 -290.960738) (xy 162.986167 -290.97443) (xy 162.937312 -290.980362) (xy 162.888137 -290.978381)
			(xy 162.839918 -290.968537) (xy 162.793902 -290.951085) (xy 162.751281 -290.926478) (xy 162.71316 -290.895353)
			(xy 162.680525 -290.858516) (xy 162.654222 -290.81692) (xy 162.634931 -290.771644) (xy 162.623154 -290.72386)
			(xy 162.619194 -290.674806) (xy 162.280346 -290.674806) (xy 162.279851 -290.699413) (xy 162.271956 -290.74799)
			(xy 162.256372 -290.794671) (xy 162.233501 -290.838248) (xy 162.203936 -290.877592) (xy 162.168443 -290.911684)
			(xy 162.12794 -290.93964) (xy 162.083478 -290.960738) (xy 162.036207 -290.97443) (xy 161.987352 -290.980362)
			(xy 161.938177 -290.978381) (xy 161.889958 -290.968537) (xy 161.843942 -290.951085) (xy 161.801321 -290.926478)
			(xy 161.7632 -290.895353) (xy 161.730565 -290.858516) (xy 161.704262 -290.81692) (xy 161.684971 -290.771644)
			(xy 161.673194 -290.72386) (xy 161.669234 -290.674806) (xy 161.330386 -290.674806) (xy 161.329891 -290.699413)
			(xy 161.321996 -290.74799) (xy 161.306412 -290.794671) (xy 161.283541 -290.838248) (xy 161.253976 -290.877592)
			(xy 161.218483 -290.911684) (xy 161.17798 -290.93964) (xy 161.133518 -290.960738) (xy 161.086247 -290.97443)
			(xy 161.037392 -290.980362) (xy 160.988217 -290.978381) (xy 160.939998 -290.968537) (xy 160.893982 -290.951085)
			(xy 160.851361 -290.926478) (xy 160.81324 -290.895353) (xy 160.780605 -290.858516) (xy 160.754302 -290.81692)
			(xy 160.735011 -290.771644) (xy 160.723234 -290.72386) (xy 160.719274 -290.674806) (xy 160.380172 -290.674806)
			(xy 160.379677 -290.699413) (xy 160.371782 -290.74799) (xy 160.356198 -290.794671) (xy 160.333327 -290.838248)
			(xy 160.303762 -290.877592) (xy 160.268269 -290.911684) (xy 160.227766 -290.93964) (xy 160.183304 -290.960738)
			(xy 160.136033 -290.97443) (xy 160.087178 -290.980362) (xy 160.038003 -290.978381) (xy 159.989784 -290.968537)
			(xy 159.943768 -290.951085) (xy 159.901147 -290.926478) (xy 159.863026 -290.895353) (xy 159.830391 -290.858516)
			(xy 159.804088 -290.81692) (xy 159.784797 -290.771644) (xy 159.77302 -290.72386) (xy 159.76906 -290.674806)
			(xy 159.430212 -290.674806) (xy 159.429717 -290.699413) (xy 159.421822 -290.74799) (xy 159.406238 -290.794671)
			(xy 159.383367 -290.838248) (xy 159.353802 -290.877592) (xy 159.318309 -290.911684) (xy 159.277806 -290.93964)
			(xy 159.233344 -290.960738) (xy 159.186073 -290.97443) (xy 159.137218 -290.980362) (xy 159.088043 -290.978381)
			(xy 159.039824 -290.968537) (xy 158.993808 -290.951085) (xy 158.951187 -290.926478) (xy 158.913066 -290.895353)
			(xy 158.880431 -290.858516) (xy 158.854128 -290.81692) (xy 158.834837 -290.771644) (xy 158.82306 -290.72386)
			(xy 158.8191 -290.674806) (xy 158.480252 -290.674806) (xy 158.479757 -290.699413) (xy 158.471862 -290.74799)
			(xy 158.456278 -290.794671) (xy 158.433407 -290.838248) (xy 158.403842 -290.877592) (xy 158.368349 -290.911684)
			(xy 158.327846 -290.93964) (xy 158.283384 -290.960738) (xy 158.236113 -290.97443) (xy 158.187258 -290.980362)
			(xy 158.138083 -290.978381) (xy 158.089864 -290.968537) (xy 158.043848 -290.951085) (xy 158.001227 -290.926478)
			(xy 157.963106 -290.895353) (xy 157.930471 -290.858516) (xy 157.904168 -290.81692) (xy 157.884877 -290.771644)
			(xy 157.8731 -290.72386) (xy 157.86914 -290.674806) (xy 157.530292 -290.674806) (xy 157.529797 -290.699413)
			(xy 157.521902 -290.74799) (xy 157.506318 -290.794671) (xy 157.483447 -290.838248) (xy 157.453882 -290.877592)
			(xy 157.418389 -290.911684) (xy 157.377886 -290.93964) (xy 157.333424 -290.960738) (xy 157.286153 -290.97443)
			(xy 157.237298 -290.980362) (xy 157.188123 -290.978381) (xy 157.139904 -290.968537) (xy 157.093888 -290.951085)
			(xy 157.051267 -290.926478) (xy 157.013146 -290.895353) (xy 156.980511 -290.858516) (xy 156.954208 -290.81692)
			(xy 156.934917 -290.771644) (xy 156.92314 -290.72386) (xy 156.91918 -290.674806) (xy 154.680412 -290.674806)
			(xy 154.679917 -290.699413) (xy 154.672022 -290.74799) (xy 154.656438 -290.794671) (xy 154.633567 -290.838248)
			(xy 154.604002 -290.877592) (xy 154.568509 -290.911684) (xy 154.528006 -290.93964) (xy 154.483544 -290.960738)
			(xy 154.436273 -290.97443) (xy 154.387418 -290.980362) (xy 154.338243 -290.978381) (xy 154.290024 -290.968537)
			(xy 154.244008 -290.951085) (xy 154.201387 -290.926478) (xy 154.163266 -290.895353) (xy 154.130631 -290.858516)
			(xy 154.104328 -290.81692) (xy 154.085037 -290.771644) (xy 154.07326 -290.72386) (xy 154.0693 -290.674806)
			(xy 153.730198 -290.674806) (xy 153.729703 -290.699413) (xy 153.721808 -290.74799) (xy 153.706224 -290.794671)
			(xy 153.683353 -290.838248) (xy 153.653788 -290.877592) (xy 153.618295 -290.911684) (xy 153.577792 -290.93964)
			(xy 153.53333 -290.960738) (xy 153.486059 -290.97443) (xy 153.437204 -290.980362) (xy 153.388029 -290.978381)
			(xy 153.33981 -290.968537) (xy 153.293794 -290.951085) (xy 153.251173 -290.926478) (xy 153.213052 -290.895353)
			(xy 153.180417 -290.858516) (xy 153.154114 -290.81692) (xy 153.134823 -290.771644) (xy 153.123046 -290.72386)
			(xy 153.119086 -290.674806) (xy 152.780238 -290.674806) (xy 152.779743 -290.699413) (xy 152.771848 -290.74799)
			(xy 152.756264 -290.794671) (xy 152.733393 -290.838248) (xy 152.703828 -290.877592) (xy 152.668335 -290.911684)
			(xy 152.627832 -290.93964) (xy 152.58337 -290.960738) (xy 152.536099 -290.97443) (xy 152.487244 -290.980362)
			(xy 152.438069 -290.978381) (xy 152.38985 -290.968537) (xy 152.343834 -290.951085) (xy 152.301213 -290.926478)
			(xy 152.263092 -290.895353) (xy 152.230457 -290.858516) (xy 152.204154 -290.81692) (xy 152.184863 -290.771644)
			(xy 152.173086 -290.72386) (xy 152.169126 -290.674806) (xy 150.128581 -290.674806) (xy 150.11703 -290.676077)
			(xy 150.061296 -290.67404) (xy 150.006453 -290.66391) (xy 149.953669 -290.645903) (xy 149.904069 -290.620402)
			(xy 149.858711 -290.587951) (xy 149.818562 -290.549242) (xy 149.784476 -290.505099) (xy 149.75718 -290.456464)
			(xy 149.737257 -290.404373) (xy 149.725131 -290.349936) (xy 149.72106 -290.294314) (xy 149.598126 -290.294314)
			(xy 149.597617 -290.3222) (xy 149.589497 -290.377376) (xy 149.573429 -290.430783) (xy 149.549757 -290.48128)
			(xy 149.518984 -290.527793) (xy 149.481767 -290.56933) (xy 149.438899 -290.605005) (xy 149.391293 -290.634059)
			(xy 149.339964 -290.655871) (xy 149.286007 -290.669977) (xy 149.23057 -290.676077) (xy 149.174836 -290.67404)
			(xy 149.119993 -290.66391) (xy 149.067209 -290.645903) (xy 149.017609 -290.620402) (xy 148.972251 -290.587951)
			(xy 148.932102 -290.549242) (xy 148.898016 -290.505099) (xy 148.87072 -290.456464) (xy 148.850797 -290.404373)
			(xy 148.838671 -290.349936) (xy 148.8346 -290.294314) (xy 148.201126 -290.294314) (xy 148.20064 -290.321565)
			(xy 148.192884 -290.375513) (xy 148.177529 -290.427808) (xy 148.154887 -290.477385) (xy 148.125421 -290.523235)
			(xy 148.08973 -290.564426) (xy 148.048539 -290.600117) (xy 148.002689 -290.629583) (xy 147.953112 -290.652225)
			(xy 147.900817 -290.66758) (xy 147.846869 -290.675336) (xy 147.792367 -290.675336) (xy 147.738419 -290.66758)
			(xy 147.686124 -290.652225) (xy 147.636547 -290.629583) (xy 147.590697 -290.600117) (xy 147.549506 -290.564426)
			(xy 147.513815 -290.523235) (xy 147.484349 -290.477385) (xy 147.461707 -290.427808) (xy 147.446352 -290.375513)
			(xy 147.438596 -290.321565) (xy 147.43811 -290.294314) (xy 136.349994 -290.294314) (xy 136.349994 -291.430456)
			(xy 141.911576 -291.430456) (xy 141.915647 -291.374834) (xy 141.927773 -291.320397) (xy 141.947696 -291.268306)
			(xy 141.974992 -291.219671) (xy 142.009078 -291.175528) (xy 142.049227 -291.136819) (xy 142.094585 -291.104368)
			(xy 142.144185 -291.078867) (xy 142.196969 -291.06086) (xy 142.251812 -291.05073) (xy 142.307546 -291.048693)
			(xy 142.362983 -291.054793) (xy 142.41694 -291.068899) (xy 142.468269 -291.090711) (xy 142.515875 -291.119765)
			(xy 142.558743 -291.15544) (xy 142.59596 -291.196977) (xy 142.626733 -291.24349) (xy 142.650405 -291.293987)
			(xy 142.666473 -291.347394) (xy 142.674593 -291.40257) (xy 142.675102 -291.430456) (xy 143.396714 -291.430456)
			(xy 143.400785 -291.374834) (xy 143.412911 -291.320397) (xy 143.432834 -291.268306) (xy 143.46013 -291.219671)
			(xy 143.494216 -291.175528) (xy 143.534365 -291.136819) (xy 143.579723 -291.104368) (xy 143.629323 -291.078867)
			(xy 143.682107 -291.06086) (xy 143.73695 -291.05073) (xy 143.792684 -291.048693) (xy 143.848121 -291.054793)
			(xy 143.902078 -291.068899) (xy 143.953407 -291.090711) (xy 144.001013 -291.119765) (xy 144.043881 -291.15544)
			(xy 144.081098 -291.196977) (xy 144.111871 -291.24349) (xy 144.135543 -291.293987) (xy 144.151611 -291.347394)
			(xy 144.159731 -291.40257) (xy 144.16024 -291.430456) (xy 144.159731 -291.458342) (xy 144.151611 -291.513518)
			(xy 144.135543 -291.566925) (xy 144.111871 -291.617422) (xy 144.107012 -291.624766) (xy 152.169126 -291.624766)
			(xy 152.173086 -291.575712) (xy 152.184863 -291.527928) (xy 152.204154 -291.482652) (xy 152.230457 -291.441056)
			(xy 152.263092 -291.404219) (xy 152.301213 -291.373094) (xy 152.343834 -291.348487) (xy 152.38985 -291.331035)
			(xy 152.438069 -291.321191) (xy 152.487244 -291.31921) (xy 152.536099 -291.325142) (xy 152.58337 -291.338834)
			(xy 152.627832 -291.359932) (xy 152.668335 -291.387888) (xy 152.703828 -291.42198) (xy 152.733393 -291.461324)
			(xy 152.756264 -291.504901) (xy 152.771848 -291.551582) (xy 152.779743 -291.600159) (xy 152.780238 -291.624766)
			(xy 153.119086 -291.624766) (xy 153.123046 -291.575712) (xy 153.134823 -291.527928) (xy 153.154114 -291.482652)
			(xy 153.180417 -291.441056) (xy 153.213052 -291.404219) (xy 153.251173 -291.373094) (xy 153.293794 -291.348487)
			(xy 153.33981 -291.331035) (xy 153.388029 -291.321191) (xy 153.437204 -291.31921) (xy 153.486059 -291.325142)
			(xy 153.53333 -291.338834) (xy 153.577792 -291.359932) (xy 153.618295 -291.387888) (xy 153.653788 -291.42198)
			(xy 153.683353 -291.461324) (xy 153.706224 -291.504901) (xy 153.721808 -291.551582) (xy 153.729703 -291.600159)
			(xy 153.730198 -291.624766) (xy 154.0693 -291.624766) (xy 154.07326 -291.575712) (xy 154.085037 -291.527928)
			(xy 154.104328 -291.482652) (xy 154.130631 -291.441056) (xy 154.163266 -291.404219) (xy 154.201387 -291.373094)
			(xy 154.244008 -291.348487) (xy 154.290024 -291.331035) (xy 154.338243 -291.321191) (xy 154.387418 -291.31921)
			(xy 154.436273 -291.325142) (xy 154.483544 -291.338834) (xy 154.528006 -291.359932) (xy 154.568509 -291.387888)
			(xy 154.604002 -291.42198) (xy 154.633567 -291.461324) (xy 154.656438 -291.504901) (xy 154.672022 -291.551582)
			(xy 154.679917 -291.600159) (xy 154.680412 -291.624766) (xy 156.91918 -291.624766) (xy 156.92314 -291.575712)
			(xy 156.934917 -291.527928) (xy 156.954208 -291.482652) (xy 156.980511 -291.441056) (xy 157.013146 -291.404219)
			(xy 157.051267 -291.373094) (xy 157.093888 -291.348487) (xy 157.139904 -291.331035) (xy 157.188123 -291.321191)
			(xy 157.237298 -291.31921) (xy 157.286153 -291.325142) (xy 157.333424 -291.338834) (xy 157.377886 -291.359932)
			(xy 157.418389 -291.387888) (xy 157.453882 -291.42198) (xy 157.483447 -291.461324) (xy 157.506318 -291.504901)
			(xy 157.521902 -291.551582) (xy 157.529797 -291.600159) (xy 157.530292 -291.624766) (xy 157.86914 -291.624766)
			(xy 157.8731 -291.575712) (xy 157.884877 -291.527928) (xy 157.904168 -291.482652) (xy 157.930471 -291.441056)
			(xy 157.963106 -291.404219) (xy 158.001227 -291.373094) (xy 158.043848 -291.348487) (xy 158.089864 -291.331035)
			(xy 158.138083 -291.321191) (xy 158.187258 -291.31921) (xy 158.236113 -291.325142) (xy 158.283384 -291.338834)
			(xy 158.327846 -291.359932) (xy 158.368349 -291.387888) (xy 158.403842 -291.42198) (xy 158.433407 -291.461324)
			(xy 158.456278 -291.504901) (xy 158.471862 -291.551582) (xy 158.479757 -291.600159) (xy 158.480252 -291.624766)
			(xy 158.8191 -291.624766) (xy 158.82306 -291.575712) (xy 158.834837 -291.527928) (xy 158.854128 -291.482652)
			(xy 158.880431 -291.441056) (xy 158.913066 -291.404219) (xy 158.951187 -291.373094) (xy 158.993808 -291.348487)
			(xy 159.039824 -291.331035) (xy 159.088043 -291.321191) (xy 159.137218 -291.31921) (xy 159.186073 -291.325142)
			(xy 159.233344 -291.338834) (xy 159.277806 -291.359932) (xy 159.318309 -291.387888) (xy 159.353802 -291.42198)
			(xy 159.383367 -291.461324) (xy 159.406238 -291.504901) (xy 159.421822 -291.551582) (xy 159.429717 -291.600159)
			(xy 159.430212 -291.624766) (xy 159.76906 -291.624766) (xy 159.77302 -291.575712) (xy 159.784797 -291.527928)
			(xy 159.804088 -291.482652) (xy 159.830391 -291.441056) (xy 159.863026 -291.404219) (xy 159.901147 -291.373094)
			(xy 159.943768 -291.348487) (xy 159.989784 -291.331035) (xy 160.038003 -291.321191) (xy 160.087178 -291.31921)
			(xy 160.136033 -291.325142) (xy 160.183304 -291.338834) (xy 160.227766 -291.359932) (xy 160.268269 -291.387888)
			(xy 160.303762 -291.42198) (xy 160.333327 -291.461324) (xy 160.356198 -291.504901) (xy 160.371782 -291.551582)
			(xy 160.379677 -291.600159) (xy 160.380172 -291.624766) (xy 160.719274 -291.624766) (xy 160.723234 -291.575712)
			(xy 160.735011 -291.527928) (xy 160.754302 -291.482652) (xy 160.780605 -291.441056) (xy 160.81324 -291.404219)
			(xy 160.851361 -291.373094) (xy 160.893982 -291.348487) (xy 160.939998 -291.331035) (xy 160.988217 -291.321191)
			(xy 161.037392 -291.31921) (xy 161.086247 -291.325142) (xy 161.133518 -291.338834) (xy 161.17798 -291.359932)
			(xy 161.218483 -291.387888) (xy 161.253976 -291.42198) (xy 161.283541 -291.461324) (xy 161.306412 -291.504901)
			(xy 161.321996 -291.551582) (xy 161.329891 -291.600159) (xy 161.330386 -291.624766) (xy 161.669234 -291.624766)
			(xy 161.673194 -291.575712) (xy 161.684971 -291.527928) (xy 161.704262 -291.482652) (xy 161.730565 -291.441056)
			(xy 161.7632 -291.404219) (xy 161.801321 -291.373094) (xy 161.843942 -291.348487) (xy 161.889958 -291.331035)
			(xy 161.938177 -291.321191) (xy 161.987352 -291.31921) (xy 162.036207 -291.325142) (xy 162.083478 -291.338834)
			(xy 162.12794 -291.359932) (xy 162.168443 -291.387888) (xy 162.203936 -291.42198) (xy 162.233501 -291.461324)
			(xy 162.256372 -291.504901) (xy 162.271956 -291.551582) (xy 162.279851 -291.600159) (xy 162.280346 -291.624766)
			(xy 163.569154 -291.624766) (xy 163.573114 -291.575712) (xy 163.584891 -291.527928) (xy 163.604182 -291.482652)
			(xy 163.630485 -291.441056) (xy 163.66312 -291.404219) (xy 163.701241 -291.373094) (xy 163.743862 -291.348487)
			(xy 163.789878 -291.331035) (xy 163.838097 -291.321191) (xy 163.887272 -291.31921) (xy 163.936127 -291.325142)
			(xy 163.983398 -291.338834) (xy 164.02786 -291.359932) (xy 164.068363 -291.387888) (xy 164.103856 -291.42198)
			(xy 164.133421 -291.461324) (xy 164.156292 -291.504901) (xy 164.171876 -291.551582) (xy 164.179771 -291.600159)
			(xy 164.180266 -291.624766) (xy 164.519114 -291.624766) (xy 164.523074 -291.575712) (xy 164.534851 -291.527928)
			(xy 164.554142 -291.482652) (xy 164.580445 -291.441056) (xy 164.61308 -291.404219) (xy 164.651201 -291.373094)
			(xy 164.693822 -291.348487) (xy 164.739838 -291.331035) (xy 164.788057 -291.321191) (xy 164.837232 -291.31921)
			(xy 164.886087 -291.325142) (xy 164.933358 -291.338834) (xy 164.97782 -291.359932) (xy 165.018323 -291.387888)
			(xy 165.053816 -291.42198) (xy 165.083381 -291.461324) (xy 165.106252 -291.504901) (xy 165.121836 -291.551582)
			(xy 165.129731 -291.600159) (xy 165.130226 -291.624766) (xy 166.419288 -291.624766) (xy 166.423248 -291.575712)
			(xy 166.435025 -291.527928) (xy 166.454316 -291.482652) (xy 166.480619 -291.441056) (xy 166.513254 -291.404219)
			(xy 166.551375 -291.373094) (xy 166.593996 -291.348487) (xy 166.640012 -291.331035) (xy 166.688231 -291.321191)
			(xy 166.737406 -291.31921) (xy 166.786261 -291.325142) (xy 166.833532 -291.338834) (xy 166.877994 -291.359932)
			(xy 166.918497 -291.387888) (xy 166.95399 -291.42198) (xy 166.983555 -291.461324) (xy 167.006426 -291.504901)
			(xy 167.02201 -291.551582) (xy 167.029905 -291.600159) (xy 167.0304 -291.624766) (xy 167.369248 -291.624766)
			(xy 167.373208 -291.575712) (xy 167.384985 -291.527928) (xy 167.404276 -291.482652) (xy 167.430579 -291.441056)
			(xy 167.463214 -291.404219) (xy 167.501335 -291.373094) (xy 167.543956 -291.348487) (xy 167.589972 -291.331035)
			(xy 167.638191 -291.321191) (xy 167.687366 -291.31921) (xy 167.736221 -291.325142) (xy 167.783492 -291.338834)
			(xy 167.827954 -291.359932) (xy 167.868457 -291.387888) (xy 167.90395 -291.42198) (xy 167.933515 -291.461324)
			(xy 167.956386 -291.504901) (xy 167.97197 -291.551582) (xy 167.979865 -291.600159) (xy 167.98036 -291.624766)
			(xy 168.319208 -291.624766) (xy 168.323168 -291.575712) (xy 168.334945 -291.527928) (xy 168.354236 -291.482652)
			(xy 168.380539 -291.441056) (xy 168.413174 -291.404219) (xy 168.451295 -291.373094) (xy 168.493916 -291.348487)
			(xy 168.539932 -291.331035) (xy 168.588151 -291.321191) (xy 168.637326 -291.31921) (xy 168.686181 -291.325142)
			(xy 168.733452 -291.338834) (xy 168.777914 -291.359932) (xy 168.818417 -291.387888) (xy 168.85391 -291.42198)
			(xy 168.883475 -291.461324) (xy 168.906346 -291.504901) (xy 168.92193 -291.551582) (xy 168.929825 -291.600159)
			(xy 168.93032 -291.624766) (xy 169.269168 -291.624766) (xy 169.273128 -291.575712) (xy 169.284905 -291.527928)
			(xy 169.304196 -291.482652) (xy 169.330499 -291.441056) (xy 169.363134 -291.404219) (xy 169.401255 -291.373094)
			(xy 169.443876 -291.348487) (xy 169.489892 -291.331035) (xy 169.538111 -291.321191) (xy 169.587286 -291.31921)
			(xy 169.636141 -291.325142) (xy 169.683412 -291.338834) (xy 169.727874 -291.359932) (xy 169.768377 -291.387888)
			(xy 169.80387 -291.42198) (xy 169.833435 -291.461324) (xy 169.856306 -291.504901) (xy 169.87189 -291.551582)
			(xy 169.879785 -291.600159) (xy 169.88028 -291.624766) (xy 170.219128 -291.624766) (xy 170.223088 -291.575712)
			(xy 170.234865 -291.527928) (xy 170.254156 -291.482652) (xy 170.280459 -291.441056) (xy 170.313094 -291.404219)
			(xy 170.351215 -291.373094) (xy 170.393836 -291.348487) (xy 170.439852 -291.331035) (xy 170.488071 -291.321191)
			(xy 170.537246 -291.31921) (xy 170.586101 -291.325142) (xy 170.633372 -291.338834) (xy 170.677834 -291.359932)
			(xy 170.718337 -291.387888) (xy 170.75383 -291.42198) (xy 170.783395 -291.461324) (xy 170.806266 -291.504901)
			(xy 170.82185 -291.551582) (xy 170.829745 -291.600159) (xy 170.83024 -291.624766) (xy 171.169088 -291.624766)
			(xy 171.173048 -291.575712) (xy 171.184825 -291.527928) (xy 171.204116 -291.482652) (xy 171.230419 -291.441056)
			(xy 171.263054 -291.404219) (xy 171.301175 -291.373094) (xy 171.343796 -291.348487) (xy 171.389812 -291.331035)
			(xy 171.438031 -291.321191) (xy 171.487206 -291.31921) (xy 171.536061 -291.325142) (xy 171.583332 -291.338834)
			(xy 171.627794 -291.359932) (xy 171.668297 -291.387888) (xy 171.70379 -291.42198) (xy 171.733355 -291.461324)
			(xy 171.756226 -291.504901) (xy 171.77181 -291.551582) (xy 171.779705 -291.600159) (xy 171.7802 -291.624766)
			(xy 172.119048 -291.624766) (xy 172.123008 -291.575712) (xy 172.134785 -291.527928) (xy 172.154076 -291.482652)
			(xy 172.180379 -291.441056) (xy 172.213014 -291.404219) (xy 172.251135 -291.373094) (xy 172.293756 -291.348487)
			(xy 172.339772 -291.331035) (xy 172.387991 -291.321191) (xy 172.437166 -291.31921) (xy 172.486021 -291.325142)
			(xy 172.533292 -291.338834) (xy 172.577754 -291.359932) (xy 172.618257 -291.387888) (xy 172.65375 -291.42198)
			(xy 172.683315 -291.461324) (xy 172.706186 -291.504901) (xy 172.72177 -291.551582) (xy 172.729665 -291.600159)
			(xy 172.73016 -291.624766) (xy 173.069262 -291.624766) (xy 173.073222 -291.575712) (xy 173.084999 -291.527928)
			(xy 173.10429 -291.482652) (xy 173.130593 -291.441056) (xy 173.163228 -291.404219) (xy 173.201349 -291.373094)
			(xy 173.24397 -291.348487) (xy 173.289986 -291.331035) (xy 173.338205 -291.321191) (xy 173.38738 -291.31921)
			(xy 173.436235 -291.325142) (xy 173.483506 -291.338834) (xy 173.527968 -291.359932) (xy 173.568471 -291.387888)
			(xy 173.603964 -291.42198) (xy 173.633529 -291.461324) (xy 173.6564 -291.504901) (xy 173.671984 -291.551582)
			(xy 173.679879 -291.600159) (xy 173.680374 -291.624766) (xy 174.019222 -291.624766) (xy 174.023182 -291.575712)
			(xy 174.034959 -291.527928) (xy 174.05425 -291.482652) (xy 174.080553 -291.441056) (xy 174.113188 -291.404219)
			(xy 174.151309 -291.373094) (xy 174.19393 -291.348487) (xy 174.239946 -291.331035) (xy 174.288165 -291.321191)
			(xy 174.33734 -291.31921) (xy 174.386195 -291.325142) (xy 174.433466 -291.338834) (xy 174.477928 -291.359932)
			(xy 174.518431 -291.387888) (xy 174.553924 -291.42198) (xy 174.583489 -291.461324) (xy 174.60636 -291.504901)
			(xy 174.621944 -291.551582) (xy 174.629839 -291.600159) (xy 174.630334 -291.624766) (xy 175.919142 -291.624766)
			(xy 175.923102 -291.575712) (xy 175.934879 -291.527928) (xy 175.95417 -291.482652) (xy 175.980473 -291.441056)
			(xy 176.013108 -291.404219) (xy 176.051229 -291.373094) (xy 176.09385 -291.348487) (xy 176.139866 -291.331035)
			(xy 176.188085 -291.321191) (xy 176.23726 -291.31921) (xy 176.286115 -291.325142) (xy 176.333386 -291.338834)
			(xy 176.377848 -291.359932) (xy 176.418351 -291.387888) (xy 176.453844 -291.42198) (xy 176.483409 -291.461324)
			(xy 176.50628 -291.504901) (xy 176.521864 -291.551582) (xy 176.529759 -291.600159) (xy 176.530254 -291.624766)
			(xy 176.869102 -291.624766) (xy 176.873062 -291.575712) (xy 176.884839 -291.527928) (xy 176.90413 -291.482652)
			(xy 176.930433 -291.441056) (xy 176.963068 -291.404219) (xy 177.001189 -291.373094) (xy 177.04381 -291.348487)
			(xy 177.089826 -291.331035) (xy 177.138045 -291.321191) (xy 177.18722 -291.31921) (xy 177.236075 -291.325142)
			(xy 177.283346 -291.338834) (xy 177.327808 -291.359932) (xy 177.368311 -291.387888) (xy 177.403804 -291.42198)
			(xy 177.433369 -291.461324) (xy 177.45624 -291.504901) (xy 177.471824 -291.551582) (xy 177.479719 -291.600159)
			(xy 177.480214 -291.624766) (xy 177.819062 -291.624766) (xy 177.823022 -291.575712) (xy 177.834799 -291.527928)
			(xy 177.85409 -291.482652) (xy 177.880393 -291.441056) (xy 177.913028 -291.404219) (xy 177.951149 -291.373094)
			(xy 177.99377 -291.348487) (xy 178.039786 -291.331035) (xy 178.088005 -291.321191) (xy 178.13718 -291.31921)
			(xy 178.186035 -291.325142) (xy 178.233306 -291.338834) (xy 178.277768 -291.359932) (xy 178.318271 -291.387888)
			(xy 178.353764 -291.42198) (xy 178.383329 -291.461324) (xy 178.4062 -291.504901) (xy 178.421784 -291.551582)
			(xy 178.429679 -291.600159) (xy 178.430174 -291.624766) (xy 178.769276 -291.624766) (xy 178.773236 -291.575712)
			(xy 178.785013 -291.527928) (xy 178.804304 -291.482652) (xy 178.830607 -291.441056) (xy 178.863242 -291.404219)
			(xy 178.901363 -291.373094) (xy 178.943984 -291.348487) (xy 178.99 -291.331035) (xy 179.038219 -291.321191)
			(xy 179.087394 -291.31921) (xy 179.136249 -291.325142) (xy 179.18352 -291.338834) (xy 179.227982 -291.359932)
			(xy 179.268485 -291.387888) (xy 179.303978 -291.42198) (xy 179.333543 -291.461324) (xy 179.356414 -291.504901)
			(xy 179.371998 -291.551582) (xy 179.379893 -291.600159) (xy 179.380388 -291.624766) (xy 179.719236 -291.624766)
			(xy 179.723196 -291.575712) (xy 179.734973 -291.527928) (xy 179.754264 -291.482652) (xy 179.780567 -291.441056)
			(xy 179.813202 -291.404219) (xy 179.851323 -291.373094) (xy 179.893944 -291.348487) (xy 179.93996 -291.331035)
			(xy 179.988179 -291.321191) (xy 180.037354 -291.31921) (xy 180.086209 -291.325142) (xy 180.13348 -291.338834)
			(xy 180.177942 -291.359932) (xy 180.218445 -291.387888) (xy 180.253938 -291.42198) (xy 180.283503 -291.461324)
			(xy 180.306374 -291.504901) (xy 180.321958 -291.551582) (xy 180.329853 -291.600159) (xy 180.330348 -291.624766)
			(xy 180.669196 -291.624766) (xy 180.673156 -291.575712) (xy 180.684933 -291.527928) (xy 180.704224 -291.482652)
			(xy 180.730527 -291.441056) (xy 180.763162 -291.404219) (xy 180.801283 -291.373094) (xy 180.843904 -291.348487)
			(xy 180.88992 -291.331035) (xy 180.938139 -291.321191) (xy 180.987314 -291.31921) (xy 181.036169 -291.325142)
			(xy 181.08344 -291.338834) (xy 181.127902 -291.359932) (xy 181.168405 -291.387888) (xy 181.203898 -291.42198)
			(xy 181.233463 -291.461324) (xy 181.256334 -291.504901) (xy 181.271918 -291.551582) (xy 181.279813 -291.600159)
			(xy 181.280308 -291.624766) (xy 181.619156 -291.624766) (xy 181.623116 -291.575712) (xy 181.634893 -291.527928)
			(xy 181.654184 -291.482652) (xy 181.680487 -291.441056) (xy 181.713122 -291.404219) (xy 181.751243 -291.373094)
			(xy 181.793864 -291.348487) (xy 181.83988 -291.331035) (xy 181.888099 -291.321191) (xy 181.937274 -291.31921)
			(xy 181.986129 -291.325142) (xy 182.0334 -291.338834) (xy 182.077862 -291.359932) (xy 182.118365 -291.387888)
			(xy 182.153858 -291.42198) (xy 182.183423 -291.461324) (xy 182.206294 -291.504901) (xy 182.221878 -291.551582)
			(xy 182.229773 -291.600159) (xy 182.230268 -291.624766) (xy 182.569116 -291.624766) (xy 182.573076 -291.575712)
			(xy 182.584853 -291.527928) (xy 182.604144 -291.482652) (xy 182.630447 -291.441056) (xy 182.663082 -291.404219)
			(xy 182.701203 -291.373094) (xy 182.743824 -291.348487) (xy 182.78984 -291.331035) (xy 182.838059 -291.321191)
			(xy 182.887234 -291.31921) (xy 182.936089 -291.325142) (xy 182.98336 -291.338834) (xy 183.027822 -291.359932)
			(xy 183.068325 -291.387888) (xy 183.103818 -291.42198) (xy 183.133383 -291.461324) (xy 183.156254 -291.504901)
			(xy 183.171838 -291.551582) (xy 183.179733 -291.600159) (xy 183.180228 -291.624766) (xy 183.519076 -291.624766)
			(xy 183.523036 -291.575712) (xy 183.534813 -291.527928) (xy 183.554104 -291.482652) (xy 183.580407 -291.441056)
			(xy 183.613042 -291.404219) (xy 183.651163 -291.373094) (xy 183.693784 -291.348487) (xy 183.7398 -291.331035)
			(xy 183.788019 -291.321191) (xy 183.837194 -291.31921) (xy 183.886049 -291.325142) (xy 183.93332 -291.338834)
			(xy 183.977782 -291.359932) (xy 184.018285 -291.387888) (xy 184.053778 -291.42198) (xy 184.083343 -291.461324)
			(xy 184.106214 -291.504901) (xy 184.121798 -291.551582) (xy 184.129693 -291.600159) (xy 184.130188 -291.624766)
			(xy 184.129693 -291.649373) (xy 184.121798 -291.69795) (xy 184.106214 -291.744631) (xy 184.083343 -291.788208)
			(xy 184.053778 -291.827552) (xy 184.018285 -291.861644) (xy 183.977782 -291.8896) (xy 183.93332 -291.910698)
			(xy 183.886049 -291.92439) (xy 183.837194 -291.930322) (xy 183.788019 -291.928341) (xy 183.7398 -291.918497)
			(xy 183.693784 -291.901045) (xy 183.651163 -291.876438) (xy 183.613042 -291.845313) (xy 183.580407 -291.808476)
			(xy 183.554104 -291.76688) (xy 183.534813 -291.721604) (xy 183.523036 -291.67382) (xy 183.519076 -291.624766)
			(xy 183.180228 -291.624766) (xy 183.179733 -291.649373) (xy 183.171838 -291.69795) (xy 183.156254 -291.744631)
			(xy 183.133383 -291.788208) (xy 183.103818 -291.827552) (xy 183.068325 -291.861644) (xy 183.027822 -291.8896)
			(xy 182.98336 -291.910698) (xy 182.936089 -291.92439) (xy 182.887234 -291.930322) (xy 182.838059 -291.928341)
			(xy 182.78984 -291.918497) (xy 182.743824 -291.901045) (xy 182.701203 -291.876438) (xy 182.663082 -291.845313)
			(xy 182.630447 -291.808476) (xy 182.604144 -291.76688) (xy 182.584853 -291.721604) (xy 182.573076 -291.67382)
			(xy 182.569116 -291.624766) (xy 182.230268 -291.624766) (xy 182.229773 -291.649373) (xy 182.221878 -291.69795)
			(xy 182.206294 -291.744631) (xy 182.183423 -291.788208) (xy 182.153858 -291.827552) (xy 182.118365 -291.861644)
			(xy 182.077862 -291.8896) (xy 182.0334 -291.910698) (xy 181.986129 -291.92439) (xy 181.937274 -291.930322)
			(xy 181.888099 -291.928341) (xy 181.83988 -291.918497) (xy 181.793864 -291.901045) (xy 181.751243 -291.876438)
			(xy 181.713122 -291.845313) (xy 181.680487 -291.808476) (xy 181.654184 -291.76688) (xy 181.634893 -291.721604)
			(xy 181.623116 -291.67382) (xy 181.619156 -291.624766) (xy 181.280308 -291.624766) (xy 181.279813 -291.649373)
			(xy 181.271918 -291.69795) (xy 181.256334 -291.744631) (xy 181.233463 -291.788208) (xy 181.203898 -291.827552)
			(xy 181.168405 -291.861644) (xy 181.127902 -291.8896) (xy 181.08344 -291.910698) (xy 181.036169 -291.92439)
			(xy 180.987314 -291.930322) (xy 180.938139 -291.928341) (xy 180.88992 -291.918497) (xy 180.843904 -291.901045)
			(xy 180.801283 -291.876438) (xy 180.763162 -291.845313) (xy 180.730527 -291.808476) (xy 180.704224 -291.76688)
			(xy 180.684933 -291.721604) (xy 180.673156 -291.67382) (xy 180.669196 -291.624766) (xy 180.330348 -291.624766)
			(xy 180.329853 -291.649373) (xy 180.321958 -291.69795) (xy 180.306374 -291.744631) (xy 180.283503 -291.788208)
			(xy 180.253938 -291.827552) (xy 180.218445 -291.861644) (xy 180.177942 -291.8896) (xy 180.13348 -291.910698)
			(xy 180.086209 -291.92439) (xy 180.037354 -291.930322) (xy 179.988179 -291.928341) (xy 179.93996 -291.918497)
			(xy 179.893944 -291.901045) (xy 179.851323 -291.876438) (xy 179.813202 -291.845313) (xy 179.780567 -291.808476)
			(xy 179.754264 -291.76688) (xy 179.734973 -291.721604) (xy 179.723196 -291.67382) (xy 179.719236 -291.624766)
			(xy 179.380388 -291.624766) (xy 179.379893 -291.649373) (xy 179.371998 -291.69795) (xy 179.356414 -291.744631)
			(xy 179.333543 -291.788208) (xy 179.303978 -291.827552) (xy 179.268485 -291.861644) (xy 179.227982 -291.8896)
			(xy 179.18352 -291.910698) (xy 179.136249 -291.92439) (xy 179.087394 -291.930322) (xy 179.038219 -291.928341)
			(xy 178.99 -291.918497) (xy 178.943984 -291.901045) (xy 178.901363 -291.876438) (xy 178.863242 -291.845313)
			(xy 178.830607 -291.808476) (xy 178.804304 -291.76688) (xy 178.785013 -291.721604) (xy 178.773236 -291.67382)
			(xy 178.769276 -291.624766) (xy 178.430174 -291.624766) (xy 178.429679 -291.649373) (xy 178.421784 -291.69795)
			(xy 178.4062 -291.744631) (xy 178.383329 -291.788208) (xy 178.353764 -291.827552) (xy 178.318271 -291.861644)
			(xy 178.277768 -291.8896) (xy 178.233306 -291.910698) (xy 178.186035 -291.92439) (xy 178.13718 -291.930322)
			(xy 178.088005 -291.928341) (xy 178.039786 -291.918497) (xy 177.99377 -291.901045) (xy 177.951149 -291.876438)
			(xy 177.913028 -291.845313) (xy 177.880393 -291.808476) (xy 177.85409 -291.76688) (xy 177.834799 -291.721604)
			(xy 177.823022 -291.67382) (xy 177.819062 -291.624766) (xy 177.480214 -291.624766) (xy 177.479719 -291.649373)
			(xy 177.471824 -291.69795) (xy 177.45624 -291.744631) (xy 177.433369 -291.788208) (xy 177.403804 -291.827552)
			(xy 177.368311 -291.861644) (xy 177.327808 -291.8896) (xy 177.283346 -291.910698) (xy 177.236075 -291.92439)
			(xy 177.18722 -291.930322) (xy 177.138045 -291.928341) (xy 177.089826 -291.918497) (xy 177.04381 -291.901045)
			(xy 177.001189 -291.876438) (xy 176.963068 -291.845313) (xy 176.930433 -291.808476) (xy 176.90413 -291.76688)
			(xy 176.884839 -291.721604) (xy 176.873062 -291.67382) (xy 176.869102 -291.624766) (xy 176.530254 -291.624766)
			(xy 176.529759 -291.649373) (xy 176.521864 -291.69795) (xy 176.50628 -291.744631) (xy 176.483409 -291.788208)
			(xy 176.453844 -291.827552) (xy 176.418351 -291.861644) (xy 176.377848 -291.8896) (xy 176.333386 -291.910698)
			(xy 176.286115 -291.92439) (xy 176.23726 -291.930322) (xy 176.188085 -291.928341) (xy 176.139866 -291.918497)
			(xy 176.09385 -291.901045) (xy 176.051229 -291.876438) (xy 176.013108 -291.845313) (xy 175.980473 -291.808476)
			(xy 175.95417 -291.76688) (xy 175.934879 -291.721604) (xy 175.923102 -291.67382) (xy 175.919142 -291.624766)
			(xy 174.630334 -291.624766) (xy 174.629839 -291.649373) (xy 174.621944 -291.69795) (xy 174.60636 -291.744631)
			(xy 174.583489 -291.788208) (xy 174.553924 -291.827552) (xy 174.518431 -291.861644) (xy 174.477928 -291.8896)
			(xy 174.433466 -291.910698) (xy 174.386195 -291.92439) (xy 174.33734 -291.930322) (xy 174.288165 -291.928341)
			(xy 174.239946 -291.918497) (xy 174.19393 -291.901045) (xy 174.151309 -291.876438) (xy 174.113188 -291.845313)
			(xy 174.080553 -291.808476) (xy 174.05425 -291.76688) (xy 174.034959 -291.721604) (xy 174.023182 -291.67382)
			(xy 174.019222 -291.624766) (xy 173.680374 -291.624766) (xy 173.679879 -291.649373) (xy 173.671984 -291.69795)
			(xy 173.6564 -291.744631) (xy 173.633529 -291.788208) (xy 173.603964 -291.827552) (xy 173.568471 -291.861644)
			(xy 173.527968 -291.8896) (xy 173.483506 -291.910698) (xy 173.436235 -291.92439) (xy 173.38738 -291.930322)
			(xy 173.338205 -291.928341) (xy 173.289986 -291.918497) (xy 173.24397 -291.901045) (xy 173.201349 -291.876438)
			(xy 173.163228 -291.845313) (xy 173.130593 -291.808476) (xy 173.10429 -291.76688) (xy 173.084999 -291.721604)
			(xy 173.073222 -291.67382) (xy 173.069262 -291.624766) (xy 172.73016 -291.624766) (xy 172.729665 -291.649373)
			(xy 172.72177 -291.69795) (xy 172.706186 -291.744631) (xy 172.683315 -291.788208) (xy 172.65375 -291.827552)
			(xy 172.618257 -291.861644) (xy 172.577754 -291.8896) (xy 172.533292 -291.910698) (xy 172.486021 -291.92439)
			(xy 172.437166 -291.930322) (xy 172.387991 -291.928341) (xy 172.339772 -291.918497) (xy 172.293756 -291.901045)
			(xy 172.251135 -291.876438) (xy 172.213014 -291.845313) (xy 172.180379 -291.808476) (xy 172.154076 -291.76688)
			(xy 172.134785 -291.721604) (xy 172.123008 -291.67382) (xy 172.119048 -291.624766) (xy 171.7802 -291.624766)
			(xy 171.779705 -291.649373) (xy 171.77181 -291.69795) (xy 171.756226 -291.744631) (xy 171.733355 -291.788208)
			(xy 171.70379 -291.827552) (xy 171.668297 -291.861644) (xy 171.627794 -291.8896) (xy 171.583332 -291.910698)
			(xy 171.536061 -291.92439) (xy 171.487206 -291.930322) (xy 171.438031 -291.928341) (xy 171.389812 -291.918497)
			(xy 171.343796 -291.901045) (xy 171.301175 -291.876438) (xy 171.263054 -291.845313) (xy 171.230419 -291.808476)
			(xy 171.204116 -291.76688) (xy 171.184825 -291.721604) (xy 171.173048 -291.67382) (xy 171.169088 -291.624766)
			(xy 170.83024 -291.624766) (xy 170.829745 -291.649373) (xy 170.82185 -291.69795) (xy 170.806266 -291.744631)
			(xy 170.783395 -291.788208) (xy 170.75383 -291.827552) (xy 170.718337 -291.861644) (xy 170.677834 -291.8896)
			(xy 170.633372 -291.910698) (xy 170.586101 -291.92439) (xy 170.537246 -291.930322) (xy 170.488071 -291.928341)
			(xy 170.439852 -291.918497) (xy 170.393836 -291.901045) (xy 170.351215 -291.876438) (xy 170.313094 -291.845313)
			(xy 170.280459 -291.808476) (xy 170.254156 -291.76688) (xy 170.234865 -291.721604) (xy 170.223088 -291.67382)
			(xy 170.219128 -291.624766) (xy 169.88028 -291.624766) (xy 169.879785 -291.649373) (xy 169.87189 -291.69795)
			(xy 169.856306 -291.744631) (xy 169.833435 -291.788208) (xy 169.80387 -291.827552) (xy 169.768377 -291.861644)
			(xy 169.727874 -291.8896) (xy 169.683412 -291.910698) (xy 169.636141 -291.92439) (xy 169.587286 -291.930322)
			(xy 169.538111 -291.928341) (xy 169.489892 -291.918497) (xy 169.443876 -291.901045) (xy 169.401255 -291.876438)
			(xy 169.363134 -291.845313) (xy 169.330499 -291.808476) (xy 169.304196 -291.76688) (xy 169.284905 -291.721604)
			(xy 169.273128 -291.67382) (xy 169.269168 -291.624766) (xy 168.93032 -291.624766) (xy 168.929825 -291.649373)
			(xy 168.92193 -291.69795) (xy 168.906346 -291.744631) (xy 168.883475 -291.788208) (xy 168.85391 -291.827552)
			(xy 168.818417 -291.861644) (xy 168.777914 -291.8896) (xy 168.733452 -291.910698) (xy 168.686181 -291.92439)
			(xy 168.637326 -291.930322) (xy 168.588151 -291.928341) (xy 168.539932 -291.918497) (xy 168.493916 -291.901045)
			(xy 168.451295 -291.876438) (xy 168.413174 -291.845313) (xy 168.380539 -291.808476) (xy 168.354236 -291.76688)
			(xy 168.334945 -291.721604) (xy 168.323168 -291.67382) (xy 168.319208 -291.624766) (xy 167.98036 -291.624766)
			(xy 167.979865 -291.649373) (xy 167.97197 -291.69795) (xy 167.956386 -291.744631) (xy 167.933515 -291.788208)
			(xy 167.90395 -291.827552) (xy 167.868457 -291.861644) (xy 167.827954 -291.8896) (xy 167.783492 -291.910698)
			(xy 167.736221 -291.92439) (xy 167.687366 -291.930322) (xy 167.638191 -291.928341) (xy 167.589972 -291.918497)
			(xy 167.543956 -291.901045) (xy 167.501335 -291.876438) (xy 167.463214 -291.845313) (xy 167.430579 -291.808476)
			(xy 167.404276 -291.76688) (xy 167.384985 -291.721604) (xy 167.373208 -291.67382) (xy 167.369248 -291.624766)
			(xy 167.0304 -291.624766) (xy 167.029905 -291.649373) (xy 167.02201 -291.69795) (xy 167.006426 -291.744631)
			(xy 166.983555 -291.788208) (xy 166.95399 -291.827552) (xy 166.918497 -291.861644) (xy 166.877994 -291.8896)
			(xy 166.833532 -291.910698) (xy 166.786261 -291.92439) (xy 166.737406 -291.930322) (xy 166.688231 -291.928341)
			(xy 166.640012 -291.918497) (xy 166.593996 -291.901045) (xy 166.551375 -291.876438) (xy 166.513254 -291.845313)
			(xy 166.480619 -291.808476) (xy 166.454316 -291.76688) (xy 166.435025 -291.721604) (xy 166.423248 -291.67382)
			(xy 166.419288 -291.624766) (xy 165.130226 -291.624766) (xy 165.129731 -291.649373) (xy 165.121836 -291.69795)
			(xy 165.106252 -291.744631) (xy 165.083381 -291.788208) (xy 165.053816 -291.827552) (xy 165.018323 -291.861644)
			(xy 164.97782 -291.8896) (xy 164.933358 -291.910698) (xy 164.886087 -291.92439) (xy 164.837232 -291.930322)
			(xy 164.788057 -291.928341) (xy 164.739838 -291.918497) (xy 164.693822 -291.901045) (xy 164.651201 -291.876438)
			(xy 164.61308 -291.845313) (xy 164.580445 -291.808476) (xy 164.554142 -291.76688) (xy 164.534851 -291.721604)
			(xy 164.523074 -291.67382) (xy 164.519114 -291.624766) (xy 164.180266 -291.624766) (xy 164.179771 -291.649373)
			(xy 164.171876 -291.69795) (xy 164.156292 -291.744631) (xy 164.133421 -291.788208) (xy 164.103856 -291.827552)
			(xy 164.068363 -291.861644) (xy 164.02786 -291.8896) (xy 163.983398 -291.910698) (xy 163.936127 -291.92439)
			(xy 163.887272 -291.930322) (xy 163.838097 -291.928341) (xy 163.789878 -291.918497) (xy 163.743862 -291.901045)
			(xy 163.701241 -291.876438) (xy 163.66312 -291.845313) (xy 163.630485 -291.808476) (xy 163.604182 -291.76688)
			(xy 163.584891 -291.721604) (xy 163.573114 -291.67382) (xy 163.569154 -291.624766) (xy 162.280346 -291.624766)
			(xy 162.279851 -291.649373) (xy 162.271956 -291.69795) (xy 162.256372 -291.744631) (xy 162.233501 -291.788208)
			(xy 162.203936 -291.827552) (xy 162.168443 -291.861644) (xy 162.12794 -291.8896) (xy 162.083478 -291.910698)
			(xy 162.036207 -291.92439) (xy 161.987352 -291.930322) (xy 161.938177 -291.928341) (xy 161.889958 -291.918497)
			(xy 161.843942 -291.901045) (xy 161.801321 -291.876438) (xy 161.7632 -291.845313) (xy 161.730565 -291.808476)
			(xy 161.704262 -291.76688) (xy 161.684971 -291.721604) (xy 161.673194 -291.67382) (xy 161.669234 -291.624766)
			(xy 161.330386 -291.624766) (xy 161.329891 -291.649373) (xy 161.321996 -291.69795) (xy 161.306412 -291.744631)
			(xy 161.283541 -291.788208) (xy 161.253976 -291.827552) (xy 161.218483 -291.861644) (xy 161.17798 -291.8896)
			(xy 161.133518 -291.910698) (xy 161.086247 -291.92439) (xy 161.037392 -291.930322) (xy 160.988217 -291.928341)
			(xy 160.939998 -291.918497) (xy 160.893982 -291.901045) (xy 160.851361 -291.876438) (xy 160.81324 -291.845313)
			(xy 160.780605 -291.808476) (xy 160.754302 -291.76688) (xy 160.735011 -291.721604) (xy 160.723234 -291.67382)
			(xy 160.719274 -291.624766) (xy 160.380172 -291.624766) (xy 160.379677 -291.649373) (xy 160.371782 -291.69795)
			(xy 160.356198 -291.744631) (xy 160.333327 -291.788208) (xy 160.303762 -291.827552) (xy 160.268269 -291.861644)
			(xy 160.227766 -291.8896) (xy 160.183304 -291.910698) (xy 160.136033 -291.92439) (xy 160.087178 -291.930322)
			(xy 160.038003 -291.928341) (xy 159.989784 -291.918497) (xy 159.943768 -291.901045) (xy 159.901147 -291.876438)
			(xy 159.863026 -291.845313) (xy 159.830391 -291.808476) (xy 159.804088 -291.76688) (xy 159.784797 -291.721604)
			(xy 159.77302 -291.67382) (xy 159.76906 -291.624766) (xy 159.430212 -291.624766) (xy 159.429717 -291.649373)
			(xy 159.421822 -291.69795) (xy 159.406238 -291.744631) (xy 159.383367 -291.788208) (xy 159.353802 -291.827552)
			(xy 159.318309 -291.861644) (xy 159.277806 -291.8896) (xy 159.233344 -291.910698) (xy 159.186073 -291.92439)
			(xy 159.137218 -291.930322) (xy 159.088043 -291.928341) (xy 159.039824 -291.918497) (xy 158.993808 -291.901045)
			(xy 158.951187 -291.876438) (xy 158.913066 -291.845313) (xy 158.880431 -291.808476) (xy 158.854128 -291.76688)
			(xy 158.834837 -291.721604) (xy 158.82306 -291.67382) (xy 158.8191 -291.624766) (xy 158.480252 -291.624766)
			(xy 158.479757 -291.649373) (xy 158.471862 -291.69795) (xy 158.456278 -291.744631) (xy 158.433407 -291.788208)
			(xy 158.403842 -291.827552) (xy 158.368349 -291.861644) (xy 158.327846 -291.8896) (xy 158.283384 -291.910698)
			(xy 158.236113 -291.92439) (xy 158.187258 -291.930322) (xy 158.138083 -291.928341) (xy 158.089864 -291.918497)
			(xy 158.043848 -291.901045) (xy 158.001227 -291.876438) (xy 157.963106 -291.845313) (xy 157.930471 -291.808476)
			(xy 157.904168 -291.76688) (xy 157.884877 -291.721604) (xy 157.8731 -291.67382) (xy 157.86914 -291.624766)
			(xy 157.530292 -291.624766) (xy 157.529797 -291.649373) (xy 157.521902 -291.69795) (xy 157.506318 -291.744631)
			(xy 157.483447 -291.788208) (xy 157.453882 -291.827552) (xy 157.418389 -291.861644) (xy 157.377886 -291.8896)
			(xy 157.333424 -291.910698) (xy 157.286153 -291.92439) (xy 157.237298 -291.930322) (xy 157.188123 -291.928341)
			(xy 157.139904 -291.918497) (xy 157.093888 -291.901045) (xy 157.051267 -291.876438) (xy 157.013146 -291.845313)
			(xy 156.980511 -291.808476) (xy 156.954208 -291.76688) (xy 156.934917 -291.721604) (xy 156.92314 -291.67382)
			(xy 156.91918 -291.624766) (xy 154.680412 -291.624766) (xy 154.679917 -291.649373) (xy 154.672022 -291.69795)
			(xy 154.656438 -291.744631) (xy 154.633567 -291.788208) (xy 154.604002 -291.827552) (xy 154.568509 -291.861644)
			(xy 154.528006 -291.8896) (xy 154.483544 -291.910698) (xy 154.436273 -291.92439) (xy 154.387418 -291.930322)
			(xy 154.338243 -291.928341) (xy 154.290024 -291.918497) (xy 154.244008 -291.901045) (xy 154.201387 -291.876438)
			(xy 154.163266 -291.845313) (xy 154.130631 -291.808476) (xy 154.104328 -291.76688) (xy 154.085037 -291.721604)
			(xy 154.07326 -291.67382) (xy 154.0693 -291.624766) (xy 153.730198 -291.624766) (xy 153.729703 -291.649373)
			(xy 153.721808 -291.69795) (xy 153.706224 -291.744631) (xy 153.683353 -291.788208) (xy 153.653788 -291.827552)
			(xy 153.618295 -291.861644) (xy 153.577792 -291.8896) (xy 153.53333 -291.910698) (xy 153.486059 -291.92439)
			(xy 153.437204 -291.930322) (xy 153.388029 -291.928341) (xy 153.33981 -291.918497) (xy 153.293794 -291.901045)
			(xy 153.251173 -291.876438) (xy 153.213052 -291.845313) (xy 153.180417 -291.808476) (xy 153.154114 -291.76688)
			(xy 153.134823 -291.721604) (xy 153.123046 -291.67382) (xy 153.119086 -291.624766) (xy 152.780238 -291.624766)
			(xy 152.779743 -291.649373) (xy 152.771848 -291.69795) (xy 152.756264 -291.744631) (xy 152.733393 -291.788208)
			(xy 152.703828 -291.827552) (xy 152.668335 -291.861644) (xy 152.627832 -291.8896) (xy 152.58337 -291.910698)
			(xy 152.536099 -291.92439) (xy 152.487244 -291.930322) (xy 152.438069 -291.928341) (xy 152.38985 -291.918497)
			(xy 152.343834 -291.901045) (xy 152.301213 -291.876438) (xy 152.263092 -291.845313) (xy 152.230457 -291.808476)
			(xy 152.204154 -291.76688) (xy 152.184863 -291.721604) (xy 152.173086 -291.67382) (xy 152.169126 -291.624766)
			(xy 144.107012 -291.624766) (xy 144.081098 -291.663935) (xy 144.043881 -291.705472) (xy 144.001013 -291.741147)
			(xy 143.953407 -291.770201) (xy 143.902078 -291.792013) (xy 143.848121 -291.806119) (xy 143.792684 -291.812219)
			(xy 143.73695 -291.810182) (xy 143.682107 -291.800052) (xy 143.629323 -291.782045) (xy 143.579723 -291.756544)
			(xy 143.534365 -291.724093) (xy 143.494216 -291.685384) (xy 143.46013 -291.641241) (xy 143.432834 -291.592606)
			(xy 143.412911 -291.540515) (xy 143.400785 -291.486078) (xy 143.396714 -291.430456) (xy 142.675102 -291.430456)
			(xy 142.674593 -291.458342) (xy 142.666473 -291.513518) (xy 142.650405 -291.566925) (xy 142.626733 -291.617422)
			(xy 142.59596 -291.663935) (xy 142.558743 -291.705472) (xy 142.515875 -291.741147) (xy 142.468269 -291.770201)
			(xy 142.41694 -291.792013) (xy 142.362983 -291.806119) (xy 142.307546 -291.812219) (xy 142.251812 -291.810182)
			(xy 142.196969 -291.800052) (xy 142.144185 -291.782045) (xy 142.094585 -291.756544) (xy 142.049227 -291.724093)
			(xy 142.009078 -291.685384) (xy 141.974992 -291.641241) (xy 141.947696 -291.592606) (xy 141.927773 -291.540515)
			(xy 141.915647 -291.486078) (xy 141.911576 -291.430456) (xy 136.349994 -291.430456) (xy 136.349994 -292.732714)
			(xy 141.911576 -292.732714) (xy 141.915647 -292.677092) (xy 141.927773 -292.622655) (xy 141.947696 -292.570564)
			(xy 141.974992 -292.521929) (xy 142.009078 -292.477786) (xy 142.049227 -292.439077) (xy 142.094585 -292.406626)
			(xy 142.144185 -292.381125) (xy 142.196969 -292.363118) (xy 142.251812 -292.352988) (xy 142.307546 -292.350951)
			(xy 142.362983 -292.357051) (xy 142.41694 -292.371157) (xy 142.468269 -292.392969) (xy 142.515875 -292.422023)
			(xy 142.558743 -292.457698) (xy 142.59596 -292.499235) (xy 142.626733 -292.545748) (xy 142.650405 -292.596245)
			(xy 142.666473 -292.649652) (xy 142.674593 -292.704828) (xy 142.675102 -292.732714) (xy 143.387062 -292.732714)
			(xy 143.391133 -292.677092) (xy 143.403259 -292.622655) (xy 143.423182 -292.570564) (xy 143.450478 -292.521929)
			(xy 143.484564 -292.477786) (xy 143.524713 -292.439077) (xy 143.570071 -292.406626) (xy 143.619671 -292.381125)
			(xy 143.672455 -292.363118) (xy 143.727298 -292.352988) (xy 143.783032 -292.350951) (xy 143.838469 -292.357051)
			(xy 143.892426 -292.371157) (xy 143.943755 -292.392969) (xy 143.991361 -292.422023) (xy 144.034229 -292.457698)
			(xy 144.071446 -292.499235) (xy 144.102219 -292.545748) (xy 144.125891 -292.596245) (xy 144.141959 -292.649652)
			(xy 144.150079 -292.704828) (xy 144.150588 -292.732714) (xy 144.276062 -292.732714) (xy 144.280133 -292.677092)
			(xy 144.292259 -292.622655) (xy 144.312182 -292.570564) (xy 144.339478 -292.521929) (xy 144.373564 -292.477786)
			(xy 144.413713 -292.439077) (xy 144.459071 -292.406626) (xy 144.508671 -292.381125) (xy 144.561455 -292.363118)
			(xy 144.616298 -292.352988) (xy 144.672032 -292.350951) (xy 144.727469 -292.357051) (xy 144.781426 -292.371157)
			(xy 144.832755 -292.392969) (xy 144.880361 -292.422023) (xy 144.923229 -292.457698) (xy 144.960446 -292.499235)
			(xy 144.991219 -292.545748) (xy 145.014891 -292.596245) (xy 145.030959 -292.649652) (xy 145.039079 -292.704828)
			(xy 145.039588 -292.732714) (xy 145.039079 -292.7606) (xy 145.030959 -292.815776) (xy 145.014891 -292.869183)
			(xy 144.991219 -292.91968) (xy 144.960446 -292.966193) (xy 144.923229 -293.00773) (xy 144.880361 -293.043405)
			(xy 144.832755 -293.072459) (xy 144.781426 -293.094271) (xy 144.727469 -293.108377) (xy 144.672032 -293.114477)
			(xy 144.616298 -293.11244) (xy 144.561455 -293.10231) (xy 144.508671 -293.084303) (xy 144.459071 -293.058802)
			(xy 144.413713 -293.026351) (xy 144.373564 -292.987642) (xy 144.339478 -292.943499) (xy 144.312182 -292.894864)
			(xy 144.292259 -292.842773) (xy 144.280133 -292.788336) (xy 144.276062 -292.732714) (xy 144.150588 -292.732714)
			(xy 144.150079 -292.7606) (xy 144.141959 -292.815776) (xy 144.125891 -292.869183) (xy 144.102219 -292.91968)
			(xy 144.071446 -292.966193) (xy 144.034229 -293.00773) (xy 143.991361 -293.043405) (xy 143.943755 -293.072459)
			(xy 143.892426 -293.094271) (xy 143.838469 -293.108377) (xy 143.783032 -293.114477) (xy 143.727298 -293.11244)
			(xy 143.672455 -293.10231) (xy 143.619671 -293.084303) (xy 143.570071 -293.058802) (xy 143.524713 -293.026351)
			(xy 143.484564 -292.987642) (xy 143.450478 -292.943499) (xy 143.423182 -292.894864) (xy 143.403259 -292.842773)
			(xy 143.391133 -292.788336) (xy 143.387062 -292.732714) (xy 142.675102 -292.732714) (xy 142.674593 -292.7606)
			(xy 142.666473 -292.815776) (xy 142.650405 -292.869183) (xy 142.626733 -292.91968) (xy 142.59596 -292.966193)
			(xy 142.558743 -293.00773) (xy 142.515875 -293.043405) (xy 142.468269 -293.072459) (xy 142.41694 -293.094271)
			(xy 142.362983 -293.108377) (xy 142.307546 -293.114477) (xy 142.251812 -293.11244) (xy 142.196969 -293.10231)
			(xy 142.144185 -293.084303) (xy 142.094585 -293.058802) (xy 142.049227 -293.026351) (xy 142.009078 -292.987642)
			(xy 141.974992 -292.943499) (xy 141.947696 -292.894864) (xy 141.927773 -292.842773) (xy 141.915647 -292.788336)
			(xy 141.911576 -292.732714) (xy 136.349994 -292.732714) (xy 136.349994 -293.201852) (xy 136.349561 -293.211918)
			(xy 136.341833 -293.230508) (xy 136.335008 -293.23792) (xy 136.078214 -293.494714) (xy 147.43811 -293.494714)
			(xy 147.438654 -293.465332) (xy 147.447683 -293.407265) (xy 147.465514 -293.351271) (xy 147.491725 -293.298675)
			(xy 147.525695 -293.250724) (xy 147.56662 -293.208552) (xy 147.589748 -293.190422) (xy 147.598672 -293.182942)
			(xy 147.609132 -293.162168) (xy 147.609814 -293.150544) (xy 147.611084 -293.058596) (xy 147.601178 -293.037514)
			(xy 147.592034 -293.030148) (xy 147.570186 -293.011942) (xy 147.531644 -292.970124) (xy 147.499736 -292.923049)
			(xy 147.475169 -292.871759) (xy 147.458486 -292.817391) (xy 147.450058 -292.761149) (xy 147.44954 -292.732714)
			(xy 147.450026 -292.705463) (xy 147.457782 -292.651515) (xy 147.473137 -292.59922) (xy 147.495779 -292.549643)
			(xy 147.525245 -292.503793) (xy 147.560936 -292.462602) (xy 147.602127 -292.426911) (xy 147.647977 -292.397445)
			(xy 147.697554 -292.374803) (xy 147.749849 -292.359448) (xy 147.803797 -292.351692) (xy 147.858299 -292.351692)
			(xy 147.912247 -292.359448) (xy 147.964542 -292.374803) (xy 148.014119 -292.397445) (xy 148.059969 -292.426911)
			(xy 148.10116 -292.462602) (xy 148.136851 -292.503793) (xy 148.166317 -292.549643) (xy 148.177889 -292.57498)
			(xy 152.169126 -292.57498) (xy 152.173086 -292.525926) (xy 152.184863 -292.478142) (xy 152.204154 -292.432866)
			(xy 152.230457 -292.39127) (xy 152.263092 -292.354433) (xy 152.301213 -292.323308) (xy 152.343834 -292.298701)
			(xy 152.38985 -292.281249) (xy 152.438069 -292.271405) (xy 152.487244 -292.269424) (xy 152.536099 -292.275356)
			(xy 152.58337 -292.289048) (xy 152.627832 -292.310146) (xy 152.668335 -292.338102) (xy 152.703828 -292.372194)
			(xy 152.733393 -292.411538) (xy 152.756264 -292.455115) (xy 152.771848 -292.501796) (xy 152.779743 -292.550373)
			(xy 152.780238 -292.57498) (xy 153.119086 -292.57498) (xy 153.123046 -292.525926) (xy 153.134823 -292.478142)
			(xy 153.154114 -292.432866) (xy 153.180417 -292.39127) (xy 153.213052 -292.354433) (xy 153.251173 -292.323308)
			(xy 153.293794 -292.298701) (xy 153.33981 -292.281249) (xy 153.388029 -292.271405) (xy 153.437204 -292.269424)
			(xy 153.486059 -292.275356) (xy 153.53333 -292.289048) (xy 153.577792 -292.310146) (xy 153.618295 -292.338102)
			(xy 153.653788 -292.372194) (xy 153.683353 -292.411538) (xy 153.706224 -292.455115) (xy 153.721808 -292.501796)
			(xy 153.729703 -292.550373) (xy 153.730198 -292.57498) (xy 154.0693 -292.57498) (xy 154.07326 -292.525926)
			(xy 154.085037 -292.478142) (xy 154.104328 -292.432866) (xy 154.130631 -292.39127) (xy 154.163266 -292.354433)
			(xy 154.201387 -292.323308) (xy 154.244008 -292.298701) (xy 154.290024 -292.281249) (xy 154.338243 -292.271405)
			(xy 154.387418 -292.269424) (xy 154.436273 -292.275356) (xy 154.483544 -292.289048) (xy 154.528006 -292.310146)
			(xy 154.568509 -292.338102) (xy 154.604002 -292.372194) (xy 154.633567 -292.411538) (xy 154.656438 -292.455115)
			(xy 154.672022 -292.501796) (xy 154.679917 -292.550373) (xy 154.680407 -292.574726) (xy 155.01926 -292.574726)
			(xy 155.02322 -292.525672) (xy 155.034997 -292.477888) (xy 155.054288 -292.432612) (xy 155.080591 -292.391016)
			(xy 155.113226 -292.354179) (xy 155.151347 -292.323054) (xy 155.193968 -292.298447) (xy 155.239984 -292.280995)
			(xy 155.288203 -292.271151) (xy 155.337378 -292.26917) (xy 155.386233 -292.275102) (xy 155.433504 -292.288794)
			(xy 155.477966 -292.309892) (xy 155.518469 -292.337848) (xy 155.553962 -292.37194) (xy 155.583527 -292.411284)
			(xy 155.606398 -292.454861) (xy 155.621982 -292.501542) (xy 155.629877 -292.550119) (xy 155.630372 -292.574726)
			(xy 155.96922 -292.574726) (xy 155.97318 -292.525672) (xy 155.984957 -292.477888) (xy 156.004248 -292.432612)
			(xy 156.030551 -292.391016) (xy 156.063186 -292.354179) (xy 156.101307 -292.323054) (xy 156.143928 -292.298447)
			(xy 156.189944 -292.280995) (xy 156.238163 -292.271151) (xy 156.287338 -292.26917) (xy 156.336193 -292.275102)
			(xy 156.383464 -292.288794) (xy 156.427926 -292.309892) (xy 156.468429 -292.337848) (xy 156.503922 -292.37194)
			(xy 156.533487 -292.411284) (xy 156.556358 -292.454861) (xy 156.571942 -292.501542) (xy 156.579837 -292.550119)
			(xy 156.580332 -292.574726) (xy 156.580327 -292.57498) (xy 156.91918 -292.57498) (xy 156.92314 -292.525926)
			(xy 156.934917 -292.478142) (xy 156.954208 -292.432866) (xy 156.980511 -292.39127) (xy 157.013146 -292.354433)
			(xy 157.051267 -292.323308) (xy 157.093888 -292.298701) (xy 157.139904 -292.281249) (xy 157.188123 -292.271405)
			(xy 157.237298 -292.269424) (xy 157.286153 -292.275356) (xy 157.333424 -292.289048) (xy 157.377886 -292.310146)
			(xy 157.418389 -292.338102) (xy 157.453882 -292.372194) (xy 157.483447 -292.411538) (xy 157.506318 -292.455115)
			(xy 157.521902 -292.501796) (xy 157.529797 -292.550373) (xy 157.530292 -292.57498) (xy 157.529797 -292.599587)
			(xy 157.529465 -292.601629) (xy 157.819334 -292.601629) (xy 157.819334 -292.548331) (xy 157.827277 -292.495627)
			(xy 157.842987 -292.444697) (xy 157.866113 -292.396676) (xy 157.896137 -292.352639) (xy 157.932389 -292.313568)
			(xy 157.97406 -292.280337) (xy 158.020218 -292.253688) (xy 158.069832 -292.234216) (xy 158.121794 -292.222356)
			(xy 158.174944 -292.218373) (xy 158.228094 -292.222356) (xy 158.280056 -292.234216) (xy 158.32967 -292.253688)
			(xy 158.375828 -292.280337) (xy 158.417499 -292.313568) (xy 158.453751 -292.352639) (xy 158.483775 -292.396676)
			(xy 158.506901 -292.444697) (xy 158.522611 -292.495627) (xy 158.530554 -292.548331) (xy 158.531052 -292.57498)
			(xy 158.8191 -292.57498) (xy 158.82306 -292.525926) (xy 158.834837 -292.478142) (xy 158.854128 -292.432866)
			(xy 158.880431 -292.39127) (xy 158.913066 -292.354433) (xy 158.951187 -292.323308) (xy 158.993808 -292.298701)
			(xy 159.039824 -292.281249) (xy 159.088043 -292.271405) (xy 159.137218 -292.269424) (xy 159.186073 -292.275356)
			(xy 159.233344 -292.289048) (xy 159.277806 -292.310146) (xy 159.318309 -292.338102) (xy 159.353802 -292.372194)
			(xy 159.383367 -292.411538) (xy 159.406238 -292.455115) (xy 159.421822 -292.501796) (xy 159.429717 -292.550373)
			(xy 159.430212 -292.57498) (xy 159.76906 -292.57498) (xy 159.77302 -292.525926) (xy 159.784797 -292.478142)
			(xy 159.804088 -292.432866) (xy 159.830391 -292.39127) (xy 159.863026 -292.354433) (xy 159.901147 -292.323308)
			(xy 159.943768 -292.298701) (xy 159.989784 -292.281249) (xy 160.038003 -292.271405) (xy 160.087178 -292.269424)
			(xy 160.136033 -292.275356) (xy 160.183304 -292.289048) (xy 160.227766 -292.310146) (xy 160.268269 -292.338102)
			(xy 160.303762 -292.372194) (xy 160.333327 -292.411538) (xy 160.356198 -292.455115) (xy 160.371782 -292.501796)
			(xy 160.379677 -292.550373) (xy 160.380172 -292.57498) (xy 160.719274 -292.57498) (xy 160.723234 -292.525926)
			(xy 160.735011 -292.478142) (xy 160.754302 -292.432866) (xy 160.780605 -292.39127) (xy 160.81324 -292.354433)
			(xy 160.851361 -292.323308) (xy 160.893982 -292.298701) (xy 160.939998 -292.281249) (xy 160.988217 -292.271405)
			(xy 161.037392 -292.269424) (xy 161.086247 -292.275356) (xy 161.133518 -292.289048) (xy 161.17798 -292.310146)
			(xy 161.218483 -292.338102) (xy 161.253976 -292.372194) (xy 161.283541 -292.411538) (xy 161.306412 -292.455115)
			(xy 161.321996 -292.501796) (xy 161.329891 -292.550373) (xy 161.330386 -292.57498) (xy 161.669234 -292.57498)
			(xy 161.673194 -292.525926) (xy 161.684971 -292.478142) (xy 161.704262 -292.432866) (xy 161.730565 -292.39127)
			(xy 161.7632 -292.354433) (xy 161.801321 -292.323308) (xy 161.843942 -292.298701) (xy 161.889958 -292.281249)
			(xy 161.938177 -292.271405) (xy 161.987352 -292.269424) (xy 162.036207 -292.275356) (xy 162.083478 -292.289048)
			(xy 162.12794 -292.310146) (xy 162.168443 -292.338102) (xy 162.203936 -292.372194) (xy 162.233501 -292.411538)
			(xy 162.256372 -292.455115) (xy 162.271956 -292.501796) (xy 162.279851 -292.550373) (xy 162.280346 -292.57498)
			(xy 162.619194 -292.57498) (xy 162.623154 -292.525926) (xy 162.634931 -292.478142) (xy 162.654222 -292.432866)
			(xy 162.680525 -292.39127) (xy 162.71316 -292.354433) (xy 162.751281 -292.323308) (xy 162.793902 -292.298701)
			(xy 162.839918 -292.281249) (xy 162.888137 -292.271405) (xy 162.937312 -292.269424) (xy 162.986167 -292.275356)
			(xy 163.033438 -292.289048) (xy 163.0779 -292.310146) (xy 163.118403 -292.338102) (xy 163.153896 -292.372194)
			(xy 163.183461 -292.411538) (xy 163.206332 -292.455115) (xy 163.221916 -292.501796) (xy 163.229811 -292.550373)
			(xy 163.230306 -292.57498) (xy 163.569154 -292.57498) (xy 163.573114 -292.525926) (xy 163.584891 -292.478142)
			(xy 163.604182 -292.432866) (xy 163.630485 -292.39127) (xy 163.66312 -292.354433) (xy 163.701241 -292.323308)
			(xy 163.743862 -292.298701) (xy 163.789878 -292.281249) (xy 163.838097 -292.271405) (xy 163.887272 -292.269424)
			(xy 163.936127 -292.275356) (xy 163.983398 -292.289048) (xy 164.02786 -292.310146) (xy 164.068363 -292.338102)
			(xy 164.103856 -292.372194) (xy 164.133421 -292.411538) (xy 164.156292 -292.455115) (xy 164.171876 -292.501796)
			(xy 164.179771 -292.550373) (xy 164.180261 -292.574726) (xy 165.469074 -292.574726) (xy 165.473034 -292.525672)
			(xy 165.484811 -292.477888) (xy 165.504102 -292.432612) (xy 165.530405 -292.391016) (xy 165.56304 -292.354179)
			(xy 165.601161 -292.323054) (xy 165.643782 -292.298447) (xy 165.689798 -292.280995) (xy 165.738017 -292.271151)
			(xy 165.787192 -292.26917) (xy 165.836047 -292.275102) (xy 165.883318 -292.288794) (xy 165.92778 -292.309892)
			(xy 165.968283 -292.337848) (xy 166.003776 -292.37194) (xy 166.033341 -292.411284) (xy 166.056212 -292.454861)
			(xy 166.071796 -292.501542) (xy 166.079691 -292.550119) (xy 166.080186 -292.574726) (xy 166.080181 -292.57498)
			(xy 166.419288 -292.57498) (xy 166.423248 -292.525926) (xy 166.435025 -292.478142) (xy 166.454316 -292.432866)
			(xy 166.480619 -292.39127) (xy 166.513254 -292.354433) (xy 166.551375 -292.323308) (xy 166.593996 -292.298701)
			(xy 166.640012 -292.281249) (xy 166.688231 -292.271405) (xy 166.737406 -292.269424) (xy 166.786261 -292.275356)
			(xy 166.833532 -292.289048) (xy 166.877994 -292.310146) (xy 166.918497 -292.338102) (xy 166.95399 -292.372194)
			(xy 166.983555 -292.411538) (xy 167.006426 -292.455115) (xy 167.02201 -292.501796) (xy 167.029905 -292.550373)
			(xy 167.0304 -292.57498) (xy 167.369248 -292.57498) (xy 167.373208 -292.525926) (xy 167.384985 -292.478142)
			(xy 167.404276 -292.432866) (xy 167.430579 -292.39127) (xy 167.463214 -292.354433) (xy 167.501335 -292.323308)
			(xy 167.543956 -292.298701) (xy 167.589972 -292.281249) (xy 167.638191 -292.271405) (xy 167.687366 -292.269424)
			(xy 167.736221 -292.275356) (xy 167.783492 -292.289048) (xy 167.827954 -292.310146) (xy 167.868457 -292.338102)
			(xy 167.90395 -292.372194) (xy 167.933515 -292.411538) (xy 167.956386 -292.455115) (xy 167.97197 -292.501796)
			(xy 167.979865 -292.550373) (xy 167.98036 -292.57498) (xy 168.319208 -292.57498) (xy 168.323168 -292.525926)
			(xy 168.334945 -292.478142) (xy 168.354236 -292.432866) (xy 168.380539 -292.39127) (xy 168.413174 -292.354433)
			(xy 168.451295 -292.323308) (xy 168.493916 -292.298701) (xy 168.539932 -292.281249) (xy 168.588151 -292.271405)
			(xy 168.637326 -292.269424) (xy 168.686181 -292.275356) (xy 168.733452 -292.289048) (xy 168.777914 -292.310146)
			(xy 168.818417 -292.338102) (xy 168.85391 -292.372194) (xy 168.883475 -292.411538) (xy 168.906346 -292.455115)
			(xy 168.92193 -292.501796) (xy 168.929825 -292.550373) (xy 168.93032 -292.57498) (xy 169.269168 -292.57498)
			(xy 169.273128 -292.525926) (xy 169.284905 -292.478142) (xy 169.304196 -292.432866) (xy 169.330499 -292.39127)
			(xy 169.363134 -292.354433) (xy 169.401255 -292.323308) (xy 169.443876 -292.298701) (xy 169.489892 -292.281249)
			(xy 169.538111 -292.271405) (xy 169.587286 -292.269424) (xy 169.636141 -292.275356) (xy 169.683412 -292.289048)
			(xy 169.727874 -292.310146) (xy 169.768377 -292.338102) (xy 169.80387 -292.372194) (xy 169.833435 -292.411538)
			(xy 169.856306 -292.455115) (xy 169.87189 -292.501796) (xy 169.879785 -292.550373) (xy 169.88028 -292.57498)
			(xy 170.219128 -292.57498) (xy 170.223088 -292.525926) (xy 170.234865 -292.478142) (xy 170.254156 -292.432866)
			(xy 170.280459 -292.39127) (xy 170.313094 -292.354433) (xy 170.351215 -292.323308) (xy 170.393836 -292.298701)
			(xy 170.439852 -292.281249) (xy 170.488071 -292.271405) (xy 170.537246 -292.269424) (xy 170.586101 -292.275356)
			(xy 170.633372 -292.289048) (xy 170.677834 -292.310146) (xy 170.718337 -292.338102) (xy 170.75383 -292.372194)
			(xy 170.783395 -292.411538) (xy 170.806266 -292.455115) (xy 170.82185 -292.501796) (xy 170.829745 -292.550373)
			(xy 170.83024 -292.57498) (xy 171.169088 -292.57498) (xy 171.173048 -292.525926) (xy 171.184825 -292.478142)
			(xy 171.204116 -292.432866) (xy 171.230419 -292.39127) (xy 171.263054 -292.354433) (xy 171.301175 -292.323308)
			(xy 171.343796 -292.298701) (xy 171.389812 -292.281249) (xy 171.438031 -292.271405) (xy 171.487206 -292.269424)
			(xy 171.536061 -292.275356) (xy 171.583332 -292.289048) (xy 171.627794 -292.310146) (xy 171.668297 -292.338102)
			(xy 171.70379 -292.372194) (xy 171.733355 -292.411538) (xy 171.756226 -292.455115) (xy 171.77181 -292.501796)
			(xy 171.779705 -292.550373) (xy 171.7802 -292.57498) (xy 172.119302 -292.57498) (xy 172.123262 -292.525926)
			(xy 172.135039 -292.478142) (xy 172.15433 -292.432866) (xy 172.180633 -292.39127) (xy 172.213268 -292.354433)
			(xy 172.251389 -292.323308) (xy 172.29401 -292.298701) (xy 172.340026 -292.281249) (xy 172.388245 -292.271405)
			(xy 172.43742 -292.269424) (xy 172.486275 -292.275356) (xy 172.533546 -292.289048) (xy 172.578008 -292.310146)
			(xy 172.618511 -292.338102) (xy 172.654004 -292.372194) (xy 172.683569 -292.411538) (xy 172.70644 -292.455115)
			(xy 172.722024 -292.501796) (xy 172.729919 -292.550373) (xy 172.730414 -292.57498) (xy 173.069262 -292.57498)
			(xy 173.073222 -292.525926) (xy 173.084999 -292.478142) (xy 173.10429 -292.432866) (xy 173.130593 -292.39127)
			(xy 173.163228 -292.354433) (xy 173.201349 -292.323308) (xy 173.24397 -292.298701) (xy 173.289986 -292.281249)
			(xy 173.338205 -292.271405) (xy 173.38738 -292.269424) (xy 173.436235 -292.275356) (xy 173.483506 -292.289048)
			(xy 173.527968 -292.310146) (xy 173.568471 -292.338102) (xy 173.603964 -292.372194) (xy 173.633529 -292.411538)
			(xy 173.6564 -292.455115) (xy 173.671984 -292.501796) (xy 173.679879 -292.550373) (xy 173.680374 -292.57498)
			(xy 174.019222 -292.57498) (xy 174.023182 -292.525926) (xy 174.034959 -292.478142) (xy 174.05425 -292.432866)
			(xy 174.080553 -292.39127) (xy 174.113188 -292.354433) (xy 174.151309 -292.323308) (xy 174.19393 -292.298701)
			(xy 174.239946 -292.281249) (xy 174.288165 -292.271405) (xy 174.33734 -292.269424) (xy 174.386195 -292.275356)
			(xy 174.433466 -292.289048) (xy 174.477928 -292.310146) (xy 174.518431 -292.338102) (xy 174.553924 -292.372194)
			(xy 174.583489 -292.411538) (xy 174.60636 -292.455115) (xy 174.621944 -292.501796) (xy 174.629839 -292.550373)
			(xy 174.630329 -292.574726) (xy 175.919142 -292.574726) (xy 175.923102 -292.525672) (xy 175.934879 -292.477888)
			(xy 175.95417 -292.432612) (xy 175.980473 -292.391016) (xy 176.013108 -292.354179) (xy 176.051229 -292.323054)
			(xy 176.09385 -292.298447) (xy 176.139866 -292.280995) (xy 176.188085 -292.271151) (xy 176.23726 -292.26917)
			(xy 176.286115 -292.275102) (xy 176.333386 -292.288794) (xy 176.377848 -292.309892) (xy 176.418351 -292.337848)
			(xy 176.453844 -292.37194) (xy 176.483409 -292.411284) (xy 176.50628 -292.454861) (xy 176.521864 -292.501542)
			(xy 176.529759 -292.550119) (xy 176.530254 -292.574726) (xy 176.869102 -292.574726) (xy 176.873062 -292.525672)
			(xy 176.884839 -292.477888) (xy 176.90413 -292.432612) (xy 176.930433 -292.391016) (xy 176.963068 -292.354179)
			(xy 177.001189 -292.323054) (xy 177.04381 -292.298447) (xy 177.089826 -292.280995) (xy 177.138045 -292.271151)
			(xy 177.18722 -292.26917) (xy 177.236075 -292.275102) (xy 177.283346 -292.288794) (xy 177.327808 -292.309892)
			(xy 177.368311 -292.337848) (xy 177.403804 -292.37194) (xy 177.433369 -292.411284) (xy 177.45624 -292.454861)
			(xy 177.471824 -292.501542) (xy 177.479719 -292.550119) (xy 177.480214 -292.574726) (xy 177.819062 -292.574726)
			(xy 177.823022 -292.525672) (xy 177.834799 -292.477888) (xy 177.85409 -292.432612) (xy 177.880393 -292.391016)
			(xy 177.913028 -292.354179) (xy 177.951149 -292.323054) (xy 177.99377 -292.298447) (xy 178.039786 -292.280995)
			(xy 178.088005 -292.271151) (xy 178.13718 -292.26917) (xy 178.186035 -292.275102) (xy 178.233306 -292.288794)
			(xy 178.277768 -292.309892) (xy 178.318271 -292.337848) (xy 178.353764 -292.37194) (xy 178.383329 -292.411284)
			(xy 178.4062 -292.454861) (xy 178.421784 -292.501542) (xy 178.429679 -292.550119) (xy 178.430174 -292.574726)
			(xy 178.769276 -292.574726) (xy 178.773236 -292.525672) (xy 178.785013 -292.477888) (xy 178.804304 -292.432612)
			(xy 178.830607 -292.391016) (xy 178.863242 -292.354179) (xy 178.901363 -292.323054) (xy 178.943984 -292.298447)
			(xy 178.99 -292.280995) (xy 179.038219 -292.271151) (xy 179.087394 -292.26917) (xy 179.136249 -292.275102)
			(xy 179.18352 -292.288794) (xy 179.227982 -292.309892) (xy 179.268485 -292.337848) (xy 179.303978 -292.37194)
			(xy 179.333543 -292.411284) (xy 179.356414 -292.454861) (xy 179.371998 -292.501542) (xy 179.379893 -292.550119)
			(xy 179.380388 -292.574726) (xy 179.719236 -292.574726) (xy 179.723196 -292.525672) (xy 179.734973 -292.477888)
			(xy 179.754264 -292.432612) (xy 179.780567 -292.391016) (xy 179.813202 -292.354179) (xy 179.851323 -292.323054)
			(xy 179.893944 -292.298447) (xy 179.93996 -292.280995) (xy 179.988179 -292.271151) (xy 180.037354 -292.26917)
			(xy 180.086209 -292.275102) (xy 180.13348 -292.288794) (xy 180.177942 -292.309892) (xy 180.218445 -292.337848)
			(xy 180.253938 -292.37194) (xy 180.283503 -292.411284) (xy 180.306374 -292.454861) (xy 180.321958 -292.501542)
			(xy 180.329853 -292.550119) (xy 180.330348 -292.574726) (xy 180.669196 -292.574726) (xy 180.673156 -292.525672)
			(xy 180.684933 -292.477888) (xy 180.704224 -292.432612) (xy 180.730527 -292.391016) (xy 180.763162 -292.354179)
			(xy 180.801283 -292.323054) (xy 180.843904 -292.298447) (xy 180.88992 -292.280995) (xy 180.938139 -292.271151)
			(xy 180.987314 -292.26917) (xy 181.036169 -292.275102) (xy 181.08344 -292.288794) (xy 181.127902 -292.309892)
			(xy 181.168405 -292.337848) (xy 181.203898 -292.37194) (xy 181.233463 -292.411284) (xy 181.256334 -292.454861)
			(xy 181.271918 -292.501542) (xy 181.279813 -292.550119) (xy 181.280308 -292.574726) (xy 181.619156 -292.574726)
			(xy 181.623116 -292.525672) (xy 181.634893 -292.477888) (xy 181.654184 -292.432612) (xy 181.680487 -292.391016)
			(xy 181.713122 -292.354179) (xy 181.751243 -292.323054) (xy 181.793864 -292.298447) (xy 181.83988 -292.280995)
			(xy 181.888099 -292.271151) (xy 181.937274 -292.26917) (xy 181.986129 -292.275102) (xy 182.0334 -292.288794)
			(xy 182.077862 -292.309892) (xy 182.118365 -292.337848) (xy 182.153858 -292.37194) (xy 182.183423 -292.411284)
			(xy 182.206294 -292.454861) (xy 182.221878 -292.501542) (xy 182.229773 -292.550119) (xy 182.230268 -292.574726)
			(xy 182.569116 -292.574726) (xy 182.573076 -292.525672) (xy 182.584853 -292.477888) (xy 182.604144 -292.432612)
			(xy 182.630447 -292.391016) (xy 182.663082 -292.354179) (xy 182.701203 -292.323054) (xy 182.743824 -292.298447)
			(xy 182.78984 -292.280995) (xy 182.838059 -292.271151) (xy 182.887234 -292.26917) (xy 182.936089 -292.275102)
			(xy 182.98336 -292.288794) (xy 183.027822 -292.309892) (xy 183.068325 -292.337848) (xy 183.103818 -292.37194)
			(xy 183.133383 -292.411284) (xy 183.156254 -292.454861) (xy 183.171838 -292.501542) (xy 183.179733 -292.550119)
			(xy 183.180228 -292.574726) (xy 183.519076 -292.574726) (xy 183.523036 -292.525672) (xy 183.534813 -292.477888)
			(xy 183.554104 -292.432612) (xy 183.580407 -292.391016) (xy 183.613042 -292.354179) (xy 183.651163 -292.323054)
			(xy 183.693784 -292.298447) (xy 183.7398 -292.280995) (xy 183.788019 -292.271151) (xy 183.837194 -292.26917)
			(xy 183.886049 -292.275102) (xy 183.93332 -292.288794) (xy 183.977782 -292.309892) (xy 184.018285 -292.337848)
			(xy 184.053778 -292.37194) (xy 184.083343 -292.411284) (xy 184.106214 -292.454861) (xy 184.121798 -292.501542)
			(xy 184.129693 -292.550119) (xy 184.130188 -292.574726) (xy 184.129693 -292.599333) (xy 184.121798 -292.64791)
			(xy 184.106214 -292.694591) (xy 184.083343 -292.738168) (xy 184.053778 -292.777512) (xy 184.018285 -292.811604)
			(xy 183.977782 -292.83956) (xy 183.93332 -292.860658) (xy 183.886049 -292.87435) (xy 183.837194 -292.880282)
			(xy 183.788019 -292.878301) (xy 183.7398 -292.868457) (xy 183.693784 -292.851005) (xy 183.651163 -292.826398)
			(xy 183.613042 -292.795273) (xy 183.580407 -292.758436) (xy 183.554104 -292.71684) (xy 183.534813 -292.671564)
			(xy 183.523036 -292.62378) (xy 183.519076 -292.574726) (xy 183.180228 -292.574726) (xy 183.179733 -292.599333)
			(xy 183.171838 -292.64791) (xy 183.156254 -292.694591) (xy 183.133383 -292.738168) (xy 183.103818 -292.777512)
			(xy 183.068325 -292.811604) (xy 183.027822 -292.83956) (xy 182.98336 -292.860658) (xy 182.936089 -292.87435)
			(xy 182.887234 -292.880282) (xy 182.838059 -292.878301) (xy 182.78984 -292.868457) (xy 182.743824 -292.851005)
			(xy 182.701203 -292.826398) (xy 182.663082 -292.795273) (xy 182.630447 -292.758436) (xy 182.604144 -292.71684)
			(xy 182.584853 -292.671564) (xy 182.573076 -292.62378) (xy 182.569116 -292.574726) (xy 182.230268 -292.574726)
			(xy 182.229773 -292.599333) (xy 182.221878 -292.64791) (xy 182.206294 -292.694591) (xy 182.183423 -292.738168)
			(xy 182.153858 -292.777512) (xy 182.118365 -292.811604) (xy 182.077862 -292.83956) (xy 182.0334 -292.860658)
			(xy 181.986129 -292.87435) (xy 181.937274 -292.880282) (xy 181.888099 -292.878301) (xy 181.83988 -292.868457)
			(xy 181.793864 -292.851005) (xy 181.751243 -292.826398) (xy 181.713122 -292.795273) (xy 181.680487 -292.758436)
			(xy 181.654184 -292.71684) (xy 181.634893 -292.671564) (xy 181.623116 -292.62378) (xy 181.619156 -292.574726)
			(xy 181.280308 -292.574726) (xy 181.279813 -292.599333) (xy 181.271918 -292.64791) (xy 181.256334 -292.694591)
			(xy 181.233463 -292.738168) (xy 181.203898 -292.777512) (xy 181.168405 -292.811604) (xy 181.127902 -292.83956)
			(xy 181.08344 -292.860658) (xy 181.036169 -292.87435) (xy 180.987314 -292.880282) (xy 180.938139 -292.878301)
			(xy 180.88992 -292.868457) (xy 180.843904 -292.851005) (xy 180.801283 -292.826398) (xy 180.763162 -292.795273)
			(xy 180.730527 -292.758436) (xy 180.704224 -292.71684) (xy 180.684933 -292.671564) (xy 180.673156 -292.62378)
			(xy 180.669196 -292.574726) (xy 180.330348 -292.574726) (xy 180.329853 -292.599333) (xy 180.321958 -292.64791)
			(xy 180.306374 -292.694591) (xy 180.283503 -292.738168) (xy 180.253938 -292.777512) (xy 180.218445 -292.811604)
			(xy 180.177942 -292.83956) (xy 180.13348 -292.860658) (xy 180.086209 -292.87435) (xy 180.037354 -292.880282)
			(xy 179.988179 -292.878301) (xy 179.93996 -292.868457) (xy 179.893944 -292.851005) (xy 179.851323 -292.826398)
			(xy 179.813202 -292.795273) (xy 179.780567 -292.758436) (xy 179.754264 -292.71684) (xy 179.734973 -292.671564)
			(xy 179.723196 -292.62378) (xy 179.719236 -292.574726) (xy 179.380388 -292.574726) (xy 179.379893 -292.599333)
			(xy 179.371998 -292.64791) (xy 179.356414 -292.694591) (xy 179.333543 -292.738168) (xy 179.303978 -292.777512)
			(xy 179.268485 -292.811604) (xy 179.227982 -292.83956) (xy 179.18352 -292.860658) (xy 179.136249 -292.87435)
			(xy 179.087394 -292.880282) (xy 179.038219 -292.878301) (xy 178.99 -292.868457) (xy 178.943984 -292.851005)
			(xy 178.901363 -292.826398) (xy 178.863242 -292.795273) (xy 178.830607 -292.758436) (xy 178.804304 -292.71684)
			(xy 178.785013 -292.671564) (xy 178.773236 -292.62378) (xy 178.769276 -292.574726) (xy 178.430174 -292.574726)
			(xy 178.429679 -292.599333) (xy 178.421784 -292.64791) (xy 178.4062 -292.694591) (xy 178.383329 -292.738168)
			(xy 178.353764 -292.777512) (xy 178.318271 -292.811604) (xy 178.277768 -292.83956) (xy 178.233306 -292.860658)
			(xy 178.186035 -292.87435) (xy 178.13718 -292.880282) (xy 178.088005 -292.878301) (xy 178.039786 -292.868457)
			(xy 177.99377 -292.851005) (xy 177.951149 -292.826398) (xy 177.913028 -292.795273) (xy 177.880393 -292.758436)
			(xy 177.85409 -292.71684) (xy 177.834799 -292.671564) (xy 177.823022 -292.62378) (xy 177.819062 -292.574726)
			(xy 177.480214 -292.574726) (xy 177.479719 -292.599333) (xy 177.471824 -292.64791) (xy 177.45624 -292.694591)
			(xy 177.433369 -292.738168) (xy 177.403804 -292.777512) (xy 177.368311 -292.811604) (xy 177.327808 -292.83956)
			(xy 177.283346 -292.860658) (xy 177.236075 -292.87435) (xy 177.18722 -292.880282) (xy 177.138045 -292.878301)
			(xy 177.089826 -292.868457) (xy 177.04381 -292.851005) (xy 177.001189 -292.826398) (xy 176.963068 -292.795273)
			(xy 176.930433 -292.758436) (xy 176.90413 -292.71684) (xy 176.884839 -292.671564) (xy 176.873062 -292.62378)
			(xy 176.869102 -292.574726) (xy 176.530254 -292.574726) (xy 176.529759 -292.599333) (xy 176.521864 -292.64791)
			(xy 176.50628 -292.694591) (xy 176.483409 -292.738168) (xy 176.453844 -292.777512) (xy 176.418351 -292.811604)
			(xy 176.377848 -292.83956) (xy 176.333386 -292.860658) (xy 176.286115 -292.87435) (xy 176.23726 -292.880282)
			(xy 176.188085 -292.878301) (xy 176.139866 -292.868457) (xy 176.09385 -292.851005) (xy 176.051229 -292.826398)
			(xy 176.013108 -292.795273) (xy 175.980473 -292.758436) (xy 175.95417 -292.71684) (xy 175.934879 -292.671564)
			(xy 175.923102 -292.62378) (xy 175.919142 -292.574726) (xy 174.630329 -292.574726) (xy 174.630334 -292.57498)
			(xy 174.629839 -292.599587) (xy 174.621944 -292.648164) (xy 174.60636 -292.694845) (xy 174.583489 -292.738422)
			(xy 174.553924 -292.777766) (xy 174.518431 -292.811858) (xy 174.477928 -292.839814) (xy 174.433466 -292.860912)
			(xy 174.386195 -292.874604) (xy 174.33734 -292.880536) (xy 174.288165 -292.878555) (xy 174.239946 -292.868711)
			(xy 174.19393 -292.851259) (xy 174.151309 -292.826652) (xy 174.113188 -292.795527) (xy 174.080553 -292.75869)
			(xy 174.05425 -292.717094) (xy 174.034959 -292.671818) (xy 174.023182 -292.624034) (xy 174.019222 -292.57498)
			(xy 173.680374 -292.57498) (xy 173.679879 -292.599587) (xy 173.671984 -292.648164) (xy 173.6564 -292.694845)
			(xy 173.633529 -292.738422) (xy 173.603964 -292.777766) (xy 173.568471 -292.811858) (xy 173.527968 -292.839814)
			(xy 173.483506 -292.860912) (xy 173.436235 -292.874604) (xy 173.38738 -292.880536) (xy 173.338205 -292.878555)
			(xy 173.289986 -292.868711) (xy 173.24397 -292.851259) (xy 173.201349 -292.826652) (xy 173.163228 -292.795527)
			(xy 173.130593 -292.75869) (xy 173.10429 -292.717094) (xy 173.084999 -292.671818) (xy 173.073222 -292.624034)
			(xy 173.069262 -292.57498) (xy 172.730414 -292.57498) (xy 172.729919 -292.599587) (xy 172.722024 -292.648164)
			(xy 172.70644 -292.694845) (xy 172.683569 -292.738422) (xy 172.654004 -292.777766) (xy 172.618511 -292.811858)
			(xy 172.578008 -292.839814) (xy 172.533546 -292.860912) (xy 172.486275 -292.874604) (xy 172.43742 -292.880536)
			(xy 172.388245 -292.878555) (xy 172.340026 -292.868711) (xy 172.29401 -292.851259) (xy 172.251389 -292.826652)
			(xy 172.213268 -292.795527) (xy 172.180633 -292.75869) (xy 172.15433 -292.717094) (xy 172.135039 -292.671818)
			(xy 172.123262 -292.624034) (xy 172.119302 -292.57498) (xy 171.7802 -292.57498) (xy 171.779705 -292.599587)
			(xy 171.77181 -292.648164) (xy 171.756226 -292.694845) (xy 171.733355 -292.738422) (xy 171.70379 -292.777766)
			(xy 171.668297 -292.811858) (xy 171.627794 -292.839814) (xy 171.583332 -292.860912) (xy 171.536061 -292.874604)
			(xy 171.487206 -292.880536) (xy 171.438031 -292.878555) (xy 171.389812 -292.868711) (xy 171.343796 -292.851259)
			(xy 171.301175 -292.826652) (xy 171.263054 -292.795527) (xy 171.230419 -292.75869) (xy 171.204116 -292.717094)
			(xy 171.184825 -292.671818) (xy 171.173048 -292.624034) (xy 171.169088 -292.57498) (xy 170.83024 -292.57498)
			(xy 170.829745 -292.599587) (xy 170.82185 -292.648164) (xy 170.806266 -292.694845) (xy 170.783395 -292.738422)
			(xy 170.75383 -292.777766) (xy 170.718337 -292.811858) (xy 170.677834 -292.839814) (xy 170.633372 -292.860912)
			(xy 170.586101 -292.874604) (xy 170.537246 -292.880536) (xy 170.488071 -292.878555) (xy 170.439852 -292.868711)
			(xy 170.393836 -292.851259) (xy 170.351215 -292.826652) (xy 170.313094 -292.795527) (xy 170.280459 -292.75869)
			(xy 170.254156 -292.717094) (xy 170.234865 -292.671818) (xy 170.223088 -292.624034) (xy 170.219128 -292.57498)
			(xy 169.88028 -292.57498) (xy 169.879785 -292.599587) (xy 169.87189 -292.648164) (xy 169.856306 -292.694845)
			(xy 169.833435 -292.738422) (xy 169.80387 -292.777766) (xy 169.768377 -292.811858) (xy 169.727874 -292.839814)
			(xy 169.683412 -292.860912) (xy 169.636141 -292.874604) (xy 169.587286 -292.880536) (xy 169.538111 -292.878555)
			(xy 169.489892 -292.868711) (xy 169.443876 -292.851259) (xy 169.401255 -292.826652) (xy 169.363134 -292.795527)
			(xy 169.330499 -292.75869) (xy 169.304196 -292.717094) (xy 169.284905 -292.671818) (xy 169.273128 -292.624034)
			(xy 169.269168 -292.57498) (xy 168.93032 -292.57498) (xy 168.929825 -292.599587) (xy 168.92193 -292.648164)
			(xy 168.906346 -292.694845) (xy 168.883475 -292.738422) (xy 168.85391 -292.777766) (xy 168.818417 -292.811858)
			(xy 168.777914 -292.839814) (xy 168.733452 -292.860912) (xy 168.686181 -292.874604) (xy 168.637326 -292.880536)
			(xy 168.588151 -292.878555) (xy 168.539932 -292.868711) (xy 168.493916 -292.851259) (xy 168.451295 -292.826652)
			(xy 168.413174 -292.795527) (xy 168.380539 -292.75869) (xy 168.354236 -292.717094) (xy 168.334945 -292.671818)
			(xy 168.323168 -292.624034) (xy 168.319208 -292.57498) (xy 167.98036 -292.57498) (xy 167.979865 -292.599587)
			(xy 167.97197 -292.648164) (xy 167.956386 -292.694845) (xy 167.933515 -292.738422) (xy 167.90395 -292.777766)
			(xy 167.868457 -292.811858) (xy 167.827954 -292.839814) (xy 167.783492 -292.860912) (xy 167.736221 -292.874604)
			(xy 167.687366 -292.880536) (xy 167.638191 -292.878555) (xy 167.589972 -292.868711) (xy 167.543956 -292.851259)
			(xy 167.501335 -292.826652) (xy 167.463214 -292.795527) (xy 167.430579 -292.75869) (xy 167.404276 -292.717094)
			(xy 167.384985 -292.671818) (xy 167.373208 -292.624034) (xy 167.369248 -292.57498) (xy 167.0304 -292.57498)
			(xy 167.029905 -292.599587) (xy 167.02201 -292.648164) (xy 167.006426 -292.694845) (xy 166.983555 -292.738422)
			(xy 166.95399 -292.777766) (xy 166.918497 -292.811858) (xy 166.877994 -292.839814) (xy 166.833532 -292.860912)
			(xy 166.786261 -292.874604) (xy 166.737406 -292.880536) (xy 166.688231 -292.878555) (xy 166.640012 -292.868711)
			(xy 166.593996 -292.851259) (xy 166.551375 -292.826652) (xy 166.513254 -292.795527) (xy 166.480619 -292.75869)
			(xy 166.454316 -292.717094) (xy 166.435025 -292.671818) (xy 166.423248 -292.624034) (xy 166.419288 -292.57498)
			(xy 166.080181 -292.57498) (xy 166.079691 -292.599333) (xy 166.071796 -292.64791) (xy 166.056212 -292.694591)
			(xy 166.033341 -292.738168) (xy 166.003776 -292.777512) (xy 165.968283 -292.811604) (xy 165.92778 -292.83956)
			(xy 165.883318 -292.860658) (xy 165.836047 -292.87435) (xy 165.787192 -292.880282) (xy 165.738017 -292.878301)
			(xy 165.689798 -292.868457) (xy 165.643782 -292.851005) (xy 165.601161 -292.826398) (xy 165.56304 -292.795273)
			(xy 165.530405 -292.758436) (xy 165.504102 -292.71684) (xy 165.484811 -292.671564) (xy 165.473034 -292.62378)
			(xy 165.469074 -292.574726) (xy 164.180261 -292.574726) (xy 164.180266 -292.57498) (xy 164.179771 -292.599587)
			(xy 164.171876 -292.648164) (xy 164.156292 -292.694845) (xy 164.133421 -292.738422) (xy 164.103856 -292.777766)
			(xy 164.068363 -292.811858) (xy 164.02786 -292.839814) (xy 163.983398 -292.860912) (xy 163.936127 -292.874604)
			(xy 163.887272 -292.880536) (xy 163.838097 -292.878555) (xy 163.789878 -292.868711) (xy 163.743862 -292.851259)
			(xy 163.701241 -292.826652) (xy 163.66312 -292.795527) (xy 163.630485 -292.75869) (xy 163.604182 -292.717094)
			(xy 163.584891 -292.671818) (xy 163.573114 -292.624034) (xy 163.569154 -292.57498) (xy 163.230306 -292.57498)
			(xy 163.229811 -292.599587) (xy 163.221916 -292.648164) (xy 163.206332 -292.694845) (xy 163.183461 -292.738422)
			(xy 163.153896 -292.777766) (xy 163.118403 -292.811858) (xy 163.0779 -292.839814) (xy 163.033438 -292.860912)
			(xy 162.986167 -292.874604) (xy 162.937312 -292.880536) (xy 162.888137 -292.878555) (xy 162.839918 -292.868711)
			(xy 162.793902 -292.851259) (xy 162.751281 -292.826652) (xy 162.71316 -292.795527) (xy 162.680525 -292.75869)
			(xy 162.654222 -292.717094) (xy 162.634931 -292.671818) (xy 162.623154 -292.624034) (xy 162.619194 -292.57498)
			(xy 162.280346 -292.57498) (xy 162.279851 -292.599587) (xy 162.271956 -292.648164) (xy 162.256372 -292.694845)
			(xy 162.233501 -292.738422) (xy 162.203936 -292.777766) (xy 162.168443 -292.811858) (xy 162.12794 -292.839814)
			(xy 162.083478 -292.860912) (xy 162.036207 -292.874604) (xy 161.987352 -292.880536) (xy 161.938177 -292.878555)
			(xy 161.889958 -292.868711) (xy 161.843942 -292.851259) (xy 161.801321 -292.826652) (xy 161.7632 -292.795527)
			(xy 161.730565 -292.75869) (xy 161.704262 -292.717094) (xy 161.684971 -292.671818) (xy 161.673194 -292.624034)
			(xy 161.669234 -292.57498) (xy 161.330386 -292.57498) (xy 161.329891 -292.599587) (xy 161.321996 -292.648164)
			(xy 161.306412 -292.694845) (xy 161.283541 -292.738422) (xy 161.253976 -292.777766) (xy 161.218483 -292.811858)
			(xy 161.17798 -292.839814) (xy 161.133518 -292.860912) (xy 161.086247 -292.874604) (xy 161.037392 -292.880536)
			(xy 160.988217 -292.878555) (xy 160.939998 -292.868711) (xy 160.893982 -292.851259) (xy 160.851361 -292.826652)
			(xy 160.81324 -292.795527) (xy 160.780605 -292.75869) (xy 160.754302 -292.717094) (xy 160.735011 -292.671818)
			(xy 160.723234 -292.624034) (xy 160.719274 -292.57498) (xy 160.380172 -292.57498) (xy 160.379677 -292.599587)
			(xy 160.371782 -292.648164) (xy 160.356198 -292.694845) (xy 160.333327 -292.738422) (xy 160.303762 -292.777766)
			(xy 160.268269 -292.811858) (xy 160.227766 -292.839814) (xy 160.183304 -292.860912) (xy 160.136033 -292.874604)
			(xy 160.087178 -292.880536) (xy 160.038003 -292.878555) (xy 159.989784 -292.868711) (xy 159.943768 -292.851259)
			(xy 159.901147 -292.826652) (xy 159.863026 -292.795527) (xy 159.830391 -292.75869) (xy 159.804088 -292.717094)
			(xy 159.784797 -292.671818) (xy 159.77302 -292.624034) (xy 159.76906 -292.57498) (xy 159.430212 -292.57498)
			(xy 159.429717 -292.599587) (xy 159.421822 -292.648164) (xy 159.406238 -292.694845) (xy 159.383367 -292.738422)
			(xy 159.353802 -292.777766) (xy 159.318309 -292.811858) (xy 159.277806 -292.839814) (xy 159.233344 -292.860912)
			(xy 159.186073 -292.874604) (xy 159.137218 -292.880536) (xy 159.088043 -292.878555) (xy 159.039824 -292.868711)
			(xy 158.993808 -292.851259) (xy 158.951187 -292.826652) (xy 158.913066 -292.795527) (xy 158.880431 -292.75869)
			(xy 158.854128 -292.717094) (xy 158.834837 -292.671818) (xy 158.82306 -292.624034) (xy 158.8191 -292.57498)
			(xy 158.531052 -292.57498) (xy 158.530554 -292.601629) (xy 158.522611 -292.654333) (xy 158.506901 -292.705263)
			(xy 158.483775 -292.753284) (xy 158.453751 -292.797321) (xy 158.417499 -292.836392) (xy 158.375828 -292.869623)
			(xy 158.32967 -292.896272) (xy 158.280056 -292.915744) (xy 158.228094 -292.927604) (xy 158.174944 -292.931588)
			(xy 158.121794 -292.927604) (xy 158.069832 -292.915744) (xy 158.020218 -292.896272) (xy 157.97406 -292.869623)
			(xy 157.932389 -292.836392) (xy 157.896137 -292.797321) (xy 157.866113 -292.753284) (xy 157.842987 -292.705263)
			(xy 157.827277 -292.654333) (xy 157.819334 -292.601629) (xy 157.529465 -292.601629) (xy 157.521902 -292.648164)
			(xy 157.506318 -292.694845) (xy 157.483447 -292.738422) (xy 157.453882 -292.777766) (xy 157.418389 -292.811858)
			(xy 157.377886 -292.839814) (xy 157.333424 -292.860912) (xy 157.286153 -292.874604) (xy 157.237298 -292.880536)
			(xy 157.188123 -292.878555) (xy 157.139904 -292.868711) (xy 157.093888 -292.851259) (xy 157.051267 -292.826652)
			(xy 157.013146 -292.795527) (xy 156.980511 -292.75869) (xy 156.954208 -292.717094) (xy 156.934917 -292.671818)
			(xy 156.92314 -292.624034) (xy 156.91918 -292.57498) (xy 156.580327 -292.57498) (xy 156.579837 -292.599333)
			(xy 156.571942 -292.64791) (xy 156.556358 -292.694591) (xy 156.533487 -292.738168) (xy 156.503922 -292.777512)
			(xy 156.468429 -292.811604) (xy 156.427926 -292.83956) (xy 156.383464 -292.860658) (xy 156.336193 -292.87435)
			(xy 156.287338 -292.880282) (xy 156.238163 -292.878301) (xy 156.189944 -292.868457) (xy 156.143928 -292.851005)
			(xy 156.101307 -292.826398) (xy 156.063186 -292.795273) (xy 156.030551 -292.758436) (xy 156.004248 -292.71684)
			(xy 155.984957 -292.671564) (xy 155.97318 -292.62378) (xy 155.96922 -292.574726) (xy 155.630372 -292.574726)
			(xy 155.629877 -292.599333) (xy 155.621982 -292.64791) (xy 155.606398 -292.694591) (xy 155.583527 -292.738168)
			(xy 155.553962 -292.777512) (xy 155.518469 -292.811604) (xy 155.477966 -292.83956) (xy 155.433504 -292.860658)
			(xy 155.386233 -292.87435) (xy 155.337378 -292.880282) (xy 155.288203 -292.878301) (xy 155.239984 -292.868457)
			(xy 155.193968 -292.851005) (xy 155.151347 -292.826398) (xy 155.113226 -292.795273) (xy 155.080591 -292.758436)
			(xy 155.054288 -292.71684) (xy 155.034997 -292.671564) (xy 155.02322 -292.62378) (xy 155.01926 -292.574726)
			(xy 154.680407 -292.574726) (xy 154.680412 -292.57498) (xy 154.679917 -292.599587) (xy 154.672022 -292.648164)
			(xy 154.656438 -292.694845) (xy 154.633567 -292.738422) (xy 154.604002 -292.777766) (xy 154.568509 -292.811858)
			(xy 154.528006 -292.839814) (xy 154.483544 -292.860912) (xy 154.436273 -292.874604) (xy 154.387418 -292.880536)
			(xy 154.338243 -292.878555) (xy 154.290024 -292.868711) (xy 154.244008 -292.851259) (xy 154.201387 -292.826652)
			(xy 154.163266 -292.795527) (xy 154.130631 -292.75869) (xy 154.104328 -292.717094) (xy 154.085037 -292.671818)
			(xy 154.07326 -292.624034) (xy 154.0693 -292.57498) (xy 153.730198 -292.57498) (xy 153.729703 -292.599587)
			(xy 153.721808 -292.648164) (xy 153.706224 -292.694845) (xy 153.683353 -292.738422) (xy 153.653788 -292.777766)
			(xy 153.618295 -292.811858) (xy 153.577792 -292.839814) (xy 153.53333 -292.860912) (xy 153.486059 -292.874604)
			(xy 153.437204 -292.880536) (xy 153.388029 -292.878555) (xy 153.33981 -292.868711) (xy 153.293794 -292.851259)
			(xy 153.251173 -292.826652) (xy 153.213052 -292.795527) (xy 153.180417 -292.75869) (xy 153.154114 -292.717094)
			(xy 153.134823 -292.671818) (xy 153.123046 -292.624034) (xy 153.119086 -292.57498) (xy 152.780238 -292.57498)
			(xy 152.779743 -292.599587) (xy 152.771848 -292.648164) (xy 152.756264 -292.694845) (xy 152.733393 -292.738422)
			(xy 152.703828 -292.777766) (xy 152.668335 -292.811858) (xy 152.627832 -292.839814) (xy 152.58337 -292.860912)
			(xy 152.536099 -292.874604) (xy 152.487244 -292.880536) (xy 152.438069 -292.878555) (xy 152.38985 -292.868711)
			(xy 152.343834 -292.851259) (xy 152.301213 -292.826652) (xy 152.263092 -292.795527) (xy 152.230457 -292.75869)
			(xy 152.204154 -292.717094) (xy 152.184863 -292.671818) (xy 152.173086 -292.624034) (xy 152.169126 -292.57498)
			(xy 148.177889 -292.57498) (xy 148.188959 -292.59922) (xy 148.204314 -292.651515) (xy 148.21207 -292.705463)
			(xy 148.212556 -292.732714) (xy 148.212006 -292.762096) (xy 148.202975 -292.820161) (xy 148.185143 -292.876154)
			(xy 148.158933 -292.928749) (xy 148.124966 -292.976701) (xy 148.084044 -293.018874) (xy 148.060918 -293.037006)
			(xy 148.051975 -293.044467) (xy 148.041527 -293.065256) (xy 148.040852 -293.076884) (xy 148.039582 -293.168832)
			(xy 148.049488 -293.189914) (xy 148.058632 -293.19728) (xy 148.080459 -293.215509) (xy 148.118999 -293.257324)
			(xy 148.150908 -293.304395) (xy 148.175478 -293.35568) (xy 148.192166 -293.410043) (xy 148.200603 -293.466281)
			(xy 148.201126 -293.494714) (xy 148.8346 -293.494714) (xy 148.838671 -293.439092) (xy 148.850797 -293.384655)
			(xy 148.87072 -293.332564) (xy 148.898016 -293.283929) (xy 148.932102 -293.239786) (xy 148.972251 -293.201077)
			(xy 149.017609 -293.168626) (xy 149.067209 -293.143125) (xy 149.119993 -293.125118) (xy 149.174836 -293.114988)
			(xy 149.23057 -293.112951) (xy 149.286007 -293.119051) (xy 149.339964 -293.133157) (xy 149.391293 -293.154969)
			(xy 149.438899 -293.184023) (xy 149.481767 -293.219698) (xy 149.518984 -293.261235) (xy 149.549757 -293.307748)
			(xy 149.573429 -293.358245) (xy 149.589497 -293.411652) (xy 149.597617 -293.466828) (xy 149.598126 -293.494714)
			(xy 149.72106 -293.494714) (xy 149.725131 -293.439092) (xy 149.737257 -293.384655) (xy 149.75718 -293.332564)
			(xy 149.784476 -293.283929) (xy 149.818562 -293.239786) (xy 149.858711 -293.201077) (xy 149.904069 -293.168626)
			(xy 149.953669 -293.143125) (xy 150.006453 -293.125118) (xy 150.061296 -293.114988) (xy 150.11703 -293.112951)
			(xy 150.172467 -293.119051) (xy 150.226424 -293.133157) (xy 150.277753 -293.154969) (xy 150.325359 -293.184023)
			(xy 150.368227 -293.219698) (xy 150.405444 -293.261235) (xy 150.436217 -293.307748) (xy 150.459889 -293.358245)
			(xy 150.475957 -293.411652) (xy 150.484077 -293.466828) (xy 150.484586 -293.494714) (xy 150.484077 -293.5226)
			(xy 150.483733 -293.52494) (xy 154.0693 -293.52494) (xy 154.07326 -293.475886) (xy 154.085037 -293.428102)
			(xy 154.104328 -293.382826) (xy 154.130631 -293.34123) (xy 154.163266 -293.304393) (xy 154.201387 -293.273268)
			(xy 154.244008 -293.248661) (xy 154.290024 -293.231209) (xy 154.338243 -293.221365) (xy 154.387418 -293.219384)
			(xy 154.436273 -293.225316) (xy 154.483544 -293.239008) (xy 154.528006 -293.260106) (xy 154.568509 -293.288062)
			(xy 154.604002 -293.322154) (xy 154.633567 -293.361498) (xy 154.656438 -293.405075) (xy 154.672022 -293.451756)
			(xy 154.679917 -293.500333) (xy 154.680412 -293.52494) (xy 155.01926 -293.52494) (xy 155.02322 -293.475886)
			(xy 155.034997 -293.428102) (xy 155.054288 -293.382826) (xy 155.080591 -293.34123) (xy 155.113226 -293.304393)
			(xy 155.151347 -293.273268) (xy 155.193968 -293.248661) (xy 155.239984 -293.231209) (xy 155.288203 -293.221365)
			(xy 155.337378 -293.219384) (xy 155.386233 -293.225316) (xy 155.433504 -293.239008) (xy 155.477966 -293.260106)
			(xy 155.518469 -293.288062) (xy 155.553962 -293.322154) (xy 155.583527 -293.361498) (xy 155.606398 -293.405075)
			(xy 155.621982 -293.451756) (xy 155.629877 -293.500333) (xy 155.630372 -293.52494) (xy 155.96922 -293.52494)
			(xy 155.97318 -293.475886) (xy 155.984957 -293.428102) (xy 156.004248 -293.382826) (xy 156.030551 -293.34123)
			(xy 156.063186 -293.304393) (xy 156.101307 -293.273268) (xy 156.143928 -293.248661) (xy 156.189944 -293.231209)
			(xy 156.238163 -293.221365) (xy 156.287338 -293.219384) (xy 156.336193 -293.225316) (xy 156.383464 -293.239008)
			(xy 156.427926 -293.260106) (xy 156.468429 -293.288062) (xy 156.503922 -293.322154) (xy 156.533487 -293.361498)
			(xy 156.556358 -293.405075) (xy 156.571942 -293.451756) (xy 156.579837 -293.500333) (xy 156.580332 -293.52494)
			(xy 156.91918 -293.52494) (xy 156.92314 -293.475886) (xy 156.934917 -293.428102) (xy 156.954208 -293.382826)
			(xy 156.980511 -293.34123) (xy 157.013146 -293.304393) (xy 157.051267 -293.273268) (xy 157.093888 -293.248661)
			(xy 157.139904 -293.231209) (xy 157.188123 -293.221365) (xy 157.237298 -293.219384) (xy 157.286153 -293.225316)
			(xy 157.333424 -293.239008) (xy 157.377886 -293.260106) (xy 157.418389 -293.288062) (xy 157.453882 -293.322154)
			(xy 157.483447 -293.361498) (xy 157.506318 -293.405075) (xy 157.521902 -293.451756) (xy 157.529797 -293.500333)
			(xy 157.530292 -293.52494) (xy 157.86914 -293.52494) (xy 157.8731 -293.475886) (xy 157.884877 -293.428102)
			(xy 157.904168 -293.382826) (xy 157.930471 -293.34123) (xy 157.963106 -293.304393) (xy 158.001227 -293.273268)
			(xy 158.043848 -293.248661) (xy 158.089864 -293.231209) (xy 158.138083 -293.221365) (xy 158.187258 -293.219384)
			(xy 158.236113 -293.225316) (xy 158.283384 -293.239008) (xy 158.327846 -293.260106) (xy 158.368349 -293.288062)
			(xy 158.403842 -293.322154) (xy 158.433407 -293.361498) (xy 158.456278 -293.405075) (xy 158.471862 -293.451756)
			(xy 158.479757 -293.500333) (xy 158.480252 -293.52494) (xy 158.479757 -293.549547) (xy 158.479425 -293.551589)
			(xy 158.769294 -293.551589) (xy 158.769294 -293.498291) (xy 158.777237 -293.445587) (xy 158.792947 -293.394657)
			(xy 158.816073 -293.346636) (xy 158.846097 -293.302599) (xy 158.882349 -293.263528) (xy 158.92402 -293.230297)
			(xy 158.970178 -293.203648) (xy 159.019792 -293.184176) (xy 159.071754 -293.172316) (xy 159.124904 -293.168333)
			(xy 159.178054 -293.172316) (xy 159.230016 -293.184176) (xy 159.27963 -293.203648) (xy 159.325788 -293.230297)
			(xy 159.367459 -293.263528) (xy 159.403711 -293.302599) (xy 159.433735 -293.346636) (xy 159.456861 -293.394657)
			(xy 159.472571 -293.445587) (xy 159.480514 -293.498291) (xy 159.481012 -293.52494) (xy 159.76906 -293.52494)
			(xy 159.77302 -293.475886) (xy 159.784797 -293.428102) (xy 159.804088 -293.382826) (xy 159.830391 -293.34123)
			(xy 159.863026 -293.304393) (xy 159.901147 -293.273268) (xy 159.943768 -293.248661) (xy 159.989784 -293.231209)
			(xy 160.038003 -293.221365) (xy 160.087178 -293.219384) (xy 160.136033 -293.225316) (xy 160.183304 -293.239008)
			(xy 160.227766 -293.260106) (xy 160.268269 -293.288062) (xy 160.303762 -293.322154) (xy 160.333327 -293.361498)
			(xy 160.356198 -293.405075) (xy 160.371782 -293.451756) (xy 160.379677 -293.500333) (xy 160.380172 -293.52494)
			(xy 161.669234 -293.52494) (xy 161.673194 -293.475886) (xy 161.684971 -293.428102) (xy 161.704262 -293.382826)
			(xy 161.730565 -293.34123) (xy 161.7632 -293.304393) (xy 161.801321 -293.273268) (xy 161.843942 -293.248661)
			(xy 161.889958 -293.231209) (xy 161.938177 -293.221365) (xy 161.987352 -293.219384) (xy 162.036207 -293.225316)
			(xy 162.083478 -293.239008) (xy 162.12794 -293.260106) (xy 162.168443 -293.288062) (xy 162.203936 -293.322154)
			(xy 162.233501 -293.361498) (xy 162.256372 -293.405075) (xy 162.271956 -293.451756) (xy 162.279851 -293.500333)
			(xy 162.280346 -293.52494) (xy 163.569154 -293.52494) (xy 163.573114 -293.475886) (xy 163.584891 -293.428102)
			(xy 163.604182 -293.382826) (xy 163.630485 -293.34123) (xy 163.66312 -293.304393) (xy 163.701241 -293.273268)
			(xy 163.743862 -293.248661) (xy 163.789878 -293.231209) (xy 163.838097 -293.221365) (xy 163.887272 -293.219384)
			(xy 163.936127 -293.225316) (xy 163.983398 -293.239008) (xy 164.02786 -293.260106) (xy 164.068363 -293.288062)
			(xy 164.103856 -293.322154) (xy 164.133421 -293.361498) (xy 164.156292 -293.405075) (xy 164.171876 -293.451756)
			(xy 164.179771 -293.500333) (xy 164.180266 -293.52494) (xy 164.519114 -293.52494) (xy 164.523074 -293.475886)
			(xy 164.534851 -293.428102) (xy 164.554142 -293.382826) (xy 164.580445 -293.34123) (xy 164.61308 -293.304393)
			(xy 164.651201 -293.273268) (xy 164.693822 -293.248661) (xy 164.739838 -293.231209) (xy 164.788057 -293.221365)
			(xy 164.837232 -293.219384) (xy 164.886087 -293.225316) (xy 164.933358 -293.239008) (xy 164.97782 -293.260106)
			(xy 165.018323 -293.288062) (xy 165.053816 -293.322154) (xy 165.083381 -293.361498) (xy 165.106252 -293.405075)
			(xy 165.121836 -293.451756) (xy 165.129731 -293.500333) (xy 165.130226 -293.52494) (xy 166.419288 -293.52494)
			(xy 166.423248 -293.475886) (xy 166.435025 -293.428102) (xy 166.454316 -293.382826) (xy 166.480619 -293.34123)
			(xy 166.513254 -293.304393) (xy 166.551375 -293.273268) (xy 166.593996 -293.248661) (xy 166.640012 -293.231209)
			(xy 166.688231 -293.221365) (xy 166.737406 -293.219384) (xy 166.786261 -293.225316) (xy 166.833532 -293.239008)
			(xy 166.877994 -293.260106) (xy 166.918497 -293.288062) (xy 166.95399 -293.322154) (xy 166.983555 -293.361498)
			(xy 167.006426 -293.405075) (xy 167.02201 -293.451756) (xy 167.029905 -293.500333) (xy 167.0304 -293.52494)
			(xy 168.319208 -293.52494) (xy 168.323168 -293.475886) (xy 168.334945 -293.428102) (xy 168.354236 -293.382826)
			(xy 168.380539 -293.34123) (xy 168.413174 -293.304393) (xy 168.451295 -293.273268) (xy 168.493916 -293.248661)
			(xy 168.539932 -293.231209) (xy 168.588151 -293.221365) (xy 168.637326 -293.219384) (xy 168.686181 -293.225316)
			(xy 168.733452 -293.239008) (xy 168.777914 -293.260106) (xy 168.818417 -293.288062) (xy 168.85391 -293.322154)
			(xy 168.883475 -293.361498) (xy 168.906346 -293.405075) (xy 168.92193 -293.451756) (xy 168.929825 -293.500333)
			(xy 168.93032 -293.52494) (xy 170.219128 -293.52494) (xy 170.223088 -293.475886) (xy 170.234865 -293.428102)
			(xy 170.254156 -293.382826) (xy 170.280459 -293.34123) (xy 170.313094 -293.304393) (xy 170.351215 -293.273268)
			(xy 170.393836 -293.248661) (xy 170.439852 -293.231209) (xy 170.488071 -293.221365) (xy 170.537246 -293.219384)
			(xy 170.586101 -293.225316) (xy 170.633372 -293.239008) (xy 170.677834 -293.260106) (xy 170.718337 -293.288062)
			(xy 170.75383 -293.322154) (xy 170.783395 -293.361498) (xy 170.806266 -293.405075) (xy 170.82185 -293.451756)
			(xy 170.829745 -293.500333) (xy 170.83024 -293.52494) (xy 172.119048 -293.52494) (xy 172.123008 -293.475886)
			(xy 172.134785 -293.428102) (xy 172.154076 -293.382826) (xy 172.180379 -293.34123) (xy 172.213014 -293.304393)
			(xy 172.251135 -293.273268) (xy 172.293756 -293.248661) (xy 172.339772 -293.231209) (xy 172.387991 -293.221365)
			(xy 172.437166 -293.219384) (xy 172.486021 -293.225316) (xy 172.533292 -293.239008) (xy 172.577754 -293.260106)
			(xy 172.618257 -293.288062) (xy 172.65375 -293.322154) (xy 172.683315 -293.361498) (xy 172.706186 -293.405075)
			(xy 172.72177 -293.451756) (xy 172.729665 -293.500333) (xy 172.73016 -293.52494) (xy 174.019222 -293.52494)
			(xy 174.023182 -293.475886) (xy 174.034959 -293.428102) (xy 174.05425 -293.382826) (xy 174.080553 -293.34123)
			(xy 174.113188 -293.304393) (xy 174.151309 -293.273268) (xy 174.19393 -293.248661) (xy 174.239946 -293.231209)
			(xy 174.288165 -293.221365) (xy 174.33734 -293.219384) (xy 174.386195 -293.225316) (xy 174.433466 -293.239008)
			(xy 174.477928 -293.260106) (xy 174.518431 -293.288062) (xy 174.553924 -293.322154) (xy 174.583489 -293.361498)
			(xy 174.60636 -293.405075) (xy 174.621944 -293.451756) (xy 174.629839 -293.500333) (xy 174.630334 -293.52494)
			(xy 176.869102 -293.52494) (xy 176.873062 -293.475886) (xy 176.884839 -293.428102) (xy 176.90413 -293.382826)
			(xy 176.930433 -293.34123) (xy 176.963068 -293.304393) (xy 177.001189 -293.273268) (xy 177.04381 -293.248661)
			(xy 177.089826 -293.231209) (xy 177.138045 -293.221365) (xy 177.18722 -293.219384) (xy 177.236075 -293.225316)
			(xy 177.283346 -293.239008) (xy 177.327808 -293.260106) (xy 177.368311 -293.288062) (xy 177.403804 -293.322154)
			(xy 177.433369 -293.361498) (xy 177.45624 -293.405075) (xy 177.471824 -293.451756) (xy 177.479719 -293.500333)
			(xy 177.480214 -293.52494) (xy 178.769276 -293.52494) (xy 178.773236 -293.475886) (xy 178.785013 -293.428102)
			(xy 178.804304 -293.382826) (xy 178.830607 -293.34123) (xy 178.863242 -293.304393) (xy 178.901363 -293.273268)
			(xy 178.943984 -293.248661) (xy 178.99 -293.231209) (xy 179.038219 -293.221365) (xy 179.087394 -293.219384)
			(xy 179.136249 -293.225316) (xy 179.18352 -293.239008) (xy 179.227982 -293.260106) (xy 179.268485 -293.288062)
			(xy 179.303978 -293.322154) (xy 179.333543 -293.361498) (xy 179.356414 -293.405075) (xy 179.371998 -293.451756)
			(xy 179.379893 -293.500333) (xy 179.380388 -293.52494) (xy 180.669196 -293.52494) (xy 180.673156 -293.475886)
			(xy 180.684933 -293.428102) (xy 180.704224 -293.382826) (xy 180.730527 -293.34123) (xy 180.763162 -293.304393)
			(xy 180.801283 -293.273268) (xy 180.843904 -293.248661) (xy 180.88992 -293.231209) (xy 180.938139 -293.221365)
			(xy 180.987314 -293.219384) (xy 181.036169 -293.225316) (xy 181.08344 -293.239008) (xy 181.127902 -293.260106)
			(xy 181.168405 -293.288062) (xy 181.203898 -293.322154) (xy 181.233463 -293.361498) (xy 181.256334 -293.405075)
			(xy 181.271918 -293.451756) (xy 181.279813 -293.500333) (xy 181.280308 -293.52494) (xy 182.569116 -293.52494)
			(xy 182.573076 -293.475886) (xy 182.584853 -293.428102) (xy 182.604144 -293.382826) (xy 182.630447 -293.34123)
			(xy 182.663082 -293.304393) (xy 182.701203 -293.273268) (xy 182.743824 -293.248661) (xy 182.78984 -293.231209)
			(xy 182.838059 -293.221365) (xy 182.887234 -293.219384) (xy 182.936089 -293.225316) (xy 182.98336 -293.239008)
			(xy 183.027822 -293.260106) (xy 183.068325 -293.288062) (xy 183.103818 -293.322154) (xy 183.133383 -293.361498)
			(xy 183.156254 -293.405075) (xy 183.171838 -293.451756) (xy 183.179733 -293.500333) (xy 183.180228 -293.52494)
			(xy 183.179733 -293.549547) (xy 183.171838 -293.598124) (xy 183.156254 -293.644805) (xy 183.133383 -293.688382)
			(xy 183.103818 -293.727726) (xy 183.068325 -293.761818) (xy 183.027822 -293.789774) (xy 182.98336 -293.810872)
			(xy 182.936089 -293.824564) (xy 182.887234 -293.830496) (xy 182.838059 -293.828515) (xy 182.78984 -293.818671)
			(xy 182.743824 -293.801219) (xy 182.701203 -293.776612) (xy 182.663082 -293.745487) (xy 182.630447 -293.70865)
			(xy 182.604144 -293.667054) (xy 182.584853 -293.621778) (xy 182.573076 -293.573994) (xy 182.569116 -293.52494)
			(xy 181.280308 -293.52494) (xy 181.279813 -293.549547) (xy 181.271918 -293.598124) (xy 181.256334 -293.644805)
			(xy 181.233463 -293.688382) (xy 181.203898 -293.727726) (xy 181.168405 -293.761818) (xy 181.127902 -293.789774)
			(xy 181.08344 -293.810872) (xy 181.036169 -293.824564) (xy 180.987314 -293.830496) (xy 180.938139 -293.828515)
			(xy 180.88992 -293.818671) (xy 180.843904 -293.801219) (xy 180.801283 -293.776612) (xy 180.763162 -293.745487)
			(xy 180.730527 -293.70865) (xy 180.704224 -293.667054) (xy 180.684933 -293.621778) (xy 180.673156 -293.573994)
			(xy 180.669196 -293.52494) (xy 179.380388 -293.52494) (xy 179.379893 -293.549547) (xy 179.371998 -293.598124)
			(xy 179.356414 -293.644805) (xy 179.333543 -293.688382) (xy 179.303978 -293.727726) (xy 179.268485 -293.761818)
			(xy 179.227982 -293.789774) (xy 179.18352 -293.810872) (xy 179.136249 -293.824564) (xy 179.087394 -293.830496)
			(xy 179.038219 -293.828515) (xy 178.99 -293.818671) (xy 178.943984 -293.801219) (xy 178.901363 -293.776612)
			(xy 178.863242 -293.745487) (xy 178.830607 -293.70865) (xy 178.804304 -293.667054) (xy 178.785013 -293.621778)
			(xy 178.773236 -293.573994) (xy 178.769276 -293.52494) (xy 177.480214 -293.52494) (xy 177.479719 -293.549547)
			(xy 177.471824 -293.598124) (xy 177.45624 -293.644805) (xy 177.433369 -293.688382) (xy 177.403804 -293.727726)
			(xy 177.368311 -293.761818) (xy 177.327808 -293.789774) (xy 177.283346 -293.810872) (xy 177.236075 -293.824564)
			(xy 177.18722 -293.830496) (xy 177.138045 -293.828515) (xy 177.089826 -293.818671) (xy 177.04381 -293.801219)
			(xy 177.001189 -293.776612) (xy 176.963068 -293.745487) (xy 176.930433 -293.70865) (xy 176.90413 -293.667054)
			(xy 176.884839 -293.621778) (xy 176.873062 -293.573994) (xy 176.869102 -293.52494) (xy 174.630334 -293.52494)
			(xy 174.629839 -293.549547) (xy 174.621944 -293.598124) (xy 174.60636 -293.644805) (xy 174.583489 -293.688382)
			(xy 174.553924 -293.727726) (xy 174.518431 -293.761818) (xy 174.477928 -293.789774) (xy 174.433466 -293.810872)
			(xy 174.386195 -293.824564) (xy 174.33734 -293.830496) (xy 174.288165 -293.828515) (xy 174.239946 -293.818671)
			(xy 174.19393 -293.801219) (xy 174.151309 -293.776612) (xy 174.113188 -293.745487) (xy 174.080553 -293.70865)
			(xy 174.05425 -293.667054) (xy 174.034959 -293.621778) (xy 174.023182 -293.573994) (xy 174.019222 -293.52494)
			(xy 172.73016 -293.52494) (xy 172.729665 -293.549547) (xy 172.72177 -293.598124) (xy 172.706186 -293.644805)
			(xy 172.683315 -293.688382) (xy 172.65375 -293.727726) (xy 172.618257 -293.761818) (xy 172.577754 -293.789774)
			(xy 172.533292 -293.810872) (xy 172.486021 -293.824564) (xy 172.437166 -293.830496) (xy 172.387991 -293.828515)
			(xy 172.339772 -293.818671) (xy 172.293756 -293.801219) (xy 172.251135 -293.776612) (xy 172.213014 -293.745487)
			(xy 172.180379 -293.70865) (xy 172.154076 -293.667054) (xy 172.134785 -293.621778) (xy 172.123008 -293.573994)
			(xy 172.119048 -293.52494) (xy 170.83024 -293.52494) (xy 170.829745 -293.549547) (xy 170.82185 -293.598124)
			(xy 170.806266 -293.644805) (xy 170.783395 -293.688382) (xy 170.75383 -293.727726) (xy 170.718337 -293.761818)
			(xy 170.677834 -293.789774) (xy 170.633372 -293.810872) (xy 170.586101 -293.824564) (xy 170.537246 -293.830496)
			(xy 170.488071 -293.828515) (xy 170.439852 -293.818671) (xy 170.393836 -293.801219) (xy 170.351215 -293.776612)
			(xy 170.313094 -293.745487) (xy 170.280459 -293.70865) (xy 170.254156 -293.667054) (xy 170.234865 -293.621778)
			(xy 170.223088 -293.573994) (xy 170.219128 -293.52494) (xy 168.93032 -293.52494) (xy 168.929825 -293.549547)
			(xy 168.92193 -293.598124) (xy 168.906346 -293.644805) (xy 168.883475 -293.688382) (xy 168.85391 -293.727726)
			(xy 168.818417 -293.761818) (xy 168.777914 -293.789774) (xy 168.733452 -293.810872) (xy 168.686181 -293.824564)
			(xy 168.637326 -293.830496) (xy 168.588151 -293.828515) (xy 168.539932 -293.818671) (xy 168.493916 -293.801219)
			(xy 168.451295 -293.776612) (xy 168.413174 -293.745487) (xy 168.380539 -293.70865) (xy 168.354236 -293.667054)
			(xy 168.334945 -293.621778) (xy 168.323168 -293.573994) (xy 168.319208 -293.52494) (xy 167.0304 -293.52494)
			(xy 167.029905 -293.549547) (xy 167.02201 -293.598124) (xy 167.006426 -293.644805) (xy 166.983555 -293.688382)
			(xy 166.95399 -293.727726) (xy 166.918497 -293.761818) (xy 166.877994 -293.789774) (xy 166.833532 -293.810872)
			(xy 166.786261 -293.824564) (xy 166.737406 -293.830496) (xy 166.688231 -293.828515) (xy 166.640012 -293.818671)
			(xy 166.593996 -293.801219) (xy 166.551375 -293.776612) (xy 166.513254 -293.745487) (xy 166.480619 -293.70865)
			(xy 166.454316 -293.667054) (xy 166.435025 -293.621778) (xy 166.423248 -293.573994) (xy 166.419288 -293.52494)
			(xy 165.130226 -293.52494) (xy 165.129731 -293.549547) (xy 165.121836 -293.598124) (xy 165.106252 -293.644805)
			(xy 165.083381 -293.688382) (xy 165.053816 -293.727726) (xy 165.018323 -293.761818) (xy 164.97782 -293.789774)
			(xy 164.933358 -293.810872) (xy 164.886087 -293.824564) (xy 164.837232 -293.830496) (xy 164.788057 -293.828515)
			(xy 164.739838 -293.818671) (xy 164.693822 -293.801219) (xy 164.651201 -293.776612) (xy 164.61308 -293.745487)
			(xy 164.580445 -293.70865) (xy 164.554142 -293.667054) (xy 164.534851 -293.621778) (xy 164.523074 -293.573994)
			(xy 164.519114 -293.52494) (xy 164.180266 -293.52494) (xy 164.179771 -293.549547) (xy 164.171876 -293.598124)
			(xy 164.156292 -293.644805) (xy 164.133421 -293.688382) (xy 164.103856 -293.727726) (xy 164.068363 -293.761818)
			(xy 164.02786 -293.789774) (xy 163.983398 -293.810872) (xy 163.936127 -293.824564) (xy 163.887272 -293.830496)
			(xy 163.838097 -293.828515) (xy 163.789878 -293.818671) (xy 163.743862 -293.801219) (xy 163.701241 -293.776612)
			(xy 163.66312 -293.745487) (xy 163.630485 -293.70865) (xy 163.604182 -293.667054) (xy 163.584891 -293.621778)
			(xy 163.573114 -293.573994) (xy 163.569154 -293.52494) (xy 162.280346 -293.52494) (xy 162.279851 -293.549547)
			(xy 162.271956 -293.598124) (xy 162.256372 -293.644805) (xy 162.233501 -293.688382) (xy 162.203936 -293.727726)
			(xy 162.168443 -293.761818) (xy 162.12794 -293.789774) (xy 162.083478 -293.810872) (xy 162.036207 -293.824564)
			(xy 161.987352 -293.830496) (xy 161.938177 -293.828515) (xy 161.889958 -293.818671) (xy 161.843942 -293.801219)
			(xy 161.801321 -293.776612) (xy 161.7632 -293.745487) (xy 161.730565 -293.70865) (xy 161.704262 -293.667054)
			(xy 161.684971 -293.621778) (xy 161.673194 -293.573994) (xy 161.669234 -293.52494) (xy 160.380172 -293.52494)
			(xy 160.379677 -293.549547) (xy 160.371782 -293.598124) (xy 160.356198 -293.644805) (xy 160.333327 -293.688382)
			(xy 160.303762 -293.727726) (xy 160.268269 -293.761818) (xy 160.227766 -293.789774) (xy 160.183304 -293.810872)
			(xy 160.136033 -293.824564) (xy 160.087178 -293.830496) (xy 160.038003 -293.828515) (xy 159.989784 -293.818671)
			(xy 159.943768 -293.801219) (xy 159.901147 -293.776612) (xy 159.863026 -293.745487) (xy 159.830391 -293.70865)
			(xy 159.804088 -293.667054) (xy 159.784797 -293.621778) (xy 159.77302 -293.573994) (xy 159.76906 -293.52494)
			(xy 159.481012 -293.52494) (xy 159.480514 -293.551589) (xy 159.472571 -293.604293) (xy 159.456861 -293.655223)
			(xy 159.433735 -293.703244) (xy 159.403711 -293.747281) (xy 159.367459 -293.786352) (xy 159.325788 -293.819583)
			(xy 159.27963 -293.846232) (xy 159.230016 -293.865704) (xy 159.178054 -293.877564) (xy 159.124904 -293.881548)
			(xy 159.071754 -293.877564) (xy 159.019792 -293.865704) (xy 158.970178 -293.846232) (xy 158.92402 -293.819583)
			(xy 158.882349 -293.786352) (xy 158.846097 -293.747281) (xy 158.816073 -293.703244) (xy 158.792947 -293.655223)
			(xy 158.777237 -293.604293) (xy 158.769294 -293.551589) (xy 158.479425 -293.551589) (xy 158.471862 -293.598124)
			(xy 158.456278 -293.644805) (xy 158.433407 -293.688382) (xy 158.403842 -293.727726) (xy 158.368349 -293.761818)
			(xy 158.327846 -293.789774) (xy 158.283384 -293.810872) (xy 158.236113 -293.824564) (xy 158.187258 -293.830496)
			(xy 158.138083 -293.828515) (xy 158.089864 -293.818671) (xy 158.043848 -293.801219) (xy 158.001227 -293.776612)
			(xy 157.963106 -293.745487) (xy 157.930471 -293.70865) (xy 157.904168 -293.667054) (xy 157.884877 -293.621778)
			(xy 157.8731 -293.573994) (xy 157.86914 -293.52494) (xy 157.530292 -293.52494) (xy 157.529797 -293.549547)
			(xy 157.521902 -293.598124) (xy 157.506318 -293.644805) (xy 157.483447 -293.688382) (xy 157.453882 -293.727726)
			(xy 157.418389 -293.761818) (xy 157.377886 -293.789774) (xy 157.333424 -293.810872) (xy 157.286153 -293.824564)
			(xy 157.237298 -293.830496) (xy 157.188123 -293.828515) (xy 157.139904 -293.818671) (xy 157.093888 -293.801219)
			(xy 157.051267 -293.776612) (xy 157.013146 -293.745487) (xy 156.980511 -293.70865) (xy 156.954208 -293.667054)
			(xy 156.934917 -293.621778) (xy 156.92314 -293.573994) (xy 156.91918 -293.52494) (xy 156.580332 -293.52494)
			(xy 156.579837 -293.549547) (xy 156.571942 -293.598124) (xy 156.556358 -293.644805) (xy 156.533487 -293.688382)
			(xy 156.503922 -293.727726) (xy 156.468429 -293.761818) (xy 156.427926 -293.789774) (xy 156.383464 -293.810872)
			(xy 156.336193 -293.824564) (xy 156.287338 -293.830496) (xy 156.238163 -293.828515) (xy 156.189944 -293.818671)
			(xy 156.143928 -293.801219) (xy 156.101307 -293.776612) (xy 156.063186 -293.745487) (xy 156.030551 -293.70865)
			(xy 156.004248 -293.667054) (xy 155.984957 -293.621778) (xy 155.97318 -293.573994) (xy 155.96922 -293.52494)
			(xy 155.630372 -293.52494) (xy 155.629877 -293.549547) (xy 155.621982 -293.598124) (xy 155.606398 -293.644805)
			(xy 155.583527 -293.688382) (xy 155.553962 -293.727726) (xy 155.518469 -293.761818) (xy 155.477966 -293.789774)
			(xy 155.433504 -293.810872) (xy 155.386233 -293.824564) (xy 155.337378 -293.830496) (xy 155.288203 -293.828515)
			(xy 155.239984 -293.818671) (xy 155.193968 -293.801219) (xy 155.151347 -293.776612) (xy 155.113226 -293.745487)
			(xy 155.080591 -293.70865) (xy 155.054288 -293.667054) (xy 155.034997 -293.621778) (xy 155.02322 -293.573994)
			(xy 155.01926 -293.52494) (xy 154.680412 -293.52494) (xy 154.679917 -293.549547) (xy 154.672022 -293.598124)
			(xy 154.656438 -293.644805) (xy 154.633567 -293.688382) (xy 154.604002 -293.727726) (xy 154.568509 -293.761818)
			(xy 154.528006 -293.789774) (xy 154.483544 -293.810872) (xy 154.436273 -293.824564) (xy 154.387418 -293.830496)
			(xy 154.338243 -293.828515) (xy 154.290024 -293.818671) (xy 154.244008 -293.801219) (xy 154.201387 -293.776612)
			(xy 154.163266 -293.745487) (xy 154.130631 -293.70865) (xy 154.104328 -293.667054) (xy 154.085037 -293.621778)
			(xy 154.07326 -293.573994) (xy 154.0693 -293.52494) (xy 150.483733 -293.52494) (xy 150.475957 -293.577776)
			(xy 150.459889 -293.631183) (xy 150.436217 -293.68168) (xy 150.405444 -293.728193) (xy 150.368227 -293.76973)
			(xy 150.325359 -293.805405) (xy 150.277753 -293.834459) (xy 150.226424 -293.856271) (xy 150.172467 -293.870377)
			(xy 150.11703 -293.876477) (xy 150.061296 -293.87444) (xy 150.006453 -293.86431) (xy 149.953669 -293.846303)
			(xy 149.904069 -293.820802) (xy 149.858711 -293.788351) (xy 149.818562 -293.749642) (xy 149.784476 -293.705499)
			(xy 149.75718 -293.656864) (xy 149.737257 -293.604773) (xy 149.725131 -293.550336) (xy 149.72106 -293.494714)
			(xy 149.598126 -293.494714) (xy 149.597617 -293.5226) (xy 149.589497 -293.577776) (xy 149.573429 -293.631183)
			(xy 149.549757 -293.68168) (xy 149.518984 -293.728193) (xy 149.481767 -293.76973) (xy 149.438899 -293.805405)
			(xy 149.391293 -293.834459) (xy 149.339964 -293.856271) (xy 149.286007 -293.870377) (xy 149.23057 -293.876477)
			(xy 149.174836 -293.87444) (xy 149.119993 -293.86431) (xy 149.067209 -293.846303) (xy 149.017609 -293.820802)
			(xy 148.972251 -293.788351) (xy 148.932102 -293.749642) (xy 148.898016 -293.705499) (xy 148.87072 -293.656864)
			(xy 148.850797 -293.604773) (xy 148.838671 -293.550336) (xy 148.8346 -293.494714) (xy 148.201126 -293.494714)
			(xy 148.20064 -293.521965) (xy 148.192884 -293.575913) (xy 148.177529 -293.628208) (xy 148.154887 -293.677785)
			(xy 148.125421 -293.723635) (xy 148.08973 -293.764826) (xy 148.048539 -293.800517) (xy 148.002689 -293.829983)
			(xy 147.953112 -293.852625) (xy 147.900817 -293.86798) (xy 147.846869 -293.875736) (xy 147.792367 -293.875736)
			(xy 147.738419 -293.86798) (xy 147.686124 -293.852625) (xy 147.636547 -293.829983) (xy 147.590697 -293.800517)
			(xy 147.549506 -293.764826) (xy 147.513815 -293.723635) (xy 147.484349 -293.677785) (xy 147.461707 -293.628208)
			(xy 147.446352 -293.575913) (xy 147.438596 -293.521965) (xy 147.43811 -293.494714) (xy 136.078214 -293.494714)
			(xy 135.622284 -293.950644) (xy 135.614887 -293.957494) (xy 135.596289 -293.965232) (xy 135.586216 -293.96563)
			(xy 119.122952 -293.96563) (xy 119.116942 -293.965797) (xy 119.105261 -293.968622) (xy 119.099838 -293.971218)
			(xy 119.096362 -293.973055) (xy 119.089979 -293.977645) (xy 119.087138 -293.980362) (xy 118.845584 -294.221916)
			(xy 118.842881 -294.224769) (xy 118.838294 -294.23115) (xy 118.83644 -294.234616) (xy 118.833852 -294.240042)
			(xy 118.83102 -294.251721) (xy 118.830852 -294.25773) (xy 118.830852 -294.630856) (xy 141.911576 -294.630856)
			(xy 141.915647 -294.575234) (xy 141.927773 -294.520797) (xy 141.947696 -294.468706) (xy 141.974992 -294.420071)
			(xy 142.009078 -294.375928) (xy 142.049227 -294.337219) (xy 142.094585 -294.304768) (xy 142.144185 -294.279267)
			(xy 142.196969 -294.26126) (xy 142.251812 -294.25113) (xy 142.307546 -294.249093) (xy 142.362983 -294.255193)
			(xy 142.41694 -294.269299) (xy 142.468269 -294.291111) (xy 142.515875 -294.320165) (xy 142.558743 -294.35584)
			(xy 142.59596 -294.397377) (xy 142.626733 -294.44389) (xy 142.650405 -294.494387) (xy 142.666473 -294.547794)
			(xy 142.674593 -294.60297) (xy 142.675102 -294.630856) (xy 143.396714 -294.630856) (xy 143.400785 -294.575234)
			(xy 143.412911 -294.520797) (xy 143.432834 -294.468706) (xy 143.46013 -294.420071) (xy 143.494216 -294.375928)
			(xy 143.534365 -294.337219) (xy 143.579723 -294.304768) (xy 143.629323 -294.279267) (xy 143.682107 -294.26126)
			(xy 143.73695 -294.25113) (xy 143.792684 -294.249093) (xy 143.848121 -294.255193) (xy 143.902078 -294.269299)
			(xy 143.953407 -294.291111) (xy 144.001013 -294.320165) (xy 144.043881 -294.35584) (xy 144.081098 -294.397377)
			(xy 144.111871 -294.44389) (xy 144.126408 -294.4749) (xy 152.169126 -294.4749) (xy 152.173086 -294.425846)
			(xy 152.184863 -294.378062) (xy 152.204154 -294.332786) (xy 152.230457 -294.29119) (xy 152.263092 -294.254353)
			(xy 152.301213 -294.223228) (xy 152.343834 -294.198621) (xy 152.38985 -294.181169) (xy 152.438069 -294.171325)
			(xy 152.487244 -294.169344) (xy 152.536099 -294.175276) (xy 152.58337 -294.188968) (xy 152.627832 -294.210066)
			(xy 152.668335 -294.238022) (xy 152.703828 -294.272114) (xy 152.733393 -294.311458) (xy 152.756264 -294.355035)
			(xy 152.771848 -294.401716) (xy 152.779743 -294.450293) (xy 152.780238 -294.4749) (xy 153.119086 -294.4749)
			(xy 153.123046 -294.425846) (xy 153.134823 -294.378062) (xy 153.154114 -294.332786) (xy 153.180417 -294.29119)
			(xy 153.213052 -294.254353) (xy 153.251173 -294.223228) (xy 153.293794 -294.198621) (xy 153.33981 -294.181169)
			(xy 153.388029 -294.171325) (xy 153.437204 -294.169344) (xy 153.486059 -294.175276) (xy 153.53333 -294.188968)
			(xy 153.577792 -294.210066) (xy 153.618295 -294.238022) (xy 153.653788 -294.272114) (xy 153.683353 -294.311458)
			(xy 153.706224 -294.355035) (xy 153.721808 -294.401716) (xy 153.729703 -294.450293) (xy 153.730198 -294.4749)
			(xy 154.0693 -294.4749) (xy 154.07326 -294.425846) (xy 154.085037 -294.378062) (xy 154.104328 -294.332786)
			(xy 154.130631 -294.29119) (xy 154.163266 -294.254353) (xy 154.201387 -294.223228) (xy 154.244008 -294.198621)
			(xy 154.290024 -294.181169) (xy 154.338243 -294.171325) (xy 154.387418 -294.169344) (xy 154.436273 -294.175276)
			(xy 154.483544 -294.188968) (xy 154.528006 -294.210066) (xy 154.568509 -294.238022) (xy 154.604002 -294.272114)
			(xy 154.633567 -294.311458) (xy 154.656438 -294.355035) (xy 154.672022 -294.401716) (xy 154.679917 -294.450293)
			(xy 154.680412 -294.4749) (xy 156.91918 -294.4749) (xy 156.92314 -294.425846) (xy 156.934917 -294.378062)
			(xy 156.954208 -294.332786) (xy 156.980511 -294.29119) (xy 157.013146 -294.254353) (xy 157.051267 -294.223228)
			(xy 157.093888 -294.198621) (xy 157.139904 -294.181169) (xy 157.188123 -294.171325) (xy 157.237298 -294.169344)
			(xy 157.286153 -294.175276) (xy 157.333424 -294.188968) (xy 157.377886 -294.210066) (xy 157.418389 -294.238022)
			(xy 157.453882 -294.272114) (xy 157.483447 -294.311458) (xy 157.506318 -294.355035) (xy 157.521902 -294.401716)
			(xy 157.529797 -294.450293) (xy 157.530292 -294.4749) (xy 157.529797 -294.499507) (xy 157.529465 -294.501549)
			(xy 157.819334 -294.501549) (xy 157.819334 -294.448251) (xy 157.827277 -294.395547) (xy 157.842987 -294.344617)
			(xy 157.866113 -294.296596) (xy 157.896137 -294.252559) (xy 157.932389 -294.213488) (xy 157.97406 -294.180257)
			(xy 158.020218 -294.153608) (xy 158.069832 -294.134136) (xy 158.121794 -294.122276) (xy 158.174944 -294.118293)
			(xy 158.228094 -294.122276) (xy 158.280056 -294.134136) (xy 158.32967 -294.153608) (xy 158.375828 -294.180257)
			(xy 158.417499 -294.213488) (xy 158.453751 -294.252559) (xy 158.483775 -294.296596) (xy 158.506901 -294.344617)
			(xy 158.522611 -294.395547) (xy 158.530554 -294.448251) (xy 158.531052 -294.4749) (xy 158.8191 -294.4749)
			(xy 158.82306 -294.425846) (xy 158.834837 -294.378062) (xy 158.854128 -294.332786) (xy 158.880431 -294.29119)
			(xy 158.913066 -294.254353) (xy 158.951187 -294.223228) (xy 158.993808 -294.198621) (xy 159.039824 -294.181169)
			(xy 159.088043 -294.171325) (xy 159.137218 -294.169344) (xy 159.186073 -294.175276) (xy 159.233344 -294.188968)
			(xy 159.277806 -294.210066) (xy 159.318309 -294.238022) (xy 159.353802 -294.272114) (xy 159.383367 -294.311458)
			(xy 159.406238 -294.355035) (xy 159.421822 -294.401716) (xy 159.429717 -294.450293) (xy 159.430212 -294.4749)
			(xy 159.76906 -294.4749) (xy 159.77302 -294.425846) (xy 159.784797 -294.378062) (xy 159.804088 -294.332786)
			(xy 159.830391 -294.29119) (xy 159.863026 -294.254353) (xy 159.901147 -294.223228) (xy 159.943768 -294.198621)
			(xy 159.989784 -294.181169) (xy 160.038003 -294.171325) (xy 160.087178 -294.169344) (xy 160.136033 -294.175276)
			(xy 160.183304 -294.188968) (xy 160.227766 -294.210066) (xy 160.268269 -294.238022) (xy 160.303762 -294.272114)
			(xy 160.333327 -294.311458) (xy 160.356198 -294.355035) (xy 160.371782 -294.401716) (xy 160.379677 -294.450293)
			(xy 160.380172 -294.4749) (xy 160.719274 -294.4749) (xy 160.723234 -294.425846) (xy 160.735011 -294.378062)
			(xy 160.754302 -294.332786) (xy 160.780605 -294.29119) (xy 160.81324 -294.254353) (xy 160.851361 -294.223228)
			(xy 160.893982 -294.198621) (xy 160.939998 -294.181169) (xy 160.988217 -294.171325) (xy 161.037392 -294.169344)
			(xy 161.086247 -294.175276) (xy 161.133518 -294.188968) (xy 161.17798 -294.210066) (xy 161.218483 -294.238022)
			(xy 161.253976 -294.272114) (xy 161.283541 -294.311458) (xy 161.306412 -294.355035) (xy 161.321996 -294.401716)
			(xy 161.329891 -294.450293) (xy 161.330386 -294.4749) (xy 161.669234 -294.4749) (xy 161.673194 -294.425846)
			(xy 161.684971 -294.378062) (xy 161.704262 -294.332786) (xy 161.730565 -294.29119) (xy 161.7632 -294.254353)
			(xy 161.801321 -294.223228) (xy 161.843942 -294.198621) (xy 161.889958 -294.181169) (xy 161.938177 -294.171325)
			(xy 161.987352 -294.169344) (xy 162.036207 -294.175276) (xy 162.083478 -294.188968) (xy 162.12794 -294.210066)
			(xy 162.168443 -294.238022) (xy 162.203936 -294.272114) (xy 162.233501 -294.311458) (xy 162.256372 -294.355035)
			(xy 162.271956 -294.401716) (xy 162.279851 -294.450293) (xy 162.280346 -294.4749) (xy 162.619194 -294.4749)
			(xy 162.623154 -294.425846) (xy 162.634931 -294.378062) (xy 162.654222 -294.332786) (xy 162.680525 -294.29119)
			(xy 162.71316 -294.254353) (xy 162.751281 -294.223228) (xy 162.793902 -294.198621) (xy 162.839918 -294.181169)
			(xy 162.888137 -294.171325) (xy 162.937312 -294.169344) (xy 162.986167 -294.175276) (xy 163.033438 -294.188968)
			(xy 163.0779 -294.210066) (xy 163.118403 -294.238022) (xy 163.153896 -294.272114) (xy 163.183461 -294.311458)
			(xy 163.206332 -294.355035) (xy 163.221916 -294.401716) (xy 163.229811 -294.450293) (xy 163.230306 -294.4749)
			(xy 163.569154 -294.4749) (xy 163.573114 -294.425846) (xy 163.584891 -294.378062) (xy 163.604182 -294.332786)
			(xy 163.630485 -294.29119) (xy 163.66312 -294.254353) (xy 163.701241 -294.223228) (xy 163.743862 -294.198621)
			(xy 163.789878 -294.181169) (xy 163.838097 -294.171325) (xy 163.887272 -294.169344) (xy 163.936127 -294.175276)
			(xy 163.983398 -294.188968) (xy 164.02786 -294.210066) (xy 164.068363 -294.238022) (xy 164.103856 -294.272114)
			(xy 164.133421 -294.311458) (xy 164.156292 -294.355035) (xy 164.171876 -294.401716) (xy 164.179771 -294.450293)
			(xy 164.180266 -294.4749) (xy 165.469074 -294.4749) (xy 165.473034 -294.425846) (xy 165.484811 -294.378062)
			(xy 165.504102 -294.332786) (xy 165.530405 -294.29119) (xy 165.56304 -294.254353) (xy 165.601161 -294.223228)
			(xy 165.643782 -294.198621) (xy 165.689798 -294.181169) (xy 165.738017 -294.171325) (xy 165.787192 -294.169344)
			(xy 165.836047 -294.175276) (xy 165.883318 -294.188968) (xy 165.92778 -294.210066) (xy 165.968283 -294.238022)
			(xy 166.003776 -294.272114) (xy 166.033341 -294.311458) (xy 166.056212 -294.355035) (xy 166.071796 -294.401716)
			(xy 166.079691 -294.450293) (xy 166.080186 -294.4749) (xy 167.369248 -294.4749) (xy 167.373208 -294.425846)
			(xy 167.384985 -294.378062) (xy 167.404276 -294.332786) (xy 167.430579 -294.29119) (xy 167.463214 -294.254353)
			(xy 167.501335 -294.223228) (xy 167.543956 -294.198621) (xy 167.589972 -294.181169) (xy 167.638191 -294.171325)
			(xy 167.687366 -294.169344) (xy 167.736221 -294.175276) (xy 167.783492 -294.188968) (xy 167.827954 -294.210066)
			(xy 167.868457 -294.238022) (xy 167.90395 -294.272114) (xy 167.933515 -294.311458) (xy 167.956386 -294.355035)
			(xy 167.97197 -294.401716) (xy 167.979865 -294.450293) (xy 167.98036 -294.4749) (xy 169.269168 -294.4749)
			(xy 169.273128 -294.425846) (xy 169.284905 -294.378062) (xy 169.304196 -294.332786) (xy 169.330499 -294.29119)
			(xy 169.363134 -294.254353) (xy 169.401255 -294.223228) (xy 169.443876 -294.198621) (xy 169.489892 -294.181169)
			(xy 169.538111 -294.171325) (xy 169.587286 -294.169344) (xy 169.636141 -294.175276) (xy 169.683412 -294.188968)
			(xy 169.727874 -294.210066) (xy 169.768377 -294.238022) (xy 169.80387 -294.272114) (xy 169.833435 -294.311458)
			(xy 169.856306 -294.355035) (xy 169.87189 -294.401716) (xy 169.879785 -294.450293) (xy 169.88028 -294.4749)
			(xy 171.169088 -294.4749) (xy 171.173048 -294.425846) (xy 171.184825 -294.378062) (xy 171.204116 -294.332786)
			(xy 171.230419 -294.29119) (xy 171.263054 -294.254353) (xy 171.301175 -294.223228) (xy 171.343796 -294.198621)
			(xy 171.389812 -294.181169) (xy 171.438031 -294.171325) (xy 171.487206 -294.169344) (xy 171.536061 -294.175276)
			(xy 171.583332 -294.188968) (xy 171.627794 -294.210066) (xy 171.668297 -294.238022) (xy 171.70379 -294.272114)
			(xy 171.733355 -294.311458) (xy 171.756226 -294.355035) (xy 171.77181 -294.401716) (xy 171.779705 -294.450293)
			(xy 171.7802 -294.4749) (xy 173.069262 -294.4749) (xy 173.073222 -294.425846) (xy 173.084999 -294.378062)
			(xy 173.10429 -294.332786) (xy 173.130593 -294.29119) (xy 173.163228 -294.254353) (xy 173.201349 -294.223228)
			(xy 173.24397 -294.198621) (xy 173.289986 -294.181169) (xy 173.338205 -294.171325) (xy 173.38738 -294.169344)
			(xy 173.436235 -294.175276) (xy 173.483506 -294.188968) (xy 173.527968 -294.210066) (xy 173.568471 -294.238022)
			(xy 173.603964 -294.272114) (xy 173.633529 -294.311458) (xy 173.6564 -294.355035) (xy 173.671984 -294.401716)
			(xy 173.679879 -294.450293) (xy 173.680374 -294.4749) (xy 175.919142 -294.4749) (xy 175.923102 -294.425846)
			(xy 175.934879 -294.378062) (xy 175.95417 -294.332786) (xy 175.980473 -294.29119) (xy 176.013108 -294.254353)
			(xy 176.051229 -294.223228) (xy 176.09385 -294.198621) (xy 176.139866 -294.181169) (xy 176.188085 -294.171325)
			(xy 176.23726 -294.169344) (xy 176.286115 -294.175276) (xy 176.333386 -294.188968) (xy 176.377848 -294.210066)
			(xy 176.418351 -294.238022) (xy 176.453844 -294.272114) (xy 176.483409 -294.311458) (xy 176.50628 -294.355035)
			(xy 176.521864 -294.401716) (xy 176.529759 -294.450293) (xy 176.530254 -294.4749) (xy 177.819062 -294.4749)
			(xy 177.823022 -294.425846) (xy 177.834799 -294.378062) (xy 177.85409 -294.332786) (xy 177.880393 -294.29119)
			(xy 177.913028 -294.254353) (xy 177.951149 -294.223228) (xy 177.99377 -294.198621) (xy 178.039786 -294.181169)
			(xy 178.088005 -294.171325) (xy 178.13718 -294.169344) (xy 178.186035 -294.175276) (xy 178.233306 -294.188968)
			(xy 178.277768 -294.210066) (xy 178.318271 -294.238022) (xy 178.353764 -294.272114) (xy 178.383329 -294.311458)
			(xy 178.4062 -294.355035) (xy 178.421784 -294.401716) (xy 178.429679 -294.450293) (xy 178.430174 -294.4749)
			(xy 179.719236 -294.4749) (xy 179.723196 -294.425846) (xy 179.734973 -294.378062) (xy 179.754264 -294.332786)
			(xy 179.780567 -294.29119) (xy 179.813202 -294.254353) (xy 179.851323 -294.223228) (xy 179.893944 -294.198621)
			(xy 179.93996 -294.181169) (xy 179.988179 -294.171325) (xy 180.037354 -294.169344) (xy 180.086209 -294.175276)
			(xy 180.13348 -294.188968) (xy 180.177942 -294.210066) (xy 180.218445 -294.238022) (xy 180.253938 -294.272114)
			(xy 180.283503 -294.311458) (xy 180.306374 -294.355035) (xy 180.321958 -294.401716) (xy 180.329853 -294.450293)
			(xy 180.330348 -294.4749) (xy 181.619156 -294.4749) (xy 181.623116 -294.425846) (xy 181.634893 -294.378062)
			(xy 181.654184 -294.332786) (xy 181.680487 -294.29119) (xy 181.713122 -294.254353) (xy 181.751243 -294.223228)
			(xy 181.793864 -294.198621) (xy 181.83988 -294.181169) (xy 181.888099 -294.171325) (xy 181.937274 -294.169344)
			(xy 181.986129 -294.175276) (xy 182.0334 -294.188968) (xy 182.077862 -294.210066) (xy 182.118365 -294.238022)
			(xy 182.153858 -294.272114) (xy 182.183423 -294.311458) (xy 182.206294 -294.355035) (xy 182.221878 -294.401716)
			(xy 182.229773 -294.450293) (xy 182.230268 -294.4749) (xy 182.569116 -294.4749) (xy 182.573076 -294.425846)
			(xy 182.584853 -294.378062) (xy 182.604144 -294.332786) (xy 182.630447 -294.29119) (xy 182.663082 -294.254353)
			(xy 182.701203 -294.223228) (xy 182.743824 -294.198621) (xy 182.78984 -294.181169) (xy 182.838059 -294.171325)
			(xy 182.887234 -294.169344) (xy 182.936089 -294.175276) (xy 182.98336 -294.188968) (xy 183.027822 -294.210066)
			(xy 183.068325 -294.238022) (xy 183.103818 -294.272114) (xy 183.133383 -294.311458) (xy 183.156254 -294.355035)
			(xy 183.171838 -294.401716) (xy 183.179733 -294.450293) (xy 183.180228 -294.4749) (xy 183.519076 -294.4749)
			(xy 183.523036 -294.425846) (xy 183.534813 -294.378062) (xy 183.554104 -294.332786) (xy 183.580407 -294.29119)
			(xy 183.613042 -294.254353) (xy 183.651163 -294.223228) (xy 183.693784 -294.198621) (xy 183.7398 -294.181169)
			(xy 183.788019 -294.171325) (xy 183.837194 -294.169344) (xy 183.886049 -294.175276) (xy 183.93332 -294.188968)
			(xy 183.977782 -294.210066) (xy 184.018285 -294.238022) (xy 184.053778 -294.272114) (xy 184.083343 -294.311458)
			(xy 184.106214 -294.355035) (xy 184.121798 -294.401716) (xy 184.129693 -294.450293) (xy 184.130188 -294.4749)
			(xy 184.129693 -294.499507) (xy 184.121798 -294.548084) (xy 184.106214 -294.594765) (xy 184.083343 -294.638342)
			(xy 184.053778 -294.677686) (xy 184.018285 -294.711778) (xy 183.977782 -294.739734) (xy 183.93332 -294.760832)
			(xy 183.886049 -294.774524) (xy 183.837194 -294.780456) (xy 183.788019 -294.778475) (xy 183.7398 -294.768631)
			(xy 183.693784 -294.751179) (xy 183.651163 -294.726572) (xy 183.613042 -294.695447) (xy 183.580407 -294.65861)
			(xy 183.554104 -294.617014) (xy 183.534813 -294.571738) (xy 183.523036 -294.523954) (xy 183.519076 -294.4749)
			(xy 183.180228 -294.4749) (xy 183.179733 -294.499507) (xy 183.171838 -294.548084) (xy 183.156254 -294.594765)
			(xy 183.133383 -294.638342) (xy 183.103818 -294.677686) (xy 183.068325 -294.711778) (xy 183.027822 -294.739734)
			(xy 182.98336 -294.760832) (xy 182.936089 -294.774524) (xy 182.887234 -294.780456) (xy 182.838059 -294.778475)
			(xy 182.78984 -294.768631) (xy 182.743824 -294.751179) (xy 182.701203 -294.726572) (xy 182.663082 -294.695447)
			(xy 182.630447 -294.65861) (xy 182.604144 -294.617014) (xy 182.584853 -294.571738) (xy 182.573076 -294.523954)
			(xy 182.569116 -294.4749) (xy 182.230268 -294.4749) (xy 182.229773 -294.499507) (xy 182.221878 -294.548084)
			(xy 182.206294 -294.594765) (xy 182.183423 -294.638342) (xy 182.153858 -294.677686) (xy 182.118365 -294.711778)
			(xy 182.077862 -294.739734) (xy 182.0334 -294.760832) (xy 181.986129 -294.774524) (xy 181.937274 -294.780456)
			(xy 181.888099 -294.778475) (xy 181.83988 -294.768631) (xy 181.793864 -294.751179) (xy 181.751243 -294.726572)
			(xy 181.713122 -294.695447) (xy 181.680487 -294.65861) (xy 181.654184 -294.617014) (xy 181.634893 -294.571738)
			(xy 181.623116 -294.523954) (xy 181.619156 -294.4749) (xy 180.330348 -294.4749) (xy 180.329853 -294.499507)
			(xy 180.321958 -294.548084) (xy 180.306374 -294.594765) (xy 180.283503 -294.638342) (xy 180.253938 -294.677686)
			(xy 180.218445 -294.711778) (xy 180.177942 -294.739734) (xy 180.13348 -294.760832) (xy 180.086209 -294.774524)
			(xy 180.037354 -294.780456) (xy 179.988179 -294.778475) (xy 179.93996 -294.768631) (xy 179.893944 -294.751179)
			(xy 179.851323 -294.726572) (xy 179.813202 -294.695447) (xy 179.780567 -294.65861) (xy 179.754264 -294.617014)
			(xy 179.734973 -294.571738) (xy 179.723196 -294.523954) (xy 179.719236 -294.4749) (xy 178.430174 -294.4749)
			(xy 178.429679 -294.499507) (xy 178.421784 -294.548084) (xy 178.4062 -294.594765) (xy 178.383329 -294.638342)
			(xy 178.353764 -294.677686) (xy 178.318271 -294.711778) (xy 178.277768 -294.739734) (xy 178.233306 -294.760832)
			(xy 178.186035 -294.774524) (xy 178.13718 -294.780456) (xy 178.088005 -294.778475) (xy 178.039786 -294.768631)
			(xy 177.99377 -294.751179) (xy 177.951149 -294.726572) (xy 177.913028 -294.695447) (xy 177.880393 -294.65861)
			(xy 177.85409 -294.617014) (xy 177.834799 -294.571738) (xy 177.823022 -294.523954) (xy 177.819062 -294.4749)
			(xy 176.530254 -294.4749) (xy 176.529759 -294.499507) (xy 176.521864 -294.548084) (xy 176.50628 -294.594765)
			(xy 176.483409 -294.638342) (xy 176.453844 -294.677686) (xy 176.418351 -294.711778) (xy 176.377848 -294.739734)
			(xy 176.333386 -294.760832) (xy 176.286115 -294.774524) (xy 176.23726 -294.780456) (xy 176.188085 -294.778475)
			(xy 176.139866 -294.768631) (xy 176.09385 -294.751179) (xy 176.051229 -294.726572) (xy 176.013108 -294.695447)
			(xy 175.980473 -294.65861) (xy 175.95417 -294.617014) (xy 175.934879 -294.571738) (xy 175.923102 -294.523954)
			(xy 175.919142 -294.4749) (xy 173.680374 -294.4749) (xy 173.679879 -294.499507) (xy 173.671984 -294.548084)
			(xy 173.6564 -294.594765) (xy 173.633529 -294.638342) (xy 173.603964 -294.677686) (xy 173.568471 -294.711778)
			(xy 173.527968 -294.739734) (xy 173.483506 -294.760832) (xy 173.436235 -294.774524) (xy 173.38738 -294.780456)
			(xy 173.338205 -294.778475) (xy 173.289986 -294.768631) (xy 173.24397 -294.751179) (xy 173.201349 -294.726572)
			(xy 173.163228 -294.695447) (xy 173.130593 -294.65861) (xy 173.10429 -294.617014) (xy 173.084999 -294.571738)
			(xy 173.073222 -294.523954) (xy 173.069262 -294.4749) (xy 171.7802 -294.4749) (xy 171.779705 -294.499507)
			(xy 171.77181 -294.548084) (xy 171.756226 -294.594765) (xy 171.733355 -294.638342) (xy 171.70379 -294.677686)
			(xy 171.668297 -294.711778) (xy 171.627794 -294.739734) (xy 171.583332 -294.760832) (xy 171.536061 -294.774524)
			(xy 171.487206 -294.780456) (xy 171.438031 -294.778475) (xy 171.389812 -294.768631) (xy 171.343796 -294.751179)
			(xy 171.301175 -294.726572) (xy 171.263054 -294.695447) (xy 171.230419 -294.65861) (xy 171.204116 -294.617014)
			(xy 171.184825 -294.571738) (xy 171.173048 -294.523954) (xy 171.169088 -294.4749) (xy 169.88028 -294.4749)
			(xy 169.879785 -294.499507) (xy 169.87189 -294.548084) (xy 169.856306 -294.594765) (xy 169.833435 -294.638342)
			(xy 169.80387 -294.677686) (xy 169.768377 -294.711778) (xy 169.727874 -294.739734) (xy 169.683412 -294.760832)
			(xy 169.636141 -294.774524) (xy 169.587286 -294.780456) (xy 169.538111 -294.778475) (xy 169.489892 -294.768631)
			(xy 169.443876 -294.751179) (xy 169.401255 -294.726572) (xy 169.363134 -294.695447) (xy 169.330499 -294.65861)
			(xy 169.304196 -294.617014) (xy 169.284905 -294.571738) (xy 169.273128 -294.523954) (xy 169.269168 -294.4749)
			(xy 167.98036 -294.4749) (xy 167.979865 -294.499507) (xy 167.97197 -294.548084) (xy 167.956386 -294.594765)
			(xy 167.933515 -294.638342) (xy 167.90395 -294.677686) (xy 167.868457 -294.711778) (xy 167.827954 -294.739734)
			(xy 167.783492 -294.760832) (xy 167.736221 -294.774524) (xy 167.687366 -294.780456) (xy 167.638191 -294.778475)
			(xy 167.589972 -294.768631) (xy 167.543956 -294.751179) (xy 167.501335 -294.726572) (xy 167.463214 -294.695447)
			(xy 167.430579 -294.65861) (xy 167.404276 -294.617014) (xy 167.384985 -294.571738) (xy 167.373208 -294.523954)
			(xy 167.369248 -294.4749) (xy 166.080186 -294.4749) (xy 166.079691 -294.499507) (xy 166.071796 -294.548084)
			(xy 166.056212 -294.594765) (xy 166.033341 -294.638342) (xy 166.003776 -294.677686) (xy 165.968283 -294.711778)
			(xy 165.92778 -294.739734) (xy 165.883318 -294.760832) (xy 165.836047 -294.774524) (xy 165.787192 -294.780456)
			(xy 165.738017 -294.778475) (xy 165.689798 -294.768631) (xy 165.643782 -294.751179) (xy 165.601161 -294.726572)
			(xy 165.56304 -294.695447) (xy 165.530405 -294.65861) (xy 165.504102 -294.617014) (xy 165.484811 -294.571738)
			(xy 165.473034 -294.523954) (xy 165.469074 -294.4749) (xy 164.180266 -294.4749) (xy 164.179771 -294.499507)
			(xy 164.171876 -294.548084) (xy 164.156292 -294.594765) (xy 164.133421 -294.638342) (xy 164.103856 -294.677686)
			(xy 164.068363 -294.711778) (xy 164.02786 -294.739734) (xy 163.983398 -294.760832) (xy 163.936127 -294.774524)
			(xy 163.887272 -294.780456) (xy 163.838097 -294.778475) (xy 163.789878 -294.768631) (xy 163.743862 -294.751179)
			(xy 163.701241 -294.726572) (xy 163.66312 -294.695447) (xy 163.630485 -294.65861) (xy 163.604182 -294.617014)
			(xy 163.584891 -294.571738) (xy 163.573114 -294.523954) (xy 163.569154 -294.4749) (xy 163.230306 -294.4749)
			(xy 163.229811 -294.499507) (xy 163.221916 -294.548084) (xy 163.206332 -294.594765) (xy 163.183461 -294.638342)
			(xy 163.153896 -294.677686) (xy 163.118403 -294.711778) (xy 163.0779 -294.739734) (xy 163.033438 -294.760832)
			(xy 162.986167 -294.774524) (xy 162.937312 -294.780456) (xy 162.888137 -294.778475) (xy 162.839918 -294.768631)
			(xy 162.793902 -294.751179) (xy 162.751281 -294.726572) (xy 162.71316 -294.695447) (xy 162.680525 -294.65861)
			(xy 162.654222 -294.617014) (xy 162.634931 -294.571738) (xy 162.623154 -294.523954) (xy 162.619194 -294.4749)
			(xy 162.280346 -294.4749) (xy 162.279851 -294.499507) (xy 162.271956 -294.548084) (xy 162.256372 -294.594765)
			(xy 162.233501 -294.638342) (xy 162.203936 -294.677686) (xy 162.168443 -294.711778) (xy 162.12794 -294.739734)
			(xy 162.083478 -294.760832) (xy 162.036207 -294.774524) (xy 161.987352 -294.780456) (xy 161.938177 -294.778475)
			(xy 161.889958 -294.768631) (xy 161.843942 -294.751179) (xy 161.801321 -294.726572) (xy 161.7632 -294.695447)
			(xy 161.730565 -294.65861) (xy 161.704262 -294.617014) (xy 161.684971 -294.571738) (xy 161.673194 -294.523954)
			(xy 161.669234 -294.4749) (xy 161.330386 -294.4749) (xy 161.329891 -294.499507) (xy 161.321996 -294.548084)
			(xy 161.306412 -294.594765) (xy 161.283541 -294.638342) (xy 161.253976 -294.677686) (xy 161.218483 -294.711778)
			(xy 161.17798 -294.739734) (xy 161.133518 -294.760832) (xy 161.086247 -294.774524) (xy 161.037392 -294.780456)
			(xy 160.988217 -294.778475) (xy 160.939998 -294.768631) (xy 160.893982 -294.751179) (xy 160.851361 -294.726572)
			(xy 160.81324 -294.695447) (xy 160.780605 -294.65861) (xy 160.754302 -294.617014) (xy 160.735011 -294.571738)
			(xy 160.723234 -294.523954) (xy 160.719274 -294.4749) (xy 160.380172 -294.4749) (xy 160.379677 -294.499507)
			(xy 160.371782 -294.548084) (xy 160.356198 -294.594765) (xy 160.333327 -294.638342) (xy 160.303762 -294.677686)
			(xy 160.268269 -294.711778) (xy 160.227766 -294.739734) (xy 160.183304 -294.760832) (xy 160.136033 -294.774524)
			(xy 160.087178 -294.780456) (xy 160.038003 -294.778475) (xy 159.989784 -294.768631) (xy 159.943768 -294.751179)
			(xy 159.901147 -294.726572) (xy 159.863026 -294.695447) (xy 159.830391 -294.65861) (xy 159.804088 -294.617014)
			(xy 159.784797 -294.571738) (xy 159.77302 -294.523954) (xy 159.76906 -294.4749) (xy 159.430212 -294.4749)
			(xy 159.429717 -294.499507) (xy 159.421822 -294.548084) (xy 159.406238 -294.594765) (xy 159.383367 -294.638342)
			(xy 159.353802 -294.677686) (xy 159.318309 -294.711778) (xy 159.277806 -294.739734) (xy 159.233344 -294.760832)
			(xy 159.186073 -294.774524) (xy 159.137218 -294.780456) (xy 159.088043 -294.778475) (xy 159.039824 -294.768631)
			(xy 158.993808 -294.751179) (xy 158.951187 -294.726572) (xy 158.913066 -294.695447) (xy 158.880431 -294.65861)
			(xy 158.854128 -294.617014) (xy 158.834837 -294.571738) (xy 158.82306 -294.523954) (xy 158.8191 -294.4749)
			(xy 158.531052 -294.4749) (xy 158.530554 -294.501549) (xy 158.522611 -294.554253) (xy 158.506901 -294.605183)
			(xy 158.483775 -294.653204) (xy 158.453751 -294.697241) (xy 158.417499 -294.736312) (xy 158.375828 -294.769543)
			(xy 158.32967 -294.796192) (xy 158.280056 -294.815664) (xy 158.228094 -294.827524) (xy 158.174944 -294.831508)
			(xy 158.121794 -294.827524) (xy 158.069832 -294.815664) (xy 158.020218 -294.796192) (xy 157.97406 -294.769543)
			(xy 157.932389 -294.736312) (xy 157.896137 -294.697241) (xy 157.866113 -294.653204) (xy 157.842987 -294.605183)
			(xy 157.827277 -294.554253) (xy 157.819334 -294.501549) (xy 157.529465 -294.501549) (xy 157.521902 -294.548084)
			(xy 157.506318 -294.594765) (xy 157.483447 -294.638342) (xy 157.453882 -294.677686) (xy 157.418389 -294.711778)
			(xy 157.377886 -294.739734) (xy 157.333424 -294.760832) (xy 157.286153 -294.774524) (xy 157.237298 -294.780456)
			(xy 157.188123 -294.778475) (xy 157.139904 -294.768631) (xy 157.093888 -294.751179) (xy 157.051267 -294.726572)
			(xy 157.013146 -294.695447) (xy 156.980511 -294.65861) (xy 156.954208 -294.617014) (xy 156.934917 -294.571738)
			(xy 156.92314 -294.523954) (xy 156.91918 -294.4749) (xy 154.680412 -294.4749) (xy 154.679917 -294.499507)
			(xy 154.672022 -294.548084) (xy 154.656438 -294.594765) (xy 154.633567 -294.638342) (xy 154.604002 -294.677686)
			(xy 154.568509 -294.711778) (xy 154.528006 -294.739734) (xy 154.483544 -294.760832) (xy 154.436273 -294.774524)
			(xy 154.387418 -294.780456) (xy 154.338243 -294.778475) (xy 154.290024 -294.768631) (xy 154.244008 -294.751179)
			(xy 154.201387 -294.726572) (xy 154.163266 -294.695447) (xy 154.130631 -294.65861) (xy 154.104328 -294.617014)
			(xy 154.085037 -294.571738) (xy 154.07326 -294.523954) (xy 154.0693 -294.4749) (xy 153.730198 -294.4749)
			(xy 153.729703 -294.499507) (xy 153.721808 -294.548084) (xy 153.706224 -294.594765) (xy 153.683353 -294.638342)
			(xy 153.653788 -294.677686) (xy 153.618295 -294.711778) (xy 153.577792 -294.739734) (xy 153.53333 -294.760832)
			(xy 153.486059 -294.774524) (xy 153.437204 -294.780456) (xy 153.388029 -294.778475) (xy 153.33981 -294.768631)
			(xy 153.293794 -294.751179) (xy 153.251173 -294.726572) (xy 153.213052 -294.695447) (xy 153.180417 -294.65861)
			(xy 153.154114 -294.617014) (xy 153.134823 -294.571738) (xy 153.123046 -294.523954) (xy 153.119086 -294.4749)
			(xy 152.780238 -294.4749) (xy 152.779743 -294.499507) (xy 152.771848 -294.548084) (xy 152.756264 -294.594765)
			(xy 152.733393 -294.638342) (xy 152.703828 -294.677686) (xy 152.668335 -294.711778) (xy 152.627832 -294.739734)
			(xy 152.58337 -294.760832) (xy 152.536099 -294.774524) (xy 152.487244 -294.780456) (xy 152.438069 -294.778475)
			(xy 152.38985 -294.768631) (xy 152.343834 -294.751179) (xy 152.301213 -294.726572) (xy 152.263092 -294.695447)
			(xy 152.230457 -294.65861) (xy 152.204154 -294.617014) (xy 152.184863 -294.571738) (xy 152.173086 -294.523954)
			(xy 152.169126 -294.4749) (xy 144.126408 -294.4749) (xy 144.135543 -294.494387) (xy 144.151611 -294.547794)
			(xy 144.159731 -294.60297) (xy 144.16024 -294.630856) (xy 144.159731 -294.658742) (xy 144.151611 -294.713918)
			(xy 144.135543 -294.767325) (xy 144.111871 -294.817822) (xy 144.081098 -294.864335) (xy 144.043881 -294.905872)
			(xy 144.001013 -294.941547) (xy 143.953407 -294.970601) (xy 143.902078 -294.992413) (xy 143.848121 -295.006519)
			(xy 143.792684 -295.012619) (xy 143.73695 -295.010582) (xy 143.682107 -295.000452) (xy 143.629323 -294.982445)
			(xy 143.579723 -294.956944) (xy 143.534365 -294.924493) (xy 143.494216 -294.885784) (xy 143.46013 -294.841641)
			(xy 143.432834 -294.793006) (xy 143.412911 -294.740915) (xy 143.400785 -294.686478) (xy 143.396714 -294.630856)
			(xy 142.675102 -294.630856) (xy 142.674593 -294.658742) (xy 142.666473 -294.713918) (xy 142.650405 -294.767325)
			(xy 142.626733 -294.817822) (xy 142.59596 -294.864335) (xy 142.558743 -294.905872) (xy 142.515875 -294.941547)
			(xy 142.468269 -294.970601) (xy 142.41694 -294.992413) (xy 142.362983 -295.006519) (xy 142.307546 -295.012619)
			(xy 142.251812 -295.010582) (xy 142.196969 -295.000452) (xy 142.144185 -294.982445) (xy 142.094585 -294.956944)
			(xy 142.049227 -294.924493) (xy 142.009078 -294.885784) (xy 141.974992 -294.841641) (xy 141.947696 -294.793006)
			(xy 141.927773 -294.740915) (xy 141.915647 -294.686478) (xy 141.911576 -294.630856) (xy 118.830852 -294.630856)
			(xy 118.830852 -295.933114) (xy 141.911576 -295.933114) (xy 141.915647 -295.877492) (xy 141.927773 -295.823055)
			(xy 141.947696 -295.770964) (xy 141.974992 -295.722329) (xy 142.009078 -295.678186) (xy 142.049227 -295.639477)
			(xy 142.094585 -295.607026) (xy 142.144185 -295.581525) (xy 142.196969 -295.563518) (xy 142.251812 -295.553388)
			(xy 142.307546 -295.551351) (xy 142.362983 -295.557451) (xy 142.41694 -295.571557) (xy 142.468269 -295.593369)
			(xy 142.515875 -295.622423) (xy 142.558743 -295.658098) (xy 142.59596 -295.699635) (xy 142.626733 -295.746148)
			(xy 142.650405 -295.796645) (xy 142.666473 -295.850052) (xy 142.674593 -295.905228) (xy 142.675102 -295.933114)
			(xy 143.387062 -295.933114) (xy 143.391133 -295.877492) (xy 143.403259 -295.823055) (xy 143.423182 -295.770964)
			(xy 143.450478 -295.722329) (xy 143.484564 -295.678186) (xy 143.524713 -295.639477) (xy 143.570071 -295.607026)
			(xy 143.619671 -295.581525) (xy 143.672455 -295.563518) (xy 143.727298 -295.553388) (xy 143.783032 -295.551351)
			(xy 143.838469 -295.557451) (xy 143.892426 -295.571557) (xy 143.943755 -295.593369) (xy 143.991361 -295.622423)
			(xy 144.034229 -295.658098) (xy 144.071446 -295.699635) (xy 144.102219 -295.746148) (xy 144.125891 -295.796645)
			(xy 144.141959 -295.850052) (xy 144.150079 -295.905228) (xy 144.150588 -295.933114) (xy 144.276062 -295.933114)
			(xy 144.280133 -295.877492) (xy 144.292259 -295.823055) (xy 144.312182 -295.770964) (xy 144.339478 -295.722329)
			(xy 144.373564 -295.678186) (xy 144.413713 -295.639477) (xy 144.459071 -295.607026) (xy 144.508671 -295.581525)
			(xy 144.561455 -295.563518) (xy 144.616298 -295.553388) (xy 144.672032 -295.551351) (xy 144.727469 -295.557451)
			(xy 144.781426 -295.571557) (xy 144.832755 -295.593369) (xy 144.880361 -295.622423) (xy 144.923229 -295.658098)
			(xy 144.960446 -295.699635) (xy 144.991219 -295.746148) (xy 145.014891 -295.796645) (xy 145.030959 -295.850052)
			(xy 145.039079 -295.905228) (xy 145.039588 -295.933114) (xy 145.039079 -295.961) (xy 145.030959 -296.016176)
			(xy 145.014891 -296.069583) (xy 144.991219 -296.12008) (xy 144.960446 -296.166593) (xy 144.923229 -296.20813)
			(xy 144.880361 -296.243805) (xy 144.832755 -296.272859) (xy 144.781426 -296.294671) (xy 144.727469 -296.308777)
			(xy 144.672032 -296.314877) (xy 144.616298 -296.31284) (xy 144.561455 -296.30271) (xy 144.508671 -296.284703)
			(xy 144.459071 -296.259202) (xy 144.413713 -296.226751) (xy 144.373564 -296.188042) (xy 144.339478 -296.143899)
			(xy 144.312182 -296.095264) (xy 144.292259 -296.043173) (xy 144.280133 -295.988736) (xy 144.276062 -295.933114)
			(xy 144.150588 -295.933114) (xy 144.150079 -295.961) (xy 144.141959 -296.016176) (xy 144.125891 -296.069583)
			(xy 144.102219 -296.12008) (xy 144.071446 -296.166593) (xy 144.034229 -296.20813) (xy 143.991361 -296.243805)
			(xy 143.943755 -296.272859) (xy 143.892426 -296.294671) (xy 143.838469 -296.308777) (xy 143.783032 -296.314877)
			(xy 143.727298 -296.31284) (xy 143.672455 -296.30271) (xy 143.619671 -296.284703) (xy 143.570071 -296.259202)
			(xy 143.524713 -296.226751) (xy 143.484564 -296.188042) (xy 143.450478 -296.143899) (xy 143.423182 -296.095264)
			(xy 143.403259 -296.043173) (xy 143.391133 -295.988736) (xy 143.387062 -295.933114) (xy 142.675102 -295.933114)
			(xy 142.674593 -295.961) (xy 142.666473 -296.016176) (xy 142.650405 -296.069583) (xy 142.626733 -296.12008)
			(xy 142.59596 -296.166593) (xy 142.558743 -296.20813) (xy 142.515875 -296.243805) (xy 142.468269 -296.272859)
			(xy 142.41694 -296.294671) (xy 142.362983 -296.308777) (xy 142.307546 -296.314877) (xy 142.251812 -296.31284)
			(xy 142.196969 -296.30271) (xy 142.144185 -296.284703) (xy 142.094585 -296.259202) (xy 142.049227 -296.226751)
			(xy 142.009078 -296.188042) (xy 141.974992 -296.143899) (xy 141.947696 -296.095264) (xy 141.927773 -296.043173)
			(xy 141.915647 -295.988736) (xy 141.911576 -295.933114) (xy 118.830852 -295.933114) (xy 118.830852 -296.695114)
			(xy 147.43811 -296.695114) (xy 147.438654 -296.665732) (xy 147.447683 -296.607665) (xy 147.465514 -296.551671)
			(xy 147.491725 -296.499075) (xy 147.525695 -296.451124) (xy 147.56662 -296.408952) (xy 147.589748 -296.390822)
			(xy 147.598672 -296.383342) (xy 147.609132 -296.362568) (xy 147.609814 -296.350944) (xy 147.611084 -296.258996)
			(xy 147.601178 -296.237914) (xy 147.592034 -296.230548) (xy 147.570186 -296.212342) (xy 147.531644 -296.170524)
			(xy 147.499736 -296.123449) (xy 147.475169 -296.072159) (xy 147.458486 -296.017791) (xy 147.450058 -295.961549)
			(xy 147.44954 -295.933114) (xy 147.450026 -295.905863) (xy 147.457782 -295.851915) (xy 147.473137 -295.79962)
			(xy 147.495779 -295.750043) (xy 147.525245 -295.704193) (xy 147.560936 -295.663002) (xy 147.602127 -295.627311)
			(xy 147.647977 -295.597845) (xy 147.697554 -295.575203) (xy 147.749849 -295.559848) (xy 147.803797 -295.552092)
			(xy 147.858299 -295.552092) (xy 147.912247 -295.559848) (xy 147.964542 -295.575203) (xy 148.014119 -295.597845)
			(xy 148.059969 -295.627311) (xy 148.10116 -295.663002) (xy 148.136851 -295.704193) (xy 148.166317 -295.750043)
			(xy 148.188959 -295.79962) (xy 148.204314 -295.851915) (xy 148.21207 -295.905863) (xy 148.212556 -295.933114)
			(xy 148.212006 -295.962496) (xy 148.202975 -296.020561) (xy 148.185143 -296.076554) (xy 148.158933 -296.129149)
			(xy 148.124966 -296.177101) (xy 148.084044 -296.219274) (xy 148.060918 -296.237406) (xy 148.051975 -296.244867)
			(xy 148.041527 -296.265656) (xy 148.040852 -296.277284) (xy 148.039582 -296.369232) (xy 148.049488 -296.390314)
			(xy 148.058632 -296.39768) (xy 148.080459 -296.415909) (xy 148.118999 -296.457724) (xy 148.150908 -296.504795)
			(xy 148.175478 -296.55608) (xy 148.192166 -296.610443) (xy 148.200603 -296.666681) (xy 148.201126 -296.695114)
			(xy 148.8346 -296.695114) (xy 148.838671 -296.639492) (xy 148.850797 -296.585055) (xy 148.87072 -296.532964)
			(xy 148.898016 -296.484329) (xy 148.932102 -296.440186) (xy 148.972251 -296.401477) (xy 149.017609 -296.369026)
			(xy 149.067209 -296.343525) (xy 149.119993 -296.325518) (xy 149.174836 -296.315388) (xy 149.23057 -296.313351)
			(xy 149.286007 -296.319451) (xy 149.339964 -296.333557) (xy 149.391293 -296.355369) (xy 149.438899 -296.384423)
			(xy 149.481767 -296.420098) (xy 149.518984 -296.461635) (xy 149.549757 -296.508148) (xy 149.573429 -296.558645)
			(xy 149.589497 -296.612052) (xy 149.597617 -296.667228) (xy 149.598126 -296.695114) (xy 149.72106 -296.695114)
			(xy 149.725131 -296.639492) (xy 149.737257 -296.585055) (xy 149.75718 -296.532964) (xy 149.784476 -296.484329)
			(xy 149.818562 -296.440186) (xy 149.858711 -296.401477) (xy 149.904069 -296.369026) (xy 149.953669 -296.343525)
			(xy 150.006453 -296.325518) (xy 150.061296 -296.315388) (xy 150.11703 -296.313351) (xy 150.172467 -296.319451)
			(xy 150.226424 -296.333557) (xy 150.277753 -296.355369) (xy 150.309624 -296.37482) (xy 153.11934 -296.37482)
			(xy 153.1233 -296.325766) (xy 153.135077 -296.277982) (xy 153.154368 -296.232706) (xy 153.180671 -296.19111)
			(xy 153.213306 -296.154273) (xy 153.251427 -296.123148) (xy 153.294048 -296.098541) (xy 153.340064 -296.081089)
			(xy 153.388283 -296.071245) (xy 153.437458 -296.069264) (xy 153.486313 -296.075196) (xy 153.533584 -296.088888)
			(xy 153.578046 -296.109986) (xy 153.618549 -296.137942) (xy 153.654042 -296.172034) (xy 153.683607 -296.211378)
			(xy 153.706478 -296.254955) (xy 153.722062 -296.301636) (xy 153.729957 -296.350213) (xy 153.730452 -296.37482)
			(xy 154.069046 -296.37482) (xy 154.073006 -296.325766) (xy 154.084783 -296.277982) (xy 154.104074 -296.232706)
			(xy 154.130377 -296.19111) (xy 154.163012 -296.154273) (xy 154.201133 -296.123148) (xy 154.243754 -296.098541)
			(xy 154.28977 -296.081089) (xy 154.337989 -296.071245) (xy 154.387164 -296.069264) (xy 154.436019 -296.075196)
			(xy 154.48329 -296.088888) (xy 154.527752 -296.109986) (xy 154.568255 -296.137942) (xy 154.603748 -296.172034)
			(xy 154.633313 -296.211378) (xy 154.656184 -296.254955) (xy 154.671768 -296.301636) (xy 154.679663 -296.350213)
			(xy 154.680158 -296.37482) (xy 155.01926 -296.37482) (xy 155.02322 -296.325766) (xy 155.034997 -296.277982)
			(xy 155.054288 -296.232706) (xy 155.080591 -296.19111) (xy 155.113226 -296.154273) (xy 155.151347 -296.123148)
			(xy 155.193968 -296.098541) (xy 155.239984 -296.081089) (xy 155.288203 -296.071245) (xy 155.337378 -296.069264)
			(xy 155.386233 -296.075196) (xy 155.433504 -296.088888) (xy 155.477966 -296.109986) (xy 155.518469 -296.137942)
			(xy 155.553962 -296.172034) (xy 155.583527 -296.211378) (xy 155.606398 -296.254955) (xy 155.621982 -296.301636)
			(xy 155.629877 -296.350213) (xy 155.630372 -296.37482) (xy 155.96922 -296.37482) (xy 155.97318 -296.325766)
			(xy 155.984957 -296.277982) (xy 156.004248 -296.232706) (xy 156.030551 -296.19111) (xy 156.063186 -296.154273)
			(xy 156.101307 -296.123148) (xy 156.143928 -296.098541) (xy 156.189944 -296.081089) (xy 156.238163 -296.071245)
			(xy 156.287338 -296.069264) (xy 156.336193 -296.075196) (xy 156.383464 -296.088888) (xy 156.427926 -296.109986)
			(xy 156.468429 -296.137942) (xy 156.503922 -296.172034) (xy 156.533487 -296.211378) (xy 156.556358 -296.254955)
			(xy 156.571942 -296.301636) (xy 156.579837 -296.350213) (xy 156.580332 -296.37482) (xy 157.86914 -296.37482)
			(xy 157.8731 -296.325766) (xy 157.884877 -296.277982) (xy 157.904168 -296.232706) (xy 157.930471 -296.19111)
			(xy 157.963106 -296.154273) (xy 158.001227 -296.123148) (xy 158.043848 -296.098541) (xy 158.089864 -296.081089)
			(xy 158.138083 -296.071245) (xy 158.187258 -296.069264) (xy 158.236113 -296.075196) (xy 158.283384 -296.088888)
			(xy 158.327846 -296.109986) (xy 158.368349 -296.137942) (xy 158.403842 -296.172034) (xy 158.433407 -296.211378)
			(xy 158.456278 -296.254955) (xy 158.471862 -296.301636) (xy 158.479757 -296.350213) (xy 158.480252 -296.37482)
			(xy 159.76906 -296.37482) (xy 159.77302 -296.325766) (xy 159.784797 -296.277982) (xy 159.804088 -296.232706)
			(xy 159.830391 -296.19111) (xy 159.863026 -296.154273) (xy 159.901147 -296.123148) (xy 159.943768 -296.098541)
			(xy 159.989784 -296.081089) (xy 160.038003 -296.071245) (xy 160.087178 -296.069264) (xy 160.136033 -296.075196)
			(xy 160.183304 -296.088888) (xy 160.227766 -296.109986) (xy 160.268269 -296.137942) (xy 160.303762 -296.172034)
			(xy 160.333327 -296.211378) (xy 160.356198 -296.254955) (xy 160.371782 -296.301636) (xy 160.379677 -296.350213)
			(xy 160.380172 -296.37482) (xy 160.719274 -296.37482) (xy 160.723234 -296.325766) (xy 160.735011 -296.277982)
			(xy 160.754302 -296.232706) (xy 160.780605 -296.19111) (xy 160.81324 -296.154273) (xy 160.851361 -296.123148)
			(xy 160.893982 -296.098541) (xy 160.939998 -296.081089) (xy 160.988217 -296.071245) (xy 161.037392 -296.069264)
			(xy 161.086247 -296.075196) (xy 161.133518 -296.088888) (xy 161.17798 -296.109986) (xy 161.218483 -296.137942)
			(xy 161.253976 -296.172034) (xy 161.283541 -296.211378) (xy 161.306412 -296.254955) (xy 161.321996 -296.301636)
			(xy 161.329891 -296.350213) (xy 161.330386 -296.37482) (xy 161.669234 -296.37482) (xy 161.673194 -296.325766)
			(xy 161.684971 -296.277982) (xy 161.704262 -296.232706) (xy 161.730565 -296.19111) (xy 161.7632 -296.154273)
			(xy 161.801321 -296.123148) (xy 161.843942 -296.098541) (xy 161.889958 -296.081089) (xy 161.938177 -296.071245)
			(xy 161.987352 -296.069264) (xy 162.036207 -296.075196) (xy 162.083478 -296.088888) (xy 162.12794 -296.109986)
			(xy 162.168443 -296.137942) (xy 162.203936 -296.172034) (xy 162.233501 -296.211378) (xy 162.256372 -296.254955)
			(xy 162.271956 -296.301636) (xy 162.279851 -296.350213) (xy 162.280346 -296.37482) (xy 163.569154 -296.37482)
			(xy 163.573114 -296.325766) (xy 163.584891 -296.277982) (xy 163.604182 -296.232706) (xy 163.630485 -296.19111)
			(xy 163.66312 -296.154273) (xy 163.701241 -296.123148) (xy 163.743862 -296.098541) (xy 163.789878 -296.081089)
			(xy 163.838097 -296.071245) (xy 163.887272 -296.069264) (xy 163.936127 -296.075196) (xy 163.983398 -296.088888)
			(xy 164.02786 -296.109986) (xy 164.068363 -296.137942) (xy 164.103856 -296.172034) (xy 164.133421 -296.211378)
			(xy 164.156292 -296.254955) (xy 164.171876 -296.301636) (xy 164.179771 -296.350213) (xy 164.180266 -296.37482)
			(xy 164.519114 -296.37482) (xy 164.523074 -296.325766) (xy 164.534851 -296.277982) (xy 164.554142 -296.232706)
			(xy 164.580445 -296.19111) (xy 164.61308 -296.154273) (xy 164.651201 -296.123148) (xy 164.693822 -296.098541)
			(xy 164.739838 -296.081089) (xy 164.788057 -296.071245) (xy 164.837232 -296.069264) (xy 164.886087 -296.075196)
			(xy 164.933358 -296.088888) (xy 164.97782 -296.109986) (xy 165.018323 -296.137942) (xy 165.053816 -296.172034)
			(xy 165.083381 -296.211378) (xy 165.106252 -296.254955) (xy 165.121836 -296.301636) (xy 165.129731 -296.350213)
			(xy 165.130226 -296.37482) (xy 166.419288 -296.37482) (xy 166.423248 -296.325766) (xy 166.435025 -296.277982)
			(xy 166.454316 -296.232706) (xy 166.480619 -296.19111) (xy 166.513254 -296.154273) (xy 166.551375 -296.123148)
			(xy 166.593996 -296.098541) (xy 166.640012 -296.081089) (xy 166.688231 -296.071245) (xy 166.737406 -296.069264)
			(xy 166.786261 -296.075196) (xy 166.833532 -296.088888) (xy 166.877994 -296.109986) (xy 166.918497 -296.137942)
			(xy 166.95399 -296.172034) (xy 166.983555 -296.211378) (xy 167.006426 -296.254955) (xy 167.02201 -296.301636)
			(xy 167.029905 -296.350213) (xy 167.0304 -296.37482) (xy 168.319208 -296.37482) (xy 168.323168 -296.325766)
			(xy 168.334945 -296.277982) (xy 168.354236 -296.232706) (xy 168.380539 -296.19111) (xy 168.413174 -296.154273)
			(xy 168.451295 -296.123148) (xy 168.493916 -296.098541) (xy 168.539932 -296.081089) (xy 168.588151 -296.071245)
			(xy 168.637326 -296.069264) (xy 168.686181 -296.075196) (xy 168.733452 -296.088888) (xy 168.777914 -296.109986)
			(xy 168.818417 -296.137942) (xy 168.85391 -296.172034) (xy 168.883475 -296.211378) (xy 168.906346 -296.254955)
			(xy 168.92193 -296.301636) (xy 168.929825 -296.350213) (xy 168.93032 -296.37482) (xy 170.219128 -296.37482)
			(xy 170.223088 -296.325766) (xy 170.234865 -296.277982) (xy 170.254156 -296.232706) (xy 170.280459 -296.19111)
			(xy 170.313094 -296.154273) (xy 170.351215 -296.123148) (xy 170.393836 -296.098541) (xy 170.439852 -296.081089)
			(xy 170.488071 -296.071245) (xy 170.537246 -296.069264) (xy 170.586101 -296.075196) (xy 170.633372 -296.088888)
			(xy 170.677834 -296.109986) (xy 170.718337 -296.137942) (xy 170.75383 -296.172034) (xy 170.783395 -296.211378)
			(xy 170.806266 -296.254955) (xy 170.82185 -296.301636) (xy 170.829745 -296.350213) (xy 170.83024 -296.37482)
			(xy 172.119302 -296.37482) (xy 172.123262 -296.325766) (xy 172.135039 -296.277982) (xy 172.15433 -296.232706)
			(xy 172.180633 -296.19111) (xy 172.213268 -296.154273) (xy 172.251389 -296.123148) (xy 172.29401 -296.098541)
			(xy 172.340026 -296.081089) (xy 172.388245 -296.071245) (xy 172.43742 -296.069264) (xy 172.486275 -296.075196)
			(xy 172.533546 -296.088888) (xy 172.578008 -296.109986) (xy 172.618511 -296.137942) (xy 172.654004 -296.172034)
			(xy 172.683569 -296.211378) (xy 172.70644 -296.254955) (xy 172.722024 -296.301636) (xy 172.729919 -296.350213)
			(xy 172.730414 -296.37482) (xy 174.019222 -296.37482) (xy 174.023182 -296.325766) (xy 174.034959 -296.277982)
			(xy 174.05425 -296.232706) (xy 174.080553 -296.19111) (xy 174.113188 -296.154273) (xy 174.151309 -296.123148)
			(xy 174.19393 -296.098541) (xy 174.239946 -296.081089) (xy 174.288165 -296.071245) (xy 174.33734 -296.069264)
			(xy 174.386195 -296.075196) (xy 174.433466 -296.088888) (xy 174.477928 -296.109986) (xy 174.518431 -296.137942)
			(xy 174.553924 -296.172034) (xy 174.583489 -296.211378) (xy 174.60636 -296.254955) (xy 174.621944 -296.301636)
			(xy 174.629839 -296.350213) (xy 174.630334 -296.37482) (xy 176.869102 -296.37482) (xy 176.873062 -296.325766)
			(xy 176.884839 -296.277982) (xy 176.90413 -296.232706) (xy 176.930433 -296.19111) (xy 176.963068 -296.154273)
			(xy 177.001189 -296.123148) (xy 177.04381 -296.098541) (xy 177.089826 -296.081089) (xy 177.138045 -296.071245)
			(xy 177.18722 -296.069264) (xy 177.236075 -296.075196) (xy 177.283346 -296.088888) (xy 177.327808 -296.109986)
			(xy 177.368311 -296.137942) (xy 177.403804 -296.172034) (xy 177.433369 -296.211378) (xy 177.45624 -296.254955)
			(xy 177.471824 -296.301636) (xy 177.479719 -296.350213) (xy 177.480214 -296.37482) (xy 178.769276 -296.37482)
			(xy 178.773236 -296.325766) (xy 178.785013 -296.277982) (xy 178.804304 -296.232706) (xy 178.830607 -296.19111)
			(xy 178.863242 -296.154273) (xy 178.901363 -296.123148) (xy 178.943984 -296.098541) (xy 178.99 -296.081089)
			(xy 179.038219 -296.071245) (xy 179.087394 -296.069264) (xy 179.136249 -296.075196) (xy 179.18352 -296.088888)
			(xy 179.227982 -296.109986) (xy 179.268485 -296.137942) (xy 179.303978 -296.172034) (xy 179.333543 -296.211378)
			(xy 179.356414 -296.254955) (xy 179.371998 -296.301636) (xy 179.379893 -296.350213) (xy 179.380388 -296.37482)
			(xy 180.669196 -296.37482) (xy 180.673156 -296.325766) (xy 180.684933 -296.277982) (xy 180.704224 -296.232706)
			(xy 180.730527 -296.19111) (xy 180.763162 -296.154273) (xy 180.801283 -296.123148) (xy 180.843904 -296.098541)
			(xy 180.88992 -296.081089) (xy 180.938139 -296.071245) (xy 180.987314 -296.069264) (xy 181.036169 -296.075196)
			(xy 181.08344 -296.088888) (xy 181.127902 -296.109986) (xy 181.168405 -296.137942) (xy 181.203898 -296.172034)
			(xy 181.233463 -296.211378) (xy 181.256334 -296.254955) (xy 181.271918 -296.301636) (xy 181.279813 -296.350213)
			(xy 181.280308 -296.37482) (xy 182.569116 -296.37482) (xy 182.573076 -296.325766) (xy 182.584853 -296.277982)
			(xy 182.604144 -296.232706) (xy 182.630447 -296.19111) (xy 182.663082 -296.154273) (xy 182.701203 -296.123148)
			(xy 182.743824 -296.098541) (xy 182.78984 -296.081089) (xy 182.838059 -296.071245) (xy 182.887234 -296.069264)
			(xy 182.936089 -296.075196) (xy 182.98336 -296.088888) (xy 183.027822 -296.109986) (xy 183.068325 -296.137942)
			(xy 183.103818 -296.172034) (xy 183.133383 -296.211378) (xy 183.156254 -296.254955) (xy 183.171838 -296.301636)
			(xy 183.179733 -296.350213) (xy 183.180228 -296.37482) (xy 183.519076 -296.37482) (xy 183.523036 -296.325766)
			(xy 183.534813 -296.277982) (xy 183.554104 -296.232706) (xy 183.580407 -296.19111) (xy 183.613042 -296.154273)
			(xy 183.651163 -296.123148) (xy 183.693784 -296.098541) (xy 183.7398 -296.081089) (xy 183.788019 -296.071245)
			(xy 183.837194 -296.069264) (xy 183.886049 -296.075196) (xy 183.93332 -296.088888) (xy 183.977782 -296.109986)
			(xy 184.018285 -296.137942) (xy 184.053778 -296.172034) (xy 184.083343 -296.211378) (xy 184.106214 -296.254955)
			(xy 184.121798 -296.301636) (xy 184.129693 -296.350213) (xy 184.130188 -296.37482) (xy 184.129693 -296.399427)
			(xy 184.121798 -296.448004) (xy 184.106214 -296.494685) (xy 184.083343 -296.538262) (xy 184.053778 -296.577606)
			(xy 184.018285 -296.611698) (xy 183.977782 -296.639654) (xy 183.93332 -296.660752) (xy 183.886049 -296.674444)
			(xy 183.837194 -296.680376) (xy 183.788019 -296.678395) (xy 183.7398 -296.668551) (xy 183.693784 -296.651099)
			(xy 183.651163 -296.626492) (xy 183.613042 -296.595367) (xy 183.580407 -296.55853) (xy 183.554104 -296.516934)
			(xy 183.534813 -296.471658) (xy 183.523036 -296.423874) (xy 183.519076 -296.37482) (xy 183.180228 -296.37482)
			(xy 183.179733 -296.399427) (xy 183.171838 -296.448004) (xy 183.156254 -296.494685) (xy 183.133383 -296.538262)
			(xy 183.103818 -296.577606) (xy 183.068325 -296.611698) (xy 183.027822 -296.639654) (xy 182.98336 -296.660752)
			(xy 182.936089 -296.674444) (xy 182.887234 -296.680376) (xy 182.838059 -296.678395) (xy 182.78984 -296.668551)
			(xy 182.743824 -296.651099) (xy 182.701203 -296.626492) (xy 182.663082 -296.595367) (xy 182.630447 -296.55853)
			(xy 182.604144 -296.516934) (xy 182.584853 -296.471658) (xy 182.573076 -296.423874) (xy 182.569116 -296.37482)
			(xy 181.280308 -296.37482) (xy 181.279813 -296.399427) (xy 181.271918 -296.448004) (xy 181.256334 -296.494685)
			(xy 181.233463 -296.538262) (xy 181.203898 -296.577606) (xy 181.168405 -296.611698) (xy 181.127902 -296.639654)
			(xy 181.08344 -296.660752) (xy 181.036169 -296.674444) (xy 180.987314 -296.680376) (xy 180.938139 -296.678395)
			(xy 180.88992 -296.668551) (xy 180.843904 -296.651099) (xy 180.801283 -296.626492) (xy 180.763162 -296.595367)
			(xy 180.730527 -296.55853) (xy 180.704224 -296.516934) (xy 180.684933 -296.471658) (xy 180.673156 -296.423874)
			(xy 180.669196 -296.37482) (xy 179.380388 -296.37482) (xy 179.379893 -296.399427) (xy 179.371998 -296.448004)
			(xy 179.356414 -296.494685) (xy 179.333543 -296.538262) (xy 179.303978 -296.577606) (xy 179.268485 -296.611698)
			(xy 179.227982 -296.639654) (xy 179.18352 -296.660752) (xy 179.136249 -296.674444) (xy 179.087394 -296.680376)
			(xy 179.038219 -296.678395) (xy 178.99 -296.668551) (xy 178.943984 -296.651099) (xy 178.901363 -296.626492)
			(xy 178.863242 -296.595367) (xy 178.830607 -296.55853) (xy 178.804304 -296.516934) (xy 178.785013 -296.471658)
			(xy 178.773236 -296.423874) (xy 178.769276 -296.37482) (xy 177.480214 -296.37482) (xy 177.479719 -296.399427)
			(xy 177.471824 -296.448004) (xy 177.45624 -296.494685) (xy 177.433369 -296.538262) (xy 177.403804 -296.577606)
			(xy 177.368311 -296.611698) (xy 177.327808 -296.639654) (xy 177.283346 -296.660752) (xy 177.236075 -296.674444)
			(xy 177.18722 -296.680376) (xy 177.138045 -296.678395) (xy 177.089826 -296.668551) (xy 177.04381 -296.651099)
			(xy 177.001189 -296.626492) (xy 176.963068 -296.595367) (xy 176.930433 -296.55853) (xy 176.90413 -296.516934)
			(xy 176.884839 -296.471658) (xy 176.873062 -296.423874) (xy 176.869102 -296.37482) (xy 174.630334 -296.37482)
			(xy 174.629839 -296.399427) (xy 174.621944 -296.448004) (xy 174.60636 -296.494685) (xy 174.583489 -296.538262)
			(xy 174.553924 -296.577606) (xy 174.518431 -296.611698) (xy 174.477928 -296.639654) (xy 174.433466 -296.660752)
			(xy 174.386195 -296.674444) (xy 174.33734 -296.680376) (xy 174.288165 -296.678395) (xy 174.239946 -296.668551)
			(xy 174.19393 -296.651099) (xy 174.151309 -296.626492) (xy 174.113188 -296.595367) (xy 174.080553 -296.55853)
			(xy 174.05425 -296.516934) (xy 174.034959 -296.471658) (xy 174.023182 -296.423874) (xy 174.019222 -296.37482)
			(xy 172.730414 -296.37482) (xy 172.729919 -296.399427) (xy 172.722024 -296.448004) (xy 172.70644 -296.494685)
			(xy 172.683569 -296.538262) (xy 172.654004 -296.577606) (xy 172.618511 -296.611698) (xy 172.578008 -296.639654)
			(xy 172.533546 -296.660752) (xy 172.486275 -296.674444) (xy 172.43742 -296.680376) (xy 172.388245 -296.678395)
			(xy 172.340026 -296.668551) (xy 172.29401 -296.651099) (xy 172.251389 -296.626492) (xy 172.213268 -296.595367)
			(xy 172.180633 -296.55853) (xy 172.15433 -296.516934) (xy 172.135039 -296.471658) (xy 172.123262 -296.423874)
			(xy 172.119302 -296.37482) (xy 170.83024 -296.37482) (xy 170.829745 -296.399427) (xy 170.82185 -296.448004)
			(xy 170.806266 -296.494685) (xy 170.783395 -296.538262) (xy 170.75383 -296.577606) (xy 170.718337 -296.611698)
			(xy 170.677834 -296.639654) (xy 170.633372 -296.660752) (xy 170.586101 -296.674444) (xy 170.537246 -296.680376)
			(xy 170.488071 -296.678395) (xy 170.439852 -296.668551) (xy 170.393836 -296.651099) (xy 170.351215 -296.626492)
			(xy 170.313094 -296.595367) (xy 170.280459 -296.55853) (xy 170.254156 -296.516934) (xy 170.234865 -296.471658)
			(xy 170.223088 -296.423874) (xy 170.219128 -296.37482) (xy 168.93032 -296.37482) (xy 168.929825 -296.399427)
			(xy 168.92193 -296.448004) (xy 168.906346 -296.494685) (xy 168.883475 -296.538262) (xy 168.85391 -296.577606)
			(xy 168.818417 -296.611698) (xy 168.777914 -296.639654) (xy 168.733452 -296.660752) (xy 168.686181 -296.674444)
			(xy 168.637326 -296.680376) (xy 168.588151 -296.678395) (xy 168.539932 -296.668551) (xy 168.493916 -296.651099)
			(xy 168.451295 -296.626492) (xy 168.413174 -296.595367) (xy 168.380539 -296.55853) (xy 168.354236 -296.516934)
			(xy 168.334945 -296.471658) (xy 168.323168 -296.423874) (xy 168.319208 -296.37482) (xy 167.0304 -296.37482)
			(xy 167.029905 -296.399427) (xy 167.02201 -296.448004) (xy 167.006426 -296.494685) (xy 166.983555 -296.538262)
			(xy 166.95399 -296.577606) (xy 166.918497 -296.611698) (xy 166.877994 -296.639654) (xy 166.833532 -296.660752)
			(xy 166.786261 -296.674444) (xy 166.737406 -296.680376) (xy 166.688231 -296.678395) (xy 166.640012 -296.668551)
			(xy 166.593996 -296.651099) (xy 166.551375 -296.626492) (xy 166.513254 -296.595367) (xy 166.480619 -296.55853)
			(xy 166.454316 -296.516934) (xy 166.435025 -296.471658) (xy 166.423248 -296.423874) (xy 166.419288 -296.37482)
			(xy 165.130226 -296.37482) (xy 165.129731 -296.399427) (xy 165.121836 -296.448004) (xy 165.106252 -296.494685)
			(xy 165.083381 -296.538262) (xy 165.053816 -296.577606) (xy 165.018323 -296.611698) (xy 164.97782 -296.639654)
			(xy 164.933358 -296.660752) (xy 164.886087 -296.674444) (xy 164.837232 -296.680376) (xy 164.788057 -296.678395)
			(xy 164.739838 -296.668551) (xy 164.693822 -296.651099) (xy 164.651201 -296.626492) (xy 164.61308 -296.595367)
			(xy 164.580445 -296.55853) (xy 164.554142 -296.516934) (xy 164.534851 -296.471658) (xy 164.523074 -296.423874)
			(xy 164.519114 -296.37482) (xy 164.180266 -296.37482) (xy 164.179771 -296.399427) (xy 164.171876 -296.448004)
			(xy 164.156292 -296.494685) (xy 164.133421 -296.538262) (xy 164.103856 -296.577606) (xy 164.068363 -296.611698)
			(xy 164.02786 -296.639654) (xy 163.983398 -296.660752) (xy 163.936127 -296.674444) (xy 163.887272 -296.680376)
			(xy 163.838097 -296.678395) (xy 163.789878 -296.668551) (xy 163.743862 -296.651099) (xy 163.701241 -296.626492)
			(xy 163.66312 -296.595367) (xy 163.630485 -296.55853) (xy 163.604182 -296.516934) (xy 163.584891 -296.471658)
			(xy 163.573114 -296.423874) (xy 163.569154 -296.37482) (xy 162.280346 -296.37482) (xy 162.279851 -296.399427)
			(xy 162.271956 -296.448004) (xy 162.256372 -296.494685) (xy 162.233501 -296.538262) (xy 162.203936 -296.577606)
			(xy 162.168443 -296.611698) (xy 162.12794 -296.639654) (xy 162.083478 -296.660752) (xy 162.036207 -296.674444)
			(xy 161.987352 -296.680376) (xy 161.938177 -296.678395) (xy 161.889958 -296.668551) (xy 161.843942 -296.651099)
			(xy 161.801321 -296.626492) (xy 161.7632 -296.595367) (xy 161.730565 -296.55853) (xy 161.704262 -296.516934)
			(xy 161.684971 -296.471658) (xy 161.673194 -296.423874) (xy 161.669234 -296.37482) (xy 161.330386 -296.37482)
			(xy 161.329891 -296.399427) (xy 161.321996 -296.448004) (xy 161.306412 -296.494685) (xy 161.283541 -296.538262)
			(xy 161.253976 -296.577606) (xy 161.218483 -296.611698) (xy 161.17798 -296.639654) (xy 161.133518 -296.660752)
			(xy 161.086247 -296.674444) (xy 161.037392 -296.680376) (xy 160.988217 -296.678395) (xy 160.939998 -296.668551)
			(xy 160.893982 -296.651099) (xy 160.851361 -296.626492) (xy 160.81324 -296.595367) (xy 160.780605 -296.55853)
			(xy 160.754302 -296.516934) (xy 160.735011 -296.471658) (xy 160.723234 -296.423874) (xy 160.719274 -296.37482)
			(xy 160.380172 -296.37482) (xy 160.379677 -296.399427) (xy 160.371782 -296.448004) (xy 160.356198 -296.494685)
			(xy 160.333327 -296.538262) (xy 160.303762 -296.577606) (xy 160.268269 -296.611698) (xy 160.227766 -296.639654)
			(xy 160.183304 -296.660752) (xy 160.136033 -296.674444) (xy 160.087178 -296.680376) (xy 160.038003 -296.678395)
			(xy 159.989784 -296.668551) (xy 159.943768 -296.651099) (xy 159.901147 -296.626492) (xy 159.863026 -296.595367)
			(xy 159.830391 -296.55853) (xy 159.804088 -296.516934) (xy 159.784797 -296.471658) (xy 159.77302 -296.423874)
			(xy 159.76906 -296.37482) (xy 158.480252 -296.37482) (xy 158.479757 -296.399427) (xy 158.471862 -296.448004)
			(xy 158.456278 -296.494685) (xy 158.433407 -296.538262) (xy 158.403842 -296.577606) (xy 158.368349 -296.611698)
			(xy 158.327846 -296.639654) (xy 158.283384 -296.660752) (xy 158.236113 -296.674444) (xy 158.187258 -296.680376)
			(xy 158.138083 -296.678395) (xy 158.089864 -296.668551) (xy 158.043848 -296.651099) (xy 158.001227 -296.626492)
			(xy 157.963106 -296.595367) (xy 157.930471 -296.55853) (xy 157.904168 -296.516934) (xy 157.884877 -296.471658)
			(xy 157.8731 -296.423874) (xy 157.86914 -296.37482) (xy 156.580332 -296.37482) (xy 156.579837 -296.399427)
			(xy 156.571942 -296.448004) (xy 156.556358 -296.494685) (xy 156.533487 -296.538262) (xy 156.503922 -296.577606)
			(xy 156.468429 -296.611698) (xy 156.427926 -296.639654) (xy 156.383464 -296.660752) (xy 156.336193 -296.674444)
			(xy 156.287338 -296.680376) (xy 156.238163 -296.678395) (xy 156.189944 -296.668551) (xy 156.143928 -296.651099)
			(xy 156.101307 -296.626492) (xy 156.063186 -296.595367) (xy 156.030551 -296.55853) (xy 156.004248 -296.516934)
			(xy 155.984957 -296.471658) (xy 155.97318 -296.423874) (xy 155.96922 -296.37482) (xy 155.630372 -296.37482)
			(xy 155.629877 -296.399427) (xy 155.621982 -296.448004) (xy 155.606398 -296.494685) (xy 155.583527 -296.538262)
			(xy 155.553962 -296.577606) (xy 155.518469 -296.611698) (xy 155.477966 -296.639654) (xy 155.433504 -296.660752)
			(xy 155.386233 -296.674444) (xy 155.337378 -296.680376) (xy 155.288203 -296.678395) (xy 155.239984 -296.668551)
			(xy 155.193968 -296.651099) (xy 155.151347 -296.626492) (xy 155.113226 -296.595367) (xy 155.080591 -296.55853)
			(xy 155.054288 -296.516934) (xy 155.034997 -296.471658) (xy 155.02322 -296.423874) (xy 155.01926 -296.37482)
			(xy 154.680158 -296.37482) (xy 154.679663 -296.399427) (xy 154.671768 -296.448004) (xy 154.656184 -296.494685)
			(xy 154.633313 -296.538262) (xy 154.603748 -296.577606) (xy 154.568255 -296.611698) (xy 154.527752 -296.639654)
			(xy 154.48329 -296.660752) (xy 154.436019 -296.674444) (xy 154.387164 -296.680376) (xy 154.337989 -296.678395)
			(xy 154.28977 -296.668551) (xy 154.243754 -296.651099) (xy 154.201133 -296.626492) (xy 154.163012 -296.595367)
			(xy 154.130377 -296.55853) (xy 154.104074 -296.516934) (xy 154.084783 -296.471658) (xy 154.073006 -296.423874)
			(xy 154.069046 -296.37482) (xy 153.730452 -296.37482) (xy 153.729957 -296.399427) (xy 153.722062 -296.448004)
			(xy 153.706478 -296.494685) (xy 153.683607 -296.538262) (xy 153.654042 -296.577606) (xy 153.618549 -296.611698)
			(xy 153.578046 -296.639654) (xy 153.533584 -296.660752) (xy 153.486313 -296.674444) (xy 153.437458 -296.680376)
			(xy 153.388283 -296.678395) (xy 153.340064 -296.668551) (xy 153.294048 -296.651099) (xy 153.251427 -296.626492)
			(xy 153.213306 -296.595367) (xy 153.180671 -296.55853) (xy 153.154368 -296.516934) (xy 153.135077 -296.471658)
			(xy 153.1233 -296.423874) (xy 153.11934 -296.37482) (xy 150.309624 -296.37482) (xy 150.325359 -296.384423)
			(xy 150.368227 -296.420098) (xy 150.405444 -296.461635) (xy 150.436217 -296.508148) (xy 150.459889 -296.558645)
			(xy 150.475957 -296.612052) (xy 150.484077 -296.667228) (xy 150.484586 -296.695114) (xy 150.484077 -296.723)
			(xy 150.475957 -296.778176) (xy 150.459889 -296.831583) (xy 150.436217 -296.88208) (xy 150.405444 -296.928593)
			(xy 150.368227 -296.97013) (xy 150.325359 -297.005805) (xy 150.277753 -297.034859) (xy 150.226424 -297.056671)
			(xy 150.172467 -297.070777) (xy 150.11703 -297.076877) (xy 150.061296 -297.07484) (xy 150.006453 -297.06471)
			(xy 149.953669 -297.046703) (xy 149.904069 -297.021202) (xy 149.858711 -296.988751) (xy 149.818562 -296.950042)
			(xy 149.784476 -296.905899) (xy 149.75718 -296.857264) (xy 149.737257 -296.805173) (xy 149.725131 -296.750736)
			(xy 149.72106 -296.695114) (xy 149.598126 -296.695114) (xy 149.597617 -296.723) (xy 149.589497 -296.778176)
			(xy 149.573429 -296.831583) (xy 149.549757 -296.88208) (xy 149.518984 -296.928593) (xy 149.481767 -296.97013)
			(xy 149.438899 -297.005805) (xy 149.391293 -297.034859) (xy 149.339964 -297.056671) (xy 149.286007 -297.070777)
			(xy 149.23057 -297.076877) (xy 149.174836 -297.07484) (xy 149.119993 -297.06471) (xy 149.067209 -297.046703)
			(xy 149.017609 -297.021202) (xy 148.972251 -296.988751) (xy 148.932102 -296.950042) (xy 148.898016 -296.905899)
			(xy 148.87072 -296.857264) (xy 148.850797 -296.805173) (xy 148.838671 -296.750736) (xy 148.8346 -296.695114)
			(xy 148.201126 -296.695114) (xy 148.20064 -296.722365) (xy 148.192884 -296.776313) (xy 148.177529 -296.828608)
			(xy 148.154887 -296.878185) (xy 148.125421 -296.924035) (xy 148.08973 -296.965226) (xy 148.048539 -297.000917)
			(xy 148.002689 -297.030383) (xy 147.953112 -297.053025) (xy 147.900817 -297.06838) (xy 147.846869 -297.076136)
			(xy 147.792367 -297.076136) (xy 147.738419 -297.06838) (xy 147.686124 -297.053025) (xy 147.636547 -297.030383)
			(xy 147.590697 -297.000917) (xy 147.549506 -296.965226) (xy 147.513815 -296.924035) (xy 147.484349 -296.878185)
			(xy 147.461707 -296.828608) (xy 147.446352 -296.776313) (xy 147.438596 -296.722365) (xy 147.43811 -296.695114)
			(xy 118.830852 -296.695114) (xy 118.830852 -297.3248) (xy 151.53402 -297.3248) (xy 151.538192 -297.274451)
			(xy 151.550595 -297.225475) (xy 151.570891 -297.179209) (xy 151.598525 -297.136915) (xy 151.632745 -297.099746)
			(xy 151.672615 -297.068717) (xy 151.71705 -297.044674) (xy 151.764835 -297.028274) (xy 151.814669 -297.019962)
			(xy 151.83993 -297.019472) (xy 151.865324 -297.020012) (xy 151.915412 -297.028419) (xy 151.963419 -297.044996)
			(xy 152.008022 -297.069287) (xy 152.047992 -297.100622) (xy 152.065482 -297.11904) (xy 152.072848 -297.127168)
			(xy 152.092914 -297.135804) (xy 152.192228 -297.13301) (xy 152.211786 -297.123612) (xy 152.218898 -297.114976)
			(xy 152.234711 -297.096425) (xy 152.270839 -297.063704) (xy 152.311375 -297.036635) (xy 152.355443 -297.015803)
			(xy 152.402088 -297.001658) (xy 152.450304 -296.994507) (xy 152.474676 -296.994072) (xy 153.424636 -296.994072)
			(xy 153.45062 -296.994624) (xy 153.501947 -297.002759) (xy 153.55137 -297.018822) (xy 153.597671 -297.042418)
			(xy 153.639712 -297.072967) (xy 153.676457 -297.109715) (xy 153.707001 -297.151759) (xy 153.730592 -297.198064)
			(xy 153.74665 -297.247488) (xy 153.754779 -297.298816) (xy 153.754779 -297.32478) (xy 154.069046 -297.32478)
			(xy 154.073006 -297.275726) (xy 154.084783 -297.227942) (xy 154.104074 -297.182666) (xy 154.130377 -297.14107)
			(xy 154.163012 -297.104233) (xy 154.201133 -297.073108) (xy 154.243754 -297.048501) (xy 154.28977 -297.031049)
			(xy 154.337989 -297.021205) (xy 154.387164 -297.019224) (xy 154.436019 -297.025156) (xy 154.48329 -297.038848)
			(xy 154.527752 -297.059946) (xy 154.568255 -297.087902) (xy 154.603748 -297.121994) (xy 154.633313 -297.161338)
			(xy 154.656184 -297.204915) (xy 154.671768 -297.251596) (xy 154.679663 -297.300173) (xy 154.680158 -297.32478)
			(xy 155.01926 -297.32478) (xy 155.02322 -297.275726) (xy 155.034997 -297.227942) (xy 155.054288 -297.182666)
			(xy 155.080591 -297.14107) (xy 155.113226 -297.104233) (xy 155.151347 -297.073108) (xy 155.193968 -297.048501)
			(xy 155.239984 -297.031049) (xy 155.288203 -297.021205) (xy 155.337378 -297.019224) (xy 155.386233 -297.025156)
			(xy 155.433504 -297.038848) (xy 155.477966 -297.059946) (xy 155.518469 -297.087902) (xy 155.553962 -297.121994)
			(xy 155.583527 -297.161338) (xy 155.606398 -297.204915) (xy 155.621982 -297.251596) (xy 155.629877 -297.300173)
			(xy 155.630372 -297.32478) (xy 157.86914 -297.32478) (xy 157.8731 -297.275726) (xy 157.884877 -297.227942)
			(xy 157.904168 -297.182666) (xy 157.930471 -297.14107) (xy 157.963106 -297.104233) (xy 158.001227 -297.073108)
			(xy 158.043848 -297.048501) (xy 158.089864 -297.031049) (xy 158.138083 -297.021205) (xy 158.187258 -297.019224)
			(xy 158.236113 -297.025156) (xy 158.283384 -297.038848) (xy 158.327846 -297.059946) (xy 158.368349 -297.087902)
			(xy 158.403842 -297.121994) (xy 158.433407 -297.161338) (xy 158.456278 -297.204915) (xy 158.471862 -297.251596)
			(xy 158.479757 -297.300173) (xy 158.480252 -297.32478) (xy 159.76906 -297.32478) (xy 159.77302 -297.275726)
			(xy 159.784797 -297.227942) (xy 159.804088 -297.182666) (xy 159.830391 -297.14107) (xy 159.863026 -297.104233)
			(xy 159.901147 -297.073108) (xy 159.943768 -297.048501) (xy 159.989784 -297.031049) (xy 160.038003 -297.021205)
			(xy 160.087178 -297.019224) (xy 160.136033 -297.025156) (xy 160.183304 -297.038848) (xy 160.227766 -297.059946)
			(xy 160.268269 -297.087902) (xy 160.303762 -297.121994) (xy 160.333327 -297.161338) (xy 160.356198 -297.204915)
			(xy 160.371782 -297.251596) (xy 160.379677 -297.300173) (xy 160.380172 -297.32478) (xy 160.719274 -297.32478)
			(xy 160.723234 -297.275726) (xy 160.735011 -297.227942) (xy 160.754302 -297.182666) (xy 160.780605 -297.14107)
			(xy 160.81324 -297.104233) (xy 160.851361 -297.073108) (xy 160.893982 -297.048501) (xy 160.939998 -297.031049)
			(xy 160.988217 -297.021205) (xy 161.037392 -297.019224) (xy 161.086247 -297.025156) (xy 161.133518 -297.038848)
			(xy 161.17798 -297.059946) (xy 161.218483 -297.087902) (xy 161.253976 -297.121994) (xy 161.283541 -297.161338)
			(xy 161.306412 -297.204915) (xy 161.321996 -297.251596) (xy 161.329891 -297.300173) (xy 161.330386 -297.32478)
			(xy 161.669234 -297.32478) (xy 161.673194 -297.275726) (xy 161.684971 -297.227942) (xy 161.704262 -297.182666)
			(xy 161.730565 -297.14107) (xy 161.7632 -297.104233) (xy 161.801321 -297.073108) (xy 161.843942 -297.048501)
			(xy 161.889958 -297.031049) (xy 161.938177 -297.021205) (xy 161.987352 -297.019224) (xy 162.036207 -297.025156)
			(xy 162.083478 -297.038848) (xy 162.12794 -297.059946) (xy 162.168443 -297.087902) (xy 162.203936 -297.121994)
			(xy 162.233501 -297.161338) (xy 162.256372 -297.204915) (xy 162.271956 -297.251596) (xy 162.279851 -297.300173)
			(xy 162.280346 -297.32478) (xy 162.619194 -297.32478) (xy 162.623154 -297.275726) (xy 162.634931 -297.227942)
			(xy 162.654222 -297.182666) (xy 162.680525 -297.14107) (xy 162.71316 -297.104233) (xy 162.751281 -297.073108)
			(xy 162.793902 -297.048501) (xy 162.839918 -297.031049) (xy 162.888137 -297.021205) (xy 162.937312 -297.019224)
			(xy 162.986167 -297.025156) (xy 163.033438 -297.038848) (xy 163.0779 -297.059946) (xy 163.118403 -297.087902)
			(xy 163.153896 -297.121994) (xy 163.183461 -297.161338) (xy 163.206332 -297.204915) (xy 163.221916 -297.251596)
			(xy 163.229811 -297.300173) (xy 163.230306 -297.32478) (xy 163.569154 -297.32478) (xy 163.573114 -297.275726)
			(xy 163.584891 -297.227942) (xy 163.604182 -297.182666) (xy 163.630485 -297.14107) (xy 163.66312 -297.104233)
			(xy 163.701241 -297.073108) (xy 163.743862 -297.048501) (xy 163.789878 -297.031049) (xy 163.838097 -297.021205)
			(xy 163.887272 -297.019224) (xy 163.936127 -297.025156) (xy 163.983398 -297.038848) (xy 164.02786 -297.059946)
			(xy 164.068363 -297.087902) (xy 164.103856 -297.121994) (xy 164.133421 -297.161338) (xy 164.156292 -297.204915)
			(xy 164.171876 -297.251596) (xy 164.179771 -297.300173) (xy 164.180266 -297.32478) (xy 165.469074 -297.32478)
			(xy 165.473034 -297.275726) (xy 165.484811 -297.227942) (xy 165.504102 -297.182666) (xy 165.530405 -297.14107)
			(xy 165.56304 -297.104233) (xy 165.601161 -297.073108) (xy 165.643782 -297.048501) (xy 165.689798 -297.031049)
			(xy 165.738017 -297.021205) (xy 165.787192 -297.019224) (xy 165.836047 -297.025156) (xy 165.883318 -297.038848)
			(xy 165.92778 -297.059946) (xy 165.968283 -297.087902) (xy 166.003776 -297.121994) (xy 166.033341 -297.161338)
			(xy 166.056212 -297.204915) (xy 166.071796 -297.251596) (xy 166.079691 -297.300173) (xy 166.080186 -297.32478)
			(xy 167.369248 -297.32478) (xy 167.373208 -297.275726) (xy 167.384985 -297.227942) (xy 167.404276 -297.182666)
			(xy 167.430579 -297.14107) (xy 167.463214 -297.104233) (xy 167.501335 -297.073108) (xy 167.543956 -297.048501)
			(xy 167.589972 -297.031049) (xy 167.638191 -297.021205) (xy 167.687366 -297.019224) (xy 167.736221 -297.025156)
			(xy 167.783492 -297.038848) (xy 167.827954 -297.059946) (xy 167.868457 -297.087902) (xy 167.90395 -297.121994)
			(xy 167.933515 -297.161338) (xy 167.956386 -297.204915) (xy 167.97197 -297.251596) (xy 167.979865 -297.300173)
			(xy 167.98036 -297.32478) (xy 169.269168 -297.32478) (xy 169.273128 -297.275726) (xy 169.284905 -297.227942)
			(xy 169.304196 -297.182666) (xy 169.330499 -297.14107) (xy 169.363134 -297.104233) (xy 169.401255 -297.073108)
			(xy 169.443876 -297.048501) (xy 169.489892 -297.031049) (xy 169.538111 -297.021205) (xy 169.587286 -297.019224)
			(xy 169.636141 -297.025156) (xy 169.683412 -297.038848) (xy 169.727874 -297.059946) (xy 169.768377 -297.087902)
			(xy 169.80387 -297.121994) (xy 169.833435 -297.161338) (xy 169.856306 -297.204915) (xy 169.87189 -297.251596)
			(xy 169.879785 -297.300173) (xy 169.88028 -297.32478) (xy 171.169088 -297.32478) (xy 171.173048 -297.275726)
			(xy 171.184825 -297.227942) (xy 171.204116 -297.182666) (xy 171.230419 -297.14107) (xy 171.263054 -297.104233)
			(xy 171.301175 -297.073108) (xy 171.343796 -297.048501) (xy 171.389812 -297.031049) (xy 171.438031 -297.021205)
			(xy 171.487206 -297.019224) (xy 171.536061 -297.025156) (xy 171.583332 -297.038848) (xy 171.627794 -297.059946)
			(xy 171.668297 -297.087902) (xy 171.70379 -297.121994) (xy 171.733355 -297.161338) (xy 171.756226 -297.204915)
			(xy 171.77181 -297.251596) (xy 171.779705 -297.300173) (xy 171.7802 -297.32478) (xy 173.069262 -297.32478)
			(xy 173.073222 -297.275726) (xy 173.084999 -297.227942) (xy 173.10429 -297.182666) (xy 173.130593 -297.14107)
			(xy 173.163228 -297.104233) (xy 173.201349 -297.073108) (xy 173.24397 -297.048501) (xy 173.289986 -297.031049)
			(xy 173.338205 -297.021205) (xy 173.38738 -297.019224) (xy 173.436235 -297.025156) (xy 173.483506 -297.038848)
			(xy 173.527968 -297.059946) (xy 173.568471 -297.087902) (xy 173.603964 -297.121994) (xy 173.633529 -297.161338)
			(xy 173.6564 -297.204915) (xy 173.671984 -297.251596) (xy 173.679879 -297.300173) (xy 173.680374 -297.32478)
			(xy 175.919142 -297.32478) (xy 175.923102 -297.275726) (xy 175.934879 -297.227942) (xy 175.95417 -297.182666)
			(xy 175.980473 -297.14107) (xy 176.013108 -297.104233) (xy 176.051229 -297.073108) (xy 176.09385 -297.048501)
			(xy 176.139866 -297.031049) (xy 176.188085 -297.021205) (xy 176.23726 -297.019224) (xy 176.286115 -297.025156)
			(xy 176.333386 -297.038848) (xy 176.377848 -297.059946) (xy 176.418351 -297.087902) (xy 176.453844 -297.121994)
			(xy 176.483409 -297.161338) (xy 176.50628 -297.204915) (xy 176.521864 -297.251596) (xy 176.529759 -297.300173)
			(xy 176.530254 -297.32478) (xy 177.819062 -297.32478) (xy 177.823022 -297.275726) (xy 177.834799 -297.227942)
			(xy 177.85409 -297.182666) (xy 177.880393 -297.14107) (xy 177.913028 -297.104233) (xy 177.951149 -297.073108)
			(xy 177.99377 -297.048501) (xy 178.039786 -297.031049) (xy 178.088005 -297.021205) (xy 178.13718 -297.019224)
			(xy 178.186035 -297.025156) (xy 178.233306 -297.038848) (xy 178.277768 -297.059946) (xy 178.318271 -297.087902)
			(xy 178.353764 -297.121994) (xy 178.383329 -297.161338) (xy 178.4062 -297.204915) (xy 178.421784 -297.251596)
			(xy 178.429679 -297.300173) (xy 178.430174 -297.32478) (xy 179.719236 -297.32478) (xy 179.723196 -297.275726)
			(xy 179.734973 -297.227942) (xy 179.754264 -297.182666) (xy 179.780567 -297.14107) (xy 179.813202 -297.104233)
			(xy 179.851323 -297.073108) (xy 179.893944 -297.048501) (xy 179.93996 -297.031049) (xy 179.988179 -297.021205)
			(xy 180.037354 -297.019224) (xy 180.086209 -297.025156) (xy 180.13348 -297.038848) (xy 180.177942 -297.059946)
			(xy 180.218445 -297.087902) (xy 180.253938 -297.121994) (xy 180.283503 -297.161338) (xy 180.306374 -297.204915)
			(xy 180.321958 -297.251596) (xy 180.329853 -297.300173) (xy 180.330348 -297.32478) (xy 181.619156 -297.32478)
			(xy 181.623116 -297.275726) (xy 181.634893 -297.227942) (xy 181.654184 -297.182666) (xy 181.680487 -297.14107)
			(xy 181.713122 -297.104233) (xy 181.751243 -297.073108) (xy 181.793864 -297.048501) (xy 181.83988 -297.031049)
			(xy 181.888099 -297.021205) (xy 181.937274 -297.019224) (xy 181.986129 -297.025156) (xy 182.0334 -297.038848)
			(xy 182.077862 -297.059946) (xy 182.118365 -297.087902) (xy 182.153858 -297.121994) (xy 182.183423 -297.161338)
			(xy 182.206294 -297.204915) (xy 182.221878 -297.251596) (xy 182.229773 -297.300173) (xy 182.230268 -297.32478)
			(xy 182.569116 -297.32478) (xy 182.573076 -297.275726) (xy 182.584853 -297.227942) (xy 182.604144 -297.182666)
			(xy 182.630447 -297.14107) (xy 182.663082 -297.104233) (xy 182.701203 -297.073108) (xy 182.743824 -297.048501)
			(xy 182.78984 -297.031049) (xy 182.838059 -297.021205) (xy 182.887234 -297.019224) (xy 182.936089 -297.025156)
			(xy 182.98336 -297.038848) (xy 183.027822 -297.059946) (xy 183.068325 -297.087902) (xy 183.103818 -297.121994)
			(xy 183.133383 -297.161338) (xy 183.156254 -297.204915) (xy 183.171838 -297.251596) (xy 183.179733 -297.300173)
			(xy 183.180228 -297.32478) (xy 183.519076 -297.32478) (xy 183.523036 -297.275726) (xy 183.534813 -297.227942)
			(xy 183.554104 -297.182666) (xy 183.580407 -297.14107) (xy 183.613042 -297.104233) (xy 183.651163 -297.073108)
			(xy 183.693784 -297.048501) (xy 183.7398 -297.031049) (xy 183.788019 -297.021205) (xy 183.837194 -297.019224)
			(xy 183.886049 -297.025156) (xy 183.93332 -297.038848) (xy 183.977782 -297.059946) (xy 184.018285 -297.087902)
			(xy 184.053778 -297.121994) (xy 184.083343 -297.161338) (xy 184.106214 -297.204915) (xy 184.121798 -297.251596)
			(xy 184.129693 -297.300173) (xy 184.130188 -297.32478) (xy 184.129693 -297.349387) (xy 184.121798 -297.397964)
			(xy 184.106214 -297.444645) (xy 184.083343 -297.488222) (xy 184.053778 -297.527566) (xy 184.018285 -297.561658)
			(xy 183.977782 -297.589614) (xy 183.93332 -297.610712) (xy 183.886049 -297.624404) (xy 183.837194 -297.630336)
			(xy 183.788019 -297.628355) (xy 183.7398 -297.618511) (xy 183.693784 -297.601059) (xy 183.651163 -297.576452)
			(xy 183.613042 -297.545327) (xy 183.580407 -297.50849) (xy 183.554104 -297.466894) (xy 183.534813 -297.421618)
			(xy 183.523036 -297.373834) (xy 183.519076 -297.32478) (xy 183.180228 -297.32478) (xy 183.179733 -297.349387)
			(xy 183.171838 -297.397964) (xy 183.156254 -297.444645) (xy 183.133383 -297.488222) (xy 183.103818 -297.527566)
			(xy 183.068325 -297.561658) (xy 183.027822 -297.589614) (xy 182.98336 -297.610712) (xy 182.936089 -297.624404)
			(xy 182.887234 -297.630336) (xy 182.838059 -297.628355) (xy 182.78984 -297.618511) (xy 182.743824 -297.601059)
			(xy 182.701203 -297.576452) (xy 182.663082 -297.545327) (xy 182.630447 -297.50849) (xy 182.604144 -297.466894)
			(xy 182.584853 -297.421618) (xy 182.573076 -297.373834) (xy 182.569116 -297.32478) (xy 182.230268 -297.32478)
			(xy 182.229773 -297.349387) (xy 182.221878 -297.397964) (xy 182.206294 -297.444645) (xy 182.183423 -297.488222)
			(xy 182.153858 -297.527566) (xy 182.118365 -297.561658) (xy 182.077862 -297.589614) (xy 182.0334 -297.610712)
			(xy 181.986129 -297.624404) (xy 181.937274 -297.630336) (xy 181.888099 -297.628355) (xy 181.83988 -297.618511)
			(xy 181.793864 -297.601059) (xy 181.751243 -297.576452) (xy 181.713122 -297.545327) (xy 181.680487 -297.50849)
			(xy 181.654184 -297.466894) (xy 181.634893 -297.421618) (xy 181.623116 -297.373834) (xy 181.619156 -297.32478)
			(xy 180.330348 -297.32478) (xy 180.329853 -297.349387) (xy 180.321958 -297.397964) (xy 180.306374 -297.444645)
			(xy 180.283503 -297.488222) (xy 180.253938 -297.527566) (xy 180.218445 -297.561658) (xy 180.177942 -297.589614)
			(xy 180.13348 -297.610712) (xy 180.086209 -297.624404) (xy 180.037354 -297.630336) (xy 179.988179 -297.628355)
			(xy 179.93996 -297.618511) (xy 179.893944 -297.601059) (xy 179.851323 -297.576452) (xy 179.813202 -297.545327)
			(xy 179.780567 -297.50849) (xy 179.754264 -297.466894) (xy 179.734973 -297.421618) (xy 179.723196 -297.373834)
			(xy 179.719236 -297.32478) (xy 178.430174 -297.32478) (xy 178.429679 -297.349387) (xy 178.421784 -297.397964)
			(xy 178.4062 -297.444645) (xy 178.383329 -297.488222) (xy 178.353764 -297.527566) (xy 178.318271 -297.561658)
			(xy 178.277768 -297.589614) (xy 178.233306 -297.610712) (xy 178.186035 -297.624404) (xy 178.13718 -297.630336)
			(xy 178.088005 -297.628355) (xy 178.039786 -297.618511) (xy 177.99377 -297.601059) (xy 177.951149 -297.576452)
			(xy 177.913028 -297.545327) (xy 177.880393 -297.50849) (xy 177.85409 -297.466894) (xy 177.834799 -297.421618)
			(xy 177.823022 -297.373834) (xy 177.819062 -297.32478) (xy 176.530254 -297.32478) (xy 176.529759 -297.349387)
			(xy 176.521864 -297.397964) (xy 176.50628 -297.444645) (xy 176.483409 -297.488222) (xy 176.453844 -297.527566)
			(xy 176.418351 -297.561658) (xy 176.377848 -297.589614) (xy 176.333386 -297.610712) (xy 176.286115 -297.624404)
			(xy 176.23726 -297.630336) (xy 176.188085 -297.628355) (xy 176.139866 -297.618511) (xy 176.09385 -297.601059)
			(xy 176.051229 -297.576452) (xy 176.013108 -297.545327) (xy 175.980473 -297.50849) (xy 175.95417 -297.466894)
			(xy 175.934879 -297.421618) (xy 175.923102 -297.373834) (xy 175.919142 -297.32478) (xy 173.680374 -297.32478)
			(xy 173.679879 -297.349387) (xy 173.671984 -297.397964) (xy 173.6564 -297.444645) (xy 173.633529 -297.488222)
			(xy 173.603964 -297.527566) (xy 173.568471 -297.561658) (xy 173.527968 -297.589614) (xy 173.483506 -297.610712)
			(xy 173.436235 -297.624404) (xy 173.38738 -297.630336) (xy 173.338205 -297.628355) (xy 173.289986 -297.618511)
			(xy 173.24397 -297.601059) (xy 173.201349 -297.576452) (xy 173.163228 -297.545327) (xy 173.130593 -297.50849)
			(xy 173.10429 -297.466894) (xy 173.084999 -297.421618) (xy 173.073222 -297.373834) (xy 173.069262 -297.32478)
			(xy 171.7802 -297.32478) (xy 171.779705 -297.349387) (xy 171.77181 -297.397964) (xy 171.756226 -297.444645)
			(xy 171.733355 -297.488222) (xy 171.70379 -297.527566) (xy 171.668297 -297.561658) (xy 171.627794 -297.589614)
			(xy 171.583332 -297.610712) (xy 171.536061 -297.624404) (xy 171.487206 -297.630336) (xy 171.438031 -297.628355)
			(xy 171.389812 -297.618511) (xy 171.343796 -297.601059) (xy 171.301175 -297.576452) (xy 171.263054 -297.545327)
			(xy 171.230419 -297.50849) (xy 171.204116 -297.466894) (xy 171.184825 -297.421618) (xy 171.173048 -297.373834)
			(xy 171.169088 -297.32478) (xy 169.88028 -297.32478) (xy 169.879785 -297.349387) (xy 169.87189 -297.397964)
			(xy 169.856306 -297.444645) (xy 169.833435 -297.488222) (xy 169.80387 -297.527566) (xy 169.768377 -297.561658)
			(xy 169.727874 -297.589614) (xy 169.683412 -297.610712) (xy 169.636141 -297.624404) (xy 169.587286 -297.630336)
			(xy 169.538111 -297.628355) (xy 169.489892 -297.618511) (xy 169.443876 -297.601059) (xy 169.401255 -297.576452)
			(xy 169.363134 -297.545327) (xy 169.330499 -297.50849) (xy 169.304196 -297.466894) (xy 169.284905 -297.421618)
			(xy 169.273128 -297.373834) (xy 169.269168 -297.32478) (xy 167.98036 -297.32478) (xy 167.979865 -297.349387)
			(xy 167.97197 -297.397964) (xy 167.956386 -297.444645) (xy 167.933515 -297.488222) (xy 167.90395 -297.527566)
			(xy 167.868457 -297.561658) (xy 167.827954 -297.589614) (xy 167.783492 -297.610712) (xy 167.736221 -297.624404)
			(xy 167.687366 -297.630336) (xy 167.638191 -297.628355) (xy 167.589972 -297.618511) (xy 167.543956 -297.601059)
			(xy 167.501335 -297.576452) (xy 167.463214 -297.545327) (xy 167.430579 -297.50849) (xy 167.404276 -297.466894)
			(xy 167.384985 -297.421618) (xy 167.373208 -297.373834) (xy 167.369248 -297.32478) (xy 166.080186 -297.32478)
			(xy 166.079691 -297.349387) (xy 166.071796 -297.397964) (xy 166.056212 -297.444645) (xy 166.033341 -297.488222)
			(xy 166.003776 -297.527566) (xy 165.968283 -297.561658) (xy 165.92778 -297.589614) (xy 165.883318 -297.610712)
			(xy 165.836047 -297.624404) (xy 165.787192 -297.630336) (xy 165.738017 -297.628355) (xy 165.689798 -297.618511)
			(xy 165.643782 -297.601059) (xy 165.601161 -297.576452) (xy 165.56304 -297.545327) (xy 165.530405 -297.50849)
			(xy 165.504102 -297.466894) (xy 165.484811 -297.421618) (xy 165.473034 -297.373834) (xy 165.469074 -297.32478)
			(xy 164.180266 -297.32478) (xy 164.179771 -297.349387) (xy 164.171876 -297.397964) (xy 164.156292 -297.444645)
			(xy 164.133421 -297.488222) (xy 164.103856 -297.527566) (xy 164.068363 -297.561658) (xy 164.02786 -297.589614)
			(xy 163.983398 -297.610712) (xy 163.936127 -297.624404) (xy 163.887272 -297.630336) (xy 163.838097 -297.628355)
			(xy 163.789878 -297.618511) (xy 163.743862 -297.601059) (xy 163.701241 -297.576452) (xy 163.66312 -297.545327)
			(xy 163.630485 -297.50849) (xy 163.604182 -297.466894) (xy 163.584891 -297.421618) (xy 163.573114 -297.373834)
			(xy 163.569154 -297.32478) (xy 163.230306 -297.32478) (xy 163.229811 -297.349387) (xy 163.221916 -297.397964)
			(xy 163.206332 -297.444645) (xy 163.183461 -297.488222) (xy 163.153896 -297.527566) (xy 163.118403 -297.561658)
			(xy 163.0779 -297.589614) (xy 163.033438 -297.610712) (xy 162.986167 -297.624404) (xy 162.937312 -297.630336)
			(xy 162.888137 -297.628355) (xy 162.839918 -297.618511) (xy 162.793902 -297.601059) (xy 162.751281 -297.576452)
			(xy 162.71316 -297.545327) (xy 162.680525 -297.50849) (xy 162.654222 -297.466894) (xy 162.634931 -297.421618)
			(xy 162.623154 -297.373834) (xy 162.619194 -297.32478) (xy 162.280346 -297.32478) (xy 162.279851 -297.349387)
			(xy 162.271956 -297.397964) (xy 162.256372 -297.444645) (xy 162.233501 -297.488222) (xy 162.203936 -297.527566)
			(xy 162.168443 -297.561658) (xy 162.12794 -297.589614) (xy 162.083478 -297.610712) (xy 162.036207 -297.624404)
			(xy 161.987352 -297.630336) (xy 161.938177 -297.628355) (xy 161.889958 -297.618511) (xy 161.843942 -297.601059)
			(xy 161.801321 -297.576452) (xy 161.7632 -297.545327) (xy 161.730565 -297.50849) (xy 161.704262 -297.466894)
			(xy 161.684971 -297.421618) (xy 161.673194 -297.373834) (xy 161.669234 -297.32478) (xy 161.330386 -297.32478)
			(xy 161.329891 -297.349387) (xy 161.321996 -297.397964) (xy 161.306412 -297.444645) (xy 161.283541 -297.488222)
			(xy 161.253976 -297.527566) (xy 161.218483 -297.561658) (xy 161.17798 -297.589614) (xy 161.133518 -297.610712)
			(xy 161.086247 -297.624404) (xy 161.037392 -297.630336) (xy 160.988217 -297.628355) (xy 160.939998 -297.618511)
			(xy 160.893982 -297.601059) (xy 160.851361 -297.576452) (xy 160.81324 -297.545327) (xy 160.780605 -297.50849)
			(xy 160.754302 -297.466894) (xy 160.735011 -297.421618) (xy 160.723234 -297.373834) (xy 160.719274 -297.32478)
			(xy 160.380172 -297.32478) (xy 160.379677 -297.349387) (xy 160.371782 -297.397964) (xy 160.356198 -297.444645)
			(xy 160.333327 -297.488222) (xy 160.303762 -297.527566) (xy 160.268269 -297.561658) (xy 160.227766 -297.589614)
			(xy 160.183304 -297.610712) (xy 160.136033 -297.624404) (xy 160.087178 -297.630336) (xy 160.038003 -297.628355)
			(xy 159.989784 -297.618511) (xy 159.943768 -297.601059) (xy 159.901147 -297.576452) (xy 159.863026 -297.545327)
			(xy 159.830391 -297.50849) (xy 159.804088 -297.466894) (xy 159.784797 -297.421618) (xy 159.77302 -297.373834)
			(xy 159.76906 -297.32478) (xy 158.480252 -297.32478) (xy 158.479757 -297.349387) (xy 158.471862 -297.397964)
			(xy 158.456278 -297.444645) (xy 158.433407 -297.488222) (xy 158.403842 -297.527566) (xy 158.368349 -297.561658)
			(xy 158.327846 -297.589614) (xy 158.283384 -297.610712) (xy 158.236113 -297.624404) (xy 158.187258 -297.630336)
			(xy 158.138083 -297.628355) (xy 158.089864 -297.618511) (xy 158.043848 -297.601059) (xy 158.001227 -297.576452)
			(xy 157.963106 -297.545327) (xy 157.930471 -297.50849) (xy 157.904168 -297.466894) (xy 157.884877 -297.421618)
			(xy 157.8731 -297.373834) (xy 157.86914 -297.32478) (xy 155.630372 -297.32478) (xy 155.629877 -297.349387)
			(xy 155.621982 -297.397964) (xy 155.606398 -297.444645) (xy 155.583527 -297.488222) (xy 155.553962 -297.527566)
			(xy 155.518469 -297.561658) (xy 155.477966 -297.589614) (xy 155.433504 -297.610712) (xy 155.386233 -297.624404)
			(xy 155.337378 -297.630336) (xy 155.288203 -297.628355) (xy 155.239984 -297.618511) (xy 155.193968 -297.601059)
			(xy 155.151347 -297.576452) (xy 155.113226 -297.545327) (xy 155.080591 -297.50849) (xy 155.054288 -297.466894)
			(xy 155.034997 -297.421618) (xy 155.02322 -297.373834) (xy 155.01926 -297.32478) (xy 154.680158 -297.32478)
			(xy 154.679663 -297.349387) (xy 154.671768 -297.397964) (xy 154.656184 -297.444645) (xy 154.633313 -297.488222)
			(xy 154.603748 -297.527566) (xy 154.568255 -297.561658) (xy 154.527752 -297.589614) (xy 154.48329 -297.610712)
			(xy 154.436019 -297.624404) (xy 154.387164 -297.630336) (xy 154.337989 -297.628355) (xy 154.28977 -297.618511)
			(xy 154.243754 -297.601059) (xy 154.201133 -297.576452) (xy 154.163012 -297.545327) (xy 154.130377 -297.50849)
			(xy 154.104074 -297.466894) (xy 154.084783 -297.421618) (xy 154.073006 -297.373834) (xy 154.069046 -297.32478)
			(xy 153.754779 -297.32478) (xy 153.754779 -297.350784) (xy 153.74665 -297.402112) (xy 153.730592 -297.451536)
			(xy 153.707001 -297.497841) (xy 153.676457 -297.539885) (xy 153.639712 -297.576633) (xy 153.597671 -297.607182)
			(xy 153.55137 -297.630778) (xy 153.501947 -297.646841) (xy 153.45062 -297.654976) (xy 153.424636 -297.655488)
			(xy 152.474676 -297.655488) (xy 152.450304 -297.655045) (xy 152.402085 -297.647904) (xy 152.355436 -297.633766)
			(xy 152.311365 -297.612937) (xy 152.270828 -297.585868) (xy 152.234701 -297.553144) (xy 152.218898 -297.534584)
			(xy 152.211527 -297.526557) (xy 152.191922 -297.517084) (xy 152.181052 -297.516296) (xy 152.092914 -297.513756)
			(xy 152.072848 -297.522392) (xy 152.065482 -297.53052) (xy 152.048017 -297.548966) (xy 152.008048 -297.580314)
			(xy 151.96344 -297.604613) (xy 151.915425 -297.62119) (xy 151.865328 -297.629589) (xy 151.83993 -297.630088)
			(xy 151.814669 -297.629638) (xy 151.764835 -297.621326) (xy 151.71705 -297.604926) (xy 151.672615 -297.580883)
			(xy 151.632745 -297.549854) (xy 151.598525 -297.512685) (xy 151.570891 -297.470391) (xy 151.550595 -297.424125)
			(xy 151.538192 -297.375149) (xy 151.53402 -297.3248) (xy 118.830852 -297.3248) (xy 118.830852 -297.831256)
			(xy 141.911576 -297.831256) (xy 141.915647 -297.775634) (xy 141.927773 -297.721197) (xy 141.947696 -297.669106)
			(xy 141.974992 -297.620471) (xy 142.009078 -297.576328) (xy 142.049227 -297.537619) (xy 142.094585 -297.505168)
			(xy 142.144185 -297.479667) (xy 142.196969 -297.46166) (xy 142.251812 -297.45153) (xy 142.307546 -297.449493)
			(xy 142.362983 -297.455593) (xy 142.41694 -297.469699) (xy 142.468269 -297.491511) (xy 142.515875 -297.520565)
			(xy 142.558743 -297.55624) (xy 142.59596 -297.597777) (xy 142.626733 -297.64429) (xy 142.650405 -297.694787)
			(xy 142.666473 -297.748194) (xy 142.674593 -297.80337) (xy 142.675102 -297.831256) (xy 143.396714 -297.831256)
			(xy 143.400785 -297.775634) (xy 143.412911 -297.721197) (xy 143.432834 -297.669106) (xy 143.46013 -297.620471)
			(xy 143.494216 -297.576328) (xy 143.534365 -297.537619) (xy 143.579723 -297.505168) (xy 143.629323 -297.479667)
			(xy 143.682107 -297.46166) (xy 143.73695 -297.45153) (xy 143.792684 -297.449493) (xy 143.848121 -297.455593)
			(xy 143.902078 -297.469699) (xy 143.953407 -297.491511) (xy 144.001013 -297.520565) (xy 144.043881 -297.55624)
			(xy 144.081098 -297.597777) (xy 144.111871 -297.64429) (xy 144.135543 -297.694787) (xy 144.151611 -297.748194)
			(xy 144.159731 -297.80337) (xy 144.16024 -297.831256) (xy 144.159731 -297.859142) (xy 144.151611 -297.914318)
			(xy 144.135543 -297.967725) (xy 144.111871 -298.018222) (xy 144.081098 -298.064735) (xy 144.043881 -298.106272)
			(xy 144.001013 -298.141947) (xy 143.953407 -298.171001) (xy 143.902078 -298.192813) (xy 143.848121 -298.206919)
			(xy 143.792684 -298.213019) (xy 143.73695 -298.210982) (xy 143.682107 -298.200852) (xy 143.629323 -298.182845)
			(xy 143.579723 -298.157344) (xy 143.534365 -298.124893) (xy 143.494216 -298.086184) (xy 143.46013 -298.042041)
			(xy 143.432834 -297.993406) (xy 143.412911 -297.941315) (xy 143.400785 -297.886878) (xy 143.396714 -297.831256)
			(xy 142.675102 -297.831256) (xy 142.674593 -297.859142) (xy 142.666473 -297.914318) (xy 142.650405 -297.967725)
			(xy 142.626733 -298.018222) (xy 142.59596 -298.064735) (xy 142.558743 -298.106272) (xy 142.515875 -298.141947)
			(xy 142.468269 -298.171001) (xy 142.41694 -298.192813) (xy 142.362983 -298.206919) (xy 142.307546 -298.213019)
			(xy 142.251812 -298.210982) (xy 142.196969 -298.200852) (xy 142.144185 -298.182845) (xy 142.094585 -298.157344)
			(xy 142.049227 -298.124893) (xy 142.009078 -298.086184) (xy 141.974992 -298.042041) (xy 141.947696 -297.993406)
			(xy 141.927773 -297.941315) (xy 141.915647 -297.886878) (xy 141.911576 -297.831256) (xy 118.830852 -297.831256)
			(xy 118.830852 -298.27474) (xy 153.118832 -298.27474) (xy 153.122792 -298.225686) (xy 153.134569 -298.177902)
			(xy 153.15386 -298.132626) (xy 153.180163 -298.09103) (xy 153.212798 -298.054193) (xy 153.250919 -298.023068)
			(xy 153.29354 -297.998461) (xy 153.339556 -297.981009) (xy 153.387775 -297.971165) (xy 153.43695 -297.969184)
			(xy 153.485805 -297.975116) (xy 153.533076 -297.988808) (xy 153.577538 -298.009906) (xy 153.618041 -298.037862)
			(xy 153.653534 -298.071954) (xy 153.683099 -298.111298) (xy 153.70597 -298.154875) (xy 153.721554 -298.201556)
			(xy 153.729449 -298.250133) (xy 153.729944 -298.27474) (xy 154.069046 -298.27474) (xy 154.073006 -298.225686)
			(xy 154.084783 -298.177902) (xy 154.104074 -298.132626) (xy 154.130377 -298.09103) (xy 154.163012 -298.054193)
			(xy 154.201133 -298.023068) (xy 154.243754 -297.998461) (xy 154.28977 -297.981009) (xy 154.337989 -297.971165)
			(xy 154.387164 -297.969184) (xy 154.436019 -297.975116) (xy 154.48329 -297.988808) (xy 154.527752 -298.009906)
			(xy 154.568255 -298.037862) (xy 154.603748 -298.071954) (xy 154.633313 -298.111298) (xy 154.656184 -298.154875)
			(xy 154.671768 -298.201556) (xy 154.679663 -298.250133) (xy 154.680158 -298.27474) (xy 155.01926 -298.27474)
			(xy 155.02322 -298.225686) (xy 155.034997 -298.177902) (xy 155.054288 -298.132626) (xy 155.080591 -298.09103)
			(xy 155.113226 -298.054193) (xy 155.151347 -298.023068) (xy 155.193968 -297.998461) (xy 155.239984 -297.981009)
			(xy 155.288203 -297.971165) (xy 155.337378 -297.969184) (xy 155.386233 -297.975116) (xy 155.433504 -297.988808)
			(xy 155.477966 -298.009906) (xy 155.518469 -298.037862) (xy 155.553962 -298.071954) (xy 155.583527 -298.111298)
			(xy 155.606398 -298.154875) (xy 155.621982 -298.201556) (xy 155.629877 -298.250133) (xy 155.630372 -298.27474)
			(xy 155.96922 -298.27474) (xy 155.97318 -298.225686) (xy 155.984957 -298.177902) (xy 156.004248 -298.132626)
			(xy 156.030551 -298.09103) (xy 156.063186 -298.054193) (xy 156.101307 -298.023068) (xy 156.143928 -297.998461)
			(xy 156.189944 -297.981009) (xy 156.238163 -297.971165) (xy 156.287338 -297.969184) (xy 156.336193 -297.975116)
			(xy 156.383464 -297.988808) (xy 156.427926 -298.009906) (xy 156.468429 -298.037862) (xy 156.503922 -298.071954)
			(xy 156.533487 -298.111298) (xy 156.556358 -298.154875) (xy 156.571942 -298.201556) (xy 156.579837 -298.250133)
			(xy 156.580332 -298.27474) (xy 156.91918 -298.27474) (xy 156.92314 -298.225686) (xy 156.934917 -298.177902)
			(xy 156.954208 -298.132626) (xy 156.980511 -298.09103) (xy 157.013146 -298.054193) (xy 157.051267 -298.023068)
			(xy 157.093888 -297.998461) (xy 157.139904 -297.981009) (xy 157.188123 -297.971165) (xy 157.237298 -297.969184)
			(xy 157.286153 -297.975116) (xy 157.333424 -297.988808) (xy 157.377886 -298.009906) (xy 157.418389 -298.037862)
			(xy 157.453882 -298.071954) (xy 157.483447 -298.111298) (xy 157.506318 -298.154875) (xy 157.521902 -298.201556)
			(xy 157.529797 -298.250133) (xy 157.530292 -298.27474) (xy 157.86914 -298.27474) (xy 157.8731 -298.225686)
			(xy 157.884877 -298.177902) (xy 157.904168 -298.132626) (xy 157.930471 -298.09103) (xy 157.963106 -298.054193)
			(xy 158.001227 -298.023068) (xy 158.043848 -297.998461) (xy 158.089864 -297.981009) (xy 158.138083 -297.971165)
			(xy 158.187258 -297.969184) (xy 158.236113 -297.975116) (xy 158.283384 -297.988808) (xy 158.327846 -298.009906)
			(xy 158.368349 -298.037862) (xy 158.403842 -298.071954) (xy 158.433407 -298.111298) (xy 158.456278 -298.154875)
			(xy 158.471862 -298.201556) (xy 158.479757 -298.250133) (xy 158.480252 -298.27474) (xy 159.76906 -298.27474)
			(xy 159.77302 -298.225686) (xy 159.784797 -298.177902) (xy 159.804088 -298.132626) (xy 159.830391 -298.09103)
			(xy 159.863026 -298.054193) (xy 159.901147 -298.023068) (xy 159.943768 -297.998461) (xy 159.989784 -297.981009)
			(xy 160.038003 -297.971165) (xy 160.087178 -297.969184) (xy 160.136033 -297.975116) (xy 160.183304 -297.988808)
			(xy 160.227766 -298.009906) (xy 160.268269 -298.037862) (xy 160.303762 -298.071954) (xy 160.333327 -298.111298)
			(xy 160.356198 -298.154875) (xy 160.371782 -298.201556) (xy 160.379677 -298.250133) (xy 160.380172 -298.27474)
			(xy 160.719274 -298.27474) (xy 160.723234 -298.225686) (xy 160.735011 -298.177902) (xy 160.754302 -298.132626)
			(xy 160.780605 -298.09103) (xy 160.81324 -298.054193) (xy 160.851361 -298.023068) (xy 160.893982 -297.998461)
			(xy 160.939998 -297.981009) (xy 160.988217 -297.971165) (xy 161.037392 -297.969184) (xy 161.086247 -297.975116)
			(xy 161.133518 -297.988808) (xy 161.17798 -298.009906) (xy 161.218483 -298.037862) (xy 161.253976 -298.071954)
			(xy 161.283541 -298.111298) (xy 161.306412 -298.154875) (xy 161.321996 -298.201556) (xy 161.329891 -298.250133)
			(xy 161.330386 -298.27474) (xy 161.669234 -298.27474) (xy 161.673194 -298.225686) (xy 161.684971 -298.177902)
			(xy 161.704262 -298.132626) (xy 161.730565 -298.09103) (xy 161.7632 -298.054193) (xy 161.801321 -298.023068)
			(xy 161.843942 -297.998461) (xy 161.889958 -297.981009) (xy 161.938177 -297.971165) (xy 161.987352 -297.969184)
			(xy 162.036207 -297.975116) (xy 162.083478 -297.988808) (xy 162.12794 -298.009906) (xy 162.168443 -298.037862)
			(xy 162.203936 -298.071954) (xy 162.233501 -298.111298) (xy 162.256372 -298.154875) (xy 162.271956 -298.201556)
			(xy 162.279851 -298.250133) (xy 162.280346 -298.27474) (xy 163.569154 -298.27474) (xy 163.573114 -298.225686)
			(xy 163.584891 -298.177902) (xy 163.604182 -298.132626) (xy 163.630485 -298.09103) (xy 163.66312 -298.054193)
			(xy 163.701241 -298.023068) (xy 163.743862 -297.998461) (xy 163.789878 -297.981009) (xy 163.838097 -297.971165)
			(xy 163.887272 -297.969184) (xy 163.936127 -297.975116) (xy 163.983398 -297.988808) (xy 164.02786 -298.009906)
			(xy 164.068363 -298.037862) (xy 164.103856 -298.071954) (xy 164.133421 -298.111298) (xy 164.156292 -298.154875)
			(xy 164.171876 -298.201556) (xy 164.179771 -298.250133) (xy 164.180266 -298.27474) (xy 164.519114 -298.27474)
			(xy 164.523074 -298.225686) (xy 164.534851 -298.177902) (xy 164.554142 -298.132626) (xy 164.580445 -298.09103)
			(xy 164.61308 -298.054193) (xy 164.651201 -298.023068) (xy 164.693822 -297.998461) (xy 164.739838 -297.981009)
			(xy 164.788057 -297.971165) (xy 164.837232 -297.969184) (xy 164.886087 -297.975116) (xy 164.933358 -297.988808)
			(xy 164.97782 -298.009906) (xy 165.018323 -298.037862) (xy 165.053816 -298.071954) (xy 165.083381 -298.111298)
			(xy 165.106252 -298.154875) (xy 165.121836 -298.201556) (xy 165.129731 -298.250133) (xy 165.130226 -298.27474)
			(xy 165.129731 -298.299347) (xy 165.121836 -298.347924) (xy 165.106252 -298.394605) (xy 165.083381 -298.438182)
			(xy 165.053816 -298.477526) (xy 165.018323 -298.511618) (xy 164.97782 -298.539574) (xy 164.933358 -298.560672)
			(xy 164.886087 -298.574364) (xy 164.837232 -298.580296) (xy 164.788057 -298.578315) (xy 164.739838 -298.568471)
			(xy 164.693822 -298.551019) (xy 164.651201 -298.526412) (xy 164.61308 -298.495287) (xy 164.580445 -298.45845)
			(xy 164.554142 -298.416854) (xy 164.534851 -298.371578) (xy 164.523074 -298.323794) (xy 164.519114 -298.27474)
			(xy 164.180266 -298.27474) (xy 164.179771 -298.299347) (xy 164.171876 -298.347924) (xy 164.156292 -298.394605)
			(xy 164.133421 -298.438182) (xy 164.103856 -298.477526) (xy 164.068363 -298.511618) (xy 164.02786 -298.539574)
			(xy 163.983398 -298.560672) (xy 163.936127 -298.574364) (xy 163.887272 -298.580296) (xy 163.838097 -298.578315)
			(xy 163.789878 -298.568471) (xy 163.743862 -298.551019) (xy 163.701241 -298.526412) (xy 163.66312 -298.495287)
			(xy 163.630485 -298.45845) (xy 163.604182 -298.416854) (xy 163.584891 -298.371578) (xy 163.573114 -298.323794)
			(xy 163.569154 -298.27474) (xy 162.280346 -298.27474) (xy 162.279851 -298.299347) (xy 162.271956 -298.347924)
			(xy 162.256372 -298.394605) (xy 162.233501 -298.438182) (xy 162.203936 -298.477526) (xy 162.168443 -298.511618)
			(xy 162.12794 -298.539574) (xy 162.083478 -298.560672) (xy 162.036207 -298.574364) (xy 161.987352 -298.580296)
			(xy 161.938177 -298.578315) (xy 161.889958 -298.568471) (xy 161.843942 -298.551019) (xy 161.801321 -298.526412)
			(xy 161.7632 -298.495287) (xy 161.730565 -298.45845) (xy 161.704262 -298.416854) (xy 161.684971 -298.371578)
			(xy 161.673194 -298.323794) (xy 161.669234 -298.27474) (xy 161.330386 -298.27474) (xy 161.329891 -298.299347)
			(xy 161.321996 -298.347924) (xy 161.306412 -298.394605) (xy 161.283541 -298.438182) (xy 161.253976 -298.477526)
			(xy 161.218483 -298.511618) (xy 161.17798 -298.539574) (xy 161.133518 -298.560672) (xy 161.086247 -298.574364)
			(xy 161.037392 -298.580296) (xy 160.988217 -298.578315) (xy 160.939998 -298.568471) (xy 160.893982 -298.551019)
			(xy 160.851361 -298.526412) (xy 160.81324 -298.495287) (xy 160.780605 -298.45845) (xy 160.754302 -298.416854)
			(xy 160.735011 -298.371578) (xy 160.723234 -298.323794) (xy 160.719274 -298.27474) (xy 160.380172 -298.27474)
			(xy 160.379677 -298.299347) (xy 160.371782 -298.347924) (xy 160.356198 -298.394605) (xy 160.333327 -298.438182)
			(xy 160.303762 -298.477526) (xy 160.268269 -298.511618) (xy 160.227766 -298.539574) (xy 160.183304 -298.560672)
			(xy 160.136033 -298.574364) (xy 160.087178 -298.580296) (xy 160.038003 -298.578315) (xy 159.989784 -298.568471)
			(xy 159.943768 -298.551019) (xy 159.901147 -298.526412) (xy 159.863026 -298.495287) (xy 159.830391 -298.45845)
			(xy 159.804088 -298.416854) (xy 159.784797 -298.371578) (xy 159.77302 -298.323794) (xy 159.76906 -298.27474)
			(xy 158.480252 -298.27474) (xy 158.479757 -298.299347) (xy 158.471862 -298.347924) (xy 158.456278 -298.394605)
			(xy 158.433407 -298.438182) (xy 158.403842 -298.477526) (xy 158.368349 -298.511618) (xy 158.327846 -298.539574)
			(xy 158.283384 -298.560672) (xy 158.236113 -298.574364) (xy 158.187258 -298.580296) (xy 158.138083 -298.578315)
			(xy 158.089864 -298.568471) (xy 158.043848 -298.551019) (xy 158.001227 -298.526412) (xy 157.963106 -298.495287)
			(xy 157.930471 -298.45845) (xy 157.904168 -298.416854) (xy 157.884877 -298.371578) (xy 157.8731 -298.323794)
			(xy 157.86914 -298.27474) (xy 157.530292 -298.27474) (xy 157.529797 -298.299347) (xy 157.521902 -298.347924)
			(xy 157.506318 -298.394605) (xy 157.483447 -298.438182) (xy 157.453882 -298.477526) (xy 157.418389 -298.511618)
			(xy 157.377886 -298.539574) (xy 157.333424 -298.560672) (xy 157.286153 -298.574364) (xy 157.237298 -298.580296)
			(xy 157.188123 -298.578315) (xy 157.139904 -298.568471) (xy 157.093888 -298.551019) (xy 157.051267 -298.526412)
			(xy 157.013146 -298.495287) (xy 156.980511 -298.45845) (xy 156.954208 -298.416854) (xy 156.934917 -298.371578)
			(xy 156.92314 -298.323794) (xy 156.91918 -298.27474) (xy 156.580332 -298.27474) (xy 156.579837 -298.299347)
			(xy 156.571942 -298.347924) (xy 156.556358 -298.394605) (xy 156.533487 -298.438182) (xy 156.503922 -298.477526)
			(xy 156.468429 -298.511618) (xy 156.427926 -298.539574) (xy 156.383464 -298.560672) (xy 156.336193 -298.574364)
			(xy 156.287338 -298.580296) (xy 156.238163 -298.578315) (xy 156.189944 -298.568471) (xy 156.143928 -298.551019)
			(xy 156.101307 -298.526412) (xy 156.063186 -298.495287) (xy 156.030551 -298.45845) (xy 156.004248 -298.416854)
			(xy 155.984957 -298.371578) (xy 155.97318 -298.323794) (xy 155.96922 -298.27474) (xy 155.630372 -298.27474)
			(xy 155.629877 -298.299347) (xy 155.621982 -298.347924) (xy 155.606398 -298.394605) (xy 155.583527 -298.438182)
			(xy 155.553962 -298.477526) (xy 155.518469 -298.511618) (xy 155.477966 -298.539574) (xy 155.433504 -298.560672)
			(xy 155.386233 -298.574364) (xy 155.337378 -298.580296) (xy 155.288203 -298.578315) (xy 155.239984 -298.568471)
			(xy 155.193968 -298.551019) (xy 155.151347 -298.526412) (xy 155.113226 -298.495287) (xy 155.080591 -298.45845)
			(xy 155.054288 -298.416854) (xy 155.034997 -298.371578) (xy 155.02322 -298.323794) (xy 155.01926 -298.27474)
			(xy 154.680158 -298.27474) (xy 154.679663 -298.299347) (xy 154.671768 -298.347924) (xy 154.656184 -298.394605)
			(xy 154.633313 -298.438182) (xy 154.603748 -298.477526) (xy 154.568255 -298.511618) (xy 154.527752 -298.539574)
			(xy 154.48329 -298.560672) (xy 154.436019 -298.574364) (xy 154.387164 -298.580296) (xy 154.337989 -298.578315)
			(xy 154.28977 -298.568471) (xy 154.243754 -298.551019) (xy 154.201133 -298.526412) (xy 154.163012 -298.495287)
			(xy 154.130377 -298.45845) (xy 154.104074 -298.416854) (xy 154.084783 -298.371578) (xy 154.073006 -298.323794)
			(xy 154.069046 -298.27474) (xy 153.729944 -298.27474) (xy 153.729449 -298.299347) (xy 153.721554 -298.347924)
			(xy 153.70597 -298.394605) (xy 153.683099 -298.438182) (xy 153.653534 -298.477526) (xy 153.618041 -298.511618)
			(xy 153.577538 -298.539574) (xy 153.533076 -298.560672) (xy 153.485805 -298.574364) (xy 153.43695 -298.580296)
			(xy 153.387775 -298.578315) (xy 153.339556 -298.568471) (xy 153.29354 -298.551019) (xy 153.250919 -298.526412)
			(xy 153.212798 -298.495287) (xy 153.180163 -298.45845) (xy 153.15386 -298.416854) (xy 153.134569 -298.371578)
			(xy 153.122792 -298.323794) (xy 153.118832 -298.27474) (xy 118.830852 -298.27474) (xy 118.830852 -299.133514)
			(xy 141.911576 -299.133514) (xy 141.915647 -299.077892) (xy 141.927773 -299.023455) (xy 141.947696 -298.971364)
			(xy 141.974992 -298.922729) (xy 142.009078 -298.878586) (xy 142.049227 -298.839877) (xy 142.094585 -298.807426)
			(xy 142.144185 -298.781925) (xy 142.196969 -298.763918) (xy 142.251812 -298.753788) (xy 142.307546 -298.751751)
			(xy 142.362983 -298.757851) (xy 142.41694 -298.771957) (xy 142.468269 -298.793769) (xy 142.515875 -298.822823)
			(xy 142.558743 -298.858498) (xy 142.59596 -298.900035) (xy 142.626733 -298.946548) (xy 142.650405 -298.997045)
			(xy 142.666473 -299.050452) (xy 142.674593 -299.105628) (xy 142.675102 -299.133514) (xy 143.387062 -299.133514)
			(xy 143.391133 -299.077892) (xy 143.403259 -299.023455) (xy 143.423182 -298.971364) (xy 143.450478 -298.922729)
			(xy 143.484564 -298.878586) (xy 143.524713 -298.839877) (xy 143.570071 -298.807426) (xy 143.619671 -298.781925)
			(xy 143.672455 -298.763918) (xy 143.727298 -298.753788) (xy 143.783032 -298.751751) (xy 143.838469 -298.757851)
			(xy 143.892426 -298.771957) (xy 143.943755 -298.793769) (xy 143.991361 -298.822823) (xy 144.034229 -298.858498)
			(xy 144.071446 -298.900035) (xy 144.102219 -298.946548) (xy 144.125891 -298.997045) (xy 144.141959 -299.050452)
			(xy 144.150079 -299.105628) (xy 144.150588 -299.133514) (xy 144.276062 -299.133514) (xy 144.280133 -299.077892)
			(xy 144.292259 -299.023455) (xy 144.312182 -298.971364) (xy 144.339478 -298.922729) (xy 144.373564 -298.878586)
			(xy 144.413713 -298.839877) (xy 144.459071 -298.807426) (xy 144.508671 -298.781925) (xy 144.561455 -298.763918)
			(xy 144.616298 -298.753788) (xy 144.672032 -298.751751) (xy 144.727469 -298.757851) (xy 144.781426 -298.771957)
			(xy 144.832755 -298.793769) (xy 144.880361 -298.822823) (xy 144.923229 -298.858498) (xy 144.960446 -298.900035)
			(xy 144.991219 -298.946548) (xy 145.014891 -298.997045) (xy 145.030959 -299.050452) (xy 145.039079 -299.105628)
			(xy 145.039588 -299.133514) (xy 145.039079 -299.1614) (xy 145.030959 -299.216576) (xy 145.014891 -299.269983)
			(xy 144.991219 -299.32048) (xy 144.960446 -299.366993) (xy 144.923229 -299.40853) (xy 144.880361 -299.444205)
			(xy 144.832755 -299.473259) (xy 144.781426 -299.495071) (xy 144.727469 -299.509177) (xy 144.672032 -299.515277)
			(xy 144.616298 -299.51324) (xy 144.561455 -299.50311) (xy 144.508671 -299.485103) (xy 144.459071 -299.459602)
			(xy 144.413713 -299.427151) (xy 144.373564 -299.388442) (xy 144.339478 -299.344299) (xy 144.312182 -299.295664)
			(xy 144.292259 -299.243573) (xy 144.280133 -299.189136) (xy 144.276062 -299.133514) (xy 144.150588 -299.133514)
			(xy 144.150079 -299.1614) (xy 144.141959 -299.216576) (xy 144.125891 -299.269983) (xy 144.102219 -299.32048)
			(xy 144.071446 -299.366993) (xy 144.034229 -299.40853) (xy 143.991361 -299.444205) (xy 143.943755 -299.473259)
			(xy 143.892426 -299.495071) (xy 143.838469 -299.509177) (xy 143.783032 -299.515277) (xy 143.727298 -299.51324)
			(xy 143.672455 -299.50311) (xy 143.619671 -299.485103) (xy 143.570071 -299.459602) (xy 143.524713 -299.427151)
			(xy 143.484564 -299.388442) (xy 143.450478 -299.344299) (xy 143.423182 -299.295664) (xy 143.403259 -299.243573)
			(xy 143.391133 -299.189136) (xy 143.387062 -299.133514) (xy 142.675102 -299.133514) (xy 142.674593 -299.1614)
			(xy 142.666473 -299.216576) (xy 142.650405 -299.269983) (xy 142.626733 -299.32048) (xy 142.59596 -299.366993)
			(xy 142.558743 -299.40853) (xy 142.515875 -299.444205) (xy 142.468269 -299.473259) (xy 142.41694 -299.495071)
			(xy 142.362983 -299.509177) (xy 142.307546 -299.515277) (xy 142.251812 -299.51324) (xy 142.196969 -299.50311)
			(xy 142.144185 -299.485103) (xy 142.094585 -299.459602) (xy 142.049227 -299.427151) (xy 142.009078 -299.388442)
			(xy 141.974992 -299.344299) (xy 141.947696 -299.295664) (xy 141.927773 -299.243573) (xy 141.915647 -299.189136)
			(xy 141.911576 -299.133514) (xy 118.830852 -299.133514) (xy 118.830852 -299.895514) (xy 147.43811 -299.895514)
			(xy 147.438654 -299.866132) (xy 147.447683 -299.808065) (xy 147.465514 -299.752071) (xy 147.491725 -299.699475)
			(xy 147.525695 -299.651524) (xy 147.56662 -299.609352) (xy 147.589748 -299.591222) (xy 147.598672 -299.583742)
			(xy 147.609132 -299.562968) (xy 147.609814 -299.551344) (xy 147.611084 -299.459396) (xy 147.601178 -299.438314)
			(xy 147.592034 -299.430948) (xy 147.570186 -299.412742) (xy 147.531644 -299.370924) (xy 147.499736 -299.323849)
			(xy 147.475169 -299.272559) (xy 147.458486 -299.218191) (xy 147.450058 -299.161949) (xy 147.44954 -299.133514)
			(xy 147.450026 -299.106263) (xy 147.457782 -299.052315) (xy 147.473137 -299.00002) (xy 147.495779 -298.950443)
			(xy 147.525245 -298.904593) (xy 147.560936 -298.863402) (xy 147.602127 -298.827711) (xy 147.647977 -298.798245)
			(xy 147.697554 -298.775603) (xy 147.749849 -298.760248) (xy 147.803797 -298.752492) (xy 147.858299 -298.752492)
			(xy 147.912247 -298.760248) (xy 147.964542 -298.775603) (xy 148.014119 -298.798245) (xy 148.059969 -298.827711)
			(xy 148.10116 -298.863402) (xy 148.136851 -298.904593) (xy 148.166317 -298.950443) (xy 148.188959 -299.00002)
			(xy 148.204314 -299.052315) (xy 148.21207 -299.106263) (xy 148.212556 -299.133514) (xy 148.212006 -299.162896)
			(xy 148.202975 -299.220961) (xy 148.201784 -299.2247) (xy 151.53404 -299.2247) (xy 151.538212 -299.174354)
			(xy 151.550614 -299.125381) (xy 151.570909 -299.079118) (xy 151.598541 -299.036827) (xy 151.632758 -298.999661)
			(xy 151.672626 -298.968634) (xy 151.717058 -298.944593) (xy 151.76484 -298.928193) (xy 151.814671 -298.919882)
			(xy 151.83993 -298.919392) (xy 151.865325 -298.919926) (xy 151.915413 -298.928333) (xy 151.96342 -298.944912)
			(xy 152.008023 -298.969204) (xy 152.047993 -299.000541) (xy 152.065482 -299.01896) (xy 152.065736 -299.019214)
			(xy 152.07342 -299.0268) (xy 152.093294 -299.035202) (xy 152.10409 -299.03547) (xy 152.192228 -299.033184)
			(xy 152.21204 -299.023532) (xy 152.219152 -299.014896) (xy 152.234926 -298.996339) (xy 152.271023 -298.963642)
			(xy 152.311522 -298.936588) (xy 152.355548 -298.915761) (xy 152.402151 -298.90161) (xy 152.450324 -298.89444)
			(xy 152.474676 -298.893992) (xy 153.424636 -298.893992) (xy 153.450638 -298.894597) (xy 153.502 -298.902737)
			(xy 153.551457 -298.918811) (xy 153.59779 -298.942424) (xy 153.63986 -298.972993) (xy 153.67663 -299.009767)
			(xy 153.707195 -299.05184) (xy 153.730803 -299.098177) (xy 153.746871 -299.147635) (xy 153.755006 -299.198998)
			(xy 153.755006 -299.224954) (xy 154.069046 -299.224954) (xy 154.073006 -299.1759) (xy 154.084783 -299.128116)
			(xy 154.104074 -299.08284) (xy 154.130377 -299.041244) (xy 154.163012 -299.004407) (xy 154.201133 -298.973282)
			(xy 154.243754 -298.948675) (xy 154.28977 -298.931223) (xy 154.337989 -298.921379) (xy 154.387164 -298.919398)
			(xy 154.436019 -298.92533) (xy 154.48329 -298.939022) (xy 154.527752 -298.96012) (xy 154.568255 -298.988076)
			(xy 154.603748 -299.022168) (xy 154.633313 -299.061512) (xy 154.656184 -299.105089) (xy 154.671768 -299.15177)
			(xy 154.679663 -299.200347) (xy 154.680158 -299.224954) (xy 154.679663 -299.249561) (xy 154.679428 -299.251009)
			(xy 154.994602 -299.251009) (xy 154.994602 -299.198991) (xy 155.002739 -299.147613) (xy 155.018812 -299.098141)
			(xy 155.042426 -299.051792) (xy 155.073 -299.009707) (xy 155.10978 -298.972923) (xy 155.151861 -298.942345)
			(xy 155.198208 -298.918726) (xy 155.247678 -298.902647) (xy 155.299055 -298.894505) (xy 155.325064 -298.893992)
			(xy 156.275024 -298.893992) (xy 156.301026 -298.894596) (xy 156.35239 -298.902735) (xy 156.401848 -298.918808)
			(xy 156.448184 -298.94242) (xy 156.490255 -298.972989) (xy 156.527026 -299.009763) (xy 156.557593 -299.051837)
			(xy 156.581201 -299.098174) (xy 156.597271 -299.147633) (xy 156.605406 -299.198998) (xy 156.605406 -299.224954)
			(xy 156.91918 -299.224954) (xy 156.92314 -299.1759) (xy 156.934917 -299.128116) (xy 156.954208 -299.08284)
			(xy 156.980511 -299.041244) (xy 157.013146 -299.004407) (xy 157.051267 -298.973282) (xy 157.093888 -298.948675)
			(xy 157.139904 -298.931223) (xy 157.188123 -298.921379) (xy 157.237298 -298.919398) (xy 157.286153 -298.92533)
			(xy 157.333424 -298.939022) (xy 157.377886 -298.96012) (xy 157.418389 -298.988076) (xy 157.453882 -299.022168)
			(xy 157.483447 -299.061512) (xy 157.506318 -299.105089) (xy 157.521902 -299.15177) (xy 157.529797 -299.200347)
			(xy 157.530287 -299.2247) (xy 157.86914 -299.2247) (xy 157.8731 -299.175646) (xy 157.884877 -299.127862)
			(xy 157.904168 -299.082586) (xy 157.930471 -299.04099) (xy 157.963106 -299.004153) (xy 158.001227 -298.973028)
			(xy 158.043848 -298.948421) (xy 158.089864 -298.930969) (xy 158.138083 -298.921125) (xy 158.187258 -298.919144)
			(xy 158.236113 -298.925076) (xy 158.283384 -298.938768) (xy 158.327846 -298.959866) (xy 158.368349 -298.987822)
			(xy 158.403842 -299.021914) (xy 158.433407 -299.061258) (xy 158.456278 -299.104835) (xy 158.471862 -299.151516)
			(xy 158.479757 -299.200093) (xy 158.480252 -299.2247) (xy 158.480247 -299.224954) (xy 159.76906 -299.224954)
			(xy 159.77302 -299.1759) (xy 159.784797 -299.128116) (xy 159.804088 -299.08284) (xy 159.830391 -299.041244)
			(xy 159.863026 -299.004407) (xy 159.901147 -298.973282) (xy 159.943768 -298.948675) (xy 159.989784 -298.931223)
			(xy 160.038003 -298.921379) (xy 160.087178 -298.919398) (xy 160.136033 -298.92533) (xy 160.183304 -298.939022)
			(xy 160.227766 -298.96012) (xy 160.268269 -298.988076) (xy 160.303762 -299.022168) (xy 160.333327 -299.061512)
			(xy 160.356198 -299.105089) (xy 160.371782 -299.15177) (xy 160.379677 -299.200347) (xy 160.380172 -299.224954)
			(xy 160.719274 -299.224954) (xy 160.723234 -299.1759) (xy 160.735011 -299.128116) (xy 160.754302 -299.08284)
			(xy 160.780605 -299.041244) (xy 160.81324 -299.004407) (xy 160.851361 -298.973282) (xy 160.893982 -298.948675)
			(xy 160.939998 -298.931223) (xy 160.988217 -298.921379) (xy 161.037392 -298.919398) (xy 161.086247 -298.92533)
			(xy 161.133518 -298.939022) (xy 161.17798 -298.96012) (xy 161.218483 -298.988076) (xy 161.253976 -299.022168)
			(xy 161.283541 -299.061512) (xy 161.306412 -299.105089) (xy 161.321996 -299.15177) (xy 161.329891 -299.200347)
			(xy 161.330386 -299.224954) (xy 161.669234 -299.224954) (xy 161.673194 -299.1759) (xy 161.684971 -299.128116)
			(xy 161.704262 -299.08284) (xy 161.730565 -299.041244) (xy 161.7632 -299.004407) (xy 161.801321 -298.973282)
			(xy 161.843942 -298.948675) (xy 161.889958 -298.931223) (xy 161.938177 -298.921379) (xy 161.987352 -298.919398)
			(xy 162.036207 -298.92533) (xy 162.083478 -298.939022) (xy 162.12794 -298.96012) (xy 162.168443 -298.988076)
			(xy 162.203936 -299.022168) (xy 162.233501 -299.061512) (xy 162.256372 -299.105089) (xy 162.271956 -299.15177)
			(xy 162.279851 -299.200347) (xy 162.280346 -299.224954) (xy 162.619194 -299.224954) (xy 162.623154 -299.1759)
			(xy 162.634931 -299.128116) (xy 162.654222 -299.08284) (xy 162.680525 -299.041244) (xy 162.71316 -299.004407)
			(xy 162.751281 -298.973282) (xy 162.793902 -298.948675) (xy 162.839918 -298.931223) (xy 162.888137 -298.921379)
			(xy 162.937312 -298.919398) (xy 162.986167 -298.92533) (xy 163.033438 -298.939022) (xy 163.0779 -298.96012)
			(xy 163.118403 -298.988076) (xy 163.153896 -299.022168) (xy 163.183461 -299.061512) (xy 163.206332 -299.105089)
			(xy 163.221916 -299.15177) (xy 163.229811 -299.200347) (xy 163.230306 -299.224954) (xy 163.569154 -299.224954)
			(xy 163.573114 -299.1759) (xy 163.584891 -299.128116) (xy 163.604182 -299.08284) (xy 163.630485 -299.041244)
			(xy 163.66312 -299.004407) (xy 163.701241 -298.973282) (xy 163.743862 -298.948675) (xy 163.789878 -298.931223)
			(xy 163.838097 -298.921379) (xy 163.887272 -298.919398) (xy 163.936127 -298.92533) (xy 163.983398 -298.939022)
			(xy 164.02786 -298.96012) (xy 164.068363 -298.988076) (xy 164.103856 -299.022168) (xy 164.133421 -299.061512)
			(xy 164.156292 -299.105089) (xy 164.171876 -299.15177) (xy 164.179771 -299.200347) (xy 164.180266 -299.224954)
			(xy 164.179771 -299.249561) (xy 164.171876 -299.298138) (xy 164.156292 -299.344819) (xy 164.133421 -299.388396)
			(xy 164.103856 -299.42774) (xy 164.068363 -299.461832) (xy 164.02786 -299.489788) (xy 163.983398 -299.510886)
			(xy 163.936127 -299.524578) (xy 163.887272 -299.53051) (xy 163.838097 -299.528529) (xy 163.789878 -299.518685)
			(xy 163.743862 -299.501233) (xy 163.701241 -299.476626) (xy 163.66312 -299.445501) (xy 163.630485 -299.408664)
			(xy 163.604182 -299.367068) (xy 163.584891 -299.321792) (xy 163.573114 -299.274008) (xy 163.569154 -299.224954)
			(xy 163.230306 -299.224954) (xy 163.229811 -299.249561) (xy 163.221916 -299.298138) (xy 163.206332 -299.344819)
			(xy 163.183461 -299.388396) (xy 163.153896 -299.42774) (xy 163.118403 -299.461832) (xy 163.0779 -299.489788)
			(xy 163.033438 -299.510886) (xy 162.986167 -299.524578) (xy 162.937312 -299.53051) (xy 162.888137 -299.528529)
			(xy 162.839918 -299.518685) (xy 162.793902 -299.501233) (xy 162.751281 -299.476626) (xy 162.71316 -299.445501)
			(xy 162.680525 -299.408664) (xy 162.654222 -299.367068) (xy 162.634931 -299.321792) (xy 162.623154 -299.274008)
			(xy 162.619194 -299.224954) (xy 162.280346 -299.224954) (xy 162.279851 -299.249561) (xy 162.271956 -299.298138)
			(xy 162.256372 -299.344819) (xy 162.233501 -299.388396) (xy 162.203936 -299.42774) (xy 162.168443 -299.461832)
			(xy 162.12794 -299.489788) (xy 162.083478 -299.510886) (xy 162.036207 -299.524578) (xy 161.987352 -299.53051)
			(xy 161.938177 -299.528529) (xy 161.889958 -299.518685) (xy 161.843942 -299.501233) (xy 161.801321 -299.476626)
			(xy 161.7632 -299.445501) (xy 161.730565 -299.408664) (xy 161.704262 -299.367068) (xy 161.684971 -299.321792)
			(xy 161.673194 -299.274008) (xy 161.669234 -299.224954) (xy 161.330386 -299.224954) (xy 161.329891 -299.249561)
			(xy 161.321996 -299.298138) (xy 161.306412 -299.344819) (xy 161.283541 -299.388396) (xy 161.253976 -299.42774)
			(xy 161.218483 -299.461832) (xy 161.17798 -299.489788) (xy 161.133518 -299.510886) (xy 161.086247 -299.524578)
			(xy 161.037392 -299.53051) (xy 160.988217 -299.528529) (xy 160.939998 -299.518685) (xy 160.893982 -299.501233)
			(xy 160.851361 -299.476626) (xy 160.81324 -299.445501) (xy 160.780605 -299.408664) (xy 160.754302 -299.367068)
			(xy 160.735011 -299.321792) (xy 160.723234 -299.274008) (xy 160.719274 -299.224954) (xy 160.380172 -299.224954)
			(xy 160.379677 -299.249561) (xy 160.371782 -299.298138) (xy 160.356198 -299.344819) (xy 160.333327 -299.388396)
			(xy 160.303762 -299.42774) (xy 160.268269 -299.461832) (xy 160.227766 -299.489788) (xy 160.183304 -299.510886)
			(xy 160.136033 -299.524578) (xy 160.087178 -299.53051) (xy 160.038003 -299.528529) (xy 159.989784 -299.518685)
			(xy 159.943768 -299.501233) (xy 159.901147 -299.476626) (xy 159.863026 -299.445501) (xy 159.830391 -299.408664)
			(xy 159.804088 -299.367068) (xy 159.784797 -299.321792) (xy 159.77302 -299.274008) (xy 159.76906 -299.224954)
			(xy 158.480247 -299.224954) (xy 158.479757 -299.249307) (xy 158.471862 -299.297884) (xy 158.456278 -299.344565)
			(xy 158.433407 -299.388142) (xy 158.403842 -299.427486) (xy 158.368349 -299.461578) (xy 158.327846 -299.489534)
			(xy 158.283384 -299.510632) (xy 158.236113 -299.524324) (xy 158.187258 -299.530256) (xy 158.138083 -299.528275)
			(xy 158.089864 -299.518431) (xy 158.043848 -299.500979) (xy 158.001227 -299.476372) (xy 157.963106 -299.445247)
			(xy 157.930471 -299.40841) (xy 157.904168 -299.366814) (xy 157.884877 -299.321538) (xy 157.8731 -299.273754)
			(xy 157.86914 -299.2247) (xy 157.530287 -299.2247) (xy 157.530292 -299.224954) (xy 157.529797 -299.249561)
			(xy 157.521902 -299.298138) (xy 157.506318 -299.344819) (xy 157.483447 -299.388396) (xy 157.453882 -299.42774)
			(xy 157.418389 -299.461832) (xy 157.377886 -299.489788) (xy 157.333424 -299.510886) (xy 157.286153 -299.524578)
			(xy 157.237298 -299.53051) (xy 157.188123 -299.528529) (xy 157.139904 -299.518685) (xy 157.093888 -299.501233)
			(xy 157.051267 -299.476626) (xy 157.013146 -299.445501) (xy 156.980511 -299.408664) (xy 156.954208 -299.367068)
			(xy 156.934917 -299.321792) (xy 156.92314 -299.274008) (xy 156.91918 -299.224954) (xy 156.605406 -299.224954)
			(xy 156.605406 -299.251002) (xy 156.597271 -299.302367) (xy 156.581201 -299.351826) (xy 156.557593 -299.398163)
			(xy 156.527026 -299.440237) (xy 156.490255 -299.477011) (xy 156.448184 -299.50758) (xy 156.401848 -299.531192)
			(xy 156.35239 -299.547265) (xy 156.301026 -299.555404) (xy 156.275024 -299.555916) (xy 156.204666 -299.555916)
			(xy 156.193941 -299.556335) (xy 156.174336 -299.565018) (xy 156.16682 -299.57268) (xy 156.109162 -299.636942)
			(xy 156.102558 -299.657262) (xy 156.103574 -299.667676) (xy 156.103574 -299.668184) (xy 156.105352 -299.699934)
			(xy 156.10483 -299.725189) (xy 156.096517 -299.775011) (xy 156.080116 -299.822785) (xy 156.056075 -299.867208)
			(xy 156.025051 -299.907068) (xy 155.987889 -299.941278) (xy 155.945603 -299.968904) (xy 155.899347 -299.989194)
			(xy 155.850382 -300.001594) (xy 155.800044 -300.005765) (xy 155.749706 -300.001594) (xy 155.700741 -299.989194)
			(xy 155.654485 -299.968904) (xy 155.612199 -299.941278) (xy 155.575037 -299.907068) (xy 155.544013 -299.867208)
			(xy 155.519972 -299.822785) (xy 155.503571 -299.775011) (xy 155.495258 -299.725189) (xy 155.494736 -299.699934)
			(xy 155.496514 -299.66793) (xy 155.49753 -299.657262) (xy 155.490926 -299.636942) (xy 155.433268 -299.57268)
			(xy 155.425667 -299.56514) (xy 155.406114 -299.55648) (xy 155.395422 -299.555916) (xy 155.325064 -299.555916)
			(xy 155.299055 -299.555495) (xy 155.247678 -299.547353) (xy 155.198208 -299.531274) (xy 155.151861 -299.507655)
			(xy 155.10978 -299.477077) (xy 155.073 -299.440293) (xy 155.042426 -299.398208) (xy 155.018812 -299.351859)
			(xy 155.002739 -299.302387) (xy 154.994602 -299.251009) (xy 154.679428 -299.251009) (xy 154.671768 -299.298138)
			(xy 154.656184 -299.344819) (xy 154.633313 -299.388396) (xy 154.603748 -299.42774) (xy 154.568255 -299.461832)
			(xy 154.527752 -299.489788) (xy 154.48329 -299.510886) (xy 154.436019 -299.524578) (xy 154.387164 -299.53051)
			(xy 154.337989 -299.528529) (xy 154.28977 -299.518685) (xy 154.243754 -299.501233) (xy 154.201133 -299.476626)
			(xy 154.163012 -299.445501) (xy 154.130377 -299.408664) (xy 154.104074 -299.367068) (xy 154.084783 -299.321792)
			(xy 154.073006 -299.274008) (xy 154.069046 -299.224954) (xy 153.755006 -299.224954) (xy 153.755006 -299.251002)
			(xy 153.746871 -299.302365) (xy 153.730803 -299.351823) (xy 153.707195 -299.39816) (xy 153.67663 -299.440233)
			(xy 153.63986 -299.477007) (xy 153.59779 -299.507576) (xy 153.551457 -299.531189) (xy 153.502 -299.547263)
			(xy 153.450638 -299.555403) (xy 153.424636 -299.555916) (xy 152.474676 -299.555916) (xy 152.450291 -299.555513)
			(xy 152.402052 -299.548333) (xy 152.355391 -299.534148) (xy 152.311318 -299.513264) (xy 152.27079 -299.486135)
			(xy 152.234684 -299.453349) (xy 152.218898 -299.434758) (xy 152.211523 -299.426595) (xy 152.191772 -299.416968)
			(xy 152.180798 -299.416216) (xy 152.10409 -299.41393) (xy 152.093104 -299.414173) (xy 152.072952 -299.422877)
			(xy 152.065228 -299.430694) (xy 152.047764 -299.449091) (xy 152.007828 -299.480363) (xy 151.96327 -299.5046)
			(xy 151.915318 -299.521135) (xy 151.865292 -299.529511) (xy 151.83993 -299.530008) (xy 151.814671 -299.529518)
			(xy 151.76484 -299.521207) (xy 151.717058 -299.504807) (xy 151.672626 -299.480766) (xy 151.632758 -299.449739)
			(xy 151.598541 -299.412573) (xy 151.570909 -299.370282) (xy 151.550614 -299.324019) (xy 151.538212 -299.275046)
			(xy 151.53404 -299.2247) (xy 148.201784 -299.2247) (xy 148.185143 -299.276954) (xy 148.158933 -299.329549)
			(xy 148.124966 -299.377501) (xy 148.084044 -299.419674) (xy 148.060918 -299.437806) (xy 148.051975 -299.445267)
			(xy 148.041527 -299.466056) (xy 148.040852 -299.477684) (xy 148.039582 -299.569632) (xy 148.049488 -299.590714)
			(xy 148.058632 -299.59808) (xy 148.080459 -299.616309) (xy 148.118999 -299.658124) (xy 148.150908 -299.705195)
			(xy 148.175478 -299.75648) (xy 148.192166 -299.810843) (xy 148.200603 -299.867081) (xy 148.201126 -299.895514)
			(xy 148.8346 -299.895514) (xy 148.838671 -299.839892) (xy 148.850797 -299.785455) (xy 148.87072 -299.733364)
			(xy 148.898016 -299.684729) (xy 148.932102 -299.640586) (xy 148.972251 -299.601877) (xy 149.017609 -299.569426)
			(xy 149.067209 -299.543925) (xy 149.119993 -299.525918) (xy 149.174836 -299.515788) (xy 149.23057 -299.513751)
			(xy 149.286007 -299.519851) (xy 149.339964 -299.533957) (xy 149.391293 -299.555769) (xy 149.438899 -299.584823)
			(xy 149.481767 -299.620498) (xy 149.518984 -299.662035) (xy 149.549757 -299.708548) (xy 149.573429 -299.759045)
			(xy 149.589497 -299.812452) (xy 149.597617 -299.867628) (xy 149.598126 -299.895514) (xy 149.72106 -299.895514)
			(xy 149.725131 -299.839892) (xy 149.737257 -299.785455) (xy 149.75718 -299.733364) (xy 149.784476 -299.684729)
			(xy 149.818562 -299.640586) (xy 149.858711 -299.601877) (xy 149.904069 -299.569426) (xy 149.953669 -299.543925)
			(xy 150.006453 -299.525918) (xy 150.061296 -299.515788) (xy 150.11703 -299.513751) (xy 150.172467 -299.519851)
			(xy 150.226424 -299.533957) (xy 150.277753 -299.555769) (xy 150.325359 -299.584823) (xy 150.368227 -299.620498)
			(xy 150.405444 -299.662035) (xy 150.436217 -299.708548) (xy 150.459889 -299.759045) (xy 150.475957 -299.812452)
			(xy 150.484077 -299.867628) (xy 150.484586 -299.895514) (xy 150.484077 -299.9234) (xy 150.475957 -299.978576)
			(xy 150.459889 -300.031983) (xy 150.436217 -300.08248) (xy 150.405444 -300.128993) (xy 150.368227 -300.17053)
			(xy 150.325359 -300.206205) (xy 150.277753 -300.235259) (xy 150.226424 -300.257071) (xy 150.172467 -300.271177)
			(xy 150.11703 -300.277277) (xy 150.061296 -300.27524) (xy 150.006453 -300.26511) (xy 149.953669 -300.247103)
			(xy 149.904069 -300.221602) (xy 149.858711 -300.189151) (xy 149.818562 -300.150442) (xy 149.784476 -300.106299)
			(xy 149.75718 -300.057664) (xy 149.737257 -300.005573) (xy 149.725131 -299.951136) (xy 149.72106 -299.895514)
			(xy 149.598126 -299.895514) (xy 149.597617 -299.9234) (xy 149.589497 -299.978576) (xy 149.573429 -300.031983)
			(xy 149.549757 -300.08248) (xy 149.518984 -300.128993) (xy 149.481767 -300.17053) (xy 149.438899 -300.206205)
			(xy 149.391293 -300.235259) (xy 149.339964 -300.257071) (xy 149.286007 -300.271177) (xy 149.23057 -300.277277)
			(xy 149.174836 -300.27524) (xy 149.119993 -300.26511) (xy 149.067209 -300.247103) (xy 149.017609 -300.221602)
			(xy 148.972251 -300.189151) (xy 148.932102 -300.150442) (xy 148.898016 -300.106299) (xy 148.87072 -300.057664)
			(xy 148.850797 -300.005573) (xy 148.838671 -299.951136) (xy 148.8346 -299.895514) (xy 148.201126 -299.895514)
			(xy 148.20064 -299.922765) (xy 148.192884 -299.976713) (xy 148.177529 -300.029008) (xy 148.154887 -300.078585)
			(xy 148.125421 -300.124435) (xy 148.08973 -300.165626) (xy 148.048539 -300.201317) (xy 148.002689 -300.230783)
			(xy 147.953112 -300.253425) (xy 147.900817 -300.26878) (xy 147.846869 -300.276536) (xy 147.792367 -300.276536)
			(xy 147.738419 -300.26878) (xy 147.686124 -300.253425) (xy 147.636547 -300.230783) (xy 147.590697 -300.201317)
			(xy 147.549506 -300.165626) (xy 147.513815 -300.124435) (xy 147.484349 -300.078585) (xy 147.461707 -300.029008)
			(xy 147.446352 -299.976713) (xy 147.438596 -299.922765) (xy 147.43811 -299.895514) (xy 118.830852 -299.895514)
			(xy 118.830852 -301.031656) (xy 141.911576 -301.031656) (xy 141.915647 -300.976034) (xy 141.927773 -300.921597)
			(xy 141.947696 -300.869506) (xy 141.974992 -300.820871) (xy 142.009078 -300.776728) (xy 142.049227 -300.738019)
			(xy 142.094585 -300.705568) (xy 142.144185 -300.680067) (xy 142.196969 -300.66206) (xy 142.251812 -300.65193)
			(xy 142.307546 -300.649893) (xy 142.362983 -300.655993) (xy 142.41694 -300.670099) (xy 142.468269 -300.691911)
			(xy 142.515875 -300.720965) (xy 142.558743 -300.75664) (xy 142.59596 -300.798177) (xy 142.626733 -300.84469)
			(xy 142.650405 -300.895187) (xy 142.666473 -300.948594) (xy 142.674593 -301.00377) (xy 142.675102 -301.031656)
			(xy 143.396714 -301.031656) (xy 143.400785 -300.976034) (xy 143.412911 -300.921597) (xy 143.432834 -300.869506)
			(xy 143.46013 -300.820871) (xy 143.494216 -300.776728) (xy 143.534365 -300.738019) (xy 143.579723 -300.705568)
			(xy 143.629323 -300.680067) (xy 143.682107 -300.66206) (xy 143.73695 -300.65193) (xy 143.792684 -300.649893)
			(xy 143.792693 -300.649894) (xy 152.644106 -300.649894) (xy 152.648066 -300.60084) (xy 152.659843 -300.553056)
			(xy 152.679134 -300.50778) (xy 152.705437 -300.466184) (xy 152.738072 -300.429347) (xy 152.776193 -300.398222)
			(xy 152.818814 -300.373615) (xy 152.86483 -300.356163) (xy 152.913049 -300.346319) (xy 152.962224 -300.344338)
			(xy 153.011079 -300.35027) (xy 153.05835 -300.363962) (xy 153.102812 -300.38506) (xy 153.143315 -300.413016)
			(xy 153.178808 -300.447108) (xy 153.208373 -300.486452) (xy 153.231244 -300.530029) (xy 153.246828 -300.57671)
			(xy 153.254723 -300.625287) (xy 153.255218 -300.649894) (xy 153.594066 -300.649894) (xy 153.598026 -300.60084)
			(xy 153.609803 -300.553056) (xy 153.629094 -300.50778) (xy 153.655397 -300.466184) (xy 153.688032 -300.429347)
			(xy 153.726153 -300.398222) (xy 153.768774 -300.373615) (xy 153.81479 -300.356163) (xy 153.863009 -300.346319)
			(xy 153.912184 -300.344338) (xy 153.961039 -300.35027) (xy 154.00831 -300.363962) (xy 154.052772 -300.38506)
			(xy 154.093275 -300.413016) (xy 154.128768 -300.447108) (xy 154.158333 -300.486452) (xy 154.181204 -300.530029)
			(xy 154.196788 -300.57671) (xy 154.204683 -300.625287) (xy 154.205178 -300.649894) (xy 154.54428 -300.649894)
			(xy 154.54824 -300.60084) (xy 154.560017 -300.553056) (xy 154.579308 -300.50778) (xy 154.605611 -300.466184)
			(xy 154.638246 -300.429347) (xy 154.676367 -300.398222) (xy 154.718988 -300.373615) (xy 154.765004 -300.356163)
			(xy 154.813223 -300.346319) (xy 154.862398 -300.344338) (xy 154.911253 -300.35027) (xy 154.958524 -300.363962)
			(xy 155.002986 -300.38506) (xy 155.043489 -300.413016) (xy 155.078982 -300.447108) (xy 155.108547 -300.486452)
			(xy 155.131418 -300.530029) (xy 155.147002 -300.57671) (xy 155.154897 -300.625287) (xy 155.155392 -300.649894)
			(xy 155.49424 -300.649894) (xy 155.4982 -300.60084) (xy 155.509977 -300.553056) (xy 155.529268 -300.50778)
			(xy 155.555571 -300.466184) (xy 155.588206 -300.429347) (xy 155.626327 -300.398222) (xy 155.668948 -300.373615)
			(xy 155.714964 -300.356163) (xy 155.763183 -300.346319) (xy 155.812358 -300.344338) (xy 155.861213 -300.35027)
			(xy 155.908484 -300.363962) (xy 155.952946 -300.38506) (xy 155.993449 -300.413016) (xy 156.028942 -300.447108)
			(xy 156.058507 -300.486452) (xy 156.081378 -300.530029) (xy 156.096962 -300.57671) (xy 156.104857 -300.625287)
			(xy 156.105352 -300.649894) (xy 156.4442 -300.649894) (xy 156.44816 -300.60084) (xy 156.459937 -300.553056)
			(xy 156.479228 -300.50778) (xy 156.505531 -300.466184) (xy 156.538166 -300.429347) (xy 156.576287 -300.398222)
			(xy 156.618908 -300.373615) (xy 156.664924 -300.356163) (xy 156.713143 -300.346319) (xy 156.762318 -300.344338)
			(xy 156.811173 -300.35027) (xy 156.858444 -300.363962) (xy 156.902906 -300.38506) (xy 156.943409 -300.413016)
			(xy 156.978902 -300.447108) (xy 157.008467 -300.486452) (xy 157.031338 -300.530029) (xy 157.046922 -300.57671)
			(xy 157.054817 -300.625287) (xy 157.055312 -300.649894) (xy 157.39416 -300.649894) (xy 157.39812 -300.60084)
			(xy 157.409897 -300.553056) (xy 157.429188 -300.50778) (xy 157.455491 -300.466184) (xy 157.488126 -300.429347)
			(xy 157.526247 -300.398222) (xy 157.568868 -300.373615) (xy 157.614884 -300.356163) (xy 157.663103 -300.346319)
			(xy 157.712278 -300.344338) (xy 157.761133 -300.35027) (xy 157.808404 -300.363962) (xy 157.852866 -300.38506)
			(xy 157.893369 -300.413016) (xy 157.928862 -300.447108) (xy 157.958427 -300.486452) (xy 157.981298 -300.530029)
			(xy 157.996882 -300.57671) (xy 158.004777 -300.625287) (xy 158.005272 -300.649894) (xy 158.34412 -300.649894)
			(xy 158.34808 -300.60084) (xy 158.359857 -300.553056) (xy 158.379148 -300.50778) (xy 158.405451 -300.466184)
			(xy 158.438086 -300.429347) (xy 158.476207 -300.398222) (xy 158.518828 -300.373615) (xy 158.564844 -300.356163)
			(xy 158.613063 -300.346319) (xy 158.662238 -300.344338) (xy 158.711093 -300.35027) (xy 158.758364 -300.363962)
			(xy 158.802826 -300.38506) (xy 158.843329 -300.413016) (xy 158.878822 -300.447108) (xy 158.908387 -300.486452)
			(xy 158.931258 -300.530029) (xy 158.946842 -300.57671) (xy 158.954737 -300.625287) (xy 158.955066 -300.641631)
			(xy 159.294175 -300.641631) (xy 159.29954 -300.592279) (xy 159.312819 -300.544446) (xy 159.333661 -300.499391)
			(xy 159.361518 -300.458301) (xy 159.395655 -300.422259) (xy 159.435174 -300.392215) (xy 159.479032 -300.36896)
			(xy 159.526075 -300.353107) (xy 159.575063 -300.345073) (xy 159.599884 -300.344586) (xy 159.614067 -300.344765)
			(xy 159.642307 -300.347436) (xy 159.656272 -300.34992) (xy 159.670242 -300.352051) (xy 159.698371 -300.349479)
			(xy 159.724717 -300.339295) (xy 159.747264 -300.322281) (xy 159.764284 -300.299738) (xy 159.774473 -300.273394)
			(xy 159.777053 -300.245266) (xy 159.77489 -300.231302) (xy 159.772418 -300.217335) (xy 159.769743 -300.189096)
			(xy 159.769556 -300.174914) (xy 159.770063 -300.150091) (xy 159.778093 -300.101099) (xy 159.793943 -300.054052)
			(xy 159.817196 -300.010188) (xy 159.84724 -299.970665) (xy 159.883282 -299.936523) (xy 159.924372 -299.908662)
			(xy 159.969429 -299.887816) (xy 160.017266 -299.874534) (xy 160.06662 -299.869167) (xy 160.116193 -299.871855)
			(xy 160.164678 -299.882529) (xy 160.210797 -299.900905) (xy 160.253336 -299.926502) (xy 160.291173 -299.958643)
			(xy 160.323311 -299.996482) (xy 160.348904 -300.039022) (xy 160.367278 -300.085143) (xy 160.377948 -300.133629)
			(xy 160.380183 -300.174914) (xy 160.719274 -300.174914) (xy 160.723234 -300.12586) (xy 160.735011 -300.078076)
			(xy 160.754302 -300.0328) (xy 160.780605 -299.991204) (xy 160.81324 -299.954367) (xy 160.851361 -299.923242)
			(xy 160.893982 -299.898635) (xy 160.939998 -299.881183) (xy 160.988217 -299.871339) (xy 161.037392 -299.869358)
			(xy 161.086247 -299.87529) (xy 161.133518 -299.888982) (xy 161.17798 -299.91008) (xy 161.218483 -299.938036)
			(xy 161.253976 -299.972128) (xy 161.283541 -300.011472) (xy 161.306412 -300.055049) (xy 161.321996 -300.10173)
			(xy 161.329891 -300.150307) (xy 161.330386 -300.174914) (xy 161.669234 -300.174914) (xy 161.673194 -300.12586)
			(xy 161.684971 -300.078076) (xy 161.704262 -300.0328) (xy 161.730565 -299.991204) (xy 161.7632 -299.954367)
			(xy 161.801321 -299.923242) (xy 161.843942 -299.898635) (xy 161.889958 -299.881183) (xy 161.938177 -299.871339)
			(xy 161.987352 -299.869358) (xy 162.036207 -299.87529) (xy 162.083478 -299.888982) (xy 162.12794 -299.91008)
			(xy 162.168443 -299.938036) (xy 162.203936 -299.972128) (xy 162.233501 -300.011472) (xy 162.256372 -300.055049)
			(xy 162.271956 -300.10173) (xy 162.279851 -300.150307) (xy 162.280346 -300.174914) (xy 163.569154 -300.174914)
			(xy 163.573114 -300.12586) (xy 163.584891 -300.078076) (xy 163.604182 -300.0328) (xy 163.630485 -299.991204)
			(xy 163.66312 -299.954367) (xy 163.701241 -299.923242) (xy 163.743862 -299.898635) (xy 163.789878 -299.881183)
			(xy 163.838097 -299.871339) (xy 163.887272 -299.869358) (xy 163.936127 -299.87529) (xy 163.983398 -299.888982)
			(xy 164.02786 -299.91008) (xy 164.068363 -299.938036) (xy 164.103856 -299.972128) (xy 164.133421 -300.011472)
			(xy 164.156292 -300.055049) (xy 164.171876 -300.10173) (xy 164.179771 -300.150307) (xy 164.180266 -300.174914)
			(xy 164.519114 -300.174914) (xy 164.523074 -300.12586) (xy 164.534851 -300.078076) (xy 164.554142 -300.0328)
			(xy 164.580445 -299.991204) (xy 164.61308 -299.954367) (xy 164.651201 -299.923242) (xy 164.693822 -299.898635)
			(xy 164.739838 -299.881183) (xy 164.788057 -299.871339) (xy 164.837232 -299.869358) (xy 164.886087 -299.87529)
			(xy 164.933358 -299.888982) (xy 164.97782 -299.91008) (xy 165.018323 -299.938036) (xy 165.053816 -299.972128)
			(xy 165.083381 -300.011472) (xy 165.106252 -300.055049) (xy 165.121836 -300.10173) (xy 165.129731 -300.150307)
			(xy 165.130226 -300.174914) (xy 165.129731 -300.199521) (xy 165.121836 -300.248098) (xy 165.106252 -300.294779)
			(xy 165.083381 -300.338356) (xy 165.053816 -300.3777) (xy 165.018323 -300.411792) (xy 164.97782 -300.439748)
			(xy 164.933358 -300.460846) (xy 164.886087 -300.474538) (xy 164.837232 -300.48047) (xy 164.788057 -300.478489)
			(xy 164.739838 -300.468645) (xy 164.693822 -300.451193) (xy 164.651201 -300.426586) (xy 164.61308 -300.395461)
			(xy 164.580445 -300.358624) (xy 164.554142 -300.317028) (xy 164.534851 -300.271752) (xy 164.523074 -300.223968)
			(xy 164.519114 -300.174914) (xy 164.180266 -300.174914) (xy 164.179771 -300.199521) (xy 164.171876 -300.248098)
			(xy 164.156292 -300.294779) (xy 164.133421 -300.338356) (xy 164.103856 -300.3777) (xy 164.068363 -300.411792)
			(xy 164.02786 -300.439748) (xy 163.983398 -300.460846) (xy 163.936127 -300.474538) (xy 163.887272 -300.48047)
			(xy 163.838097 -300.478489) (xy 163.789878 -300.468645) (xy 163.743862 -300.451193) (xy 163.701241 -300.426586)
			(xy 163.66312 -300.395461) (xy 163.630485 -300.358624) (xy 163.604182 -300.317028) (xy 163.584891 -300.271752)
			(xy 163.573114 -300.223968) (xy 163.569154 -300.174914) (xy 162.280346 -300.174914) (xy 162.279851 -300.199521)
			(xy 162.271956 -300.248098) (xy 162.256372 -300.294779) (xy 162.233501 -300.338356) (xy 162.203936 -300.3777)
			(xy 162.168443 -300.411792) (xy 162.12794 -300.439748) (xy 162.083478 -300.460846) (xy 162.036207 -300.474538)
			(xy 161.987352 -300.48047) (xy 161.938177 -300.478489) (xy 161.889958 -300.468645) (xy 161.843942 -300.451193)
			(xy 161.801321 -300.426586) (xy 161.7632 -300.395461) (xy 161.730565 -300.358624) (xy 161.704262 -300.317028)
			(xy 161.684971 -300.271752) (xy 161.673194 -300.223968) (xy 161.669234 -300.174914) (xy 161.330386 -300.174914)
			(xy 161.329891 -300.199521) (xy 161.321996 -300.248098) (xy 161.306412 -300.294779) (xy 161.283541 -300.338356)
			(xy 161.253976 -300.3777) (xy 161.218483 -300.411792) (xy 161.17798 -300.439748) (xy 161.133518 -300.460846)
			(xy 161.086247 -300.474538) (xy 161.037392 -300.48047) (xy 160.988217 -300.478489) (xy 160.939998 -300.468645)
			(xy 160.893982 -300.451193) (xy 160.851361 -300.426586) (xy 160.81324 -300.395461) (xy 160.780605 -300.358624)
			(xy 160.754302 -300.317028) (xy 160.735011 -300.271752) (xy 160.723234 -300.223968) (xy 160.719274 -300.174914)
			(xy 160.380183 -300.174914) (xy 160.380632 -300.183202) (xy 160.375261 -300.232556) (xy 160.361976 -300.280391)
			(xy 160.341127 -300.325447) (xy 160.313263 -300.366536) (xy 160.279118 -300.402575) (xy 160.239593 -300.432616)
			(xy 160.195728 -300.455866) (xy 160.14868 -300.471713) (xy 160.099687 -300.479739) (xy 160.074864 -300.480222)
			(xy 160.060681 -300.48005) (xy 160.032441 -300.477375) (xy 160.018476 -300.474888) (xy 160.004514 -300.472693)
			(xy 159.976379 -300.475278) (xy 159.950029 -300.485473) (xy 159.927482 -300.502499) (xy 159.910462 -300.52505)
			(xy 159.900273 -300.551403) (xy 159.897694 -300.579538) (xy 159.899858 -300.593506) (xy 159.902331 -300.607472)
			(xy 159.905005 -300.635712) (xy 159.905192 -300.649894) (xy 159.904729 -300.674715) (xy 159.896698 -300.723704)
			(xy 159.880849 -300.770748) (xy 159.857597 -300.814608) (xy 159.827555 -300.854129) (xy 159.791516 -300.888268)
			(xy 159.750428 -300.916128) (xy 159.705375 -300.936974) (xy 159.657542 -300.950256) (xy 159.608191 -300.955625)
			(xy 159.558622 -300.952939) (xy 159.510139 -300.942268) (xy 159.464022 -300.923895) (xy 159.421485 -300.898304)
			(xy 159.383648 -300.866167) (xy 159.351509 -300.828333) (xy 159.325914 -300.785797) (xy 159.307538 -300.739682)
			(xy 159.296864 -300.6912) (xy 159.294175 -300.641631) (xy 158.955066 -300.641631) (xy 158.955232 -300.649894)
			(xy 158.954737 -300.674501) (xy 158.946842 -300.723078) (xy 158.931258 -300.769759) (xy 158.908387 -300.813336)
			(xy 158.878822 -300.85268) (xy 158.843329 -300.886772) (xy 158.802826 -300.914728) (xy 158.758364 -300.935826)
			(xy 158.711093 -300.949518) (xy 158.662238 -300.95545) (xy 158.613063 -300.953469) (xy 158.564844 -300.943625)
			(xy 158.518828 -300.926173) (xy 158.476207 -300.901566) (xy 158.438086 -300.870441) (xy 158.405451 -300.833604)
			(xy 158.379148 -300.792008) (xy 158.359857 -300.746732) (xy 158.34808 -300.698948) (xy 158.34412 -300.649894)
			(xy 158.005272 -300.649894) (xy 158.004777 -300.674501) (xy 157.996882 -300.723078) (xy 157.981298 -300.769759)
			(xy 157.958427 -300.813336) (xy 157.928862 -300.85268) (xy 157.893369 -300.886772) (xy 157.852866 -300.914728)
			(xy 157.808404 -300.935826) (xy 157.761133 -300.949518) (xy 157.712278 -300.95545) (xy 157.663103 -300.953469)
			(xy 157.614884 -300.943625) (xy 157.568868 -300.926173) (xy 157.526247 -300.901566) (xy 157.488126 -300.870441)
			(xy 157.455491 -300.833604) (xy 157.429188 -300.792008) (xy 157.409897 -300.746732) (xy 157.39812 -300.698948)
			(xy 157.39416 -300.649894) (xy 157.055312 -300.649894) (xy 157.054817 -300.674501) (xy 157.046922 -300.723078)
			(xy 157.031338 -300.769759) (xy 157.008467 -300.813336) (xy 156.978902 -300.85268) (xy 156.943409 -300.886772)
			(xy 156.902906 -300.914728) (xy 156.858444 -300.935826) (xy 156.811173 -300.949518) (xy 156.762318 -300.95545)
			(xy 156.713143 -300.953469) (xy 156.664924 -300.943625) (xy 156.618908 -300.926173) (xy 156.576287 -300.901566)
			(xy 156.538166 -300.870441) (xy 156.505531 -300.833604) (xy 156.479228 -300.792008) (xy 156.459937 -300.746732)
			(xy 156.44816 -300.698948) (xy 156.4442 -300.649894) (xy 156.105352 -300.649894) (xy 156.104857 -300.674501)
			(xy 156.096962 -300.723078) (xy 156.081378 -300.769759) (xy 156.058507 -300.813336) (xy 156.028942 -300.85268)
			(xy 155.993449 -300.886772) (xy 155.952946 -300.914728) (xy 155.908484 -300.935826) (xy 155.861213 -300.949518)
			(xy 155.812358 -300.95545) (xy 155.763183 -300.953469) (xy 155.714964 -300.943625) (xy 155.668948 -300.926173)
			(xy 155.626327 -300.901566) (xy 155.588206 -300.870441) (xy 155.555571 -300.833604) (xy 155.529268 -300.792008)
			(xy 155.509977 -300.746732) (xy 155.4982 -300.698948) (xy 155.49424 -300.649894) (xy 155.155392 -300.649894)
			(xy 155.154897 -300.674501) (xy 155.147002 -300.723078) (xy 155.131418 -300.769759) (xy 155.108547 -300.813336)
			(xy 155.078982 -300.85268) (xy 155.043489 -300.886772) (xy 155.002986 -300.914728) (xy 154.958524 -300.935826)
			(xy 154.911253 -300.949518) (xy 154.862398 -300.95545) (xy 154.813223 -300.953469) (xy 154.765004 -300.943625)
			(xy 154.718988 -300.926173) (xy 154.676367 -300.901566) (xy 154.638246 -300.870441) (xy 154.605611 -300.833604)
			(xy 154.579308 -300.792008) (xy 154.560017 -300.746732) (xy 154.54824 -300.698948) (xy 154.54428 -300.649894)
			(xy 154.205178 -300.649894) (xy 154.204683 -300.674501) (xy 154.196788 -300.723078) (xy 154.181204 -300.769759)
			(xy 154.158333 -300.813336) (xy 154.128768 -300.85268) (xy 154.093275 -300.886772) (xy 154.052772 -300.914728)
			(xy 154.00831 -300.935826) (xy 153.961039 -300.949518) (xy 153.912184 -300.95545) (xy 153.863009 -300.953469)
			(xy 153.81479 -300.943625) (xy 153.768774 -300.926173) (xy 153.726153 -300.901566) (xy 153.688032 -300.870441)
			(xy 153.655397 -300.833604) (xy 153.629094 -300.792008) (xy 153.609803 -300.746732) (xy 153.598026 -300.698948)
			(xy 153.594066 -300.649894) (xy 153.255218 -300.649894) (xy 153.254723 -300.674501) (xy 153.246828 -300.723078)
			(xy 153.231244 -300.769759) (xy 153.208373 -300.813336) (xy 153.178808 -300.85268) (xy 153.143315 -300.886772)
			(xy 153.102812 -300.914728) (xy 153.05835 -300.935826) (xy 153.011079 -300.949518) (xy 152.962224 -300.95545)
			(xy 152.913049 -300.953469) (xy 152.86483 -300.943625) (xy 152.818814 -300.926173) (xy 152.776193 -300.901566)
			(xy 152.738072 -300.870441) (xy 152.705437 -300.833604) (xy 152.679134 -300.792008) (xy 152.659843 -300.746732)
			(xy 152.648066 -300.698948) (xy 152.644106 -300.649894) (xy 143.792693 -300.649894) (xy 143.848121 -300.655993)
			(xy 143.902078 -300.670099) (xy 143.953407 -300.691911) (xy 144.001013 -300.720965) (xy 144.043881 -300.75664)
			(xy 144.081098 -300.798177) (xy 144.111871 -300.84469) (xy 144.135543 -300.895187) (xy 144.151611 -300.948594)
			(xy 144.159731 -301.00377) (xy 144.16024 -301.031656) (xy 144.159731 -301.059542) (xy 144.151611 -301.114718)
			(xy 144.135543 -301.168125) (xy 144.111871 -301.218622) (xy 144.081098 -301.265135) (xy 144.043881 -301.306672)
			(xy 144.001013 -301.342347) (xy 143.953407 -301.371401) (xy 143.902078 -301.393213) (xy 143.848121 -301.407319)
			(xy 143.792684 -301.413419) (xy 143.73695 -301.411382) (xy 143.682107 -301.401252) (xy 143.629323 -301.383245)
			(xy 143.579723 -301.357744) (xy 143.534365 -301.325293) (xy 143.494216 -301.286584) (xy 143.46013 -301.242441)
			(xy 143.432834 -301.193806) (xy 143.412911 -301.141715) (xy 143.400785 -301.087278) (xy 143.396714 -301.031656)
			(xy 142.675102 -301.031656) (xy 142.674593 -301.059542) (xy 142.666473 -301.114718) (xy 142.650405 -301.168125)
			(xy 142.626733 -301.218622) (xy 142.59596 -301.265135) (xy 142.558743 -301.306672) (xy 142.515875 -301.342347)
			(xy 142.468269 -301.371401) (xy 142.41694 -301.393213) (xy 142.362983 -301.407319) (xy 142.307546 -301.413419)
			(xy 142.251812 -301.411382) (xy 142.196969 -301.401252) (xy 142.144185 -301.383245) (xy 142.094585 -301.357744)
			(xy 142.049227 -301.325293) (xy 142.009078 -301.286584) (xy 141.974992 -301.242441) (xy 141.947696 -301.193806)
			(xy 141.927773 -301.141715) (xy 141.915647 -301.087278) (xy 141.911576 -301.031656) (xy 118.830852 -301.031656)
			(xy 118.830852 -301.599854) (xy 152.644106 -301.599854) (xy 152.648066 -301.5508) (xy 152.659843 -301.503016)
			(xy 152.679134 -301.45774) (xy 152.705437 -301.416144) (xy 152.738072 -301.379307) (xy 152.776193 -301.348182)
			(xy 152.818814 -301.323575) (xy 152.86483 -301.306123) (xy 152.913049 -301.296279) (xy 152.962224 -301.294298)
			(xy 153.011079 -301.30023) (xy 153.05835 -301.313922) (xy 153.102812 -301.33502) (xy 153.143315 -301.362976)
			(xy 153.178808 -301.397068) (xy 153.208373 -301.436412) (xy 153.231244 -301.479989) (xy 153.246828 -301.52667)
			(xy 153.254723 -301.575247) (xy 153.255218 -301.599854) (xy 153.594066 -301.599854) (xy 153.598026 -301.5508)
			(xy 153.609803 -301.503016) (xy 153.629094 -301.45774) (xy 153.655397 -301.416144) (xy 153.688032 -301.379307)
			(xy 153.726153 -301.348182) (xy 153.768774 -301.323575) (xy 153.81479 -301.306123) (xy 153.863009 -301.296279)
			(xy 153.912184 -301.294298) (xy 153.961039 -301.30023) (xy 154.00831 -301.313922) (xy 154.052772 -301.33502)
			(xy 154.093275 -301.362976) (xy 154.128768 -301.397068) (xy 154.158333 -301.436412) (xy 154.181204 -301.479989)
			(xy 154.196788 -301.52667) (xy 154.204683 -301.575247) (xy 154.205178 -301.599854) (xy 154.204683 -301.624461)
			(xy 154.204504 -301.625562) (xy 154.523436 -301.625562) (xy 154.523436 -301.574146) (xy 154.531479 -301.523364)
			(xy 154.547367 -301.474465) (xy 154.57071 -301.428653) (xy 154.600931 -301.387057) (xy 154.637287 -301.350701)
			(xy 154.678883 -301.32048) (xy 154.724695 -301.297137) (xy 154.773594 -301.281249) (xy 154.824376 -301.273206)
			(xy 154.875792 -301.273206) (xy 154.926574 -301.281249) (xy 154.975473 -301.297137) (xy 155.021285 -301.32048)
			(xy 155.062881 -301.350701) (xy 155.099237 -301.387057) (xy 155.129458 -301.428653) (xy 155.152801 -301.474465)
			(xy 155.168689 -301.523364) (xy 155.176732 -301.574146) (xy 155.177236 -301.599854) (xy 155.176732 -301.625562)
			(xy 155.473396 -301.625562) (xy 155.473396 -301.574146) (xy 155.481439 -301.523364) (xy 155.497327 -301.474465)
			(xy 155.52067 -301.428653) (xy 155.550891 -301.387057) (xy 155.587247 -301.350701) (xy 155.628843 -301.32048)
			(xy 155.674655 -301.297137) (xy 155.723554 -301.281249) (xy 155.774336 -301.273206) (xy 155.825752 -301.273206)
			(xy 155.876534 -301.281249) (xy 155.925433 -301.297137) (xy 155.971245 -301.32048) (xy 156.012841 -301.350701)
			(xy 156.049197 -301.387057) (xy 156.079418 -301.428653) (xy 156.102761 -301.474465) (xy 156.118649 -301.523364)
			(xy 156.126692 -301.574146) (xy 156.127196 -301.599854) (xy 156.4442 -301.599854) (xy 156.44816 -301.5508)
			(xy 156.459937 -301.503016) (xy 156.479228 -301.45774) (xy 156.505531 -301.416144) (xy 156.538166 -301.379307)
			(xy 156.576287 -301.348182) (xy 156.618908 -301.323575) (xy 156.664924 -301.306123) (xy 156.713143 -301.296279)
			(xy 156.762318 -301.294298) (xy 156.811173 -301.30023) (xy 156.858444 -301.313922) (xy 156.902906 -301.33502)
			(xy 156.943409 -301.362976) (xy 156.978902 -301.397068) (xy 157.008467 -301.436412) (xy 157.031338 -301.479989)
			(xy 157.046922 -301.52667) (xy 157.054817 -301.575247) (xy 157.055312 -301.599854) (xy 157.054817 -301.624461)
			(xy 157.054638 -301.625562) (xy 157.373316 -301.625562) (xy 157.373316 -301.574146) (xy 157.381359 -301.523364)
			(xy 157.397247 -301.474465) (xy 157.42059 -301.428653) (xy 157.450811 -301.387057) (xy 157.487167 -301.350701)
			(xy 157.528763 -301.32048) (xy 157.574575 -301.297137) (xy 157.623474 -301.281249) (xy 157.674256 -301.273206)
			(xy 157.725672 -301.273206) (xy 157.776454 -301.281249) (xy 157.825353 -301.297137) (xy 157.871165 -301.32048)
			(xy 157.912761 -301.350701) (xy 157.949117 -301.387057) (xy 157.979338 -301.428653) (xy 158.002681 -301.474465)
			(xy 158.018569 -301.523364) (xy 158.026612 -301.574146) (xy 158.027116 -301.599854) (xy 158.026612 -301.625562)
			(xy 158.323276 -301.625562) (xy 158.323276 -301.574146) (xy 158.331319 -301.523364) (xy 158.347207 -301.474465)
			(xy 158.37055 -301.428653) (xy 158.400771 -301.387057) (xy 158.437127 -301.350701) (xy 158.478723 -301.32048)
			(xy 158.524535 -301.297137) (xy 158.573434 -301.281249) (xy 158.624216 -301.273206) (xy 158.675632 -301.273206)
			(xy 158.726414 -301.281249) (xy 158.775313 -301.297137) (xy 158.821125 -301.32048) (xy 158.862721 -301.350701)
			(xy 158.899077 -301.387057) (xy 158.929298 -301.428653) (xy 158.952641 -301.474465) (xy 158.968529 -301.523364)
			(xy 158.976572 -301.574146) (xy 158.977076 -301.599854) (xy 159.29408 -301.599854) (xy 159.29804 -301.5508)
			(xy 159.309817 -301.503016) (xy 159.329108 -301.45774) (xy 159.355411 -301.416144) (xy 159.388046 -301.379307)
			(xy 159.426167 -301.348182) (xy 159.468788 -301.323575) (xy 159.514804 -301.306123) (xy 159.563023 -301.296279)
			(xy 159.612198 -301.294298) (xy 159.661053 -301.30023) (xy 159.708324 -301.313922) (xy 159.752786 -301.33502)
			(xy 159.793289 -301.362976) (xy 159.828782 -301.397068) (xy 159.858347 -301.436412) (xy 159.881218 -301.479989)
			(xy 159.896802 -301.52667) (xy 159.904697 -301.575247) (xy 159.905026 -301.591602) (xy 160.244035 -301.591602)
			(xy 160.249406 -301.542241) (xy 160.262692 -301.4944) (xy 160.283544 -301.449338) (xy 160.311412 -301.408244)
			(xy 160.345561 -301.372199) (xy 160.385092 -301.342155) (xy 160.428963 -301.318903) (xy 160.476018 -301.303054)
			(xy 160.525018 -301.295028) (xy 160.549844 -301.294546) (xy 160.564091 -301.294708) (xy 160.592459 -301.297381)
			(xy 160.606486 -301.29988) (xy 160.618932 -301.302166) (xy 160.642554 -301.2948) (xy 160.711134 -301.226474)
			(xy 160.719324 -301.217262) (xy 160.726611 -301.193752) (xy 160.725104 -301.181516) (xy 160.725104 -301.181008)
			(xy 160.722645 -301.167104) (xy 160.719971 -301.138993) (xy 160.71977 -301.124874) (xy 160.720292 -301.099619)
			(xy 160.728605 -301.049797) (xy 160.745006 -301.002023) (xy 160.769047 -300.9576) (xy 160.800071 -300.91774)
			(xy 160.837233 -300.88353) (xy 160.879519 -300.855904) (xy 160.925775 -300.835614) (xy 160.97474 -300.823214)
			(xy 161.025078 -300.819043) (xy 161.075416 -300.823214) (xy 161.124381 -300.835614) (xy 161.170637 -300.855904)
			(xy 161.212923 -300.88353) (xy 161.250085 -300.91774) (xy 161.281109 -300.9576) (xy 161.30515 -301.002023)
			(xy 161.321551 -301.049797) (xy 161.329864 -301.099619) (xy 161.330386 -301.124874) (xy 161.330206 -301.139057)
			(xy 161.327536 -301.167297) (xy 161.325052 -301.181262) (xy 161.322766 -301.193708) (xy 161.330132 -301.21733)
			(xy 161.407602 -301.2948) (xy 161.431224 -301.302166) (xy 161.44367 -301.29988) (xy 161.457635 -301.297398)
			(xy 161.485875 -301.29473) (xy 161.500058 -301.294546) (xy 161.514241 -301.294729) (xy 161.542481 -301.297397)
			(xy 161.556446 -301.29988) (xy 161.568892 -301.302166) (xy 161.592514 -301.2948) (xy 161.669984 -301.21733)
			(xy 161.67735 -301.193708) (xy 161.675064 -301.181262) (xy 161.672587 -301.167296) (xy 161.669915 -301.139057)
			(xy 161.66973 -301.124874) (xy 161.670206 -301.100056) (xy 161.67824 -301.051076) (xy 161.694092 -301.00404)
			(xy 161.717344 -300.960188) (xy 161.747384 -300.920675) (xy 161.783421 -300.886543) (xy 161.824505 -300.85869)
			(xy 161.869553 -300.83785) (xy 161.91738 -300.824573) (xy 161.966724 -300.819207) (xy 162.016286 -300.821895)
			(xy 162.064761 -300.832565) (xy 162.110871 -300.850937) (xy 162.153402 -300.876526) (xy 162.191233 -300.908659)
			(xy 162.223367 -300.946488) (xy 162.248958 -300.989018) (xy 162.267331 -301.035127) (xy 162.278004 -301.083602)
			(xy 162.280243 -301.124874) (xy 162.619194 -301.124874) (xy 162.623154 -301.07582) (xy 162.634931 -301.028036)
			(xy 162.654222 -300.98276) (xy 162.680525 -300.941164) (xy 162.71316 -300.904327) (xy 162.751281 -300.873202)
			(xy 162.793902 -300.848595) (xy 162.839918 -300.831143) (xy 162.888137 -300.821299) (xy 162.937312 -300.819318)
			(xy 162.986167 -300.82525) (xy 163.033438 -300.838942) (xy 163.0779 -300.86004) (xy 163.118403 -300.887996)
			(xy 163.153896 -300.922088) (xy 163.183461 -300.961432) (xy 163.206332 -301.005009) (xy 163.221916 -301.05169)
			(xy 163.229811 -301.100267) (xy 163.230306 -301.124874) (xy 163.569154 -301.124874) (xy 163.573114 -301.07582)
			(xy 163.584891 -301.028036) (xy 163.604182 -300.98276) (xy 163.630485 -300.941164) (xy 163.66312 -300.904327)
			(xy 163.701241 -300.873202) (xy 163.743862 -300.848595) (xy 163.789878 -300.831143) (xy 163.838097 -300.821299)
			(xy 163.887272 -300.819318) (xy 163.936127 -300.82525) (xy 163.983398 -300.838942) (xy 164.02786 -300.86004)
			(xy 164.068363 -300.887996) (xy 164.103856 -300.922088) (xy 164.133421 -300.961432) (xy 164.156292 -301.005009)
			(xy 164.171876 -301.05169) (xy 164.179771 -301.100267) (xy 164.180266 -301.124874) (xy 164.179771 -301.149481)
			(xy 164.171876 -301.198058) (xy 164.156292 -301.244739) (xy 164.133421 -301.288316) (xy 164.103856 -301.32766)
			(xy 164.068363 -301.361752) (xy 164.02786 -301.389708) (xy 163.983398 -301.410806) (xy 163.936127 -301.424498)
			(xy 163.887272 -301.43043) (xy 163.838097 -301.428449) (xy 163.789878 -301.418605) (xy 163.743862 -301.401153)
			(xy 163.701241 -301.376546) (xy 163.66312 -301.345421) (xy 163.630485 -301.308584) (xy 163.604182 -301.266988)
			(xy 163.584891 -301.221712) (xy 163.573114 -301.173928) (xy 163.569154 -301.124874) (xy 163.230306 -301.124874)
			(xy 163.229811 -301.149481) (xy 163.221916 -301.198058) (xy 163.206332 -301.244739) (xy 163.183461 -301.288316)
			(xy 163.153896 -301.32766) (xy 163.118403 -301.361752) (xy 163.0779 -301.389708) (xy 163.033438 -301.410806)
			(xy 162.986167 -301.424498) (xy 162.937312 -301.43043) (xy 162.888137 -301.428449) (xy 162.839918 -301.418605)
			(xy 162.793902 -301.401153) (xy 162.751281 -301.376546) (xy 162.71316 -301.345421) (xy 162.680525 -301.308584)
			(xy 162.654222 -301.266988) (xy 162.634931 -301.221712) (xy 162.623154 -301.173928) (xy 162.619194 -301.124874)
			(xy 162.280243 -301.124874) (xy 162.280693 -301.133164) (xy 162.27533 -301.182509) (xy 162.262054 -301.230336)
			(xy 162.241216 -301.275385) (xy 162.213365 -301.31647) (xy 162.179234 -301.352508) (xy 162.139722 -301.382549)
			(xy 162.095871 -301.405804) (xy 162.048836 -301.421657) (xy 161.999856 -301.429693) (xy 161.975038 -301.430182)
			(xy 161.960855 -301.430001) (xy 161.932615 -301.427332) (xy 161.91865 -301.424848) (xy 161.906204 -301.422562)
			(xy 161.882582 -301.429928) (xy 161.805112 -301.507398) (xy 161.797746 -301.53102) (xy 161.800032 -301.543466)
			(xy 161.802514 -301.557431) (xy 161.805182 -301.585671) (xy 161.805366 -301.599854) (xy 161.805184 -301.614037)
			(xy 161.802515 -301.642277) (xy 161.800032 -301.656242) (xy 161.797746 -301.668688) (xy 161.805112 -301.69231)
			(xy 161.882582 -301.76978) (xy 161.906204 -301.777146) (xy 161.91865 -301.77486) (xy 161.932616 -301.772381)
			(xy 161.960855 -301.769711) (xy 161.975038 -301.769526) (xy 162.000294 -301.769983) (xy 162.050117 -301.778302)
			(xy 162.09789 -301.794708) (xy 162.142312 -301.818753) (xy 162.182171 -301.849781) (xy 162.21638 -301.886946)
			(xy 162.244006 -301.929235) (xy 162.264295 -301.975493) (xy 162.276694 -302.02446) (xy 162.280865 -302.0748)
			(xy 162.276694 -302.12514) (xy 162.264295 -302.174107) (xy 162.244006 -302.220365) (xy 162.21638 -302.262654)
			(xy 162.182171 -302.299819) (xy 162.142312 -302.330847) (xy 162.09789 -302.354892) (xy 162.050116 -302.371298)
			(xy 162.000294 -302.379617) (xy 161.975038 -302.380142) (xy 161.960855 -302.37996) (xy 161.932615 -302.377291)
			(xy 161.91865 -302.374808) (xy 161.906204 -302.372522) (xy 161.882582 -302.379888) (xy 161.805112 -302.457358)
			(xy 161.797746 -302.48098) (xy 161.800032 -302.493426) (xy 161.802508 -302.507392) (xy 161.80518 -302.535631)
			(xy 161.805366 -302.549814) (xy 161.805192 -302.563997) (xy 161.802518 -302.592237) (xy 161.800032 -302.606202)
			(xy 161.797746 -302.618648) (xy 161.805112 -302.64227) (xy 161.882582 -302.71974) (xy 161.906204 -302.727106)
			(xy 161.91865 -302.72482) (xy 161.932615 -302.722341) (xy 161.960855 -302.719671) (xy 161.975038 -302.719486)
			(xy 162.000291 -302.720023) (xy 162.050107 -302.728341) (xy 162.097874 -302.744745) (xy 162.142291 -302.768787)
			(xy 162.182144 -302.799811) (xy 162.216349 -302.836971) (xy 162.243971 -302.879254) (xy 162.264257 -302.925506)
			(xy 162.276655 -302.974467) (xy 162.280825 -303.024794) (xy 162.619194 -303.024794) (xy 162.623154 -302.97574)
			(xy 162.634931 -302.927956) (xy 162.654222 -302.88268) (xy 162.680525 -302.841084) (xy 162.71316 -302.804247)
			(xy 162.751281 -302.773122) (xy 162.793902 -302.748515) (xy 162.839918 -302.731063) (xy 162.888137 -302.721219)
			(xy 162.937312 -302.719238) (xy 162.986167 -302.72517) (xy 163.033438 -302.738862) (xy 163.0779 -302.75996)
			(xy 163.118403 -302.787916) (xy 163.153896 -302.822008) (xy 163.183461 -302.861352) (xy 163.206332 -302.904929)
			(xy 163.221916 -302.95161) (xy 163.229811 -303.000187) (xy 163.230306 -303.024794) (xy 163.569154 -303.024794)
			(xy 163.573114 -302.97574) (xy 163.584891 -302.927956) (xy 163.604182 -302.88268) (xy 163.630485 -302.841084)
			(xy 163.66312 -302.804247) (xy 163.701241 -302.773122) (xy 163.743862 -302.748515) (xy 163.789878 -302.731063)
			(xy 163.838097 -302.721219) (xy 163.887272 -302.719238) (xy 163.936127 -302.72517) (xy 163.983398 -302.738862)
			(xy 164.02786 -302.75996) (xy 164.068363 -302.787916) (xy 164.103856 -302.822008) (xy 164.133421 -302.861352)
			(xy 164.156292 -302.904929) (xy 164.171876 -302.95161) (xy 164.179771 -303.000187) (xy 164.180266 -303.024794)
			(xy 164.519114 -303.024794) (xy 164.523074 -302.97574) (xy 164.534851 -302.927956) (xy 164.554142 -302.88268)
			(xy 164.580445 -302.841084) (xy 164.61308 -302.804247) (xy 164.651201 -302.773122) (xy 164.693822 -302.748515)
			(xy 164.739838 -302.731063) (xy 164.788057 -302.721219) (xy 164.837232 -302.719238) (xy 164.886087 -302.72517)
			(xy 164.933358 -302.738862) (xy 164.97782 -302.75996) (xy 165.018323 -302.787916) (xy 165.053816 -302.822008)
			(xy 165.083381 -302.861352) (xy 165.106252 -302.904929) (xy 165.121836 -302.95161) (xy 165.129731 -303.000187)
			(xy 165.130226 -303.024794) (xy 165.129731 -303.049401) (xy 165.121836 -303.097978) (xy 165.106252 -303.144659)
			(xy 165.083381 -303.188236) (xy 165.053816 -303.22758) (xy 165.018323 -303.261672) (xy 164.97782 -303.289628)
			(xy 164.933358 -303.310726) (xy 164.886087 -303.324418) (xy 164.837232 -303.33035) (xy 164.788057 -303.328369)
			(xy 164.739838 -303.318525) (xy 164.693822 -303.301073) (xy 164.651201 -303.276466) (xy 164.61308 -303.245341)
			(xy 164.580445 -303.208504) (xy 164.554142 -303.166908) (xy 164.534851 -303.121632) (xy 164.523074 -303.073848)
			(xy 164.519114 -303.024794) (xy 164.180266 -303.024794) (xy 164.179771 -303.049401) (xy 164.171876 -303.097978)
			(xy 164.156292 -303.144659) (xy 164.133421 -303.188236) (xy 164.103856 -303.22758) (xy 164.068363 -303.261672)
			(xy 164.02786 -303.289628) (xy 163.983398 -303.310726) (xy 163.936127 -303.324418) (xy 163.887272 -303.33035)
			(xy 163.838097 -303.328369) (xy 163.789878 -303.318525) (xy 163.743862 -303.301073) (xy 163.701241 -303.276466)
			(xy 163.66312 -303.245341) (xy 163.630485 -303.208504) (xy 163.604182 -303.166908) (xy 163.584891 -303.121632)
			(xy 163.573114 -303.073848) (xy 163.569154 -303.024794) (xy 163.230306 -303.024794) (xy 163.229811 -303.049401)
			(xy 163.221916 -303.097978) (xy 163.206332 -303.144659) (xy 163.183461 -303.188236) (xy 163.153896 -303.22758)
			(xy 163.118403 -303.261672) (xy 163.0779 -303.289628) (xy 163.033438 -303.310726) (xy 162.986167 -303.324418)
			(xy 162.937312 -303.33035) (xy 162.888137 -303.328369) (xy 162.839918 -303.318525) (xy 162.793902 -303.301073)
			(xy 162.751281 -303.276466) (xy 162.71316 -303.245341) (xy 162.680525 -303.208504) (xy 162.654222 -303.166908)
			(xy 162.634931 -303.121632) (xy 162.623154 -303.073848) (xy 162.619194 -303.024794) (xy 162.280825 -303.024794)
			(xy 162.280825 -303.0248) (xy 162.276655 -303.075133) (xy 162.264257 -303.124094) (xy 162.243971 -303.170346)
			(xy 162.216349 -303.212629) (xy 162.182144 -303.249789) (xy 162.142291 -303.280813) (xy 162.097874 -303.304855)
			(xy 162.050107 -303.321259) (xy 162.000291 -303.329577) (xy 161.975038 -303.330102) (xy 161.960855 -303.32992)
			(xy 161.932615 -303.327252) (xy 161.91865 -303.324768) (xy 161.906204 -303.322482) (xy 161.882582 -303.329848)
			(xy 161.805112 -303.407318) (xy 161.797746 -303.43094) (xy 161.800032 -303.443386) (xy 161.802503 -303.457353)
			(xy 161.805178 -303.485592) (xy 161.805366 -303.499774) (xy 161.80495 -303.524597) (xy 161.796923 -303.573589)
			(xy 161.781075 -303.620637) (xy 161.757825 -303.664501) (xy 161.727784 -303.704026) (xy 161.691745 -303.738171)
			(xy 161.650657 -303.766035) (xy 161.605602 -303.786885) (xy 161.557768 -303.800171) (xy 161.508414 -303.805544)
			(xy 161.458841 -303.802861) (xy 161.410355 -303.792194) (xy 161.364234 -303.773823) (xy 161.321692 -303.748233)
			(xy 161.283851 -303.716098) (xy 161.251707 -303.678263) (xy 161.226107 -303.635727) (xy 161.207726 -303.58961)
			(xy 161.197048 -303.541127) (xy 161.194354 -303.491554) (xy 161.199716 -303.442199) (xy 161.212991 -303.394362)
			(xy 161.233831 -303.349302) (xy 161.261687 -303.308208) (xy 161.295823 -303.272161) (xy 161.335341 -303.242112)
			(xy 161.379201 -303.218852) (xy 161.426245 -303.202994) (xy 161.475235 -303.194955) (xy 161.500058 -303.194466)
			(xy 161.514241 -303.194649) (xy 161.542481 -303.197317) (xy 161.556446 -303.1998) (xy 161.568892 -303.202086)
			(xy 161.592514 -303.19472) (xy 161.669984 -303.11725) (xy 161.67735 -303.093628) (xy 161.675064 -303.081182)
			(xy 161.67259 -303.067216) (xy 161.669916 -303.038976) (xy 161.66973 -303.024794) (xy 161.669905 -303.010611)
			(xy 161.672578 -302.982371) (xy 161.675064 -302.968406) (xy 161.67735 -302.95596) (xy 161.669984 -302.932338)
			(xy 161.592514 -302.854868) (xy 161.568892 -302.847502) (xy 161.556446 -302.849788) (xy 161.542481 -302.852268)
			(xy 161.514241 -302.854937) (xy 161.500058 -302.855122) (xy 161.474806 -302.854569) (xy 161.424992 -302.84625)
			(xy 161.377226 -302.829847) (xy 161.332812 -302.805805) (xy 161.292959 -302.774782) (xy 161.258757 -302.737623)
			(xy 161.231136 -302.695341) (xy 161.21085 -302.64909) (xy 161.198453 -302.600131) (xy 161.194283 -302.5498)
			(xy 161.198453 -302.499469) (xy 161.21085 -302.45051) (xy 161.231136 -302.404259) (xy 161.258757 -302.361977)
			(xy 161.292959 -302.324818) (xy 161.332812 -302.293795) (xy 161.377226 -302.269753) (xy 161.424992 -302.25335)
			(xy 161.474806 -302.245031) (xy 161.500058 -302.244506) (xy 161.514241 -302.244688) (xy 161.542481 -302.247357)
			(xy 161.556446 -302.24984) (xy 161.568892 -302.252126) (xy 161.592514 -302.24476) (xy 161.669984 -302.16729)
			(xy 161.67735 -302.143668) (xy 161.675064 -302.131222) (xy 161.672581 -302.117257) (xy 161.669914 -302.089017)
			(xy 161.66973 -302.074834) (xy 161.669911 -302.060651) (xy 161.67258 -302.032411) (xy 161.675064 -302.018446)
			(xy 161.67735 -302.006) (xy 161.669984 -301.982378) (xy 161.592514 -301.904908) (xy 161.568892 -301.897542)
			(xy 161.556446 -301.899828) (xy 161.542481 -301.902308) (xy 161.514241 -301.904977) (xy 161.500058 -301.905162)
			(xy 161.476061 -301.9048) (xy 161.42866 -301.897286) (xy 161.383018 -301.882449) (xy 161.340259 -301.860654)
			(xy 161.301435 -301.832439) (xy 161.267504 -301.798498) (xy 161.2393 -301.759666) (xy 161.217517 -301.716901)
			(xy 161.202693 -301.671254) (xy 161.195193 -301.623851) (xy 161.19475 -301.599854) (xy 161.194935 -301.585671)
			(xy 161.197602 -301.557431) (xy 161.200084 -301.543466) (xy 161.20237 -301.53102) (xy 161.195004 -301.507398)
			(xy 161.117534 -301.429928) (xy 161.093912 -301.422562) (xy 161.081466 -301.424848) (xy 161.0675 -301.427325)
			(xy 161.039261 -301.429996) (xy 161.025078 -301.430182) (xy 161.010831 -301.430011) (xy 160.982464 -301.427341)
			(xy 160.968436 -301.424848) (xy 160.95599 -301.422562) (xy 160.932368 -301.429928) (xy 160.863788 -301.498254)
			(xy 160.855641 -301.507499) (xy 160.848328 -301.530983) (xy 160.849818 -301.543212) (xy 160.849818 -301.54372)
			(xy 160.85228 -301.557624) (xy 160.854952 -301.585735) (xy 160.855152 -301.599854) (xy 160.854672 -301.62468)
			(xy 160.846646 -301.67368) (xy 160.830798 -301.720735) (xy 160.807546 -301.764606) (xy 160.777502 -301.804137)
			(xy 160.741458 -301.838287) (xy 160.700364 -301.866155) (xy 160.655302 -301.887007) (xy 160.60746 -301.900294)
			(xy 160.5581 -301.905665) (xy 160.50852 -301.902979) (xy 160.460028 -301.892307) (xy 160.413902 -301.87393)
			(xy 160.371356 -301.848333) (xy 160.333513 -301.816189) (xy 160.301368 -301.778346) (xy 160.275771 -301.7358)
			(xy 160.257393 -301.689674) (xy 160.246721 -301.641182) (xy 160.244035 -301.591602) (xy 159.905026 -301.591602)
			(xy 159.905192 -301.599854) (xy 159.904697 -301.624461) (xy 159.896802 -301.673038) (xy 159.881218 -301.719719)
			(xy 159.858347 -301.763296) (xy 159.828782 -301.80264) (xy 159.793289 -301.836732) (xy 159.752786 -301.864688)
			(xy 159.708324 -301.885786) (xy 159.661053 -301.899478) (xy 159.612198 -301.90541) (xy 159.563023 -301.903429)
			(xy 159.514804 -301.893585) (xy 159.468788 -301.876133) (xy 159.426167 -301.851526) (xy 159.388046 -301.820401)
			(xy 159.355411 -301.783564) (xy 159.329108 -301.741968) (xy 159.309817 -301.696692) (xy 159.29804 -301.648908)
			(xy 159.29408 -301.599854) (xy 158.977076 -301.599854) (xy 158.976572 -301.625562) (xy 158.968529 -301.676344)
			(xy 158.952641 -301.725243) (xy 158.929298 -301.771055) (xy 158.899077 -301.812651) (xy 158.862721 -301.849007)
			(xy 158.821125 -301.879228) (xy 158.775313 -301.902571) (xy 158.726414 -301.918459) (xy 158.675632 -301.926502)
			(xy 158.624216 -301.926502) (xy 158.573434 -301.918459) (xy 158.524535 -301.902571) (xy 158.478723 -301.879228)
			(xy 158.437127 -301.849007) (xy 158.400771 -301.812651) (xy 158.37055 -301.771055) (xy 158.347207 -301.725243)
			(xy 158.331319 -301.676344) (xy 158.323276 -301.625562) (xy 158.026612 -301.625562) (xy 158.018569 -301.676344)
			(xy 158.002681 -301.725243) (xy 157.979338 -301.771055) (xy 157.949117 -301.812651) (xy 157.912761 -301.849007)
			(xy 157.871165 -301.879228) (xy 157.825353 -301.902571) (xy 157.776454 -301.918459) (xy 157.725672 -301.926502)
			(xy 157.674256 -301.926502) (xy 157.623474 -301.918459) (xy 157.574575 -301.902571) (xy 157.528763 -301.879228)
			(xy 157.487167 -301.849007) (xy 157.450811 -301.812651) (xy 157.42059 -301.771055) (xy 157.397247 -301.725243)
			(xy 157.381359 -301.676344) (xy 157.373316 -301.625562) (xy 157.054638 -301.625562) (xy 157.046922 -301.673038)
			(xy 157.031338 -301.719719) (xy 157.008467 -301.763296) (xy 156.978902 -301.80264) (xy 156.943409 -301.836732)
			(xy 156.902906 -301.864688) (xy 156.858444 -301.885786) (xy 156.811173 -301.899478) (xy 156.762318 -301.90541)
			(xy 156.713143 -301.903429) (xy 156.664924 -301.893585) (xy 156.618908 -301.876133) (xy 156.576287 -301.851526)
			(xy 156.538166 -301.820401) (xy 156.505531 -301.783564) (xy 156.479228 -301.741968) (xy 156.459937 -301.696692)
			(xy 156.44816 -301.648908) (xy 156.4442 -301.599854) (xy 156.127196 -301.599854) (xy 156.126692 -301.625562)
			(xy 156.118649 -301.676344) (xy 156.102761 -301.725243) (xy 156.079418 -301.771055) (xy 156.049197 -301.812651)
			(xy 156.012841 -301.849007) (xy 155.971245 -301.879228) (xy 155.925433 -301.902571) (xy 155.876534 -301.918459)
			(xy 155.825752 -301.926502) (xy 155.774336 -301.926502) (xy 155.723554 -301.918459) (xy 155.674655 -301.902571)
			(xy 155.628843 -301.879228) (xy 155.587247 -301.849007) (xy 155.550891 -301.812651) (xy 155.52067 -301.771055)
			(xy 155.497327 -301.725243) (xy 155.481439 -301.676344) (xy 155.473396 -301.625562) (xy 155.176732 -301.625562)
			(xy 155.168689 -301.676344) (xy 155.152801 -301.725243) (xy 155.129458 -301.771055) (xy 155.099237 -301.812651)
			(xy 155.062881 -301.849007) (xy 155.021285 -301.879228) (xy 154.975473 -301.902571) (xy 154.926574 -301.918459)
			(xy 154.875792 -301.926502) (xy 154.824376 -301.926502) (xy 154.773594 -301.918459) (xy 154.724695 -301.902571)
			(xy 154.678883 -301.879228) (xy 154.637287 -301.849007) (xy 154.600931 -301.812651) (xy 154.57071 -301.771055)
			(xy 154.547367 -301.725243) (xy 154.531479 -301.676344) (xy 154.523436 -301.625562) (xy 154.204504 -301.625562)
			(xy 154.196788 -301.673038) (xy 154.181204 -301.719719) (xy 154.158333 -301.763296) (xy 154.128768 -301.80264)
			(xy 154.093275 -301.836732) (xy 154.052772 -301.864688) (xy 154.00831 -301.885786) (xy 153.961039 -301.899478)
			(xy 153.912184 -301.90541) (xy 153.863009 -301.903429) (xy 153.81479 -301.893585) (xy 153.768774 -301.876133)
			(xy 153.726153 -301.851526) (xy 153.688032 -301.820401) (xy 153.655397 -301.783564) (xy 153.629094 -301.741968)
			(xy 153.609803 -301.696692) (xy 153.598026 -301.648908) (xy 153.594066 -301.599854) (xy 153.255218 -301.599854)
			(xy 153.254723 -301.624461) (xy 153.246828 -301.673038) (xy 153.231244 -301.719719) (xy 153.208373 -301.763296)
			(xy 153.178808 -301.80264) (xy 153.143315 -301.836732) (xy 153.102812 -301.864688) (xy 153.05835 -301.885786)
			(xy 153.011079 -301.899478) (xy 152.962224 -301.90541) (xy 152.913049 -301.903429) (xy 152.86483 -301.893585)
			(xy 152.818814 -301.876133) (xy 152.776193 -301.851526) (xy 152.738072 -301.820401) (xy 152.705437 -301.783564)
			(xy 152.679134 -301.741968) (xy 152.659843 -301.696692) (xy 152.648066 -301.648908) (xy 152.644106 -301.599854)
			(xy 118.830852 -301.599854) (xy 118.830852 -302.550068) (xy 151.693892 -302.550068) (xy 151.697852 -302.501014)
			(xy 151.709629 -302.45323) (xy 151.72892 -302.407954) (xy 151.755223 -302.366358) (xy 151.787858 -302.329521)
			(xy 151.825979 -302.298396) (xy 151.8686 -302.273789) (xy 151.914616 -302.256337) (xy 151.962835 -302.246493)
			(xy 152.01201 -302.244512) (xy 152.060865 -302.250444) (xy 152.108136 -302.264136) (xy 152.152598 -302.285234)
			(xy 152.193101 -302.31319) (xy 152.228594 -302.347282) (xy 152.258159 -302.386626) (xy 152.28103 -302.430203)
			(xy 152.296614 -302.476884) (xy 152.304509 -302.525461) (xy 152.305004 -302.550068) (xy 152.304509 -302.574675)
			(xy 152.304371 -302.575522) (xy 152.623262 -302.575522) (xy 152.623262 -302.524106) (xy 152.631305 -302.473324)
			(xy 152.647193 -302.424425) (xy 152.670536 -302.378613) (xy 152.700757 -302.337017) (xy 152.737113 -302.300661)
			(xy 152.778709 -302.27044) (xy 152.824521 -302.247097) (xy 152.87342 -302.231209) (xy 152.924202 -302.223166)
			(xy 152.975618 -302.223166) (xy 153.0264 -302.231209) (xy 153.075299 -302.247097) (xy 153.121111 -302.27044)
			(xy 153.162707 -302.300661) (xy 153.199063 -302.337017) (xy 153.229284 -302.378613) (xy 153.252627 -302.424425)
			(xy 153.268515 -302.473324) (xy 153.276558 -302.524106) (xy 153.277062 -302.549814) (xy 153.276558 -302.575522)
			(xy 153.573222 -302.575522) (xy 153.573222 -302.524106) (xy 153.581265 -302.473324) (xy 153.597153 -302.424425)
			(xy 153.620496 -302.378613) (xy 153.650717 -302.337017) (xy 153.687073 -302.300661) (xy 153.728669 -302.27044)
			(xy 153.774481 -302.247097) (xy 153.82338 -302.231209) (xy 153.874162 -302.223166) (xy 153.925578 -302.223166)
			(xy 153.97636 -302.231209) (xy 154.025259 -302.247097) (xy 154.071071 -302.27044) (xy 154.112667 -302.300661)
			(xy 154.149023 -302.337017) (xy 154.179244 -302.378613) (xy 154.202587 -302.424425) (xy 154.218475 -302.473324)
			(xy 154.226518 -302.524106) (xy 154.227022 -302.549814) (xy 154.54428 -302.549814) (xy 154.54824 -302.50076)
			(xy 154.560017 -302.452976) (xy 154.579308 -302.4077) (xy 154.605611 -302.366104) (xy 154.638246 -302.329267)
			(xy 154.676367 -302.298142) (xy 154.718988 -302.273535) (xy 154.765004 -302.256083) (xy 154.813223 -302.246239)
			(xy 154.862398 -302.244258) (xy 154.911253 -302.25019) (xy 154.958524 -302.263882) (xy 155.002986 -302.28498)
			(xy 155.043489 -302.312936) (xy 155.078982 -302.347028) (xy 155.108547 -302.386372) (xy 155.131418 -302.429949)
			(xy 155.147002 -302.47663) (xy 155.154897 -302.525207) (xy 155.155392 -302.549814) (xy 155.49424 -302.549814)
			(xy 155.4982 -302.50076) (xy 155.509977 -302.452976) (xy 155.529268 -302.4077) (xy 155.555571 -302.366104)
			(xy 155.588206 -302.329267) (xy 155.626327 -302.298142) (xy 155.668948 -302.273535) (xy 155.714964 -302.256083)
			(xy 155.763183 -302.246239) (xy 155.812358 -302.244258) (xy 155.861213 -302.25019) (xy 155.908484 -302.263882)
			(xy 155.952946 -302.28498) (xy 155.993449 -302.312936) (xy 156.028942 -302.347028) (xy 156.058507 -302.386372)
			(xy 156.081378 -302.429949) (xy 156.096962 -302.47663) (xy 156.104857 -302.525207) (xy 156.105352 -302.549814)
			(xy 156.4442 -302.549814) (xy 156.44816 -302.50076) (xy 156.459937 -302.452976) (xy 156.479228 -302.4077)
			(xy 156.505531 -302.366104) (xy 156.538166 -302.329267) (xy 156.576287 -302.298142) (xy 156.618908 -302.273535)
			(xy 156.664924 -302.256083) (xy 156.713143 -302.246239) (xy 156.762318 -302.244258) (xy 156.811173 -302.25019)
			(xy 156.858444 -302.263882) (xy 156.902906 -302.28498) (xy 156.943409 -302.312936) (xy 156.978902 -302.347028)
			(xy 157.008467 -302.386372) (xy 157.031338 -302.429949) (xy 157.046922 -302.47663) (xy 157.054817 -302.525207)
			(xy 157.055312 -302.549814) (xy 157.39416 -302.549814) (xy 157.39812 -302.50076) (xy 157.409897 -302.452976)
			(xy 157.429188 -302.4077) (xy 157.455491 -302.366104) (xy 157.488126 -302.329267) (xy 157.526247 -302.298142)
			(xy 157.568868 -302.273535) (xy 157.614884 -302.256083) (xy 157.663103 -302.246239) (xy 157.712278 -302.244258)
			(xy 157.761133 -302.25019) (xy 157.808404 -302.263882) (xy 157.852866 -302.28498) (xy 157.893369 -302.312936)
			(xy 157.928862 -302.347028) (xy 157.958427 -302.386372) (xy 157.981298 -302.429949) (xy 157.996882 -302.47663)
			(xy 158.004777 -302.525207) (xy 158.005272 -302.549814) (xy 158.34412 -302.549814) (xy 158.34808 -302.50076)
			(xy 158.359857 -302.452976) (xy 158.379148 -302.4077) (xy 158.405451 -302.366104) (xy 158.438086 -302.329267)
			(xy 158.476207 -302.298142) (xy 158.518828 -302.273535) (xy 158.564844 -302.256083) (xy 158.613063 -302.246239)
			(xy 158.662238 -302.244258) (xy 158.711093 -302.25019) (xy 158.758364 -302.263882) (xy 158.802826 -302.28498)
			(xy 158.843329 -302.312936) (xy 158.878822 -302.347028) (xy 158.908387 -302.386372) (xy 158.931258 -302.429949)
			(xy 158.946842 -302.47663) (xy 158.954737 -302.525207) (xy 158.955232 -302.549814) (xy 158.954737 -302.574421)
			(xy 158.954558 -302.575522) (xy 159.273236 -302.575522) (xy 159.273236 -302.524106) (xy 159.281279 -302.473324)
			(xy 159.297167 -302.424425) (xy 159.32051 -302.378613) (xy 159.350731 -302.337017) (xy 159.387087 -302.300661)
			(xy 159.428683 -302.27044) (xy 159.474495 -302.247097) (xy 159.523394 -302.231209) (xy 159.574176 -302.223166)
			(xy 159.625592 -302.223166) (xy 159.676374 -302.231209) (xy 159.725273 -302.247097) (xy 159.771085 -302.27044)
			(xy 159.812681 -302.300661) (xy 159.849037 -302.337017) (xy 159.879258 -302.378613) (xy 159.902601 -302.424425)
			(xy 159.918489 -302.473324) (xy 159.926532 -302.524106) (xy 159.927036 -302.549814) (xy 159.926532 -302.575522)
			(xy 160.223196 -302.575522) (xy 160.223196 -302.524106) (xy 160.231239 -302.473324) (xy 160.247127 -302.424425)
			(xy 160.27047 -302.378613) (xy 160.300691 -302.337017) (xy 160.337047 -302.300661) (xy 160.378643 -302.27044)
			(xy 160.424455 -302.247097) (xy 160.473354 -302.231209) (xy 160.524136 -302.223166) (xy 160.575552 -302.223166)
			(xy 160.626334 -302.231209) (xy 160.675233 -302.247097) (xy 160.721045 -302.27044) (xy 160.762641 -302.300661)
			(xy 160.798997 -302.337017) (xy 160.829218 -302.378613) (xy 160.852561 -302.424425) (xy 160.868449 -302.473324)
			(xy 160.876492 -302.524106) (xy 160.876996 -302.549814) (xy 160.876492 -302.575522) (xy 160.868449 -302.626304)
			(xy 160.852561 -302.675203) (xy 160.829218 -302.721015) (xy 160.798997 -302.762611) (xy 160.762641 -302.798967)
			(xy 160.721045 -302.829188) (xy 160.675233 -302.852531) (xy 160.626334 -302.868419) (xy 160.575552 -302.876462)
			(xy 160.524136 -302.876462) (xy 160.473354 -302.868419) (xy 160.424455 -302.852531) (xy 160.378643 -302.829188)
			(xy 160.337047 -302.798967) (xy 160.300691 -302.762611) (xy 160.27047 -302.721015) (xy 160.247127 -302.675203)
			(xy 160.231239 -302.626304) (xy 160.223196 -302.575522) (xy 159.926532 -302.575522) (xy 159.918489 -302.626304)
			(xy 159.902601 -302.675203) (xy 159.879258 -302.721015) (xy 159.849037 -302.762611) (xy 159.812681 -302.798967)
			(xy 159.771085 -302.829188) (xy 159.725273 -302.852531) (xy 159.676374 -302.868419) (xy 159.625592 -302.876462)
			(xy 159.574176 -302.876462) (xy 159.523394 -302.868419) (xy 159.474495 -302.852531) (xy 159.428683 -302.829188)
			(xy 159.387087 -302.798967) (xy 159.350731 -302.762611) (xy 159.32051 -302.721015) (xy 159.297167 -302.675203)
			(xy 159.281279 -302.626304) (xy 159.273236 -302.575522) (xy 158.954558 -302.575522) (xy 158.946842 -302.622998)
			(xy 158.931258 -302.669679) (xy 158.908387 -302.713256) (xy 158.878822 -302.7526) (xy 158.843329 -302.786692)
			(xy 158.802826 -302.814648) (xy 158.758364 -302.835746) (xy 158.711093 -302.849438) (xy 158.662238 -302.85537)
			(xy 158.613063 -302.853389) (xy 158.564844 -302.843545) (xy 158.518828 -302.826093) (xy 158.476207 -302.801486)
			(xy 158.438086 -302.770361) (xy 158.405451 -302.733524) (xy 158.379148 -302.691928) (xy 158.359857 -302.646652)
			(xy 158.34808 -302.598868) (xy 158.34412 -302.549814) (xy 158.005272 -302.549814) (xy 158.004777 -302.574421)
			(xy 157.996882 -302.622998) (xy 157.981298 -302.669679) (xy 157.958427 -302.713256) (xy 157.928862 -302.7526)
			(xy 157.893369 -302.786692) (xy 157.852866 -302.814648) (xy 157.808404 -302.835746) (xy 157.761133 -302.849438)
			(xy 157.712278 -302.85537) (xy 157.663103 -302.853389) (xy 157.614884 -302.843545) (xy 157.568868 -302.826093)
			(xy 157.526247 -302.801486) (xy 157.488126 -302.770361) (xy 157.455491 -302.733524) (xy 157.429188 -302.691928)
			(xy 157.409897 -302.646652) (xy 157.39812 -302.598868) (xy 157.39416 -302.549814) (xy 157.055312 -302.549814)
			(xy 157.054817 -302.574421) (xy 157.046922 -302.622998) (xy 157.031338 -302.669679) (xy 157.008467 -302.713256)
			(xy 156.978902 -302.7526) (xy 156.943409 -302.786692) (xy 156.902906 -302.814648) (xy 156.858444 -302.835746)
			(xy 156.811173 -302.849438) (xy 156.762318 -302.85537) (xy 156.713143 -302.853389) (xy 156.664924 -302.843545)
			(xy 156.618908 -302.826093) (xy 156.576287 -302.801486) (xy 156.538166 -302.770361) (xy 156.505531 -302.733524)
			(xy 156.479228 -302.691928) (xy 156.459937 -302.646652) (xy 156.44816 -302.598868) (xy 156.4442 -302.549814)
			(xy 156.105352 -302.549814) (xy 156.104857 -302.574421) (xy 156.096962 -302.622998) (xy 156.081378 -302.669679)
			(xy 156.058507 -302.713256) (xy 156.028942 -302.7526) (xy 155.993449 -302.786692) (xy 155.952946 -302.814648)
			(xy 155.908484 -302.835746) (xy 155.861213 -302.849438) (xy 155.812358 -302.85537) (xy 155.763183 -302.853389)
			(xy 155.714964 -302.843545) (xy 155.668948 -302.826093) (xy 155.626327 -302.801486) (xy 155.588206 -302.770361)
			(xy 155.555571 -302.733524) (xy 155.529268 -302.691928) (xy 155.509977 -302.646652) (xy 155.4982 -302.598868)
			(xy 155.49424 -302.549814) (xy 155.155392 -302.549814) (xy 155.154897 -302.574421) (xy 155.147002 -302.622998)
			(xy 155.131418 -302.669679) (xy 155.108547 -302.713256) (xy 155.078982 -302.7526) (xy 155.043489 -302.786692)
			(xy 155.002986 -302.814648) (xy 154.958524 -302.835746) (xy 154.911253 -302.849438) (xy 154.862398 -302.85537)
			(xy 154.813223 -302.853389) (xy 154.765004 -302.843545) (xy 154.718988 -302.826093) (xy 154.676367 -302.801486)
			(xy 154.638246 -302.770361) (xy 154.605611 -302.733524) (xy 154.579308 -302.691928) (xy 154.560017 -302.646652)
			(xy 154.54824 -302.598868) (xy 154.54428 -302.549814) (xy 154.227022 -302.549814) (xy 154.226518 -302.575522)
			(xy 154.218475 -302.626304) (xy 154.202587 -302.675203) (xy 154.179244 -302.721015) (xy 154.149023 -302.762611)
			(xy 154.112667 -302.798967) (xy 154.071071 -302.829188) (xy 154.025259 -302.852531) (xy 153.97636 -302.868419)
			(xy 153.925578 -302.876462) (xy 153.874162 -302.876462) (xy 153.82338 -302.868419) (xy 153.774481 -302.852531)
			(xy 153.728669 -302.829188) (xy 153.687073 -302.798967) (xy 153.650717 -302.762611) (xy 153.620496 -302.721015)
			(xy 153.597153 -302.675203) (xy 153.581265 -302.626304) (xy 153.573222 -302.575522) (xy 153.276558 -302.575522)
			(xy 153.268515 -302.626304) (xy 153.252627 -302.675203) (xy 153.229284 -302.721015) (xy 153.199063 -302.762611)
			(xy 153.162707 -302.798967) (xy 153.121111 -302.829188) (xy 153.075299 -302.852531) (xy 153.0264 -302.868419)
			(xy 152.975618 -302.876462) (xy 152.924202 -302.876462) (xy 152.87342 -302.868419) (xy 152.824521 -302.852531)
			(xy 152.778709 -302.829188) (xy 152.737113 -302.798967) (xy 152.700757 -302.762611) (xy 152.670536 -302.721015)
			(xy 152.647193 -302.675203) (xy 152.631305 -302.626304) (xy 152.623262 -302.575522) (xy 152.304371 -302.575522)
			(xy 152.296614 -302.623252) (xy 152.28103 -302.669933) (xy 152.258159 -302.71351) (xy 152.228594 -302.752854)
			(xy 152.193101 -302.786946) (xy 152.152598 -302.814902) (xy 152.108136 -302.836) (xy 152.060865 -302.849692)
			(xy 152.01201 -302.855624) (xy 151.962835 -302.853643) (xy 151.914616 -302.843799) (xy 151.8686 -302.826347)
			(xy 151.825979 -302.80174) (xy 151.787858 -302.770615) (xy 151.755223 -302.733778) (xy 151.72892 -302.692182)
			(xy 151.709629 -302.646906) (xy 151.697852 -302.599122) (xy 151.693892 -302.550068) (xy 118.830852 -302.550068)
			(xy 118.830852 -303.499774) (xy 152.644106 -303.499774) (xy 152.648066 -303.45072) (xy 152.659843 -303.402936)
			(xy 152.679134 -303.35766) (xy 152.705437 -303.316064) (xy 152.738072 -303.279227) (xy 152.776193 -303.248102)
			(xy 152.818814 -303.223495) (xy 152.86483 -303.206043) (xy 152.913049 -303.196199) (xy 152.962224 -303.194218)
			(xy 153.011079 -303.20015) (xy 153.05835 -303.213842) (xy 153.102812 -303.23494) (xy 153.143315 -303.262896)
			(xy 153.178808 -303.296988) (xy 153.208373 -303.336332) (xy 153.231244 -303.379909) (xy 153.246828 -303.42659)
			(xy 153.254723 -303.475167) (xy 153.255218 -303.499774) (xy 153.594066 -303.499774) (xy 153.598026 -303.45072)
			(xy 153.609803 -303.402936) (xy 153.629094 -303.35766) (xy 153.655397 -303.316064) (xy 153.688032 -303.279227)
			(xy 153.726153 -303.248102) (xy 153.768774 -303.223495) (xy 153.81479 -303.206043) (xy 153.863009 -303.196199)
			(xy 153.912184 -303.194218) (xy 153.961039 -303.20015) (xy 154.00831 -303.213842) (xy 154.052772 -303.23494)
			(xy 154.093275 -303.262896) (xy 154.128768 -303.296988) (xy 154.158333 -303.336332) (xy 154.181204 -303.379909)
			(xy 154.196788 -303.42659) (xy 154.204683 -303.475167) (xy 154.205178 -303.499774) (xy 154.204683 -303.524381)
			(xy 154.204504 -303.525482) (xy 154.523436 -303.525482) (xy 154.523436 -303.474066) (xy 154.531479 -303.423284)
			(xy 154.547367 -303.374385) (xy 154.57071 -303.328573) (xy 154.600931 -303.286977) (xy 154.637287 -303.250621)
			(xy 154.678883 -303.2204) (xy 154.724695 -303.197057) (xy 154.773594 -303.181169) (xy 154.824376 -303.173126)
			(xy 154.875792 -303.173126) (xy 154.926574 -303.181169) (xy 154.975473 -303.197057) (xy 155.021285 -303.2204)
			(xy 155.062881 -303.250621) (xy 155.099237 -303.286977) (xy 155.129458 -303.328573) (xy 155.152801 -303.374385)
			(xy 155.168689 -303.423284) (xy 155.176732 -303.474066) (xy 155.177236 -303.499774) (xy 155.176732 -303.525482)
			(xy 155.473396 -303.525482) (xy 155.473396 -303.474066) (xy 155.481439 -303.423284) (xy 155.497327 -303.374385)
			(xy 155.52067 -303.328573) (xy 155.550891 -303.286977) (xy 155.587247 -303.250621) (xy 155.628843 -303.2204)
			(xy 155.674655 -303.197057) (xy 155.723554 -303.181169) (xy 155.774336 -303.173126) (xy 155.825752 -303.173126)
			(xy 155.876534 -303.181169) (xy 155.925433 -303.197057) (xy 155.971245 -303.2204) (xy 156.012841 -303.250621)
			(xy 156.049197 -303.286977) (xy 156.079418 -303.328573) (xy 156.102761 -303.374385) (xy 156.118649 -303.423284)
			(xy 156.126692 -303.474066) (xy 156.127196 -303.499774) (xy 156.4442 -303.499774) (xy 156.44816 -303.45072)
			(xy 156.459937 -303.402936) (xy 156.479228 -303.35766) (xy 156.505531 -303.316064) (xy 156.538166 -303.279227)
			(xy 156.576287 -303.248102) (xy 156.618908 -303.223495) (xy 156.664924 -303.206043) (xy 156.713143 -303.196199)
			(xy 156.762318 -303.194218) (xy 156.811173 -303.20015) (xy 156.858444 -303.213842) (xy 156.902906 -303.23494)
			(xy 156.943409 -303.262896) (xy 156.978902 -303.296988) (xy 157.008467 -303.336332) (xy 157.031338 -303.379909)
			(xy 157.046922 -303.42659) (xy 157.054817 -303.475167) (xy 157.055312 -303.499774) (xy 157.054817 -303.524381)
			(xy 157.054638 -303.525482) (xy 157.373316 -303.525482) (xy 157.373316 -303.474066) (xy 157.381359 -303.423284)
			(xy 157.397247 -303.374385) (xy 157.42059 -303.328573) (xy 157.450811 -303.286977) (xy 157.487167 -303.250621)
			(xy 157.528763 -303.2204) (xy 157.574575 -303.197057) (xy 157.623474 -303.181169) (xy 157.674256 -303.173126)
			(xy 157.725672 -303.173126) (xy 157.776454 -303.181169) (xy 157.825353 -303.197057) (xy 157.871165 -303.2204)
			(xy 157.912761 -303.250621) (xy 157.949117 -303.286977) (xy 157.979338 -303.328573) (xy 158.002681 -303.374385)
			(xy 158.018569 -303.423284) (xy 158.026612 -303.474066) (xy 158.027116 -303.499774) (xy 158.026612 -303.525482)
			(xy 158.323276 -303.525482) (xy 158.323276 -303.474066) (xy 158.331319 -303.423284) (xy 158.347207 -303.374385)
			(xy 158.37055 -303.328573) (xy 158.400771 -303.286977) (xy 158.437127 -303.250621) (xy 158.478723 -303.2204)
			(xy 158.524535 -303.197057) (xy 158.573434 -303.181169) (xy 158.624216 -303.173126) (xy 158.675632 -303.173126)
			(xy 158.726414 -303.181169) (xy 158.775313 -303.197057) (xy 158.821125 -303.2204) (xy 158.862721 -303.250621)
			(xy 158.899077 -303.286977) (xy 158.929298 -303.328573) (xy 158.952641 -303.374385) (xy 158.968529 -303.423284)
			(xy 158.976572 -303.474066) (xy 158.977076 -303.499774) (xy 159.29408 -303.499774) (xy 159.29804 -303.45072)
			(xy 159.309817 -303.402936) (xy 159.329108 -303.35766) (xy 159.355411 -303.316064) (xy 159.388046 -303.279227)
			(xy 159.426167 -303.248102) (xy 159.468788 -303.223495) (xy 159.514804 -303.206043) (xy 159.563023 -303.196199)
			(xy 159.612198 -303.194218) (xy 159.661053 -303.20015) (xy 159.708324 -303.213842) (xy 159.752786 -303.23494)
			(xy 159.793289 -303.262896) (xy 159.828782 -303.296988) (xy 159.858347 -303.336332) (xy 159.881218 -303.379909)
			(xy 159.896802 -303.42659) (xy 159.904697 -303.475167) (xy 159.905192 -303.499774) (xy 160.24404 -303.499774)
			(xy 160.248 -303.45072) (xy 160.259777 -303.402936) (xy 160.279068 -303.35766) (xy 160.305371 -303.316064)
			(xy 160.338006 -303.279227) (xy 160.376127 -303.248102) (xy 160.418748 -303.223495) (xy 160.464764 -303.206043)
			(xy 160.512983 -303.196199) (xy 160.562158 -303.194218) (xy 160.611013 -303.20015) (xy 160.658284 -303.213842)
			(xy 160.702746 -303.23494) (xy 160.743249 -303.262896) (xy 160.778742 -303.296988) (xy 160.808307 -303.336332)
			(xy 160.831178 -303.379909) (xy 160.846762 -303.42659) (xy 160.854657 -303.475167) (xy 160.855152 -303.499774)
			(xy 160.854657 -303.524381) (xy 160.846762 -303.572958) (xy 160.831178 -303.619639) (xy 160.808307 -303.663216)
			(xy 160.778742 -303.70256) (xy 160.743249 -303.736652) (xy 160.702746 -303.764608) (xy 160.658284 -303.785706)
			(xy 160.611013 -303.799398) (xy 160.562158 -303.80533) (xy 160.512983 -303.803349) (xy 160.464764 -303.793505)
			(xy 160.418748 -303.776053) (xy 160.376127 -303.751446) (xy 160.338006 -303.720321) (xy 160.305371 -303.683484)
			(xy 160.279068 -303.641888) (xy 160.259777 -303.596612) (xy 160.248 -303.548828) (xy 160.24404 -303.499774)
			(xy 159.905192 -303.499774) (xy 159.904697 -303.524381) (xy 159.896802 -303.572958) (xy 159.881218 -303.619639)
			(xy 159.858347 -303.663216) (xy 159.828782 -303.70256) (xy 159.793289 -303.736652) (xy 159.752786 -303.764608)
			(xy 159.708324 -303.785706) (xy 159.661053 -303.799398) (xy 159.612198 -303.80533) (xy 159.563023 -303.803349)
			(xy 159.514804 -303.793505) (xy 159.468788 -303.776053) (xy 159.426167 -303.751446) (xy 159.388046 -303.720321)
			(xy 159.355411 -303.683484) (xy 159.329108 -303.641888) (xy 159.309817 -303.596612) (xy 159.29804 -303.548828)
			(xy 159.29408 -303.499774) (xy 158.977076 -303.499774) (xy 158.976572 -303.525482) (xy 158.968529 -303.576264)
			(xy 158.952641 -303.625163) (xy 158.929298 -303.670975) (xy 158.899077 -303.712571) (xy 158.862721 -303.748927)
			(xy 158.821125 -303.779148) (xy 158.775313 -303.802491) (xy 158.726414 -303.818379) (xy 158.675632 -303.826422)
			(xy 158.624216 -303.826422) (xy 158.573434 -303.818379) (xy 158.524535 -303.802491) (xy 158.478723 -303.779148)
			(xy 158.437127 -303.748927) (xy 158.400771 -303.712571) (xy 158.37055 -303.670975) (xy 158.347207 -303.625163)
			(xy 158.331319 -303.576264) (xy 158.323276 -303.525482) (xy 158.026612 -303.525482) (xy 158.018569 -303.576264)
			(xy 158.002681 -303.625163) (xy 157.979338 -303.670975) (xy 157.949117 -303.712571) (xy 157.912761 -303.748927)
			(xy 157.871165 -303.779148) (xy 157.825353 -303.802491) (xy 157.776454 -303.818379) (xy 157.725672 -303.826422)
			(xy 157.674256 -303.826422) (xy 157.623474 -303.818379) (xy 157.574575 -303.802491) (xy 157.528763 -303.779148)
			(xy 157.487167 -303.748927) (xy 157.450811 -303.712571) (xy 157.42059 -303.670975) (xy 157.397247 -303.625163)
			(xy 157.381359 -303.576264) (xy 157.373316 -303.525482) (xy 157.054638 -303.525482) (xy 157.046922 -303.572958)
			(xy 157.031338 -303.619639) (xy 157.008467 -303.663216) (xy 156.978902 -303.70256) (xy 156.943409 -303.736652)
			(xy 156.902906 -303.764608) (xy 156.858444 -303.785706) (xy 156.811173 -303.799398) (xy 156.762318 -303.80533)
			(xy 156.713143 -303.803349) (xy 156.664924 -303.793505) (xy 156.618908 -303.776053) (xy 156.576287 -303.751446)
			(xy 156.538166 -303.720321) (xy 156.505531 -303.683484) (xy 156.479228 -303.641888) (xy 156.459937 -303.596612)
			(xy 156.44816 -303.548828) (xy 156.4442 -303.499774) (xy 156.127196 -303.499774) (xy 156.126692 -303.525482)
			(xy 156.118649 -303.576264) (xy 156.102761 -303.625163) (xy 156.079418 -303.670975) (xy 156.049197 -303.712571)
			(xy 156.012841 -303.748927) (xy 155.971245 -303.779148) (xy 155.925433 -303.802491) (xy 155.876534 -303.818379)
			(xy 155.825752 -303.826422) (xy 155.774336 -303.826422) (xy 155.723554 -303.818379) (xy 155.674655 -303.802491)
			(xy 155.628843 -303.779148) (xy 155.587247 -303.748927) (xy 155.550891 -303.712571) (xy 155.52067 -303.670975)
			(xy 155.497327 -303.625163) (xy 155.481439 -303.576264) (xy 155.473396 -303.525482) (xy 155.176732 -303.525482)
			(xy 155.168689 -303.576264) (xy 155.152801 -303.625163) (xy 155.129458 -303.670975) (xy 155.099237 -303.712571)
			(xy 155.062881 -303.748927) (xy 155.021285 -303.779148) (xy 154.975473 -303.802491) (xy 154.926574 -303.818379)
			(xy 154.875792 -303.826422) (xy 154.824376 -303.826422) (xy 154.773594 -303.818379) (xy 154.724695 -303.802491)
			(xy 154.678883 -303.779148) (xy 154.637287 -303.748927) (xy 154.600931 -303.712571) (xy 154.57071 -303.670975)
			(xy 154.547367 -303.625163) (xy 154.531479 -303.576264) (xy 154.523436 -303.525482) (xy 154.204504 -303.525482)
			(xy 154.196788 -303.572958) (xy 154.181204 -303.619639) (xy 154.158333 -303.663216) (xy 154.128768 -303.70256)
			(xy 154.093275 -303.736652) (xy 154.052772 -303.764608) (xy 154.00831 -303.785706) (xy 153.961039 -303.799398)
			(xy 153.912184 -303.80533) (xy 153.863009 -303.803349) (xy 153.81479 -303.793505) (xy 153.768774 -303.776053)
			(xy 153.726153 -303.751446) (xy 153.688032 -303.720321) (xy 153.655397 -303.683484) (xy 153.629094 -303.641888)
			(xy 153.609803 -303.596612) (xy 153.598026 -303.548828) (xy 153.594066 -303.499774) (xy 153.255218 -303.499774)
			(xy 153.254723 -303.524381) (xy 153.246828 -303.572958) (xy 153.231244 -303.619639) (xy 153.208373 -303.663216)
			(xy 153.178808 -303.70256) (xy 153.143315 -303.736652) (xy 153.102812 -303.764608) (xy 153.05835 -303.785706)
			(xy 153.011079 -303.799398) (xy 152.962224 -303.80533) (xy 152.913049 -303.803349) (xy 152.86483 -303.793505)
			(xy 152.818814 -303.776053) (xy 152.776193 -303.751446) (xy 152.738072 -303.720321) (xy 152.705437 -303.683484)
			(xy 152.679134 -303.641888) (xy 152.659843 -303.596612) (xy 152.648066 -303.548828) (xy 152.644106 -303.499774)
			(xy 118.830852 -303.499774) (xy 118.830852 -303.974754) (xy 162.619194 -303.974754) (xy 162.623154 -303.9257)
			(xy 162.634931 -303.877916) (xy 162.654222 -303.83264) (xy 162.680525 -303.791044) (xy 162.71316 -303.754207)
			(xy 162.751281 -303.723082) (xy 162.793902 -303.698475) (xy 162.839918 -303.681023) (xy 162.888137 -303.671179)
			(xy 162.937312 -303.669198) (xy 162.986167 -303.67513) (xy 163.033438 -303.688822) (xy 163.0779 -303.70992)
			(xy 163.118403 -303.737876) (xy 163.153896 -303.771968) (xy 163.183461 -303.811312) (xy 163.206332 -303.854889)
			(xy 163.221916 -303.90157) (xy 163.229811 -303.950147) (xy 163.230306 -303.974754) (xy 163.569154 -303.974754)
			(xy 163.573114 -303.9257) (xy 163.584891 -303.877916) (xy 163.604182 -303.83264) (xy 163.630485 -303.791044)
			(xy 163.66312 -303.754207) (xy 163.701241 -303.723082) (xy 163.743862 -303.698475) (xy 163.789878 -303.681023)
			(xy 163.838097 -303.671179) (xy 163.887272 -303.669198) (xy 163.936127 -303.67513) (xy 163.983398 -303.688822)
			(xy 164.02786 -303.70992) (xy 164.068363 -303.737876) (xy 164.103856 -303.771968) (xy 164.133421 -303.811312)
			(xy 164.156292 -303.854889) (xy 164.171876 -303.90157) (xy 164.179771 -303.950147) (xy 164.180266 -303.974754)
			(xy 164.519114 -303.974754) (xy 164.523074 -303.9257) (xy 164.534851 -303.877916) (xy 164.554142 -303.83264)
			(xy 164.580445 -303.791044) (xy 164.61308 -303.754207) (xy 164.651201 -303.723082) (xy 164.693822 -303.698475)
			(xy 164.739838 -303.681023) (xy 164.788057 -303.671179) (xy 164.837232 -303.669198) (xy 164.886087 -303.67513)
			(xy 164.933358 -303.688822) (xy 164.97782 -303.70992) (xy 165.018323 -303.737876) (xy 165.053816 -303.771968)
			(xy 165.083381 -303.811312) (xy 165.106252 -303.854889) (xy 165.121836 -303.90157) (xy 165.129731 -303.950147)
			(xy 165.130226 -303.974754) (xy 165.129731 -303.999361) (xy 165.121836 -304.047938) (xy 165.106252 -304.094619)
			(xy 165.083381 -304.138196) (xy 165.053816 -304.17754) (xy 165.018323 -304.211632) (xy 164.97782 -304.239588)
			(xy 164.933358 -304.260686) (xy 164.886087 -304.274378) (xy 164.837232 -304.28031) (xy 164.788057 -304.278329)
			(xy 164.739838 -304.268485) (xy 164.693822 -304.251033) (xy 164.651201 -304.226426) (xy 164.61308 -304.195301)
			(xy 164.580445 -304.158464) (xy 164.554142 -304.116868) (xy 164.534851 -304.071592) (xy 164.523074 -304.023808)
			(xy 164.519114 -303.974754) (xy 164.180266 -303.974754) (xy 164.179771 -303.999361) (xy 164.171876 -304.047938)
			(xy 164.156292 -304.094619) (xy 164.133421 -304.138196) (xy 164.103856 -304.17754) (xy 164.068363 -304.211632)
			(xy 164.02786 -304.239588) (xy 163.983398 -304.260686) (xy 163.936127 -304.274378) (xy 163.887272 -304.28031)
			(xy 163.838097 -304.278329) (xy 163.789878 -304.268485) (xy 163.743862 -304.251033) (xy 163.701241 -304.226426)
			(xy 163.66312 -304.195301) (xy 163.630485 -304.158464) (xy 163.604182 -304.116868) (xy 163.584891 -304.071592)
			(xy 163.573114 -304.023808) (xy 163.569154 -303.974754) (xy 163.230306 -303.974754) (xy 163.229811 -303.999361)
			(xy 163.221916 -304.047938) (xy 163.206332 -304.094619) (xy 163.183461 -304.138196) (xy 163.153896 -304.17754)
			(xy 163.118403 -304.211632) (xy 163.0779 -304.239588) (xy 163.033438 -304.260686) (xy 162.986167 -304.274378)
			(xy 162.937312 -304.28031) (xy 162.888137 -304.278329) (xy 162.839918 -304.268485) (xy 162.793902 -304.251033)
			(xy 162.751281 -304.226426) (xy 162.71316 -304.195301) (xy 162.680525 -304.158464) (xy 162.654222 -304.116868)
			(xy 162.634931 -304.071592) (xy 162.623154 -304.023808) (xy 162.619194 -303.974754) (xy 118.830852 -303.974754)
			(xy 118.830852 -305.008534) (xy 120.828816 -305.008534) (xy 120.829298 -304.981164) (xy 120.837111 -304.926986)
			(xy 120.852597 -304.874483) (xy 120.875435 -304.824736) (xy 120.905156 -304.778768) (xy 120.922796 -304.757836)
			(xy 120.92305 -304.757582) (xy 120.928656 -304.750509) (xy 120.93489 -304.733582) (xy 120.935242 -304.724562)
			(xy 120.935242 -304.657506) (xy 120.934895 -304.648488) (xy 120.928642 -304.63157) (xy 120.92305 -304.624486)
			(xy 120.922796 -304.624486) (xy 120.922796 -304.624232) (xy 120.905158 -304.603299) (xy 120.875446 -304.557327)
			(xy 120.85261 -304.507579) (xy 120.837119 -304.455079) (xy 120.82929 -304.400903) (xy 120.828816 -304.373534)
			(xy 120.829302 -304.346283) (xy 120.837058 -304.292335) (xy 120.852413 -304.24004) (xy 120.875055 -304.190463)
			(xy 120.904521 -304.144613) (xy 120.940212 -304.103422) (xy 120.981403 -304.067731) (xy 121.027253 -304.038265)
			(xy 121.07683 -304.015623) (xy 121.129125 -304.000268) (xy 121.183073 -303.992512) (xy 121.237575 -303.992512)
			(xy 121.291523 -304.000268) (xy 121.343818 -304.015623) (xy 121.393395 -304.038265) (xy 121.439245 -304.067731)
			(xy 121.480436 -304.103422) (xy 121.516127 -304.144613) (xy 121.545593 -304.190463) (xy 121.568235 -304.24004)
			(xy 121.58359 -304.292335) (xy 121.591346 -304.346283) (xy 121.591832 -304.373534) (xy 121.591402 -304.400906)
			(xy 121.583578 -304.455087) (xy 121.568082 -304.507591) (xy 121.545231 -304.557338) (xy 121.515498 -304.603302)
			(xy 121.497852 -304.624232) (xy 121.497598 -304.624486) (xy 121.492011 -304.631572) (xy 121.485765 -304.648489)
			(xy 121.485406 -304.657506) (xy 121.485406 -304.724562) (xy 121.48578 -304.733577) (xy 121.492016 -304.750494)
			(xy 121.497598 -304.757582) (xy 121.497852 -304.757582) (xy 121.497852 -304.757836) (xy 121.515467 -304.778788)
			(xy 121.545184 -304.824754) (xy 121.568026 -304.874497) (xy 121.583522 -304.926993) (xy 121.591355 -304.981166)
			(xy 121.591832 -305.008534) (xy 124.248926 -305.008534) (xy 124.249406 -304.981164) (xy 124.257219 -304.926985)
			(xy 124.272705 -304.874482) (xy 124.295544 -304.824735) (xy 124.325266 -304.778768) (xy 124.342906 -304.757836)
			(xy 124.34316 -304.757582) (xy 124.348767 -304.75051) (xy 124.355 -304.733582) (xy 124.355352 -304.724562)
			(xy 124.355352 -304.657506) (xy 124.355002 -304.648488) (xy 124.348751 -304.631571) (xy 124.34316 -304.624486)
			(xy 124.342906 -304.624486) (xy 124.342906 -304.624232) (xy 124.325269 -304.603298) (xy 124.295557 -304.557326)
			(xy 124.27272 -304.507579) (xy 124.257229 -304.455079) (xy 124.2494 -304.400903) (xy 124.248926 -304.373534)
			(xy 124.249412 -304.346283) (xy 124.257168 -304.292335) (xy 124.272523 -304.24004) (xy 124.295165 -304.190463)
			(xy 124.324631 -304.144613) (xy 124.360322 -304.103422) (xy 124.401513 -304.067731) (xy 124.447363 -304.038265)
			(xy 124.49694 -304.015623) (xy 124.549235 -304.000268) (xy 124.603183 -303.992512) (xy 124.657685 -303.992512)
			(xy 124.711633 -304.000268) (xy 124.763928 -304.015623) (xy 124.813505 -304.038265) (xy 124.859355 -304.067731)
			(xy 124.900546 -304.103422) (xy 124.936237 -304.144613) (xy 124.965703 -304.190463) (xy 124.988345 -304.24004)
			(xy 125.0037 -304.292335) (xy 125.011456 -304.346283) (xy 125.011942 -304.373534) (xy 125.01151 -304.400906)
			(xy 125.003686 -304.455087) (xy 124.98819 -304.507591) (xy 124.96534 -304.557337) (xy 124.935607 -304.603302)
			(xy 124.917962 -304.624232) (xy 124.917708 -304.624486) (xy 124.912122 -304.631573) (xy 124.905875 -304.648489)
			(xy 124.905516 -304.657506) (xy 124.905516 -304.724562) (xy 124.905888 -304.733577) (xy 124.912125 -304.750495)
			(xy 124.917708 -304.757582) (xy 124.917962 -304.757582) (xy 124.917962 -304.757836) (xy 124.935579 -304.778786)
			(xy 124.965295 -304.824753) (xy 124.988136 -304.874496) (xy 125.003632 -304.926993) (xy 125.011465 -304.981166)
			(xy 125.011942 -305.008534) (xy 125.637036 -305.008534) (xy 125.637513 -304.981164) (xy 125.645327 -304.926985)
			(xy 125.660813 -304.874482) (xy 125.683652 -304.824735) (xy 125.713375 -304.778768) (xy 125.731016 -304.757836)
			(xy 125.73127 -304.757582) (xy 125.736878 -304.750511) (xy 125.74311 -304.733582) (xy 125.743462 -304.724562)
			(xy 125.743462 -304.657506) (xy 125.74311 -304.648488) (xy 125.73686 -304.631571) (xy 125.73127 -304.624486)
			(xy 125.731016 -304.624486) (xy 125.731016 -304.624232) (xy 125.713381 -304.603297) (xy 125.683668 -304.557325)
			(xy 125.660831 -304.507578) (xy 125.645339 -304.455078) (xy 125.63751 -304.400903) (xy 125.637036 -304.373534)
			(xy 125.637522 -304.346283) (xy 125.645278 -304.292335) (xy 125.660633 -304.24004) (xy 125.683275 -304.190463)
			(xy 125.712741 -304.144613) (xy 125.748432 -304.103422) (xy 125.789623 -304.067731) (xy 125.835473 -304.038265)
			(xy 125.88505 -304.015623) (xy 125.937345 -304.000268) (xy 125.991293 -303.992512) (xy 126.045795 -303.992512)
			(xy 126.099743 -304.000268) (xy 126.152038 -304.015623) (xy 126.201615 -304.038265) (xy 126.247465 -304.067731)
			(xy 126.288656 -304.103422) (xy 126.324347 -304.144613) (xy 126.353813 -304.190463) (xy 126.376455 -304.24004)
			(xy 126.39181 -304.292335) (xy 126.399566 -304.346283) (xy 126.400052 -304.373534) (xy 126.399618 -304.400906)
			(xy 126.391794 -304.455086) (xy 126.376298 -304.50759) (xy 126.353449 -304.557337) (xy 126.323717 -304.603302)
			(xy 126.306072 -304.624232) (xy 126.305818 -304.624486) (xy 126.300234 -304.631574) (xy 126.293985 -304.64849)
			(xy 126.293626 -304.657506) (xy 126.293626 -304.724562) (xy 126.293996 -304.733578) (xy 126.300234 -304.750495)
			(xy 126.305818 -304.757582) (xy 126.306072 -304.757582) (xy 126.306072 -304.757836) (xy 126.32369 -304.778785)
			(xy 126.353406 -304.824753) (xy 126.376247 -304.874496) (xy 126.391742 -304.926993) (xy 126.399576 -304.981166)
			(xy 126.400052 -305.008534) (xy 127.669036 -305.008534) (xy 127.669513 -304.981164) (xy 127.677327 -304.926985)
			(xy 127.692813 -304.874482) (xy 127.715652 -304.824735) (xy 127.745375 -304.778768) (xy 127.763016 -304.757836)
			(xy 127.76327 -304.757582) (xy 127.768878 -304.750511) (xy 127.77511 -304.733582) (xy 127.775462 -304.724562)
			(xy 127.775462 -304.657506) (xy 127.77511 -304.648488) (xy 127.76886 -304.631571) (xy 127.76327 -304.624486)
			(xy 127.763016 -304.624486) (xy 127.763016 -304.624232) (xy 127.745381 -304.603297) (xy 127.715668 -304.557325)
			(xy 127.692831 -304.507578) (xy 127.677339 -304.455078) (xy 127.66951 -304.400903) (xy 127.669036 -304.373534)
			(xy 127.669522 -304.346283) (xy 127.677278 -304.292335) (xy 127.692633 -304.24004) (xy 127.715275 -304.190463)
			(xy 127.744741 -304.144613) (xy 127.780432 -304.103422) (xy 127.821623 -304.067731) (xy 127.867473 -304.038265)
			(xy 127.91705 -304.015623) (xy 127.969345 -304.000268) (xy 128.023293 -303.992512) (xy 128.077795 -303.992512)
			(xy 128.131743 -304.000268) (xy 128.184038 -304.015623) (xy 128.233615 -304.038265) (xy 128.279465 -304.067731)
			(xy 128.320656 -304.103422) (xy 128.356347 -304.144613) (xy 128.385813 -304.190463) (xy 128.408455 -304.24004)
			(xy 128.42381 -304.292335) (xy 128.431566 -304.346283) (xy 128.432052 -304.373534) (xy 128.431618 -304.400906)
			(xy 128.423794 -304.455086) (xy 128.408298 -304.50759) (xy 128.385449 -304.557337) (xy 128.355717 -304.603302)
			(xy 128.338072 -304.624232) (xy 128.337818 -304.624486) (xy 128.332234 -304.631574) (xy 128.325985 -304.64849)
			(xy 128.325626 -304.657506) (xy 128.325626 -304.724562) (xy 128.325996 -304.733578) (xy 128.332234 -304.750495)
			(xy 128.337818 -304.757582) (xy 128.338072 -304.757582) (xy 128.338072 -304.757836) (xy 128.35569 -304.778785)
			(xy 128.385406 -304.824753) (xy 128.408247 -304.874496) (xy 128.423742 -304.926993) (xy 128.431576 -304.981166)
			(xy 128.432052 -305.008534) (xy 132.477256 -305.008534) (xy 132.477728 -304.981164) (xy 132.485543 -304.926984)
			(xy 132.501029 -304.874481) (xy 132.52387 -304.824734) (xy 132.553595 -304.778767) (xy 132.571236 -304.757836)
			(xy 132.57149 -304.757582) (xy 132.577089 -304.750504) (xy 132.583329 -304.733581) (xy 132.583682 -304.724562)
			(xy 132.583682 -304.657506) (xy 132.583326 -304.648489) (xy 132.577078 -304.631572) (xy 132.57149 -304.624486)
			(xy 132.571236 -304.624486) (xy 132.571236 -304.624232) (xy 132.553604 -304.603294) (xy 132.52389 -304.557323)
			(xy 132.501052 -304.507577) (xy 132.485559 -304.455078) (xy 132.47773 -304.400903) (xy 132.477256 -304.373534)
			(xy 132.477742 -304.346283) (xy 132.485498 -304.292335) (xy 132.500853 -304.24004) (xy 132.523495 -304.190463)
			(xy 132.552961 -304.144613) (xy 132.588652 -304.103422) (xy 132.629843 -304.067731) (xy 132.675693 -304.038265)
			(xy 132.72527 -304.015623) (xy 132.777565 -304.000268) (xy 132.831513 -303.992512) (xy 132.886015 -303.992512)
			(xy 132.939963 -304.000268) (xy 132.992258 -304.015623) (xy 133.041835 -304.038265) (xy 133.087685 -304.067731)
			(xy 133.128876 -304.103422) (xy 133.164567 -304.144613) (xy 133.194033 -304.190463) (xy 133.216675 -304.24004)
			(xy 133.23203 -304.292335) (xy 133.239786 -304.346283) (xy 133.240272 -304.373534) (xy 133.239833 -304.400905)
			(xy 133.232009 -304.455086) (xy 133.216514 -304.507589) (xy 133.193667 -304.557336) (xy 133.163936 -304.603301)
			(xy 133.146292 -304.624232) (xy 133.146038 -304.624486) (xy 133.140444 -304.631567) (xy 133.134203 -304.648488)
			(xy 133.133846 -304.657506) (xy 133.133846 -304.724562) (xy 133.134211 -304.733578) (xy 133.140452 -304.750496)
			(xy 133.146038 -304.757582) (xy 133.146292 -304.757582) (xy 133.146292 -304.757836) (xy 133.163913 -304.778782)
			(xy 133.193628 -304.824751) (xy 133.216468 -304.874495) (xy 133.231963 -304.926993) (xy 133.239796 -304.981166)
			(xy 133.240272 -305.008534) (xy 133.239786 -305.035785) (xy 133.23203 -305.089733) (xy 133.216675 -305.142028)
			(xy 133.194033 -305.191605) (xy 133.164567 -305.237455) (xy 133.128876 -305.278646) (xy 133.096209 -305.306951)
			(xy 143.510416 -305.306951) (xy 143.518174 -305.252993) (xy 143.533531 -305.200689) (xy 143.556176 -305.151102)
			(xy 143.585647 -305.105243) (xy 143.621345 -305.064045) (xy 143.662543 -305.028347) (xy 143.708403 -304.998876)
			(xy 143.757989 -304.976231) (xy 143.810294 -304.960873) (xy 143.864252 -304.953116) (xy 143.891508 -304.952654)
			(xy 143.891762 -304.952654) (xy 143.919448 -304.95367) (xy 143.930624 -304.954432) (xy 143.951706 -304.946558)
			(xy 144.02181 -304.873914) (xy 144.029176 -304.852578) (xy 144.027906 -304.841402) (xy 144.026845 -304.831148)
			(xy 144.025701 -304.810562) (xy 144.02562 -304.800254) (xy 144.026127 -304.773007) (xy 144.033889 -304.719069)
			(xy 144.049247 -304.666785) (xy 144.07189 -304.617218) (xy 144.101356 -304.571378) (xy 144.137045 -304.530197)
			(xy 144.178232 -304.494515) (xy 144.224077 -304.465057) (xy 144.273648 -304.442424) (xy 144.325935 -304.427074)
			(xy 144.379874 -304.419323) (xy 144.434368 -304.419326) (xy 144.488307 -304.427084) (xy 144.540592 -304.442438)
			(xy 144.557122 -304.449988) (xy 151.693892 -304.449988) (xy 151.697852 -304.400934) (xy 151.709629 -304.35315)
			(xy 151.72892 -304.307874) (xy 151.755223 -304.266278) (xy 151.787858 -304.229441) (xy 151.825979 -304.198316)
			(xy 151.8686 -304.173709) (xy 151.914616 -304.156257) (xy 151.962835 -304.146413) (xy 152.01201 -304.144432)
			(xy 152.060865 -304.150364) (xy 152.108136 -304.164056) (xy 152.152598 -304.185154) (xy 152.193101 -304.21311)
			(xy 152.228594 -304.247202) (xy 152.258159 -304.286546) (xy 152.28103 -304.330123) (xy 152.296614 -304.376804)
			(xy 152.304509 -304.425381) (xy 152.305004 -304.449988) (xy 152.304509 -304.474595) (xy 152.304371 -304.475442)
			(xy 152.623262 -304.475442) (xy 152.623262 -304.424026) (xy 152.631305 -304.373244) (xy 152.647193 -304.324345)
			(xy 152.670536 -304.278533) (xy 152.700757 -304.236937) (xy 152.737113 -304.200581) (xy 152.778709 -304.17036)
			(xy 152.824521 -304.147017) (xy 152.87342 -304.131129) (xy 152.924202 -304.123086) (xy 152.975618 -304.123086)
			(xy 153.0264 -304.131129) (xy 153.075299 -304.147017) (xy 153.121111 -304.17036) (xy 153.162707 -304.200581)
			(xy 153.199063 -304.236937) (xy 153.229284 -304.278533) (xy 153.252627 -304.324345) (xy 153.268515 -304.373244)
			(xy 153.276558 -304.424026) (xy 153.277062 -304.449734) (xy 153.276558 -304.475442) (xy 153.573222 -304.475442)
			(xy 153.573222 -304.424026) (xy 153.581265 -304.373244) (xy 153.597153 -304.324345) (xy 153.620496 -304.278533)
			(xy 153.650717 -304.236937) (xy 153.687073 -304.200581) (xy 153.728669 -304.17036) (xy 153.774481 -304.147017)
			(xy 153.82338 -304.131129) (xy 153.874162 -304.123086) (xy 153.925578 -304.123086) (xy 153.97636 -304.131129)
			(xy 154.025259 -304.147017) (xy 154.071071 -304.17036) (xy 154.112667 -304.200581) (xy 154.149023 -304.236937)
			(xy 154.179244 -304.278533) (xy 154.202587 -304.324345) (xy 154.218475 -304.373244) (xy 154.226518 -304.424026)
			(xy 154.227022 -304.449734) (xy 154.54428 -304.449734) (xy 154.54824 -304.40068) (xy 154.560017 -304.352896)
			(xy 154.579308 -304.30762) (xy 154.605611 -304.266024) (xy 154.638246 -304.229187) (xy 154.676367 -304.198062)
			(xy 154.718988 -304.173455) (xy 154.765004 -304.156003) (xy 154.813223 -304.146159) (xy 154.862398 -304.144178)
			(xy 154.911253 -304.15011) (xy 154.958524 -304.163802) (xy 155.002986 -304.1849) (xy 155.043489 -304.212856)
			(xy 155.078982 -304.246948) (xy 155.108547 -304.286292) (xy 155.131418 -304.329869) (xy 155.147002 -304.37655)
			(xy 155.154897 -304.425127) (xy 155.155392 -304.449734) (xy 155.49424 -304.449734) (xy 155.4982 -304.40068)
			(xy 155.509977 -304.352896) (xy 155.529268 -304.30762) (xy 155.555571 -304.266024) (xy 155.588206 -304.229187)
			(xy 155.626327 -304.198062) (xy 155.668948 -304.173455) (xy 155.714964 -304.156003) (xy 155.763183 -304.146159)
			(xy 155.812358 -304.144178) (xy 155.861213 -304.15011) (xy 155.908484 -304.163802) (xy 155.952946 -304.1849)
			(xy 155.993449 -304.212856) (xy 156.028942 -304.246948) (xy 156.058507 -304.286292) (xy 156.081378 -304.329869)
			(xy 156.096962 -304.37655) (xy 156.104857 -304.425127) (xy 156.105352 -304.449734) (xy 156.4442 -304.449734)
			(xy 156.44816 -304.40068) (xy 156.459937 -304.352896) (xy 156.479228 -304.30762) (xy 156.505531 -304.266024)
			(xy 156.538166 -304.229187) (xy 156.576287 -304.198062) (xy 156.618908 -304.173455) (xy 156.664924 -304.156003)
			(xy 156.713143 -304.146159) (xy 156.762318 -304.144178) (xy 156.811173 -304.15011) (xy 156.858444 -304.163802)
			(xy 156.902906 -304.1849) (xy 156.943409 -304.212856) (xy 156.978902 -304.246948) (xy 157.008467 -304.286292)
			(xy 157.031338 -304.329869) (xy 157.046922 -304.37655) (xy 157.054817 -304.425127) (xy 157.055312 -304.449734)
			(xy 157.39416 -304.449734) (xy 157.39812 -304.40068) (xy 157.409897 -304.352896) (xy 157.429188 -304.30762)
			(xy 157.455491 -304.266024) (xy 157.488126 -304.229187) (xy 157.526247 -304.198062) (xy 157.568868 -304.173455)
			(xy 157.614884 -304.156003) (xy 157.663103 -304.146159) (xy 157.712278 -304.144178) (xy 157.761133 -304.15011)
			(xy 157.808404 -304.163802) (xy 157.852866 -304.1849) (xy 157.893369 -304.212856) (xy 157.928862 -304.246948)
			(xy 157.958427 -304.286292) (xy 157.981298 -304.329869) (xy 157.996882 -304.37655) (xy 158.004777 -304.425127)
			(xy 158.005272 -304.449734) (xy 158.34412 -304.449734) (xy 158.34808 -304.40068) (xy 158.359857 -304.352896)
			(xy 158.379148 -304.30762) (xy 158.405451 -304.266024) (xy 158.438086 -304.229187) (xy 158.476207 -304.198062)
			(xy 158.518828 -304.173455) (xy 158.564844 -304.156003) (xy 158.613063 -304.146159) (xy 158.662238 -304.144178)
			(xy 158.711093 -304.15011) (xy 158.758364 -304.163802) (xy 158.802826 -304.1849) (xy 158.843329 -304.212856)
			(xy 158.878822 -304.246948) (xy 158.908387 -304.286292) (xy 158.931258 -304.329869) (xy 158.946842 -304.37655)
			(xy 158.954737 -304.425127) (xy 158.955232 -304.449734) (xy 158.954737 -304.474341) (xy 158.954558 -304.475442)
			(xy 159.273236 -304.475442) (xy 159.273236 -304.424026) (xy 159.281279 -304.373244) (xy 159.297167 -304.324345)
			(xy 159.32051 -304.278533) (xy 159.350731 -304.236937) (xy 159.387087 -304.200581) (xy 159.428683 -304.17036)
			(xy 159.474495 -304.147017) (xy 159.523394 -304.131129) (xy 159.574176 -304.123086) (xy 159.625592 -304.123086)
			(xy 159.676374 -304.131129) (xy 159.725273 -304.147017) (xy 159.771085 -304.17036) (xy 159.812681 -304.200581)
			(xy 159.849037 -304.236937) (xy 159.879258 -304.278533) (xy 159.902601 -304.324345) (xy 159.918489 -304.373244)
			(xy 159.926532 -304.424026) (xy 159.927036 -304.449734) (xy 159.926532 -304.475442) (xy 160.223196 -304.475442)
			(xy 160.223196 -304.424026) (xy 160.231239 -304.373244) (xy 160.247127 -304.324345) (xy 160.27047 -304.278533)
			(xy 160.300691 -304.236937) (xy 160.337047 -304.200581) (xy 160.378643 -304.17036) (xy 160.424455 -304.147017)
			(xy 160.473354 -304.131129) (xy 160.524136 -304.123086) (xy 160.575552 -304.123086) (xy 160.626334 -304.131129)
			(xy 160.675233 -304.147017) (xy 160.721045 -304.17036) (xy 160.762641 -304.200581) (xy 160.798997 -304.236937)
			(xy 160.829218 -304.278533) (xy 160.852561 -304.324345) (xy 160.868449 -304.373244) (xy 160.876492 -304.424026)
			(xy 160.876996 -304.449734) (xy 161.194254 -304.449734) (xy 161.198214 -304.40068) (xy 161.209991 -304.352896)
			(xy 161.229282 -304.30762) (xy 161.255585 -304.266024) (xy 161.28822 -304.229187) (xy 161.326341 -304.198062)
			(xy 161.368962 -304.173455) (xy 161.414978 -304.156003) (xy 161.463197 -304.146159) (xy 161.512372 -304.144178)
			(xy 161.561227 -304.15011) (xy 161.608498 -304.163802) (xy 161.65296 -304.1849) (xy 161.693463 -304.212856)
			(xy 161.728956 -304.246948) (xy 161.758521 -304.286292) (xy 161.781392 -304.329869) (xy 161.796976 -304.37655)
			(xy 161.804871 -304.425127) (xy 161.805366 -304.449734) (xy 161.804871 -304.474341) (xy 161.796976 -304.522918)
			(xy 161.781392 -304.569599) (xy 161.758521 -304.613176) (xy 161.728956 -304.65252) (xy 161.693463 -304.686612)
			(xy 161.65296 -304.714568) (xy 161.608498 -304.735666) (xy 161.561227 -304.749358) (xy 161.512372 -304.75529)
			(xy 161.463197 -304.753309) (xy 161.414978 -304.743465) (xy 161.368962 -304.726013) (xy 161.326341 -304.701406)
			(xy 161.28822 -304.670281) (xy 161.255585 -304.633444) (xy 161.229282 -304.591848) (xy 161.209991 -304.546572)
			(xy 161.198214 -304.498788) (xy 161.194254 -304.449734) (xy 160.876996 -304.449734) (xy 160.876492 -304.475442)
			(xy 160.868449 -304.526224) (xy 160.852561 -304.575123) (xy 160.829218 -304.620935) (xy 160.798997 -304.662531)
			(xy 160.762641 -304.698887) (xy 160.721045 -304.729108) (xy 160.675233 -304.752451) (xy 160.626334 -304.768339)
			(xy 160.575552 -304.776382) (xy 160.524136 -304.776382) (xy 160.473354 -304.768339) (xy 160.424455 -304.752451)
			(xy 160.378643 -304.729108) (xy 160.337047 -304.698887) (xy 160.300691 -304.662531) (xy 160.27047 -304.620935)
			(xy 160.247127 -304.575123) (xy 160.231239 -304.526224) (xy 160.223196 -304.475442) (xy 159.926532 -304.475442)
			(xy 159.918489 -304.526224) (xy 159.902601 -304.575123) (xy 159.879258 -304.620935) (xy 159.849037 -304.662531)
			(xy 159.812681 -304.698887) (xy 159.771085 -304.729108) (xy 159.725273 -304.752451) (xy 159.676374 -304.768339)
			(xy 159.625592 -304.776382) (xy 159.574176 -304.776382) (xy 159.523394 -304.768339) (xy 159.474495 -304.752451)
			(xy 159.428683 -304.729108) (xy 159.387087 -304.698887) (xy 159.350731 -304.662531) (xy 159.32051 -304.620935)
			(xy 159.297167 -304.575123) (xy 159.281279 -304.526224) (xy 159.273236 -304.475442) (xy 158.954558 -304.475442)
			(xy 158.946842 -304.522918) (xy 158.931258 -304.569599) (xy 158.908387 -304.613176) (xy 158.878822 -304.65252)
			(xy 158.843329 -304.686612) (xy 158.802826 -304.714568) (xy 158.758364 -304.735666) (xy 158.711093 -304.749358)
			(xy 158.662238 -304.75529) (xy 158.613063 -304.753309) (xy 158.564844 -304.743465) (xy 158.518828 -304.726013)
			(xy 158.476207 -304.701406) (xy 158.438086 -304.670281) (xy 158.405451 -304.633444) (xy 158.379148 -304.591848)
			(xy 158.359857 -304.546572) (xy 158.34808 -304.498788) (xy 158.34412 -304.449734) (xy 158.005272 -304.449734)
			(xy 158.004777 -304.474341) (xy 157.996882 -304.522918) (xy 157.981298 -304.569599) (xy 157.958427 -304.613176)
			(xy 157.928862 -304.65252) (xy 157.893369 -304.686612) (xy 157.852866 -304.714568) (xy 157.808404 -304.735666)
			(xy 157.761133 -304.749358) (xy 157.712278 -304.75529) (xy 157.663103 -304.753309) (xy 157.614884 -304.743465)
			(xy 157.568868 -304.726013) (xy 157.526247 -304.701406) (xy 157.488126 -304.670281) (xy 157.455491 -304.633444)
			(xy 157.429188 -304.591848) (xy 157.409897 -304.546572) (xy 157.39812 -304.498788) (xy 157.39416 -304.449734)
			(xy 157.055312 -304.449734) (xy 157.054817 -304.474341) (xy 157.046922 -304.522918) (xy 157.031338 -304.569599)
			(xy 157.008467 -304.613176) (xy 156.978902 -304.65252) (xy 156.943409 -304.686612) (xy 156.902906 -304.714568)
			(xy 156.858444 -304.735666) (xy 156.811173 -304.749358) (xy 156.762318 -304.75529) (xy 156.713143 -304.753309)
			(xy 156.664924 -304.743465) (xy 156.618908 -304.726013) (xy 156.576287 -304.701406) (xy 156.538166 -304.670281)
			(xy 156.505531 -304.633444) (xy 156.479228 -304.591848) (xy 156.459937 -304.546572) (xy 156.44816 -304.498788)
			(xy 156.4442 -304.449734) (xy 156.105352 -304.449734) (xy 156.104857 -304.474341) (xy 156.096962 -304.522918)
			(xy 156.081378 -304.569599) (xy 156.058507 -304.613176) (xy 156.028942 -304.65252) (xy 155.993449 -304.686612)
			(xy 155.952946 -304.714568) (xy 155.908484 -304.735666) (xy 155.861213 -304.749358) (xy 155.812358 -304.75529)
			(xy 155.763183 -304.753309) (xy 155.714964 -304.743465) (xy 155.668948 -304.726013) (xy 155.626327 -304.701406)
			(xy 155.588206 -304.670281) (xy 155.555571 -304.633444) (xy 155.529268 -304.591848) (xy 155.509977 -304.546572)
			(xy 155.4982 -304.498788) (xy 155.49424 -304.449734) (xy 155.155392 -304.449734) (xy 155.154897 -304.474341)
			(xy 155.147002 -304.522918) (xy 155.131418 -304.569599) (xy 155.108547 -304.613176) (xy 155.078982 -304.65252)
			(xy 155.043489 -304.686612) (xy 155.002986 -304.714568) (xy 154.958524 -304.735666) (xy 154.911253 -304.749358)
			(xy 154.862398 -304.75529) (xy 154.813223 -304.753309) (xy 154.765004 -304.743465) (xy 154.718988 -304.726013)
			(xy 154.676367 -304.701406) (xy 154.638246 -304.670281) (xy 154.605611 -304.633444) (xy 154.579308 -304.591848)
			(xy 154.560017 -304.546572) (xy 154.54824 -304.498788) (xy 154.54428 -304.449734) (xy 154.227022 -304.449734)
			(xy 154.226518 -304.475442) (xy 154.218475 -304.526224) (xy 154.202587 -304.575123) (xy 154.179244 -304.620935)
			(xy 154.149023 -304.662531) (xy 154.112667 -304.698887) (xy 154.071071 -304.729108) (xy 154.025259 -304.752451)
			(xy 153.97636 -304.768339) (xy 153.925578 -304.776382) (xy 153.874162 -304.776382) (xy 153.82338 -304.768339)
			(xy 153.774481 -304.752451) (xy 153.728669 -304.729108) (xy 153.687073 -304.698887) (xy 153.650717 -304.662531)
			(xy 153.620496 -304.620935) (xy 153.597153 -304.575123) (xy 153.581265 -304.526224) (xy 153.573222 -304.475442)
			(xy 153.276558 -304.475442) (xy 153.268515 -304.526224) (xy 153.252627 -304.575123) (xy 153.229284 -304.620935)
			(xy 153.199063 -304.662531) (xy 153.162707 -304.698887) (xy 153.121111 -304.729108) (xy 153.075299 -304.752451)
			(xy 153.0264 -304.768339) (xy 152.975618 -304.776382) (xy 152.924202 -304.776382) (xy 152.87342 -304.768339)
			(xy 152.824521 -304.752451) (xy 152.778709 -304.729108) (xy 152.737113 -304.698887) (xy 152.700757 -304.662531)
			(xy 152.670536 -304.620935) (xy 152.647193 -304.575123) (xy 152.631305 -304.526224) (xy 152.623262 -304.475442)
			(xy 152.304371 -304.475442) (xy 152.296614 -304.523172) (xy 152.28103 -304.569853) (xy 152.258159 -304.61343)
			(xy 152.228594 -304.652774) (xy 152.193101 -304.686866) (xy 152.152598 -304.714822) (xy 152.108136 -304.73592)
			(xy 152.060865 -304.749612) (xy 152.01201 -304.755544) (xy 151.962835 -304.753563) (xy 151.914616 -304.743719)
			(xy 151.8686 -304.726267) (xy 151.825979 -304.70166) (xy 151.787858 -304.670535) (xy 151.755223 -304.633698)
			(xy 151.72892 -304.592102) (xy 151.709629 -304.546826) (xy 151.697852 -304.499042) (xy 151.693892 -304.449988)
			(xy 144.557122 -304.449988) (xy 144.590161 -304.465078) (xy 144.636003 -304.494541) (xy 144.677185 -304.530228)
			(xy 144.71287 -304.571412) (xy 144.742331 -304.617255) (xy 144.764968 -304.666825) (xy 144.78032 -304.719111)
			(xy 144.788076 -304.77305) (xy 144.788076 -304.827543) (xy 144.780322 -304.881483) (xy 144.767629 -304.924714)
			(xy 162.619194 -304.924714) (xy 162.623154 -304.87566) (xy 162.634931 -304.827876) (xy 162.654222 -304.7826)
			(xy 162.680525 -304.741004) (xy 162.71316 -304.704167) (xy 162.751281 -304.673042) (xy 162.793902 -304.648435)
			(xy 162.839918 -304.630983) (xy 162.888137 -304.621139) (xy 162.937312 -304.619158) (xy 162.986167 -304.62509)
			(xy 163.033438 -304.638782) (xy 163.0779 -304.65988) (xy 163.118403 -304.687836) (xy 163.153896 -304.721928)
			(xy 163.183461 -304.761272) (xy 163.206332 -304.804849) (xy 163.221916 -304.85153) (xy 163.229811 -304.900107)
			(xy 163.230306 -304.924714) (xy 163.569154 -304.924714) (xy 163.573114 -304.87566) (xy 163.584891 -304.827876)
			(xy 163.604182 -304.7826) (xy 163.630485 -304.741004) (xy 163.66312 -304.704167) (xy 163.701241 -304.673042)
			(xy 163.743862 -304.648435) (xy 163.789878 -304.630983) (xy 163.838097 -304.621139) (xy 163.887272 -304.619158)
			(xy 163.936127 -304.62509) (xy 163.983398 -304.638782) (xy 164.02786 -304.65988) (xy 164.068363 -304.687836)
			(xy 164.103856 -304.721928) (xy 164.133421 -304.761272) (xy 164.156292 -304.804849) (xy 164.171876 -304.85153)
			(xy 164.179771 -304.900107) (xy 164.180266 -304.924714) (xy 164.519114 -304.924714) (xy 164.523074 -304.87566)
			(xy 164.534851 -304.827876) (xy 164.554142 -304.7826) (xy 164.580445 -304.741004) (xy 164.61308 -304.704167)
			(xy 164.651201 -304.673042) (xy 164.693822 -304.648435) (xy 164.739838 -304.630983) (xy 164.788057 -304.621139)
			(xy 164.837232 -304.619158) (xy 164.886087 -304.62509) (xy 164.933358 -304.638782) (xy 164.97782 -304.65988)
			(xy 165.018323 -304.687836) (xy 165.053816 -304.721928) (xy 165.083381 -304.761272) (xy 165.106252 -304.804849)
			(xy 165.121836 -304.85153) (xy 165.129731 -304.900107) (xy 165.130226 -304.924714) (xy 165.129731 -304.949321)
			(xy 165.121836 -304.997898) (xy 165.106252 -305.044579) (xy 165.083381 -305.088156) (xy 165.053816 -305.1275)
			(xy 165.018323 -305.161592) (xy 164.97782 -305.189548) (xy 164.933358 -305.210646) (xy 164.886087 -305.224338)
			(xy 164.837232 -305.23027) (xy 164.788057 -305.228289) (xy 164.739838 -305.218445) (xy 164.693822 -305.200993)
			(xy 164.651201 -305.176386) (xy 164.61308 -305.145261) (xy 164.580445 -305.108424) (xy 164.554142 -305.066828)
			(xy 164.534851 -305.021552) (xy 164.523074 -304.973768) (xy 164.519114 -304.924714) (xy 164.180266 -304.924714)
			(xy 164.179771 -304.949321) (xy 164.171876 -304.997898) (xy 164.156292 -305.044579) (xy 164.133421 -305.088156)
			(xy 164.103856 -305.1275) (xy 164.068363 -305.161592) (xy 164.02786 -305.189548) (xy 163.983398 -305.210646)
			(xy 163.936127 -305.224338) (xy 163.887272 -305.23027) (xy 163.838097 -305.228289) (xy 163.789878 -305.218445)
			(xy 163.743862 -305.200993) (xy 163.701241 -305.176386) (xy 163.66312 -305.145261) (xy 163.630485 -305.108424)
			(xy 163.604182 -305.066828) (xy 163.584891 -305.021552) (xy 163.573114 -304.973768) (xy 163.569154 -304.924714)
			(xy 163.230306 -304.924714) (xy 163.229811 -304.949321) (xy 163.221916 -304.997898) (xy 163.206332 -305.044579)
			(xy 163.183461 -305.088156) (xy 163.153896 -305.1275) (xy 163.118403 -305.161592) (xy 163.0779 -305.189548)
			(xy 163.033438 -305.210646) (xy 162.986167 -305.224338) (xy 162.937312 -305.23027) (xy 162.888137 -305.228289)
			(xy 162.839918 -305.218445) (xy 162.793902 -305.200993) (xy 162.751281 -305.176386) (xy 162.71316 -305.145261)
			(xy 162.680525 -305.108424) (xy 162.654222 -305.066828) (xy 162.634931 -305.021552) (xy 162.623154 -304.973768)
			(xy 162.619194 -304.924714) (xy 144.767629 -304.924714) (xy 144.76497 -304.933769) (xy 144.742334 -304.983339)
			(xy 144.712874 -305.029183) (xy 144.67719 -305.070368) (xy 144.636008 -305.106055) (xy 144.590166 -305.135519)
			(xy 144.540599 -305.158159) (xy 144.488313 -305.173515) (xy 144.434375 -305.181274) (xy 144.407128 -305.181762)
			(xy 144.406874 -305.181762) (xy 144.379188 -305.180746) (xy 144.368012 -305.179984) (xy 144.34693 -305.187858)
			(xy 144.276826 -305.260502) (xy 144.26946 -305.281838) (xy 144.27073 -305.293014) (xy 144.271792 -305.303268)
			(xy 144.272935 -305.323853) (xy 144.273016 -305.334162) (xy 144.272586 -305.361418) (xy 144.26705 -305.399948)
			(xy 152.644106 -305.399948) (xy 152.648066 -305.350894) (xy 152.659843 -305.30311) (xy 152.679134 -305.257834)
			(xy 152.705437 -305.216238) (xy 152.738072 -305.179401) (xy 152.776193 -305.148276) (xy 152.818814 -305.123669)
			(xy 152.86483 -305.106217) (xy 152.913049 -305.096373) (xy 152.962224 -305.094392) (xy 153.011079 -305.100324)
			(xy 153.05835 -305.114016) (xy 153.102812 -305.135114) (xy 153.143315 -305.16307) (xy 153.178808 -305.197162)
			(xy 153.208373 -305.236506) (xy 153.231244 -305.280083) (xy 153.246828 -305.326764) (xy 153.254723 -305.375341)
			(xy 153.255218 -305.399948) (xy 153.594066 -305.399948) (xy 153.598026 -305.350894) (xy 153.609803 -305.30311)
			(xy 153.629094 -305.257834) (xy 153.655397 -305.216238) (xy 153.688032 -305.179401) (xy 153.726153 -305.148276)
			(xy 153.768774 -305.123669) (xy 153.81479 -305.106217) (xy 153.863009 -305.096373) (xy 153.912184 -305.094392)
			(xy 153.961039 -305.100324) (xy 154.00831 -305.114016) (xy 154.052772 -305.135114) (xy 154.093275 -305.16307)
			(xy 154.128768 -305.197162) (xy 154.158333 -305.236506) (xy 154.181204 -305.280083) (xy 154.196788 -305.326764)
			(xy 154.204683 -305.375341) (xy 154.205178 -305.399948) (xy 154.204683 -305.424555) (xy 154.204504 -305.425656)
			(xy 154.523436 -305.425656) (xy 154.523436 -305.37424) (xy 154.531479 -305.323458) (xy 154.547367 -305.274559)
			(xy 154.57071 -305.228747) (xy 154.600931 -305.187151) (xy 154.637287 -305.150795) (xy 154.678883 -305.120574)
			(xy 154.724695 -305.097231) (xy 154.773594 -305.081343) (xy 154.824376 -305.0733) (xy 154.875792 -305.0733)
			(xy 154.926574 -305.081343) (xy 154.975473 -305.097231) (xy 155.021285 -305.120574) (xy 155.062881 -305.150795)
			(xy 155.099237 -305.187151) (xy 155.129458 -305.228747) (xy 155.152801 -305.274559) (xy 155.168689 -305.323458)
			(xy 155.176732 -305.37424) (xy 155.177236 -305.399948) (xy 155.176732 -305.425656) (xy 155.473396 -305.425656)
			(xy 155.473396 -305.37424) (xy 155.481439 -305.323458) (xy 155.497327 -305.274559) (xy 155.52067 -305.228747)
			(xy 155.550891 -305.187151) (xy 155.587247 -305.150795) (xy 155.628843 -305.120574) (xy 155.674655 -305.097231)
			(xy 155.723554 -305.081343) (xy 155.774336 -305.0733) (xy 155.825752 -305.0733) (xy 155.876534 -305.081343)
			(xy 155.925433 -305.097231) (xy 155.971245 -305.120574) (xy 156.012841 -305.150795) (xy 156.049197 -305.187151)
			(xy 156.079418 -305.228747) (xy 156.102761 -305.274559) (xy 156.118649 -305.323458) (xy 156.126692 -305.37424)
			(xy 156.127196 -305.399948) (xy 156.4442 -305.399948) (xy 156.44816 -305.350894) (xy 156.459937 -305.30311)
			(xy 156.479228 -305.257834) (xy 156.505531 -305.216238) (xy 156.538166 -305.179401) (xy 156.576287 -305.148276)
			(xy 156.618908 -305.123669) (xy 156.664924 -305.106217) (xy 156.713143 -305.096373) (xy 156.762318 -305.094392)
			(xy 156.811173 -305.100324) (xy 156.858444 -305.114016) (xy 156.902906 -305.135114) (xy 156.943409 -305.16307)
			(xy 156.978902 -305.197162) (xy 157.008467 -305.236506) (xy 157.031338 -305.280083) (xy 157.046922 -305.326764)
			(xy 157.054817 -305.375341) (xy 157.055312 -305.399948) (xy 157.054817 -305.424555) (xy 157.054638 -305.425656)
			(xy 157.373316 -305.425656) (xy 157.373316 -305.37424) (xy 157.381359 -305.323458) (xy 157.397247 -305.274559)
			(xy 157.42059 -305.228747) (xy 157.450811 -305.187151) (xy 157.487167 -305.150795) (xy 157.528763 -305.120574)
			(xy 157.574575 -305.097231) (xy 157.623474 -305.081343) (xy 157.674256 -305.0733) (xy 157.725672 -305.0733)
			(xy 157.776454 -305.081343) (xy 157.825353 -305.097231) (xy 157.871165 -305.120574) (xy 157.912761 -305.150795)
			(xy 157.949117 -305.187151) (xy 157.979338 -305.228747) (xy 158.002681 -305.274559) (xy 158.018569 -305.323458)
			(xy 158.026612 -305.37424) (xy 158.027116 -305.399948) (xy 158.026612 -305.425656) (xy 158.323276 -305.425656)
			(xy 158.323276 -305.37424) (xy 158.331319 -305.323458) (xy 158.347207 -305.274559) (xy 158.37055 -305.228747)
			(xy 158.400771 -305.187151) (xy 158.437127 -305.150795) (xy 158.478723 -305.120574) (xy 158.524535 -305.097231)
			(xy 158.573434 -305.081343) (xy 158.624216 -305.0733) (xy 158.675632 -305.0733) (xy 158.726414 -305.081343)
			(xy 158.775313 -305.097231) (xy 158.821125 -305.120574) (xy 158.862721 -305.150795) (xy 158.899077 -305.187151)
			(xy 158.929298 -305.228747) (xy 158.952641 -305.274559) (xy 158.968529 -305.323458) (xy 158.976572 -305.37424)
			(xy 158.977076 -305.399948) (xy 159.29408 -305.399948) (xy 159.29804 -305.350894) (xy 159.309817 -305.30311)
			(xy 159.329108 -305.257834) (xy 159.355411 -305.216238) (xy 159.388046 -305.179401) (xy 159.426167 -305.148276)
			(xy 159.468788 -305.123669) (xy 159.514804 -305.106217) (xy 159.563023 -305.096373) (xy 159.612198 -305.094392)
			(xy 159.661053 -305.100324) (xy 159.708324 -305.114016) (xy 159.752786 -305.135114) (xy 159.793289 -305.16307)
			(xy 159.828782 -305.197162) (xy 159.858347 -305.236506) (xy 159.881218 -305.280083) (xy 159.896802 -305.326764)
			(xy 159.904697 -305.375341) (xy 159.905192 -305.399948) (xy 160.24404 -305.399948) (xy 160.248 -305.350894)
			(xy 160.259777 -305.30311) (xy 160.279068 -305.257834) (xy 160.305371 -305.216238) (xy 160.338006 -305.179401)
			(xy 160.376127 -305.148276) (xy 160.418748 -305.123669) (xy 160.464764 -305.106217) (xy 160.512983 -305.096373)
			(xy 160.562158 -305.094392) (xy 160.611013 -305.100324) (xy 160.658284 -305.114016) (xy 160.702746 -305.135114)
			(xy 160.743249 -305.16307) (xy 160.778742 -305.197162) (xy 160.808307 -305.236506) (xy 160.831178 -305.280083)
			(xy 160.846762 -305.326764) (xy 160.854657 -305.375341) (xy 160.855152 -305.399948) (xy 161.194254 -305.399948)
			(xy 161.198214 -305.350894) (xy 161.209991 -305.30311) (xy 161.229282 -305.257834) (xy 161.255585 -305.216238)
			(xy 161.28822 -305.179401) (xy 161.326341 -305.148276) (xy 161.368962 -305.123669) (xy 161.414978 -305.106217)
			(xy 161.463197 -305.096373) (xy 161.512372 -305.094392) (xy 161.561227 -305.100324) (xy 161.608498 -305.114016)
			(xy 161.65296 -305.135114) (xy 161.693463 -305.16307) (xy 161.728956 -305.197162) (xy 161.758521 -305.236506)
			(xy 161.781392 -305.280083) (xy 161.796976 -305.326764) (xy 161.804871 -305.375341) (xy 161.805366 -305.399948)
			(xy 161.804871 -305.424555) (xy 161.796976 -305.473132) (xy 161.781392 -305.519813) (xy 161.758521 -305.56339)
			(xy 161.728956 -305.602734) (xy 161.693463 -305.636826) (xy 161.65296 -305.664782) (xy 161.608498 -305.68588)
			(xy 161.561227 -305.699572) (xy 161.512372 -305.705504) (xy 161.463197 -305.703523) (xy 161.414978 -305.693679)
			(xy 161.368962 -305.676227) (xy 161.326341 -305.65162) (xy 161.28822 -305.620495) (xy 161.255585 -305.583658)
			(xy 161.229282 -305.542062) (xy 161.209991 -305.496786) (xy 161.198214 -305.449002) (xy 161.194254 -305.399948)
			(xy 160.855152 -305.399948) (xy 160.854657 -305.424555) (xy 160.846762 -305.473132) (xy 160.831178 -305.519813)
			(xy 160.808307 -305.56339) (xy 160.778742 -305.602734) (xy 160.743249 -305.636826) (xy 160.702746 -305.664782)
			(xy 160.658284 -305.68588) (xy 160.611013 -305.699572) (xy 160.562158 -305.705504) (xy 160.512983 -305.703523)
			(xy 160.464764 -305.693679) (xy 160.418748 -305.676227) (xy 160.376127 -305.65162) (xy 160.338006 -305.620495)
			(xy 160.305371 -305.583658) (xy 160.279068 -305.542062) (xy 160.259777 -305.496786) (xy 160.248 -305.449002)
			(xy 160.24404 -305.399948) (xy 159.905192 -305.399948) (xy 159.904697 -305.424555) (xy 159.896802 -305.473132)
			(xy 159.881218 -305.519813) (xy 159.858347 -305.56339) (xy 159.828782 -305.602734) (xy 159.793289 -305.636826)
			(xy 159.752786 -305.664782) (xy 159.708324 -305.68588) (xy 159.661053 -305.699572) (xy 159.612198 -305.705504)
			(xy 159.563023 -305.703523) (xy 159.514804 -305.693679) (xy 159.468788 -305.676227) (xy 159.426167 -305.65162)
			(xy 159.388046 -305.620495) (xy 159.355411 -305.583658) (xy 159.329108 -305.542062) (xy 159.309817 -305.496786)
			(xy 159.29804 -305.449002) (xy 159.29408 -305.399948) (xy 158.977076 -305.399948) (xy 158.976572 -305.425656)
			(xy 158.968529 -305.476438) (xy 158.952641 -305.525337) (xy 158.929298 -305.571149) (xy 158.899077 -305.612745)
			(xy 158.862721 -305.649101) (xy 158.821125 -305.679322) (xy 158.775313 -305.702665) (xy 158.726414 -305.718553)
			(xy 158.675632 -305.726596) (xy 158.624216 -305.726596) (xy 158.573434 -305.718553) (xy 158.524535 -305.702665)
			(xy 158.478723 -305.679322) (xy 158.437127 -305.649101) (xy 158.400771 -305.612745) (xy 158.37055 -305.571149)
			(xy 158.347207 -305.525337) (xy 158.331319 -305.476438) (xy 158.323276 -305.425656) (xy 158.026612 -305.425656)
			(xy 158.018569 -305.476438) (xy 158.002681 -305.525337) (xy 157.979338 -305.571149) (xy 157.949117 -305.612745)
			(xy 157.912761 -305.649101) (xy 157.871165 -305.679322) (xy 157.825353 -305.702665) (xy 157.776454 -305.718553)
			(xy 157.725672 -305.726596) (xy 157.674256 -305.726596) (xy 157.623474 -305.718553) (xy 157.574575 -305.702665)
			(xy 157.528763 -305.679322) (xy 157.487167 -305.649101) (xy 157.450811 -305.612745) (xy 157.42059 -305.571149)
			(xy 157.397247 -305.525337) (xy 157.381359 -305.476438) (xy 157.373316 -305.425656) (xy 157.054638 -305.425656)
			(xy 157.046922 -305.473132) (xy 157.031338 -305.519813) (xy 157.008467 -305.56339) (xy 156.978902 -305.602734)
			(xy 156.943409 -305.636826) (xy 156.902906 -305.664782) (xy 156.858444 -305.68588) (xy 156.811173 -305.699572)
			(xy 156.762318 -305.705504) (xy 156.713143 -305.703523) (xy 156.664924 -305.693679) (xy 156.618908 -305.676227)
			(xy 156.576287 -305.65162) (xy 156.538166 -305.620495) (xy 156.505531 -305.583658) (xy 156.479228 -305.542062)
			(xy 156.459937 -305.496786) (xy 156.44816 -305.449002) (xy 156.4442 -305.399948) (xy 156.127196 -305.399948)
			(xy 156.126692 -305.425656) (xy 156.118649 -305.476438) (xy 156.102761 -305.525337) (xy 156.079418 -305.571149)
			(xy 156.049197 -305.612745) (xy 156.012841 -305.649101) (xy 155.971245 -305.679322) (xy 155.925433 -305.702665)
			(xy 155.876534 -305.718553) (xy 155.825752 -305.726596) (xy 155.774336 -305.726596) (xy 155.723554 -305.718553)
			(xy 155.674655 -305.702665) (xy 155.628843 -305.679322) (xy 155.587247 -305.649101) (xy 155.550891 -305.612745)
			(xy 155.52067 -305.571149) (xy 155.497327 -305.525337) (xy 155.481439 -305.476438) (xy 155.473396 -305.425656)
			(xy 155.176732 -305.425656) (xy 155.168689 -305.476438) (xy 155.152801 -305.525337) (xy 155.129458 -305.571149)
			(xy 155.099237 -305.612745) (xy 155.062881 -305.649101) (xy 155.021285 -305.679322) (xy 154.975473 -305.702665)
			(xy 154.926574 -305.718553) (xy 154.875792 -305.726596) (xy 154.824376 -305.726596) (xy 154.773594 -305.718553)
			(xy 154.724695 -305.702665) (xy 154.678883 -305.679322) (xy 154.637287 -305.649101) (xy 154.600931 -305.612745)
			(xy 154.57071 -305.571149) (xy 154.547367 -305.525337) (xy 154.531479 -305.476438) (xy 154.523436 -305.425656)
			(xy 154.204504 -305.425656) (xy 154.196788 -305.473132) (xy 154.181204 -305.519813) (xy 154.158333 -305.56339)
			(xy 154.128768 -305.602734) (xy 154.093275 -305.636826) (xy 154.052772 -305.664782) (xy 154.00831 -305.68588)
			(xy 153.961039 -305.699572) (xy 153.912184 -305.705504) (xy 153.863009 -305.703523) (xy 153.81479 -305.693679)
			(xy 153.768774 -305.676227) (xy 153.726153 -305.65162) (xy 153.688032 -305.620495) (xy 153.655397 -305.583658)
			(xy 153.629094 -305.542062) (xy 153.609803 -305.496786) (xy 153.598026 -305.449002) (xy 153.594066 -305.399948)
			(xy 153.255218 -305.399948) (xy 153.254723 -305.424555) (xy 153.246828 -305.473132) (xy 153.231244 -305.519813)
			(xy 153.208373 -305.56339) (xy 153.178808 -305.602734) (xy 153.143315 -305.636826) (xy 153.102812 -305.664782)
			(xy 153.05835 -305.68588) (xy 153.011079 -305.699572) (xy 152.962224 -305.705504) (xy 152.913049 -305.703523)
			(xy 152.86483 -305.693679) (xy 152.818814 -305.676227) (xy 152.776193 -305.65162) (xy 152.738072 -305.620495)
			(xy 152.705437 -305.583658) (xy 152.679134 -305.542062) (xy 152.659843 -305.496786) (xy 152.648066 -305.449002)
			(xy 152.644106 -305.399948) (xy 144.26705 -305.399948) (xy 144.264833 -305.415377) (xy 144.24948 -305.467683)
			(xy 144.226839 -305.517271) (xy 144.197371 -305.563132) (xy 144.161676 -305.604333) (xy 144.120481 -305.640035)
			(xy 144.074624 -305.66951) (xy 144.02504 -305.692159) (xy 143.972736 -305.70752) (xy 143.918779 -305.715281)
			(xy 143.864266 -305.715285) (xy 143.810308 -305.70753) (xy 143.758003 -305.692174) (xy 143.708415 -305.669531)
			(xy 143.662555 -305.640062) (xy 143.621356 -305.604365) (xy 143.585656 -305.563169) (xy 143.556183 -305.517311)
			(xy 143.533536 -305.467725) (xy 143.518177 -305.415421) (xy 143.510418 -305.361464) (xy 143.510416 -305.306951)
			(xy 133.096209 -305.306951) (xy 133.087685 -305.314337) (xy 133.041835 -305.343803) (xy 132.992258 -305.366445)
			(xy 132.939963 -305.3818) (xy 132.886015 -305.389556) (xy 132.831513 -305.389556) (xy 132.777565 -305.3818)
			(xy 132.72527 -305.366445) (xy 132.675693 -305.343803) (xy 132.629843 -305.314337) (xy 132.588652 -305.278646)
			(xy 132.552961 -305.237455) (xy 132.523495 -305.191605) (xy 132.500853 -305.142028) (xy 132.485498 -305.089733)
			(xy 132.477742 -305.035785) (xy 132.477256 -305.008534) (xy 128.432052 -305.008534) (xy 128.431566 -305.035785)
			(xy 128.42381 -305.089733) (xy 128.408455 -305.142028) (xy 128.385813 -305.191605) (xy 128.356347 -305.237455)
			(xy 128.320656 -305.278646) (xy 128.279465 -305.314337) (xy 128.233615 -305.343803) (xy 128.184038 -305.366445)
			(xy 128.131743 -305.3818) (xy 128.077795 -305.389556) (xy 128.023293 -305.389556) (xy 127.969345 -305.3818)
			(xy 127.91705 -305.366445) (xy 127.867473 -305.343803) (xy 127.821623 -305.314337) (xy 127.780432 -305.278646)
			(xy 127.744741 -305.237455) (xy 127.715275 -305.191605) (xy 127.692633 -305.142028) (xy 127.677278 -305.089733)
			(xy 127.669522 -305.035785) (xy 127.669036 -305.008534) (xy 126.400052 -305.008534) (xy 126.399566 -305.035785)
			(xy 126.39181 -305.089733) (xy 126.376455 -305.142028) (xy 126.353813 -305.191605) (xy 126.324347 -305.237455)
			(xy 126.288656 -305.278646) (xy 126.247465 -305.314337) (xy 126.201615 -305.343803) (xy 126.152038 -305.366445)
			(xy 126.099743 -305.3818) (xy 126.045795 -305.389556) (xy 125.991293 -305.389556) (xy 125.937345 -305.3818)
			(xy 125.88505 -305.366445) (xy 125.835473 -305.343803) (xy 125.789623 -305.314337) (xy 125.748432 -305.278646)
			(xy 125.712741 -305.237455) (xy 125.683275 -305.191605) (xy 125.660633 -305.142028) (xy 125.645278 -305.089733)
			(xy 125.637522 -305.035785) (xy 125.637036 -305.008534) (xy 125.011942 -305.008534) (xy 125.011456 -305.035785)
			(xy 125.0037 -305.089733) (xy 124.988345 -305.142028) (xy 124.965703 -305.191605) (xy 124.936237 -305.237455)
			(xy 124.900546 -305.278646) (xy 124.859355 -305.314337) (xy 124.813505 -305.343803) (xy 124.763928 -305.366445)
			(xy 124.711633 -305.3818) (xy 124.657685 -305.389556) (xy 124.603183 -305.389556) (xy 124.549235 -305.3818)
			(xy 124.49694 -305.366445) (xy 124.447363 -305.343803) (xy 124.401513 -305.314337) (xy 124.360322 -305.278646)
			(xy 124.324631 -305.237455) (xy 124.295165 -305.191605) (xy 124.272523 -305.142028) (xy 124.257168 -305.089733)
			(xy 124.249412 -305.035785) (xy 124.248926 -305.008534) (xy 121.591832 -305.008534) (xy 121.591346 -305.035785)
			(xy 121.58359 -305.089733) (xy 121.568235 -305.142028) (xy 121.545593 -305.191605) (xy 121.516127 -305.237455)
			(xy 121.480436 -305.278646) (xy 121.439245 -305.314337) (xy 121.393395 -305.343803) (xy 121.343818 -305.366445)
			(xy 121.291523 -305.3818) (xy 121.237575 -305.389556) (xy 121.183073 -305.389556) (xy 121.129125 -305.3818)
			(xy 121.07683 -305.366445) (xy 121.027253 -305.343803) (xy 120.981403 -305.314337) (xy 120.940212 -305.278646)
			(xy 120.904521 -305.237455) (xy 120.875055 -305.191605) (xy 120.852413 -305.142028) (xy 120.837058 -305.089733)
			(xy 120.829302 -305.035785) (xy 120.828816 -305.008534) (xy 118.830852 -305.008534) (xy 118.830852 -307.82387)
			(xy 121.416826 -307.82387) (xy 121.417268 -307.796499) (xy 121.425091 -307.742318) (xy 121.440585 -307.689815)
			(xy 121.463432 -307.640068) (xy 121.493162 -307.594103) (xy 121.510806 -307.573172) (xy 121.51106 -307.572918)
			(xy 121.516652 -307.565836) (xy 121.522894 -307.548915) (xy 121.523252 -307.539898) (xy 121.523252 -307.472842)
			(xy 121.522885 -307.463826) (xy 121.516646 -307.446908) (xy 121.51106 -307.439822) (xy 121.510806 -307.439822)
			(xy 121.510806 -307.439568) (xy 121.493137 -307.418659) (xy 121.463415 -307.372686) (xy 121.440572 -307.322936)
			(xy 121.425079 -307.270431) (xy 121.417254 -307.216249) (xy 121.417257 -307.161506) (xy 121.425089 -307.107325)
			(xy 121.440588 -307.054822) (xy 121.463437 -307.005074) (xy 121.493164 -306.959105) (xy 121.510806 -306.938172)
			(xy 121.51106 -306.937918) (xy 121.516652 -306.930836) (xy 121.522894 -306.913915) (xy 121.523252 -306.904898)
			(xy 121.523252 -306.837842) (xy 121.522885 -306.828826) (xy 121.516646 -306.811908) (xy 121.51106 -306.804822)
			(xy 121.510806 -306.804822) (xy 121.510806 -306.804568) (xy 121.493137 -306.783659) (xy 121.463415 -306.737686)
			(xy 121.440572 -306.687936) (xy 121.425079 -306.635431) (xy 121.417254 -306.581249) (xy 121.417257 -306.526506)
			(xy 121.425089 -306.472325) (xy 121.440588 -306.419822) (xy 121.463437 -306.370074) (xy 121.493164 -306.324105)
			(xy 121.510806 -306.303172) (xy 121.51106 -306.302918) (xy 121.516652 -306.295836) (xy 121.522894 -306.278915)
			(xy 121.523252 -306.269898) (xy 121.523252 -306.202842) (xy 121.522885 -306.193826) (xy 121.516646 -306.176908)
			(xy 121.51106 -306.169822) (xy 121.510806 -306.169822) (xy 121.510806 -306.169568) (xy 121.493186 -306.14862)
			(xy 121.463471 -306.102652) (xy 121.440632 -306.052908) (xy 121.425136 -306.000411) (xy 121.417303 -305.946238)
			(xy 121.416826 -305.91887) (xy 121.417312 -305.891619) (xy 121.425068 -305.837671) (xy 121.440423 -305.785376)
			(xy 121.463065 -305.735799) (xy 121.492531 -305.689949) (xy 121.528222 -305.648758) (xy 121.569413 -305.613067)
			(xy 121.615263 -305.583601) (xy 121.66484 -305.560959) (xy 121.717135 -305.545604) (xy 121.771083 -305.537848)
			(xy 121.825585 -305.537848) (xy 121.879533 -305.545604) (xy 121.931828 -305.560959) (xy 121.981405 -305.583601)
			(xy 122.027255 -305.613067) (xy 122.068446 -305.648758) (xy 122.104137 -305.689949) (xy 122.133603 -305.735799)
			(xy 122.156245 -305.785376) (xy 122.1716 -305.837671) (xy 122.179356 -305.891619) (xy 122.179842 -305.91887)
			(xy 122.179372 -305.94624) (xy 122.171558 -306.00042) (xy 122.15607 -306.052923) (xy 122.133229 -306.10267)
			(xy 122.103504 -306.148637) (xy 122.085862 -306.169568) (xy 122.085608 -306.169822) (xy 122.080007 -306.176899)
			(xy 122.073769 -306.193823) (xy 122.073416 -306.202842) (xy 122.073416 -306.269898) (xy 122.07377 -306.278915)
			(xy 122.080019 -306.295832) (xy 122.085608 -306.302918) (xy 122.085862 -306.302918) (xy 122.085862 -306.303172)
			(xy 122.103474 -306.324128) (xy 122.133201 -306.370092) (xy 122.156048 -306.419834) (xy 122.171547 -306.472333)
			(xy 122.179379 -306.526508) (xy 122.179382 -306.581247) (xy 122.171557 -306.635423) (xy 122.156064 -306.687924)
			(xy 122.133222 -306.737669) (xy 122.103501 -306.783636) (xy 122.085862 -306.804568) (xy 122.085608 -306.804822)
			(xy 122.080007 -306.811899) (xy 122.073769 -306.828823) (xy 122.073416 -306.837842) (xy 122.073416 -306.904898)
			(xy 122.07377 -306.913915) (xy 122.080019 -306.930832) (xy 122.085608 -306.937918) (xy 122.085862 -306.937918)
			(xy 122.085862 -306.938172) (xy 122.103474 -306.959128) (xy 122.133201 -307.005092) (xy 122.156048 -307.054834)
			(xy 122.171547 -307.107333) (xy 122.179379 -307.161508) (xy 122.179382 -307.216247) (xy 122.171557 -307.270423)
			(xy 122.156064 -307.322924) (xy 122.133222 -307.372669) (xy 122.103501 -307.418636) (xy 122.085862 -307.439568)
			(xy 122.085608 -307.439822) (xy 122.080007 -307.446899) (xy 122.073769 -307.463823) (xy 122.073416 -307.472842)
			(xy 122.073416 -307.539898) (xy 122.07377 -307.548915) (xy 122.080019 -307.565832) (xy 122.085608 -307.572918)
			(xy 122.085862 -307.572918) (xy 122.085862 -307.573172) (xy 122.103496 -307.594109) (xy 122.133209 -307.64008)
			(xy 122.156047 -307.689826) (xy 122.171539 -307.742326) (xy 122.179368 -307.796501) (xy 122.179842 -307.82387)
			(xy 122.179356 -307.851121) (xy 122.175532 -307.877718) (xy 125.049026 -307.877718) (xy 125.049496 -307.850348)
			(xy 125.057312 -307.796169) (xy 125.0728 -307.743665) (xy 125.095641 -307.693918) (xy 125.125365 -307.647952)
			(xy 125.143006 -307.62702) (xy 125.14326 -307.626766) (xy 125.148832 -307.61967) (xy 125.155086 -307.60276)
			(xy 125.155452 -307.593746) (xy 125.155452 -307.52669) (xy 125.15511 -307.517671) (xy 125.148853 -307.500754)
			(xy 125.14326 -307.49367) (xy 125.143006 -307.49367) (xy 125.143006 -307.493416) (xy 125.125384 -307.472469)
			(xy 125.09566 -307.426503) (xy 125.072815 -307.376759) (xy 125.057318 -307.324259) (xy 125.049488 -307.270083)
			(xy 125.049486 -307.215344) (xy 125.057312 -307.161167) (xy 125.072805 -307.108667) (xy 125.095647 -307.058921)
			(xy 125.125367 -307.012953) (xy 125.143006 -306.99202) (xy 125.14326 -306.991766) (xy 125.148832 -306.98467)
			(xy 125.155086 -306.96776) (xy 125.155452 -306.958746) (xy 125.155452 -306.89169) (xy 125.15511 -306.882671)
			(xy 125.148853 -306.865754) (xy 125.14326 -306.85867) (xy 125.143006 -306.85867) (xy 125.143006 -306.858416)
			(xy 125.125384 -306.837469) (xy 125.09566 -306.791503) (xy 125.072815 -306.741759) (xy 125.057318 -306.689259)
			(xy 125.049488 -306.635083) (xy 125.049486 -306.580344) (xy 125.057312 -306.526167) (xy 125.072805 -306.473667)
			(xy 125.095647 -306.423921) (xy 125.125367 -306.377953) (xy 125.143006 -306.35702) (xy 125.14326 -306.356766)
			(xy 125.148832 -306.34967) (xy 125.155086 -306.33276) (xy 125.155452 -306.323746) (xy 125.155452 -306.25669)
			(xy 125.15511 -306.247671) (xy 125.148853 -306.230754) (xy 125.14326 -306.22367) (xy 125.143006 -306.22367)
			(xy 125.143006 -306.223416) (xy 125.125362 -306.202488) (xy 125.095651 -306.156514) (xy 125.072816 -306.106766)
			(xy 125.057326 -306.054264) (xy 125.049499 -306.000087) (xy 125.049026 -305.972718) (xy 125.049512 -305.945467)
			(xy 125.057268 -305.891519) (xy 125.072623 -305.839224) (xy 125.095265 -305.789647) (xy 125.124731 -305.743797)
			(xy 125.160422 -305.702606) (xy 125.201613 -305.666915) (xy 125.247463 -305.637449) (xy 125.29704 -305.614807)
			(xy 125.349335 -305.599452) (xy 125.403283 -305.591696) (xy 125.457785 -305.591696) (xy 125.511733 -305.599452)
			(xy 125.564028 -305.614807) (xy 125.613605 -305.637449) (xy 125.659455 -305.666915) (xy 125.700646 -305.702606)
			(xy 125.736337 -305.743797) (xy 125.765803 -305.789647) (xy 125.788445 -305.839224) (xy 125.8038 -305.891519)
			(xy 125.811556 -305.945467) (xy 125.812042 -305.972718) (xy 125.811601 -306.000089) (xy 125.803779 -306.05427)
			(xy 125.788285 -306.106774) (xy 125.765437 -306.15652) (xy 125.735706 -306.202486) (xy 125.718062 -306.223416)
			(xy 125.717808 -306.22367) (xy 125.712229 -306.230762) (xy 125.705977 -306.247674) (xy 125.705616 -306.25669)
			(xy 125.705616 -306.323746) (xy 125.705996 -306.332761) (xy 125.712227 -306.349678) (xy 125.717808 -306.356766)
			(xy 125.718062 -306.356766) (xy 125.718062 -306.35702) (xy 125.735721 -306.377938) (xy 125.765446 -306.423908)
			(xy 125.788291 -306.473657) (xy 125.803786 -306.526161) (xy 125.811613 -306.580342) (xy 125.811611 -306.635085)
			(xy 125.80378 -306.689265) (xy 125.788281 -306.741769) (xy 125.765433 -306.791516) (xy 125.735704 -306.837483)
			(xy 125.718062 -306.858416) (xy 125.717808 -306.85867) (xy 125.712229 -306.865762) (xy 125.705977 -306.882674)
			(xy 125.705616 -306.89169) (xy 125.705616 -306.958746) (xy 125.705996 -306.967761) (xy 125.712227 -306.984678)
			(xy 125.717808 -306.991766) (xy 125.718062 -306.991766) (xy 125.718062 -306.99202) (xy 125.735721 -307.012938)
			(xy 125.765446 -307.058908) (xy 125.788291 -307.108657) (xy 125.803786 -307.161161) (xy 125.811613 -307.215342)
			(xy 125.811611 -307.270085) (xy 125.80378 -307.324265) (xy 125.788281 -307.376769) (xy 125.765433 -307.426516)
			(xy 125.735704 -307.472483) (xy 125.718062 -307.493416) (xy 125.717808 -307.49367) (xy 125.712229 -307.500762)
			(xy 125.705977 -307.517674) (xy 125.705616 -307.52669) (xy 125.705616 -307.593746) (xy 125.705996 -307.602761)
			(xy 125.712227 -307.619678) (xy 125.717808 -307.626766) (xy 125.718062 -307.626766) (xy 125.718062 -307.62702)
			(xy 125.735671 -307.647976) (xy 125.765389 -307.693942) (xy 125.788231 -307.743683) (xy 125.803729 -307.796179)
			(xy 125.807734 -307.82387) (xy 128.257046 -307.82387) (xy 128.257483 -307.796499) (xy 128.265306 -307.742318)
			(xy 128.280802 -307.689814) (xy 128.30365 -307.640068) (xy 128.333381 -307.594102) (xy 128.351026 -307.573172)
			(xy 128.35128 -307.572918) (xy 128.356875 -307.565837) (xy 128.363114 -307.548916) (xy 128.363472 -307.539898)
			(xy 128.363472 -307.472842) (xy 128.363101 -307.463826) (xy 128.356864 -307.446909) (xy 128.35128 -307.439822)
			(xy 128.351026 -307.439822) (xy 128.351026 -307.439568) (xy 128.333356 -307.418659) (xy 128.303632 -307.372687)
			(xy 128.280789 -307.322937) (xy 128.265295 -307.270431) (xy 128.257469 -307.216249) (xy 128.257472 -307.161505)
			(xy 128.265305 -307.107325) (xy 128.280805 -307.054821) (xy 128.303654 -307.005073) (xy 128.333383 -306.959105)
			(xy 128.351026 -306.938172) (xy 128.35128 -306.937918) (xy 128.356875 -306.930837) (xy 128.363114 -306.913916)
			(xy 128.363472 -306.904898) (xy 128.363472 -306.837842) (xy 128.363101 -306.828826) (xy 128.356864 -306.811909)
			(xy 128.35128 -306.804822) (xy 128.351026 -306.804822) (xy 128.351026 -306.804568) (xy 128.333356 -306.783659)
			(xy 128.303632 -306.737687) (xy 128.280789 -306.687937) (xy 128.265295 -306.635431) (xy 128.257469 -306.581249)
			(xy 128.257472 -306.526505) (xy 128.265305 -306.472325) (xy 128.280805 -306.419821) (xy 128.303654 -306.370073)
			(xy 128.333383 -306.324105) (xy 128.351026 -306.303172) (xy 128.35128 -306.302918) (xy 128.356875 -306.295837)
			(xy 128.363114 -306.278916) (xy 128.363472 -306.269898) (xy 128.363472 -306.202842) (xy 128.363101 -306.193826)
			(xy 128.356864 -306.176909) (xy 128.35128 -306.169822) (xy 128.351026 -306.169822) (xy 128.351026 -306.169568)
			(xy 128.333409 -306.148618) (xy 128.303693 -306.10265) (xy 128.280853 -306.052908) (xy 128.265356 -306.000411)
			(xy 128.257523 -305.946238) (xy 128.257046 -305.91887) (xy 128.257532 -305.891619) (xy 128.265288 -305.837671)
			(xy 128.280643 -305.785376) (xy 128.303285 -305.735799) (xy 128.332751 -305.689949) (xy 128.368442 -305.648758)
			(xy 128.409633 -305.613067) (xy 128.455483 -305.583601) (xy 128.50506 -305.560959) (xy 128.557355 -305.545604)
			(xy 128.611303 -305.537848) (xy 128.665805 -305.537848) (xy 128.719753 -305.545604) (xy 128.772048 -305.560959)
			(xy 128.821625 -305.583601) (xy 128.867475 -305.613067) (xy 128.908666 -305.648758) (xy 128.944357 -305.689949)
			(xy 128.973823 -305.735799) (xy 128.996465 -305.785376) (xy 129.01182 -305.837671) (xy 129.019576 -305.891619)
			(xy 129.020062 -305.91887) (xy 129.019588 -305.94624) (xy 129.011773 -306.000419) (xy 128.996287 -306.052923)
			(xy 128.973446 -306.10267) (xy 128.943723 -306.148636) (xy 128.926082 -306.169568) (xy 128.925828 -306.169822)
			(xy 128.920218 -306.176892) (xy 128.913987 -306.193822) (xy 128.913636 -306.202842) (xy 128.913636 -306.269898)
			(xy 128.913986 -306.278916) (xy 128.920238 -306.295833) (xy 128.925828 -306.302918) (xy 128.926082 -306.302918)
			(xy 128.926082 -306.303172) (xy 128.943693 -306.324129) (xy 128.973418 -306.370093) (xy 128.996265 -306.419835)
			(xy 129.011763 -306.472333) (xy 129.019594 -306.526508) (xy 129.019597 -306.581247) (xy 129.011773 -306.635423)
			(xy 128.996281 -306.687923) (xy 128.97344 -306.737668) (xy 128.94372 -306.783635) (xy 128.926082 -306.804568)
			(xy 128.925828 -306.804822) (xy 128.920218 -306.811892) (xy 128.913987 -306.828822) (xy 128.913636 -306.837842)
			(xy 128.913636 -306.904898) (xy 128.913986 -306.913916) (xy 128.920238 -306.930833) (xy 128.925828 -306.937918)
			(xy 128.926082 -306.937918) (xy 128.926082 -306.938172) (xy 128.943693 -306.959129) (xy 128.973418 -307.005093)
			(xy 128.996265 -307.054835) (xy 129.011763 -307.107333) (xy 129.019594 -307.161508) (xy 129.019597 -307.216247)
			(xy 129.011773 -307.270423) (xy 128.996281 -307.322923) (xy 128.97344 -307.372668) (xy 128.94372 -307.418635)
			(xy 128.926082 -307.439568) (xy 128.925828 -307.439822) (xy 128.920218 -307.446892) (xy 128.913987 -307.463822)
			(xy 128.913636 -307.472842) (xy 128.913636 -307.539898) (xy 128.913986 -307.548916) (xy 128.920238 -307.565833)
			(xy 128.925828 -307.572918) (xy 128.926082 -307.572918) (xy 128.926082 -307.573172) (xy 128.943719 -307.594106)
			(xy 128.973431 -307.640078) (xy 128.996268 -307.689825) (xy 129.01176 -307.742325) (xy 129.019588 -307.796501)
			(xy 129.020062 -307.82387) (xy 129.019576 -307.851121) (xy 129.015752 -307.877718) (xy 131.889246 -307.877718)
			(xy 131.889711 -307.850348) (xy 131.897528 -307.796168) (xy 131.913016 -307.743665) (xy 131.935858 -307.693918)
			(xy 131.965584 -307.647951) (xy 131.983226 -307.62702) (xy 131.98348 -307.626766) (xy 131.989054 -307.619672)
			(xy 131.995306 -307.60276) (xy 131.995672 -307.593746) (xy 131.995672 -307.52669) (xy 131.995326 -307.517672)
			(xy 131.989072 -307.500755) (xy 131.98348 -307.49367) (xy 131.983226 -307.49367) (xy 131.983226 -307.493416)
			(xy 131.965603 -307.472469) (xy 131.935878 -307.426504) (xy 131.913031 -307.37676) (xy 131.897534 -307.32426)
			(xy 131.889703 -307.270083) (xy 131.889701 -307.215344) (xy 131.897528 -307.161167) (xy 131.913022 -307.108666)
			(xy 131.935864 -307.05892) (xy 131.965587 -307.012953) (xy 131.983226 -306.99202) (xy 131.98348 -306.991766)
			(xy 131.989054 -306.984672) (xy 131.995306 -306.96776) (xy 131.995672 -306.958746) (xy 131.995672 -306.89169)
			(xy 131.995326 -306.882672) (xy 131.989072 -306.865755) (xy 131.98348 -306.85867) (xy 131.983226 -306.85867)
			(xy 131.983226 -306.858416) (xy 131.965603 -306.837469) (xy 131.935878 -306.791504) (xy 131.913031 -306.74176)
			(xy 131.897534 -306.68926) (xy 131.889703 -306.635083) (xy 131.889701 -306.580344) (xy 131.897528 -306.526167)
			(xy 131.913022 -306.473666) (xy 131.935864 -306.42392) (xy 131.965587 -306.377953) (xy 131.983226 -306.35702)
			(xy 131.98348 -306.356766) (xy 131.989054 -306.349672) (xy 131.995306 -306.33276) (xy 131.995672 -306.323746)
			(xy 131.995672 -306.25669) (xy 131.995326 -306.247672) (xy 131.989072 -306.230755) (xy 131.98348 -306.22367)
			(xy 131.983226 -306.22367) (xy 131.983226 -306.223416) (xy 131.965585 -306.202485) (xy 131.935873 -306.156513)
			(xy 131.913037 -306.106765) (xy 131.897546 -306.054264) (xy 131.889719 -306.000087) (xy 131.889246 -305.972718)
			(xy 131.889732 -305.945467) (xy 131.897488 -305.891519) (xy 131.912843 -305.839224) (xy 131.935485 -305.789647)
			(xy 131.964951 -305.743797) (xy 132.000642 -305.702606) (xy 132.041833 -305.666915) (xy 132.087683 -305.637449)
			(xy 132.13726 -305.614807) (xy 132.189555 -305.599452) (xy 132.243503 -305.591696) (xy 132.298005 -305.591696)
			(xy 132.351953 -305.599452) (xy 132.404248 -305.614807) (xy 132.453825 -305.637449) (xy 132.499675 -305.666915)
			(xy 132.540866 -305.702606) (xy 132.576557 -305.743797) (xy 132.606023 -305.789647) (xy 132.628665 -305.839224)
			(xy 132.64402 -305.891519) (xy 132.651776 -305.945467) (xy 132.652262 -305.972718) (xy 132.651816 -306.000089)
			(xy 132.644217 -306.052728) (xy 142.790924 -306.052728) (xy 142.794995 -305.997106) (xy 142.807121 -305.942669)
			(xy 142.827044 -305.890578) (xy 142.85434 -305.841943) (xy 142.888426 -305.7978) (xy 142.928575 -305.759091)
			(xy 142.973933 -305.72664) (xy 143.023533 -305.701139) (xy 143.076317 -305.683132) (xy 143.13116 -305.673002)
			(xy 143.186894 -305.670965) (xy 143.242331 -305.677065) (xy 143.296288 -305.691171) (xy 143.347617 -305.712983)
			(xy 143.395223 -305.742037) (xy 143.438091 -305.777712) (xy 143.475308 -305.819249) (xy 143.506081 -305.865762)
			(xy 143.510378 -305.874928) (xy 162.619194 -305.874928) (xy 162.623154 -305.825874) (xy 162.634931 -305.77809)
			(xy 162.654222 -305.732814) (xy 162.680525 -305.691218) (xy 162.71316 -305.654381) (xy 162.751281 -305.623256)
			(xy 162.793902 -305.598649) (xy 162.839918 -305.581197) (xy 162.888137 -305.571353) (xy 162.937312 -305.569372)
			(xy 162.986167 -305.575304) (xy 163.033438 -305.588996) (xy 163.0779 -305.610094) (xy 163.118403 -305.63805)
			(xy 163.153896 -305.672142) (xy 163.183461 -305.711486) (xy 163.206332 -305.755063) (xy 163.221916 -305.801744)
			(xy 163.229811 -305.850321) (xy 163.230306 -305.874928) (xy 163.569154 -305.874928) (xy 163.573114 -305.825874)
			(xy 163.584891 -305.77809) (xy 163.604182 -305.732814) (xy 163.630485 -305.691218) (xy 163.66312 -305.654381)
			(xy 163.701241 -305.623256) (xy 163.743862 -305.598649) (xy 163.789878 -305.581197) (xy 163.838097 -305.571353)
			(xy 163.887272 -305.569372) (xy 163.936127 -305.575304) (xy 163.983398 -305.588996) (xy 164.02786 -305.610094)
			(xy 164.068363 -305.63805) (xy 164.103856 -305.672142) (xy 164.133421 -305.711486) (xy 164.156292 -305.755063)
			(xy 164.171876 -305.801744) (xy 164.179771 -305.850321) (xy 164.180266 -305.874928) (xy 164.519114 -305.874928)
			(xy 164.523074 -305.825874) (xy 164.534851 -305.77809) (xy 164.554142 -305.732814) (xy 164.580445 -305.691218)
			(xy 164.61308 -305.654381) (xy 164.651201 -305.623256) (xy 164.693822 -305.598649) (xy 164.739838 -305.581197)
			(xy 164.788057 -305.571353) (xy 164.837232 -305.569372) (xy 164.886087 -305.575304) (xy 164.933358 -305.588996)
			(xy 164.97782 -305.610094) (xy 165.018323 -305.63805) (xy 165.053816 -305.672142) (xy 165.083381 -305.711486)
			(xy 165.106252 -305.755063) (xy 165.121836 -305.801744) (xy 165.129731 -305.850321) (xy 165.130226 -305.874928)
			(xy 165.129731 -305.899535) (xy 165.121836 -305.948112) (xy 165.106252 -305.994793) (xy 165.083381 -306.03837)
			(xy 165.053816 -306.077714) (xy 165.018323 -306.111806) (xy 164.97782 -306.139762) (xy 164.933358 -306.16086)
			(xy 164.886087 -306.174552) (xy 164.837232 -306.180484) (xy 164.788057 -306.178503) (xy 164.739838 -306.168659)
			(xy 164.693822 -306.151207) (xy 164.651201 -306.1266) (xy 164.61308 -306.095475) (xy 164.580445 -306.058638)
			(xy 164.554142 -306.017042) (xy 164.534851 -305.971766) (xy 164.523074 -305.923982) (xy 164.519114 -305.874928)
			(xy 164.180266 -305.874928) (xy 164.179771 -305.899535) (xy 164.171876 -305.948112) (xy 164.156292 -305.994793)
			(xy 164.133421 -306.03837) (xy 164.103856 -306.077714) (xy 164.068363 -306.111806) (xy 164.02786 -306.139762)
			(xy 163.983398 -306.16086) (xy 163.936127 -306.174552) (xy 163.887272 -306.180484) (xy 163.838097 -306.178503)
			(xy 163.789878 -306.168659) (xy 163.743862 -306.151207) (xy 163.701241 -306.1266) (xy 163.66312 -306.095475)
			(xy 163.630485 -306.058638) (xy 163.604182 -306.017042) (xy 163.584891 -305.971766) (xy 163.573114 -305.923982)
			(xy 163.569154 -305.874928) (xy 163.230306 -305.874928) (xy 163.229811 -305.899535) (xy 163.221916 -305.948112)
			(xy 163.206332 -305.994793) (xy 163.183461 -306.03837) (xy 163.153896 -306.077714) (xy 163.118403 -306.111806)
			(xy 163.0779 -306.139762) (xy 163.033438 -306.16086) (xy 162.986167 -306.174552) (xy 162.937312 -306.180484)
			(xy 162.888137 -306.178503) (xy 162.839918 -306.168659) (xy 162.793902 -306.151207) (xy 162.751281 -306.1266)
			(xy 162.71316 -306.095475) (xy 162.680525 -306.058638) (xy 162.654222 -306.017042) (xy 162.634931 -305.971766)
			(xy 162.623154 -305.923982) (xy 162.619194 -305.874928) (xy 143.510378 -305.874928) (xy 143.529753 -305.916259)
			(xy 143.545821 -305.969666) (xy 143.553941 -306.024842) (xy 143.55445 -306.052728) (xy 143.553941 -306.080614)
			(xy 143.545821 -306.13579) (xy 143.529753 -306.189197) (xy 143.506081 -306.239694) (xy 143.475308 -306.286207)
			(xy 143.438091 -306.327744) (xy 143.411153 -306.350162) (xy 151.693892 -306.350162) (xy 151.697852 -306.301108)
			(xy 151.709629 -306.253324) (xy 151.72892 -306.208048) (xy 151.755223 -306.166452) (xy 151.787858 -306.129615)
			(xy 151.825979 -306.09849) (xy 151.8686 -306.073883) (xy 151.914616 -306.056431) (xy 151.962835 -306.046587)
			(xy 152.01201 -306.044606) (xy 152.060865 -306.050538) (xy 152.108136 -306.06423) (xy 152.152598 -306.085328)
			(xy 152.193101 -306.113284) (xy 152.228594 -306.147376) (xy 152.258159 -306.18672) (xy 152.28103 -306.230297)
			(xy 152.296614 -306.276978) (xy 152.304509 -306.325555) (xy 152.305004 -306.350162) (xy 152.304509 -306.374769)
			(xy 152.304371 -306.375616) (xy 152.623262 -306.375616) (xy 152.623262 -306.3242) (xy 152.631305 -306.273418)
			(xy 152.647193 -306.224519) (xy 152.670536 -306.178707) (xy 152.700757 -306.137111) (xy 152.737113 -306.100755)
			(xy 152.778709 -306.070534) (xy 152.824521 -306.047191) (xy 152.87342 -306.031303) (xy 152.924202 -306.02326)
			(xy 152.975618 -306.02326) (xy 153.0264 -306.031303) (xy 153.075299 -306.047191) (xy 153.121111 -306.070534)
			(xy 153.162707 -306.100755) (xy 153.199063 -306.137111) (xy 153.229284 -306.178707) (xy 153.252627 -306.224519)
			(xy 153.268515 -306.273418) (xy 153.276558 -306.3242) (xy 153.277062 -306.349908) (xy 153.276558 -306.375616)
			(xy 153.573222 -306.375616) (xy 153.573222 -306.3242) (xy 153.581265 -306.273418) (xy 153.597153 -306.224519)
			(xy 153.620496 -306.178707) (xy 153.650717 -306.137111) (xy 153.687073 -306.100755) (xy 153.728669 -306.070534)
			(xy 153.774481 -306.047191) (xy 153.82338 -306.031303) (xy 153.874162 -306.02326) (xy 153.925578 -306.02326)
			(xy 153.97636 -306.031303) (xy 154.025259 -306.047191) (xy 154.071071 -306.070534) (xy 154.112667 -306.100755)
			(xy 154.149023 -306.137111) (xy 154.179244 -306.178707) (xy 154.202587 -306.224519) (xy 154.218475 -306.273418)
			(xy 154.226518 -306.3242) (xy 154.227022 -306.349908) (xy 154.54428 -306.349908) (xy 154.54824 -306.300854)
			(xy 154.560017 -306.25307) (xy 154.579308 -306.207794) (xy 154.605611 -306.166198) (xy 154.638246 -306.129361)
			(xy 154.676367 -306.098236) (xy 154.718988 -306.073629) (xy 154.765004 -306.056177) (xy 154.813223 -306.046333)
			(xy 154.862398 -306.044352) (xy 154.911253 -306.050284) (xy 154.958524 -306.063976) (xy 155.002986 -306.085074)
			(xy 155.043489 -306.11303) (xy 155.078982 -306.147122) (xy 155.108547 -306.186466) (xy 155.131418 -306.230043)
			(xy 155.147002 -306.276724) (xy 155.154897 -306.325301) (xy 155.155392 -306.349908) (xy 155.49424 -306.349908)
			(xy 155.4982 -306.300854) (xy 155.509977 -306.25307) (xy 155.529268 -306.207794) (xy 155.555571 -306.166198)
			(xy 155.588206 -306.129361) (xy 155.626327 -306.098236) (xy 155.668948 -306.073629) (xy 155.714964 -306.056177)
			(xy 155.763183 -306.046333) (xy 155.812358 -306.044352) (xy 155.861213 -306.050284) (xy 155.908484 -306.063976)
			(xy 155.952946 -306.085074) (xy 155.993449 -306.11303) (xy 156.028942 -306.147122) (xy 156.058507 -306.186466)
			(xy 156.081378 -306.230043) (xy 156.096962 -306.276724) (xy 156.104857 -306.325301) (xy 156.105352 -306.349908)
			(xy 156.4442 -306.349908) (xy 156.44816 -306.300854) (xy 156.459937 -306.25307) (xy 156.479228 -306.207794)
			(xy 156.505531 -306.166198) (xy 156.538166 -306.129361) (xy 156.576287 -306.098236) (xy 156.618908 -306.073629)
			(xy 156.664924 -306.056177) (xy 156.713143 -306.046333) (xy 156.762318 -306.044352) (xy 156.811173 -306.050284)
			(xy 156.858444 -306.063976) (xy 156.902906 -306.085074) (xy 156.943409 -306.11303) (xy 156.978902 -306.147122)
			(xy 157.008467 -306.186466) (xy 157.031338 -306.230043) (xy 157.046922 -306.276724) (xy 157.054817 -306.325301)
			(xy 157.055312 -306.349908) (xy 157.39416 -306.349908) (xy 157.39812 -306.300854) (xy 157.409897 -306.25307)
			(xy 157.429188 -306.207794) (xy 157.455491 -306.166198) (xy 157.488126 -306.129361) (xy 157.526247 -306.098236)
			(xy 157.568868 -306.073629) (xy 157.614884 -306.056177) (xy 157.663103 -306.046333) (xy 157.712278 -306.044352)
			(xy 157.761133 -306.050284) (xy 157.808404 -306.063976) (xy 157.852866 -306.085074) (xy 157.893369 -306.11303)
			(xy 157.928862 -306.147122) (xy 157.958427 -306.186466) (xy 157.981298 -306.230043) (xy 157.996882 -306.276724)
			(xy 158.004777 -306.325301) (xy 158.005272 -306.349908) (xy 158.34412 -306.349908) (xy 158.34808 -306.300854)
			(xy 158.359857 -306.25307) (xy 158.379148 -306.207794) (xy 158.405451 -306.166198) (xy 158.438086 -306.129361)
			(xy 158.476207 -306.098236) (xy 158.518828 -306.073629) (xy 158.564844 -306.056177) (xy 158.613063 -306.046333)
			(xy 158.662238 -306.044352) (xy 158.711093 -306.050284) (xy 158.758364 -306.063976) (xy 158.802826 -306.085074)
			(xy 158.843329 -306.11303) (xy 158.878822 -306.147122) (xy 158.908387 -306.186466) (xy 158.931258 -306.230043)
			(xy 158.946842 -306.276724) (xy 158.954737 -306.325301) (xy 158.955232 -306.349908) (xy 158.954737 -306.374515)
			(xy 158.954558 -306.375616) (xy 159.273236 -306.375616) (xy 159.273236 -306.3242) (xy 159.281279 -306.273418)
			(xy 159.297167 -306.224519) (xy 159.32051 -306.178707) (xy 159.350731 -306.137111) (xy 159.387087 -306.100755)
			(xy 159.428683 -306.070534) (xy 159.474495 -306.047191) (xy 159.523394 -306.031303) (xy 159.574176 -306.02326)
			(xy 159.625592 -306.02326) (xy 159.676374 -306.031303) (xy 159.725273 -306.047191) (xy 159.771085 -306.070534)
			(xy 159.812681 -306.100755) (xy 159.849037 -306.137111) (xy 159.879258 -306.178707) (xy 159.902601 -306.224519)
			(xy 159.918489 -306.273418) (xy 159.926532 -306.3242) (xy 159.927036 -306.349908) (xy 159.926532 -306.375616)
			(xy 160.223196 -306.375616) (xy 160.223196 -306.3242) (xy 160.231239 -306.273418) (xy 160.247127 -306.224519)
			(xy 160.27047 -306.178707) (xy 160.300691 -306.137111) (xy 160.337047 -306.100755) (xy 160.378643 -306.070534)
			(xy 160.424455 -306.047191) (xy 160.473354 -306.031303) (xy 160.524136 -306.02326) (xy 160.575552 -306.02326)
			(xy 160.626334 -306.031303) (xy 160.675233 -306.047191) (xy 160.721045 -306.070534) (xy 160.762641 -306.100755)
			(xy 160.798997 -306.137111) (xy 160.829218 -306.178707) (xy 160.852561 -306.224519) (xy 160.868449 -306.273418)
			(xy 160.876492 -306.3242) (xy 160.876996 -306.349908) (xy 161.194254 -306.349908) (xy 161.198214 -306.300854)
			(xy 161.209991 -306.25307) (xy 161.229282 -306.207794) (xy 161.255585 -306.166198) (xy 161.28822 -306.129361)
			(xy 161.326341 -306.098236) (xy 161.368962 -306.073629) (xy 161.414978 -306.056177) (xy 161.463197 -306.046333)
			(xy 161.512372 -306.044352) (xy 161.561227 -306.050284) (xy 161.608498 -306.063976) (xy 161.65296 -306.085074)
			(xy 161.693463 -306.11303) (xy 161.728956 -306.147122) (xy 161.758521 -306.186466) (xy 161.781392 -306.230043)
			(xy 161.796976 -306.276724) (xy 161.804871 -306.325301) (xy 161.805366 -306.349908) (xy 161.804871 -306.374515)
			(xy 161.796976 -306.423092) (xy 161.781392 -306.469773) (xy 161.758521 -306.51335) (xy 161.728956 -306.552694)
			(xy 161.693463 -306.586786) (xy 161.65296 -306.614742) (xy 161.608498 -306.63584) (xy 161.561227 -306.649532)
			(xy 161.512372 -306.655464) (xy 161.463197 -306.653483) (xy 161.414978 -306.643639) (xy 161.368962 -306.626187)
			(xy 161.326341 -306.60158) (xy 161.28822 -306.570455) (xy 161.255585 -306.533618) (xy 161.229282 -306.492022)
			(xy 161.209991 -306.446746) (xy 161.198214 -306.398962) (xy 161.194254 -306.349908) (xy 160.876996 -306.349908)
			(xy 160.876492 -306.375616) (xy 160.868449 -306.426398) (xy 160.852561 -306.475297) (xy 160.829218 -306.521109)
			(xy 160.798997 -306.562705) (xy 160.762641 -306.599061) (xy 160.721045 -306.629282) (xy 160.675233 -306.652625)
			(xy 160.626334 -306.668513) (xy 160.575552 -306.676556) (xy 160.524136 -306.676556) (xy 160.473354 -306.668513)
			(xy 160.424455 -306.652625) (xy 160.378643 -306.629282) (xy 160.337047 -306.599061) (xy 160.300691 -306.562705)
			(xy 160.27047 -306.521109) (xy 160.247127 -306.475297) (xy 160.231239 -306.426398) (xy 160.223196 -306.375616)
			(xy 159.926532 -306.375616) (xy 159.918489 -306.426398) (xy 159.902601 -306.475297) (xy 159.879258 -306.521109)
			(xy 159.849037 -306.562705) (xy 159.812681 -306.599061) (xy 159.771085 -306.629282) (xy 159.725273 -306.652625)
			(xy 159.676374 -306.668513) (xy 159.625592 -306.676556) (xy 159.574176 -306.676556) (xy 159.523394 -306.668513)
			(xy 159.474495 -306.652625) (xy 159.428683 -306.629282) (xy 159.387087 -306.599061) (xy 159.350731 -306.562705)
			(xy 159.32051 -306.521109) (xy 159.297167 -306.475297) (xy 159.281279 -306.426398) (xy 159.273236 -306.375616)
			(xy 158.954558 -306.375616) (xy 158.946842 -306.423092) (xy 158.931258 -306.469773) (xy 158.908387 -306.51335)
			(xy 158.878822 -306.552694) (xy 158.843329 -306.586786) (xy 158.802826 -306.614742) (xy 158.758364 -306.63584)
			(xy 158.711093 -306.649532) (xy 158.662238 -306.655464) (xy 158.613063 -306.653483) (xy 158.564844 -306.643639)
			(xy 158.518828 -306.626187) (xy 158.476207 -306.60158) (xy 158.438086 -306.570455) (xy 158.405451 -306.533618)
			(xy 158.379148 -306.492022) (xy 158.359857 -306.446746) (xy 158.34808 -306.398962) (xy 158.34412 -306.349908)
			(xy 158.005272 -306.349908) (xy 158.004777 -306.374515) (xy 157.996882 -306.423092) (xy 157.981298 -306.469773)
			(xy 157.958427 -306.51335) (xy 157.928862 -306.552694) (xy 157.893369 -306.586786) (xy 157.852866 -306.614742)
			(xy 157.808404 -306.63584) (xy 157.761133 -306.649532) (xy 157.712278 -306.655464) (xy 157.663103 -306.653483)
			(xy 157.614884 -306.643639) (xy 157.568868 -306.626187) (xy 157.526247 -306.60158) (xy 157.488126 -306.570455)
			(xy 157.455491 -306.533618) (xy 157.429188 -306.492022) (xy 157.409897 -306.446746) (xy 157.39812 -306.398962)
			(xy 157.39416 -306.349908) (xy 157.055312 -306.349908) (xy 157.054817 -306.374515) (xy 157.046922 -306.423092)
			(xy 157.031338 -306.469773) (xy 157.008467 -306.51335) (xy 156.978902 -306.552694) (xy 156.943409 -306.586786)
			(xy 156.902906 -306.614742) (xy 156.858444 -306.63584) (xy 156.811173 -306.649532) (xy 156.762318 -306.655464)
			(xy 156.713143 -306.653483) (xy 156.664924 -306.643639) (xy 156.618908 -306.626187) (xy 156.576287 -306.60158)
			(xy 156.538166 -306.570455) (xy 156.505531 -306.533618) (xy 156.479228 -306.492022) (xy 156.459937 -306.446746)
			(xy 156.44816 -306.398962) (xy 156.4442 -306.349908) (xy 156.105352 -306.349908) (xy 156.104857 -306.374515)
			(xy 156.096962 -306.423092) (xy 156.081378 -306.469773) (xy 156.058507 -306.51335) (xy 156.028942 -306.552694)
			(xy 155.993449 -306.586786) (xy 155.952946 -306.614742) (xy 155.908484 -306.63584) (xy 155.861213 -306.649532)
			(xy 155.812358 -306.655464) (xy 155.763183 -306.653483) (xy 155.714964 -306.643639) (xy 155.668948 -306.626187)
			(xy 155.626327 -306.60158) (xy 155.588206 -306.570455) (xy 155.555571 -306.533618) (xy 155.529268 -306.492022)
			(xy 155.509977 -306.446746) (xy 155.4982 -306.398962) (xy 155.49424 -306.349908) (xy 155.155392 -306.349908)
			(xy 155.154897 -306.374515) (xy 155.147002 -306.423092) (xy 155.131418 -306.469773) (xy 155.108547 -306.51335)
			(xy 155.078982 -306.552694) (xy 155.043489 -306.586786) (xy 155.002986 -306.614742) (xy 154.958524 -306.63584)
			(xy 154.911253 -306.649532) (xy 154.862398 -306.655464) (xy 154.813223 -306.653483) (xy 154.765004 -306.643639)
			(xy 154.718988 -306.626187) (xy 154.676367 -306.60158) (xy 154.638246 -306.570455) (xy 154.605611 -306.533618)
			(xy 154.579308 -306.492022) (xy 154.560017 -306.446746) (xy 154.54824 -306.398962) (xy 154.54428 -306.349908)
			(xy 154.227022 -306.349908) (xy 154.226518 -306.375616) (xy 154.218475 -306.426398) (xy 154.202587 -306.475297)
			(xy 154.179244 -306.521109) (xy 154.149023 -306.562705) (xy 154.112667 -306.599061) (xy 154.071071 -306.629282)
			(xy 154.025259 -306.652625) (xy 153.97636 -306.668513) (xy 153.925578 -306.676556) (xy 153.874162 -306.676556)
			(xy 153.82338 -306.668513) (xy 153.774481 -306.652625) (xy 153.728669 -306.629282) (xy 153.687073 -306.599061)
			(xy 153.650717 -306.562705) (xy 153.620496 -306.521109) (xy 153.597153 -306.475297) (xy 153.581265 -306.426398)
			(xy 153.573222 -306.375616) (xy 153.276558 -306.375616) (xy 153.268515 -306.426398) (xy 153.252627 -306.475297)
			(xy 153.229284 -306.521109) (xy 153.199063 -306.562705) (xy 153.162707 -306.599061) (xy 153.121111 -306.629282)
			(xy 153.075299 -306.652625) (xy 153.0264 -306.668513) (xy 152.975618 -306.676556) (xy 152.924202 -306.676556)
			(xy 152.87342 -306.668513) (xy 152.824521 -306.652625) (xy 152.778709 -306.629282) (xy 152.737113 -306.599061)
			(xy 152.700757 -306.562705) (xy 152.670536 -306.521109) (xy 152.647193 -306.475297) (xy 152.631305 -306.426398)
			(xy 152.623262 -306.375616) (xy 152.304371 -306.375616) (xy 152.296614 -306.423346) (xy 152.28103 -306.470027)
			(xy 152.258159 -306.513604) (xy 152.228594 -306.552948) (xy 152.193101 -306.58704) (xy 152.152598 -306.614996)
			(xy 152.108136 -306.636094) (xy 152.060865 -306.649786) (xy 152.01201 -306.655718) (xy 151.962835 -306.653737)
			(xy 151.914616 -306.643893) (xy 151.8686 -306.626441) (xy 151.825979 -306.601834) (xy 151.787858 -306.570709)
			(xy 151.755223 -306.533872) (xy 151.72892 -306.492276) (xy 151.709629 -306.447) (xy 151.697852 -306.399216)
			(xy 151.693892 -306.350162) (xy 143.411153 -306.350162) (xy 143.395223 -306.363419) (xy 143.347617 -306.392473)
			(xy 143.296288 -306.414285) (xy 143.242331 -306.428391) (xy 143.186894 -306.434491) (xy 143.13116 -306.432454)
			(xy 143.076317 -306.422324) (xy 143.023533 -306.404317) (xy 142.973933 -306.378816) (xy 142.928575 -306.346365)
			(xy 142.888426 -306.307656) (xy 142.85434 -306.263513) (xy 142.827044 -306.214878) (xy 142.807121 -306.162787)
			(xy 142.794995 -306.10835) (xy 142.790924 -306.052728) (xy 132.644217 -306.052728) (xy 132.643995 -306.054269)
			(xy 132.628501 -306.106773) (xy 132.605655 -306.15652) (xy 132.575926 -306.202485) (xy 132.558282 -306.223416)
			(xy 132.558028 -306.22367) (xy 132.552439 -306.230755) (xy 132.546196 -306.247673) (xy 132.545836 -306.25669)
			(xy 132.545836 -306.323746) (xy 132.546211 -306.332761) (xy 132.552445 -306.349679) (xy 132.558028 -306.356766)
			(xy 132.558282 -306.356766) (xy 132.558282 -306.35702) (xy 132.57594 -306.377939) (xy 132.605663 -306.423909)
			(xy 132.628507 -306.473658) (xy 132.644002 -306.526162) (xy 132.651828 -306.580342) (xy 132.651826 -306.635085)
			(xy 132.643996 -306.689265) (xy 132.628498 -306.741768) (xy 132.617737 -306.765198) (xy 145.825462 -306.765198)
			(xy 145.829533 -306.709576) (xy 145.841659 -306.655139) (xy 145.861582 -306.603048) (xy 145.888878 -306.554413)
			(xy 145.922964 -306.51027) (xy 145.963113 -306.471561) (xy 146.008471 -306.43911) (xy 146.058071 -306.413609)
			(xy 146.110855 -306.395602) (xy 146.165698 -306.385472) (xy 146.221432 -306.383435) (xy 146.276869 -306.389535)
			(xy 146.330826 -306.403641) (xy 146.382155 -306.425453) (xy 146.429761 -306.454507) (xy 146.472629 -306.490182)
			(xy 146.509846 -306.531719) (xy 146.540619 -306.578232) (xy 146.564291 -306.628729) (xy 146.580359 -306.682136)
			(xy 146.588479 -306.737312) (xy 146.588988 -306.765198) (xy 146.588479 -306.793084) (xy 146.583799 -306.824888)
			(xy 162.619194 -306.824888) (xy 162.623154 -306.775834) (xy 162.634931 -306.72805) (xy 162.654222 -306.682774)
			(xy 162.680525 -306.641178) (xy 162.71316 -306.604341) (xy 162.751281 -306.573216) (xy 162.793902 -306.548609)
			(xy 162.839918 -306.531157) (xy 162.888137 -306.521313) (xy 162.937312 -306.519332) (xy 162.986167 -306.525264)
			(xy 163.033438 -306.538956) (xy 163.0779 -306.560054) (xy 163.118403 -306.58801) (xy 163.153896 -306.622102)
			(xy 163.183461 -306.661446) (xy 163.206332 -306.705023) (xy 163.221916 -306.751704) (xy 163.229811 -306.800281)
			(xy 163.230306 -306.824888) (xy 163.569154 -306.824888) (xy 163.573114 -306.775834) (xy 163.584891 -306.72805)
			(xy 163.604182 -306.682774) (xy 163.630485 -306.641178) (xy 163.66312 -306.604341) (xy 163.701241 -306.573216)
			(xy 163.743862 -306.548609) (xy 163.789878 -306.531157) (xy 163.838097 -306.521313) (xy 163.887272 -306.519332)
			(xy 163.936127 -306.525264) (xy 163.983398 -306.538956) (xy 164.02786 -306.560054) (xy 164.068363 -306.58801)
			(xy 164.103856 -306.622102) (xy 164.133421 -306.661446) (xy 164.156292 -306.705023) (xy 164.171876 -306.751704)
			(xy 164.179771 -306.800281) (xy 164.180266 -306.824888) (xy 164.519114 -306.824888) (xy 164.523074 -306.775834)
			(xy 164.534851 -306.72805) (xy 164.554142 -306.682774) (xy 164.580445 -306.641178) (xy 164.61308 -306.604341)
			(xy 164.651201 -306.573216) (xy 164.693822 -306.548609) (xy 164.739838 -306.531157) (xy 164.788057 -306.521313)
			(xy 164.837232 -306.519332) (xy 164.886087 -306.525264) (xy 164.933358 -306.538956) (xy 164.97782 -306.560054)
			(xy 165.018323 -306.58801) (xy 165.053816 -306.622102) (xy 165.083381 -306.661446) (xy 165.106252 -306.705023)
			(xy 165.121836 -306.751704) (xy 165.129731 -306.800281) (xy 165.130226 -306.824888) (xy 165.129731 -306.849495)
			(xy 165.121836 -306.898072) (xy 165.106252 -306.944753) (xy 165.083381 -306.98833) (xy 165.053816 -307.027674)
			(xy 165.018323 -307.061766) (xy 164.97782 -307.089722) (xy 164.933358 -307.11082) (xy 164.886087 -307.124512)
			(xy 164.837232 -307.130444) (xy 164.788057 -307.128463) (xy 164.739838 -307.118619) (xy 164.693822 -307.101167)
			(xy 164.651201 -307.07656) (xy 164.61308 -307.045435) (xy 164.580445 -307.008598) (xy 164.554142 -306.967002)
			(xy 164.534851 -306.921726) (xy 164.523074 -306.873942) (xy 164.519114 -306.824888) (xy 164.180266 -306.824888)
			(xy 164.179771 -306.849495) (xy 164.171876 -306.898072) (xy 164.156292 -306.944753) (xy 164.133421 -306.98833)
			(xy 164.103856 -307.027674) (xy 164.068363 -307.061766) (xy 164.02786 -307.089722) (xy 163.983398 -307.11082)
			(xy 163.936127 -307.124512) (xy 163.887272 -307.130444) (xy 163.838097 -307.128463) (xy 163.789878 -307.118619)
			(xy 163.743862 -307.101167) (xy 163.701241 -307.07656) (xy 163.66312 -307.045435) (xy 163.630485 -307.008598)
			(xy 163.604182 -306.967002) (xy 163.584891 -306.921726) (xy 163.573114 -306.873942) (xy 163.569154 -306.824888)
			(xy 163.230306 -306.824888) (xy 163.229811 -306.849495) (xy 163.221916 -306.898072) (xy 163.206332 -306.944753)
			(xy 163.183461 -306.98833) (xy 163.153896 -307.027674) (xy 163.118403 -307.061766) (xy 163.0779 -307.089722)
			(xy 163.033438 -307.11082) (xy 162.986167 -307.124512) (xy 162.937312 -307.130444) (xy 162.888137 -307.128463)
			(xy 162.839918 -307.118619) (xy 162.793902 -307.101167) (xy 162.751281 -307.07656) (xy 162.71316 -307.045435)
			(xy 162.680525 -307.008598) (xy 162.654222 -306.967002) (xy 162.634931 -306.921726) (xy 162.623154 -306.873942)
			(xy 162.619194 -306.824888) (xy 146.583799 -306.824888) (xy 146.580359 -306.84826) (xy 146.564291 -306.901667)
			(xy 146.540619 -306.952164) (xy 146.509846 -306.998677) (xy 146.472629 -307.040214) (xy 146.429761 -307.075889)
			(xy 146.382155 -307.104943) (xy 146.330826 -307.126755) (xy 146.276869 -307.140861) (xy 146.221432 -307.146961)
			(xy 146.165698 -307.144924) (xy 146.110855 -307.134794) (xy 146.058071 -307.116787) (xy 146.008471 -307.091286)
			(xy 145.963113 -307.058835) (xy 145.922964 -307.020126) (xy 145.888878 -306.975983) (xy 145.861582 -306.927348)
			(xy 145.841659 -306.875257) (xy 145.829533 -306.82082) (xy 145.825462 -306.765198) (xy 132.617737 -306.765198)
			(xy 132.60565 -306.791515) (xy 132.575924 -306.837483) (xy 132.558282 -306.858416) (xy 132.558028 -306.85867)
			(xy 132.552439 -306.865755) (xy 132.546196 -306.882673) (xy 132.545836 -306.89169) (xy 132.545836 -306.958746)
			(xy 132.546211 -306.967761) (xy 132.552445 -306.984679) (xy 132.558028 -306.991766) (xy 132.558282 -306.991766)
			(xy 132.558282 -306.99202) (xy 132.57594 -307.012939) (xy 132.605663 -307.058909) (xy 132.628507 -307.108658)
			(xy 132.644002 -307.161162) (xy 132.651828 -307.215342) (xy 132.651827 -307.240178) (xy 147.960078 -307.240178)
			(xy 147.964149 -307.184556) (xy 147.976275 -307.130119) (xy 147.996198 -307.078028) (xy 148.023494 -307.029393)
			(xy 148.05758 -306.98525) (xy 148.097729 -306.946541) (xy 148.143087 -306.91409) (xy 148.192687 -306.888589)
			(xy 148.245471 -306.870582) (xy 148.300314 -306.860452) (xy 148.356048 -306.858415) (xy 148.411485 -306.864515)
			(xy 148.465442 -306.878621) (xy 148.516771 -306.900433) (xy 148.564377 -306.929487) (xy 148.607245 -306.965162)
			(xy 148.644462 -307.006699) (xy 148.675235 -307.053212) (xy 148.698907 -307.103709) (xy 148.714975 -307.157116)
			(xy 148.723095 -307.212292) (xy 148.723604 -307.240178) (xy 148.723095 -307.268064) (xy 148.718415 -307.299868)
			(xy 152.644106 -307.299868) (xy 152.648066 -307.250814) (xy 152.659843 -307.20303) (xy 152.679134 -307.157754)
			(xy 152.705437 -307.116158) (xy 152.738072 -307.079321) (xy 152.776193 -307.048196) (xy 152.818814 -307.023589)
			(xy 152.86483 -307.006137) (xy 152.913049 -306.996293) (xy 152.962224 -306.994312) (xy 153.011079 -307.000244)
			(xy 153.05835 -307.013936) (xy 153.102812 -307.035034) (xy 153.143315 -307.06299) (xy 153.178808 -307.097082)
			(xy 153.208373 -307.136426) (xy 153.231244 -307.180003) (xy 153.246828 -307.226684) (xy 153.254723 -307.275261)
			(xy 153.255218 -307.299868) (xy 153.594066 -307.299868) (xy 153.598026 -307.250814) (xy 153.609803 -307.20303)
			(xy 153.629094 -307.157754) (xy 153.655397 -307.116158) (xy 153.688032 -307.079321) (xy 153.726153 -307.048196)
			(xy 153.768774 -307.023589) (xy 153.81479 -307.006137) (xy 153.863009 -306.996293) (xy 153.912184 -306.994312)
			(xy 153.961039 -307.000244) (xy 154.00831 -307.013936) (xy 154.052772 -307.035034) (xy 154.093275 -307.06299)
			(xy 154.128768 -307.097082) (xy 154.158333 -307.136426) (xy 154.181204 -307.180003) (xy 154.196788 -307.226684)
			(xy 154.204683 -307.275261) (xy 154.205178 -307.299868) (xy 154.204683 -307.324475) (xy 154.204504 -307.325576)
			(xy 154.523436 -307.325576) (xy 154.523436 -307.27416) (xy 154.531479 -307.223378) (xy 154.547367 -307.174479)
			(xy 154.57071 -307.128667) (xy 154.600931 -307.087071) (xy 154.637287 -307.050715) (xy 154.678883 -307.020494)
			(xy 154.724695 -306.997151) (xy 154.773594 -306.981263) (xy 154.824376 -306.97322) (xy 154.875792 -306.97322)
			(xy 154.926574 -306.981263) (xy 154.975473 -306.997151) (xy 155.021285 -307.020494) (xy 155.062881 -307.050715)
			(xy 155.099237 -307.087071) (xy 155.129458 -307.128667) (xy 155.152801 -307.174479) (xy 155.168689 -307.223378)
			(xy 155.176732 -307.27416) (xy 155.177236 -307.299868) (xy 155.176732 -307.325576) (xy 155.473396 -307.325576)
			(xy 155.473396 -307.27416) (xy 155.481439 -307.223378) (xy 155.497327 -307.174479) (xy 155.52067 -307.128667)
			(xy 155.550891 -307.087071) (xy 155.587247 -307.050715) (xy 155.628843 -307.020494) (xy 155.674655 -306.997151)
			(xy 155.723554 -306.981263) (xy 155.774336 -306.97322) (xy 155.825752 -306.97322) (xy 155.876534 -306.981263)
			(xy 155.925433 -306.997151) (xy 155.971245 -307.020494) (xy 156.012841 -307.050715) (xy 156.049197 -307.087071)
			(xy 156.079418 -307.128667) (xy 156.102761 -307.174479) (xy 156.118649 -307.223378) (xy 156.126692 -307.27416)
			(xy 156.127196 -307.299868) (xy 156.4442 -307.299868) (xy 156.44816 -307.250814) (xy 156.459937 -307.20303)
			(xy 156.479228 -307.157754) (xy 156.505531 -307.116158) (xy 156.538166 -307.079321) (xy 156.576287 -307.048196)
			(xy 156.618908 -307.023589) (xy 156.664924 -307.006137) (xy 156.713143 -306.996293) (xy 156.762318 -306.994312)
			(xy 156.811173 -307.000244) (xy 156.858444 -307.013936) (xy 156.902906 -307.035034) (xy 156.943409 -307.06299)
			(xy 156.978902 -307.097082) (xy 157.008467 -307.136426) (xy 157.031338 -307.180003) (xy 157.046922 -307.226684)
			(xy 157.054817 -307.275261) (xy 157.055312 -307.299868) (xy 157.054817 -307.324475) (xy 157.054638 -307.325576)
			(xy 157.373316 -307.325576) (xy 157.373316 -307.27416) (xy 157.381359 -307.223378) (xy 157.397247 -307.174479)
			(xy 157.42059 -307.128667) (xy 157.450811 -307.087071) (xy 157.487167 -307.050715) (xy 157.528763 -307.020494)
			(xy 157.574575 -306.997151) (xy 157.623474 -306.981263) (xy 157.674256 -306.97322) (xy 157.725672 -306.97322)
			(xy 157.776454 -306.981263) (xy 157.825353 -306.997151) (xy 157.871165 -307.020494) (xy 157.912761 -307.050715)
			(xy 157.949117 -307.087071) (xy 157.979338 -307.128667) (xy 158.002681 -307.174479) (xy 158.018569 -307.223378)
			(xy 158.026612 -307.27416) (xy 158.027116 -307.299868) (xy 158.026612 -307.325576) (xy 158.323276 -307.325576)
			(xy 158.323276 -307.27416) (xy 158.331319 -307.223378) (xy 158.347207 -307.174479) (xy 158.37055 -307.128667)
			(xy 158.400771 -307.087071) (xy 158.437127 -307.050715) (xy 158.478723 -307.020494) (xy 158.524535 -306.997151)
			(xy 158.573434 -306.981263) (xy 158.624216 -306.97322) (xy 158.675632 -306.97322) (xy 158.726414 -306.981263)
			(xy 158.775313 -306.997151) (xy 158.821125 -307.020494) (xy 158.862721 -307.050715) (xy 158.899077 -307.087071)
			(xy 158.929298 -307.128667) (xy 158.952641 -307.174479) (xy 158.968529 -307.223378) (xy 158.976572 -307.27416)
			(xy 158.977076 -307.299868) (xy 159.29408 -307.299868) (xy 159.29804 -307.250814) (xy 159.309817 -307.20303)
			(xy 159.329108 -307.157754) (xy 159.355411 -307.116158) (xy 159.388046 -307.079321) (xy 159.426167 -307.048196)
			(xy 159.468788 -307.023589) (xy 159.514804 -307.006137) (xy 159.563023 -306.996293) (xy 159.612198 -306.994312)
			(xy 159.661053 -307.000244) (xy 159.708324 -307.013936) (xy 159.752786 -307.035034) (xy 159.793289 -307.06299)
			(xy 159.828782 -307.097082) (xy 159.858347 -307.136426) (xy 159.881218 -307.180003) (xy 159.896802 -307.226684)
			(xy 159.904697 -307.275261) (xy 159.905192 -307.299868) (xy 160.24404 -307.299868) (xy 160.248 -307.250814)
			(xy 160.259777 -307.20303) (xy 160.279068 -307.157754) (xy 160.305371 -307.116158) (xy 160.338006 -307.079321)
			(xy 160.376127 -307.048196) (xy 160.418748 -307.023589) (xy 160.464764 -307.006137) (xy 160.512983 -306.996293)
			(xy 160.562158 -306.994312) (xy 160.611013 -307.000244) (xy 160.658284 -307.013936) (xy 160.702746 -307.035034)
			(xy 160.743249 -307.06299) (xy 160.778742 -307.097082) (xy 160.808307 -307.136426) (xy 160.831178 -307.180003)
			(xy 160.846762 -307.226684) (xy 160.854657 -307.275261) (xy 160.855152 -307.299868) (xy 161.194254 -307.299868)
			(xy 161.198214 -307.250814) (xy 161.209991 -307.20303) (xy 161.229282 -307.157754) (xy 161.255585 -307.116158)
			(xy 161.28822 -307.079321) (xy 161.326341 -307.048196) (xy 161.368962 -307.023589) (xy 161.414978 -307.006137)
			(xy 161.463197 -306.996293) (xy 161.512372 -306.994312) (xy 161.561227 -307.000244) (xy 161.608498 -307.013936)
			(xy 161.65296 -307.035034) (xy 161.693463 -307.06299) (xy 161.728956 -307.097082) (xy 161.758521 -307.136426)
			(xy 161.781392 -307.180003) (xy 161.796976 -307.226684) (xy 161.804871 -307.275261) (xy 161.805366 -307.299868)
			(xy 161.804871 -307.324475) (xy 161.796976 -307.373052) (xy 161.781392 -307.419733) (xy 161.758521 -307.46331)
			(xy 161.728956 -307.502654) (xy 161.693463 -307.536746) (xy 161.65296 -307.564702) (xy 161.608498 -307.5858)
			(xy 161.561227 -307.599492) (xy 161.512372 -307.605424) (xy 161.463197 -307.603443) (xy 161.414978 -307.593599)
			(xy 161.368962 -307.576147) (xy 161.326341 -307.55154) (xy 161.28822 -307.520415) (xy 161.255585 -307.483578)
			(xy 161.229282 -307.441982) (xy 161.209991 -307.396706) (xy 161.198214 -307.348922) (xy 161.194254 -307.299868)
			(xy 160.855152 -307.299868) (xy 160.854657 -307.324475) (xy 160.846762 -307.373052) (xy 160.831178 -307.419733)
			(xy 160.808307 -307.46331) (xy 160.778742 -307.502654) (xy 160.743249 -307.536746) (xy 160.702746 -307.564702)
			(xy 160.658284 -307.5858) (xy 160.611013 -307.599492) (xy 160.562158 -307.605424) (xy 160.512983 -307.603443)
			(xy 160.464764 -307.593599) (xy 160.418748 -307.576147) (xy 160.376127 -307.55154) (xy 160.338006 -307.520415)
			(xy 160.305371 -307.483578) (xy 160.279068 -307.441982) (xy 160.259777 -307.396706) (xy 160.248 -307.348922)
			(xy 160.24404 -307.299868) (xy 159.905192 -307.299868) (xy 159.904697 -307.324475) (xy 159.896802 -307.373052)
			(xy 159.881218 -307.419733) (xy 159.858347 -307.46331) (xy 159.828782 -307.502654) (xy 159.793289 -307.536746)
			(xy 159.752786 -307.564702) (xy 159.708324 -307.5858) (xy 159.661053 -307.599492) (xy 159.612198 -307.605424)
			(xy 159.563023 -307.603443) (xy 159.514804 -307.593599) (xy 159.468788 -307.576147) (xy 159.426167 -307.55154)
			(xy 159.388046 -307.520415) (xy 159.355411 -307.483578) (xy 159.329108 -307.441982) (xy 159.309817 -307.396706)
			(xy 159.29804 -307.348922) (xy 159.29408 -307.299868) (xy 158.977076 -307.299868) (xy 158.976572 -307.325576)
			(xy 158.968529 -307.376358) (xy 158.952641 -307.425257) (xy 158.929298 -307.471069) (xy 158.899077 -307.512665)
			(xy 158.862721 -307.549021) (xy 158.821125 -307.579242) (xy 158.775313 -307.602585) (xy 158.726414 -307.618473)
			(xy 158.675632 -307.626516) (xy 158.624216 -307.626516) (xy 158.573434 -307.618473) (xy 158.524535 -307.602585)
			(xy 158.478723 -307.579242) (xy 158.437127 -307.549021) (xy 158.400771 -307.512665) (xy 158.37055 -307.471069)
			(xy 158.347207 -307.425257) (xy 158.331319 -307.376358) (xy 158.323276 -307.325576) (xy 158.026612 -307.325576)
			(xy 158.018569 -307.376358) (xy 158.002681 -307.425257) (xy 157.979338 -307.471069) (xy 157.949117 -307.512665)
			(xy 157.912761 -307.549021) (xy 157.871165 -307.579242) (xy 157.825353 -307.602585) (xy 157.776454 -307.618473)
			(xy 157.725672 -307.626516) (xy 157.674256 -307.626516) (xy 157.623474 -307.618473) (xy 157.574575 -307.602585)
			(xy 157.528763 -307.579242) (xy 157.487167 -307.549021) (xy 157.450811 -307.512665) (xy 157.42059 -307.471069)
			(xy 157.397247 -307.425257) (xy 157.381359 -307.376358) (xy 157.373316 -307.325576) (xy 157.054638 -307.325576)
			(xy 157.046922 -307.373052) (xy 157.031338 -307.419733) (xy 157.008467 -307.46331) (xy 156.978902 -307.502654)
			(xy 156.943409 -307.536746) (xy 156.902906 -307.564702) (xy 156.858444 -307.5858) (xy 156.811173 -307.599492)
			(xy 156.762318 -307.605424) (xy 156.713143 -307.603443) (xy 156.664924 -307.593599) (xy 156.618908 -307.576147)
			(xy 156.576287 -307.55154) (xy 156.538166 -307.520415) (xy 156.505531 -307.483578) (xy 156.479228 -307.441982)
			(xy 156.459937 -307.396706) (xy 156.44816 -307.348922) (xy 156.4442 -307.299868) (xy 156.127196 -307.299868)
			(xy 156.126692 -307.325576) (xy 156.118649 -307.376358) (xy 156.102761 -307.425257) (xy 156.079418 -307.471069)
			(xy 156.049197 -307.512665) (xy 156.012841 -307.549021) (xy 155.971245 -307.579242) (xy 155.925433 -307.602585)
			(xy 155.876534 -307.618473) (xy 155.825752 -307.626516) (xy 155.774336 -307.626516) (xy 155.723554 -307.618473)
			(xy 155.674655 -307.602585) (xy 155.628843 -307.579242) (xy 155.587247 -307.549021) (xy 155.550891 -307.512665)
			(xy 155.52067 -307.471069) (xy 155.497327 -307.425257) (xy 155.481439 -307.376358) (xy 155.473396 -307.325576)
			(xy 155.176732 -307.325576) (xy 155.168689 -307.376358) (xy 155.152801 -307.425257) (xy 155.129458 -307.471069)
			(xy 155.099237 -307.512665) (xy 155.062881 -307.549021) (xy 155.021285 -307.579242) (xy 154.975473 -307.602585)
			(xy 154.926574 -307.618473) (xy 154.875792 -307.626516) (xy 154.824376 -307.626516) (xy 154.773594 -307.618473)
			(xy 154.724695 -307.602585) (xy 154.678883 -307.579242) (xy 154.637287 -307.549021) (xy 154.600931 -307.512665)
			(xy 154.57071 -307.471069) (xy 154.547367 -307.425257) (xy 154.531479 -307.376358) (xy 154.523436 -307.325576)
			(xy 154.204504 -307.325576) (xy 154.196788 -307.373052) (xy 154.181204 -307.419733) (xy 154.158333 -307.46331)
			(xy 154.128768 -307.502654) (xy 154.093275 -307.536746) (xy 154.052772 -307.564702) (xy 154.00831 -307.5858)
			(xy 153.961039 -307.599492) (xy 153.912184 -307.605424) (xy 153.863009 -307.603443) (xy 153.81479 -307.593599)
			(xy 153.768774 -307.576147) (xy 153.726153 -307.55154) (xy 153.688032 -307.520415) (xy 153.655397 -307.483578)
			(xy 153.629094 -307.441982) (xy 153.609803 -307.396706) (xy 153.598026 -307.348922) (xy 153.594066 -307.299868)
			(xy 153.255218 -307.299868) (xy 153.254723 -307.324475) (xy 153.246828 -307.373052) (xy 153.231244 -307.419733)
			(xy 153.208373 -307.46331) (xy 153.178808 -307.502654) (xy 153.143315 -307.536746) (xy 153.102812 -307.564702)
			(xy 153.05835 -307.5858) (xy 153.011079 -307.599492) (xy 152.962224 -307.605424) (xy 152.913049 -307.603443)
			(xy 152.86483 -307.593599) (xy 152.818814 -307.576147) (xy 152.776193 -307.55154) (xy 152.738072 -307.520415)
			(xy 152.705437 -307.483578) (xy 152.679134 -307.441982) (xy 152.659843 -307.396706) (xy 152.648066 -307.348922)
			(xy 152.644106 -307.299868) (xy 148.718415 -307.299868) (xy 148.714975 -307.32324) (xy 148.698907 -307.376647)
			(xy 148.675235 -307.427144) (xy 148.644462 -307.473657) (xy 148.607245 -307.515194) (xy 148.564377 -307.550869)
			(xy 148.516771 -307.579923) (xy 148.465442 -307.601735) (xy 148.411485 -307.615841) (xy 148.356048 -307.621941)
			(xy 148.300314 -307.619904) (xy 148.245471 -307.609774) (xy 148.192687 -307.591767) (xy 148.143087 -307.566266)
			(xy 148.097729 -307.533815) (xy 148.05758 -307.495106) (xy 148.023494 -307.450963) (xy 147.996198 -307.402328)
			(xy 147.976275 -307.350237) (xy 147.964149 -307.2958) (xy 147.960078 -307.240178) (xy 132.651827 -307.240178)
			(xy 132.651826 -307.270085) (xy 132.643996 -307.324265) (xy 132.628498 -307.376768) (xy 132.60565 -307.426515)
			(xy 132.575924 -307.472483) (xy 132.558282 -307.493416) (xy 132.558028 -307.49367) (xy 132.552439 -307.500755)
			(xy 132.546196 -307.517673) (xy 132.545836 -307.52669) (xy 132.545836 -307.593746) (xy 132.546211 -307.602761)
			(xy 132.552445 -307.619679) (xy 132.558028 -307.626766) (xy 132.558282 -307.626766) (xy 132.558282 -307.62702)
			(xy 132.575894 -307.647974) (xy 132.605611 -307.69394) (xy 132.628452 -307.743682) (xy 132.637652 -307.774848)
			(xy 162.619194 -307.774848) (xy 162.623154 -307.725794) (xy 162.634931 -307.67801) (xy 162.654222 -307.632734)
			(xy 162.680525 -307.591138) (xy 162.71316 -307.554301) (xy 162.751281 -307.523176) (xy 162.793902 -307.498569)
			(xy 162.839918 -307.481117) (xy 162.888137 -307.471273) (xy 162.937312 -307.469292) (xy 162.986167 -307.475224)
			(xy 163.033438 -307.488916) (xy 163.0779 -307.510014) (xy 163.118403 -307.53797) (xy 163.153896 -307.572062)
			(xy 163.183461 -307.611406) (xy 163.206332 -307.654983) (xy 163.221916 -307.701664) (xy 163.229811 -307.750241)
			(xy 163.230306 -307.774848) (xy 163.569154 -307.774848) (xy 163.573114 -307.725794) (xy 163.584891 -307.67801)
			(xy 163.604182 -307.632734) (xy 163.630485 -307.591138) (xy 163.66312 -307.554301) (xy 163.701241 -307.523176)
			(xy 163.743862 -307.498569) (xy 163.789878 -307.481117) (xy 163.838097 -307.471273) (xy 163.887272 -307.469292)
			(xy 163.936127 -307.475224) (xy 163.983398 -307.488916) (xy 164.02786 -307.510014) (xy 164.068363 -307.53797)
			(xy 164.103856 -307.572062) (xy 164.133421 -307.611406) (xy 164.156292 -307.654983) (xy 164.171876 -307.701664)
			(xy 164.179771 -307.750241) (xy 164.180266 -307.774848) (xy 164.519114 -307.774848) (xy 164.523074 -307.725794)
			(xy 164.534851 -307.67801) (xy 164.554142 -307.632734) (xy 164.580445 -307.591138) (xy 164.61308 -307.554301)
			(xy 164.651201 -307.523176) (xy 164.693822 -307.498569) (xy 164.739838 -307.481117) (xy 164.788057 -307.471273)
			(xy 164.837232 -307.469292) (xy 164.886087 -307.475224) (xy 164.933358 -307.488916) (xy 164.97782 -307.510014)
			(xy 165.018323 -307.53797) (xy 165.053816 -307.572062) (xy 165.083381 -307.611406) (xy 165.106252 -307.654983)
			(xy 165.121836 -307.701664) (xy 165.129731 -307.750241) (xy 165.130226 -307.774848) (xy 165.129731 -307.799455)
			(xy 165.121836 -307.848032) (xy 165.106252 -307.894713) (xy 165.083381 -307.93829) (xy 165.053816 -307.977634)
			(xy 165.018323 -308.011726) (xy 164.97782 -308.039682) (xy 164.933358 -308.06078) (xy 164.886087 -308.074472)
			(xy 164.837232 -308.080404) (xy 164.788057 -308.078423) (xy 164.739838 -308.068579) (xy 164.693822 -308.051127)
			(xy 164.651201 -308.02652) (xy 164.61308 -307.995395) (xy 164.580445 -307.958558) (xy 164.554142 -307.916962)
			(xy 164.534851 -307.871686) (xy 164.523074 -307.823902) (xy 164.519114 -307.774848) (xy 164.180266 -307.774848)
			(xy 164.179771 -307.799455) (xy 164.171876 -307.848032) (xy 164.156292 -307.894713) (xy 164.133421 -307.93829)
			(xy 164.103856 -307.977634) (xy 164.068363 -308.011726) (xy 164.02786 -308.039682) (xy 163.983398 -308.06078)
			(xy 163.936127 -308.074472) (xy 163.887272 -308.080404) (xy 163.838097 -308.078423) (xy 163.789878 -308.068579)
			(xy 163.743862 -308.051127) (xy 163.701241 -308.02652) (xy 163.66312 -307.995395) (xy 163.630485 -307.958558)
			(xy 163.604182 -307.916962) (xy 163.584891 -307.871686) (xy 163.573114 -307.823902) (xy 163.569154 -307.774848)
			(xy 163.230306 -307.774848) (xy 163.229811 -307.799455) (xy 163.221916 -307.848032) (xy 163.206332 -307.894713)
			(xy 163.183461 -307.93829) (xy 163.153896 -307.977634) (xy 163.118403 -308.011726) (xy 163.0779 -308.039682)
			(xy 163.033438 -308.06078) (xy 162.986167 -308.074472) (xy 162.937312 -308.080404) (xy 162.888137 -308.078423)
			(xy 162.839918 -308.068579) (xy 162.793902 -308.051127) (xy 162.751281 -308.02652) (xy 162.71316 -307.995395)
			(xy 162.680525 -307.958558) (xy 162.654222 -307.916962) (xy 162.634931 -307.871686) (xy 162.623154 -307.823902)
			(xy 162.619194 -307.774848) (xy 132.637652 -307.774848) (xy 132.643949 -307.796178) (xy 132.651784 -307.85035)
			(xy 132.652262 -307.877718) (xy 132.651776 -307.904969) (xy 132.64402 -307.958917) (xy 132.628665 -308.011212)
			(xy 132.606023 -308.060789) (xy 132.576557 -308.106639) (xy 132.540866 -308.14783) (xy 132.499675 -308.183521)
			(xy 132.453825 -308.212987) (xy 132.404248 -308.235629) (xy 132.351953 -308.250984) (xy 132.298005 -308.25874)
			(xy 132.243503 -308.25874) (xy 132.189555 -308.250984) (xy 132.13726 -308.235629) (xy 132.087683 -308.212987)
			(xy 132.041833 -308.183521) (xy 132.000642 -308.14783) (xy 131.964951 -308.106639) (xy 131.935485 -308.060789)
			(xy 131.912843 -308.011212) (xy 131.897488 -307.958917) (xy 131.889732 -307.904969) (xy 131.889246 -307.877718)
			(xy 129.015752 -307.877718) (xy 129.01182 -307.905069) (xy 128.996465 -307.957364) (xy 128.973823 -308.006941)
			(xy 128.944357 -308.052791) (xy 128.908666 -308.093982) (xy 128.867475 -308.129673) (xy 128.821625 -308.159139)
			(xy 128.772048 -308.181781) (xy 128.719753 -308.197136) (xy 128.665805 -308.204892) (xy 128.611303 -308.204892)
			(xy 128.557355 -308.197136) (xy 128.50506 -308.181781) (xy 128.455483 -308.159139) (xy 128.409633 -308.129673)
			(xy 128.368442 -308.093982) (xy 128.332751 -308.052791) (xy 128.303285 -308.006941) (xy 128.280643 -307.957364)
			(xy 128.265288 -307.905069) (xy 128.257532 -307.851121) (xy 128.257046 -307.82387) (xy 125.807734 -307.82387)
			(xy 125.811564 -307.85035) (xy 125.812042 -307.877718) (xy 125.811556 -307.904969) (xy 125.8038 -307.958917)
			(xy 125.788445 -308.011212) (xy 125.765803 -308.060789) (xy 125.736337 -308.106639) (xy 125.700646 -308.14783)
			(xy 125.659455 -308.183521) (xy 125.613605 -308.212987) (xy 125.564028 -308.235629) (xy 125.511733 -308.250984)
			(xy 125.457785 -308.25874) (xy 125.403283 -308.25874) (xy 125.349335 -308.250984) (xy 125.29704 -308.235629)
			(xy 125.247463 -308.212987) (xy 125.201613 -308.183521) (xy 125.160422 -308.14783) (xy 125.124731 -308.106639)
			(xy 125.095265 -308.060789) (xy 125.072623 -308.011212) (xy 125.057268 -307.958917) (xy 125.049512 -307.904969)
			(xy 125.049026 -307.877718) (xy 122.175532 -307.877718) (xy 122.1716 -307.905069) (xy 122.156245 -307.957364)
			(xy 122.133603 -308.006941) (xy 122.104137 -308.052791) (xy 122.068446 -308.093982) (xy 122.027255 -308.129673)
			(xy 121.981405 -308.159139) (xy 121.931828 -308.181781) (xy 121.879533 -308.197136) (xy 121.825585 -308.204892)
			(xy 121.771083 -308.204892) (xy 121.717135 -308.197136) (xy 121.66484 -308.181781) (xy 121.615263 -308.159139)
			(xy 121.569413 -308.129673) (xy 121.528222 -308.093982) (xy 121.492531 -308.052791) (xy 121.463065 -308.006941)
			(xy 121.440423 -307.957364) (xy 121.425068 -307.905069) (xy 121.417312 -307.851121) (xy 121.416826 -307.82387)
			(xy 118.830852 -307.82387) (xy 118.830852 -308.450488) (xy 144.178272 -308.450488) (xy 144.182343 -308.394866)
			(xy 144.194469 -308.340429) (xy 144.214392 -308.288338) (xy 144.241688 -308.239703) (xy 144.275774 -308.19556)
			(xy 144.315923 -308.156851) (xy 144.361281 -308.1244) (xy 144.410881 -308.098899) (xy 144.463665 -308.080892)
			(xy 144.518508 -308.070762) (xy 144.574242 -308.068725) (xy 144.629679 -308.074825) (xy 144.683636 -308.088931)
			(xy 144.734965 -308.110743) (xy 144.782571 -308.139797) (xy 144.825439 -308.175472) (xy 144.862656 -308.217009)
			(xy 144.884537 -308.250082) (xy 151.693892 -308.250082) (xy 151.697852 -308.201028) (xy 151.709629 -308.153244)
			(xy 151.72892 -308.107968) (xy 151.755223 -308.066372) (xy 151.787858 -308.029535) (xy 151.825979 -307.99841)
			(xy 151.8686 -307.973803) (xy 151.914616 -307.956351) (xy 151.962835 -307.946507) (xy 152.01201 -307.944526)
			(xy 152.060865 -307.950458) (xy 152.108136 -307.96415) (xy 152.152598 -307.985248) (xy 152.193101 -308.013204)
			(xy 152.228594 -308.047296) (xy 152.258159 -308.08664) (xy 152.28103 -308.130217) (xy 152.296614 -308.176898)
			(xy 152.304509 -308.225475) (xy 152.305004 -308.250082) (xy 152.304509 -308.274689) (xy 152.304371 -308.275536)
			(xy 152.623262 -308.275536) (xy 152.623262 -308.22412) (xy 152.631305 -308.173338) (xy 152.647193 -308.124439)
			(xy 152.670536 -308.078627) (xy 152.700757 -308.037031) (xy 152.737113 -308.000675) (xy 152.778709 -307.970454)
			(xy 152.824521 -307.947111) (xy 152.87342 -307.931223) (xy 152.924202 -307.92318) (xy 152.975618 -307.92318)
			(xy 153.0264 -307.931223) (xy 153.075299 -307.947111) (xy 153.121111 -307.970454) (xy 153.162707 -308.000675)
			(xy 153.199063 -308.037031) (xy 153.229284 -308.078627) (xy 153.252627 -308.124439) (xy 153.268515 -308.173338)
			(xy 153.276558 -308.22412) (xy 153.277062 -308.249828) (xy 153.276558 -308.275536) (xy 153.573222 -308.275536)
			(xy 153.573222 -308.22412) (xy 153.581265 -308.173338) (xy 153.597153 -308.124439) (xy 153.620496 -308.078627)
			(xy 153.650717 -308.037031) (xy 153.687073 -308.000675) (xy 153.728669 -307.970454) (xy 153.774481 -307.947111)
			(xy 153.82338 -307.931223) (xy 153.874162 -307.92318) (xy 153.925578 -307.92318) (xy 153.97636 -307.931223)
			(xy 154.025259 -307.947111) (xy 154.071071 -307.970454) (xy 154.112667 -308.000675) (xy 154.149023 -308.037031)
			(xy 154.179244 -308.078627) (xy 154.202587 -308.124439) (xy 154.218475 -308.173338) (xy 154.226518 -308.22412)
			(xy 154.227022 -308.249828) (xy 154.54428 -308.249828) (xy 154.54824 -308.200774) (xy 154.560017 -308.15299)
			(xy 154.579308 -308.107714) (xy 154.605611 -308.066118) (xy 154.638246 -308.029281) (xy 154.676367 -307.998156)
			(xy 154.718988 -307.973549) (xy 154.765004 -307.956097) (xy 154.813223 -307.946253) (xy 154.862398 -307.944272)
			(xy 154.911253 -307.950204) (xy 154.958524 -307.963896) (xy 155.002986 -307.984994) (xy 155.043489 -308.01295)
			(xy 155.078982 -308.047042) (xy 155.108547 -308.086386) (xy 155.131418 -308.129963) (xy 155.147002 -308.176644)
			(xy 155.154897 -308.225221) (xy 155.155392 -308.249828) (xy 155.49424 -308.249828) (xy 155.4982 -308.200774)
			(xy 155.509977 -308.15299) (xy 155.529268 -308.107714) (xy 155.555571 -308.066118) (xy 155.588206 -308.029281)
			(xy 155.626327 -307.998156) (xy 155.668948 -307.973549) (xy 155.714964 -307.956097) (xy 155.763183 -307.946253)
			(xy 155.812358 -307.944272) (xy 155.861213 -307.950204) (xy 155.908484 -307.963896) (xy 155.952946 -307.984994)
			(xy 155.993449 -308.01295) (xy 156.028942 -308.047042) (xy 156.058507 -308.086386) (xy 156.081378 -308.129963)
			(xy 156.096962 -308.176644) (xy 156.104857 -308.225221) (xy 156.105352 -308.249828) (xy 156.4442 -308.249828)
			(xy 156.44816 -308.200774) (xy 156.459937 -308.15299) (xy 156.479228 -308.107714) (xy 156.505531 -308.066118)
			(xy 156.538166 -308.029281) (xy 156.576287 -307.998156) (xy 156.618908 -307.973549) (xy 156.664924 -307.956097)
			(xy 156.713143 -307.946253) (xy 156.762318 -307.944272) (xy 156.811173 -307.950204) (xy 156.858444 -307.963896)
			(xy 156.902906 -307.984994) (xy 156.943409 -308.01295) (xy 156.978902 -308.047042) (xy 157.008467 -308.086386)
			(xy 157.031338 -308.129963) (xy 157.046922 -308.176644) (xy 157.054817 -308.225221) (xy 157.055312 -308.249828)
			(xy 157.39416 -308.249828) (xy 157.39812 -308.200774) (xy 157.409897 -308.15299) (xy 157.429188 -308.107714)
			(xy 157.455491 -308.066118) (xy 157.488126 -308.029281) (xy 157.526247 -307.998156) (xy 157.568868 -307.973549)
			(xy 157.614884 -307.956097) (xy 157.663103 -307.946253) (xy 157.712278 -307.944272) (xy 157.761133 -307.950204)
			(xy 157.808404 -307.963896) (xy 157.852866 -307.984994) (xy 157.893369 -308.01295) (xy 157.928862 -308.047042)
			(xy 157.958427 -308.086386) (xy 157.981298 -308.129963) (xy 157.996882 -308.176644) (xy 158.004777 -308.225221)
			(xy 158.005272 -308.249828) (xy 158.34412 -308.249828) (xy 158.34808 -308.200774) (xy 158.359857 -308.15299)
			(xy 158.379148 -308.107714) (xy 158.405451 -308.066118) (xy 158.438086 -308.029281) (xy 158.476207 -307.998156)
			(xy 158.518828 -307.973549) (xy 158.564844 -307.956097) (xy 158.613063 -307.946253) (xy 158.662238 -307.944272)
			(xy 158.711093 -307.950204) (xy 158.758364 -307.963896) (xy 158.802826 -307.984994) (xy 158.843329 -308.01295)
			(xy 158.878822 -308.047042) (xy 158.908387 -308.086386) (xy 158.931258 -308.129963) (xy 158.946842 -308.176644)
			(xy 158.954737 -308.225221) (xy 158.955232 -308.249828) (xy 158.954737 -308.274435) (xy 158.954558 -308.275536)
			(xy 159.273236 -308.275536) (xy 159.273236 -308.22412) (xy 159.281279 -308.173338) (xy 159.297167 -308.124439)
			(xy 159.32051 -308.078627) (xy 159.350731 -308.037031) (xy 159.387087 -308.000675) (xy 159.428683 -307.970454)
			(xy 159.474495 -307.947111) (xy 159.523394 -307.931223) (xy 159.574176 -307.92318) (xy 159.625592 -307.92318)
			(xy 159.676374 -307.931223) (xy 159.725273 -307.947111) (xy 159.771085 -307.970454) (xy 159.812681 -308.000675)
			(xy 159.849037 -308.037031) (xy 159.879258 -308.078627) (xy 159.902601 -308.124439) (xy 159.918489 -308.173338)
			(xy 159.926532 -308.22412) (xy 159.927036 -308.249828) (xy 159.926532 -308.275536) (xy 160.223196 -308.275536)
			(xy 160.223196 -308.22412) (xy 160.231239 -308.173338) (xy 160.247127 -308.124439) (xy 160.27047 -308.078627)
			(xy 160.300691 -308.037031) (xy 160.337047 -308.000675) (xy 160.378643 -307.970454) (xy 160.424455 -307.947111)
			(xy 160.473354 -307.931223) (xy 160.524136 -307.92318) (xy 160.575552 -307.92318) (xy 160.626334 -307.931223)
			(xy 160.675233 -307.947111) (xy 160.721045 -307.970454) (xy 160.762641 -308.000675) (xy 160.798997 -308.037031)
			(xy 160.829218 -308.078627) (xy 160.852561 -308.124439) (xy 160.868449 -308.173338) (xy 160.876492 -308.22412)
			(xy 160.876996 -308.249828) (xy 161.194254 -308.249828) (xy 161.198214 -308.200774) (xy 161.209991 -308.15299)
			(xy 161.229282 -308.107714) (xy 161.255585 -308.066118) (xy 161.28822 -308.029281) (xy 161.326341 -307.998156)
			(xy 161.368962 -307.973549) (xy 161.414978 -307.956097) (xy 161.463197 -307.946253) (xy 161.512372 -307.944272)
			(xy 161.561227 -307.950204) (xy 161.608498 -307.963896) (xy 161.65296 -307.984994) (xy 161.693463 -308.01295)
			(xy 161.728956 -308.047042) (xy 161.758521 -308.086386) (xy 161.781392 -308.129963) (xy 161.796976 -308.176644)
			(xy 161.804871 -308.225221) (xy 161.805366 -308.249828) (xy 161.804871 -308.274435) (xy 161.796976 -308.323012)
			(xy 161.781392 -308.369693) (xy 161.758521 -308.41327) (xy 161.728956 -308.452614) (xy 161.693463 -308.486706)
			(xy 161.65296 -308.514662) (xy 161.608498 -308.53576) (xy 161.561227 -308.549452) (xy 161.512372 -308.555384)
			(xy 161.463197 -308.553403) (xy 161.414978 -308.543559) (xy 161.368962 -308.526107) (xy 161.326341 -308.5015)
			(xy 161.28822 -308.470375) (xy 161.255585 -308.433538) (xy 161.229282 -308.391942) (xy 161.209991 -308.346666)
			(xy 161.198214 -308.298882) (xy 161.194254 -308.249828) (xy 160.876996 -308.249828) (xy 160.876492 -308.275536)
			(xy 160.868449 -308.326318) (xy 160.852561 -308.375217) (xy 160.829218 -308.421029) (xy 160.798997 -308.462625)
			(xy 160.762641 -308.498981) (xy 160.721045 -308.529202) (xy 160.675233 -308.552545) (xy 160.626334 -308.568433)
			(xy 160.575552 -308.576476) (xy 160.524136 -308.576476) (xy 160.473354 -308.568433) (xy 160.424455 -308.552545)
			(xy 160.378643 -308.529202) (xy 160.337047 -308.498981) (xy 160.300691 -308.462625) (xy 160.27047 -308.421029)
			(xy 160.247127 -308.375217) (xy 160.231239 -308.326318) (xy 160.223196 -308.275536) (xy 159.926532 -308.275536)
			(xy 159.918489 -308.326318) (xy 159.902601 -308.375217) (xy 159.879258 -308.421029) (xy 159.849037 -308.462625)
			(xy 159.812681 -308.498981) (xy 159.771085 -308.529202) (xy 159.725273 -308.552545) (xy 159.676374 -308.568433)
			(xy 159.625592 -308.576476) (xy 159.574176 -308.576476) (xy 159.523394 -308.568433) (xy 159.474495 -308.552545)
			(xy 159.428683 -308.529202) (xy 159.387087 -308.498981) (xy 159.350731 -308.462625) (xy 159.32051 -308.421029)
			(xy 159.297167 -308.375217) (xy 159.281279 -308.326318) (xy 159.273236 -308.275536) (xy 158.954558 -308.275536)
			(xy 158.946842 -308.323012) (xy 158.931258 -308.369693) (xy 158.908387 -308.41327) (xy 158.878822 -308.452614)
			(xy 158.843329 -308.486706) (xy 158.802826 -308.514662) (xy 158.758364 -308.53576) (xy 158.711093 -308.549452)
			(xy 158.662238 -308.555384) (xy 158.613063 -308.553403) (xy 158.564844 -308.543559) (xy 158.518828 -308.526107)
			(xy 158.476207 -308.5015) (xy 158.438086 -308.470375) (xy 158.405451 -308.433538) (xy 158.379148 -308.391942)
			(xy 158.359857 -308.346666) (xy 158.34808 -308.298882) (xy 158.34412 -308.249828) (xy 158.005272 -308.249828)
			(xy 158.004777 -308.274435) (xy 157.996882 -308.323012) (xy 157.981298 -308.369693) (xy 157.958427 -308.41327)
			(xy 157.928862 -308.452614) (xy 157.893369 -308.486706) (xy 157.852866 -308.514662) (xy 157.808404 -308.53576)
			(xy 157.761133 -308.549452) (xy 157.712278 -308.555384) (xy 157.663103 -308.553403) (xy 157.614884 -308.543559)
			(xy 157.568868 -308.526107) (xy 157.526247 -308.5015) (xy 157.488126 -308.470375) (xy 157.455491 -308.433538)
			(xy 157.429188 -308.391942) (xy 157.409897 -308.346666) (xy 157.39812 -308.298882) (xy 157.39416 -308.249828)
			(xy 157.055312 -308.249828) (xy 157.054817 -308.274435) (xy 157.046922 -308.323012) (xy 157.031338 -308.369693)
			(xy 157.008467 -308.41327) (xy 156.978902 -308.452614) (xy 156.943409 -308.486706) (xy 156.902906 -308.514662)
			(xy 156.858444 -308.53576) (xy 156.811173 -308.549452) (xy 156.762318 -308.555384) (xy 156.713143 -308.553403)
			(xy 156.664924 -308.543559) (xy 156.618908 -308.526107) (xy 156.576287 -308.5015) (xy 156.538166 -308.470375)
			(xy 156.505531 -308.433538) (xy 156.479228 -308.391942) (xy 156.459937 -308.346666) (xy 156.44816 -308.298882)
			(xy 156.4442 -308.249828) (xy 156.105352 -308.249828) (xy 156.104857 -308.274435) (xy 156.096962 -308.323012)
			(xy 156.081378 -308.369693) (xy 156.058507 -308.41327) (xy 156.028942 -308.452614) (xy 155.993449 -308.486706)
			(xy 155.952946 -308.514662) (xy 155.908484 -308.53576) (xy 155.861213 -308.549452) (xy 155.812358 -308.555384)
			(xy 155.763183 -308.553403) (xy 155.714964 -308.543559) (xy 155.668948 -308.526107) (xy 155.626327 -308.5015)
			(xy 155.588206 -308.470375) (xy 155.555571 -308.433538) (xy 155.529268 -308.391942) (xy 155.509977 -308.346666)
			(xy 155.4982 -308.298882) (xy 155.49424 -308.249828) (xy 155.155392 -308.249828) (xy 155.154897 -308.274435)
			(xy 155.147002 -308.323012) (xy 155.131418 -308.369693) (xy 155.108547 -308.41327) (xy 155.078982 -308.452614)
			(xy 155.043489 -308.486706) (xy 155.002986 -308.514662) (xy 154.958524 -308.53576) (xy 154.911253 -308.549452)
			(xy 154.862398 -308.555384) (xy 154.813223 -308.553403) (xy 154.765004 -308.543559) (xy 154.718988 -308.526107)
			(xy 154.676367 -308.5015) (xy 154.638246 -308.470375) (xy 154.605611 -308.433538) (xy 154.579308 -308.391942)
			(xy 154.560017 -308.346666) (xy 154.54824 -308.298882) (xy 154.54428 -308.249828) (xy 154.227022 -308.249828)
			(xy 154.226518 -308.275536) (xy 154.218475 -308.326318) (xy 154.202587 -308.375217) (xy 154.179244 -308.421029)
			(xy 154.149023 -308.462625) (xy 154.112667 -308.498981) (xy 154.071071 -308.529202) (xy 154.025259 -308.552545)
			(xy 153.97636 -308.568433) (xy 153.925578 -308.576476) (xy 153.874162 -308.576476) (xy 153.82338 -308.568433)
			(xy 153.774481 -308.552545) (xy 153.728669 -308.529202) (xy 153.687073 -308.498981) (xy 153.650717 -308.462625)
			(xy 153.620496 -308.421029) (xy 153.597153 -308.375217) (xy 153.581265 -308.326318) (xy 153.573222 -308.275536)
			(xy 153.276558 -308.275536) (xy 153.268515 -308.326318) (xy 153.252627 -308.375217) (xy 153.229284 -308.421029)
			(xy 153.199063 -308.462625) (xy 153.162707 -308.498981) (xy 153.121111 -308.529202) (xy 153.075299 -308.552545)
			(xy 153.0264 -308.568433) (xy 152.975618 -308.576476) (xy 152.924202 -308.576476) (xy 152.87342 -308.568433)
			(xy 152.824521 -308.552545) (xy 152.778709 -308.529202) (xy 152.737113 -308.498981) (xy 152.700757 -308.462625)
			(xy 152.670536 -308.421029) (xy 152.647193 -308.375217) (xy 152.631305 -308.326318) (xy 152.623262 -308.275536)
			(xy 152.304371 -308.275536) (xy 152.296614 -308.323266) (xy 152.28103 -308.369947) (xy 152.258159 -308.413524)
			(xy 152.228594 -308.452868) (xy 152.193101 -308.48696) (xy 152.152598 -308.514916) (xy 152.108136 -308.536014)
			(xy 152.060865 -308.549706) (xy 152.01201 -308.555638) (xy 151.962835 -308.553657) (xy 151.914616 -308.543813)
			(xy 151.8686 -308.526361) (xy 151.825979 -308.501754) (xy 151.787858 -308.470629) (xy 151.755223 -308.433792)
			(xy 151.72892 -308.392196) (xy 151.709629 -308.34692) (xy 151.697852 -308.299136) (xy 151.693892 -308.250082)
			(xy 144.884537 -308.250082) (xy 144.893429 -308.263522) (xy 144.917101 -308.314019) (xy 144.933169 -308.367426)
			(xy 144.941289 -308.422602) (xy 144.941798 -308.450488) (xy 144.941289 -308.478374) (xy 144.933169 -308.53355)
			(xy 144.917101 -308.586957) (xy 144.893429 -308.637454) (xy 144.878824 -308.65953) (xy 146.505674 -308.65953)
			(xy 146.509745 -308.603908) (xy 146.521871 -308.549471) (xy 146.541794 -308.49738) (xy 146.56909 -308.448745)
			(xy 146.603176 -308.404602) (xy 146.643325 -308.365893) (xy 146.688683 -308.333442) (xy 146.738283 -308.307941)
			(xy 146.791067 -308.289934) (xy 146.84591 -308.279804) (xy 146.901644 -308.277767) (xy 146.957081 -308.283867)
			(xy 147.011038 -308.297973) (xy 147.062367 -308.319785) (xy 147.109973 -308.348839) (xy 147.152841 -308.384514)
			(xy 147.190058 -308.426051) (xy 147.220831 -308.472564) (xy 147.244503 -308.523061) (xy 147.260571 -308.576468)
			(xy 147.268691 -308.631644) (xy 147.2692 -308.65953) (xy 147.268691 -308.687416) (xy 147.263188 -308.724808)
			(xy 162.619194 -308.724808) (xy 162.623154 -308.675754) (xy 162.634931 -308.62797) (xy 162.654222 -308.582694)
			(xy 162.680525 -308.541098) (xy 162.71316 -308.504261) (xy 162.751281 -308.473136) (xy 162.793902 -308.448529)
			(xy 162.839918 -308.431077) (xy 162.888137 -308.421233) (xy 162.937312 -308.419252) (xy 162.986167 -308.425184)
			(xy 163.033438 -308.438876) (xy 163.0779 -308.459974) (xy 163.118403 -308.48793) (xy 163.153896 -308.522022)
			(xy 163.183461 -308.561366) (xy 163.206332 -308.604943) (xy 163.221916 -308.651624) (xy 163.229811 -308.700201)
			(xy 163.230306 -308.724808) (xy 163.569154 -308.724808) (xy 163.573114 -308.675754) (xy 163.584891 -308.62797)
			(xy 163.604182 -308.582694) (xy 163.630485 -308.541098) (xy 163.66312 -308.504261) (xy 163.701241 -308.473136)
			(xy 163.743862 -308.448529) (xy 163.789878 -308.431077) (xy 163.838097 -308.421233) (xy 163.887272 -308.419252)
			(xy 163.936127 -308.425184) (xy 163.983398 -308.438876) (xy 164.02786 -308.459974) (xy 164.068363 -308.48793)
			(xy 164.103856 -308.522022) (xy 164.133421 -308.561366) (xy 164.156292 -308.604943) (xy 164.171876 -308.651624)
			(xy 164.179771 -308.700201) (xy 164.180266 -308.724808) (xy 164.519114 -308.724808) (xy 164.523074 -308.675754)
			(xy 164.534851 -308.62797) (xy 164.554142 -308.582694) (xy 164.580445 -308.541098) (xy 164.61308 -308.504261)
			(xy 164.651201 -308.473136) (xy 164.693822 -308.448529) (xy 164.739838 -308.431077) (xy 164.788057 -308.421233)
			(xy 164.837232 -308.419252) (xy 164.886087 -308.425184) (xy 164.933358 -308.438876) (xy 164.97782 -308.459974)
			(xy 165.018323 -308.48793) (xy 165.053816 -308.522022) (xy 165.083381 -308.561366) (xy 165.106252 -308.604943)
			(xy 165.121836 -308.651624) (xy 165.129731 -308.700201) (xy 165.130226 -308.724808) (xy 165.129731 -308.749415)
			(xy 165.121836 -308.797992) (xy 165.106252 -308.844673) (xy 165.083381 -308.88825) (xy 165.053816 -308.927594)
			(xy 165.018323 -308.961686) (xy 164.97782 -308.989642) (xy 164.933358 -309.01074) (xy 164.886087 -309.024432)
			(xy 164.837232 -309.030364) (xy 164.788057 -309.028383) (xy 164.739838 -309.018539) (xy 164.693822 -309.001087)
			(xy 164.651201 -308.97648) (xy 164.61308 -308.945355) (xy 164.580445 -308.908518) (xy 164.554142 -308.866922)
			(xy 164.534851 -308.821646) (xy 164.523074 -308.773862) (xy 164.519114 -308.724808) (xy 164.180266 -308.724808)
			(xy 164.179771 -308.749415) (xy 164.171876 -308.797992) (xy 164.156292 -308.844673) (xy 164.133421 -308.88825)
			(xy 164.103856 -308.927594) (xy 164.068363 -308.961686) (xy 164.02786 -308.989642) (xy 163.983398 -309.01074)
			(xy 163.936127 -309.024432) (xy 163.887272 -309.030364) (xy 163.838097 -309.028383) (xy 163.789878 -309.018539)
			(xy 163.743862 -309.001087) (xy 163.701241 -308.97648) (xy 163.66312 -308.945355) (xy 163.630485 -308.908518)
			(xy 163.604182 -308.866922) (xy 163.584891 -308.821646) (xy 163.573114 -308.773862) (xy 163.569154 -308.724808)
			(xy 163.230306 -308.724808) (xy 163.229811 -308.749415) (xy 163.221916 -308.797992) (xy 163.206332 -308.844673)
			(xy 163.183461 -308.88825) (xy 163.153896 -308.927594) (xy 163.118403 -308.961686) (xy 163.0779 -308.989642)
			(xy 163.033438 -309.01074) (xy 162.986167 -309.024432) (xy 162.937312 -309.030364) (xy 162.888137 -309.028383)
			(xy 162.839918 -309.018539) (xy 162.793902 -309.001087) (xy 162.751281 -308.97648) (xy 162.71316 -308.945355)
			(xy 162.680525 -308.908518) (xy 162.654222 -308.866922) (xy 162.634931 -308.821646) (xy 162.623154 -308.773862)
			(xy 162.619194 -308.724808) (xy 147.263188 -308.724808) (xy 147.260571 -308.742592) (xy 147.244503 -308.795999)
			(xy 147.220831 -308.846496) (xy 147.190058 -308.893009) (xy 147.152841 -308.934546) (xy 147.109973 -308.970221)
			(xy 147.062367 -308.999275) (xy 147.011038 -309.021087) (xy 146.957081 -309.035193) (xy 146.901644 -309.041293)
			(xy 146.84591 -309.039256) (xy 146.791067 -309.029126) (xy 146.738283 -309.011119) (xy 146.688683 -308.985618)
			(xy 146.643325 -308.953167) (xy 146.603176 -308.914458) (xy 146.56909 -308.870315) (xy 146.541794 -308.82168)
			(xy 146.521871 -308.769589) (xy 146.509745 -308.715152) (xy 146.505674 -308.65953) (xy 144.878824 -308.65953)
			(xy 144.862656 -308.683967) (xy 144.825439 -308.725504) (xy 144.782571 -308.761179) (xy 144.734965 -308.790233)
			(xy 144.683636 -308.812045) (xy 144.629679 -308.826151) (xy 144.574242 -308.832251) (xy 144.518508 -308.830214)
			(xy 144.463665 -308.820084) (xy 144.410881 -308.802077) (xy 144.361281 -308.776576) (xy 144.315923 -308.744125)
			(xy 144.275774 -308.705416) (xy 144.241688 -308.661273) (xy 144.214392 -308.612638) (xy 144.194469 -308.560547)
			(xy 144.182343 -308.50611) (xy 144.178272 -308.450488) (xy 118.830852 -308.450488) (xy 118.830852 -309.414926)
			(xy 143.100042 -309.414926) (xy 143.104113 -309.359304) (xy 143.116239 -309.304867) (xy 143.136162 -309.252776)
			(xy 143.163458 -309.204141) (xy 143.197544 -309.159998) (xy 143.237693 -309.121289) (xy 143.283051 -309.088838)
			(xy 143.332651 -309.063337) (xy 143.385435 -309.04533) (xy 143.440278 -309.0352) (xy 143.496012 -309.033163)
			(xy 143.551449 -309.039263) (xy 143.605406 -309.053369) (xy 143.656735 -309.075181) (xy 143.704341 -309.104235)
			(xy 143.747209 -309.13991) (xy 143.784426 -309.181447) (xy 143.79656 -309.199788) (xy 152.644106 -309.199788)
			(xy 152.648066 -309.150734) (xy 152.659843 -309.10295) (xy 152.679134 -309.057674) (xy 152.705437 -309.016078)
			(xy 152.738072 -308.979241) (xy 152.776193 -308.948116) (xy 152.818814 -308.923509) (xy 152.86483 -308.906057)
			(xy 152.913049 -308.896213) (xy 152.962224 -308.894232) (xy 153.011079 -308.900164) (xy 153.05835 -308.913856)
			(xy 153.102812 -308.934954) (xy 153.143315 -308.96291) (xy 153.178808 -308.997002) (xy 153.208373 -309.036346)
			(xy 153.231244 -309.079923) (xy 153.246828 -309.126604) (xy 153.254723 -309.175181) (xy 153.255218 -309.199788)
			(xy 153.594066 -309.199788) (xy 153.598026 -309.150734) (xy 153.609803 -309.10295) (xy 153.629094 -309.057674)
			(xy 153.655397 -309.016078) (xy 153.688032 -308.979241) (xy 153.726153 -308.948116) (xy 153.768774 -308.923509)
			(xy 153.81479 -308.906057) (xy 153.863009 -308.896213) (xy 153.912184 -308.894232) (xy 153.961039 -308.900164)
			(xy 154.00831 -308.913856) (xy 154.052772 -308.934954) (xy 154.093275 -308.96291) (xy 154.128768 -308.997002)
			(xy 154.158333 -309.036346) (xy 154.181204 -309.079923) (xy 154.196788 -309.126604) (xy 154.204683 -309.175181)
			(xy 154.205178 -309.199788) (xy 154.204683 -309.224395) (xy 154.204504 -309.225496) (xy 154.523436 -309.225496)
			(xy 154.523436 -309.17408) (xy 154.531479 -309.123298) (xy 154.547367 -309.074399) (xy 154.57071 -309.028587)
			(xy 154.600931 -308.986991) (xy 154.637287 -308.950635) (xy 154.678883 -308.920414) (xy 154.724695 -308.897071)
			(xy 154.773594 -308.881183) (xy 154.824376 -308.87314) (xy 154.875792 -308.87314) (xy 154.926574 -308.881183)
			(xy 154.975473 -308.897071) (xy 155.021285 -308.920414) (xy 155.062881 -308.950635) (xy 155.099237 -308.986991)
			(xy 155.129458 -309.028587) (xy 155.152801 -309.074399) (xy 155.168689 -309.123298) (xy 155.176732 -309.17408)
			(xy 155.177236 -309.199788) (xy 155.176732 -309.225496) (xy 155.473396 -309.225496) (xy 155.473396 -309.17408)
			(xy 155.481439 -309.123298) (xy 155.497327 -309.074399) (xy 155.52067 -309.028587) (xy 155.550891 -308.986991)
			(xy 155.587247 -308.950635) (xy 155.628843 -308.920414) (xy 155.674655 -308.897071) (xy 155.723554 -308.881183)
			(xy 155.774336 -308.87314) (xy 155.825752 -308.87314) (xy 155.876534 -308.881183) (xy 155.925433 -308.897071)
			(xy 155.971245 -308.920414) (xy 156.012841 -308.950635) (xy 156.049197 -308.986991) (xy 156.079418 -309.028587)
			(xy 156.102761 -309.074399) (xy 156.118649 -309.123298) (xy 156.126692 -309.17408) (xy 156.127196 -309.199788)
			(xy 156.4442 -309.199788) (xy 156.44816 -309.150734) (xy 156.459937 -309.10295) (xy 156.479228 -309.057674)
			(xy 156.505531 -309.016078) (xy 156.538166 -308.979241) (xy 156.576287 -308.948116) (xy 156.618908 -308.923509)
			(xy 156.664924 -308.906057) (xy 156.713143 -308.896213) (xy 156.762318 -308.894232) (xy 156.811173 -308.900164)
			(xy 156.858444 -308.913856) (xy 156.902906 -308.934954) (xy 156.943409 -308.96291) (xy 156.978902 -308.997002)
			(xy 157.008467 -309.036346) (xy 157.031338 -309.079923) (xy 157.046922 -309.126604) (xy 157.054817 -309.175181)
			(xy 157.055312 -309.199788) (xy 157.054817 -309.224395) (xy 157.046922 -309.272972) (xy 157.031338 -309.319653)
			(xy 157.008467 -309.36323) (xy 156.978902 -309.402574) (xy 156.943409 -309.436666) (xy 156.902906 -309.464622)
			(xy 156.858444 -309.48572) (xy 156.811173 -309.499412) (xy 156.762318 -309.505344) (xy 156.713143 -309.503363)
			(xy 156.664924 -309.493519) (xy 156.618908 -309.476067) (xy 156.576287 -309.45146) (xy 156.538166 -309.420335)
			(xy 156.505531 -309.383498) (xy 156.479228 -309.341902) (xy 156.459937 -309.296626) (xy 156.44816 -309.248842)
			(xy 156.4442 -309.199788) (xy 156.127196 -309.199788) (xy 156.126692 -309.225496) (xy 156.118649 -309.276278)
			(xy 156.102761 -309.325177) (xy 156.079418 -309.370989) (xy 156.049197 -309.412585) (xy 156.012841 -309.448941)
			(xy 155.971245 -309.479162) (xy 155.925433 -309.502505) (xy 155.876534 -309.518393) (xy 155.825752 -309.526436)
			(xy 155.774336 -309.526436) (xy 155.723554 -309.518393) (xy 155.674655 -309.502505) (xy 155.628843 -309.479162)
			(xy 155.587247 -309.448941) (xy 155.550891 -309.412585) (xy 155.52067 -309.370989) (xy 155.497327 -309.325177)
			(xy 155.481439 -309.276278) (xy 155.473396 -309.225496) (xy 155.176732 -309.225496) (xy 155.168689 -309.276278)
			(xy 155.152801 -309.325177) (xy 155.129458 -309.370989) (xy 155.099237 -309.412585) (xy 155.062881 -309.448941)
			(xy 155.021285 -309.479162) (xy 154.975473 -309.502505) (xy 154.926574 -309.518393) (xy 154.875792 -309.526436)
			(xy 154.824376 -309.526436) (xy 154.773594 -309.518393) (xy 154.724695 -309.502505) (xy 154.678883 -309.479162)
			(xy 154.637287 -309.448941) (xy 154.600931 -309.412585) (xy 154.57071 -309.370989) (xy 154.547367 -309.325177)
			(xy 154.531479 -309.276278) (xy 154.523436 -309.225496) (xy 154.204504 -309.225496) (xy 154.196788 -309.272972)
			(xy 154.181204 -309.319653) (xy 154.158333 -309.36323) (xy 154.128768 -309.402574) (xy 154.093275 -309.436666)
			(xy 154.052772 -309.464622) (xy 154.00831 -309.48572) (xy 153.961039 -309.499412) (xy 153.912184 -309.505344)
			(xy 153.863009 -309.503363) (xy 153.81479 -309.493519) (xy 153.768774 -309.476067) (xy 153.726153 -309.45146)
			(xy 153.688032 -309.420335) (xy 153.655397 -309.383498) (xy 153.629094 -309.341902) (xy 153.609803 -309.296626)
			(xy 153.598026 -309.248842) (xy 153.594066 -309.199788) (xy 153.255218 -309.199788) (xy 153.254723 -309.224395)
			(xy 153.246828 -309.272972) (xy 153.231244 -309.319653) (xy 153.208373 -309.36323) (xy 153.178808 -309.402574)
			(xy 153.143315 -309.436666) (xy 153.102812 -309.464622) (xy 153.05835 -309.48572) (xy 153.011079 -309.499412)
			(xy 152.962224 -309.505344) (xy 152.913049 -309.503363) (xy 152.86483 -309.493519) (xy 152.818814 -309.476067)
			(xy 152.776193 -309.45146) (xy 152.738072 -309.420335) (xy 152.705437 -309.383498) (xy 152.679134 -309.341902)
			(xy 152.659843 -309.296626) (xy 152.648066 -309.248842) (xy 152.644106 -309.199788) (xy 143.79656 -309.199788)
			(xy 143.815199 -309.22796) (xy 143.838871 -309.278457) (xy 143.854939 -309.331864) (xy 143.863059 -309.38704)
			(xy 143.863568 -309.414926) (xy 143.863059 -309.442812) (xy 143.854939 -309.497988) (xy 143.838871 -309.551395)
			(xy 143.815199 -309.601892) (xy 143.784426 -309.648405) (xy 143.747209 -309.689942) (xy 143.704341 -309.725617)
			(xy 143.656735 -309.754671) (xy 143.605406 -309.776483) (xy 143.551449 -309.790589) (xy 143.496012 -309.796689)
			(xy 143.440278 -309.794652) (xy 143.385435 -309.784522) (xy 143.332651 -309.766515) (xy 143.283051 -309.741014)
			(xy 143.237693 -309.708563) (xy 143.197544 -309.669854) (xy 143.163458 -309.625711) (xy 143.136162 -309.577076)
			(xy 143.116239 -309.524985) (xy 143.104113 -309.470548) (xy 143.100042 -309.414926) (xy 118.830852 -309.414926)
			(xy 118.830852 -309.897272) (xy 150.540464 -309.897272) (xy 150.544535 -309.84165) (xy 150.556661 -309.787213)
			(xy 150.576584 -309.735122) (xy 150.60388 -309.686487) (xy 150.637966 -309.642344) (xy 150.678115 -309.603635)
			(xy 150.723473 -309.571184) (xy 150.773073 -309.545683) (xy 150.825857 -309.527676) (xy 150.8807 -309.517546)
			(xy 150.936434 -309.515509) (xy 150.991871 -309.521609) (xy 151.045828 -309.535715) (xy 151.097157 -309.557527)
			(xy 151.144763 -309.586581) (xy 151.187631 -309.622256) (xy 151.224848 -309.663793) (xy 151.255621 -309.710306)
			(xy 151.279293 -309.760803) (xy 151.295361 -309.81421) (xy 151.303481 -309.869386) (xy 151.30399 -309.897272)
			(xy 151.303481 -309.925158) (xy 151.295361 -309.980334) (xy 151.279293 -310.033741) (xy 151.255621 -310.084238)
			(xy 151.224848 -310.130751) (xy 151.207599 -310.150002) (xy 151.693892 -310.150002) (xy 151.697852 -310.100948)
			(xy 151.709629 -310.053164) (xy 151.72892 -310.007888) (xy 151.755223 -309.966292) (xy 151.787858 -309.929455)
			(xy 151.825979 -309.89833) (xy 151.8686 -309.873723) (xy 151.914616 -309.856271) (xy 151.962835 -309.846427)
			(xy 152.01201 -309.844446) (xy 152.060865 -309.850378) (xy 152.108136 -309.86407) (xy 152.152598 -309.885168)
			(xy 152.193101 -309.913124) (xy 152.228594 -309.947216) (xy 152.258159 -309.98656) (xy 152.28103 -310.030137)
			(xy 152.296614 -310.076818) (xy 152.304509 -310.125395) (xy 152.305004 -310.150002) (xy 152.304509 -310.174609)
			(xy 152.304371 -310.175456) (xy 152.623262 -310.175456) (xy 152.623262 -310.12404) (xy 152.631305 -310.073258)
			(xy 152.647193 -310.024359) (xy 152.670536 -309.978547) (xy 152.700757 -309.936951) (xy 152.737113 -309.900595)
			(xy 152.778709 -309.870374) (xy 152.824521 -309.847031) (xy 152.87342 -309.831143) (xy 152.924202 -309.8231)
			(xy 152.975618 -309.8231) (xy 153.0264 -309.831143) (xy 153.075299 -309.847031) (xy 153.121111 -309.870374)
			(xy 153.162707 -309.900595) (xy 153.199063 -309.936951) (xy 153.229284 -309.978547) (xy 153.252627 -310.024359)
			(xy 153.268515 -310.073258) (xy 153.276558 -310.12404) (xy 153.277062 -310.149748) (xy 153.276558 -310.175456)
			(xy 153.573222 -310.175456) (xy 153.573222 -310.12404) (xy 153.581265 -310.073258) (xy 153.597153 -310.024359)
			(xy 153.620496 -309.978547) (xy 153.650717 -309.936951) (xy 153.687073 -309.900595) (xy 153.728669 -309.870374)
			(xy 153.774481 -309.847031) (xy 153.82338 -309.831143) (xy 153.874162 -309.8231) (xy 153.925578 -309.8231)
			(xy 153.97636 -309.831143) (xy 154.025259 -309.847031) (xy 154.071071 -309.870374) (xy 154.112667 -309.900595)
			(xy 154.149023 -309.936951) (xy 154.179244 -309.978547) (xy 154.202587 -310.024359) (xy 154.218475 -310.073258)
			(xy 154.226518 -310.12404) (xy 154.227022 -310.149748) (xy 154.54428 -310.149748) (xy 154.54824 -310.100694)
			(xy 154.560017 -310.05291) (xy 154.579308 -310.007634) (xy 154.605611 -309.966038) (xy 154.638246 -309.929201)
			(xy 154.676367 -309.898076) (xy 154.718988 -309.873469) (xy 154.765004 -309.856017) (xy 154.813223 -309.846173)
			(xy 154.862398 -309.844192) (xy 154.911253 -309.850124) (xy 154.958524 -309.863816) (xy 155.002986 -309.884914)
			(xy 155.043489 -309.91287) (xy 155.078982 -309.946962) (xy 155.108547 -309.986306) (xy 155.131418 -310.029883)
			(xy 155.147002 -310.076564) (xy 155.154897 -310.125141) (xy 155.155392 -310.149748) (xy 155.49424 -310.149748)
			(xy 155.4982 -310.100694) (xy 155.509977 -310.05291) (xy 155.529268 -310.007634) (xy 155.555571 -309.966038)
			(xy 155.588206 -309.929201) (xy 155.626327 -309.898076) (xy 155.668948 -309.873469) (xy 155.714964 -309.856017)
			(xy 155.763183 -309.846173) (xy 155.812358 -309.844192) (xy 155.861213 -309.850124) (xy 155.908484 -309.863816)
			(xy 155.952946 -309.884914) (xy 155.993449 -309.91287) (xy 156.028942 -309.946962) (xy 156.058507 -309.986306)
			(xy 156.081378 -310.029883) (xy 156.096962 -310.076564) (xy 156.104857 -310.125141) (xy 156.105352 -310.149748)
			(xy 156.104857 -310.174355) (xy 156.096962 -310.222932) (xy 156.081378 -310.269613) (xy 156.058507 -310.31319)
			(xy 156.028942 -310.352534) (xy 155.993449 -310.386626) (xy 155.952946 -310.414582) (xy 155.908484 -310.43568)
			(xy 155.861213 -310.449372) (xy 155.812358 -310.455304) (xy 155.763183 -310.453323) (xy 155.714964 -310.443479)
			(xy 155.668948 -310.426027) (xy 155.626327 -310.40142) (xy 155.588206 -310.370295) (xy 155.555571 -310.333458)
			(xy 155.529268 -310.291862) (xy 155.509977 -310.246586) (xy 155.4982 -310.198802) (xy 155.49424 -310.149748)
			(xy 155.155392 -310.149748) (xy 155.154897 -310.174355) (xy 155.147002 -310.222932) (xy 155.131418 -310.269613)
			(xy 155.108547 -310.31319) (xy 155.078982 -310.352534) (xy 155.043489 -310.386626) (xy 155.002986 -310.414582)
			(xy 154.958524 -310.43568) (xy 154.911253 -310.449372) (xy 154.862398 -310.455304) (xy 154.813223 -310.453323)
			(xy 154.765004 -310.443479) (xy 154.718988 -310.426027) (xy 154.676367 -310.40142) (xy 154.638246 -310.370295)
			(xy 154.605611 -310.333458) (xy 154.579308 -310.291862) (xy 154.560017 -310.246586) (xy 154.54824 -310.198802)
			(xy 154.54428 -310.149748) (xy 154.227022 -310.149748) (xy 154.226518 -310.175456) (xy 154.218475 -310.226238)
			(xy 154.202587 -310.275137) (xy 154.179244 -310.320949) (xy 154.149023 -310.362545) (xy 154.112667 -310.398901)
			(xy 154.071071 -310.429122) (xy 154.025259 -310.452465) (xy 153.97636 -310.468353) (xy 153.925578 -310.476396)
			(xy 153.874162 -310.476396) (xy 153.82338 -310.468353) (xy 153.774481 -310.452465) (xy 153.728669 -310.429122)
			(xy 153.687073 -310.398901) (xy 153.650717 -310.362545) (xy 153.620496 -310.320949) (xy 153.597153 -310.275137)
			(xy 153.581265 -310.226238) (xy 153.573222 -310.175456) (xy 153.276558 -310.175456) (xy 153.268515 -310.226238)
			(xy 153.252627 -310.275137) (xy 153.229284 -310.320949) (xy 153.199063 -310.362545) (xy 153.162707 -310.398901)
			(xy 153.121111 -310.429122) (xy 153.075299 -310.452465) (xy 153.0264 -310.468353) (xy 152.975618 -310.476396)
			(xy 152.924202 -310.476396) (xy 152.87342 -310.468353) (xy 152.824521 -310.452465) (xy 152.778709 -310.429122)
			(xy 152.737113 -310.398901) (xy 152.700757 -310.362545) (xy 152.670536 -310.320949) (xy 152.647193 -310.275137)
			(xy 152.631305 -310.226238) (xy 152.623262 -310.175456) (xy 152.304371 -310.175456) (xy 152.296614 -310.223186)
			(xy 152.28103 -310.269867) (xy 152.258159 -310.313444) (xy 152.228594 -310.352788) (xy 152.193101 -310.38688)
			(xy 152.152598 -310.414836) (xy 152.108136 -310.435934) (xy 152.060865 -310.449626) (xy 152.01201 -310.455558)
			(xy 151.962835 -310.453577) (xy 151.914616 -310.443733) (xy 151.8686 -310.426281) (xy 151.825979 -310.401674)
			(xy 151.787858 -310.370549) (xy 151.755223 -310.333712) (xy 151.72892 -310.292116) (xy 151.709629 -310.24684)
			(xy 151.697852 -310.199056) (xy 151.693892 -310.150002) (xy 151.207599 -310.150002) (xy 151.187631 -310.172288)
			(xy 151.144763 -310.207963) (xy 151.097157 -310.237017) (xy 151.045828 -310.258829) (xy 150.991871 -310.272935)
			(xy 150.936434 -310.279035) (xy 150.8807 -310.276998) (xy 150.825857 -310.266868) (xy 150.773073 -310.248861)
			(xy 150.723473 -310.22336) (xy 150.678115 -310.190909) (xy 150.637966 -310.1522) (xy 150.60388 -310.108057)
			(xy 150.576584 -310.059422) (xy 150.556661 -310.007331) (xy 150.544535 -309.952894) (xy 150.540464 -309.897272)
			(xy 118.830852 -309.897272) (xy 118.830852 -310.832246) (xy 144.36801 -310.832246) (xy 144.372081 -310.776624)
			(xy 144.384207 -310.722187) (xy 144.40413 -310.670096) (xy 144.431426 -310.621461) (xy 144.465512 -310.577318)
			(xy 144.505661 -310.538609) (xy 144.551019 -310.506158) (xy 144.600619 -310.480657) (xy 144.653403 -310.46265)
			(xy 144.708246 -310.45252) (xy 144.76398 -310.450483) (xy 144.819417 -310.456583) (xy 144.873374 -310.470689)
			(xy 144.924703 -310.492501) (xy 144.972309 -310.521555) (xy 145.015177 -310.55723) (xy 145.052394 -310.598767)
			(xy 145.083167 -310.64528) (xy 145.106839 -310.695777) (xy 145.122907 -310.749184) (xy 145.131027 -310.80436)
			(xy 145.131536 -310.832246) (xy 145.131027 -310.860132) (xy 145.122907 -310.915308) (xy 145.106839 -310.968715)
			(xy 145.084725 -311.015888) (xy 150.371808 -311.015888) (xy 150.375879 -310.960266) (xy 150.388005 -310.905829)
			(xy 150.407928 -310.853738) (xy 150.435224 -310.805103) (xy 150.46931 -310.76096) (xy 150.509459 -310.722251)
			(xy 150.554817 -310.6898) (xy 150.604417 -310.664299) (xy 150.657201 -310.646292) (xy 150.712044 -310.636162)
			(xy 150.767778 -310.634125) (xy 150.823215 -310.640225) (xy 150.877172 -310.654331) (xy 150.928501 -310.676143)
			(xy 150.976107 -310.705197) (xy 151.018975 -310.740872) (xy 151.056192 -310.782409) (xy 151.086965 -310.828922)
			(xy 151.110637 -310.879419) (xy 151.126705 -310.932826) (xy 151.134825 -310.988002) (xy 151.135334 -311.015888)
			(xy 151.134825 -311.043774) (xy 151.126705 -311.09895) (xy 151.126401 -311.099962) (xy 152.644106 -311.099962)
			(xy 152.648066 -311.050908) (xy 152.659843 -311.003124) (xy 152.679134 -310.957848) (xy 152.705437 -310.916252)
			(xy 152.738072 -310.879415) (xy 152.776193 -310.84829) (xy 152.818814 -310.823683) (xy 152.86483 -310.806231)
			(xy 152.913049 -310.796387) (xy 152.962224 -310.794406) (xy 153.011079 -310.800338) (xy 153.05835 -310.81403)
			(xy 153.102812 -310.835128) (xy 153.143315 -310.863084) (xy 153.178808 -310.897176) (xy 153.208373 -310.93652)
			(xy 153.231244 -310.980097) (xy 153.246828 -311.026778) (xy 153.254723 -311.075355) (xy 153.255218 -311.099962)
			(xy 153.594066 -311.099962) (xy 153.598026 -311.050908) (xy 153.609803 -311.003124) (xy 153.629094 -310.957848)
			(xy 153.655397 -310.916252) (xy 153.688032 -310.879415) (xy 153.726153 -310.84829) (xy 153.768774 -310.823683)
			(xy 153.81479 -310.806231) (xy 153.863009 -310.796387) (xy 153.912184 -310.794406) (xy 153.961039 -310.800338)
			(xy 154.00831 -310.81403) (xy 154.052772 -310.835128) (xy 154.093275 -310.863084) (xy 154.128768 -310.897176)
			(xy 154.158333 -310.93652) (xy 154.181204 -310.980097) (xy 154.196788 -311.026778) (xy 154.204683 -311.075355)
			(xy 154.205178 -311.099962) (xy 154.54428 -311.099962) (xy 154.54824 -311.050908) (xy 154.560017 -311.003124)
			(xy 154.579308 -310.957848) (xy 154.605611 -310.916252) (xy 154.638246 -310.879415) (xy 154.676367 -310.84829)
			(xy 154.718988 -310.823683) (xy 154.765004 -310.806231) (xy 154.813223 -310.796387) (xy 154.862398 -310.794406)
			(xy 154.911253 -310.800338) (xy 154.958524 -310.81403) (xy 155.002986 -310.835128) (xy 155.043489 -310.863084)
			(xy 155.078982 -310.897176) (xy 155.108547 -310.93652) (xy 155.131418 -310.980097) (xy 155.147002 -311.026778)
			(xy 155.154897 -311.075355) (xy 155.155392 -311.099962) (xy 155.154897 -311.124569) (xy 155.154718 -311.12567)
			(xy 155.473396 -311.12567) (xy 155.473396 -311.074254) (xy 155.481439 -311.023472) (xy 155.497327 -310.974573)
			(xy 155.52067 -310.928761) (xy 155.550891 -310.887165) (xy 155.587247 -310.850809) (xy 155.628843 -310.820588)
			(xy 155.674655 -310.797245) (xy 155.723554 -310.781357) (xy 155.774336 -310.773314) (xy 155.825752 -310.773314)
			(xy 155.876534 -310.781357) (xy 155.925433 -310.797245) (xy 155.971245 -310.820588) (xy 156.012841 -310.850809)
			(xy 156.049197 -310.887165) (xy 156.079418 -310.928761) (xy 156.102761 -310.974573) (xy 156.118649 -311.023472)
			(xy 156.126692 -311.074254) (xy 156.127196 -311.099962) (xy 156.126692 -311.12567) (xy 156.118649 -311.176452)
			(xy 156.102761 -311.225351) (xy 156.079418 -311.271163) (xy 156.049197 -311.312759) (xy 156.012841 -311.349115)
			(xy 155.971245 -311.379336) (xy 155.925433 -311.402679) (xy 155.876534 -311.418567) (xy 155.825752 -311.42661)
			(xy 155.774336 -311.42661) (xy 155.723554 -311.418567) (xy 155.674655 -311.402679) (xy 155.628843 -311.379336)
			(xy 155.587247 -311.349115) (xy 155.550891 -311.312759) (xy 155.52067 -311.271163) (xy 155.497327 -311.225351)
			(xy 155.481439 -311.176452) (xy 155.473396 -311.12567) (xy 155.154718 -311.12567) (xy 155.147002 -311.173146)
			(xy 155.131418 -311.219827) (xy 155.108547 -311.263404) (xy 155.078982 -311.302748) (xy 155.043489 -311.33684)
			(xy 155.002986 -311.364796) (xy 154.958524 -311.385894) (xy 154.911253 -311.399586) (xy 154.862398 -311.405518)
			(xy 154.813223 -311.403537) (xy 154.765004 -311.393693) (xy 154.718988 -311.376241) (xy 154.676367 -311.351634)
			(xy 154.638246 -311.320509) (xy 154.605611 -311.283672) (xy 154.579308 -311.242076) (xy 154.560017 -311.1968)
			(xy 154.54824 -311.149016) (xy 154.54428 -311.099962) (xy 154.205178 -311.099962) (xy 154.204683 -311.124569)
			(xy 154.196788 -311.173146) (xy 154.181204 -311.219827) (xy 154.158333 -311.263404) (xy 154.128768 -311.302748)
			(xy 154.093275 -311.33684) (xy 154.052772 -311.364796) (xy 154.00831 -311.385894) (xy 153.961039 -311.399586)
			(xy 153.912184 -311.405518) (xy 153.863009 -311.403537) (xy 153.81479 -311.393693) (xy 153.768774 -311.376241)
			(xy 153.726153 -311.351634) (xy 153.688032 -311.320509) (xy 153.655397 -311.283672) (xy 153.629094 -311.242076)
			(xy 153.609803 -311.1968) (xy 153.598026 -311.149016) (xy 153.594066 -311.099962) (xy 153.255218 -311.099962)
			(xy 153.254723 -311.124569) (xy 153.246828 -311.173146) (xy 153.231244 -311.219827) (xy 153.208373 -311.263404)
			(xy 153.178808 -311.302748) (xy 153.143315 -311.33684) (xy 153.102812 -311.364796) (xy 153.05835 -311.385894)
			(xy 153.011079 -311.399586) (xy 152.962224 -311.405518) (xy 152.913049 -311.403537) (xy 152.86483 -311.393693)
			(xy 152.818814 -311.376241) (xy 152.776193 -311.351634) (xy 152.738072 -311.320509) (xy 152.705437 -311.283672)
			(xy 152.679134 -311.242076) (xy 152.659843 -311.1968) (xy 152.648066 -311.149016) (xy 152.644106 -311.099962)
			(xy 151.126401 -311.099962) (xy 151.110637 -311.152357) (xy 151.086965 -311.202854) (xy 151.056192 -311.249367)
			(xy 151.018975 -311.290904) (xy 150.976107 -311.326579) (xy 150.928501 -311.355633) (xy 150.877172 -311.377445)
			(xy 150.823215 -311.391551) (xy 150.767778 -311.397651) (xy 150.712044 -311.395614) (xy 150.657201 -311.385484)
			(xy 150.604417 -311.367477) (xy 150.554817 -311.341976) (xy 150.509459 -311.309525) (xy 150.46931 -311.270816)
			(xy 150.435224 -311.226673) (xy 150.407928 -311.178038) (xy 150.388005 -311.125947) (xy 150.375879 -311.07151)
			(xy 150.371808 -311.015888) (xy 145.084725 -311.015888) (xy 145.083167 -311.019212) (xy 145.052394 -311.065725)
			(xy 145.015177 -311.107262) (xy 144.972309 -311.142937) (xy 144.924703 -311.171991) (xy 144.873374 -311.193803)
			(xy 144.819417 -311.207909) (xy 144.76398 -311.214009) (xy 144.708246 -311.211972) (xy 144.653403 -311.201842)
			(xy 144.600619 -311.183835) (xy 144.551019 -311.158334) (xy 144.505661 -311.125883) (xy 144.465512 -311.087174)
			(xy 144.431426 -311.043031) (xy 144.40413 -310.994396) (xy 144.384207 -310.942305) (xy 144.372081 -310.887868)
			(xy 144.36801 -310.832246) (xy 118.830852 -310.832246) (xy 118.830852 -311.7342) (xy 148.58949 -311.7342)
			(xy 148.593561 -311.678578) (xy 148.605687 -311.624141) (xy 148.62561 -311.57205) (xy 148.652906 -311.523415)
			(xy 148.686992 -311.479272) (xy 148.727141 -311.440563) (xy 148.772499 -311.408112) (xy 148.822099 -311.382611)
			(xy 148.874883 -311.364604) (xy 148.929726 -311.354474) (xy 148.98546 -311.352437) (xy 149.040897 -311.358537)
			(xy 149.094854 -311.372643) (xy 149.146183 -311.394455) (xy 149.193789 -311.423509) (xy 149.236657 -311.459184)
			(xy 149.273874 -311.500721) (xy 149.304647 -311.547234) (xy 149.328319 -311.597731) (xy 149.344387 -311.651138)
			(xy 149.352507 -311.706314) (xy 149.353016 -311.7342) (xy 149.352507 -311.762086) (xy 149.344387 -311.817262)
			(xy 149.328319 -311.870669) (xy 149.304647 -311.921166) (xy 149.273874 -311.967679) (xy 149.236657 -312.009216)
			(xy 149.193789 -312.044891) (xy 149.146183 -312.073945) (xy 149.094854 -312.095757) (xy 149.040897 -312.109863)
			(xy 148.98546 -312.115963) (xy 148.929726 -312.113926) (xy 148.874883 -312.103796) (xy 148.822099 -312.085789)
			(xy 148.772499 -312.060288) (xy 148.727141 -312.027837) (xy 148.686992 -311.989128) (xy 148.652906 -311.944985)
			(xy 148.62561 -311.89635) (xy 148.605687 -311.844259) (xy 148.593561 -311.789822) (xy 148.58949 -311.7342)
			(xy 118.830852 -311.7342) (xy 118.830852 -312.523378) (xy 147.832062 -312.523378) (xy 147.836133 -312.467756)
			(xy 147.848259 -312.413319) (xy 147.868182 -312.361228) (xy 147.895478 -312.312593) (xy 147.929564 -312.26845)
			(xy 147.969713 -312.229741) (xy 148.015071 -312.19729) (xy 148.064671 -312.171789) (xy 148.117455 -312.153782)
			(xy 148.172298 -312.143652) (xy 148.228032 -312.141615) (xy 148.283469 -312.147715) (xy 148.337426 -312.161821)
			(xy 148.388755 -312.183633) (xy 148.436361 -312.212687) (xy 148.479229 -312.248362) (xy 148.496921 -312.268108)
			(xy 150.210772 -312.268108) (xy 150.214843 -312.212486) (xy 150.226969 -312.158049) (xy 150.246892 -312.105958)
			(xy 150.274188 -312.057323) (xy 150.308274 -312.01318) (xy 150.348423 -311.974471) (xy 150.393781 -311.94202)
			(xy 150.443381 -311.916519) (xy 150.496165 -311.898512) (xy 150.551008 -311.888382) (xy 150.606742 -311.886345)
			(xy 150.662179 -311.892445) (xy 150.716136 -311.906551) (xy 150.767465 -311.928363) (xy 150.815071 -311.957417)
			(xy 150.857939 -311.993092) (xy 150.895156 -312.034629) (xy 150.905106 -312.049668) (xy 151.693892 -312.049668)
			(xy 151.697852 -312.000614) (xy 151.709629 -311.95283) (xy 151.72892 -311.907554) (xy 151.755223 -311.865958)
			(xy 151.787858 -311.829121) (xy 151.825979 -311.797996) (xy 151.8686 -311.773389) (xy 151.914616 -311.755937)
			(xy 151.962835 -311.746093) (xy 152.01201 -311.744112) (xy 152.060865 -311.750044) (xy 152.108136 -311.763736)
			(xy 152.152598 -311.784834) (xy 152.193101 -311.81279) (xy 152.228594 -311.846882) (xy 152.258159 -311.886226)
			(xy 152.28103 -311.929803) (xy 152.296614 -311.976484) (xy 152.304509 -312.025061) (xy 152.305004 -312.049668)
			(xy 152.304509 -312.074275) (xy 152.304289 -312.07563) (xy 152.623262 -312.07563) (xy 152.623262 -312.024214)
			(xy 152.631305 -311.973432) (xy 152.647193 -311.924533) (xy 152.670536 -311.878721) (xy 152.700757 -311.837125)
			(xy 152.737113 -311.800769) (xy 152.778709 -311.770548) (xy 152.824521 -311.747205) (xy 152.87342 -311.731317)
			(xy 152.924202 -311.723274) (xy 152.975618 -311.723274) (xy 153.0264 -311.731317) (xy 153.075299 -311.747205)
			(xy 153.121111 -311.770548) (xy 153.162707 -311.800769) (xy 153.199063 -311.837125) (xy 153.229284 -311.878721)
			(xy 153.252627 -311.924533) (xy 153.268515 -311.973432) (xy 153.276558 -312.024214) (xy 153.277062 -312.049922)
			(xy 153.276558 -312.07563) (xy 153.573222 -312.07563) (xy 153.573222 -312.024214) (xy 153.581265 -311.973432)
			(xy 153.597153 -311.924533) (xy 153.620496 -311.878721) (xy 153.650717 -311.837125) (xy 153.687073 -311.800769)
			(xy 153.728669 -311.770548) (xy 153.774481 -311.747205) (xy 153.82338 -311.731317) (xy 153.874162 -311.723274)
			(xy 153.925578 -311.723274) (xy 153.97636 -311.731317) (xy 154.025259 -311.747205) (xy 154.071071 -311.770548)
			(xy 154.112667 -311.800769) (xy 154.149023 -311.837125) (xy 154.179244 -311.878721) (xy 154.202587 -311.924533)
			(xy 154.218475 -311.973432) (xy 154.226518 -312.024214) (xy 154.227022 -312.049922) (xy 154.54428 -312.049922)
			(xy 154.54824 -312.000868) (xy 154.560017 -311.953084) (xy 154.579308 -311.907808) (xy 154.605611 -311.866212)
			(xy 154.638246 -311.829375) (xy 154.676367 -311.79825) (xy 154.718988 -311.773643) (xy 154.765004 -311.756191)
			(xy 154.813223 -311.746347) (xy 154.862398 -311.744366) (xy 154.911253 -311.750298) (xy 154.958524 -311.76399)
			(xy 155.002986 -311.785088) (xy 155.043489 -311.813044) (xy 155.078982 -311.847136) (xy 155.108547 -311.88648)
			(xy 155.131418 -311.930057) (xy 155.147002 -311.976738) (xy 155.154897 -312.025315) (xy 155.155392 -312.049922)
			(xy 155.154897 -312.074529) (xy 155.154718 -312.07563) (xy 155.473396 -312.07563) (xy 155.473396 -312.024214)
			(xy 155.481439 -311.973432) (xy 155.497327 -311.924533) (xy 155.52067 -311.878721) (xy 155.550891 -311.837125)
			(xy 155.587247 -311.800769) (xy 155.628843 -311.770548) (xy 155.674655 -311.747205) (xy 155.723554 -311.731317)
			(xy 155.774336 -311.723274) (xy 155.825752 -311.723274) (xy 155.876534 -311.731317) (xy 155.925433 -311.747205)
			(xy 155.971245 -311.770548) (xy 156.012841 -311.800769) (xy 156.049197 -311.837125) (xy 156.079418 -311.878721)
			(xy 156.102761 -311.924533) (xy 156.118649 -311.973432) (xy 156.126692 -312.024214) (xy 156.127196 -312.049922)
			(xy 156.126692 -312.07563) (xy 156.118649 -312.126412) (xy 156.102761 -312.175311) (xy 156.079418 -312.221123)
			(xy 156.049197 -312.262719) (xy 156.012841 -312.299075) (xy 155.971245 -312.329296) (xy 155.925433 -312.352639)
			(xy 155.876534 -312.368527) (xy 155.825752 -312.37657) (xy 155.774336 -312.37657) (xy 155.723554 -312.368527)
			(xy 155.674655 -312.352639) (xy 155.628843 -312.329296) (xy 155.587247 -312.299075) (xy 155.550891 -312.262719)
			(xy 155.52067 -312.221123) (xy 155.497327 -312.175311) (xy 155.481439 -312.126412) (xy 155.473396 -312.07563)
			(xy 155.154718 -312.07563) (xy 155.147002 -312.123106) (xy 155.131418 -312.169787) (xy 155.108547 -312.213364)
			(xy 155.078982 -312.252708) (xy 155.043489 -312.2868) (xy 155.002986 -312.314756) (xy 154.958524 -312.335854)
			(xy 154.911253 -312.349546) (xy 154.862398 -312.355478) (xy 154.813223 -312.353497) (xy 154.765004 -312.343653)
			(xy 154.718988 -312.326201) (xy 154.676367 -312.301594) (xy 154.638246 -312.270469) (xy 154.605611 -312.233632)
			(xy 154.579308 -312.192036) (xy 154.560017 -312.14676) (xy 154.54824 -312.098976) (xy 154.54428 -312.049922)
			(xy 154.227022 -312.049922) (xy 154.226518 -312.07563) (xy 154.218475 -312.126412) (xy 154.202587 -312.175311)
			(xy 154.179244 -312.221123) (xy 154.149023 -312.262719) (xy 154.112667 -312.299075) (xy 154.071071 -312.329296)
			(xy 154.025259 -312.352639) (xy 153.97636 -312.368527) (xy 153.925578 -312.37657) (xy 153.874162 -312.37657)
			(xy 153.82338 -312.368527) (xy 153.774481 -312.352639) (xy 153.728669 -312.329296) (xy 153.687073 -312.299075)
			(xy 153.650717 -312.262719) (xy 153.620496 -312.221123) (xy 153.597153 -312.175311) (xy 153.581265 -312.126412)
			(xy 153.573222 -312.07563) (xy 153.276558 -312.07563) (xy 153.268515 -312.126412) (xy 153.252627 -312.175311)
			(xy 153.229284 -312.221123) (xy 153.199063 -312.262719) (xy 153.162707 -312.299075) (xy 153.121111 -312.329296)
			(xy 153.075299 -312.352639) (xy 153.0264 -312.368527) (xy 152.975618 -312.37657) (xy 152.924202 -312.37657)
			(xy 152.87342 -312.368527) (xy 152.824521 -312.352639) (xy 152.778709 -312.329296) (xy 152.737113 -312.299075)
			(xy 152.700757 -312.262719) (xy 152.670536 -312.221123) (xy 152.647193 -312.175311) (xy 152.631305 -312.126412)
			(xy 152.623262 -312.07563) (xy 152.304289 -312.07563) (xy 152.296614 -312.122852) (xy 152.28103 -312.169533)
			(xy 152.258159 -312.21311) (xy 152.228594 -312.252454) (xy 152.193101 -312.286546) (xy 152.152598 -312.314502)
			(xy 152.108136 -312.3356) (xy 152.060865 -312.349292) (xy 152.01201 -312.355224) (xy 151.962835 -312.353243)
			(xy 151.914616 -312.343399) (xy 151.8686 -312.325947) (xy 151.825979 -312.30134) (xy 151.787858 -312.270215)
			(xy 151.755223 -312.233378) (xy 151.72892 -312.191782) (xy 151.709629 -312.146506) (xy 151.697852 -312.098722)
			(xy 151.693892 -312.049668) (xy 150.905106 -312.049668) (xy 150.925929 -312.081142) (xy 150.949601 -312.131639)
			(xy 150.965669 -312.185046) (xy 150.973789 -312.240222) (xy 150.974298 -312.268108) (xy 150.973789 -312.295994)
			(xy 150.965669 -312.35117) (xy 150.949601 -312.404577) (xy 150.925929 -312.455074) (xy 150.895156 -312.501587)
			(xy 150.857939 -312.543124) (xy 150.815071 -312.578799) (xy 150.767465 -312.607853) (xy 150.716136 -312.629665)
			(xy 150.662179 -312.643771) (xy 150.606742 -312.649871) (xy 150.551008 -312.647834) (xy 150.496165 -312.637704)
			(xy 150.443381 -312.619697) (xy 150.393781 -312.594196) (xy 150.348423 -312.561745) (xy 150.308274 -312.523036)
			(xy 150.274188 -312.478893) (xy 150.246892 -312.430258) (xy 150.226969 -312.378167) (xy 150.214843 -312.32373)
			(xy 150.210772 -312.268108) (xy 148.496921 -312.268108) (xy 148.516446 -312.289899) (xy 148.547219 -312.336412)
			(xy 148.570891 -312.386909) (xy 148.586959 -312.440316) (xy 148.595079 -312.495492) (xy 148.595588 -312.523378)
			(xy 148.595079 -312.551264) (xy 148.586959 -312.60644) (xy 148.570891 -312.659847) (xy 148.547219 -312.710344)
			(xy 148.516446 -312.756857) (xy 148.479229 -312.798394) (xy 148.436361 -312.834069) (xy 148.388755 -312.863123)
			(xy 148.337426 -312.884935) (xy 148.283469 -312.899041) (xy 148.228032 -312.905141) (xy 148.172298 -312.903104)
			(xy 148.117455 -312.892974) (xy 148.064671 -312.874967) (xy 148.015071 -312.849466) (xy 147.969713 -312.817015)
			(xy 147.929564 -312.778306) (xy 147.895478 -312.734163) (xy 147.868182 -312.685528) (xy 147.848259 -312.633437)
			(xy 147.836133 -312.579) (xy 147.832062 -312.523378) (xy 118.830852 -312.523378) (xy 118.830852 -312.999882)
			(xy 152.644106 -312.999882) (xy 152.648066 -312.950828) (xy 152.659843 -312.903044) (xy 152.679134 -312.857768)
			(xy 152.705437 -312.816172) (xy 152.738072 -312.779335) (xy 152.776193 -312.74821) (xy 152.818814 -312.723603)
			(xy 152.86483 -312.706151) (xy 152.913049 -312.696307) (xy 152.962224 -312.694326) (xy 153.011079 -312.700258)
			(xy 153.05835 -312.71395) (xy 153.102812 -312.735048) (xy 153.143315 -312.763004) (xy 153.178808 -312.797096)
			(xy 153.208373 -312.83644) (xy 153.231244 -312.880017) (xy 153.246828 -312.926698) (xy 153.254723 -312.975275)
			(xy 153.255218 -312.999882) (xy 153.594066 -312.999882) (xy 153.598026 -312.950828) (xy 153.609803 -312.903044)
			(xy 153.629094 -312.857768) (xy 153.655397 -312.816172) (xy 153.688032 -312.779335) (xy 153.726153 -312.74821)
			(xy 153.768774 -312.723603) (xy 153.81479 -312.706151) (xy 153.863009 -312.696307) (xy 153.912184 -312.694326)
			(xy 153.961039 -312.700258) (xy 154.00831 -312.71395) (xy 154.052772 -312.735048) (xy 154.093275 -312.763004)
			(xy 154.128768 -312.797096) (xy 154.158333 -312.83644) (xy 154.181204 -312.880017) (xy 154.196788 -312.926698)
			(xy 154.204683 -312.975275) (xy 154.205178 -312.999882) (xy 154.204683 -313.024489) (xy 154.204504 -313.02559)
			(xy 154.523436 -313.02559) (xy 154.523436 -312.974174) (xy 154.531479 -312.923392) (xy 154.547367 -312.874493)
			(xy 154.57071 -312.828681) (xy 154.600931 -312.787085) (xy 154.637287 -312.750729) (xy 154.678883 -312.720508)
			(xy 154.724695 -312.697165) (xy 154.773594 -312.681277) (xy 154.824376 -312.673234) (xy 154.875792 -312.673234)
			(xy 154.926574 -312.681277) (xy 154.975473 -312.697165) (xy 155.021285 -312.720508) (xy 155.062881 -312.750729)
			(xy 155.099237 -312.787085) (xy 155.129458 -312.828681) (xy 155.152801 -312.874493) (xy 155.168689 -312.923392)
			(xy 155.176732 -312.974174) (xy 155.177236 -312.999882) (xy 155.49424 -312.999882) (xy 155.4982 -312.950828)
			(xy 155.509977 -312.903044) (xy 155.529268 -312.857768) (xy 155.555571 -312.816172) (xy 155.588206 -312.779335)
			(xy 155.626327 -312.74821) (xy 155.668948 -312.723603) (xy 155.714964 -312.706151) (xy 155.763183 -312.696307)
			(xy 155.812358 -312.694326) (xy 155.861213 -312.700258) (xy 155.908484 -312.71395) (xy 155.952946 -312.735048)
			(xy 155.993449 -312.763004) (xy 156.028942 -312.797096) (xy 156.058507 -312.83644) (xy 156.081378 -312.880017)
			(xy 156.096962 -312.926698) (xy 156.104857 -312.975275) (xy 156.105352 -312.999882) (xy 156.104857 -313.024489)
			(xy 156.096962 -313.073066) (xy 156.081378 -313.119747) (xy 156.058507 -313.163324) (xy 156.028942 -313.202668)
			(xy 155.993449 -313.23676) (xy 155.952946 -313.264716) (xy 155.908484 -313.285814) (xy 155.861213 -313.299506)
			(xy 155.812358 -313.305438) (xy 155.763183 -313.303457) (xy 155.714964 -313.293613) (xy 155.668948 -313.276161)
			(xy 155.626327 -313.251554) (xy 155.588206 -313.220429) (xy 155.555571 -313.183592) (xy 155.529268 -313.141996)
			(xy 155.509977 -313.09672) (xy 155.4982 -313.048936) (xy 155.49424 -312.999882) (xy 155.177236 -312.999882)
			(xy 155.176732 -313.02559) (xy 155.168689 -313.076372) (xy 155.152801 -313.125271) (xy 155.129458 -313.171083)
			(xy 155.099237 -313.212679) (xy 155.062881 -313.249035) (xy 155.021285 -313.279256) (xy 154.975473 -313.302599)
			(xy 154.926574 -313.318487) (xy 154.875792 -313.32653) (xy 154.824376 -313.32653) (xy 154.773594 -313.318487)
			(xy 154.724695 -313.302599) (xy 154.678883 -313.279256) (xy 154.637287 -313.249035) (xy 154.600931 -313.212679)
			(xy 154.57071 -313.171083) (xy 154.547367 -313.125271) (xy 154.531479 -313.076372) (xy 154.523436 -313.02559)
			(xy 154.204504 -313.02559) (xy 154.196788 -313.073066) (xy 154.181204 -313.119747) (xy 154.158333 -313.163324)
			(xy 154.128768 -313.202668) (xy 154.093275 -313.23676) (xy 154.052772 -313.264716) (xy 154.00831 -313.285814)
			(xy 153.961039 -313.299506) (xy 153.912184 -313.305438) (xy 153.863009 -313.303457) (xy 153.81479 -313.293613)
			(xy 153.768774 -313.276161) (xy 153.726153 -313.251554) (xy 153.688032 -313.220429) (xy 153.655397 -313.183592)
			(xy 153.629094 -313.141996) (xy 153.609803 -313.09672) (xy 153.598026 -313.048936) (xy 153.594066 -312.999882)
			(xy 153.255218 -312.999882) (xy 153.254723 -313.024489) (xy 153.246828 -313.073066) (xy 153.231244 -313.119747)
			(xy 153.208373 -313.163324) (xy 153.178808 -313.202668) (xy 153.143315 -313.23676) (xy 153.102812 -313.264716)
			(xy 153.05835 -313.285814) (xy 153.011079 -313.299506) (xy 152.962224 -313.305438) (xy 152.913049 -313.303457)
			(xy 152.86483 -313.293613) (xy 152.818814 -313.276161) (xy 152.776193 -313.251554) (xy 152.738072 -313.220429)
			(xy 152.705437 -313.183592) (xy 152.679134 -313.141996) (xy 152.659843 -313.09672) (xy 152.648066 -313.048936)
			(xy 152.644106 -312.999882) (xy 118.830852 -312.999882) (xy 118.830852 -313.376564) (xy 118.83102 -313.382573)
			(xy 118.833844 -313.394255) (xy 118.83644 -313.399678) (xy 118.838279 -313.403153) (xy 118.842871 -313.409533)
			(xy 118.845584 -313.412378) (xy 118.845838 -313.412632) (xy 118.837964 -313.433968) (xy 118.835678 -313.445398)
			(xy 118.835424 -313.449716) (xy 118.835424 -313.669934) (xy 150.147018 -313.669934) (xy 150.151089 -313.614312)
			(xy 150.163215 -313.559875) (xy 150.183138 -313.507784) (xy 150.210434 -313.459149) (xy 150.24452 -313.415006)
			(xy 150.284669 -313.376297) (xy 150.330027 -313.343846) (xy 150.379627 -313.318345) (xy 150.432411 -313.300338)
			(xy 150.487254 -313.290208) (xy 150.542988 -313.288171) (xy 150.598425 -313.294271) (xy 150.652382 -313.308377)
			(xy 150.703711 -313.330189) (xy 150.751317 -313.359243) (xy 150.794185 -313.394918) (xy 150.831402 -313.436455)
			(xy 150.862175 -313.482968) (xy 150.885847 -313.533465) (xy 150.901915 -313.586872) (xy 150.910035 -313.642048)
			(xy 150.910544 -313.669934) (xy 150.910035 -313.69782) (xy 150.901915 -313.752996) (xy 150.885847 -313.806403)
			(xy 150.862175 -313.8569) (xy 150.831402 -313.903413) (xy 150.794185 -313.94495) (xy 150.788307 -313.949842)
			(xy 152.644106 -313.949842) (xy 152.648066 -313.900788) (xy 152.659843 -313.853004) (xy 152.679134 -313.807728)
			(xy 152.705437 -313.766132) (xy 152.738072 -313.729295) (xy 152.776193 -313.69817) (xy 152.818814 -313.673563)
			(xy 152.86483 -313.656111) (xy 152.913049 -313.646267) (xy 152.962224 -313.644286) (xy 153.011079 -313.650218)
			(xy 153.05835 -313.66391) (xy 153.102812 -313.685008) (xy 153.143315 -313.712964) (xy 153.178808 -313.747056)
			(xy 153.208373 -313.7864) (xy 153.231244 -313.829977) (xy 153.246828 -313.876658) (xy 153.254723 -313.925235)
			(xy 153.255218 -313.949842) (xy 153.594066 -313.949842) (xy 153.598026 -313.900788) (xy 153.609803 -313.853004)
			(xy 153.629094 -313.807728) (xy 153.655397 -313.766132) (xy 153.688032 -313.729295) (xy 153.726153 -313.69817)
			(xy 153.768774 -313.673563) (xy 153.81479 -313.656111) (xy 153.863009 -313.646267) (xy 153.912184 -313.644286)
			(xy 153.961039 -313.650218) (xy 154.00831 -313.66391) (xy 154.052772 -313.685008) (xy 154.093275 -313.712964)
			(xy 154.128768 -313.747056) (xy 154.158333 -313.7864) (xy 154.181204 -313.829977) (xy 154.196788 -313.876658)
			(xy 154.204683 -313.925235) (xy 154.205178 -313.949842) (xy 154.204683 -313.974449) (xy 154.204504 -313.97555)
			(xy 154.523436 -313.97555) (xy 154.523436 -313.924134) (xy 154.531479 -313.873352) (xy 154.547367 -313.824453)
			(xy 154.57071 -313.778641) (xy 154.600931 -313.737045) (xy 154.637287 -313.700689) (xy 154.678883 -313.670468)
			(xy 154.724695 -313.647125) (xy 154.773594 -313.631237) (xy 154.824376 -313.623194) (xy 154.875792 -313.623194)
			(xy 154.926574 -313.631237) (xy 154.975473 -313.647125) (xy 155.021285 -313.670468) (xy 155.062881 -313.700689)
			(xy 155.099237 -313.737045) (xy 155.129458 -313.778641) (xy 155.152801 -313.824453) (xy 155.168689 -313.873352)
			(xy 155.176732 -313.924134) (xy 155.177236 -313.949842) (xy 155.49424 -313.949842) (xy 155.4982 -313.900788)
			(xy 155.509977 -313.853004) (xy 155.529268 -313.807728) (xy 155.555571 -313.766132) (xy 155.588206 -313.729295)
			(xy 155.626327 -313.69817) (xy 155.668948 -313.673563) (xy 155.714964 -313.656111) (xy 155.763183 -313.646267)
			(xy 155.812358 -313.644286) (xy 155.861213 -313.650218) (xy 155.908484 -313.66391) (xy 155.952946 -313.685008)
			(xy 155.993449 -313.712964) (xy 156.028942 -313.747056) (xy 156.058507 -313.7864) (xy 156.081378 -313.829977)
			(xy 156.096962 -313.876658) (xy 156.104857 -313.925235) (xy 156.105352 -313.949842) (xy 156.104857 -313.974449)
			(xy 156.096962 -314.023026) (xy 156.081378 -314.069707) (xy 156.058507 -314.113284) (xy 156.028942 -314.152628)
			(xy 155.993449 -314.18672) (xy 155.952946 -314.214676) (xy 155.908484 -314.235774) (xy 155.861213 -314.249466)
			(xy 155.812358 -314.255398) (xy 155.763183 -314.253417) (xy 155.714964 -314.243573) (xy 155.668948 -314.226121)
			(xy 155.626327 -314.201514) (xy 155.588206 -314.170389) (xy 155.555571 -314.133552) (xy 155.529268 -314.091956)
			(xy 155.509977 -314.04668) (xy 155.4982 -313.998896) (xy 155.49424 -313.949842) (xy 155.177236 -313.949842)
			(xy 155.176732 -313.97555) (xy 155.168689 -314.026332) (xy 155.152801 -314.075231) (xy 155.129458 -314.121043)
			(xy 155.099237 -314.162639) (xy 155.062881 -314.198995) (xy 155.021285 -314.229216) (xy 154.975473 -314.252559)
			(xy 154.926574 -314.268447) (xy 154.875792 -314.27649) (xy 154.824376 -314.27649) (xy 154.773594 -314.268447)
			(xy 154.724695 -314.252559) (xy 154.678883 -314.229216) (xy 154.637287 -314.198995) (xy 154.600931 -314.162639)
			(xy 154.57071 -314.121043) (xy 154.547367 -314.075231) (xy 154.531479 -314.026332) (xy 154.523436 -313.97555)
			(xy 154.204504 -313.97555) (xy 154.196788 -314.023026) (xy 154.181204 -314.069707) (xy 154.158333 -314.113284)
			(xy 154.128768 -314.152628) (xy 154.093275 -314.18672) (xy 154.052772 -314.214676) (xy 154.00831 -314.235774)
			(xy 153.961039 -314.249466) (xy 153.912184 -314.255398) (xy 153.863009 -314.253417) (xy 153.81479 -314.243573)
			(xy 153.768774 -314.226121) (xy 153.726153 -314.201514) (xy 153.688032 -314.170389) (xy 153.655397 -314.133552)
			(xy 153.629094 -314.091956) (xy 153.609803 -314.04668) (xy 153.598026 -313.998896) (xy 153.594066 -313.949842)
			(xy 153.255218 -313.949842) (xy 153.254723 -313.974449) (xy 153.246828 -314.023026) (xy 153.231244 -314.069707)
			(xy 153.208373 -314.113284) (xy 153.178808 -314.152628) (xy 153.143315 -314.18672) (xy 153.102812 -314.214676)
			(xy 153.05835 -314.235774) (xy 153.011079 -314.249466) (xy 152.962224 -314.255398) (xy 152.913049 -314.253417)
			(xy 152.86483 -314.243573) (xy 152.818814 -314.226121) (xy 152.776193 -314.201514) (xy 152.738072 -314.170389)
			(xy 152.705437 -314.133552) (xy 152.679134 -314.091956) (xy 152.659843 -314.04668) (xy 152.648066 -313.998896)
			(xy 152.644106 -313.949842) (xy 150.788307 -313.949842) (xy 150.751317 -313.980625) (xy 150.703711 -314.009679)
			(xy 150.652382 -314.031491) (xy 150.598425 -314.045597) (xy 150.542988 -314.051697) (xy 150.487254 -314.04966)
			(xy 150.432411 -314.03953) (xy 150.379627 -314.021523) (xy 150.330027 -313.996022) (xy 150.284669 -313.963571)
			(xy 150.24452 -313.924862) (xy 150.210434 -313.880719) (xy 150.183138 -313.832084) (xy 150.163215 -313.779993)
			(xy 150.151089 -313.725556) (xy 150.147018 -313.669934) (xy 118.835424 -313.669934) (xy 118.835424 -314.899548)
			(xy 151.693638 -314.899548) (xy 151.697598 -314.850494) (xy 151.709375 -314.80271) (xy 151.728666 -314.757434)
			(xy 151.754969 -314.715838) (xy 151.787604 -314.679001) (xy 151.825725 -314.647876) (xy 151.868346 -314.623269)
			(xy 151.914362 -314.605817) (xy 151.962581 -314.595973) (xy 152.011756 -314.593992) (xy 152.060611 -314.599924)
			(xy 152.107882 -314.613616) (xy 152.152344 -314.634714) (xy 152.192847 -314.66267) (xy 152.22834 -314.696762)
			(xy 152.257905 -314.736106) (xy 152.280776 -314.779683) (xy 152.29636 -314.826364) (xy 152.304255 -314.874941)
			(xy 152.30475 -314.899548) (xy 152.304255 -314.924155) (xy 152.304035 -314.92551) (xy 152.623262 -314.92551)
			(xy 152.623262 -314.874094) (xy 152.631305 -314.823312) (xy 152.647193 -314.774413) (xy 152.670536 -314.728601)
			(xy 152.700757 -314.687005) (xy 152.737113 -314.650649) (xy 152.778709 -314.620428) (xy 152.824521 -314.597085)
			(xy 152.87342 -314.581197) (xy 152.924202 -314.573154) (xy 152.975618 -314.573154) (xy 153.0264 -314.581197)
			(xy 153.075299 -314.597085) (xy 153.121111 -314.620428) (xy 153.162707 -314.650649) (xy 153.199063 -314.687005)
			(xy 153.229284 -314.728601) (xy 153.252627 -314.774413) (xy 153.268515 -314.823312) (xy 153.276558 -314.874094)
			(xy 153.277062 -314.899802) (xy 153.276558 -314.92551) (xy 153.573222 -314.92551) (xy 153.573222 -314.874094)
			(xy 153.581265 -314.823312) (xy 153.597153 -314.774413) (xy 153.620496 -314.728601) (xy 153.650717 -314.687005)
			(xy 153.687073 -314.650649) (xy 153.728669 -314.620428) (xy 153.774481 -314.597085) (xy 153.82338 -314.581197)
			(xy 153.874162 -314.573154) (xy 153.925578 -314.573154) (xy 153.97636 -314.581197) (xy 154.025259 -314.597085)
			(xy 154.071071 -314.620428) (xy 154.112667 -314.650649) (xy 154.149023 -314.687005) (xy 154.179244 -314.728601)
			(xy 154.202587 -314.774413) (xy 154.218475 -314.823312) (xy 154.226518 -314.874094) (xy 154.227022 -314.899802)
			(xy 154.54428 -314.899802) (xy 154.54824 -314.850748) (xy 154.560017 -314.802964) (xy 154.579308 -314.757688)
			(xy 154.605611 -314.716092) (xy 154.638246 -314.679255) (xy 154.676367 -314.64813) (xy 154.718988 -314.623523)
			(xy 154.765004 -314.606071) (xy 154.813223 -314.596227) (xy 154.862398 -314.594246) (xy 154.911253 -314.600178)
			(xy 154.958524 -314.61387) (xy 155.002986 -314.634968) (xy 155.043489 -314.662924) (xy 155.078982 -314.697016)
			(xy 155.108547 -314.73636) (xy 155.131418 -314.779937) (xy 155.147002 -314.826618) (xy 155.154897 -314.875195)
			(xy 155.155392 -314.899802) (xy 155.49424 -314.899802) (xy 155.4982 -314.850748) (xy 155.509977 -314.802964)
			(xy 155.529268 -314.757688) (xy 155.555571 -314.716092) (xy 155.588206 -314.679255) (xy 155.626327 -314.64813)
			(xy 155.668948 -314.623523) (xy 155.714964 -314.606071) (xy 155.763183 -314.596227) (xy 155.812358 -314.594246)
			(xy 155.861213 -314.600178) (xy 155.908484 -314.61387) (xy 155.952946 -314.634968) (xy 155.993449 -314.662924)
			(xy 156.028942 -314.697016) (xy 156.058507 -314.73636) (xy 156.081378 -314.779937) (xy 156.096962 -314.826618)
			(xy 156.104857 -314.875195) (xy 156.105352 -314.899802) (xy 156.104857 -314.924409) (xy 156.096962 -314.972986)
			(xy 156.081378 -315.019667) (xy 156.058507 -315.063244) (xy 156.028942 -315.102588) (xy 155.993449 -315.13668)
			(xy 155.952946 -315.164636) (xy 155.908484 -315.185734) (xy 155.861213 -315.199426) (xy 155.812358 -315.205358)
			(xy 155.763183 -315.203377) (xy 155.714964 -315.193533) (xy 155.668948 -315.176081) (xy 155.626327 -315.151474)
			(xy 155.588206 -315.120349) (xy 155.555571 -315.083512) (xy 155.529268 -315.041916) (xy 155.509977 -314.99664)
			(xy 155.4982 -314.948856) (xy 155.49424 -314.899802) (xy 155.155392 -314.899802) (xy 155.154897 -314.924409)
			(xy 155.147002 -314.972986) (xy 155.131418 -315.019667) (xy 155.108547 -315.063244) (xy 155.078982 -315.102588)
			(xy 155.043489 -315.13668) (xy 155.002986 -315.164636) (xy 154.958524 -315.185734) (xy 154.911253 -315.199426)
			(xy 154.862398 -315.205358) (xy 154.813223 -315.203377) (xy 154.765004 -315.193533) (xy 154.718988 -315.176081)
			(xy 154.676367 -315.151474) (xy 154.638246 -315.120349) (xy 154.605611 -315.083512) (xy 154.579308 -315.041916)
			(xy 154.560017 -314.99664) (xy 154.54824 -314.948856) (xy 154.54428 -314.899802) (xy 154.227022 -314.899802)
			(xy 154.226518 -314.92551) (xy 154.218475 -314.976292) (xy 154.202587 -315.025191) (xy 154.179244 -315.071003)
			(xy 154.149023 -315.112599) (xy 154.112667 -315.148955) (xy 154.071071 -315.179176) (xy 154.025259 -315.202519)
			(xy 153.97636 -315.218407) (xy 153.925578 -315.22645) (xy 153.874162 -315.22645) (xy 153.82338 -315.218407)
			(xy 153.774481 -315.202519) (xy 153.728669 -315.179176) (xy 153.687073 -315.148955) (xy 153.650717 -315.112599)
			(xy 153.620496 -315.071003) (xy 153.597153 -315.025191) (xy 153.581265 -314.976292) (xy 153.573222 -314.92551)
			(xy 153.276558 -314.92551) (xy 153.268515 -314.976292) (xy 153.252627 -315.025191) (xy 153.229284 -315.071003)
			(xy 153.199063 -315.112599) (xy 153.162707 -315.148955) (xy 153.121111 -315.179176) (xy 153.075299 -315.202519)
			(xy 153.0264 -315.218407) (xy 152.975618 -315.22645) (xy 152.924202 -315.22645) (xy 152.87342 -315.218407)
			(xy 152.824521 -315.202519) (xy 152.778709 -315.179176) (xy 152.737113 -315.148955) (xy 152.700757 -315.112599)
			(xy 152.670536 -315.071003) (xy 152.647193 -315.025191) (xy 152.631305 -314.976292) (xy 152.623262 -314.92551)
			(xy 152.304035 -314.92551) (xy 152.29636 -314.972732) (xy 152.280776 -315.019413) (xy 152.257905 -315.06299)
			(xy 152.22834 -315.102334) (xy 152.192847 -315.136426) (xy 152.152344 -315.164382) (xy 152.107882 -315.18548)
			(xy 152.060611 -315.199172) (xy 152.011756 -315.205104) (xy 151.962581 -315.203123) (xy 151.914362 -315.193279)
			(xy 151.868346 -315.175827) (xy 151.825725 -315.15122) (xy 151.787604 -315.120095) (xy 151.754969 -315.083258)
			(xy 151.728666 -315.041662) (xy 151.709375 -314.996386) (xy 151.697598 -314.948602) (xy 151.693638 -314.899548)
			(xy 118.835424 -314.899548) (xy 118.835424 -315.849762) (xy 152.644106 -315.849762) (xy 152.648066 -315.800708)
			(xy 152.659843 -315.752924) (xy 152.679134 -315.707648) (xy 152.705437 -315.666052) (xy 152.738072 -315.629215)
			(xy 152.776193 -315.59809) (xy 152.818814 -315.573483) (xy 152.86483 -315.556031) (xy 152.913049 -315.546187)
			(xy 152.962224 -315.544206) (xy 153.011079 -315.550138) (xy 153.05835 -315.56383) (xy 153.102812 -315.584928)
			(xy 153.143315 -315.612884) (xy 153.178808 -315.646976) (xy 153.208373 -315.68632) (xy 153.231244 -315.729897)
			(xy 153.246828 -315.776578) (xy 153.254723 -315.825155) (xy 153.255218 -315.849762) (xy 153.594066 -315.849762)
			(xy 153.598026 -315.800708) (xy 153.609803 -315.752924) (xy 153.629094 -315.707648) (xy 153.655397 -315.666052)
			(xy 153.688032 -315.629215) (xy 153.726153 -315.59809) (xy 153.768774 -315.573483) (xy 153.81479 -315.556031)
			(xy 153.863009 -315.546187) (xy 153.912184 -315.544206) (xy 153.961039 -315.550138) (xy 154.00831 -315.56383)
			(xy 154.052772 -315.584928) (xy 154.093275 -315.612884) (xy 154.128768 -315.646976) (xy 154.158333 -315.68632)
			(xy 154.181204 -315.729897) (xy 154.196788 -315.776578) (xy 154.204683 -315.825155) (xy 154.205178 -315.849762)
			(xy 154.54428 -315.849762) (xy 154.54824 -315.800708) (xy 154.560017 -315.752924) (xy 154.579308 -315.707648)
			(xy 154.605611 -315.666052) (xy 154.638246 -315.629215) (xy 154.676367 -315.59809) (xy 154.718988 -315.573483)
			(xy 154.765004 -315.556031) (xy 154.813223 -315.546187) (xy 154.862398 -315.544206) (xy 154.911253 -315.550138)
			(xy 154.958524 -315.56383) (xy 155.002986 -315.584928) (xy 155.043489 -315.612884) (xy 155.078982 -315.646976)
			(xy 155.108547 -315.68632) (xy 155.131418 -315.729897) (xy 155.147002 -315.776578) (xy 155.154897 -315.825155)
			(xy 155.155392 -315.849762) (xy 155.154897 -315.874369) (xy 155.154718 -315.87547) (xy 155.473396 -315.87547)
			(xy 155.473396 -315.824054) (xy 155.481439 -315.773272) (xy 155.497327 -315.724373) (xy 155.52067 -315.678561)
			(xy 155.550891 -315.636965) (xy 155.587247 -315.600609) (xy 155.628843 -315.570388) (xy 155.674655 -315.547045)
			(xy 155.723554 -315.531157) (xy 155.774336 -315.523114) (xy 155.825752 -315.523114) (xy 155.876534 -315.531157)
			(xy 155.925433 -315.547045) (xy 155.971245 -315.570388) (xy 156.012841 -315.600609) (xy 156.049197 -315.636965)
			(xy 156.079418 -315.678561) (xy 156.102761 -315.724373) (xy 156.118649 -315.773272) (xy 156.126692 -315.824054)
			(xy 156.127196 -315.849762) (xy 156.126692 -315.87547) (xy 156.118649 -315.926252) (xy 156.102761 -315.975151)
			(xy 156.079418 -316.020963) (xy 156.049197 -316.062559) (xy 156.012841 -316.098915) (xy 155.971245 -316.129136)
			(xy 155.925433 -316.152479) (xy 155.876534 -316.168367) (xy 155.825752 -316.17641) (xy 155.774336 -316.17641)
			(xy 155.723554 -316.168367) (xy 155.674655 -316.152479) (xy 155.628843 -316.129136) (xy 155.587247 -316.098915)
			(xy 155.550891 -316.062559) (xy 155.52067 -316.020963) (xy 155.497327 -315.975151) (xy 155.481439 -315.926252)
			(xy 155.473396 -315.87547) (xy 155.154718 -315.87547) (xy 155.147002 -315.922946) (xy 155.131418 -315.969627)
			(xy 155.108547 -316.013204) (xy 155.078982 -316.052548) (xy 155.043489 -316.08664) (xy 155.002986 -316.114596)
			(xy 154.958524 -316.135694) (xy 154.911253 -316.149386) (xy 154.862398 -316.155318) (xy 154.813223 -316.153337)
			(xy 154.765004 -316.143493) (xy 154.718988 -316.126041) (xy 154.676367 -316.101434) (xy 154.638246 -316.070309)
			(xy 154.605611 -316.033472) (xy 154.579308 -315.991876) (xy 154.560017 -315.9466) (xy 154.54824 -315.898816)
			(xy 154.54428 -315.849762) (xy 154.205178 -315.849762) (xy 154.204683 -315.874369) (xy 154.196788 -315.922946)
			(xy 154.181204 -315.969627) (xy 154.158333 -316.013204) (xy 154.128768 -316.052548) (xy 154.093275 -316.08664)
			(xy 154.052772 -316.114596) (xy 154.00831 -316.135694) (xy 153.961039 -316.149386) (xy 153.912184 -316.155318)
			(xy 153.863009 -316.153337) (xy 153.81479 -316.143493) (xy 153.768774 -316.126041) (xy 153.726153 -316.101434)
			(xy 153.688032 -316.070309) (xy 153.655397 -316.033472) (xy 153.629094 -315.991876) (xy 153.609803 -315.9466)
			(xy 153.598026 -315.898816) (xy 153.594066 -315.849762) (xy 153.255218 -315.849762) (xy 153.254723 -315.874369)
			(xy 153.246828 -315.922946) (xy 153.231244 -315.969627) (xy 153.208373 -316.013204) (xy 153.178808 -316.052548)
			(xy 153.143315 -316.08664) (xy 153.102812 -316.114596) (xy 153.05835 -316.135694) (xy 153.011079 -316.149386)
			(xy 152.962224 -316.155318) (xy 152.913049 -316.153337) (xy 152.86483 -316.143493) (xy 152.818814 -316.126041)
			(xy 152.776193 -316.101434) (xy 152.738072 -316.070309) (xy 152.705437 -316.033472) (xy 152.679134 -315.991876)
			(xy 152.659843 -315.9466) (xy 152.648066 -315.898816) (xy 152.644106 -315.849762) (xy 118.835424 -315.849762)
			(xy 118.835424 -320.08064) (xy 119.41683 -320.08064) (xy 119.417366 -320.051724) (xy 119.426089 -319.994553)
			(xy 119.443343 -319.939354) (xy 119.468732 -319.887392) (xy 119.501673 -319.839857) (xy 119.541411 -319.79784)
			(xy 119.563896 -319.77965) (xy 119.57267 -319.772011) (xy 119.582872 -319.751134) (xy 119.583454 -319.739518)
			(xy 119.583454 -319.659762) (xy 119.582939 -319.648127) (xy 119.572735 -319.627216) (xy 119.563896 -319.61963)
			(xy 119.541426 -319.601423) (xy 119.50169 -319.559407) (xy 119.46875 -319.511875) (xy 119.443359 -319.459917)
			(xy 119.4261 -319.404722) (xy 119.417367 -319.347555) (xy 119.41683 -319.31864) (xy 119.417293 -319.291386)
			(xy 119.425045 -319.237433) (xy 119.440398 -319.185133) (xy 119.463039 -319.135551) (xy 119.492506 -319.089696)
			(xy 119.5282 -319.048501) (xy 119.569394 -319.012807) (xy 119.615249 -318.98334) (xy 119.664831 -318.960699)
			(xy 119.717132 -318.945346) (xy 119.771084 -318.937593) (xy 119.798338 -318.937132) (xy 119.827254 -318.937683)
			(xy 119.884424 -318.946403) (xy 119.939623 -318.963654) (xy 119.991585 -318.989039) (xy 120.03912 -319.021978)
			(xy 120.081137 -319.061714) (xy 120.099328 -319.084198) (xy 120.106933 -319.093008) (xy 120.127835 -319.10319)
			(xy 120.13946 -319.103756) (xy 120.219216 -319.103756) (xy 120.23085 -319.103227) (xy 120.25176 -319.093033)
			(xy 120.259348 -319.084198) (xy 120.276101 -319.063415) (xy 120.314455 -319.026285) (xy 120.357609 -318.994863)
			(xy 120.404723 -318.969764) (xy 120.454875 -318.951478) (xy 120.507086 -318.940361) (xy 120.560338 -318.936631)
			(xy 120.61359 -318.940361) (xy 120.665801 -318.951478) (xy 120.715953 -318.969764) (xy 120.763067 -318.994863)
			(xy 120.806221 -319.026285) (xy 120.844575 -319.063415) (xy 120.861328 -319.084198) (xy 120.868933 -319.093008)
			(xy 120.889835 -319.10319) (xy 120.90146 -319.103756) (xy 120.981216 -319.103756) (xy 120.99285 -319.103227)
			(xy 121.01376 -319.093033) (xy 121.021348 -319.084198) (xy 121.038101 -319.063415) (xy 121.076455 -319.026285)
			(xy 121.119609 -318.994863) (xy 121.166723 -318.969764) (xy 121.216875 -318.951478) (xy 121.269086 -318.940361)
			(xy 121.322338 -318.936631) (xy 121.37559 -318.940361) (xy 121.427801 -318.951478) (xy 121.477953 -318.969764)
			(xy 121.525067 -318.994863) (xy 121.568221 -319.026285) (xy 121.606575 -319.063415) (xy 121.623328 -319.084198)
			(xy 121.630933 -319.093008) (xy 121.651835 -319.10319) (xy 121.66346 -319.103756) (xy 121.743216 -319.103756)
			(xy 121.75485 -319.103227) (xy 121.77576 -319.093033) (xy 121.783348 -319.084198) (xy 121.800101 -319.063415)
			(xy 121.838455 -319.026285) (xy 121.881609 -318.994863) (xy 121.928723 -318.969764) (xy 121.978875 -318.951478)
			(xy 122.031086 -318.940361) (xy 122.084338 -318.936631) (xy 122.13759 -318.940361) (xy 122.189801 -318.951478)
			(xy 122.239953 -318.969764) (xy 122.287067 -318.994863) (xy 122.330221 -319.026285) (xy 122.368575 -319.063415)
			(xy 122.385328 -319.084198) (xy 122.392933 -319.093008) (xy 122.413835 -319.10319) (xy 122.42546 -319.103756)
			(xy 122.505216 -319.103756) (xy 122.51685 -319.103227) (xy 122.53776 -319.093033) (xy 122.545348 -319.084198)
			(xy 122.562101 -319.063415) (xy 122.600455 -319.026285) (xy 122.643609 -318.994863) (xy 122.690723 -318.969764)
			(xy 122.740875 -318.951478) (xy 122.793086 -318.940361) (xy 122.846338 -318.936631) (xy 122.89959 -318.940361)
			(xy 122.951801 -318.951478) (xy 123.001953 -318.969764) (xy 123.049067 -318.994863) (xy 123.092221 -319.026285)
			(xy 123.130575 -319.063415) (xy 123.147328 -319.084198) (xy 123.154933 -319.093008) (xy 123.175835 -319.10319)
			(xy 123.18746 -319.103756) (xy 123.267216 -319.103756) (xy 123.27885 -319.103227) (xy 123.29976 -319.093033)
			(xy 123.307348 -319.084198) (xy 123.324101 -319.063415) (xy 123.362455 -319.026285) (xy 123.405609 -318.994863)
			(xy 123.452723 -318.969764) (xy 123.502875 -318.951478) (xy 123.555086 -318.940361) (xy 123.608338 -318.936631)
			(xy 123.66159 -318.940361) (xy 123.713801 -318.951478) (xy 123.763953 -318.969764) (xy 123.811067 -318.994863)
			(xy 123.854221 -319.026285) (xy 123.892575 -319.063415) (xy 123.909328 -319.084198) (xy 123.916933 -319.093008)
			(xy 123.937835 -319.10319) (xy 123.94946 -319.103756) (xy 124.029216 -319.103756) (xy 124.04085 -319.103227)
			(xy 124.06176 -319.093033) (xy 124.069348 -319.084198) (xy 124.086101 -319.063415) (xy 124.124455 -319.026285)
			(xy 124.167609 -318.994863) (xy 124.214723 -318.969764) (xy 124.264875 -318.951478) (xy 124.317086 -318.940361)
			(xy 124.370338 -318.936631) (xy 124.42359 -318.940361) (xy 124.475801 -318.951478) (xy 124.525953 -318.969764)
			(xy 124.573067 -318.994863) (xy 124.616221 -319.026285) (xy 124.654575 -319.063415) (xy 124.671328 -319.084198)
			(xy 124.678933 -319.093008) (xy 124.699835 -319.10319) (xy 124.71146 -319.103756) (xy 124.791216 -319.103756)
			(xy 124.80285 -319.103227) (xy 124.82376 -319.093033) (xy 124.831348 -319.084198) (xy 124.848101 -319.063415)
			(xy 124.886455 -319.026285) (xy 124.929609 -318.994863) (xy 124.976723 -318.969764) (xy 125.026875 -318.951478)
			(xy 125.079086 -318.940361) (xy 125.132338 -318.936631) (xy 125.18559 -318.940361) (xy 125.237801 -318.951478)
			(xy 125.287953 -318.969764) (xy 125.335067 -318.994863) (xy 125.378221 -319.026285) (xy 125.416575 -319.063415)
			(xy 125.433328 -319.084198) (xy 125.440933 -319.093008) (xy 125.461835 -319.10319) (xy 125.47346 -319.103756)
			(xy 125.553216 -319.103756) (xy 125.56485 -319.103227) (xy 125.58576 -319.093033) (xy 125.593348 -319.084198)
			(xy 125.610101 -319.063415) (xy 125.648455 -319.026285) (xy 125.691609 -318.994863) (xy 125.738723 -318.969764)
			(xy 125.788875 -318.951478) (xy 125.841086 -318.940361) (xy 125.894338 -318.936631) (xy 125.94759 -318.940361)
			(xy 125.999801 -318.951478) (xy 126.049953 -318.969764) (xy 126.097067 -318.994863) (xy 126.140221 -319.026285)
			(xy 126.178575 -319.063415) (xy 126.195328 -319.084198) (xy 126.202933 -319.093008) (xy 126.223835 -319.10319)
			(xy 126.23546 -319.103756) (xy 126.315216 -319.103756) (xy 126.32685 -319.103227) (xy 126.34776 -319.093033)
			(xy 126.355348 -319.084198) (xy 126.372101 -319.063415) (xy 126.410455 -319.026285) (xy 126.453609 -318.994863)
			(xy 126.500723 -318.969764) (xy 126.550875 -318.951478) (xy 126.603086 -318.940361) (xy 126.656338 -318.936631)
			(xy 126.70959 -318.940361) (xy 126.761801 -318.951478) (xy 126.811953 -318.969764) (xy 126.859067 -318.994863)
			(xy 126.902221 -319.026285) (xy 126.940575 -319.063415) (xy 126.957328 -319.084198) (xy 126.964933 -319.093008)
			(xy 126.985835 -319.10319) (xy 126.99746 -319.103756) (xy 127.077216 -319.103756) (xy 127.08885 -319.103227)
			(xy 127.10976 -319.093033) (xy 127.117348 -319.084198) (xy 127.134101 -319.063415) (xy 127.172455 -319.026285)
			(xy 127.215609 -318.994863) (xy 127.262723 -318.969764) (xy 127.312875 -318.951478) (xy 127.365086 -318.940361)
			(xy 127.418338 -318.936631) (xy 127.47159 -318.940361) (xy 127.523801 -318.951478) (xy 127.573953 -318.969764)
			(xy 127.621067 -318.994863) (xy 127.664221 -319.026285) (xy 127.702575 -319.063415) (xy 127.719328 -319.084198)
			(xy 127.726933 -319.093008) (xy 127.747835 -319.10319) (xy 127.75946 -319.103756) (xy 127.839216 -319.103756)
			(xy 127.85085 -319.103227) (xy 127.87176 -319.093033) (xy 127.879348 -319.084198) (xy 127.897568 -319.061739)
			(xy 127.939582 -319.022002) (xy 127.987111 -318.989061) (xy 128.039066 -318.963668) (xy 128.094259 -318.946406)
			(xy 128.151424 -318.937671) (xy 128.180338 -318.937132) (xy 128.21046 -318.937747) (xy 128.269954 -318.947218)
			(xy 128.327221 -318.965919) (xy 128.380839 -318.993385) (xy 128.429475 -319.028934) (xy 128.451102 -319.049908)
			(xy 128.458506 -319.056742) (xy 128.477102 -319.064465) (xy 128.48717 -319.064894) (xy 128.559306 -319.064894)
			(xy 128.569376 -319.064473) (xy 128.587974 -319.056749) (xy 128.595374 -319.049908) (xy 128.616988 -319.028916)
			(xy 128.66562 -318.993349) (xy 128.719239 -318.965871) (xy 128.776512 -318.947166) (xy 128.836013 -318.937698)
			(xy 128.866138 -318.937132) (xy 128.893394 -318.93752) (xy 128.947349 -318.945283) (xy 128.999651 -318.960646)
			(xy 129.049234 -318.983296) (xy 129.095089 -319.012771) (xy 129.136282 -319.048473) (xy 129.171975 -319.089673)
			(xy 129.201442 -319.135534) (xy 129.224082 -319.185122) (xy 129.239434 -319.237427) (xy 129.247186 -319.291384)
			(xy 129.247646 -319.31864) (xy 129.247105 -319.347556) (xy 129.238383 -319.404727) (xy 129.221131 -319.459927)
			(xy 129.195744 -319.511889) (xy 129.162803 -319.559423) (xy 129.123064 -319.60144) (xy 129.10058 -319.61963)
			(xy 129.091766 -319.62723) (xy 129.081587 -319.648136) (xy 129.081022 -319.659762) (xy 129.081022 -319.739518)
			(xy 129.081557 -319.751151) (xy 129.091748 -319.772061) (xy 129.10058 -319.77965) (xy 129.123035 -319.797874)
			(xy 129.162773 -319.839887) (xy 129.195716 -319.887414) (xy 129.221109 -319.939369) (xy 129.238372 -319.994561)
			(xy 129.247107 -320.051726) (xy 129.247646 -320.08064) (xy 129.24716 -320.107891) (xy 129.239399 -320.161836)
			(xy 129.22404 -320.214129) (xy 129.201397 -320.263703) (xy 129.17193 -320.309552) (xy 129.136239 -320.350741)
			(xy 129.09505 -320.386432) (xy 129.049202 -320.415898) (xy 128.999627 -320.438541) (xy 128.947334 -320.453899)
			(xy 128.893389 -320.46166) (xy 128.866138 -320.462148) (xy 128.836016 -320.461554) (xy 128.77652 -320.452079)
			(xy 128.719252 -320.433373) (xy 128.665635 -320.405903) (xy 128.617 -320.370349) (xy 128.595374 -320.349372)
			(xy 128.58798 -320.342524) (xy 128.569376 -320.33481) (xy 128.559306 -320.334386) (xy 128.48717 -320.334386)
			(xy 128.477096 -320.334773) (xy 128.458497 -320.342518) (xy 128.451102 -320.349372) (xy 128.429495 -320.370372)
			(xy 128.380862 -320.405938) (xy 128.327241 -320.433415) (xy 128.269967 -320.452119) (xy 128.210464 -320.461584)
			(xy 128.180338 -320.462148) (xy 128.151421 -320.461622) (xy 128.094249 -320.452898) (xy 128.03905 -320.435642)
			(xy 127.987088 -320.410252) (xy 127.939554 -320.377309) (xy 127.897537 -320.337568) (xy 127.879348 -320.315082)
			(xy 127.871713 -320.306303) (xy 127.850833 -320.296105) (xy 127.839216 -320.295524) (xy 127.75946 -320.295524)
			(xy 127.747826 -320.296046) (xy 127.726916 -320.306246) (xy 127.719328 -320.315082) (xy 127.702575 -320.335865)
			(xy 127.664221 -320.372995) (xy 127.621067 -320.404417) (xy 127.573953 -320.429516) (xy 127.523801 -320.447802)
			(xy 127.47159 -320.458919) (xy 127.418338 -320.462649) (xy 127.365086 -320.458919) (xy 127.312875 -320.447802)
			(xy 127.262723 -320.429516) (xy 127.215609 -320.404417) (xy 127.172455 -320.372995) (xy 127.134101 -320.335865)
			(xy 127.117348 -320.315082) (xy 127.109713 -320.306303) (xy 127.088833 -320.296105) (xy 127.077216 -320.295524)
			(xy 126.99746 -320.295524) (xy 126.985826 -320.296046) (xy 126.964916 -320.306246) (xy 126.957328 -320.315082)
			(xy 126.940575 -320.335865) (xy 126.902221 -320.372995) (xy 126.859067 -320.404417) (xy 126.811953 -320.429516)
			(xy 126.761801 -320.447802) (xy 126.70959 -320.458919) (xy 126.656338 -320.462649) (xy 126.603086 -320.458919)
			(xy 126.550875 -320.447802) (xy 126.500723 -320.429516) (xy 126.453609 -320.404417) (xy 126.410455 -320.372995)
			(xy 126.372101 -320.335865) (xy 126.355348 -320.315082) (xy 126.347713 -320.306303) (xy 126.326833 -320.296105)
			(xy 126.315216 -320.295524) (xy 126.23546 -320.295524) (xy 126.223826 -320.296046) (xy 126.202916 -320.306246)
			(xy 126.195328 -320.315082) (xy 126.178575 -320.335865) (xy 126.140221 -320.372995) (xy 126.097067 -320.404417)
			(xy 126.049953 -320.429516) (xy 125.999801 -320.447802) (xy 125.94759 -320.458919) (xy 125.894338 -320.462649)
			(xy 125.841086 -320.458919) (xy 125.788875 -320.447802) (xy 125.738723 -320.429516) (xy 125.691609 -320.404417)
			(xy 125.648455 -320.372995) (xy 125.610101 -320.335865) (xy 125.593348 -320.315082) (xy 125.585713 -320.306303)
			(xy 125.564833 -320.296105) (xy 125.553216 -320.295524) (xy 125.47346 -320.295524) (xy 125.461826 -320.296046)
			(xy 125.440916 -320.306246) (xy 125.433328 -320.315082) (xy 125.416575 -320.335865) (xy 125.378221 -320.372995)
			(xy 125.335067 -320.404417) (xy 125.287953 -320.429516) (xy 125.237801 -320.447802) (xy 125.18559 -320.458919)
			(xy 125.132338 -320.462649) (xy 125.079086 -320.458919) (xy 125.026875 -320.447802) (xy 124.976723 -320.429516)
			(xy 124.929609 -320.404417) (xy 124.886455 -320.372995) (xy 124.848101 -320.335865) (xy 124.831348 -320.315082)
			(xy 124.823713 -320.306303) (xy 124.802833 -320.296105) (xy 124.791216 -320.295524) (xy 124.71146 -320.295524)
			(xy 124.699826 -320.296046) (xy 124.678916 -320.306246) (xy 124.671328 -320.315082) (xy 124.654575 -320.335865)
			(xy 124.616221 -320.372995) (xy 124.573067 -320.404417) (xy 124.525953 -320.429516) (xy 124.475801 -320.447802)
			(xy 124.42359 -320.458919) (xy 124.370338 -320.462649) (xy 124.317086 -320.458919) (xy 124.264875 -320.447802)
			(xy 124.214723 -320.429516) (xy 124.167609 -320.404417) (xy 124.124455 -320.372995) (xy 124.086101 -320.335865)
			(xy 124.069348 -320.315082) (xy 124.061713 -320.306303) (xy 124.040833 -320.296105) (xy 124.029216 -320.295524)
			(xy 123.94946 -320.295524) (xy 123.937826 -320.296046) (xy 123.916916 -320.306246) (xy 123.909328 -320.315082)
			(xy 123.892575 -320.335865) (xy 123.854221 -320.372995) (xy 123.811067 -320.404417) (xy 123.763953 -320.429516)
			(xy 123.713801 -320.447802) (xy 123.66159 -320.458919) (xy 123.608338 -320.462649) (xy 123.555086 -320.458919)
			(xy 123.502875 -320.447802) (xy 123.452723 -320.429516) (xy 123.405609 -320.404417) (xy 123.362455 -320.372995)
			(xy 123.324101 -320.335865) (xy 123.307348 -320.315082) (xy 123.299713 -320.306303) (xy 123.278833 -320.296105)
			(xy 123.267216 -320.295524) (xy 123.18746 -320.295524) (xy 123.175826 -320.296046) (xy 123.154916 -320.306246)
			(xy 123.147328 -320.315082) (xy 123.130575 -320.335865) (xy 123.092221 -320.372995) (xy 123.049067 -320.404417)
			(xy 123.001953 -320.429516) (xy 122.951801 -320.447802) (xy 122.89959 -320.458919) (xy 122.846338 -320.462649)
			(xy 122.793086 -320.458919) (xy 122.740875 -320.447802) (xy 122.690723 -320.429516) (xy 122.643609 -320.404417)
			(xy 122.600455 -320.372995) (xy 122.562101 -320.335865) (xy 122.545348 -320.315082) (xy 122.537713 -320.306303)
			(xy 122.516833 -320.296105) (xy 122.505216 -320.295524) (xy 122.42546 -320.295524) (xy 122.413826 -320.296046)
			(xy 122.392916 -320.306246) (xy 122.385328 -320.315082) (xy 122.368575 -320.335865) (xy 122.330221 -320.372995)
			(xy 122.287067 -320.404417) (xy 122.239953 -320.429516) (xy 122.189801 -320.447802) (xy 122.13759 -320.458919)
			(xy 122.084338 -320.462649) (xy 122.031086 -320.458919) (xy 121.978875 -320.447802) (xy 121.928723 -320.429516)
			(xy 121.881609 -320.404417) (xy 121.838455 -320.372995) (xy 121.800101 -320.335865) (xy 121.783348 -320.315082)
			(xy 121.775713 -320.306303) (xy 121.754833 -320.296105) (xy 121.743216 -320.295524) (xy 121.66346 -320.295524)
			(xy 121.651826 -320.296046) (xy 121.630916 -320.306246) (xy 121.623328 -320.315082) (xy 121.606575 -320.335865)
			(xy 121.568221 -320.372995) (xy 121.525067 -320.404417) (xy 121.477953 -320.429516) (xy 121.427801 -320.447802)
			(xy 121.37559 -320.458919) (xy 121.322338 -320.462649) (xy 121.269086 -320.458919) (xy 121.216875 -320.447802)
			(xy 121.166723 -320.429516) (xy 121.119609 -320.404417) (xy 121.076455 -320.372995) (xy 121.038101 -320.335865)
			(xy 121.021348 -320.315082) (xy 121.013713 -320.306303) (xy 120.992833 -320.296105) (xy 120.981216 -320.295524)
			(xy 120.90146 -320.295524) (xy 120.889826 -320.296046) (xy 120.868916 -320.306246) (xy 120.861328 -320.315082)
			(xy 120.844575 -320.335865) (xy 120.806221 -320.372995) (xy 120.763067 -320.404417) (xy 120.715953 -320.429516)
			(xy 120.665801 -320.447802) (xy 120.61359 -320.458919) (xy 120.560338 -320.462649) (xy 120.507086 -320.458919)
			(xy 120.454875 -320.447802) (xy 120.404723 -320.429516) (xy 120.357609 -320.404417) (xy 120.314455 -320.372995)
			(xy 120.276101 -320.335865) (xy 120.259348 -320.315082) (xy 120.251713 -320.306303) (xy 120.230833 -320.296105)
			(xy 120.219216 -320.295524) (xy 120.13946 -320.295524) (xy 120.127826 -320.296046) (xy 120.106916 -320.306246)
			(xy 120.099328 -320.315082) (xy 120.081117 -320.337548) (xy 120.039102 -320.377285) (xy 119.991571 -320.410227)
			(xy 119.939614 -320.435618) (xy 119.88442 -320.452878) (xy 119.827253 -320.461611) (xy 119.798338 -320.462148)
			(xy 119.77109 -320.461587) (xy 119.717147 -320.453836) (xy 119.664856 -320.438488) (xy 119.615281 -320.415854)
			(xy 119.569433 -320.386396) (xy 119.528243 -320.350712) (xy 119.492551 -320.30953) (xy 119.463083 -320.263687)
			(xy 119.440439 -320.214117) (xy 119.42508 -320.16183) (xy 119.417319 -320.107888) (xy 119.41683 -320.08064)
			(xy 118.835424 -320.08064) (xy 118.835424 -327.019254) (xy 130.267135 -327.019254) (xy 130.267135 -326.964746)
			(xy 130.274892 -326.910792) (xy 130.290249 -326.858491) (xy 130.312893 -326.808908) (xy 130.342363 -326.763052)
			(xy 130.378059 -326.721857) (xy 130.419254 -326.686162) (xy 130.46511 -326.656692) (xy 130.514693 -326.634049)
			(xy 130.566994 -326.618692) (xy 130.620948 -326.610935) (xy 130.648202 -326.610472) (xy 130.675749 -326.610902)
			(xy 130.730271 -326.618822) (xy 130.783085 -326.634511) (xy 130.833088 -326.657641) (xy 130.87924 -326.687732)
			(xy 130.920577 -326.724155) (xy 130.938778 -326.744838) (xy 130.94677 -326.75338) (xy 130.968227 -326.762635)
			(xy 130.979926 -326.762618) (xy 131.072382 -326.758046) (xy 131.092702 -326.746616) (xy 131.09956 -326.736964)
			(xy 131.114868 -326.715586) (xy 131.150479 -326.6769) (xy 131.191069 -326.643473) (xy 131.235866 -326.615941)
			(xy 131.284021 -326.594825) (xy 131.334621 -326.580526) (xy 131.386705 -326.573314) (xy 131.412996 -326.57288)
			(xy 131.439561 -326.573317) (xy 131.492178 -326.580685) (xy 131.543265 -326.595277) (xy 131.591834 -326.616813)
			(xy 131.636948 -326.644876) (xy 131.677735 -326.678924) (xy 131.713406 -326.718299) (xy 131.728718 -326.740012)
			(xy 131.73583 -326.75068) (xy 131.758436 -326.762364) (xy 131.868926 -326.761094) (xy 131.891278 -326.748648)
			(xy 131.898136 -326.73798) (xy 131.913211 -326.715247) (xy 131.948898 -326.673993) (xy 131.9901 -326.638245)
			(xy 132.035975 -326.608733) (xy 132.085588 -326.586058) (xy 132.137924 -326.570684) (xy 132.191918 -326.562925)
			(xy 132.219192 -326.562466) (xy 132.246443 -326.562981) (xy 132.300391 -326.570736) (xy 132.352687 -326.586091)
			(xy 132.402264 -326.608731) (xy 132.448115 -326.638197) (xy 132.489306 -326.673888) (xy 132.524998 -326.715078)
			(xy 132.554465 -326.760928) (xy 132.577107 -326.810506) (xy 132.592462 -326.862801) (xy 132.600219 -326.916749)
			(xy 132.600219 -326.971251) (xy 132.592462 -327.025199) (xy 132.577107 -327.077494) (xy 132.554465 -327.127072)
			(xy 132.524998 -327.172922) (xy 132.489306 -327.214112) (xy 132.448115 -327.249803) (xy 132.402264 -327.279269)
			(xy 132.352687 -327.301909) (xy 132.300391 -327.317264) (xy 132.246443 -327.325019) (xy 132.219192 -327.325482)
			(xy 132.192628 -327.325027) (xy 132.140013 -327.317659) (xy 132.088928 -327.303068) (xy 132.040359 -327.281534)
			(xy 131.995245 -327.253475) (xy 131.954457 -327.219431) (xy 131.918784 -327.180061) (xy 131.90347 -327.15835)
			(xy 131.896358 -327.147682) (xy 131.873752 -327.135998) (xy 131.763262 -327.137268) (xy 131.74091 -327.149714)
			(xy 131.734052 -327.160382) (xy 131.718907 -327.183066) (xy 131.683232 -327.224323) (xy 131.642043 -327.260075)
			(xy 131.59618 -327.289594) (xy 131.546579 -327.312277) (xy 131.494252 -327.32766) (xy 131.440267 -327.335431)
			(xy 131.412996 -327.335896) (xy 131.385452 -327.335374) (xy 131.330935 -327.32747) (xy 131.278125 -327.311798)
			(xy 131.228121 -327.288684) (xy 131.181967 -327.258611) (xy 131.140625 -327.222205) (xy 131.12242 -327.20153)
			(xy 131.114419 -327.192998) (xy 131.092969 -327.183734) (xy 131.081272 -327.18375) (xy 130.988816 -327.188322)
			(xy 130.968496 -327.199752) (xy 130.961638 -327.209404) (xy 130.94626 -327.230729) (xy 130.910661 -327.269418)
			(xy 130.870084 -327.30285) (xy 130.825299 -327.330389) (xy 130.777155 -327.351514) (xy 130.726565 -327.365824)
			(xy 130.674489 -327.373047) (xy 130.648202 -327.373488) (xy 130.620948 -327.373065) (xy 130.566994 -327.365308)
			(xy 130.514693 -327.349951) (xy 130.46511 -327.327308) (xy 130.419254 -327.297838) (xy 130.378059 -327.262143)
			(xy 130.342363 -327.220948) (xy 130.312893 -327.175092) (xy 130.290249 -327.125509) (xy 130.274892 -327.073208)
			(xy 130.267135 -327.019254) (xy 118.835424 -327.019254) (xy 118.835424 -327.900538) (xy 118.83644 -327.91019)
			(xy 118.838073 -327.917431) (xy 118.844922 -327.930593) (xy 118.849902 -327.936098) (xy 119.571516 -328.657712)
			(xy 119.577015 -328.6627) (xy 119.590181 -328.669544) (xy 119.597424 -328.671174) (xy 119.607076 -328.67219)
			(xy 131.782058 -328.67219)
		)
		(stroke
			(width 0)
			(type solid)
		)
		(fill yes)
		(layer "In13.Cu")
		(net "P0V8_PEX1")
	)
	(gr_poly
		(pts
			(xy 358.004872 -330.578206) (xy 358.00919 -330.561442) (xy 358.016778 -330.534658) (xy 358.038648 -330.483469)
			(xy 358.067728 -330.436002) (xy 358.103398 -330.393267) (xy 358.144902 -330.35617) (xy 358.191357 -330.3255)
			(xy 358.241777 -330.301909) (xy 358.29509 -330.285898) (xy 358.350165 -330.277806) (xy 358.405831 -330.277806)
			(xy 358.460906 -330.285898) (xy 358.514219 -330.301909) (xy 358.564639 -330.3255) (xy 358.611094 -330.35617)
			(xy 358.652598 -330.393267) (xy 358.688268 -330.436002) (xy 358.717348 -330.483469) (xy 358.739218 -330.534658)
			(xy 358.746806 -330.561442) (xy 358.751124 -330.578206) (xy 358.778556 -330.599288) (xy 359.142284 -330.599288)
			(xy 359.148634 -330.597764) (xy 359.172035 -330.592077) (xy 359.219805 -330.585969) (xy 359.243884 -330.585572)
			(xy 359.267963 -330.585972) (xy 359.315731 -330.592087) (xy 359.339134 -330.597764) (xy 359.345484 -330.599288)
			(xy 359.693972 -330.599288) (xy 359.721658 -330.576936) (xy 359.725468 -330.559156) (xy 359.731653 -330.532542)
			(xy 359.750611 -330.481297) (xy 359.776685 -330.43328) (xy 359.80934 -330.389473) (xy 359.847909 -330.350771)
			(xy 359.891604 -330.317966) (xy 359.939531 -330.291728) (xy 359.99071 -330.272593) (xy 360.044095 -330.260954)
			(xy 360.098594 -330.257048) (xy 360.153093 -330.260954) (xy 360.206478 -330.272593) (xy 360.257657 -330.291728)
			(xy 360.305584 -330.317966) (xy 360.349279 -330.350771) (xy 360.387848 -330.389473) (xy 360.420503 -330.43328)
			(xy 360.446577 -330.481297) (xy 360.465535 -330.532542) (xy 360.47172 -330.559156) (xy 360.47553 -330.576936)
			(xy 360.503216 -330.599288) (xy 360.588814 -330.599288) (xy 360.617008 -330.576428) (xy 360.620564 -330.558648)
			(xy 360.626532 -330.531777) (xy 360.64516 -330.479982) (xy 360.671036 -330.431401) (xy 360.703624 -330.387042)
			(xy 360.742248 -330.347826) (xy 360.786105 -330.314567) (xy 360.834287 -330.287954) (xy 360.885792 -330.26854)
			(xy 360.939552 -330.256728) (xy 360.994452 -330.252764) (xy 361.049352 -330.256728) (xy 361.103112 -330.26854)
			(xy 361.154617 -330.287954) (xy 361.202799 -330.314567) (xy 361.246656 -330.347826) (xy 361.28528 -330.387042)
			(xy 361.317868 -330.431401) (xy 361.343744 -330.479982) (xy 361.362372 -330.531777) (xy 361.36834 -330.558648)
			(xy 361.371896 -330.576428) (xy 361.40009 -330.599288) (xy 361.472734 -330.599288) (xy 361.501436 -330.574396)
			(xy 361.503976 -330.555346) (xy 361.508164 -330.528287) (xy 361.523282 -330.475662) (xy 361.545767 -330.425739)
			(xy 361.575157 -330.379542) (xy 361.610849 -330.33802) (xy 361.652109 -330.302026) (xy 361.69809 -330.2723)
			(xy 361.747848 -330.249451) (xy 361.800362 -330.233949) (xy 361.854551 -330.226113) (xy 361.881928 -330.225654)
			(xy 361.90788 -330.226093) (xy 361.959304 -330.233137) (xy 362.009297 -330.24709) (xy 362.056935 -330.267696)
			(xy 362.101339 -330.294572) (xy 362.141687 -330.327222) (xy 362.177233 -330.365043) (xy 362.207322 -330.407336)
			(xy 362.219748 -330.430124) (xy 362.226098 -330.442062) (xy 362.248704 -330.45654) (xy 362.363512 -330.462128)
			(xy 362.387388 -330.449682) (xy 362.394754 -330.438506) (xy 362.409939 -330.416101) (xy 362.44563 -330.375413)
			(xy 362.486714 -330.34018) (xy 362.532368 -330.31111) (xy 362.581674 -330.288787) (xy 362.633641 -330.27366)
			(xy 362.687224 -330.266034) (xy 362.714286 -330.265532) (xy 362.743581 -330.266065) (xy 362.801484 -330.27502)
			(xy 362.857337 -330.29272) (xy 362.909828 -330.31875) (xy 362.957722 -330.352498) (xy 362.999896 -330.393171)
			(xy 363.01807 -330.416154) (xy 363.018324 -330.416408) (xy 363.026108 -330.425437) (xy 363.04756 -330.43577)
			(xy 363.059472 -330.43622) (xy 363.153706 -330.434442) (xy 363.175042 -330.423266) (xy 363.182154 -330.413106)
			(xy 363.19751 -330.391955) (xy 363.233084 -330.353661) (xy 363.273557 -330.320588) (xy 363.31817 -330.293356)
			(xy 363.366086 -330.272476) (xy 363.416406 -330.258341) (xy 363.468186 -330.251214) (xy 363.49432 -330.2508)
			(xy 363.52349 -330.251356) (xy 363.581149 -330.260244) (xy 363.636782 -330.277809) (xy 363.689092 -330.303642)
			(xy 363.736856 -330.33714) (xy 363.778963 -330.377521) (xy 363.814428 -330.423844) (xy 363.842425 -330.475027)
			(xy 363.8623 -330.529877) (xy 363.868462 -330.558394) (xy 363.872272 -330.576428) (xy 363.899958 -330.599288)
			(xy 374.278906 -330.599288) (xy 374.286636 -330.599018) (xy 374.301377 -330.59436) (xy 374.307862 -330.590144)
			(xy 388.637526 -320.627248) (xy 388.640828 -320.623946) (xy 389.40994 -319.854834) (xy 389.416783 -319.847435)
			(xy 389.424503 -319.828836) (xy 389.424926 -319.818766) (xy 389.424926 -319.508378) (xy 389.400288 -319.47993)
			(xy 389.381492 -319.47739) (xy 389.368538 -319.475104) (xy 389.356346 -319.472818) (xy 389.332216 -319.480184)
			(xy 389.255 -319.5574) (xy 389.247634 -319.581276) (xy 389.24992 -319.593722) (xy 389.252404 -319.607687)
			(xy 389.255075 -319.635927) (xy 389.255254 -319.65011) (xy 389.254768 -319.674935) (xy 389.246733 -319.723931)
			(xy 389.230878 -319.770982) (xy 389.207619 -319.814848) (xy 389.17757 -319.854373) (xy 389.141522 -319.888516)
			(xy 389.100425 -319.916376) (xy 389.055363 -319.937221) (xy 389.007521 -319.950501) (xy 388.958161 -319.955866)
			(xy 388.908584 -319.953174) (xy 388.860095 -319.942497) (xy 388.813972 -319.924116) (xy 388.771431 -319.898515)
			(xy 388.733592 -319.866368) (xy 388.701453 -319.828523) (xy 388.675859 -319.785978) (xy 388.657486 -319.739852)
			(xy 388.646818 -319.691361) (xy 388.644136 -319.641783) (xy 388.649509 -319.592424) (xy 388.662798 -319.544585)
			(xy 388.683651 -319.499526) (xy 388.71152 -319.458434) (xy 388.745669 -319.422393) (xy 388.785199 -319.392351)
			(xy 388.829069 -319.3691) (xy 388.876123 -319.353253) (xy 388.925121 -319.345228) (xy 388.949946 -319.344802)
			(xy 388.964129 -319.344986) (xy 388.992369 -319.347655) (xy 389.006334 -319.350136) (xy 389.01878 -319.352422)
			(xy 389.042656 -319.345056) (xy 389.119872 -319.26784) (xy 389.127238 -319.24371) (xy 389.124952 -319.231518)
			(xy 389.120907 -319.207727) (xy 389.119507 -319.159492) (xy 389.122158 -319.135506) (xy 389.123682 -319.123568)
			(xy 389.115808 -319.100962) (xy 389.039354 -319.027302) (xy 389.016494 -319.020444) (xy 389.004556 -319.022222)
			(xy 388.991009 -319.024423) (xy 388.963669 -319.02684) (xy 388.949946 -319.027048) (xy 388.924234 -319.026573)
			(xy 388.873443 -319.018535) (xy 388.824534 -319.00265) (xy 388.778713 -318.979309) (xy 388.737108 -318.949086)
			(xy 388.700744 -318.912727) (xy 388.670515 -318.871126) (xy 388.647168 -318.825308) (xy 388.631275 -318.776402)
			(xy 388.62323 -318.725612) (xy 388.62323 -318.674188) (xy 388.631275 -318.623398) (xy 388.647168 -318.574492)
			(xy 388.670515 -318.528674) (xy 388.700744 -318.487073) (xy 388.737108 -318.450714) (xy 388.778713 -318.420491)
			(xy 388.824534 -318.39715) (xy 388.873443 -318.381265) (xy 388.924234 -318.373227) (xy 388.949946 -318.372744)
			(xy 388.96367 -318.372937) (xy 388.991011 -318.375354) (xy 389.004556 -318.37757) (xy 389.016494 -318.379348)
			(xy 389.039354 -318.37249) (xy 389.115808 -318.29883) (xy 389.123682 -318.276224) (xy 389.122158 -318.264286)
			(xy 389.11992 -318.244663) (xy 389.119918 -318.205168) (xy 389.122158 -318.185546) (xy 389.123682 -318.173608)
			(xy 389.115808 -318.151002) (xy 389.039354 -318.077342) (xy 389.016494 -318.070484) (xy 389.004556 -318.072262)
			(xy 388.991009 -318.074463) (xy 388.963669 -318.07688) (xy 388.949946 -318.077088) (xy 388.924231 -318.076613)
			(xy 388.873433 -318.068574) (xy 388.824519 -318.052687) (xy 388.778692 -318.029343) (xy 388.737082 -317.999117)
			(xy 388.700713 -317.962753) (xy 388.670481 -317.921147) (xy 388.647131 -317.875324) (xy 388.631237 -317.826411)
			(xy 388.62319 -317.775615) (xy 388.62319 -317.724185) (xy 388.631237 -317.673389) (xy 388.647131 -317.624476)
			(xy 388.670481 -317.578653) (xy 388.700713 -317.537047) (xy 388.737082 -317.500683) (xy 388.778692 -317.470457)
			(xy 388.824519 -317.447113) (xy 388.873433 -317.431226) (xy 388.924231 -317.423187) (xy 388.949946 -317.422784)
			(xy 388.983982 -317.424816) (xy 388.995666 -317.425832) (xy 389.017256 -317.418212) (xy 389.089392 -317.345314)
			(xy 389.097012 -317.323724) (xy 389.095488 -317.31204) (xy 389.094521 -317.302736) (xy 389.093507 -317.284056)
			(xy 389.093456 -317.274702) (xy 389.093456 -317.204344) (xy 389.093004 -317.193682) (xy 389.084327 -317.174207)
			(xy 389.076692 -317.166752) (xy 389.01243 -317.10884) (xy 388.992364 -317.102236) (xy 388.981442 -317.103506)
			(xy 388.949946 -317.10503) (xy 388.924684 -317.104541) (xy 388.874848 -317.096232) (xy 388.82706 -317.079832)
			(xy 388.782623 -317.05579) (xy 388.74275 -317.024761) (xy 388.708528 -316.987592) (xy 388.680892 -316.945297)
			(xy 388.660595 -316.899029) (xy 388.648191 -316.850051) (xy 388.644018 -316.7997) (xy 388.648191 -316.749349)
			(xy 388.660595 -316.700371) (xy 388.680892 -316.654103) (xy 388.708528 -316.611808) (xy 388.74275 -316.574639)
			(xy 388.782623 -316.54361) (xy 388.82706 -316.519568) (xy 388.874848 -316.503168) (xy 388.924684 -316.494859)
			(xy 388.949946 -316.494414) (xy 388.981442 -316.495938) (xy 388.992364 -316.497208) (xy 389.01243 -316.490604)
			(xy 389.076692 -316.432692) (xy 389.084196 -316.425145) (xy 389.092847 -316.405726) (xy 389.093456 -316.3951)
			(xy 389.093456 -316.324742) (xy 389.093618 -316.311088) (xy 389.095907 -316.283875) (xy 389.098028 -316.270386)
			(xy 389.099806 -316.258448) (xy 389.092948 -316.235842) (xy 389.02005 -316.159642) (xy 388.997952 -316.151514)
			(xy 388.98576 -316.153038) (xy 388.976838 -316.154001) (xy 388.95892 -316.15502) (xy 388.949946 -316.15507)
			(xy 388.924689 -316.154581) (xy 388.874863 -316.146273) (xy 388.827084 -316.129877) (xy 388.782656 -316.10584)
			(xy 388.74279 -316.074817) (xy 388.708575 -316.037655) (xy 388.680945 -315.995368) (xy 388.660651 -315.949109)
			(xy 388.64825 -315.900141) (xy 388.644078 -315.8498) (xy 388.64825 -315.799459) (xy 388.660651 -315.750491)
			(xy 388.680944 -315.704232) (xy 388.708575 -315.661945) (xy 388.74279 -315.624783) (xy 388.782656 -315.59376)
			(xy 388.827084 -315.569723) (xy 388.874863 -315.553327) (xy 388.924689 -315.545019) (xy 388.949946 -315.544454)
			(xy 388.964129 -315.544638) (xy 388.992369 -315.547306) (xy 389.006334 -315.549788) (xy 389.01878 -315.552074)
			(xy 389.042402 -315.544708) (xy 389.119872 -315.467238) (xy 389.127238 -315.443616) (xy 389.124952 -315.43117)
			(xy 389.122468 -315.417205) (xy 389.119794 -315.388965) (xy 389.119618 -315.374782) (xy 389.119805 -315.3606)
			(xy 389.122481 -315.332361) (xy 389.124952 -315.318394) (xy 389.127238 -315.305948) (xy 389.119872 -315.282326)
			(xy 389.042402 -315.204856) (xy 389.01878 -315.19749) (xy 389.006334 -315.199776) (xy 388.992369 -315.202259)
			(xy 388.964129 -315.204926) (xy 388.949946 -315.20511) (xy 388.924686 -315.204621) (xy 388.874853 -315.196312)
			(xy 388.827068 -315.179914) (xy 388.782634 -315.155873) (xy 388.742763 -315.124846) (xy 388.708544 -315.08768)
			(xy 388.680909 -315.045387) (xy 388.660614 -314.999122) (xy 388.64821 -314.950148) (xy 388.644038 -314.8998)
			(xy 388.64821 -314.849452) (xy 388.660614 -314.800478) (xy 388.680909 -314.754213) (xy 388.708544 -314.71192)
			(xy 388.742763 -314.674754) (xy 388.782634 -314.643727) (xy 388.827068 -314.619686) (xy 388.874853 -314.603288)
			(xy 388.924686 -314.594979) (xy 388.949946 -314.594494) (xy 388.95905 -314.594592) (xy 388.977223 -314.595736)
			(xy 388.986268 -314.59678) (xy 388.99846 -314.59805) (xy 389.020812 -314.590176) (xy 389.09371 -314.513722)
			(xy 389.100822 -314.491116) (xy 389.09879 -314.479178) (xy 389.096659 -314.46569) (xy 389.094369 -314.438477)
			(xy 389.094218 -314.424822) (xy 389.09426 -314.415468) (xy 389.095275 -314.396787) (xy 389.09625 -314.387484)
			(xy 389.097774 -314.3758) (xy 389.090154 -314.35421) (xy 389.017764 -314.281566) (xy 388.996174 -314.273692)
			(xy 388.98449 -314.274962) (xy 388.949946 -314.27674) (xy 388.92425 -314.276266) (xy 388.873491 -314.268233)
			(xy 388.824614 -314.252358) (xy 388.778822 -314.229031) (xy 388.737243 -314.198828) (xy 388.700902 -314.162492)
			(xy 388.670693 -314.120917) (xy 388.64736 -314.075129) (xy 388.631478 -314.026254) (xy 388.623438 -313.975495)
			(xy 388.623438 -313.924105) (xy 388.631478 -313.873346) (xy 388.64736 -313.824471) (xy 388.670693 -313.778683)
			(xy 388.700902 -313.737108) (xy 388.737243 -313.700772) (xy 388.778822 -313.670569) (xy 388.824614 -313.647242)
			(xy 388.873491 -313.631367) (xy 388.92425 -313.623334) (xy 388.949946 -313.622944) (xy 388.98449 -313.624722)
			(xy 388.996174 -313.625992) (xy 389.017764 -313.618118) (xy 389.090154 -313.545474) (xy 389.097774 -313.523884)
			(xy 389.09625 -313.5122) (xy 389.095281 -313.502896) (xy 389.094264 -313.484216) (xy 389.094218 -313.474862)
			(xy 389.094262 -313.465508) (xy 389.09528 -313.446828) (xy 389.09625 -313.437524) (xy 389.097774 -313.42584)
			(xy 389.090154 -313.40425) (xy 389.017764 -313.331606) (xy 388.996174 -313.323732) (xy 388.98449 -313.325002)
			(xy 388.949946 -313.32678) (xy 388.924255 -313.326306) (xy 388.873505 -313.318274) (xy 388.824637 -313.302402)
			(xy 388.778853 -313.27908) (xy 388.737283 -313.248882) (xy 388.700948 -313.212553) (xy 388.670744 -313.170986)
			(xy 388.647416 -313.125206) (xy 388.631537 -313.076339) (xy 388.623498 -313.025591) (xy 388.623498 -312.974209)
			(xy 388.631537 -312.923461) (xy 388.647416 -312.874594) (xy 388.670744 -312.828814) (xy 388.700948 -312.787247)
			(xy 388.737283 -312.750918) (xy 388.778853 -312.72072) (xy 388.824637 -312.697398) (xy 388.873505 -312.681526)
			(xy 388.924255 -312.673494) (xy 388.949946 -312.672984) (xy 388.98449 -312.674762) (xy 388.996174 -312.676032)
			(xy 389.017764 -312.668158) (xy 389.090154 -312.595514) (xy 389.097774 -312.573924) (xy 389.09625 -312.56224)
			(xy 389.095283 -312.552936) (xy 389.094269 -312.534256) (xy 389.094218 -312.524902) (xy 389.094381 -312.511248)
			(xy 389.096673 -312.484036) (xy 389.09879 -312.470546) (xy 389.100822 -312.458608) (xy 389.09371 -312.436002)
			(xy 389.020812 -312.359548) (xy 388.99846 -312.351674) (xy 388.986268 -312.352944) (xy 388.977224 -312.353994)
			(xy 388.95905 -312.35514) (xy 388.949946 -312.35523) (xy 388.924684 -312.354741) (xy 388.874848 -312.346432)
			(xy 388.82706 -312.330032) (xy 388.782623 -312.30599) (xy 388.74275 -312.274961) (xy 388.708528 -312.237792)
			(xy 388.680892 -312.195497) (xy 388.660595 -312.149229) (xy 388.648191 -312.100251) (xy 388.644018 -312.0499)
			(xy 388.648191 -311.999549) (xy 388.660595 -311.950571) (xy 388.680892 -311.904303) (xy 388.708528 -311.862008)
			(xy 388.74275 -311.824839) (xy 388.782623 -311.79381) (xy 388.82706 -311.769768) (xy 388.874848 -311.753368)
			(xy 388.924684 -311.745059) (xy 388.949946 -311.744614) (xy 388.958983 -311.74466) (xy 388.977029 -311.745675)
			(xy 388.986014 -311.746646) (xy 388.998206 -311.74817) (xy 389.020304 -311.740296) (xy 389.093202 -311.663842)
			(xy 389.100314 -311.641236) (xy 389.098282 -311.629044) (xy 389.096152 -311.615556) (xy 389.093864 -311.588343)
			(xy 389.09371 -311.574688) (xy 389.09371 -311.504584) (xy 389.093248 -311.493926) (xy 389.084562 -311.474462)
			(xy 389.076946 -311.466992) (xy 389.012684 -311.40908) (xy 388.992364 -311.402476) (xy 388.981696 -311.403746)
			(xy 388.949946 -311.40527) (xy 388.924689 -311.404781) (xy 388.874863 -311.396473) (xy 388.827084 -311.380077)
			(xy 388.782656 -311.35604) (xy 388.74279 -311.325017) (xy 388.708575 -311.287855) (xy 388.680945 -311.245568)
			(xy 388.660651 -311.199309) (xy 388.64825 -311.150341) (xy 388.644078 -311.1) (xy 388.64825 -311.049659)
			(xy 388.660651 -311.000691) (xy 388.680944 -310.954432) (xy 388.708575 -310.912145) (xy 388.74279 -310.874983)
			(xy 388.782656 -310.84396) (xy 388.827084 -310.819923) (xy 388.874863 -310.803527) (xy 388.924689 -310.795219)
			(xy 388.949946 -310.794654) (xy 388.981696 -310.796432) (xy 388.992618 -310.797448) (xy 389.012938 -310.790844)
			(xy 389.0772 -310.732932) (xy 389.084709 -310.725387) (xy 389.093374 -310.705968) (xy 389.093964 -310.69534)
			(xy 389.093964 -310.624728) (xy 389.094126 -310.611074) (xy 389.096416 -310.583862) (xy 389.098536 -310.570372)
			(xy 389.100568 -310.558434) (xy 389.093456 -310.535828) (xy 389.020558 -310.459374) (xy 388.998206 -310.4515)
			(xy 388.986268 -310.453024) (xy 388.977221 -310.454014) (xy 388.959047 -310.455031) (xy 388.949946 -310.455056)
			(xy 388.92512 -310.454574) (xy 388.87612 -310.446548) (xy 388.829064 -310.4307) (xy 388.785192 -310.407447)
			(xy 388.745661 -310.377403) (xy 388.711511 -310.341359) (xy 388.683643 -310.300264) (xy 388.662791 -310.255202)
			(xy 388.649504 -310.20736) (xy 388.644133 -310.157998) (xy 388.646819 -310.108418) (xy 388.657491 -310.059926)
			(xy 388.675869 -310.013799) (xy 388.701467 -309.971253) (xy 388.733611 -309.93341) (xy 388.771455 -309.901266)
			(xy 388.814001 -309.875668) (xy 388.860128 -309.857291) (xy 388.90862 -309.846619) (xy 388.9582 -309.843933)
			(xy 389.007562 -309.849305) (xy 389.055404 -309.862592) (xy 389.100466 -309.883444) (xy 389.14156 -309.911312)
			(xy 389.177604 -309.945462) (xy 389.207648 -309.984994) (xy 389.230901 -310.028866) (xy 389.246748 -310.075922)
			(xy 389.254774 -310.124922) (xy 389.255254 -310.149748) (xy 389.255156 -310.158852) (xy 389.254012 -310.177025)
			(xy 389.252968 -310.18607) (xy 389.251698 -310.198262) (xy 389.259572 -310.220614) (xy 389.336026 -310.293512)
			(xy 389.358632 -310.30037) (xy 389.37057 -310.298592) (xy 389.383995 -310.296471) (xy 389.411081 -310.294178)
			(xy 389.424672 -310.29402) (xy 389.445862 -310.294325) (xy 389.487902 -310.299674) (xy 389.508492 -310.304688)
			(xy 389.509 -310.304688) (xy 389.521954 -310.308498) (xy 389.546084 -310.31688) (xy 389.555299 -310.320023)
			(xy 389.574752 -310.319859) (xy 389.592743 -310.31246) (xy 389.606683 -310.298892) (xy 389.614566 -310.281107)
			(xy 389.615256 -310.261666) (xy 389.612378 -310.252364) (xy 389.604079 -310.227526) (xy 389.595137 -310.17593)
			(xy 389.594598 -310.149748) (xy 389.595041 -310.125753) (xy 389.602541 -310.078352) (xy 389.617366 -310.032708)
			(xy 389.639149 -309.989946) (xy 389.667354 -309.951118) (xy 389.701286 -309.917181) (xy 389.74011 -309.888971)
			(xy 389.782869 -309.867182) (xy 389.828511 -309.852351) (xy 389.875911 -309.844844) (xy 389.899906 -309.84444)
			(xy 389.90901 -309.844537) (xy 389.927184 -309.845678) (xy 389.936228 -309.846726) (xy 389.94842 -309.847996)
			(xy 389.970772 -309.840122) (xy 390.04367 -309.763668) (xy 390.050782 -309.741062) (xy 390.04875 -309.729124)
			(xy 390.046621 -309.715636) (xy 390.044335 -309.688422) (xy 390.044178 -309.674768) (xy 390.044222 -309.665414)
			(xy 390.04524 -309.646734) (xy 390.04621 -309.63743) (xy 390.047734 -309.625746) (xy 390.040114 -309.604156)
			(xy 389.967724 -309.531512) (xy 389.946134 -309.523638) (xy 389.93445 -309.524908) (xy 389.899906 -309.52694)
			(xy 389.874218 -309.526437) (xy 389.823475 -309.518402) (xy 389.774613 -309.502529) (xy 389.728836 -309.479209)
			(xy 389.687269 -309.449016) (xy 389.650937 -309.412692) (xy 389.620733 -309.371133) (xy 389.597402 -309.325361)
			(xy 389.581517 -309.276503) (xy 389.57347 -309.225762) (xy 389.573458 -309.174387) (xy 389.581482 -309.123642)
			(xy 389.597345 -309.074777) (xy 389.620655 -309.028994) (xy 389.65084 -308.987422) (xy 389.687156 -308.951082)
			(xy 389.728708 -308.920869) (xy 389.774475 -308.897528) (xy 389.82333 -308.881633) (xy 389.874069 -308.873575)
			(xy 389.925445 -308.873552) (xy 389.976191 -308.881566) (xy 390.025059 -308.897418) (xy 390.070847 -308.920719)
			(xy 390.112426 -308.950895) (xy 390.148774 -308.987203) (xy 390.178995 -309.02875) (xy 390.202345 -309.074512)
			(xy 390.218251 -309.123363) (xy 390.22632 -309.174101) (xy 390.226804 -309.199788) (xy 390.225026 -309.234332)
			(xy 390.223756 -309.246016) (xy 390.23163 -309.267606) (xy 390.304274 -309.339996) (xy 390.325864 -309.347616)
			(xy 390.337548 -309.346092) (xy 390.346852 -309.345124) (xy 390.365532 -309.34411) (xy 390.374886 -309.34406)
			(xy 390.38424 -309.344103) (xy 390.402921 -309.345118) (xy 390.412224 -309.346092) (xy 390.423908 -309.347616)
			(xy 390.445498 -309.339996) (xy 390.518142 -309.267606) (xy 390.526016 -309.246016) (xy 390.524746 -309.234332)
			(xy 390.522968 -309.199788) (xy 390.523472 -309.1741) (xy 390.531509 -309.123357) (xy 390.547385 -309.074496)
			(xy 390.570709 -309.02872) (xy 390.600906 -308.987156) (xy 390.637234 -308.950828) (xy 390.678798 -308.920631)
			(xy 390.724574 -308.897307) (xy 390.773435 -308.881431) (xy 390.824178 -308.873394) (xy 390.875554 -308.873394)
			(xy 390.926297 -308.881431) (xy 390.975158 -308.897307) (xy 391.020934 -308.920631) (xy 391.062498 -308.950828)
			(xy 391.098826 -308.987156) (xy 391.129023 -309.02872) (xy 391.152347 -309.074496) (xy 391.168223 -309.123357)
			(xy 391.17626 -309.1741) (xy 391.176764 -309.199788) (xy 391.174986 -309.234332) (xy 391.173716 -309.246016)
			(xy 391.18159 -309.267606) (xy 391.254234 -309.339996) (xy 391.275824 -309.347616) (xy 391.287508 -309.346092)
			(xy 391.296812 -309.345123) (xy 391.315492 -309.344106) (xy 391.324846 -309.34406) (xy 391.3385 -309.344221)
			(xy 391.365713 -309.346509) (xy 391.379202 -309.348632) (xy 391.39114 -309.350664) (xy 391.413746 -309.343552)
			(xy 391.4902 -309.270654) (xy 391.498074 -309.248302) (xy 391.496804 -309.23611) (xy 391.495756 -309.227066)
			(xy 391.494613 -309.208892) (xy 391.494518 -309.199788) (xy 391.49504 -309.174533) (xy 391.503353 -309.124711)
			(xy 391.519754 -309.076937) (xy 391.543795 -309.032514) (xy 391.574819 -308.992654) (xy 391.611981 -308.958444)
			(xy 391.654267 -308.930818) (xy 391.700523 -308.910528) (xy 391.749488 -308.898128) (xy 391.799826 -308.893957)
			(xy 391.850164 -308.898128) (xy 391.899129 -308.910528) (xy 391.945385 -308.930818) (xy 391.987671 -308.958444)
			(xy 392.024833 -308.992654) (xy 392.055857 -309.032514) (xy 392.079898 -309.076937) (xy 392.096299 -309.124711)
			(xy 392.104612 -309.174533) (xy 392.105134 -309.199788) (xy 392.105035 -309.208892) (xy 392.103888 -309.227065)
			(xy 392.102848 -309.23611) (xy 392.101578 -309.248302) (xy 392.109452 -309.270654) (xy 392.185906 -309.343552)
			(xy 392.208512 -309.350664) (xy 392.22045 -309.348632) (xy 392.233938 -309.346502) (xy 392.261151 -309.344214)
			(xy 392.274806 -309.34406) (xy 392.28846 -309.344224) (xy 392.315672 -309.346516) (xy 392.329162 -309.348632)
			(xy 392.3411 -309.350664) (xy 392.363706 -309.343552) (xy 392.44016 -309.270654) (xy 392.448034 -309.248302)
			(xy 392.446764 -309.23611) (xy 392.445716 -309.227066) (xy 392.444573 -309.208892) (xy 392.444478 -309.199788)
			(xy 392.445 -309.174533) (xy 392.453313 -309.124711) (xy 392.469714 -309.076937) (xy 392.493755 -309.032514)
			(xy 392.524779 -308.992654) (xy 392.561941 -308.958444) (xy 392.604227 -308.930818) (xy 392.650483 -308.910528)
			(xy 392.699448 -308.898128) (xy 392.749786 -308.893957) (xy 392.800124 -308.898128) (xy 392.849089 -308.910528)
			(xy 392.895345 -308.930818) (xy 392.937631 -308.958444) (xy 392.974793 -308.992654) (xy 393.005817 -309.032514)
			(xy 393.029858 -309.076937) (xy 393.046259 -309.124711) (xy 393.054572 -309.174533) (xy 393.055094 -309.199788)
			(xy 393.055002 -309.208956) (xy 393.053859 -309.227256) (xy 393.052808 -309.236364) (xy 393.051538 -309.248302)
			(xy 393.059412 -309.270654) (xy 393.135866 -309.343552) (xy 393.158472 -309.350664) (xy 393.17041 -309.348632)
			(xy 393.183961 -309.346493) (xy 393.211302 -309.344204) (xy 393.22502 -309.34406) (xy 393.238674 -309.34422)
			(xy 393.265887 -309.346506) (xy 393.279376 -309.348632) (xy 393.291314 -309.350664) (xy 393.31392 -309.343552)
			(xy 393.390374 -309.270654) (xy 393.398248 -309.248302) (xy 393.396978 -309.23611) (xy 393.39593 -309.227066)
			(xy 393.394787 -309.208892) (xy 393.394692 -309.199788) (xy 393.395214 -309.174533) (xy 393.403527 -309.124711)
			(xy 393.419928 -309.076937) (xy 393.443969 -309.032514) (xy 393.474993 -308.992654) (xy 393.512155 -308.958444)
			(xy 393.554441 -308.930818) (xy 393.600697 -308.910528) (xy 393.649662 -308.898128) (xy 393.7 -308.893957)
			(xy 393.750338 -308.898128) (xy 393.799303 -308.910528) (xy 393.845559 -308.930818) (xy 393.887845 -308.958444)
			(xy 393.925007 -308.992654) (xy 393.956031 -309.032514) (xy 393.980072 -309.076937) (xy 393.996473 -309.124711)
			(xy 394.004786 -309.174533) (xy 394.005308 -309.199788) (xy 394.005209 -309.208892) (xy 394.004063 -309.227065)
			(xy 394.003022 -309.23611) (xy 394.001752 -309.248302) (xy 394.009626 -309.270654) (xy 394.08608 -309.343552)
			(xy 394.108686 -309.350664) (xy 394.120624 -309.348632) (xy 394.134112 -309.346501) (xy 394.161325 -309.344211)
			(xy 394.17498 -309.34406) (xy 394.188634 -309.344223) (xy 394.215846 -309.346513) (xy 394.229336 -309.348632)
			(xy 394.241274 -309.350664) (xy 394.26388 -309.343552) (xy 394.340334 -309.270654) (xy 394.348208 -309.248302)
			(xy 394.346938 -309.23611) (xy 394.34589 -309.227066) (xy 394.344747 -309.208892) (xy 394.344652 -309.199788)
			(xy 394.345123 -309.175796) (xy 394.352631 -309.128404) (xy 394.367459 -309.082769) (xy 394.389242 -309.040015)
			(xy 394.417445 -309.001194) (xy 394.451373 -308.967263) (xy 394.490191 -308.939057) (xy 394.532943 -308.91727)
			(xy 394.578576 -308.902437) (xy 394.625968 -308.894926) (xy 394.64996 -308.89448) (xy 394.664143 -308.894665)
			(xy 394.692383 -308.897334) (xy 394.706348 -308.899814) (xy 394.718794 -308.9021) (xy 394.742416 -308.894734)
			(xy 394.819886 -308.817264) (xy 394.827252 -308.793642) (xy 394.824966 -308.781196) (xy 394.82248 -308.767231)
			(xy 394.819807 -308.738991) (xy 394.819632 -308.724808) (xy 394.820117 -308.699991) (xy 394.828145 -308.65101)
			(xy 394.843992 -308.603974) (xy 394.86724 -308.560121) (xy 394.897275 -308.520606) (xy 394.933308 -308.486471)
			(xy 394.974388 -308.458615) (xy 395.019434 -308.437772) (xy 395.067258 -308.424491) (xy 395.116601 -308.419122)
			(xy 395.166162 -308.421806) (xy 395.214637 -308.432472) (xy 395.260747 -308.450841) (xy 395.303278 -308.476427)
			(xy 395.34111 -308.508556) (xy 395.373245 -308.546383) (xy 395.398838 -308.58891) (xy 395.417214 -308.635017)
			(xy 395.427888 -308.68349) (xy 395.430132 -308.724808) (xy 395.769096 -308.724808) (xy 395.773056 -308.675754)
			(xy 395.784833 -308.62797) (xy 395.804124 -308.582694) (xy 395.830427 -308.541098) (xy 395.863062 -308.504261)
			(xy 395.901183 -308.473136) (xy 395.943804 -308.448529) (xy 395.98982 -308.431077) (xy 396.038039 -308.421233)
			(xy 396.087214 -308.419252) (xy 396.136069 -308.425184) (xy 396.18334 -308.438876) (xy 396.227802 -308.459974)
			(xy 396.268305 -308.48793) (xy 396.303798 -308.522022) (xy 396.333363 -308.561366) (xy 396.356234 -308.604943)
			(xy 396.371818 -308.651624) (xy 396.379713 -308.700201) (xy 396.380208 -308.724808) (xy 396.719056 -308.724808)
			(xy 396.723016 -308.675754) (xy 396.734793 -308.62797) (xy 396.754084 -308.582694) (xy 396.780387 -308.541098)
			(xy 396.813022 -308.504261) (xy 396.851143 -308.473136) (xy 396.893764 -308.448529) (xy 396.93978 -308.431077)
			(xy 396.987999 -308.421233) (xy 397.037174 -308.419252) (xy 397.086029 -308.425184) (xy 397.1333 -308.438876)
			(xy 397.177762 -308.459974) (xy 397.218265 -308.48793) (xy 397.253758 -308.522022) (xy 397.283323 -308.561366)
			(xy 397.306194 -308.604943) (xy 397.321778 -308.651624) (xy 397.329673 -308.700201) (xy 397.330168 -308.724808)
			(xy 397.329673 -308.749415) (xy 397.321778 -308.797992) (xy 397.306194 -308.844673) (xy 397.283323 -308.88825)
			(xy 397.253758 -308.927594) (xy 397.218265 -308.961686) (xy 397.177762 -308.989642) (xy 397.1333 -309.01074)
			(xy 397.086029 -309.024432) (xy 397.037174 -309.030364) (xy 396.987999 -309.028383) (xy 396.93978 -309.018539)
			(xy 396.893764 -309.001087) (xy 396.851143 -308.97648) (xy 396.813022 -308.945355) (xy 396.780387 -308.908518)
			(xy 396.754084 -308.866922) (xy 396.734793 -308.821646) (xy 396.723016 -308.773862) (xy 396.719056 -308.724808)
			(xy 396.380208 -308.724808) (xy 396.379713 -308.749415) (xy 396.371818 -308.797992) (xy 396.356234 -308.844673)
			(xy 396.333363 -308.88825) (xy 396.303798 -308.927594) (xy 396.268305 -308.961686) (xy 396.227802 -308.989642)
			(xy 396.18334 -309.01074) (xy 396.136069 -309.024432) (xy 396.087214 -309.030364) (xy 396.038039 -309.028383)
			(xy 395.98982 -309.018539) (xy 395.943804 -309.001087) (xy 395.901183 -308.97648) (xy 395.863062 -308.945355)
			(xy 395.830427 -308.908518) (xy 395.804124 -308.866922) (xy 395.784833 -308.821646) (xy 395.773056 -308.773862)
			(xy 395.769096 -308.724808) (xy 395.430132 -308.724808) (xy 395.43058 -308.733051) (xy 395.425218 -308.782395)
			(xy 395.411944 -308.830221) (xy 395.391108 -308.87527) (xy 395.363259 -308.916355) (xy 395.32913 -308.952393)
			(xy 395.28962 -308.982435) (xy 395.24577 -309.005689) (xy 395.198736 -309.021543) (xy 395.149757 -309.029579)
			(xy 395.12494 -309.030116) (xy 395.110757 -309.029931) (xy 395.082517 -309.027262) (xy 395.068552 -309.024782)
			(xy 395.056106 -309.022496) (xy 395.032484 -309.029862) (xy 394.955014 -309.107332) (xy 394.947648 -309.130954)
			(xy 394.949934 -309.1434) (xy 394.95242 -309.157365) (xy 394.955094 -309.185605) (xy 394.955268 -309.199788)
			(xy 394.955169 -309.208892) (xy 394.954022 -309.227065) (xy 394.952982 -309.23611) (xy 394.951712 -309.248302)
			(xy 394.959586 -309.270654) (xy 395.03604 -309.343552) (xy 395.058646 -309.350664) (xy 395.070584 -309.348632)
			(xy 395.084072 -309.346499) (xy 395.111285 -309.344206) (xy 395.12494 -309.34406) (xy 395.150926 -309.344572)
			(xy 395.202258 -309.352708) (xy 395.251685 -309.368772) (xy 395.297991 -309.392369) (xy 395.340036 -309.422919)
			(xy 395.376786 -309.45967) (xy 395.407335 -309.501716) (xy 395.430931 -309.548023) (xy 395.446994 -309.59745)
			(xy 395.455128 -309.648782) (xy 395.455648 -309.674768) (xy 395.455648 -309.682642) (xy 395.45514 -309.69839)
			(xy 395.472412 -309.72506) (xy 395.487398 -309.731156) (xy 395.513135 -309.741808) (xy 395.563459 -309.765698)
			(xy 395.587982 -309.778908) (xy 395.59357 -309.781956) (xy 395.60754 -309.785512) (xy 395.617596 -309.787625)
			(xy 395.637908 -309.784623) (xy 395.64691 -309.77967) (xy 395.720316 -309.734204) (xy 395.731746 -309.727092)
			(xy 395.7447 -309.70347) (xy 395.744446 -309.688992) (xy 395.744446 -309.688484) (xy 395.744192 -309.674768)
			(xy 395.744702 -309.648781) (xy 395.752832 -309.597446) (xy 395.768893 -309.548016) (xy 395.792489 -309.501706)
			(xy 395.823039 -309.459658) (xy 395.85979 -309.422907) (xy 395.901838 -309.392357) (xy 395.948148 -309.368761)
			(xy 395.997578 -309.3527) (xy 396.048913 -309.34457) (xy 396.100887 -309.34457) (xy 396.152222 -309.3527)
			(xy 396.201652 -309.368761) (xy 396.247962 -309.392357) (xy 396.29001 -309.422907) (xy 396.326761 -309.459658)
			(xy 396.357311 -309.501706) (xy 396.380907 -309.548016) (xy 396.396968 -309.597446) (xy 396.405098 -309.648781)
			(xy 396.405608 -309.674768) (xy 396.405354 -309.688484) (xy 396.405354 -309.688992) (xy 396.4051 -309.70347)
			(xy 396.418054 -309.727092) (xy 396.429484 -309.734204) (xy 396.504668 -309.780686) (xy 396.505684 -309.781194)
			(xy 396.511426 -309.784358) (xy 396.524029 -309.787955) (xy 396.530576 -309.788306) (xy 396.544546 -309.78856)
			(xy 396.573127 -309.772462) (xy 396.632108 -309.743738) (xy 396.662402 -309.731156) (xy 396.671577 -309.726971)
			(xy 396.685914 -309.712811) (xy 396.693731 -309.694239) (xy 396.694152 -309.684166) (xy 396.694152 -309.674768)
			(xy 396.694664 -309.648781) (xy 396.702798 -309.597448) (xy 396.718861 -309.54802) (xy 396.742458 -309.501712)
			(xy 396.773008 -309.459664) (xy 396.809758 -309.422913) (xy 396.851805 -309.392363) (xy 396.898112 -309.368765)
			(xy 396.947541 -309.3527) (xy 396.998873 -309.344565) (xy 397.02486 -309.34406) (xy 397.050257 -309.34452)
			(xy 397.100454 -309.35228) (xy 397.148875 -309.367623) (xy 397.19438 -309.390188) (xy 397.235901 -309.419445)
			(xy 397.254476 -309.43677) (xy 397.261842 -309.443882) (xy 397.28013 -309.451248) (xy 397.361156 -309.450486)
			(xy 397.370193 -309.450071) (xy 397.387103 -309.443682) (xy 397.394176 -309.43804) (xy 397.39697 -309.4355)
			(xy 397.73479 -309.09768) (xy 397.737838 -309.094378) (xy 397.738854 -309.093108) (xy 397.744149 -309.086182)
			(xy 397.750112 -309.069813) (xy 397.750538 -309.061104) (xy 397.7513 -308.980078) (xy 397.743934 -308.96179)
			(xy 397.736822 -308.954424) (xy 397.719522 -308.935827) (xy 397.690257 -308.894313) (xy 397.667685 -308.848814)
			(xy 397.652334 -308.800398) (xy 397.644567 -308.750204) (xy 397.644112 -308.724808) (xy 397.644594 -308.699492)
			(xy 397.652308 -308.649453) (xy 397.667558 -308.601173) (xy 397.689987 -308.555781) (xy 397.719072 -308.514337)
			(xy 397.754132 -308.477809) (xy 397.79435 -308.447051) (xy 397.838785 -308.422781) (xy 397.886399 -308.405566)
			(xy 397.936081 -308.395808) (xy 397.961358 -308.394354) (xy 397.961612 -308.394354) (xy 397.971264 -308.393846)
			(xy 397.979646 -308.39029) (xy 397.984005 -308.388306) (xy 397.991929 -308.382929) (xy 397.995394 -308.379622)
			(xy 398.016984 -308.358286) (xy 398.02393 -308.35086) (xy 398.031785 -308.332123) (xy 398.032224 -308.321964)
			(xy 398.032224 -308.177692) (xy 398.031764 -308.167444) (xy 398.023781 -308.148566) (xy 398.01673 -308.141116)
			(xy 398.00911 -308.13375) (xy 398.008602 -308.133242) (xy 397.988536 -308.113176) (xy 397.971264 -308.10581)
			(xy 397.961612 -308.105302) (xy 397.93631 -308.103823) (xy 397.886565 -308.094131) (xy 397.83888 -308.076963)
			(xy 397.794373 -308.052722) (xy 397.754084 -308.021974) (xy 397.718958 -307.985441) (xy 397.689817 -307.943976)
			(xy 397.667341 -307.898552) (xy 397.652059 -307.85023) (xy 397.644327 -307.800142) (xy 397.644327 -307.749461)
			(xy 397.652058 -307.699374) (xy 397.66734 -307.651052) (xy 397.689815 -307.605627) (xy 397.718956 -307.564162)
			(xy 397.754082 -307.527628) (xy 397.79437 -307.49688) (xy 397.838877 -307.472639) (xy 397.886561 -307.45547)
			(xy 397.936306 -307.445777) (xy 397.961612 -307.444394) (xy 397.971264 -307.44414) (xy 397.988536 -307.43652)
			(xy 398.016984 -307.408326) (xy 398.023936 -307.400902) (xy 398.031806 -307.382166) (xy 398.032224 -307.372004)
			(xy 398.032224 -307.227732) (xy 398.031753 -307.217489) (xy 398.023755 -307.198627) (xy 398.01673 -307.191156)
			(xy 398.00911 -307.18379) (xy 398.008602 -307.183282) (xy 397.988536 -307.163216) (xy 397.971264 -307.15585)
			(xy 397.961612 -307.155342) (xy 397.936315 -307.153863) (xy 397.886578 -307.144172) (xy 397.838903 -307.127007)
			(xy 397.794403 -307.10277) (xy 397.754123 -307.072028) (xy 397.719003 -307.035501) (xy 397.689867 -306.994044)
			(xy 397.667396 -306.948627) (xy 397.652117 -306.900314) (xy 397.644387 -306.850235) (xy 397.644387 -306.799564)
			(xy 397.652117 -306.749485) (xy 397.667396 -306.701172) (xy 397.689867 -306.655755) (xy 397.719004 -306.614298)
			(xy 397.754123 -306.577771) (xy 397.794404 -306.547029) (xy 397.838904 -306.522792) (xy 397.886579 -306.505627)
			(xy 397.936316 -306.495937) (xy 397.961612 -306.494434) (xy 397.971264 -306.49418) (xy 397.988536 -306.48656)
			(xy 398.016984 -306.458366) (xy 398.023927 -306.450939) (xy 398.031774 -306.432202) (xy 398.032224 -306.422044)
			(xy 398.032224 -306.277772) (xy 398.031761 -306.267525) (xy 398.023772 -306.248653) (xy 398.01673 -306.241196)
			(xy 398.00911 -306.23383) (xy 398.008602 -306.233322) (xy 397.988536 -306.213256) (xy 397.971264 -306.20589)
			(xy 397.961612 -306.205382) (xy 397.936312 -306.203903) (xy 397.886569 -306.194211) (xy 397.838888 -306.177044)
			(xy 397.794383 -306.152805) (xy 397.754097 -306.122059) (xy 397.718973 -306.085528) (xy 397.689833 -306.044066)
			(xy 397.66736 -305.998643) (xy 397.652078 -305.950325) (xy 397.644347 -305.90024) (xy 397.644347 -305.849562)
			(xy 397.652078 -305.799478) (xy 397.667359 -305.751159) (xy 397.689832 -305.705736) (xy 397.718972 -305.664274)
			(xy 397.754096 -305.627742) (xy 397.794381 -305.596997) (xy 397.838886 -305.572756) (xy 397.886567 -305.555589)
			(xy 397.936309 -305.545897) (xy 397.961612 -305.544474) (xy 397.971264 -305.54422) (xy 397.988536 -305.5366)
			(xy 398.016984 -305.508406) (xy 398.023933 -305.500981) (xy 398.031795 -305.482245) (xy 398.032224 -305.472084)
			(xy 398.032224 -305.327558) (xy 398.031758 -305.317313) (xy 398.023766 -305.298444) (xy 398.01673 -305.290982)
			(xy 398.00911 -305.283616) (xy 398.008602 -305.283108) (xy 397.988536 -305.263042) (xy 397.971264 -305.255676)
			(xy 397.961612 -305.255168) (xy 397.936313 -305.253689) (xy 397.886572 -305.243998) (xy 397.838893 -305.226831)
			(xy 397.79439 -305.202593) (xy 397.754106 -305.171848) (xy 397.718984 -305.135318) (xy 397.689845 -305.093858)
			(xy 397.667372 -305.048438) (xy 397.652092 -305.000121) (xy 397.644361 -304.950038) (xy 397.644361 -304.899363)
			(xy 397.652092 -304.84928) (xy 397.667372 -304.800963) (xy 397.689844 -304.755543) (xy 397.718983 -304.714082)
			(xy 397.754105 -304.677552) (xy 397.794389 -304.646808) (xy 397.838892 -304.622569) (xy 397.886571 -304.605403)
			(xy 397.936312 -304.595711) (xy 397.961612 -304.59426) (xy 397.971264 -304.594006) (xy 397.988536 -304.586386)
			(xy 398.016984 -304.558192) (xy 398.023931 -304.550767) (xy 398.031788 -304.53203) (xy 398.032224 -304.52187)
			(xy 398.032224 -304.377598) (xy 398.031765 -304.367349) (xy 398.023784 -304.34847) (xy 398.01673 -304.341022)
			(xy 398.00911 -304.333656) (xy 398.008602 -304.333148) (xy 397.988536 -304.313082) (xy 397.971264 -304.305716)
			(xy 397.961612 -304.305208) (xy 397.936317 -304.303729) (xy 397.886586 -304.294039) (xy 397.838915 -304.276876)
			(xy 397.794421 -304.252641) (xy 397.754144 -304.221902) (xy 397.719028 -304.185378) (xy 397.689895 -304.143925)
			(xy 397.667427 -304.098513) (xy 397.65215 -304.050205) (xy 397.644421 -304.000131) (xy 397.644421 -303.949465)
			(xy 397.652151 -303.899392) (xy 397.667428 -303.851083) (xy 397.689897 -303.805672) (xy 397.719031 -303.764219)
			(xy 397.754147 -303.727696) (xy 397.794424 -303.696957) (xy 397.838919 -303.672723) (xy 397.88659 -303.65556)
			(xy 397.936321 -303.64587) (xy 397.961612 -303.6443) (xy 397.971264 -303.644046) (xy 397.988536 -303.636426)
			(xy 398.016984 -303.608232) (xy 398.023937 -303.600808) (xy 398.031809 -303.582072) (xy 398.032224 -303.57191)
			(xy 398.032224 -303.427638) (xy 398.031754 -303.417394) (xy 398.023757 -303.398531) (xy 398.01673 -303.391062)
			(xy 398.00911 -303.383696) (xy 398.008602 -303.383188) (xy 397.988536 -303.363122) (xy 397.971264 -303.355756)
			(xy 397.961612 -303.355248) (xy 397.936314 -303.353769) (xy 397.886577 -303.344078) (xy 397.8389 -303.326913)
			(xy 397.7944 -303.302675) (xy 397.754119 -303.271933) (xy 397.718999 -303.235405) (xy 397.689862 -303.193947)
			(xy 397.667391 -303.14853) (xy 397.652111 -303.100216) (xy 397.644381 -303.050136) (xy 397.644381 -302.999463)
			(xy 397.652111 -302.949384) (xy 397.667391 -302.90107) (xy 397.689862 -302.855652) (xy 397.718999 -302.814195)
			(xy 397.754119 -302.777667) (xy 397.794401 -302.746924) (xy 397.838901 -302.722687) (xy 397.886578 -302.705522)
			(xy 397.936315 -302.695831) (xy 397.961612 -302.69434) (xy 397.971264 -302.694086) (xy 397.988536 -302.686466)
			(xy 398.016984 -302.658272) (xy 398.023928 -302.650845) (xy 398.031777 -302.632109) (xy 398.032224 -302.62195)
			(xy 398.032224 -302.477678) (xy 398.031762 -302.467431) (xy 398.023775 -302.448557) (xy 398.01673 -302.441102)
			(xy 398.00911 -302.433736) (xy 398.008602 -302.433228) (xy 397.988536 -302.413162) (xy 397.971264 -302.405796)
			(xy 397.961612 -302.405288) (xy 397.936326 -302.403795) (xy 397.886615 -302.39408) (xy 397.838968 -302.376896)
			(xy 397.794499 -302.352647) (xy 397.754248 -302.3219) (xy 397.719158 -302.285374) (xy 397.690049 -302.243923)
			(xy 397.667602 -302.198517) (xy 397.652342 -302.15022) (xy 397.644627 -302.10016) (xy 397.644112 -302.074834)
			(xy 397.644593 -302.048844) (xy 397.65272 -301.997502) (xy 397.668779 -301.948064) (xy 397.692376 -301.901748)
			(xy 397.722927 -301.859693) (xy 397.759683 -301.822937) (xy 397.801736 -301.792383) (xy 397.848051 -301.768785)
			(xy 397.897488 -301.752723) (xy 397.94883 -301.744594) (xy 397.97482 -301.744126) (xy 397.999363 -301.744594)
			(xy 398.047906 -301.751885) (xy 398.094842 -301.766259) (xy 398.139143 -301.787401) (xy 398.159732 -301.800768)
			(xy 398.162872 -301.802796) (xy 398.169631 -301.805988) (xy 398.173194 -301.807118) (xy 398.180589 -301.801143)
			(xy 398.195966 -301.789961) (xy 398.203928 -301.784766) (xy 398.208754 -301.781718) (xy 398.355312 -301.634906)
			(xy 398.361996 -301.627496) (xy 398.369578 -301.60906) (xy 398.370044 -301.599092) (xy 398.370044 -301.436786)
			(xy 398.369536 -301.432722) (xy 398.369536 -301.41418) (xy 398.369092 -301.404037) (xy 398.361251 -301.385327)
			(xy 398.346793 -301.371096) (xy 398.337532 -301.366936) (xy 398.27073 -301.340266) (xy 398.263575 -301.337756)
			(xy 398.248465 -301.336586) (xy 398.241012 -301.33798) (xy 398.240504 -301.33798) (xy 398.233177 -301.33992)
			(xy 398.220004 -301.347402) (xy 398.214596 -301.352712) (xy 398.195723 -301.371797) (xy 398.152942 -301.404208)
			(xy 398.105494 -301.429295) (xy 398.054621 -301.4464) (xy 398.001656 -301.455076) (xy 397.97482 -301.455582)
			(xy 397.948832 -301.4551) (xy 397.897495 -301.446972) (xy 397.848061 -301.430913) (xy 397.801749 -301.407318)
			(xy 397.759698 -301.376769) (xy 397.722944 -301.340017) (xy 397.692392 -301.297968) (xy 397.668795 -301.251657)
			(xy 397.652732 -301.202225) (xy 397.644601 -301.150888) (xy 397.644601 -301.098912) (xy 397.652732 -301.047575)
			(xy 397.668795 -300.998143) (xy 397.692392 -300.951832) (xy 397.722944 -300.909783) (xy 397.759698 -300.873031)
			(xy 397.801749 -300.842482) (xy 397.848061 -300.818887) (xy 397.897495 -300.802828) (xy 397.948832 -300.7947)
			(xy 397.97482 -300.794166) (xy 397.975328 -300.794166) (xy 398.002174 -300.794707) (xy 398.055157 -300.803414)
			(xy 398.106039 -300.820563) (xy 398.153483 -300.845704) (xy 398.196244 -300.878176) (xy 398.215104 -300.89729)
			(xy 398.225772 -300.908466) (xy 398.256252 -300.915324) (xy 398.337532 -300.882812) (xy 398.346366 -300.878844)
			(xy 398.360427 -300.865549) (xy 398.368579 -300.847999) (xy 398.369536 -300.838362) (xy 398.370044 -300.829218)
			(xy 398.370044 -300.540166) (xy 398.370582 -300.51465) (xy 398.378622 -300.464254) (xy 398.386046 -300.439836)
			(xy 398.387062 -300.436534) (xy 398.39011 -300.419516) (xy 398.39011 -299.917612) (xy 398.38757 -299.909738)
			(xy 398.384463 -299.900358) (xy 398.379253 -299.881294) (xy 398.377156 -299.871638) (xy 398.376902 -299.869352)
			(xy 398.376394 -299.867066) (xy 398.373479 -299.851608) (xy 398.370296 -299.82031) (xy 398.370044 -299.804582)
			(xy 398.370044 -299.536866) (xy 398.369536 -299.532802) (xy 398.369536 -299.51426) (xy 398.369089 -299.504119)
			(xy 398.361243 -299.485415) (xy 398.346784 -299.471191) (xy 398.337532 -299.467016) (xy 398.27073 -299.440346)
			(xy 398.263575 -299.437833) (xy 398.248464 -299.436661) (xy 398.241012 -299.43806) (xy 398.240504 -299.43806)
			(xy 398.233179 -299.440003) (xy 398.220014 -299.447493) (xy 398.214596 -299.452792) (xy 398.195723 -299.471878)
			(xy 398.152944 -299.504291) (xy 398.105496 -299.529379) (xy 398.054622 -299.546485) (xy 398.001656 -299.555162)
			(xy 397.97482 -299.555662) (xy 397.948833 -299.555181) (xy 397.897499 -299.547053) (xy 397.848069 -299.530995)
			(xy 397.80176 -299.507401) (xy 397.759711 -299.476854) (xy 397.722959 -299.440104) (xy 397.692409 -299.398058)
			(xy 397.668813 -299.351749) (xy 397.652752 -299.30232) (xy 397.644621 -299.250987) (xy 397.644621 -299.199013)
			(xy 397.652752 -299.14768) (xy 397.668813 -299.098251) (xy 397.692409 -299.051943) (xy 397.722959 -299.009896)
			(xy 397.759711 -298.973146) (xy 397.80176 -298.942599) (xy 397.848069 -298.919005) (xy 397.897499 -298.902947)
			(xy 397.948833 -298.894819) (xy 397.97482 -298.894246) (xy 397.975328 -298.894246) (xy 398.002175 -298.894787)
			(xy 398.055158 -298.903494) (xy 398.10604 -298.920642) (xy 398.153485 -298.945782) (xy 398.196248 -298.978253)
			(xy 398.215104 -298.99737) (xy 398.225772 -299.0088) (xy 398.255744 -299.015404) (xy 398.353026 -298.976796)
			(xy 398.35963 -298.974256) (xy 398.365472 -298.9707) (xy 398.372748 -298.965884) (xy 398.383791 -298.952389)
			(xy 398.389697 -298.935983) (xy 398.39011 -298.927266) (xy 398.39011 -298.772072) (xy 398.390539 -298.762004)
			(xy 398.398261 -298.743408) (xy 398.405096 -298.736004) (xy 398.560036 -298.581064) (xy 398.57299 -298.581064)
			(xy 398.626584 -298.491402) (xy 398.629889 -298.485374) (xy 398.633481 -298.472112) (xy 398.633696 -298.46524)
			(xy 398.633696 -298.437808) (xy 398.631156 -298.426632) (xy 398.628362 -298.421298) (xy 398.61765 -298.398455)
			(xy 398.602496 -298.350335) (xy 398.594811 -298.300473) (xy 398.594326 -298.275248) (xy 398.594326 -298.27474)
			(xy 398.594836 -298.248753) (xy 398.602966 -298.197418) (xy 398.619027 -298.147988) (xy 398.642623 -298.101678)
			(xy 398.673173 -298.05963) (xy 398.709924 -298.022879) (xy 398.751972 -297.992329) (xy 398.798282 -297.968733)
			(xy 398.847712 -297.952672) (xy 398.899047 -297.944542) (xy 398.951021 -297.944542) (xy 399.002356 -297.952672)
			(xy 399.051786 -297.968733) (xy 399.098096 -297.992329) (xy 399.140144 -298.022879) (xy 399.176895 -298.05963)
			(xy 399.207445 -298.101678) (xy 399.231041 -298.147988) (xy 399.247102 -298.197418) (xy 399.255232 -298.248753)
			(xy 399.255742 -298.27474) (xy 399.255742 -298.275248) (xy 399.255173 -298.302385) (xy 399.246264 -298.355924)
			(xy 399.228724 -298.407288) (xy 399.216372 -298.431458) (xy 399.210022 -298.443396) (xy 399.21053 -298.470066)
			(xy 399.262092 -298.556426) (xy 399.266904 -298.563766) (xy 399.280471 -298.574878) (xy 399.297009 -298.580715)
			(xy 399.30578 -298.581064) (xy 400.048476 -298.581064) (xy 400.058539 -298.581503) (xy 400.077117 -298.589244)
			(xy 400.084544 -298.59605) (xy 400.153886 -298.665392) (xy 400.161289 -298.672226) (xy 400.179887 -298.67993)
			(xy 400.189954 -298.680378) (xy 400.497548 -298.680378) (xy 400.5072 -298.681394) (xy 400.507708 -298.681394)
			(xy 400.519194 -298.682919) (xy 400.541488 -298.676695) (xy 400.558829 -298.661363) (xy 400.563842 -298.650914)
			(xy 400.60626 -298.548044) (xy 400.600418 -298.518326) (xy 400.58975 -298.507404) (xy 400.571978 -298.488712)
			(xy 400.541861 -298.446844) (xy 400.518603 -298.400811) (xy 400.502768 -298.351727) (xy 400.494738 -298.300781)
			(xy 400.494246 -298.274994) (xy 400.494246 -298.27474) (xy 400.494756 -298.248753) (xy 400.502886 -298.197418)
			(xy 400.518947 -298.147988) (xy 400.542543 -298.101678) (xy 400.573093 -298.05963) (xy 400.609844 -298.022879)
			(xy 400.651892 -297.992329) (xy 400.698202 -297.968733) (xy 400.747632 -297.952672) (xy 400.798967 -297.944542)
			(xy 400.850941 -297.944542) (xy 400.902276 -297.952672) (xy 400.951706 -297.968733) (xy 400.998016 -297.992329)
			(xy 401.040064 -298.022879) (xy 401.076815 -298.05963) (xy 401.107365 -298.101678) (xy 401.130961 -298.147988)
			(xy 401.147022 -298.197418) (xy 401.155152 -298.248753) (xy 401.155662 -298.27474) (xy 401.155662 -298.274994)
			(xy 401.155175 -298.300784) (xy 401.147174 -298.351741) (xy 401.131352 -298.400834) (xy 401.108092 -298.446873)
			(xy 401.077959 -298.488736) (xy 401.060158 -298.507404) (xy 401.059904 -298.507658) (xy 401.0533 -298.515053)
			(xy 401.045822 -298.533394) (xy 401.04586 -298.553201) (xy 401.049236 -298.562522) (xy 401.085304 -298.649136)
			(xy 401.086828 -298.652438) (xy 401.092969 -298.663088) (xy 401.112878 -298.677443) (xy 401.124928 -298.67987)
			(xy 401.132294 -298.680378) (xy 402.397468 -298.680378) (xy 402.40712 -298.681394) (xy 402.407628 -298.681394)
			(xy 402.419123 -298.682937) (xy 402.441446 -298.676734) (xy 402.458818 -298.661403) (xy 402.463762 -298.650914)
			(xy 402.50618 -298.548044) (xy 402.500338 -298.518326) (xy 402.48967 -298.507404) (xy 402.471901 -298.488711)
			(xy 402.441791 -298.44684) (xy 402.41854 -298.400807) (xy 402.402708 -298.351724) (xy 402.39468 -298.30078)
			(xy 402.394166 -298.274994) (xy 402.394166 -298.27474) (xy 402.394676 -298.248753) (xy 402.402806 -298.197418)
			(xy 402.418867 -298.147988) (xy 402.442463 -298.101678) (xy 402.473013 -298.05963) (xy 402.509764 -298.022879)
			(xy 402.551812 -297.992329) (xy 402.598122 -297.968733) (xy 402.647552 -297.952672) (xy 402.698887 -297.944542)
			(xy 402.750861 -297.944542) (xy 402.802196 -297.952672) (xy 402.851626 -297.968733) (xy 402.897936 -297.992329)
			(xy 402.939984 -298.022879) (xy 402.976735 -298.05963) (xy 403.007285 -298.101678) (xy 403.030881 -298.147988)
			(xy 403.046942 -298.197418) (xy 403.055072 -298.248753) (xy 403.055582 -298.27474) (xy 403.055582 -298.274994)
			(xy 403.055095 -298.300785) (xy 403.047095 -298.351741) (xy 403.031273 -298.400836) (xy 403.008014 -298.446875)
			(xy 402.977882 -298.488739) (xy 402.960078 -298.507404) (xy 402.959824 -298.507658) (xy 402.953229 -298.515057)
			(xy 402.945763 -298.533396) (xy 402.945801 -298.553197) (xy 402.949156 -298.562522) (xy 402.985224 -298.649136)
			(xy 402.986748 -298.652438) (xy 402.992891 -298.663085) (xy 403.012801 -298.677432) (xy 403.024848 -298.67987)
			(xy 403.032214 -298.680378) (xy 404.297388 -298.680378) (xy 404.30704 -298.681394) (xy 404.307548 -298.681394)
			(xy 404.31904 -298.682932) (xy 404.341357 -298.676725) (xy 404.358721 -298.661393) (xy 404.363682 -298.650914)
			(xy 404.4061 -298.548044) (xy 404.400258 -298.518326) (xy 404.38959 -298.507404) (xy 404.37182 -298.488711)
			(xy 404.341709 -298.446841) (xy 404.318455 -298.400808) (xy 404.302623 -298.351725) (xy 404.294595 -298.30078)
			(xy 404.294086 -298.274994) (xy 404.294086 -298.27474) (xy 404.294596 -298.248753) (xy 404.302726 -298.197418)
			(xy 404.318787 -298.147988) (xy 404.342383 -298.101678) (xy 404.372933 -298.05963) (xy 404.409684 -298.022879)
			(xy 404.451732 -297.992329) (xy 404.498042 -297.968733) (xy 404.547472 -297.952672) (xy 404.598807 -297.944542)
			(xy 404.650781 -297.944542) (xy 404.702116 -297.952672) (xy 404.751546 -297.968733) (xy 404.797856 -297.992329)
			(xy 404.839904 -298.022879) (xy 404.876655 -298.05963) (xy 404.907205 -298.101678) (xy 404.930801 -298.147988)
			(xy 404.946862 -298.197418) (xy 404.954992 -298.248753) (xy 404.955502 -298.27474) (xy 404.955502 -298.274994)
			(xy 404.955015 -298.300785) (xy 404.947015 -298.351742) (xy 404.931194 -298.400837) (xy 404.907936 -298.446876)
			(xy 404.877806 -298.488743) (xy 404.859998 -298.507404) (xy 404.859744 -298.507658) (xy 404.853147 -298.515056)
			(xy 404.845677 -298.533396) (xy 404.845715 -298.553198) (xy 404.849076 -298.562522) (xy 404.885144 -298.649136)
			(xy 404.886668 -298.652438) (xy 404.892812 -298.663082) (xy 404.912724 -298.677422) (xy 404.924768 -298.67987)
			(xy 404.932134 -298.680378) (xy 406.197562 -298.680378) (xy 406.207214 -298.681394) (xy 406.207722 -298.681394)
			(xy 406.219217 -298.682938) (xy 406.241543 -298.676737) (xy 406.258917 -298.661407) (xy 406.263856 -298.650914)
			(xy 406.306274 -298.548044) (xy 406.300432 -298.518326) (xy 406.289764 -298.507404) (xy 406.271991 -298.488713)
			(xy 406.241873 -298.446845) (xy 406.218615 -298.400812) (xy 406.202778 -298.351728) (xy 406.194748 -298.300781)
			(xy 406.19426 -298.274994) (xy 406.19426 -298.27474) (xy 406.19477 -298.248753) (xy 406.2029 -298.197418)
			(xy 406.218961 -298.147988) (xy 406.242557 -298.101678) (xy 406.273107 -298.05963) (xy 406.309858 -298.022879)
			(xy 406.351906 -297.992329) (xy 406.398216 -297.968733) (xy 406.447646 -297.952672) (xy 406.498981 -297.944542)
			(xy 406.550955 -297.944542) (xy 406.60229 -297.952672) (xy 406.65172 -297.968733) (xy 406.69803 -297.992329)
			(xy 406.740078 -298.022879) (xy 406.776829 -298.05963) (xy 406.807379 -298.101678) (xy 406.830975 -298.147988)
			(xy 406.847036 -298.197418) (xy 406.855166 -298.248753) (xy 406.855676 -298.27474) (xy 406.855676 -298.274994)
			(xy 406.855189 -298.300785) (xy 406.847189 -298.351741) (xy 406.831367 -298.400835) (xy 406.808107 -298.446874)
			(xy 406.777975 -298.488738) (xy 406.760172 -298.507404) (xy 406.759918 -298.507658) (xy 406.753324 -298.515057)
			(xy 406.745858 -298.533396) (xy 406.745896 -298.553196) (xy 406.74925 -298.562522) (xy 406.785318 -298.649136)
			(xy 406.786842 -298.652438) (xy 406.792985 -298.663086) (xy 406.812894 -298.677435) (xy 406.824942 -298.67987)
			(xy 406.832308 -298.680378) (xy 409.047442 -298.680378) (xy 409.057094 -298.681394) (xy 409.057602 -298.681394)
			(xy 409.069088 -298.68292) (xy 409.091385 -298.676698) (xy 409.108728 -298.661366) (xy 409.113736 -298.650914)
			(xy 409.156154 -298.548044) (xy 409.150312 -298.518326) (xy 409.139644 -298.507404) (xy 409.121872 -298.488712)
			(xy 409.091756 -298.446844) (xy 409.068499 -298.40081) (xy 409.052664 -298.351727) (xy 409.044634 -298.300781)
			(xy 409.04414 -298.274994) (xy 409.04414 -298.27474) (xy 409.04465 -298.248753) (xy 409.05278 -298.197418)
			(xy 409.068841 -298.147988) (xy 409.092437 -298.101678) (xy 409.122987 -298.05963) (xy 409.159738 -298.022879)
			(xy 409.201786 -297.992329) (xy 409.248096 -297.968733) (xy 409.297526 -297.952672) (xy 409.348861 -297.944542)
			(xy 409.400835 -297.944542) (xy 409.45217 -297.952672) (xy 409.5016 -297.968733) (xy 409.54791 -297.992329)
			(xy 409.589958 -298.022879) (xy 409.626709 -298.05963) (xy 409.657259 -298.101678) (xy 409.680855 -298.147988)
			(xy 409.696916 -298.197418) (xy 409.705046 -298.248753) (xy 409.705556 -298.27474) (xy 409.705556 -298.274994)
			(xy 409.705069 -298.300784) (xy 409.697068 -298.351741) (xy 409.681246 -298.400834) (xy 409.657985 -298.446872)
			(xy 409.627852 -298.488735) (xy 409.610052 -298.507404) (xy 409.609798 -298.507658) (xy 409.603195 -298.515054)
			(xy 409.595717 -298.533395) (xy 409.595756 -298.553201) (xy 409.59913 -298.562522) (xy 409.635198 -298.649136)
			(xy 409.636722 -298.652438) (xy 409.642863 -298.663089) (xy 409.662771 -298.677446) (xy 409.674822 -298.67987)
			(xy 409.682188 -298.680378) (xy 410.947616 -298.680378) (xy 410.957268 -298.681394) (xy 410.957776 -298.681394)
			(xy 410.969265 -298.682926) (xy 410.991572 -298.676711) (xy 411.008925 -298.661379) (xy 411.01391 -298.650914)
			(xy 411.056328 -298.548044) (xy 411.050486 -298.518326) (xy 411.039818 -298.507404) (xy 411.022047 -298.488712)
			(xy 410.991933 -298.446842) (xy 410.968678 -298.400809) (xy 410.952844 -298.351726) (xy 410.944815 -298.300781)
			(xy 410.944314 -298.274994) (xy 410.944314 -298.27474) (xy 410.944824 -298.248753) (xy 410.952954 -298.197418)
			(xy 410.969015 -298.147988) (xy 410.992611 -298.101678) (xy 411.023161 -298.05963) (xy 411.059912 -298.022879)
			(xy 411.10196 -297.992329) (xy 411.14827 -297.968733) (xy 411.1977 -297.952672) (xy 411.249035 -297.944542)
			(xy 411.301009 -297.944542) (xy 411.352344 -297.952672) (xy 411.401774 -297.968733) (xy 411.448084 -297.992329)
			(xy 411.490132 -298.022879) (xy 411.526883 -298.05963) (xy 411.557433 -298.101678) (xy 411.581029 -298.147988)
			(xy 411.59709 -298.197418) (xy 411.60522 -298.248753) (xy 411.60573 -298.27474) (xy 411.60573 -298.274994)
			(xy 411.605243 -298.300785) (xy 411.597244 -298.351742) (xy 411.581424 -298.400838) (xy 411.558167 -298.446879)
			(xy 411.528039 -298.488747) (xy 411.510226 -298.507404) (xy 411.509972 -298.507658) (xy 411.503372 -298.515055)
			(xy 411.495898 -298.533395) (xy 411.495937 -298.5532) (xy 411.499304 -298.562522) (xy 411.535372 -298.649136)
			(xy 411.536896 -298.652438) (xy 411.543035 -298.663092) (xy 411.562942 -298.677459) (xy 411.574996 -298.67987)
			(xy 411.582362 -298.680378) (xy 412.847536 -298.680378) (xy 412.857188 -298.681394) (xy 412.857696 -298.681394)
			(xy 412.869183 -298.682922) (xy 412.891482 -298.676701) (xy 412.908828 -298.661369) (xy 412.91383 -298.650914)
			(xy 412.956248 -298.548044) (xy 412.950406 -298.518326) (xy 412.939738 -298.507404) (xy 412.921966 -298.488712)
			(xy 412.891851 -298.446843) (xy 412.868594 -298.40081) (xy 412.852759 -298.351727) (xy 412.844729 -298.300781)
			(xy 412.844234 -298.274994) (xy 412.844234 -298.27474) (xy 412.844744 -298.248753) (xy 412.852874 -298.197418)
			(xy 412.868935 -298.147988) (xy 412.892531 -298.101678) (xy 412.923081 -298.05963) (xy 412.959832 -298.022879)
			(xy 413.00188 -297.992329) (xy 413.04819 -297.968733) (xy 413.09762 -297.952672) (xy 413.148955 -297.944542)
			(xy 413.200929 -297.944542) (xy 413.252264 -297.952672) (xy 413.301694 -297.968733) (xy 413.348004 -297.992329)
			(xy 413.390052 -298.022879) (xy 413.426803 -298.05963) (xy 413.457353 -298.101678) (xy 413.480949 -298.147988)
			(xy 413.49701 -298.197418) (xy 413.50514 -298.248753) (xy 413.50565 -298.27474) (xy 413.50565 -298.274994)
			(xy 413.505163 -298.300784) (xy 413.497162 -298.35174) (xy 413.481339 -298.400834) (xy 413.458078 -298.446871)
			(xy 413.427945 -298.488734) (xy 413.410146 -298.507404) (xy 413.409892 -298.507658) (xy 413.40329 -298.515054)
			(xy 413.395813 -298.533395) (xy 413.395851 -298.553201) (xy 413.399224 -298.562522) (xy 413.435292 -298.649136)
			(xy 413.436816 -298.652438) (xy 413.442957 -298.663089) (xy 413.462865 -298.677449) (xy 413.474916 -298.67987)
			(xy 413.482282 -298.680378) (xy 414.747456 -298.680378) (xy 414.757108 -298.681394) (xy 414.757616 -298.681394)
			(xy 414.769101 -298.682917) (xy 414.791393 -298.676691) (xy 414.80873 -298.661359) (xy 414.81375 -298.650914)
			(xy 414.856168 -298.548044) (xy 414.850326 -298.518326) (xy 414.839658 -298.507404) (xy 414.821885 -298.488713)
			(xy 414.791768 -298.446844) (xy 414.76851 -298.400811) (xy 414.752674 -298.351727) (xy 414.744644 -298.300781)
			(xy 414.744154 -298.274994) (xy 414.744154 -298.27474) (xy 414.744664 -298.248753) (xy 414.752794 -298.197418)
			(xy 414.768855 -298.147988) (xy 414.792451 -298.101678) (xy 414.823001 -298.05963) (xy 414.859752 -298.022879)
			(xy 414.9018 -297.992329) (xy 414.94811 -297.968733) (xy 414.99754 -297.952672) (xy 415.048875 -297.944542)
			(xy 415.100849 -297.944542) (xy 415.152184 -297.952672) (xy 415.201614 -297.968733) (xy 415.247924 -297.992329)
			(xy 415.289972 -298.022879) (xy 415.326723 -298.05963) (xy 415.357273 -298.101678) (xy 415.380869 -298.147988)
			(xy 415.39693 -298.197418) (xy 415.40506 -298.248753) (xy 415.40557 -298.27474) (xy 415.40557 -298.274994)
			(xy 415.405083 -298.300784) (xy 415.397083 -298.351741) (xy 415.38126 -298.400835) (xy 415.358001 -298.446873)
			(xy 415.327868 -298.488737) (xy 415.310066 -298.507404) (xy 415.309812 -298.507658) (xy 415.303207 -298.515053)
			(xy 415.295728 -298.533394) (xy 415.295766 -298.553202) (xy 415.299144 -298.562522) (xy 415.335212 -298.649136)
			(xy 415.336736 -298.652438) (xy 415.342878 -298.663087) (xy 415.362787 -298.677439) (xy 415.374836 -298.67987)
			(xy 415.382202 -298.680378) (xy 416.220656 -298.680378) (xy 416.229038 -298.679616) (xy 416.236641 -298.678097)
			(xy 416.250468 -298.671105) (xy 416.256216 -298.6659) (xy 416.325304 -298.596812) (xy 416.332152 -298.589414)
			(xy 416.33989 -298.570816) (xy 416.34029 -298.560744) (xy 416.34029 -298.242736) (xy 416.340724 -298.232671)
			(xy 416.348454 -298.214082) (xy 416.355276 -298.206668) (xy 416.805872 -297.756072) (xy 416.809892 -297.751786)
			(xy 416.816048 -297.74178) (xy 416.818064 -297.73626) (xy 416.821874 -297.725084) (xy 416.812984 -297.636692)
			(xy 416.811281 -297.625613) (xy 416.799816 -297.606383) (xy 416.790886 -297.599608) (xy 416.790632 -297.599608)
			(xy 416.768477 -297.584097) (xy 416.729064 -297.547066) (xy 416.696197 -297.50412) (xy 416.670751 -297.456402)
			(xy 416.653402 -297.40518) (xy 416.644612 -297.35182) (xy 416.644074 -297.32478) (xy 416.644585 -297.298793)
			(xy 416.652718 -297.24746) (xy 416.66878 -297.198031) (xy 416.692377 -297.151723) (xy 416.722927 -297.109676)
			(xy 416.759678 -297.072926) (xy 416.801725 -297.042376) (xy 416.848033 -297.01878) (xy 416.897462 -297.002717)
			(xy 416.948795 -296.994585) (xy 416.974782 -296.994072) (xy 417.0045 -296.995342) (xy 417.015168 -296.996358)
			(xy 417.035234 -296.9895) (xy 417.098226 -296.931588) (xy 417.105663 -296.924091) (xy 417.114183 -296.904797)
			(xy 417.114736 -296.89425) (xy 417.114736 -296.805858) (xy 417.114221 -296.795341) (xy 417.105842 -296.776046)
			(xy 417.09848 -296.76852) (xy 417.043362 -296.717466) (xy 417.035143 -296.710506) (xy 417.014745 -296.703661)
			(xy 417.003992 -296.704258) (xy 416.97529 -296.705528) (xy 416.974782 -296.705528) (xy 416.948794 -296.705017)
			(xy 416.897459 -296.696884) (xy 416.848028 -296.68082) (xy 416.801718 -296.657222) (xy 416.75967 -296.62667)
			(xy 416.722918 -296.589917) (xy 416.692369 -296.547867) (xy 416.668773 -296.501556) (xy 416.652712 -296.452124)
			(xy 416.644582 -296.400788) (xy 416.644582 -296.348812) (xy 416.652712 -296.297476) (xy 416.668773 -296.248044)
			(xy 416.692369 -296.201733) (xy 416.722918 -296.159683) (xy 416.75967 -296.12293) (xy 416.801718 -296.092378)
			(xy 416.848028 -296.06878) (xy 416.897459 -296.052716) (xy 416.948794 -296.044583) (xy 416.974782 -296.044112)
			(xy 417.0045 -296.045382) (xy 417.015168 -296.046398) (xy 417.035234 -296.03954) (xy 417.098226 -295.981628)
			(xy 417.10567 -295.974134) (xy 417.114204 -295.954839) (xy 417.114736 -295.94429) (xy 417.114736 -294.905938)
			(xy 417.114217 -294.895422) (xy 417.105833 -294.876133) (xy 417.09848 -294.8686) (xy 417.043362 -294.817546)
			(xy 417.035142 -294.810589) (xy 417.014745 -294.803747) (xy 417.003992 -294.804338) (xy 416.97529 -294.805608)
			(xy 416.974782 -294.805608) (xy 416.948796 -294.805097) (xy 416.897463 -294.796964) (xy 416.848035 -294.780902)
			(xy 416.801728 -294.757305) (xy 416.759683 -294.726755) (xy 416.722933 -294.690004) (xy 416.692386 -294.647956)
			(xy 416.668791 -294.601648) (xy 416.652731 -294.552219) (xy 416.644601 -294.500886) (xy 416.644601 -294.448914)
			(xy 416.652731 -294.397581) (xy 416.668791 -294.348152) (xy 416.692386 -294.301844) (xy 416.722933 -294.259796)
			(xy 416.759683 -294.223045) (xy 416.801728 -294.192495) (xy 416.848035 -294.168898) (xy 416.897463 -294.152836)
			(xy 416.948796 -294.144703) (xy 416.974782 -294.144192) (xy 417.0045 -294.145462) (xy 417.015168 -294.146478)
			(xy 417.035234 -294.13962) (xy 417.098226 -294.081708) (xy 417.105667 -294.074213) (xy 417.114194 -294.054918)
			(xy 417.114736 -294.04437) (xy 417.114736 -293.955978) (xy 417.114206 -293.945468) (xy 417.105807 -293.926195)
			(xy 417.09848 -293.91864) (xy 417.043362 -293.867586) (xy 417.03514 -293.860635) (xy 417.014744 -293.853802)
			(xy 417.003992 -293.854378) (xy 416.97529 -293.855648) (xy 416.974782 -293.855648) (xy 416.948793 -293.855137)
			(xy 416.897454 -293.847003) (xy 416.84802 -293.830939) (xy 416.801707 -293.807339) (xy 416.759657 -293.776785)
			(xy 416.722903 -293.74003) (xy 416.692352 -293.697977) (xy 416.668754 -293.651663) (xy 416.652693 -293.602228)
			(xy 416.644562 -293.550889) (xy 416.644562 -293.498911) (xy 416.652693 -293.447572) (xy 416.668754 -293.398137)
			(xy 416.692352 -293.351823) (xy 416.722903 -293.30977) (xy 416.759657 -293.273015) (xy 416.801707 -293.242461)
			(xy 416.84802 -293.218861) (xy 416.897454 -293.202797) (xy 416.948793 -293.194663) (xy 416.974782 -293.194232)
			(xy 417.0045 -293.195502) (xy 417.015168 -293.196518) (xy 417.035234 -293.18966) (xy 417.098226 -293.131748)
			(xy 417.105673 -293.124255) (xy 417.114215 -293.10496) (xy 417.114736 -293.09441) (xy 417.114736 -293.005764)
			(xy 417.114222 -292.995246) (xy 417.105845 -292.97595) (xy 417.09848 -292.968426) (xy 417.043362 -292.917372)
			(xy 417.035139 -292.910423) (xy 417.014744 -292.903591) (xy 417.003992 -292.904164) (xy 416.97529 -292.905434)
			(xy 416.974782 -292.905434) (xy 416.948794 -292.904923) (xy 416.897457 -292.89679) (xy 416.848025 -292.880726)
			(xy 416.801715 -292.857127) (xy 416.759666 -292.826575) (xy 416.722914 -292.789821) (xy 416.692363 -292.74777)
			(xy 416.668767 -292.701458) (xy 416.652706 -292.652025) (xy 416.644576 -292.600688) (xy 416.644576 -292.548712)
			(xy 416.652706 -292.497375) (xy 416.668767 -292.447942) (xy 416.692363 -292.40163) (xy 416.722914 -292.359579)
			(xy 416.759666 -292.322825) (xy 416.801715 -292.292273) (xy 416.848025 -292.268674) (xy 416.897457 -292.25261)
			(xy 416.948794 -292.244477) (xy 416.974782 -292.244018) (xy 417.0045 -292.245288) (xy 417.015168 -292.246304)
			(xy 417.035234 -292.239446) (xy 417.098226 -292.181534) (xy 417.105671 -292.17404) (xy 417.114208 -292.154745)
			(xy 417.114736 -292.144196) (xy 417.114736 -292.055804) (xy 417.114211 -292.045291) (xy 417.105818 -292.026012)
			(xy 417.09848 -292.018466) (xy 417.043362 -291.967412) (xy 417.035141 -291.960458) (xy 417.014744 -291.953621)
			(xy 417.003992 -291.954204) (xy 416.97529 -291.955474) (xy 416.974782 -291.955474) (xy 416.948798 -291.954963)
			(xy 416.897471 -291.946831) (xy 416.848048 -291.93077) (xy 416.801746 -291.907176) (xy 416.759705 -291.876629)
			(xy 416.722959 -291.839882) (xy 416.692415 -291.797839) (xy 416.668823 -291.751535) (xy 416.652765 -291.702111)
			(xy 416.644635 -291.650784) (xy 416.644635 -291.598816) (xy 416.652765 -291.547489) (xy 416.668823 -291.498065)
			(xy 416.692415 -291.451761) (xy 416.722959 -291.409718) (xy 416.759705 -291.372971) (xy 416.801746 -291.342424)
			(xy 416.848048 -291.31883) (xy 416.897471 -291.302769) (xy 416.948798 -291.294637) (xy 416.974782 -291.294058)
			(xy 417.0045 -291.295328) (xy 417.015168 -291.296344) (xy 417.035234 -291.289486) (xy 417.098226 -291.231574)
			(xy 417.105661 -291.224077) (xy 417.114175 -291.204782) (xy 417.114736 -291.194236) (xy 417.114736 -291.105844)
			(xy 417.114218 -291.095328) (xy 417.105836 -291.076037) (xy 417.09848 -291.068506) (xy 417.043362 -291.017452)
			(xy 417.035143 -291.010494) (xy 417.014745 -291.003651) (xy 417.003992 -291.004244) (xy 416.97529 -291.005514)
			(xy 416.974782 -291.005514) (xy 416.948795 -291.005003) (xy 416.897462 -290.99687) (xy 416.848033 -290.980807)
			(xy 416.801725 -290.95721) (xy 416.759679 -290.926659) (xy 416.722929 -290.889908) (xy 416.692381 -290.847859)
			(xy 416.668786 -290.80155) (xy 416.652726 -290.75212) (xy 416.644595 -290.700787) (xy 416.644595 -290.648813)
			(xy 416.652726 -290.59748) (xy 416.668786 -290.54805) (xy 416.692381 -290.501741) (xy 416.722929 -290.459692)
			(xy 416.759679 -290.422941) (xy 416.801725 -290.39239) (xy 416.848033 -290.368793) (xy 416.897462 -290.35273)
			(xy 416.948795 -290.344597) (xy 416.974782 -290.344098) (xy 417.0045 -290.345368) (xy 417.015168 -290.346384)
			(xy 417.035234 -290.339526) (xy 417.098226 -290.281614) (xy 417.105668 -290.274119) (xy 417.114197 -290.254824)
			(xy 417.114736 -290.244276) (xy 417.114736 -290.155884) (xy 417.114207 -290.145373) (xy 417.105809 -290.126099)
			(xy 417.09848 -290.118546) (xy 417.043362 -290.067492) (xy 417.03514 -290.060541) (xy 417.014744 -290.053706)
			(xy 417.003992 -290.054284) (xy 416.97529 -290.055554) (xy 416.974782 -290.055554) (xy 416.948794 -290.055043)
			(xy 416.897459 -290.046911) (xy 416.848028 -290.030849) (xy 416.801718 -290.007253) (xy 416.759668 -289.976703)
			(xy 416.722915 -289.939953) (xy 416.692362 -289.897906) (xy 416.668762 -289.851598) (xy 416.652696 -289.802168)
			(xy 416.644559 -289.750834) (xy 416.644074 -289.724846) (xy 416.644579 -289.698869) (xy 416.652696 -289.647552)
			(xy 416.668737 -289.598136) (xy 416.692308 -289.551836) (xy 416.722829 -289.509791) (xy 416.759549 -289.473036)
			(xy 416.801564 -289.442475) (xy 416.847841 -289.418859) (xy 416.897242 -289.40277) (xy 416.948551 -289.394604)
			(xy 416.974528 -289.394138) (xy 416.975036 -289.394138) (xy 416.985196 -289.394392) (xy 416.98672 -289.394392)
			(xy 416.994241 -289.394234) (xy 417.0087 -289.390105) (xy 417.015168 -289.386264) (xy 417.041584 -289.368992)
			(xy 417.050474 -289.36188) (xy 417.054792 -289.357308) (xy 417.057586 -289.352482) (xy 417.060888 -289.347656)
			(xy 417.083494 -289.318954) (xy 417.08853 -289.312074) (xy 417.094127 -289.295979) (xy 417.094416 -289.287458)
			(xy 417.094416 -289.214306) (xy 417.093906 -289.203885) (xy 417.085638 -289.184751) (xy 417.078414 -289.177222)
			(xy 417.016438 -289.11931) (xy 417.01141 -289.114862) (xy 416.999569 -289.108544) (xy 416.99307 -289.106864)
			(xy 416.987228 -289.105594) (xy 416.974782 -289.105594) (xy 416.948796 -289.105083) (xy 416.897465 -289.09695)
			(xy 416.848037 -289.080887) (xy 416.801731 -289.05729) (xy 416.759687 -289.02674) (xy 416.722939 -288.989989)
			(xy 416.692393 -288.947941) (xy 416.6688 -288.901633) (xy 416.652742 -288.852204) (xy 416.644614 -288.800872)
			(xy 416.644074 -288.774886) (xy 416.64458 -288.748962) (xy 416.652672 -288.697751) (xy 416.668657 -288.648429)
			(xy 416.692143 -288.602206) (xy 416.722553 -288.560214) (xy 416.759144 -288.523482) (xy 416.801019 -288.49291)
			(xy 416.847151 -288.469247) (xy 416.89641 -288.453072) (xy 416.947591 -288.444782) (xy 416.973512 -288.444178)
			(xy 416.985196 -288.444178) (xy 417.02736 -288.423096) (xy 417.033456 -288.415984) (xy 417.070286 -288.380424)
			(xy 417.070794 -288.379916) (xy 417.07943 -288.37128) (xy 417.086281 -288.363884) (xy 417.094019 -288.345285)
			(xy 417.094416 -288.335212) (xy 417.094416 -288.264346) (xy 417.093914 -288.253922) (xy 417.085656 -288.234777)
			(xy 417.078414 -288.227262) (xy 417.058094 -288.208212) (xy 417.05784 -288.207958) (xy 417.052506 -288.20237)
			(xy 417.040314 -288.186368) (xy 417.039806 -288.18586) (xy 417.033202 -288.17697) (xy 417.028098 -288.170222)
			(xy 417.01441 -288.160293) (xy 416.998229 -288.155381) (xy 416.989768 -288.15538) (xy 416.974782 -288.155634)
			(xy 416.948795 -288.155123) (xy 416.897461 -288.14699) (xy 416.848031 -288.130928) (xy 416.801722 -288.107332)
			(xy 416.759675 -288.076782) (xy 416.722923 -288.040031) (xy 416.692372 -287.997984) (xy 416.668775 -287.951676)
			(xy 416.652711 -287.902247) (xy 416.644577 -287.850913) (xy 416.644074 -287.824926) (xy 416.644502 -287.800578)
			(xy 416.651626 -287.752406) (xy 416.665724 -287.705796) (xy 416.686493 -287.661751) (xy 416.713484 -287.621221)
			(xy 416.746118 -287.585078) (xy 416.78369 -287.554101) (xy 416.804348 -287.541208) (xy 416.815016 -287.534858)
			(xy 416.827716 -287.514538) (xy 416.82924 -287.498028) (xy 416.829676 -287.4869) (xy 416.822169 -287.465958)
			(xy 416.814762 -287.457642) (xy 416.791394 -287.43402) (xy 416.783996 -287.427172) (xy 416.765398 -287.419437)
			(xy 416.755326 -287.419034) (xy 416.733228 -287.419034) (xy 416.717226 -287.421828) (xy 416.71367 -287.422844)
			(xy 416.689083 -287.430405) (xy 416.638296 -287.438568) (xy 416.612578 -287.4391) (xy 416.340544 -287.4391)
			(xy 416.329881 -287.439551) (xy 416.3104 -287.448222) (xy 416.302952 -287.455864) (xy 416.265106 -287.497774)
			(xy 416.261804 -287.505902) (xy 416.245802 -287.544002) (xy 416.245802 -287.56737) (xy 416.253168 -287.585658)
			(xy 416.260534 -287.593024) (xy 416.27823 -287.611691) (xy 416.308205 -287.653488) (xy 416.331339 -287.699425)
			(xy 416.347072 -287.748394) (xy 416.355025 -287.799209) (xy 416.35553 -287.824926) (xy 416.35502 -287.850913)
			(xy 416.34689 -287.902248) (xy 416.330829 -287.951678) (xy 416.307233 -287.997988) (xy 416.276683 -288.040036)
			(xy 416.239932 -288.076787) (xy 416.197884 -288.107337) (xy 416.151574 -288.130933) (xy 416.102144 -288.146994)
			(xy 416.050809 -288.155124) (xy 415.998835 -288.155124) (xy 415.9475 -288.146994) (xy 415.89807 -288.130933)
			(xy 415.85176 -288.107337) (xy 415.809712 -288.076787) (xy 415.772961 -288.040036) (xy 415.742411 -287.997988)
			(xy 415.718815 -287.951678) (xy 415.702754 -287.902248) (xy 415.694624 -287.850913) (xy 415.694114 -287.824926)
			(xy 415.694617 -287.799103) (xy 415.70266 -287.748088) (xy 415.718538 -287.698944) (xy 415.741865 -287.652867)
			(xy 415.772074 -287.610979) (xy 415.789872 -287.592262) (xy 415.800794 -287.58134) (xy 415.806636 -287.551368)
			(xy 415.78403 -287.497266) (xy 415.78118 -287.490841) (xy 415.772541 -287.479761) (xy 415.767012 -287.475422)
			(xy 415.759138 -287.468564) (xy 415.758884 -287.46831) (xy 415.746946 -287.455356) (xy 415.739424 -287.447979)
			(xy 415.720132 -287.439569) (xy 415.709608 -287.4391) (xy 415.39033 -287.4391) (xy 415.379907 -287.439606)
			(xy 415.360769 -287.447869) (xy 415.353246 -287.455102) (xy 415.316416 -287.494472) (xy 415.31286 -287.503108)
			(xy 415.293048 -287.551114) (xy 415.298382 -287.580578) (xy 415.308542 -287.5915) (xy 415.330386 -287.614868)
			(xy 415.347963 -287.637222) (xy 415.375992 -287.686695) (xy 415.395167 -287.740225) (xy 415.404926 -287.796242)
			(xy 415.40557 -287.824672) (xy 415.40557 -287.824926) (xy 415.40506 -287.850913) (xy 415.39693 -287.902248)
			(xy 415.380869 -287.951678) (xy 415.357273 -287.997988) (xy 415.326723 -288.040036) (xy 415.289972 -288.076787)
			(xy 415.247924 -288.107337) (xy 415.201614 -288.130933) (xy 415.152184 -288.146994) (xy 415.100849 -288.155124)
			(xy 415.048875 -288.155124) (xy 414.99754 -288.146994) (xy 414.94811 -288.130933) (xy 414.9018 -288.107337)
			(xy 414.859752 -288.076787) (xy 414.823001 -288.040036) (xy 414.792451 -287.997988) (xy 414.768855 -287.951678)
			(xy 414.752794 -287.902248) (xy 414.744664 -287.850913) (xy 414.744154 -287.824926) (xy 414.744657 -287.799103)
			(xy 414.752699 -287.748087) (xy 414.768574 -287.698941) (xy 414.791898 -287.652862) (xy 414.822103 -287.610969)
			(xy 414.839912 -287.592262) (xy 414.850834 -287.58134) (xy 414.856676 -287.551368) (xy 414.83407 -287.497266)
			(xy 414.831222 -287.49084) (xy 414.822587 -287.479754) (xy 414.817052 -287.475422) (xy 414.809178 -287.468564)
			(xy 414.808924 -287.46831) (xy 414.796986 -287.455356) (xy 414.78946 -287.447989) (xy 414.770169 -287.439602)
			(xy 414.759648 -287.4391) (xy 414.44037 -287.4391) (xy 414.429944 -287.439598) (xy 414.410794 -287.447852)
			(xy 414.403286 -287.455102) (xy 414.366456 -287.494472) (xy 414.3629 -287.503108) (xy 414.343088 -287.551114)
			(xy 414.348422 -287.580578) (xy 414.358582 -287.5915) (xy 414.380426 -287.614868) (xy 414.398001 -287.637223)
			(xy 414.426026 -287.686696) (xy 414.445199 -287.740226) (xy 414.454957 -287.796243) (xy 414.45561 -287.824672)
			(xy 414.45561 -287.824926) (xy 414.4551 -287.850913) (xy 414.44697 -287.902248) (xy 414.430909 -287.951678)
			(xy 414.407313 -287.997988) (xy 414.376763 -288.040036) (xy 414.340012 -288.076787) (xy 414.297964 -288.107337)
			(xy 414.251654 -288.130933) (xy 414.202224 -288.146994) (xy 414.150889 -288.155124) (xy 414.098915 -288.155124)
			(xy 414.04758 -288.146994) (xy 413.99815 -288.130933) (xy 413.95184 -288.107337) (xy 413.909792 -288.076787)
			(xy 413.873041 -288.040036) (xy 413.842491 -287.997988) (xy 413.818895 -287.951678) (xy 413.802834 -287.902248)
			(xy 413.794704 -287.850913) (xy 413.794194 -287.824926) (xy 413.794697 -287.799103) (xy 413.802739 -287.748088)
			(xy 413.818617 -287.698943) (xy 413.841943 -287.652865) (xy 413.87215 -287.610975) (xy 413.889952 -287.592262)
			(xy 413.900874 -287.58134) (xy 413.906716 -287.551368) (xy 413.88411 -287.497266) (xy 413.881264 -287.490838)
			(xy 413.872634 -287.479747) (xy 413.867092 -287.475422) (xy 413.859218 -287.468564) (xy 413.858964 -287.46831)
			(xy 413.847026 -287.455356) (xy 413.839502 -287.447983) (xy 413.820211 -287.43958) (xy 413.809688 -287.4391)
			(xy 413.49041 -287.4391) (xy 413.479989 -287.439609) (xy 413.460856 -287.447878) (xy 413.453326 -287.455102)
			(xy 413.416496 -287.494472) (xy 413.41294 -287.503108) (xy 413.393128 -287.551114) (xy 413.398462 -287.580578)
			(xy 413.408622 -287.5915) (xy 413.430466 -287.614868) (xy 413.448044 -287.637222) (xy 413.476074 -287.686694)
			(xy 413.495251 -287.740224) (xy 413.50501 -287.796242) (xy 413.50565 -287.824672) (xy 413.50565 -287.824926)
			(xy 413.50514 -287.850913) (xy 413.49701 -287.902248) (xy 413.480949 -287.951678) (xy 413.457353 -287.997988)
			(xy 413.426803 -288.040036) (xy 413.390052 -288.076787) (xy 413.348004 -288.107337) (xy 413.301694 -288.130933)
			(xy 413.252264 -288.146994) (xy 413.200929 -288.155124) (xy 413.148955 -288.155124) (xy 413.09762 -288.146994)
			(xy 413.04819 -288.130933) (xy 413.00188 -288.107337) (xy 412.959832 -288.076787) (xy 412.923081 -288.040036)
			(xy 412.892531 -287.997988) (xy 412.868935 -287.951678) (xy 412.852874 -287.902248) (xy 412.844744 -287.850913)
			(xy 412.844234 -287.824926) (xy 412.844737 -287.799104) (xy 412.85278 -287.748089) (xy 412.868659 -287.698945)
			(xy 412.891987 -287.652869) (xy 412.922197 -287.610982) (xy 412.939992 -287.592262) (xy 412.950914 -287.58134)
			(xy 412.956756 -287.551368) (xy 412.93415 -287.497266) (xy 412.931301 -287.490841) (xy 412.922664 -287.479758)
			(xy 412.917132 -287.475422) (xy 412.909258 -287.468564) (xy 412.909004 -287.46831) (xy 412.897066 -287.455356)
			(xy 412.889539 -287.447993) (xy 412.870247 -287.439613) (xy 412.859728 -287.4391) (xy 412.540704 -287.4391)
			(xy 412.530045 -287.439558) (xy 412.510576 -287.44824) (xy 412.503112 -287.455864) (xy 412.465266 -287.497774)
			(xy 412.461964 -287.505902) (xy 412.445962 -287.544002) (xy 412.445962 -287.56737) (xy 412.453328 -287.585658)
			(xy 412.460694 -287.593024) (xy 412.478392 -287.61169) (xy 412.50837 -287.653485) (xy 412.531507 -287.699423)
			(xy 412.547243 -287.748392) (xy 412.555197 -287.799208) (xy 412.55569 -287.824926) (xy 412.55518 -287.850913)
			(xy 412.54705 -287.902248) (xy 412.530989 -287.951678) (xy 412.507393 -287.997988) (xy 412.476843 -288.040036)
			(xy 412.440092 -288.076787) (xy 412.398044 -288.107337) (xy 412.351734 -288.130933) (xy 412.302304 -288.146994)
			(xy 412.250969 -288.155124) (xy 412.198995 -288.155124) (xy 412.14766 -288.146994) (xy 412.09823 -288.130933)
			(xy 412.05192 -288.107337) (xy 412.009872 -288.076787) (xy 411.973121 -288.040036) (xy 411.942571 -287.997988)
			(xy 411.918975 -287.951678) (xy 411.902914 -287.902248) (xy 411.894784 -287.850913) (xy 411.894274 -287.824926)
			(xy 411.894777 -287.799103) (xy 411.902819 -287.748087) (xy 411.918696 -287.698942) (xy 411.942021 -287.652864)
			(xy 411.972227 -287.610972) (xy 411.990032 -287.592262) (xy 412.000954 -287.58134) (xy 412.006796 -287.551368)
			(xy 411.98419 -287.497266) (xy 411.981343 -287.490839) (xy 411.97271 -287.479751) (xy 411.967172 -287.475422)
			(xy 411.959298 -287.468564) (xy 411.959044 -287.46831) (xy 411.947106 -287.455356) (xy 411.939581 -287.447986)
			(xy 411.92029 -287.439591) (xy 411.909768 -287.4391) (xy 411.59049 -287.4391) (xy 411.580071 -287.439613)
			(xy 411.560943 -287.447887) (xy 411.553406 -287.455102) (xy 411.516576 -287.494472) (xy 411.51302 -287.503108)
			(xy 411.493208 -287.551114) (xy 411.498542 -287.580578) (xy 411.508702 -287.5915) (xy 411.530546 -287.614868)
			(xy 411.548125 -287.637221) (xy 411.576157 -287.686693) (xy 411.595335 -287.740223) (xy 411.605095 -287.796242)
			(xy 411.60573 -287.824672) (xy 411.60573 -287.824926) (xy 411.60522 -287.850913) (xy 411.59709 -287.902248)
			(xy 411.581029 -287.951678) (xy 411.557433 -287.997988) (xy 411.526883 -288.040036) (xy 411.490132 -288.076787)
			(xy 411.448084 -288.107337) (xy 411.401774 -288.130933) (xy 411.352344 -288.146994) (xy 411.301009 -288.155124)
			(xy 411.249035 -288.155124) (xy 411.1977 -288.146994) (xy 411.14827 -288.130933) (xy 411.10196 -288.107337)
			(xy 411.059912 -288.076787) (xy 411.023161 -288.040036) (xy 410.992611 -287.997988) (xy 410.969015 -287.951678)
			(xy 410.952954 -287.902248) (xy 410.944824 -287.850913) (xy 410.944314 -287.824926) (xy 410.944817 -287.799103)
			(xy 410.95286 -287.748088) (xy 410.968738 -287.698944) (xy 410.992065 -287.652867) (xy 411.022274 -287.610979)
			(xy 411.040072 -287.592262) (xy 411.050994 -287.58134) (xy 411.056836 -287.551368) (xy 411.03423 -287.497266)
			(xy 411.03138 -287.490841) (xy 411.022741 -287.479761) (xy 411.017212 -287.475422) (xy 411.009338 -287.468564)
			(xy 411.009084 -287.46831) (xy 410.997146 -287.455356) (xy 410.989624 -287.447979) (xy 410.970332 -287.439569)
			(xy 410.959808 -287.4391) (xy 410.64053 -287.4391) (xy 410.629868 -287.439553) (xy 410.610392 -287.448228)
			(xy 410.602938 -287.455864) (xy 410.565092 -287.497774) (xy 410.56179 -287.505902) (xy 410.545788 -287.544002)
			(xy 410.545788 -287.56737) (xy 410.553154 -287.585658) (xy 410.56052 -287.593024) (xy 410.578217 -287.611691)
			(xy 410.608193 -287.653487) (xy 410.631328 -287.699424) (xy 410.647062 -287.748393) (xy 410.655015 -287.799209)
			(xy 410.655516 -287.824926) (xy 410.655006 -287.850913) (xy 410.646876 -287.902248) (xy 410.630815 -287.951678)
			(xy 410.607219 -287.997988) (xy 410.576669 -288.040036) (xy 410.539918 -288.076787) (xy 410.49787 -288.107337)
			(xy 410.45156 -288.130933) (xy 410.40213 -288.146994) (xy 410.350795 -288.155124) (xy 410.298821 -288.155124)
			(xy 410.247486 -288.146994) (xy 410.198056 -288.130933) (xy 410.151746 -288.107337) (xy 410.109698 -288.076787)
			(xy 410.072947 -288.040036) (xy 410.042397 -287.997988) (xy 410.018801 -287.951678) (xy 410.00274 -287.902248)
			(xy 409.99461 -287.850913) (xy 409.9941 -287.824926) (xy 409.994603 -287.799103) (xy 410.002646 -287.748088)
			(xy 410.018523 -287.698944) (xy 410.041849 -287.652866) (xy 410.072057 -287.610976) (xy 410.089858 -287.592262)
			(xy 410.10078 -287.58134) (xy 410.106622 -287.551368) (xy 410.084016 -287.497266) (xy 410.081165 -287.490842)
			(xy 410.072525 -287.479764) (xy 410.066998 -287.475422) (xy 410.059124 -287.468564) (xy 410.05887 -287.46831)
			(xy 410.046932 -287.455356) (xy 410.039409 -287.447982) (xy 410.020117 -287.439577) (xy 410.009594 -287.4391)
			(xy 409.69057 -287.4391) (xy 409.679914 -287.439565) (xy 409.660455 -287.448255) (xy 409.652978 -287.455864)
			(xy 409.615132 -287.497774) (xy 409.61183 -287.505902) (xy 409.595828 -287.544002) (xy 409.595828 -287.56737)
			(xy 409.603194 -287.585658) (xy 409.61056 -287.593024) (xy 409.62826 -287.611689) (xy 409.658241 -287.653484)
			(xy 409.68138 -287.699421) (xy 409.697117 -287.748391) (xy 409.705072 -287.799208) (xy 409.705556 -287.824926)
			(xy 409.705046 -287.850913) (xy 409.696916 -287.902248) (xy 409.680855 -287.951678) (xy 409.657259 -287.997988)
			(xy 409.626709 -288.040036) (xy 409.589958 -288.076787) (xy 409.54791 -288.107337) (xy 409.5016 -288.130933)
			(xy 409.45217 -288.146994) (xy 409.400835 -288.155124) (xy 409.348861 -288.155124) (xy 409.297526 -288.146994)
			(xy 409.248096 -288.130933) (xy 409.201786 -288.107337) (xy 409.159738 -288.076787) (xy 409.122987 -288.040036)
			(xy 409.092437 -287.997988) (xy 409.068841 -287.951678) (xy 409.05278 -287.902248) (xy 409.04465 -287.850913)
			(xy 409.04414 -287.824926) (xy 409.044643 -287.799104) (xy 409.052686 -287.748089) (xy 409.068565 -287.698946)
			(xy 409.091894 -287.65287) (xy 409.122104 -287.610983) (xy 409.139898 -287.592262) (xy 409.15082 -287.58134)
			(xy 409.156662 -287.551368) (xy 409.134056 -287.497266) (xy 409.131207 -287.49084) (xy 409.122571 -287.479757)
			(xy 409.117038 -287.475422) (xy 409.109164 -287.468564) (xy 409.10891 -287.46831) (xy 409.096972 -287.455356)
			(xy 409.089445 -287.447992) (xy 409.070154 -287.43961) (xy 409.059634 -287.4391) (xy 406.961086 -287.4391)
			(xy 406.950418 -287.440116) (xy 406.943052 -287.441894) (xy 406.933357 -287.444338) (xy 406.916852 -287.455597)
			(xy 406.911048 -287.463738) (xy 406.864058 -287.53562) (xy 406.85974 -287.543494) (xy 406.858292 -287.547097)
			(xy 406.856377 -287.554623) (xy 406.85593 -287.55848) (xy 406.85466 -287.570672) (xy 406.858978 -287.582102)
			(xy 406.86906 -287.610451) (xy 406.879923 -287.669623) (xy 406.880568 -287.699704) (xy 406.880568 -287.699958)
			(xy 406.880058 -287.725945) (xy 406.871928 -287.77728) (xy 406.855867 -287.82671) (xy 406.832271 -287.87302)
			(xy 406.812773 -287.899856) (xy 408.119084 -287.899856) (xy 408.123044 -287.850802) (xy 408.134821 -287.803018)
			(xy 408.154112 -287.757742) (xy 408.180415 -287.716146) (xy 408.21305 -287.679309) (xy 408.251171 -287.648184)
			(xy 408.293792 -287.623577) (xy 408.339808 -287.606125) (xy 408.388027 -287.596281) (xy 408.437202 -287.5943)
			(xy 408.486057 -287.600232) (xy 408.533328 -287.613924) (xy 408.57779 -287.635022) (xy 408.618293 -287.662978)
			(xy 408.653786 -287.69707) (xy 408.683351 -287.736414) (xy 408.706222 -287.779991) (xy 408.721806 -287.826672)
			(xy 408.729701 -287.875249) (xy 408.730196 -287.899856) (xy 408.729701 -287.924463) (xy 408.721806 -287.97304)
			(xy 408.706222 -288.019721) (xy 408.683351 -288.063298) (xy 408.653786 -288.102642) (xy 408.618293 -288.136734)
			(xy 408.57779 -288.16469) (xy 408.533328 -288.185788) (xy 408.486057 -288.19948) (xy 408.437202 -288.205412)
			(xy 408.388027 -288.203431) (xy 408.339808 -288.193587) (xy 408.293792 -288.176135) (xy 408.251171 -288.151528)
			(xy 408.21305 -288.120403) (xy 408.180415 -288.083566) (xy 408.154112 -288.04197) (xy 408.134821 -287.996694)
			(xy 408.123044 -287.94891) (xy 408.119084 -287.899856) (xy 406.812773 -287.899856) (xy 406.801721 -287.915068)
			(xy 406.76497 -287.951819) (xy 406.722922 -287.982369) (xy 406.676612 -288.005965) (xy 406.627182 -288.022026)
			(xy 406.575847 -288.030156) (xy 406.523873 -288.030156) (xy 406.472538 -288.022026) (xy 406.423108 -288.005965)
			(xy 406.376798 -287.982369) (xy 406.33475 -287.951819) (xy 406.297999 -287.915068) (xy 406.267449 -287.87302)
			(xy 406.243853 -287.82671) (xy 406.227792 -287.77728) (xy 406.219662 -287.725945) (xy 406.219152 -287.699958)
			(xy 406.219152 -287.699704) (xy 406.219815 -287.669625) (xy 406.230683 -287.610457) (xy 406.240742 -287.582102)
			(xy 406.245314 -287.570418) (xy 406.24252 -287.546034) (xy 406.230582 -287.528254) (xy 406.230582 -287.527746)
			(xy 406.188672 -287.462468) (xy 406.183338 -287.45561) (xy 406.176158 -287.448383) (xy 406.157682 -287.439845)
			(xy 406.147524 -287.4391) (xy 405.890476 -287.4391) (xy 405.880049 -287.439597) (xy 405.860898 -287.447849)
			(xy 405.853392 -287.455102) (xy 405.816562 -287.494472) (xy 405.813006 -287.503108) (xy 405.793194 -287.551114)
			(xy 405.798528 -287.580578) (xy 405.808688 -287.5915) (xy 405.830532 -287.614868) (xy 405.848111 -287.637221)
			(xy 405.876145 -287.686693) (xy 405.895323 -287.740223) (xy 405.905084 -287.796241) (xy 405.905716 -287.824672)
			(xy 405.905716 -287.824926) (xy 405.905206 -287.850913) (xy 405.897076 -287.902248) (xy 405.881015 -287.951678)
			(xy 405.857419 -287.997988) (xy 405.826869 -288.040036) (xy 405.790118 -288.076787) (xy 405.74807 -288.107337)
			(xy 405.70176 -288.130933) (xy 405.65233 -288.146994) (xy 405.600995 -288.155124) (xy 405.549021 -288.155124)
			(xy 405.497686 -288.146994) (xy 405.448256 -288.130933) (xy 405.401946 -288.107337) (xy 405.359898 -288.076787)
			(xy 405.323147 -288.040036) (xy 405.292597 -287.997988) (xy 405.269001 -287.951678) (xy 405.25294 -287.902248)
			(xy 405.24481 -287.850913) (xy 405.2443 -287.824926) (xy 405.244803 -287.799103) (xy 405.252846 -287.748088)
			(xy 405.268723 -287.698944) (xy 405.292049 -287.652866) (xy 405.322257 -287.610976) (xy 405.340058 -287.592262)
			(xy 405.35098 -287.58134) (xy 405.356822 -287.551368) (xy 405.334216 -287.497266) (xy 405.331365 -287.490842)
			(xy 405.322725 -287.479764) (xy 405.317198 -287.475422) (xy 405.309324 -287.468564) (xy 405.30907 -287.46831)
			(xy 405.297132 -287.455356) (xy 405.289609 -287.447982) (xy 405.270317 -287.439577) (xy 405.259794 -287.4391)
			(xy 404.940516 -287.4391) (xy 404.929855 -287.439556) (xy 404.910383 -287.448235) (xy 404.902924 -287.455864)
			(xy 404.865078 -287.497774) (xy 404.861776 -287.505902) (xy 404.845774 -287.544002) (xy 404.845774 -287.56737)
			(xy 404.85314 -287.585658) (xy 404.860506 -287.593024) (xy 404.878203 -287.61169) (xy 404.908181 -287.653486)
			(xy 404.931316 -287.699424) (xy 404.947052 -287.748392) (xy 404.955005 -287.799208) (xy 404.955502 -287.824926)
			(xy 404.954992 -287.850913) (xy 404.946862 -287.902248) (xy 404.930801 -287.951678) (xy 404.907205 -287.997988)
			(xy 404.876655 -288.040036) (xy 404.839904 -288.076787) (xy 404.797856 -288.107337) (xy 404.751546 -288.130933)
			(xy 404.702116 -288.146994) (xy 404.650781 -288.155124) (xy 404.598807 -288.155124) (xy 404.547472 -288.146994)
			(xy 404.498042 -288.130933) (xy 404.451732 -288.107337) (xy 404.409684 -288.076787) (xy 404.372933 -288.040036)
			(xy 404.342383 -287.997988) (xy 404.318787 -287.951678) (xy 404.302726 -287.902248) (xy 404.294596 -287.850913)
			(xy 404.294086 -287.824926) (xy 404.294589 -287.799103) (xy 404.302631 -287.748088) (xy 404.318508 -287.698943)
			(xy 404.341834 -287.652865) (xy 404.372041 -287.610974) (xy 404.389844 -287.592262) (xy 404.400766 -287.58134)
			(xy 404.406608 -287.551368) (xy 404.384002 -287.497266) (xy 404.381155 -287.490838) (xy 404.372524 -287.479749)
			(xy 404.366984 -287.475422) (xy 404.35911 -287.468564) (xy 404.358856 -287.46831) (xy 404.346918 -287.455356)
			(xy 404.339394 -287.447984) (xy 404.320102 -287.439585) (xy 404.30958 -287.4391) (xy 403.990556 -287.4391)
			(xy 403.979892 -287.439548) (xy 403.960408 -287.448217) (xy 403.952964 -287.455864) (xy 403.915118 -287.497774)
			(xy 403.911816 -287.505902) (xy 403.895814 -287.544002) (xy 403.895814 -287.56737) (xy 403.90318 -287.585658)
			(xy 403.910546 -287.593024) (xy 403.928241 -287.611691) (xy 403.958215 -287.653488) (xy 403.981348 -287.699426)
			(xy 403.997081 -287.748394) (xy 404.005034 -287.799209) (xy 404.005542 -287.824926) (xy 404.005032 -287.850913)
			(xy 403.996902 -287.902248) (xy 403.980841 -287.951678) (xy 403.957245 -287.997988) (xy 403.926695 -288.040036)
			(xy 403.889944 -288.076787) (xy 403.847896 -288.107337) (xy 403.801586 -288.130933) (xy 403.752156 -288.146994)
			(xy 403.700821 -288.155124) (xy 403.648847 -288.155124) (xy 403.597512 -288.146994) (xy 403.548082 -288.130933)
			(xy 403.501772 -288.107337) (xy 403.459724 -288.076787) (xy 403.422973 -288.040036) (xy 403.392423 -287.997988)
			(xy 403.368827 -287.951678) (xy 403.352766 -287.902248) (xy 403.344636 -287.850913) (xy 403.344126 -287.824926)
			(xy 403.344629 -287.799104) (xy 403.352672 -287.748089) (xy 403.368551 -287.698945) (xy 403.391878 -287.652869)
			(xy 403.422088 -287.610981) (xy 403.439884 -287.592262) (xy 403.450806 -287.58134) (xy 403.456648 -287.551368)
			(xy 403.434042 -287.497266) (xy 403.431192 -287.490841) (xy 403.422555 -287.479759) (xy 403.417024 -287.475422)
			(xy 403.40915 -287.468564) (xy 403.408896 -287.46831) (xy 403.396958 -287.455356) (xy 403.38943 -287.447994)
			(xy 403.370139 -287.439617) (xy 403.35962 -287.4391) (xy 403.040342 -287.4391) (xy 403.029918 -287.439603)
			(xy 403.010776 -287.447864) (xy 403.003258 -287.455102) (xy 402.966428 -287.494472) (xy 402.962872 -287.503108)
			(xy 402.94306 -287.551114) (xy 402.948394 -287.580578) (xy 402.958554 -287.5915) (xy 402.980398 -287.614868)
			(xy 402.997974 -287.637222) (xy 403.026002 -287.686695) (xy 403.045177 -287.740225) (xy 403.054935 -287.796242)
			(xy 403.055582 -287.824672) (xy 403.055582 -287.824926) (xy 403.055072 -287.850913) (xy 403.046942 -287.902248)
			(xy 403.030881 -287.951678) (xy 403.007285 -287.997988) (xy 402.976735 -288.040036) (xy 402.939984 -288.076787)
			(xy 402.897936 -288.107337) (xy 402.851626 -288.130933) (xy 402.802196 -288.146994) (xy 402.750861 -288.155124)
			(xy 402.698887 -288.155124) (xy 402.647552 -288.146994) (xy 402.598122 -288.130933) (xy 402.551812 -288.107337)
			(xy 402.509764 -288.076787) (xy 402.473013 -288.040036) (xy 402.442463 -287.997988) (xy 402.418867 -287.951678)
			(xy 402.402806 -287.902248) (xy 402.394676 -287.850913) (xy 402.394166 -287.824926) (xy 402.394669 -287.799103)
			(xy 402.402711 -287.748087) (xy 402.418587 -287.698942) (xy 402.441912 -287.652863) (xy 402.472117 -287.610971)
			(xy 402.489924 -287.592262) (xy 402.500846 -287.58134) (xy 402.506688 -287.551368) (xy 402.484082 -287.497266)
			(xy 402.481234 -287.490839) (xy 402.472601 -287.479752) (xy 402.467064 -287.475422) (xy 402.45919 -287.468564)
			(xy 402.458936 -287.46831) (xy 402.446998 -287.455356) (xy 402.439473 -287.447987) (xy 402.420181 -287.439595)
			(xy 402.40966 -287.4391) (xy 402.090382 -287.4391) (xy 402.079964 -287.439615) (xy 402.060838 -287.447891)
			(xy 402.053298 -287.455102) (xy 402.016468 -287.494472) (xy 402.012912 -287.503108) (xy 401.9931 -287.551114)
			(xy 401.998434 -287.580578) (xy 402.008594 -287.5915) (xy 402.030438 -287.614868) (xy 402.048017 -287.637221)
			(xy 402.07605 -287.686693) (xy 402.095228 -287.740223) (xy 402.104989 -287.796241) (xy 402.105622 -287.824672)
			(xy 402.105622 -287.824926) (xy 402.105112 -287.850913) (xy 402.096982 -287.902248) (xy 402.080921 -287.951678)
			(xy 402.057325 -287.997988) (xy 402.026775 -288.040036) (xy 401.990024 -288.076787) (xy 401.947976 -288.107337)
			(xy 401.901666 -288.130933) (xy 401.852236 -288.146994) (xy 401.800901 -288.155124) (xy 401.748927 -288.155124)
			(xy 401.697592 -288.146994) (xy 401.648162 -288.130933) (xy 401.601852 -288.107337) (xy 401.559804 -288.076787)
			(xy 401.523053 -288.040036) (xy 401.492503 -287.997988) (xy 401.468907 -287.951678) (xy 401.452846 -287.902248)
			(xy 401.444716 -287.850913) (xy 401.444206 -287.824926) (xy 401.444709 -287.799103) (xy 401.452752 -287.748088)
			(xy 401.468629 -287.698944) (xy 401.491956 -287.652867) (xy 401.522164 -287.610977) (xy 401.539964 -287.592262)
			(xy 401.550886 -287.58134) (xy 401.556728 -287.551368) (xy 401.534122 -287.497266) (xy 401.531271 -287.490842)
			(xy 401.522632 -287.479763) (xy 401.517104 -287.475422) (xy 401.50923 -287.468564) (xy 401.508976 -287.46831)
			(xy 401.497038 -287.455356) (xy 401.489515 -287.447981) (xy 401.470224 -287.439573) (xy 401.4597 -287.4391)
			(xy 401.140422 -287.4391) (xy 401.13 -287.439607) (xy 401.110863 -287.447873) (xy 401.103338 -287.455102)
			(xy 401.066508 -287.494472) (xy 401.062952 -287.503108) (xy 401.04314 -287.551114) (xy 401.048474 -287.580578)
			(xy 401.058634 -287.5915) (xy 401.080478 -287.614868) (xy 401.098055 -287.637222) (xy 401.126085 -287.686694)
			(xy 401.14526 -287.740225) (xy 401.15502 -287.796242) (xy 401.155662 -287.824672) (xy 401.155662 -287.824926)
			(xy 401.155152 -287.850913) (xy 401.147022 -287.902248) (xy 401.130961 -287.951678) (xy 401.107365 -287.997988)
			(xy 401.076815 -288.040036) (xy 401.040064 -288.076787) (xy 400.998016 -288.107337) (xy 400.951706 -288.130933)
			(xy 400.902276 -288.146994) (xy 400.850941 -288.155124) (xy 400.798967 -288.155124) (xy 400.747632 -288.146994)
			(xy 400.698202 -288.130933) (xy 400.651892 -288.107337) (xy 400.609844 -288.076787) (xy 400.573093 -288.040036)
			(xy 400.542543 -287.997988) (xy 400.518947 -287.951678) (xy 400.502886 -287.902248) (xy 400.494756 -287.850913)
			(xy 400.494246 -287.824926) (xy 400.494749 -287.799104) (xy 400.502793 -287.748089) (xy 400.518672 -287.698946)
			(xy 400.542001 -287.652871) (xy 400.572211 -287.610984) (xy 400.590004 -287.592262) (xy 400.600926 -287.58134)
			(xy 400.606768 -287.551368) (xy 400.584162 -287.497266) (xy 400.581313 -287.49084) (xy 400.572678 -287.479756)
			(xy 400.567144 -287.475422) (xy 400.55927 -287.468564) (xy 400.559016 -287.46831) (xy 400.547078 -287.455356)
			(xy 400.539552 -287.44799) (xy 400.52026 -287.439606) (xy 400.50974 -287.4391) (xy 400.190462 -287.4391)
			(xy 400.180037 -287.4396) (xy 400.160889 -287.447855) (xy 400.153378 -287.455102) (xy 400.116548 -287.494472)
			(xy 400.112992 -287.503108) (xy 400.09318 -287.551114) (xy 400.098514 -287.580578) (xy 400.108674 -287.5915)
			(xy 400.130518 -287.614868) (xy 400.148093 -287.637223) (xy 400.176119 -287.686696) (xy 400.195293 -287.740226)
			(xy 400.205051 -287.796243) (xy 400.205702 -287.824672) (xy 400.205702 -287.824926) (xy 400.205192 -287.850913)
			(xy 400.197062 -287.902248) (xy 400.181001 -287.951678) (xy 400.157405 -287.997988) (xy 400.126855 -288.040036)
			(xy 400.090104 -288.076787) (xy 400.048056 -288.107337) (xy 400.001746 -288.130933) (xy 399.952316 -288.146994)
			(xy 399.900981 -288.155124) (xy 399.849007 -288.155124) (xy 399.797672 -288.146994) (xy 399.748242 -288.130933)
			(xy 399.701932 -288.107337) (xy 399.659884 -288.076787) (xy 399.623133 -288.040036) (xy 399.592583 -287.997988)
			(xy 399.568987 -287.951678) (xy 399.552926 -287.902248) (xy 399.544796 -287.850913) (xy 399.544286 -287.824926)
			(xy 399.544789 -287.799103) (xy 399.552831 -287.748088) (xy 399.568708 -287.698943) (xy 399.592034 -287.652865)
			(xy 399.622241 -287.610974) (xy 399.640044 -287.592262) (xy 399.650966 -287.58134) (xy 399.656808 -287.551368)
			(xy 399.634202 -287.497266) (xy 399.631355 -287.490838) (xy 399.622724 -287.479749) (xy 399.617184 -287.475422)
			(xy 399.60931 -287.468564) (xy 399.609056 -287.46831) (xy 399.597118 -287.455356) (xy 399.589594 -287.447984)
			(xy 399.570302 -287.439585) (xy 399.55978 -287.4391) (xy 399.240502 -287.4391) (xy 399.230082 -287.439611)
			(xy 399.210951 -287.447882) (xy 399.203418 -287.455102) (xy 399.166588 -287.494472) (xy 399.163032 -287.503108)
			(xy 399.14322 -287.551114) (xy 399.148554 -287.580578) (xy 399.158714 -287.5915) (xy 399.180558 -287.614868)
			(xy 399.198136 -287.637221) (xy 399.226167 -287.686694) (xy 399.245344 -287.740224) (xy 399.255104 -287.796242)
			(xy 399.255742 -287.824672) (xy 399.255742 -287.824926) (xy 399.255232 -287.850913) (xy 399.247102 -287.902248)
			(xy 399.231041 -287.951678) (xy 399.207445 -287.997988) (xy 399.176895 -288.040036) (xy 399.140144 -288.076787)
			(xy 399.098096 -288.107337) (xy 399.051786 -288.130933) (xy 399.002356 -288.146994) (xy 398.951021 -288.155124)
			(xy 398.899047 -288.155124) (xy 398.847712 -288.146994) (xy 398.798282 -288.130933) (xy 398.751972 -288.107337)
			(xy 398.709924 -288.076787) (xy 398.673173 -288.040036) (xy 398.642623 -287.997988) (xy 398.619027 -287.951678)
			(xy 398.602966 -287.902248) (xy 398.594836 -287.850913) (xy 398.594326 -287.824926) (xy 398.594829 -287.799104)
			(xy 398.602872 -287.748089) (xy 398.618751 -287.698945) (xy 398.642078 -287.652869) (xy 398.672288 -287.610981)
			(xy 398.690084 -287.592262) (xy 398.701006 -287.58134) (xy 398.706848 -287.551368) (xy 398.684242 -287.497266)
			(xy 398.681392 -287.490841) (xy 398.672755 -287.479759) (xy 398.667224 -287.475422) (xy 398.65935 -287.468564)
			(xy 398.659096 -287.46831) (xy 398.647158 -287.455356) (xy 398.63963 -287.447994) (xy 398.620339 -287.439617)
			(xy 398.60982 -287.4391) (xy 398.284954 -287.4391) (xy 398.278858 -287.439354) (xy 398.267174 -287.440878)
			(xy 398.258239 -287.442268) (xy 398.242111 -287.45042) (xy 398.229801 -287.463651) (xy 398.226026 -287.471866)
			(xy 398.198848 -287.53689) (xy 398.19538 -287.5463) (xy 398.195348 -287.566339) (xy 398.203006 -287.584856)
			(xy 398.20977 -287.592262) (xy 398.227596 -287.610953) (xy 398.257806 -287.652845) (xy 398.281126 -287.698928)
			(xy 398.29699 -287.74808) (xy 398.305009 -287.799102) (xy 398.305528 -287.824926) (xy 398.305018 -287.850913)
			(xy 398.296888 -287.902248) (xy 398.280827 -287.951678) (xy 398.257231 -287.997988) (xy 398.226681 -288.040036)
			(xy 398.18993 -288.076787) (xy 398.147882 -288.107337) (xy 398.101572 -288.130933) (xy 398.052142 -288.146994)
			(xy 398.000807 -288.155124) (xy 397.948833 -288.155124) (xy 397.897498 -288.146994) (xy 397.848068 -288.130933)
			(xy 397.801758 -288.107337) (xy 397.75971 -288.076787) (xy 397.722959 -288.040036) (xy 397.692409 -287.997988)
			(xy 397.668813 -287.951678) (xy 397.652752 -287.902248) (xy 397.644622 -287.850913) (xy 397.644112 -287.824926)
			(xy 397.644615 -287.799103) (xy 397.652658 -287.748088) (xy 397.668536 -287.698944) (xy 397.691863 -287.652867)
			(xy 397.722071 -287.610978) (xy 397.73987 -287.592262) (xy 397.746574 -287.58482) (xy 397.754195 -287.566317)
			(xy 397.754199 -287.546307) (xy 397.750792 -287.53689) (xy 397.723614 -287.471866) (xy 397.71828 -287.458912)
			(xy 397.69669 -287.442402) (xy 397.672052 -287.439354) (xy 397.665956 -287.4391) (xy 397.518636 -287.4391)
			(xy 397.496517 -287.437708) (xy 397.45293 -287.429683) (xy 397.431768 -287.423098) (xy 397.427958 -287.421828)
			(xy 397.415258 -287.419796) (xy 397.406876 -287.419034) (xy 397.34363 -287.419034) (xy 397.337788 -287.41878)
			(xy 397.321024 -287.416748) (xy 397.291814 -287.43402) (xy 397.248888 -287.53689) (xy 397.245423 -287.546301)
			(xy 397.245391 -287.56634) (xy 397.253041 -287.584861) (xy 397.25981 -287.592262) (xy 397.277634 -287.610954)
			(xy 397.30784 -287.652847) (xy 397.331158 -287.698931) (xy 397.347019 -287.748082) (xy 397.355038 -287.799102)
			(xy 397.355568 -287.824926) (xy 397.355058 -287.850913) (xy 397.346928 -287.902248) (xy 397.330867 -287.951678)
			(xy 397.307271 -287.997988) (xy 397.276721 -288.040036) (xy 397.23997 -288.076787) (xy 397.197922 -288.107337)
			(xy 397.151612 -288.130933) (xy 397.102182 -288.146994) (xy 397.050847 -288.155124) (xy 396.998873 -288.155124)
			(xy 396.947538 -288.146994) (xy 396.898108 -288.130933) (xy 396.851798 -288.107337) (xy 396.80975 -288.076787)
			(xy 396.772999 -288.040036) (xy 396.742449 -287.997988) (xy 396.718853 -287.951678) (xy 396.702792 -287.902248)
			(xy 396.694662 -287.850913) (xy 396.694152 -287.824926) (xy 396.694655 -287.799103) (xy 396.702697 -287.748087)
			(xy 396.718572 -287.698941) (xy 396.741896 -287.652861) (xy 396.772101 -287.610969) (xy 396.78991 -287.592262)
			(xy 396.796621 -287.584822) (xy 396.80425 -287.566318) (xy 396.804255 -287.546303) (xy 396.800832 -287.53689)
			(xy 396.764764 -287.450276) (xy 396.76054 -287.441173) (xy 396.746348 -287.427007) (xy 396.727802 -287.419383)
			(xy 396.717774 -287.419034) (xy 396.39367 -287.419034) (xy 396.387828 -287.41878) (xy 396.371064 -287.416748)
			(xy 396.341854 -287.43402) (xy 396.298928 -287.53689) (xy 396.295461 -287.5463) (xy 396.295429 -287.566339)
			(xy 396.303084 -287.584858) (xy 396.30985 -287.592262) (xy 396.327677 -287.610952) (xy 396.357888 -287.652844)
			(xy 396.38121 -287.698927) (xy 396.397075 -287.748079) (xy 396.405095 -287.799101) (xy 396.405608 -287.824926)
			(xy 396.405098 -287.850913) (xy 396.396968 -287.902248) (xy 396.380907 -287.951678) (xy 396.357311 -287.997988)
			(xy 396.326761 -288.040036) (xy 396.29001 -288.076787) (xy 396.247962 -288.107337) (xy 396.201652 -288.130933)
			(xy 396.152222 -288.146994) (xy 396.100887 -288.155124) (xy 396.048913 -288.155124) (xy 395.997578 -288.146994)
			(xy 395.948148 -288.130933) (xy 395.901838 -288.107337) (xy 395.85979 -288.076787) (xy 395.823039 -288.040036)
			(xy 395.792489 -287.997988) (xy 395.768893 -287.951678) (xy 395.752832 -287.902248) (xy 395.744702 -287.850913)
			(xy 395.744192 -287.824926) (xy 395.744695 -287.799103) (xy 395.752737 -287.748088) (xy 395.768615 -287.698943)
			(xy 395.791941 -287.652865) (xy 395.822148 -287.610975) (xy 395.83995 -287.592262) (xy 395.846656 -287.58482)
			(xy 395.85428 -287.566318) (xy 395.854284 -287.546306) (xy 395.850872 -287.53689) (xy 395.814804 -287.450276)
			(xy 395.810582 -287.441168) (xy 395.796392 -287.426991) (xy 395.777845 -287.419354) (xy 395.767814 -287.419034)
			(xy 395.44371 -287.419034) (xy 395.437868 -287.41878) (xy 395.421104 -287.416748) (xy 395.391894 -287.43402)
			(xy 395.348968 -287.53689) (xy 395.345499 -287.546299) (xy 395.345467 -287.566338) (xy 395.353127 -287.584855)
			(xy 395.35989 -287.592262) (xy 395.377715 -287.610953) (xy 395.407923 -287.652846) (xy 395.431242 -287.698929)
			(xy 395.447104 -287.748081) (xy 395.455123 -287.799102) (xy 395.455648 -287.824926) (xy 395.455138 -287.850913)
			(xy 395.447008 -287.902248) (xy 395.430947 -287.951678) (xy 395.407351 -287.997988) (xy 395.376801 -288.040036)
			(xy 395.34005 -288.076787) (xy 395.298002 -288.107337) (xy 395.251692 -288.130933) (xy 395.202262 -288.146994)
			(xy 395.150927 -288.155124) (xy 395.098953 -288.155124) (xy 395.047618 -288.146994) (xy 394.998188 -288.130933)
			(xy 394.951878 -288.107337) (xy 394.90983 -288.076787) (xy 394.873079 -288.040036) (xy 394.842529 -287.997988)
			(xy 394.818933 -287.951678) (xy 394.802872 -287.902248) (xy 394.794742 -287.850913) (xy 394.794232 -287.824926)
			(xy 394.794735 -287.799104) (xy 394.802778 -287.748089) (xy 394.818657 -287.698945) (xy 394.841985 -287.652869)
			(xy 394.872195 -287.610982) (xy 394.88999 -287.592262) (xy 394.896692 -287.584819) (xy 394.904309 -287.566317)
			(xy 394.904314 -287.546308) (xy 394.900912 -287.53689) (xy 394.864844 -287.450276) (xy 394.86062 -287.441175)
			(xy 394.846426 -287.427015) (xy 394.82788 -287.419398) (xy 394.817854 -287.419034) (xy 394.49375 -287.419034)
			(xy 394.487908 -287.41878) (xy 394.471144 -287.416748) (xy 394.441934 -287.43402) (xy 394.399008 -287.53689)
			(xy 394.395542 -287.5463) (xy 394.39551 -287.566339) (xy 394.403163 -287.58486) (xy 394.40993 -287.592262)
			(xy 394.427758 -287.610952) (xy 394.457971 -287.652843) (xy 394.481295 -287.698926) (xy 394.49716 -287.748078)
			(xy 394.505181 -287.799101) (xy 394.505688 -287.824926) (xy 394.505178 -287.850913) (xy 394.497048 -287.902248)
			(xy 394.480987 -287.951678) (xy 394.457391 -287.997988) (xy 394.426841 -288.040036) (xy 394.39009 -288.076787)
			(xy 394.348042 -288.107337) (xy 394.301732 -288.130933) (xy 394.252302 -288.146994) (xy 394.200967 -288.155124)
			(xy 394.148993 -288.155124) (xy 394.097658 -288.146994) (xy 394.048228 -288.130933) (xy 394.001918 -288.107337)
			(xy 393.95987 -288.076787) (xy 393.923119 -288.040036) (xy 393.892569 -287.997988) (xy 393.868973 -287.951678)
			(xy 393.852912 -287.902248) (xy 393.844782 -287.850913) (xy 393.844272 -287.824926) (xy 393.844775 -287.799103)
			(xy 393.852817 -287.748087) (xy 393.868693 -287.698942) (xy 393.892018 -287.652863) (xy 393.922224 -287.610972)
			(xy 393.94003 -287.592262) (xy 393.946738 -287.584821) (xy 393.954365 -287.566318) (xy 393.954369 -287.546305)
			(xy 393.950952 -287.53689) (xy 393.914884 -287.450276) (xy 393.910662 -287.441171) (xy 393.89647 -287.426999)
			(xy 393.877923 -287.419368) (xy 393.867894 -287.419034) (xy 393.54379 -287.419034) (xy 393.537948 -287.41878)
			(xy 393.521184 -287.416748) (xy 393.491974 -287.43402) (xy 393.449048 -287.53689) (xy 393.44558 -287.5463)
			(xy 393.445548 -287.566339) (xy 393.453206 -287.584856) (xy 393.45997 -287.592262) (xy 393.477796 -287.610953)
			(xy 393.508006 -287.652845) (xy 393.531326 -287.698928) (xy 393.54719 -287.74808) (xy 393.555209 -287.799102)
			(xy 393.555728 -287.824926) (xy 393.555218 -287.850913) (xy 393.547088 -287.902248) (xy 393.531027 -287.951678)
			(xy 393.507431 -287.997988) (xy 393.476881 -288.040036) (xy 393.44013 -288.076787) (xy 393.398082 -288.107337)
			(xy 393.351772 -288.130933) (xy 393.302342 -288.146994) (xy 393.251007 -288.155124) (xy 393.199033 -288.155124)
			(xy 393.147698 -288.146994) (xy 393.098268 -288.130933) (xy 393.051958 -288.107337) (xy 393.00991 -288.076787)
			(xy 392.973159 -288.040036) (xy 392.942609 -287.997988) (xy 392.919013 -287.951678) (xy 392.902952 -287.902248)
			(xy 392.894822 -287.850913) (xy 392.894312 -287.824926) (xy 392.894815 -287.799103) (xy 392.902858 -287.748088)
			(xy 392.918736 -287.698944) (xy 392.942063 -287.652867) (xy 392.972271 -287.610978) (xy 392.99007 -287.592262)
			(xy 392.996774 -287.58482) (xy 393.004395 -287.566317) (xy 393.004399 -287.546307) (xy 393.000992 -287.53689)
			(xy 392.964924 -287.450276) (xy 392.960699 -287.441177) (xy 392.946504 -287.427022) (xy 392.927959 -287.419413)
			(xy 392.917934 -287.419034) (xy 389.743696 -287.419034) (xy 389.737854 -287.41878) (xy 389.72109 -287.416748)
			(xy 389.69188 -287.43402) (xy 389.648954 -287.53689) (xy 389.645486 -287.5463) (xy 389.645453 -287.566338)
			(xy 389.653112 -287.584856) (xy 389.659876 -287.592262) (xy 389.677702 -287.610953) (xy 389.707911 -287.652845)
			(xy 389.731231 -287.698929) (xy 389.747094 -287.74808) (xy 389.755113 -287.799102) (xy 389.755634 -287.824926)
			(xy 389.755124 -287.850913) (xy 389.746994 -287.902248) (xy 389.730933 -287.951678) (xy 389.707337 -287.997988)
			(xy 389.676787 -288.040036) (xy 389.640036 -288.076787) (xy 389.597988 -288.107337) (xy 389.551678 -288.130933)
			(xy 389.502248 -288.146994) (xy 389.450913 -288.155124) (xy 389.398939 -288.155124) (xy 389.347604 -288.146994)
			(xy 389.298174 -288.130933) (xy 389.251864 -288.107337) (xy 389.209816 -288.076787) (xy 389.173065 -288.040036)
			(xy 389.142515 -287.997988) (xy 389.118919 -287.951678) (xy 389.102858 -287.902248) (xy 389.094728 -287.850913)
			(xy 389.094218 -287.824926) (xy 389.094721 -287.799104) (xy 389.102764 -287.748088) (xy 389.118642 -287.698945)
			(xy 389.141969 -287.652868) (xy 389.172178 -287.610979) (xy 389.189976 -287.592262) (xy 389.196679 -287.584819)
			(xy 389.204299 -287.566317) (xy 389.204304 -287.546307) (xy 389.200898 -287.53689) (xy 389.16483 -287.450276)
			(xy 389.160605 -287.441177) (xy 389.146411 -287.42702) (xy 389.127865 -287.419408) (xy 389.11784 -287.419034)
			(xy 386.893816 -287.419034) (xy 386.887974 -287.41878) (xy 386.87121 -287.416748) (xy 386.842 -287.43402)
			(xy 386.799074 -287.53689) (xy 386.795605 -287.546299) (xy 386.795573 -287.566338) (xy 386.803234 -287.584854)
			(xy 386.809996 -287.592262) (xy 386.827821 -287.610954) (xy 386.858028 -287.652846) (xy 386.881347 -287.69893)
			(xy 386.897209 -287.748081) (xy 386.905228 -287.799102) (xy 386.905754 -287.824926) (xy 386.905244 -287.850913)
			(xy 386.897114 -287.902248) (xy 386.881053 -287.951678) (xy 386.857457 -287.997988) (xy 386.826907 -288.040036)
			(xy 386.790156 -288.076787) (xy 386.748108 -288.107337) (xy 386.701798 -288.130933) (xy 386.652368 -288.146994)
			(xy 386.601033 -288.155124) (xy 386.549059 -288.155124) (xy 386.497724 -288.146994) (xy 386.448294 -288.130933)
			(xy 386.401984 -288.107337) (xy 386.359936 -288.076787) (xy 386.323185 -288.040036) (xy 386.292635 -287.997988)
			(xy 386.269039 -287.951678) (xy 386.252978 -287.902248) (xy 386.244848 -287.850913) (xy 386.244338 -287.824926)
			(xy 386.244841 -287.799104) (xy 386.252884 -287.748089) (xy 386.268763 -287.698946) (xy 386.292092 -287.65287)
			(xy 386.322302 -287.610983) (xy 386.340096 -287.592262) (xy 386.346797 -287.584819) (xy 386.354414 -287.566317)
			(xy 386.354418 -287.546309) (xy 386.351018 -287.53689) (xy 386.31495 -287.450276) (xy 386.310726 -287.441174)
			(xy 386.296533 -287.427012) (xy 386.277987 -287.419394) (xy 386.26796 -287.419034) (xy 385.943602 -287.419034)
			(xy 385.93776 -287.41878) (xy 385.920996 -287.416748) (xy 385.891786 -287.43402) (xy 385.84886 -287.53689)
			(xy 385.845391 -287.546299) (xy 385.845359 -287.566338) (xy 385.853018 -287.584856) (xy 385.859782 -287.592262)
			(xy 385.877608 -287.610953) (xy 385.907816 -287.652846) (xy 385.931136 -287.698929) (xy 385.946998 -287.74808)
			(xy 385.955018 -287.799102) (xy 385.95554 -287.824926) (xy 385.95503 -287.850913) (xy 385.9469 -287.902248)
			(xy 385.930839 -287.951678) (xy 385.907243 -287.997988) (xy 385.876693 -288.040036) (xy 385.839942 -288.076787)
			(xy 385.797894 -288.107337) (xy 385.751584 -288.130933) (xy 385.702154 -288.146994) (xy 385.650819 -288.155124)
			(xy 385.598845 -288.155124) (xy 385.54751 -288.146994) (xy 385.49808 -288.130933) (xy 385.45177 -288.107337)
			(xy 385.409722 -288.076787) (xy 385.372971 -288.040036) (xy 385.342421 -287.997988) (xy 385.318825 -287.951678)
			(xy 385.302764 -287.902248) (xy 385.294634 -287.850913) (xy 385.294124 -287.824926) (xy 385.294627 -287.799104)
			(xy 385.30267 -287.748089) (xy 385.318549 -287.698945) (xy 385.341876 -287.652868) (xy 385.372085 -287.61098)
			(xy 385.389882 -287.592262) (xy 385.396585 -287.584819) (xy 385.404203 -287.566317) (xy 385.404208 -287.546308)
			(xy 385.400804 -287.53689) (xy 385.364736 -287.450276) (xy 385.360511 -287.441176) (xy 385.346318 -287.427018)
			(xy 385.327772 -287.419404) (xy 385.317746 -287.419034) (xy 384.993642 -287.419034) (xy 384.9878 -287.41878)
			(xy 384.971036 -287.416748) (xy 384.941826 -287.43402) (xy 384.8989 -287.53689) (xy 384.895434 -287.546301)
			(xy 384.895402 -287.56634) (xy 384.903054 -287.58486) (xy 384.909822 -287.592262) (xy 384.927651 -287.610952)
			(xy 384.957864 -287.652842) (xy 384.981188 -287.698926) (xy 384.997054 -287.748078) (xy 385.005075 -287.799101)
			(xy 385.00558 -287.824926) (xy 385.00507 -287.850913) (xy 384.99694 -287.902248) (xy 384.980879 -287.951678)
			(xy 384.957283 -287.997988) (xy 384.926733 -288.040036) (xy 384.889982 -288.076787) (xy 384.847934 -288.107337)
			(xy 384.801624 -288.130933) (xy 384.752194 -288.146994) (xy 384.700859 -288.155124) (xy 384.648885 -288.155124)
			(xy 384.59755 -288.146994) (xy 384.54812 -288.130933) (xy 384.50181 -288.107337) (xy 384.459762 -288.076787)
			(xy 384.423011 -288.040036) (xy 384.392461 -287.997988) (xy 384.368865 -287.951678) (xy 384.352804 -287.902248)
			(xy 384.344674 -287.850913) (xy 384.344164 -287.824926) (xy 384.344667 -287.799103) (xy 384.352709 -287.748087)
			(xy 384.368585 -287.698942) (xy 384.391909 -287.652863) (xy 384.422115 -287.610971) (xy 384.439922 -287.592262)
			(xy 384.446631 -287.584822) (xy 384.454259 -287.566318) (xy 384.454264 -287.546304) (xy 384.450844 -287.53689)
			(xy 384.414776 -287.450276) (xy 384.410553 -287.441171) (xy 384.396362 -287.427002) (xy 384.377815 -287.419374)
			(xy 384.367786 -287.419034) (xy 382.516888 -287.419034) (xy 382.491742 -287.425638) (xy 382.486154 -287.428686)
			(xy 382.457932 -287.443377) (xy 382.397817 -287.464201) (xy 382.335083 -287.474782) (xy 382.303274 -287.475422)
			(xy 382.30302 -287.475422) (xy 382.271209 -287.474785) (xy 382.20847 -287.464224) (xy 382.148355 -287.443391)
			(xy 382.12014 -287.428686) (xy 382.114298 -287.425638) (xy 382.089152 -287.419034) (xy 381.630428 -287.419034)
			(xy 381.605282 -287.425638) (xy 381.599694 -287.428686) (xy 381.571471 -287.443372) (xy 381.511355 -287.464187)
			(xy 381.448622 -287.474758) (xy 381.416814 -287.475422) (xy 381.41656 -287.475422) (xy 381.384748 -287.474788)
			(xy 381.322006 -287.464233) (xy 381.261888 -287.443406) (xy 381.23368 -287.428686) (xy 381.227838 -287.425638)
			(xy 381.202692 -287.419034) (xy 380.233428 -287.419034) (xy 380.208282 -287.425638) (xy 380.202694 -287.428686)
			(xy 380.174471 -287.443372) (xy 380.114355 -287.464187) (xy 380.051622 -287.474758) (xy 380.019814 -287.475422)
			(xy 380.01956 -287.475422) (xy 379.987748 -287.474788) (xy 379.925006 -287.464233) (xy 379.864888 -287.443406)
			(xy 379.83668 -287.428686) (xy 379.830838 -287.425638) (xy 379.805692 -287.419034) (xy 369.09756 -287.419034)
			(xy 369.078764 -287.426654) (xy 369.071652 -287.43402) (xy 368.565176 -287.940496) (xy 368.55832 -287.94789)
			(xy 368.550573 -287.966489) (xy 368.55019 -287.976564) (xy 368.55019 -288.230056) (xy 374.111518 -288.230056)
			(xy 374.115589 -288.174434) (xy 374.127715 -288.119997) (xy 374.147638 -288.067906) (xy 374.174934 -288.019271)
			(xy 374.20902 -287.975128) (xy 374.249169 -287.936419) (xy 374.294527 -287.903968) (xy 374.344127 -287.878467)
			(xy 374.396911 -287.86046) (xy 374.451754 -287.85033) (xy 374.507488 -287.848293) (xy 374.562925 -287.854393)
			(xy 374.616882 -287.868499) (xy 374.668211 -287.890311) (xy 374.715817 -287.919365) (xy 374.758685 -287.95504)
			(xy 374.795902 -287.996577) (xy 374.826675 -288.04309) (xy 374.850347 -288.093587) (xy 374.866415 -288.146994)
			(xy 374.874535 -288.20217) (xy 374.875044 -288.230056) (xy 375.596656 -288.230056) (xy 375.600727 -288.174434)
			(xy 375.612853 -288.119997) (xy 375.632776 -288.067906) (xy 375.660072 -288.019271) (xy 375.694158 -287.975128)
			(xy 375.734307 -287.936419) (xy 375.779665 -287.903968) (xy 375.829265 -287.878467) (xy 375.882049 -287.86046)
			(xy 375.936892 -287.85033) (xy 375.992626 -287.848293) (xy 376.048063 -287.854393) (xy 376.10202 -287.868499)
			(xy 376.153349 -287.890311) (xy 376.200955 -287.919365) (xy 376.243823 -287.95504) (xy 376.28104 -287.996577)
			(xy 376.311813 -288.04309) (xy 376.335485 -288.093587) (xy 376.351553 -288.146994) (xy 376.359673 -288.20217)
			(xy 376.360182 -288.230056) (xy 376.359673 -288.257942) (xy 376.351553 -288.313118) (xy 376.335485 -288.366525)
			(xy 376.311813 -288.417022) (xy 376.28104 -288.463535) (xy 376.243823 -288.505072) (xy 376.200955 -288.540747)
			(xy 376.153349 -288.569801) (xy 376.10202 -288.591613) (xy 376.048063 -288.605719) (xy 375.992626 -288.611819)
			(xy 375.936892 -288.609782) (xy 375.882049 -288.599652) (xy 375.829265 -288.581645) (xy 375.779665 -288.556144)
			(xy 375.734307 -288.523693) (xy 375.694158 -288.484984) (xy 375.660072 -288.440841) (xy 375.632776 -288.392206)
			(xy 375.612853 -288.340115) (xy 375.600727 -288.285678) (xy 375.596656 -288.230056) (xy 374.875044 -288.230056)
			(xy 374.874535 -288.257942) (xy 374.866415 -288.313118) (xy 374.850347 -288.366525) (xy 374.826675 -288.417022)
			(xy 374.795902 -288.463535) (xy 374.758685 -288.505072) (xy 374.715817 -288.540747) (xy 374.668211 -288.569801)
			(xy 374.616882 -288.591613) (xy 374.562925 -288.605719) (xy 374.507488 -288.611819) (xy 374.451754 -288.609782)
			(xy 374.396911 -288.599652) (xy 374.344127 -288.581645) (xy 374.294527 -288.556144) (xy 374.249169 -288.523693)
			(xy 374.20902 -288.484984) (xy 374.174934 -288.440841) (xy 374.147638 -288.392206) (xy 374.127715 -288.340115)
			(xy 374.115589 -288.285678) (xy 374.111518 -288.230056) (xy 368.55019 -288.230056) (xy 368.55019 -288.774886)
			(xy 384.369068 -288.774886) (xy 384.373028 -288.725832) (xy 384.384805 -288.678048) (xy 384.404096 -288.632772)
			(xy 384.430399 -288.591176) (xy 384.463034 -288.554339) (xy 384.501155 -288.523214) (xy 384.543776 -288.498607)
			(xy 384.589792 -288.481155) (xy 384.638011 -288.471311) (xy 384.687186 -288.46933) (xy 384.736041 -288.475262)
			(xy 384.783312 -288.488954) (xy 384.827774 -288.510052) (xy 384.868277 -288.538008) (xy 384.90377 -288.5721)
			(xy 384.933335 -288.611444) (xy 384.956206 -288.655021) (xy 384.97179 -288.701702) (xy 384.979685 -288.750279)
			(xy 384.98018 -288.774886) (xy 385.319028 -288.774886) (xy 385.322988 -288.725832) (xy 385.334765 -288.678048)
			(xy 385.354056 -288.632772) (xy 385.380359 -288.591176) (xy 385.412994 -288.554339) (xy 385.451115 -288.523214)
			(xy 385.493736 -288.498607) (xy 385.539752 -288.481155) (xy 385.587971 -288.471311) (xy 385.637146 -288.46933)
			(xy 385.686001 -288.475262) (xy 385.733272 -288.488954) (xy 385.777734 -288.510052) (xy 385.818237 -288.538008)
			(xy 385.85373 -288.5721) (xy 385.883295 -288.611444) (xy 385.906166 -288.655021) (xy 385.92175 -288.701702)
			(xy 385.929645 -288.750279) (xy 385.93014 -288.774886) (xy 386.269242 -288.774886) (xy 386.273202 -288.725832)
			(xy 386.284979 -288.678048) (xy 386.30427 -288.632772) (xy 386.330573 -288.591176) (xy 386.363208 -288.554339)
			(xy 386.401329 -288.523214) (xy 386.44395 -288.498607) (xy 386.489966 -288.481155) (xy 386.538185 -288.471311)
			(xy 386.58736 -288.46933) (xy 386.636215 -288.475262) (xy 386.683486 -288.488954) (xy 386.727948 -288.510052)
			(xy 386.768451 -288.538008) (xy 386.803944 -288.5721) (xy 386.833509 -288.611444) (xy 386.85638 -288.655021)
			(xy 386.871964 -288.701702) (xy 386.879859 -288.750279) (xy 386.880354 -288.774886) (xy 391.019042 -288.774886)
			(xy 391.023002 -288.725832) (xy 391.034779 -288.678048) (xy 391.05407 -288.632772) (xy 391.080373 -288.591176)
			(xy 391.113008 -288.554339) (xy 391.151129 -288.523214) (xy 391.19375 -288.498607) (xy 391.239766 -288.481155)
			(xy 391.287985 -288.471311) (xy 391.33716 -288.46933) (xy 391.386015 -288.475262) (xy 391.433286 -288.488954)
			(xy 391.477748 -288.510052) (xy 391.518251 -288.538008) (xy 391.553744 -288.5721) (xy 391.583309 -288.611444)
			(xy 391.60618 -288.655021) (xy 391.621764 -288.701702) (xy 391.629659 -288.750279) (xy 391.630154 -288.774886)
			(xy 391.969002 -288.774886) (xy 391.972962 -288.725832) (xy 391.984739 -288.678048) (xy 392.00403 -288.632772)
			(xy 392.030333 -288.591176) (xy 392.062968 -288.554339) (xy 392.101089 -288.523214) (xy 392.14371 -288.498607)
			(xy 392.189726 -288.481155) (xy 392.237945 -288.471311) (xy 392.28712 -288.46933) (xy 392.335975 -288.475262)
			(xy 392.383246 -288.488954) (xy 392.427708 -288.510052) (xy 392.468211 -288.538008) (xy 392.503704 -288.5721)
			(xy 392.533269 -288.611444) (xy 392.55614 -288.655021) (xy 392.571724 -288.701702) (xy 392.579619 -288.750279)
			(xy 392.580114 -288.774886) (xy 392.919216 -288.774886) (xy 392.923176 -288.725832) (xy 392.934953 -288.678048)
			(xy 392.954244 -288.632772) (xy 392.980547 -288.591176) (xy 393.013182 -288.554339) (xy 393.051303 -288.523214)
			(xy 393.093924 -288.498607) (xy 393.13994 -288.481155) (xy 393.188159 -288.471311) (xy 393.237334 -288.46933)
			(xy 393.286189 -288.475262) (xy 393.33346 -288.488954) (xy 393.377922 -288.510052) (xy 393.418425 -288.538008)
			(xy 393.453918 -288.5721) (xy 393.483483 -288.611444) (xy 393.506354 -288.655021) (xy 393.521938 -288.701702)
			(xy 393.529833 -288.750279) (xy 393.530328 -288.774886) (xy 393.869176 -288.774886) (xy 393.873136 -288.725832)
			(xy 393.884913 -288.678048) (xy 393.904204 -288.632772) (xy 393.930507 -288.591176) (xy 393.963142 -288.554339)
			(xy 394.001263 -288.523214) (xy 394.043884 -288.498607) (xy 394.0899 -288.481155) (xy 394.138119 -288.471311)
			(xy 394.187294 -288.46933) (xy 394.236149 -288.475262) (xy 394.28342 -288.488954) (xy 394.327882 -288.510052)
			(xy 394.368385 -288.538008) (xy 394.403878 -288.5721) (xy 394.433443 -288.611444) (xy 394.456314 -288.655021)
			(xy 394.471898 -288.701702) (xy 394.479793 -288.750279) (xy 394.480288 -288.774886) (xy 394.819136 -288.774886)
			(xy 394.823096 -288.725832) (xy 394.834873 -288.678048) (xy 394.854164 -288.632772) (xy 394.880467 -288.591176)
			(xy 394.913102 -288.554339) (xy 394.951223 -288.523214) (xy 394.993844 -288.498607) (xy 395.03986 -288.481155)
			(xy 395.088079 -288.471311) (xy 395.137254 -288.46933) (xy 395.186109 -288.475262) (xy 395.23338 -288.488954)
			(xy 395.277842 -288.510052) (xy 395.318345 -288.538008) (xy 395.353838 -288.5721) (xy 395.383403 -288.611444)
			(xy 395.406274 -288.655021) (xy 395.421858 -288.701702) (xy 395.429753 -288.750279) (xy 395.430248 -288.774886)
			(xy 395.769096 -288.774886) (xy 395.773056 -288.725832) (xy 395.784833 -288.678048) (xy 395.804124 -288.632772)
			(xy 395.830427 -288.591176) (xy 395.863062 -288.554339) (xy 395.901183 -288.523214) (xy 395.943804 -288.498607)
			(xy 395.98982 -288.481155) (xy 396.038039 -288.471311) (xy 396.087214 -288.46933) (xy 396.136069 -288.475262)
			(xy 396.18334 -288.488954) (xy 396.227802 -288.510052) (xy 396.268305 -288.538008) (xy 396.303798 -288.5721)
			(xy 396.333363 -288.611444) (xy 396.356234 -288.655021) (xy 396.371818 -288.701702) (xy 396.379713 -288.750279)
			(xy 396.380208 -288.774886) (xy 396.719056 -288.774886) (xy 396.723016 -288.725832) (xy 396.734793 -288.678048)
			(xy 396.754084 -288.632772) (xy 396.780387 -288.591176) (xy 396.813022 -288.554339) (xy 396.851143 -288.523214)
			(xy 396.893764 -288.498607) (xy 396.93978 -288.481155) (xy 396.987999 -288.471311) (xy 397.037174 -288.46933)
			(xy 397.086029 -288.475262) (xy 397.1333 -288.488954) (xy 397.177762 -288.510052) (xy 397.218265 -288.538008)
			(xy 397.253758 -288.5721) (xy 397.283323 -288.611444) (xy 397.306194 -288.655021) (xy 397.321778 -288.701702)
			(xy 397.329673 -288.750279) (xy 397.330168 -288.774886) (xy 397.669016 -288.774886) (xy 397.672976 -288.725832)
			(xy 397.684753 -288.678048) (xy 397.704044 -288.632772) (xy 397.730347 -288.591176) (xy 397.762982 -288.554339)
			(xy 397.801103 -288.523214) (xy 397.843724 -288.498607) (xy 397.88974 -288.481155) (xy 397.937959 -288.471311)
			(xy 397.987134 -288.46933) (xy 398.035989 -288.475262) (xy 398.08326 -288.488954) (xy 398.127722 -288.510052)
			(xy 398.168225 -288.538008) (xy 398.203718 -288.5721) (xy 398.233283 -288.611444) (xy 398.256154 -288.655021)
			(xy 398.271738 -288.701702) (xy 398.279633 -288.750279) (xy 398.280128 -288.774886) (xy 398.61923 -288.774886)
			(xy 398.62319 -288.725832) (xy 398.634967 -288.678048) (xy 398.654258 -288.632772) (xy 398.680561 -288.591176)
			(xy 398.713196 -288.554339) (xy 398.751317 -288.523214) (xy 398.793938 -288.498607) (xy 398.839954 -288.481155)
			(xy 398.888173 -288.471311) (xy 398.937348 -288.46933) (xy 398.986203 -288.475262) (xy 399.033474 -288.488954)
			(xy 399.077936 -288.510052) (xy 399.118439 -288.538008) (xy 399.153932 -288.5721) (xy 399.183497 -288.611444)
			(xy 399.206368 -288.655021) (xy 399.221952 -288.701702) (xy 399.229847 -288.750279) (xy 399.230342 -288.774886)
			(xy 399.56919 -288.774886) (xy 399.57315 -288.725832) (xy 399.584927 -288.678048) (xy 399.604218 -288.632772)
			(xy 399.630521 -288.591176) (xy 399.663156 -288.554339) (xy 399.701277 -288.523214) (xy 399.743898 -288.498607)
			(xy 399.789914 -288.481155) (xy 399.838133 -288.471311) (xy 399.887308 -288.46933) (xy 399.936163 -288.475262)
			(xy 399.983434 -288.488954) (xy 400.027896 -288.510052) (xy 400.068399 -288.538008) (xy 400.103892 -288.5721)
			(xy 400.133457 -288.611444) (xy 400.156328 -288.655021) (xy 400.171912 -288.701702) (xy 400.179807 -288.750279)
			(xy 400.180302 -288.774886) (xy 400.51915 -288.774886) (xy 400.52311 -288.725832) (xy 400.534887 -288.678048)
			(xy 400.554178 -288.632772) (xy 400.580481 -288.591176) (xy 400.613116 -288.554339) (xy 400.651237 -288.523214)
			(xy 400.693858 -288.498607) (xy 400.739874 -288.481155) (xy 400.788093 -288.471311) (xy 400.837268 -288.46933)
			(xy 400.886123 -288.475262) (xy 400.933394 -288.488954) (xy 400.977856 -288.510052) (xy 401.018359 -288.538008)
			(xy 401.053852 -288.5721) (xy 401.083417 -288.611444) (xy 401.106288 -288.655021) (xy 401.121872 -288.701702)
			(xy 401.129767 -288.750279) (xy 401.130262 -288.774886) (xy 401.46911 -288.774886) (xy 401.47307 -288.725832)
			(xy 401.484847 -288.678048) (xy 401.504138 -288.632772) (xy 401.530441 -288.591176) (xy 401.563076 -288.554339)
			(xy 401.601197 -288.523214) (xy 401.643818 -288.498607) (xy 401.689834 -288.481155) (xy 401.738053 -288.471311)
			(xy 401.787228 -288.46933) (xy 401.836083 -288.475262) (xy 401.883354 -288.488954) (xy 401.927816 -288.510052)
			(xy 401.968319 -288.538008) (xy 402.003812 -288.5721) (xy 402.033377 -288.611444) (xy 402.056248 -288.655021)
			(xy 402.071832 -288.701702) (xy 402.079727 -288.750279) (xy 402.080222 -288.774886) (xy 402.41907 -288.774886)
			(xy 402.42303 -288.725832) (xy 402.434807 -288.678048) (xy 402.454098 -288.632772) (xy 402.480401 -288.591176)
			(xy 402.513036 -288.554339) (xy 402.551157 -288.523214) (xy 402.593778 -288.498607) (xy 402.639794 -288.481155)
			(xy 402.688013 -288.471311) (xy 402.737188 -288.46933) (xy 402.786043 -288.475262) (xy 402.833314 -288.488954)
			(xy 402.877776 -288.510052) (xy 402.918279 -288.538008) (xy 402.953772 -288.5721) (xy 402.983337 -288.611444)
			(xy 403.006208 -288.655021) (xy 403.021792 -288.701702) (xy 403.029687 -288.750279) (xy 403.030182 -288.774886)
			(xy 403.36903 -288.774886) (xy 403.37299 -288.725832) (xy 403.384767 -288.678048) (xy 403.404058 -288.632772)
			(xy 403.430361 -288.591176) (xy 403.462996 -288.554339) (xy 403.501117 -288.523214) (xy 403.543738 -288.498607)
			(xy 403.589754 -288.481155) (xy 403.637973 -288.471311) (xy 403.687148 -288.46933) (xy 403.736003 -288.475262)
			(xy 403.783274 -288.488954) (xy 403.827736 -288.510052) (xy 403.868239 -288.538008) (xy 403.903732 -288.5721)
			(xy 403.933297 -288.611444) (xy 403.956168 -288.655021) (xy 403.971752 -288.701702) (xy 403.979647 -288.750279)
			(xy 403.980142 -288.774886) (xy 404.31899 -288.774886) (xy 404.32295 -288.725832) (xy 404.334727 -288.678048)
			(xy 404.354018 -288.632772) (xy 404.380321 -288.591176) (xy 404.412956 -288.554339) (xy 404.451077 -288.523214)
			(xy 404.493698 -288.498607) (xy 404.539714 -288.481155) (xy 404.587933 -288.471311) (xy 404.637108 -288.46933)
			(xy 404.685963 -288.475262) (xy 404.733234 -288.488954) (xy 404.777696 -288.510052) (xy 404.818199 -288.538008)
			(xy 404.853692 -288.5721) (xy 404.883257 -288.611444) (xy 404.906128 -288.655021) (xy 404.921712 -288.701702)
			(xy 404.929607 -288.750279) (xy 404.930102 -288.774886) (xy 405.269204 -288.774886) (xy 405.273164 -288.725832)
			(xy 405.284941 -288.678048) (xy 405.304232 -288.632772) (xy 405.330535 -288.591176) (xy 405.36317 -288.554339)
			(xy 405.401291 -288.523214) (xy 405.443912 -288.498607) (xy 405.489928 -288.481155) (xy 405.538147 -288.471311)
			(xy 405.587322 -288.46933) (xy 405.636177 -288.475262) (xy 405.683448 -288.488954) (xy 405.72791 -288.510052)
			(xy 405.768413 -288.538008) (xy 405.803906 -288.5721) (xy 405.833471 -288.611444) (xy 405.856342 -288.655021)
			(xy 405.871926 -288.701702) (xy 405.879821 -288.750279) (xy 405.880316 -288.774886) (xy 406.219164 -288.774886)
			(xy 406.223124 -288.725832) (xy 406.234901 -288.678048) (xy 406.254192 -288.632772) (xy 406.280495 -288.591176)
			(xy 406.31313 -288.554339) (xy 406.351251 -288.523214) (xy 406.393872 -288.498607) (xy 406.439888 -288.481155)
			(xy 406.488107 -288.471311) (xy 406.537282 -288.46933) (xy 406.586137 -288.475262) (xy 406.633408 -288.488954)
			(xy 406.67787 -288.510052) (xy 406.718373 -288.538008) (xy 406.753866 -288.5721) (xy 406.783431 -288.611444)
			(xy 406.806302 -288.655021) (xy 406.821886 -288.701702) (xy 406.829781 -288.750279) (xy 406.830276 -288.774886)
			(xy 408.119084 -288.774886) (xy 408.123044 -288.725832) (xy 408.134821 -288.678048) (xy 408.154112 -288.632772)
			(xy 408.180415 -288.591176) (xy 408.21305 -288.554339) (xy 408.251171 -288.523214) (xy 408.293792 -288.498607)
			(xy 408.339808 -288.481155) (xy 408.388027 -288.471311) (xy 408.437202 -288.46933) (xy 408.486057 -288.475262)
			(xy 408.533328 -288.488954) (xy 408.57779 -288.510052) (xy 408.618293 -288.538008) (xy 408.653786 -288.5721)
			(xy 408.683351 -288.611444) (xy 408.706222 -288.655021) (xy 408.721806 -288.701702) (xy 408.729701 -288.750279)
			(xy 408.730196 -288.774886) (xy 409.069044 -288.774886) (xy 409.073004 -288.725832) (xy 409.084781 -288.678048)
			(xy 409.104072 -288.632772) (xy 409.130375 -288.591176) (xy 409.16301 -288.554339) (xy 409.201131 -288.523214)
			(xy 409.243752 -288.498607) (xy 409.289768 -288.481155) (xy 409.337987 -288.471311) (xy 409.387162 -288.46933)
			(xy 409.436017 -288.475262) (xy 409.483288 -288.488954) (xy 409.52775 -288.510052) (xy 409.568253 -288.538008)
			(xy 409.603746 -288.5721) (xy 409.633311 -288.611444) (xy 409.656182 -288.655021) (xy 409.671766 -288.701702)
			(xy 409.679661 -288.750279) (xy 409.680156 -288.774886) (xy 410.019004 -288.774886) (xy 410.022964 -288.725832)
			(xy 410.034741 -288.678048) (xy 410.054032 -288.632772) (xy 410.080335 -288.591176) (xy 410.11297 -288.554339)
			(xy 410.151091 -288.523214) (xy 410.193712 -288.498607) (xy 410.239728 -288.481155) (xy 410.287947 -288.471311)
			(xy 410.337122 -288.46933) (xy 410.385977 -288.475262) (xy 410.433248 -288.488954) (xy 410.47771 -288.510052)
			(xy 410.518213 -288.538008) (xy 410.553706 -288.5721) (xy 410.583271 -288.611444) (xy 410.606142 -288.655021)
			(xy 410.621726 -288.701702) (xy 410.629621 -288.750279) (xy 410.630116 -288.774886) (xy 410.969218 -288.774886)
			(xy 410.973178 -288.725832) (xy 410.984955 -288.678048) (xy 411.004246 -288.632772) (xy 411.030549 -288.591176)
			(xy 411.063184 -288.554339) (xy 411.101305 -288.523214) (xy 411.143926 -288.498607) (xy 411.189942 -288.481155)
			(xy 411.238161 -288.471311) (xy 411.287336 -288.46933) (xy 411.336191 -288.475262) (xy 411.383462 -288.488954)
			(xy 411.427924 -288.510052) (xy 411.468427 -288.538008) (xy 411.50392 -288.5721) (xy 411.533485 -288.611444)
			(xy 411.556356 -288.655021) (xy 411.57194 -288.701702) (xy 411.579835 -288.750279) (xy 411.58033 -288.774886)
			(xy 411.919178 -288.774886) (xy 411.923138 -288.725832) (xy 411.934915 -288.678048) (xy 411.954206 -288.632772)
			(xy 411.980509 -288.591176) (xy 412.013144 -288.554339) (xy 412.051265 -288.523214) (xy 412.093886 -288.498607)
			(xy 412.139902 -288.481155) (xy 412.188121 -288.471311) (xy 412.237296 -288.46933) (xy 412.286151 -288.475262)
			(xy 412.333422 -288.488954) (xy 412.377884 -288.510052) (xy 412.418387 -288.538008) (xy 412.45388 -288.5721)
			(xy 412.483445 -288.611444) (xy 412.506316 -288.655021) (xy 412.5219 -288.701702) (xy 412.529795 -288.750279)
			(xy 412.53029 -288.774886) (xy 412.869138 -288.774886) (xy 412.873098 -288.725832) (xy 412.884875 -288.678048)
			(xy 412.904166 -288.632772) (xy 412.930469 -288.591176) (xy 412.963104 -288.554339) (xy 413.001225 -288.523214)
			(xy 413.043846 -288.498607) (xy 413.089862 -288.481155) (xy 413.138081 -288.471311) (xy 413.187256 -288.46933)
			(xy 413.236111 -288.475262) (xy 413.283382 -288.488954) (xy 413.327844 -288.510052) (xy 413.368347 -288.538008)
			(xy 413.40384 -288.5721) (xy 413.433405 -288.611444) (xy 413.456276 -288.655021) (xy 413.47186 -288.701702)
			(xy 413.479755 -288.750279) (xy 413.48025 -288.774886) (xy 413.819098 -288.774886) (xy 413.823058 -288.725832)
			(xy 413.834835 -288.678048) (xy 413.854126 -288.632772) (xy 413.880429 -288.591176) (xy 413.913064 -288.554339)
			(xy 413.951185 -288.523214) (xy 413.993806 -288.498607) (xy 414.039822 -288.481155) (xy 414.088041 -288.471311)
			(xy 414.137216 -288.46933) (xy 414.186071 -288.475262) (xy 414.233342 -288.488954) (xy 414.277804 -288.510052)
			(xy 414.318307 -288.538008) (xy 414.3538 -288.5721) (xy 414.383365 -288.611444) (xy 414.406236 -288.655021)
			(xy 414.42182 -288.701702) (xy 414.429715 -288.750279) (xy 414.43021 -288.774886) (xy 414.769058 -288.774886)
			(xy 414.773018 -288.725832) (xy 414.784795 -288.678048) (xy 414.804086 -288.632772) (xy 414.830389 -288.591176)
			(xy 414.863024 -288.554339) (xy 414.901145 -288.523214) (xy 414.943766 -288.498607) (xy 414.989782 -288.481155)
			(xy 415.038001 -288.471311) (xy 415.087176 -288.46933) (xy 415.136031 -288.475262) (xy 415.183302 -288.488954)
			(xy 415.227764 -288.510052) (xy 415.268267 -288.538008) (xy 415.30376 -288.5721) (xy 415.333325 -288.611444)
			(xy 415.356196 -288.655021) (xy 415.37178 -288.701702) (xy 415.379675 -288.750279) (xy 415.38017 -288.774886)
			(xy 415.719018 -288.774886) (xy 415.722978 -288.725832) (xy 415.734755 -288.678048) (xy 415.754046 -288.632772)
			(xy 415.780349 -288.591176) (xy 415.812984 -288.554339) (xy 415.851105 -288.523214) (xy 415.893726 -288.498607)
			(xy 415.939742 -288.481155) (xy 415.987961 -288.471311) (xy 416.037136 -288.46933) (xy 416.085991 -288.475262)
			(xy 416.133262 -288.488954) (xy 416.177724 -288.510052) (xy 416.218227 -288.538008) (xy 416.25372 -288.5721)
			(xy 416.283285 -288.611444) (xy 416.306156 -288.655021) (xy 416.32174 -288.701702) (xy 416.329635 -288.750279)
			(xy 416.33013 -288.774886) (xy 416.329635 -288.799493) (xy 416.32174 -288.84807) (xy 416.306156 -288.894751)
			(xy 416.283285 -288.938328) (xy 416.25372 -288.977672) (xy 416.218227 -289.011764) (xy 416.177724 -289.03972)
			(xy 416.133262 -289.060818) (xy 416.085991 -289.07451) (xy 416.037136 -289.080442) (xy 415.987961 -289.078461)
			(xy 415.939742 -289.068617) (xy 415.893726 -289.051165) (xy 415.851105 -289.026558) (xy 415.812984 -288.995433)
			(xy 415.780349 -288.958596) (xy 415.754046 -288.917) (xy 415.734755 -288.871724) (xy 415.722978 -288.82394)
			(xy 415.719018 -288.774886) (xy 415.38017 -288.774886) (xy 415.379675 -288.799493) (xy 415.37178 -288.84807)
			(xy 415.356196 -288.894751) (xy 415.333325 -288.938328) (xy 415.30376 -288.977672) (xy 415.268267 -289.011764)
			(xy 415.227764 -289.03972) (xy 415.183302 -289.060818) (xy 415.136031 -289.07451) (xy 415.087176 -289.080442)
			(xy 415.038001 -289.078461) (xy 414.989782 -289.068617) (xy 414.943766 -289.051165) (xy 414.901145 -289.026558)
			(xy 414.863024 -288.995433) (xy 414.830389 -288.958596) (xy 414.804086 -288.917) (xy 414.784795 -288.871724)
			(xy 414.773018 -288.82394) (xy 414.769058 -288.774886) (xy 414.43021 -288.774886) (xy 414.429715 -288.799493)
			(xy 414.42182 -288.84807) (xy 414.406236 -288.894751) (xy 414.383365 -288.938328) (xy 414.3538 -288.977672)
			(xy 414.318307 -289.011764) (xy 414.277804 -289.03972) (xy 414.233342 -289.060818) (xy 414.186071 -289.07451)
			(xy 414.137216 -289.080442) (xy 414.088041 -289.078461) (xy 414.039822 -289.068617) (xy 413.993806 -289.051165)
			(xy 413.951185 -289.026558) (xy 413.913064 -288.995433) (xy 413.880429 -288.958596) (xy 413.854126 -288.917)
			(xy 413.834835 -288.871724) (xy 413.823058 -288.82394) (xy 413.819098 -288.774886) (xy 413.48025 -288.774886)
			(xy 413.479755 -288.799493) (xy 413.47186 -288.84807) (xy 413.456276 -288.894751) (xy 413.433405 -288.938328)
			(xy 413.40384 -288.977672) (xy 413.368347 -289.011764) (xy 413.327844 -289.03972) (xy 413.283382 -289.060818)
			(xy 413.236111 -289.07451) (xy 413.187256 -289.080442) (xy 413.138081 -289.078461) (xy 413.089862 -289.068617)
			(xy 413.043846 -289.051165) (xy 413.001225 -289.026558) (xy 412.963104 -288.995433) (xy 412.930469 -288.958596)
			(xy 412.904166 -288.917) (xy 412.884875 -288.871724) (xy 412.873098 -288.82394) (xy 412.869138 -288.774886)
			(xy 412.53029 -288.774886) (xy 412.529795 -288.799493) (xy 412.5219 -288.84807) (xy 412.506316 -288.894751)
			(xy 412.483445 -288.938328) (xy 412.45388 -288.977672) (xy 412.418387 -289.011764) (xy 412.377884 -289.03972)
			(xy 412.333422 -289.060818) (xy 412.286151 -289.07451) (xy 412.237296 -289.080442) (xy 412.188121 -289.078461)
			(xy 412.139902 -289.068617) (xy 412.093886 -289.051165) (xy 412.051265 -289.026558) (xy 412.013144 -288.995433)
			(xy 411.980509 -288.958596) (xy 411.954206 -288.917) (xy 411.934915 -288.871724) (xy 411.923138 -288.82394)
			(xy 411.919178 -288.774886) (xy 411.58033 -288.774886) (xy 411.579835 -288.799493) (xy 411.57194 -288.84807)
			(xy 411.556356 -288.894751) (xy 411.533485 -288.938328) (xy 411.50392 -288.977672) (xy 411.468427 -289.011764)
			(xy 411.427924 -289.03972) (xy 411.383462 -289.060818) (xy 411.336191 -289.07451) (xy 411.287336 -289.080442)
			(xy 411.238161 -289.078461) (xy 411.189942 -289.068617) (xy 411.143926 -289.051165) (xy 411.101305 -289.026558)
			(xy 411.063184 -288.995433) (xy 411.030549 -288.958596) (xy 411.004246 -288.917) (xy 410.984955 -288.871724)
			(xy 410.973178 -288.82394) (xy 410.969218 -288.774886) (xy 410.630116 -288.774886) (xy 410.629621 -288.799493)
			(xy 410.621726 -288.84807) (xy 410.606142 -288.894751) (xy 410.583271 -288.938328) (xy 410.553706 -288.977672)
			(xy 410.518213 -289.011764) (xy 410.47771 -289.03972) (xy 410.433248 -289.060818) (xy 410.385977 -289.07451)
			(xy 410.337122 -289.080442) (xy 410.287947 -289.078461) (xy 410.239728 -289.068617) (xy 410.193712 -289.051165)
			(xy 410.151091 -289.026558) (xy 410.11297 -288.995433) (xy 410.080335 -288.958596) (xy 410.054032 -288.917)
			(xy 410.034741 -288.871724) (xy 410.022964 -288.82394) (xy 410.019004 -288.774886) (xy 409.680156 -288.774886)
			(xy 409.679661 -288.799493) (xy 409.671766 -288.84807) (xy 409.656182 -288.894751) (xy 409.633311 -288.938328)
			(xy 409.603746 -288.977672) (xy 409.568253 -289.011764) (xy 409.52775 -289.03972) (xy 409.483288 -289.060818)
			(xy 409.436017 -289.07451) (xy 409.387162 -289.080442) (xy 409.337987 -289.078461) (xy 409.289768 -289.068617)
			(xy 409.243752 -289.051165) (xy 409.201131 -289.026558) (xy 409.16301 -288.995433) (xy 409.130375 -288.958596)
			(xy 409.104072 -288.917) (xy 409.084781 -288.871724) (xy 409.073004 -288.82394) (xy 409.069044 -288.774886)
			(xy 408.730196 -288.774886) (xy 408.729701 -288.799493) (xy 408.721806 -288.84807) (xy 408.706222 -288.894751)
			(xy 408.683351 -288.938328) (xy 408.653786 -288.977672) (xy 408.618293 -289.011764) (xy 408.57779 -289.03972)
			(xy 408.533328 -289.060818) (xy 408.486057 -289.07451) (xy 408.437202 -289.080442) (xy 408.388027 -289.078461)
			(xy 408.339808 -289.068617) (xy 408.293792 -289.051165) (xy 408.251171 -289.026558) (xy 408.21305 -288.995433)
			(xy 408.180415 -288.958596) (xy 408.154112 -288.917) (xy 408.134821 -288.871724) (xy 408.123044 -288.82394)
			(xy 408.119084 -288.774886) (xy 406.830276 -288.774886) (xy 406.829781 -288.799493) (xy 406.821886 -288.84807)
			(xy 406.806302 -288.894751) (xy 406.783431 -288.938328) (xy 406.753866 -288.977672) (xy 406.718373 -289.011764)
			(xy 406.67787 -289.03972) (xy 406.633408 -289.060818) (xy 406.586137 -289.07451) (xy 406.537282 -289.080442)
			(xy 406.488107 -289.078461) (xy 406.439888 -289.068617) (xy 406.393872 -289.051165) (xy 406.351251 -289.026558)
			(xy 406.31313 -288.995433) (xy 406.280495 -288.958596) (xy 406.254192 -288.917) (xy 406.234901 -288.871724)
			(xy 406.223124 -288.82394) (xy 406.219164 -288.774886) (xy 405.880316 -288.774886) (xy 405.879821 -288.799493)
			(xy 405.871926 -288.84807) (xy 405.856342 -288.894751) (xy 405.833471 -288.938328) (xy 405.803906 -288.977672)
			(xy 405.768413 -289.011764) (xy 405.72791 -289.03972) (xy 405.683448 -289.060818) (xy 405.636177 -289.07451)
			(xy 405.587322 -289.080442) (xy 405.538147 -289.078461) (xy 405.489928 -289.068617) (xy 405.443912 -289.051165)
			(xy 405.401291 -289.026558) (xy 405.36317 -288.995433) (xy 405.330535 -288.958596) (xy 405.304232 -288.917)
			(xy 405.284941 -288.871724) (xy 405.273164 -288.82394) (xy 405.269204 -288.774886) (xy 404.930102 -288.774886)
			(xy 404.929607 -288.799493) (xy 404.921712 -288.84807) (xy 404.906128 -288.894751) (xy 404.883257 -288.938328)
			(xy 404.853692 -288.977672) (xy 404.818199 -289.011764) (xy 404.777696 -289.03972) (xy 404.733234 -289.060818)
			(xy 404.685963 -289.07451) (xy 404.637108 -289.080442) (xy 404.587933 -289.078461) (xy 404.539714 -289.068617)
			(xy 404.493698 -289.051165) (xy 404.451077 -289.026558) (xy 404.412956 -288.995433) (xy 404.380321 -288.958596)
			(xy 404.354018 -288.917) (xy 404.334727 -288.871724) (xy 404.32295 -288.82394) (xy 404.31899 -288.774886)
			(xy 403.980142 -288.774886) (xy 403.979647 -288.799493) (xy 403.971752 -288.84807) (xy 403.956168 -288.894751)
			(xy 403.933297 -288.938328) (xy 403.903732 -288.977672) (xy 403.868239 -289.011764) (xy 403.827736 -289.03972)
			(xy 403.783274 -289.060818) (xy 403.736003 -289.07451) (xy 403.687148 -289.080442) (xy 403.637973 -289.078461)
			(xy 403.589754 -289.068617) (xy 403.543738 -289.051165) (xy 403.501117 -289.026558) (xy 403.462996 -288.995433)
			(xy 403.430361 -288.958596) (xy 403.404058 -288.917) (xy 403.384767 -288.871724) (xy 403.37299 -288.82394)
			(xy 403.36903 -288.774886) (xy 403.030182 -288.774886) (xy 403.029687 -288.799493) (xy 403.021792 -288.84807)
			(xy 403.006208 -288.894751) (xy 402.983337 -288.938328) (xy 402.953772 -288.977672) (xy 402.918279 -289.011764)
			(xy 402.877776 -289.03972) (xy 402.833314 -289.060818) (xy 402.786043 -289.07451) (xy 402.737188 -289.080442)
			(xy 402.688013 -289.078461) (xy 402.639794 -289.068617) (xy 402.593778 -289.051165) (xy 402.551157 -289.026558)
			(xy 402.513036 -288.995433) (xy 402.480401 -288.958596) (xy 402.454098 -288.917) (xy 402.434807 -288.871724)
			(xy 402.42303 -288.82394) (xy 402.41907 -288.774886) (xy 402.080222 -288.774886) (xy 402.079727 -288.799493)
			(xy 402.071832 -288.84807) (xy 402.056248 -288.894751) (xy 402.033377 -288.938328) (xy 402.003812 -288.977672)
			(xy 401.968319 -289.011764) (xy 401.927816 -289.03972) (xy 401.883354 -289.060818) (xy 401.836083 -289.07451)
			(xy 401.787228 -289.080442) (xy 401.738053 -289.078461) (xy 401.689834 -289.068617) (xy 401.643818 -289.051165)
			(xy 401.601197 -289.026558) (xy 401.563076 -288.995433) (xy 401.530441 -288.958596) (xy 401.504138 -288.917)
			(xy 401.484847 -288.871724) (xy 401.47307 -288.82394) (xy 401.46911 -288.774886) (xy 401.130262 -288.774886)
			(xy 401.129767 -288.799493) (xy 401.121872 -288.84807) (xy 401.106288 -288.894751) (xy 401.083417 -288.938328)
			(xy 401.053852 -288.977672) (xy 401.018359 -289.011764) (xy 400.977856 -289.03972) (xy 400.933394 -289.060818)
			(xy 400.886123 -289.07451) (xy 400.837268 -289.080442) (xy 400.788093 -289.078461) (xy 400.739874 -289.068617)
			(xy 400.693858 -289.051165) (xy 400.651237 -289.026558) (xy 400.613116 -288.995433) (xy 400.580481 -288.958596)
			(xy 400.554178 -288.917) (xy 400.534887 -288.871724) (xy 400.52311 -288.82394) (xy 400.51915 -288.774886)
			(xy 400.180302 -288.774886) (xy 400.179807 -288.799493) (xy 400.171912 -288.84807) (xy 400.156328 -288.894751)
			(xy 400.133457 -288.938328) (xy 400.103892 -288.977672) (xy 400.068399 -289.011764) (xy 400.027896 -289.03972)
			(xy 399.983434 -289.060818) (xy 399.936163 -289.07451) (xy 399.887308 -289.080442) (xy 399.838133 -289.078461)
			(xy 399.789914 -289.068617) (xy 399.743898 -289.051165) (xy 399.701277 -289.026558) (xy 399.663156 -288.995433)
			(xy 399.630521 -288.958596) (xy 399.604218 -288.917) (xy 399.584927 -288.871724) (xy 399.57315 -288.82394)
			(xy 399.56919 -288.774886) (xy 399.230342 -288.774886) (xy 399.229847 -288.799493) (xy 399.221952 -288.84807)
			(xy 399.206368 -288.894751) (xy 399.183497 -288.938328) (xy 399.153932 -288.977672) (xy 399.118439 -289.011764)
			(xy 399.077936 -289.03972) (xy 399.033474 -289.060818) (xy 398.986203 -289.07451) (xy 398.937348 -289.080442)
			(xy 398.888173 -289.078461) (xy 398.839954 -289.068617) (xy 398.793938 -289.051165) (xy 398.751317 -289.026558)
			(xy 398.713196 -288.995433) (xy 398.680561 -288.958596) (xy 398.654258 -288.917) (xy 398.634967 -288.871724)
			(xy 398.62319 -288.82394) (xy 398.61923 -288.774886) (xy 398.280128 -288.774886) (xy 398.279633 -288.799493)
			(xy 398.271738 -288.84807) (xy 398.256154 -288.894751) (xy 398.233283 -288.938328) (xy 398.203718 -288.977672)
			(xy 398.168225 -289.011764) (xy 398.127722 -289.03972) (xy 398.08326 -289.060818) (xy 398.035989 -289.07451)
			(xy 397.987134 -289.080442) (xy 397.937959 -289.078461) (xy 397.88974 -289.068617) (xy 397.843724 -289.051165)
			(xy 397.801103 -289.026558) (xy 397.762982 -288.995433) (xy 397.730347 -288.958596) (xy 397.704044 -288.917)
			(xy 397.684753 -288.871724) (xy 397.672976 -288.82394) (xy 397.669016 -288.774886) (xy 397.330168 -288.774886)
			(xy 397.329673 -288.799493) (xy 397.321778 -288.84807) (xy 397.306194 -288.894751) (xy 397.283323 -288.938328)
			(xy 397.253758 -288.977672) (xy 397.218265 -289.011764) (xy 397.177762 -289.03972) (xy 397.1333 -289.060818)
			(xy 397.086029 -289.07451) (xy 397.037174 -289.080442) (xy 396.987999 -289.078461) (xy 396.93978 -289.068617)
			(xy 396.893764 -289.051165) (xy 396.851143 -289.026558) (xy 396.813022 -288.995433) (xy 396.780387 -288.958596)
			(xy 396.754084 -288.917) (xy 396.734793 -288.871724) (xy 396.723016 -288.82394) (xy 396.719056 -288.774886)
			(xy 396.380208 -288.774886) (xy 396.379713 -288.799493) (xy 396.371818 -288.84807) (xy 396.356234 -288.894751)
			(xy 396.333363 -288.938328) (xy 396.303798 -288.977672) (xy 396.268305 -289.011764) (xy 396.227802 -289.03972)
			(xy 396.18334 -289.060818) (xy 396.136069 -289.07451) (xy 396.087214 -289.080442) (xy 396.038039 -289.078461)
			(xy 395.98982 -289.068617) (xy 395.943804 -289.051165) (xy 395.901183 -289.026558) (xy 395.863062 -288.995433)
			(xy 395.830427 -288.958596) (xy 395.804124 -288.917) (xy 395.784833 -288.871724) (xy 395.773056 -288.82394)
			(xy 395.769096 -288.774886) (xy 395.430248 -288.774886) (xy 395.429753 -288.799493) (xy 395.421858 -288.84807)
			(xy 395.406274 -288.894751) (xy 395.383403 -288.938328) (xy 395.353838 -288.977672) (xy 395.318345 -289.011764)
			(xy 395.277842 -289.03972) (xy 395.23338 -289.060818) (xy 395.186109 -289.07451) (xy 395.137254 -289.080442)
			(xy 395.088079 -289.078461) (xy 395.03986 -289.068617) (xy 394.993844 -289.051165) (xy 394.951223 -289.026558)
			(xy 394.913102 -288.995433) (xy 394.880467 -288.958596) (xy 394.854164 -288.917) (xy 394.834873 -288.871724)
			(xy 394.823096 -288.82394) (xy 394.819136 -288.774886) (xy 394.480288 -288.774886) (xy 394.479793 -288.799493)
			(xy 394.471898 -288.84807) (xy 394.456314 -288.894751) (xy 394.433443 -288.938328) (xy 394.403878 -288.977672)
			(xy 394.368385 -289.011764) (xy 394.327882 -289.03972) (xy 394.28342 -289.060818) (xy 394.236149 -289.07451)
			(xy 394.187294 -289.080442) (xy 394.138119 -289.078461) (xy 394.0899 -289.068617) (xy 394.043884 -289.051165)
			(xy 394.001263 -289.026558) (xy 393.963142 -288.995433) (xy 393.930507 -288.958596) (xy 393.904204 -288.917)
			(xy 393.884913 -288.871724) (xy 393.873136 -288.82394) (xy 393.869176 -288.774886) (xy 393.530328 -288.774886)
			(xy 393.529833 -288.799493) (xy 393.521938 -288.84807) (xy 393.506354 -288.894751) (xy 393.483483 -288.938328)
			(xy 393.453918 -288.977672) (xy 393.418425 -289.011764) (xy 393.377922 -289.03972) (xy 393.33346 -289.060818)
			(xy 393.286189 -289.07451) (xy 393.237334 -289.080442) (xy 393.188159 -289.078461) (xy 393.13994 -289.068617)
			(xy 393.093924 -289.051165) (xy 393.051303 -289.026558) (xy 393.013182 -288.995433) (xy 392.980547 -288.958596)
			(xy 392.954244 -288.917) (xy 392.934953 -288.871724) (xy 392.923176 -288.82394) (xy 392.919216 -288.774886)
			(xy 392.580114 -288.774886) (xy 392.579619 -288.799493) (xy 392.571724 -288.84807) (xy 392.55614 -288.894751)
			(xy 392.533269 -288.938328) (xy 392.503704 -288.977672) (xy 392.468211 -289.011764) (xy 392.427708 -289.03972)
			(xy 392.383246 -289.060818) (xy 392.335975 -289.07451) (xy 392.28712 -289.080442) (xy 392.237945 -289.078461)
			(xy 392.189726 -289.068617) (xy 392.14371 -289.051165) (xy 392.101089 -289.026558) (xy 392.062968 -288.995433)
			(xy 392.030333 -288.958596) (xy 392.00403 -288.917) (xy 391.984739 -288.871724) (xy 391.972962 -288.82394)
			(xy 391.969002 -288.774886) (xy 391.630154 -288.774886) (xy 391.629659 -288.799493) (xy 391.621764 -288.84807)
			(xy 391.60618 -288.894751) (xy 391.583309 -288.938328) (xy 391.553744 -288.977672) (xy 391.518251 -289.011764)
			(xy 391.477748 -289.03972) (xy 391.433286 -289.060818) (xy 391.386015 -289.07451) (xy 391.33716 -289.080442)
			(xy 391.287985 -289.078461) (xy 391.239766 -289.068617) (xy 391.19375 -289.051165) (xy 391.151129 -289.026558)
			(xy 391.113008 -288.995433) (xy 391.080373 -288.958596) (xy 391.05407 -288.917) (xy 391.034779 -288.871724)
			(xy 391.023002 -288.82394) (xy 391.019042 -288.774886) (xy 386.880354 -288.774886) (xy 386.879859 -288.799493)
			(xy 386.871964 -288.84807) (xy 386.85638 -288.894751) (xy 386.833509 -288.938328) (xy 386.803944 -288.977672)
			(xy 386.768451 -289.011764) (xy 386.727948 -289.03972) (xy 386.683486 -289.060818) (xy 386.636215 -289.07451)
			(xy 386.58736 -289.080442) (xy 386.538185 -289.078461) (xy 386.489966 -289.068617) (xy 386.44395 -289.051165)
			(xy 386.401329 -289.026558) (xy 386.363208 -288.995433) (xy 386.330573 -288.958596) (xy 386.30427 -288.917)
			(xy 386.284979 -288.871724) (xy 386.273202 -288.82394) (xy 386.269242 -288.774886) (xy 385.93014 -288.774886)
			(xy 385.929645 -288.799493) (xy 385.92175 -288.84807) (xy 385.906166 -288.894751) (xy 385.883295 -288.938328)
			(xy 385.85373 -288.977672) (xy 385.818237 -289.011764) (xy 385.777734 -289.03972) (xy 385.733272 -289.060818)
			(xy 385.686001 -289.07451) (xy 385.637146 -289.080442) (xy 385.587971 -289.078461) (xy 385.539752 -289.068617)
			(xy 385.493736 -289.051165) (xy 385.451115 -289.026558) (xy 385.412994 -288.995433) (xy 385.380359 -288.958596)
			(xy 385.354056 -288.917) (xy 385.334765 -288.871724) (xy 385.322988 -288.82394) (xy 385.319028 -288.774886)
			(xy 384.98018 -288.774886) (xy 384.979685 -288.799493) (xy 384.97179 -288.84807) (xy 384.956206 -288.894751)
			(xy 384.933335 -288.938328) (xy 384.90377 -288.977672) (xy 384.868277 -289.011764) (xy 384.827774 -289.03972)
			(xy 384.783312 -289.060818) (xy 384.736041 -289.07451) (xy 384.687186 -289.080442) (xy 384.638011 -289.078461)
			(xy 384.589792 -289.068617) (xy 384.543776 -289.051165) (xy 384.501155 -289.026558) (xy 384.463034 -288.995433)
			(xy 384.430399 -288.958596) (xy 384.404096 -288.917) (xy 384.384805 -288.871724) (xy 384.373028 -288.82394)
			(xy 384.369068 -288.774886) (xy 368.55019 -288.774886) (xy 368.55019 -289.532314) (xy 374.111518 -289.532314)
			(xy 374.115589 -289.476692) (xy 374.127715 -289.422255) (xy 374.147638 -289.370164) (xy 374.174934 -289.321529)
			(xy 374.20902 -289.277386) (xy 374.249169 -289.238677) (xy 374.294527 -289.206226) (xy 374.344127 -289.180725)
			(xy 374.396911 -289.162718) (xy 374.451754 -289.152588) (xy 374.507488 -289.150551) (xy 374.562925 -289.156651)
			(xy 374.616882 -289.170757) (xy 374.668211 -289.192569) (xy 374.715817 -289.221623) (xy 374.758685 -289.257298)
			(xy 374.795902 -289.298835) (xy 374.826675 -289.345348) (xy 374.850347 -289.395845) (xy 374.866415 -289.449252)
			(xy 374.874535 -289.504428) (xy 374.875044 -289.532314) (xy 375.587004 -289.532314) (xy 375.591075 -289.476692)
			(xy 375.603201 -289.422255) (xy 375.623124 -289.370164) (xy 375.65042 -289.321529) (xy 375.684506 -289.277386)
			(xy 375.724655 -289.238677) (xy 375.770013 -289.206226) (xy 375.819613 -289.180725) (xy 375.872397 -289.162718)
			(xy 375.92724 -289.152588) (xy 375.982974 -289.150551) (xy 376.038411 -289.156651) (xy 376.092368 -289.170757)
			(xy 376.143697 -289.192569) (xy 376.191303 -289.221623) (xy 376.234171 -289.257298) (xy 376.271388 -289.298835)
			(xy 376.302161 -289.345348) (xy 376.325833 -289.395845) (xy 376.341901 -289.449252) (xy 376.350021 -289.504428)
			(xy 376.35053 -289.532314) (xy 376.476004 -289.532314) (xy 376.480075 -289.476692) (xy 376.492201 -289.422255)
			(xy 376.512124 -289.370164) (xy 376.53942 -289.321529) (xy 376.573506 -289.277386) (xy 376.613655 -289.238677)
			(xy 376.659013 -289.206226) (xy 376.708613 -289.180725) (xy 376.761397 -289.162718) (xy 376.81624 -289.152588)
			(xy 376.871974 -289.150551) (xy 376.927411 -289.156651) (xy 376.981368 -289.170757) (xy 377.032697 -289.192569)
			(xy 377.080303 -289.221623) (xy 377.123171 -289.257298) (xy 377.160388 -289.298835) (xy 377.191161 -289.345348)
			(xy 377.214833 -289.395845) (xy 377.230901 -289.449252) (xy 377.239021 -289.504428) (xy 377.23953 -289.532314)
			(xy 377.239021 -289.5602) (xy 377.230901 -289.615376) (xy 377.214833 -289.668783) (xy 377.191161 -289.71928)
			(xy 377.160388 -289.765793) (xy 377.123171 -289.80733) (xy 377.080303 -289.843005) (xy 377.032697 -289.872059)
			(xy 376.981368 -289.893871) (xy 376.927411 -289.907977) (xy 376.871974 -289.914077) (xy 376.81624 -289.91204)
			(xy 376.761397 -289.90191) (xy 376.708613 -289.883903) (xy 376.659013 -289.858402) (xy 376.613655 -289.825951)
			(xy 376.573506 -289.787242) (xy 376.53942 -289.743099) (xy 376.512124 -289.694464) (xy 376.492201 -289.642373)
			(xy 376.480075 -289.587936) (xy 376.476004 -289.532314) (xy 376.35053 -289.532314) (xy 376.350021 -289.5602)
			(xy 376.341901 -289.615376) (xy 376.325833 -289.668783) (xy 376.302161 -289.71928) (xy 376.271388 -289.765793)
			(xy 376.234171 -289.80733) (xy 376.191303 -289.843005) (xy 376.143697 -289.872059) (xy 376.092368 -289.893871)
			(xy 376.038411 -289.907977) (xy 375.982974 -289.914077) (xy 375.92724 -289.91204) (xy 375.872397 -289.90191)
			(xy 375.819613 -289.883903) (xy 375.770013 -289.858402) (xy 375.724655 -289.825951) (xy 375.684506 -289.787242)
			(xy 375.65042 -289.743099) (xy 375.623124 -289.694464) (xy 375.603201 -289.642373) (xy 375.591075 -289.587936)
			(xy 375.587004 -289.532314) (xy 374.875044 -289.532314) (xy 374.874535 -289.5602) (xy 374.866415 -289.615376)
			(xy 374.850347 -289.668783) (xy 374.826675 -289.71928) (xy 374.795902 -289.765793) (xy 374.758685 -289.80733)
			(xy 374.715817 -289.843005) (xy 374.668211 -289.872059) (xy 374.616882 -289.893871) (xy 374.562925 -289.907977)
			(xy 374.507488 -289.914077) (xy 374.451754 -289.91204) (xy 374.396911 -289.90191) (xy 374.344127 -289.883903)
			(xy 374.294527 -289.858402) (xy 374.249169 -289.825951) (xy 374.20902 -289.787242) (xy 374.174934 -289.743099)
			(xy 374.147638 -289.694464) (xy 374.127715 -289.642373) (xy 374.115589 -289.587936) (xy 374.111518 -289.532314)
			(xy 368.55019 -289.532314) (xy 368.55019 -290.294314) (xy 379.638052 -290.294314) (xy 379.638619 -290.264933)
			(xy 379.647646 -290.206868) (xy 379.665474 -290.150875) (xy 379.691681 -290.09828) (xy 379.725646 -290.050328)
			(xy 379.766565 -290.008154) (xy 379.78969 -289.990022) (xy 379.799088 -289.982656) (xy 379.809502 -289.962082)
			(xy 379.811026 -289.858196) (xy 379.80112 -289.837114) (xy 379.791976 -289.829748) (xy 379.770116 -289.811556)
			(xy 379.731578 -289.769734) (xy 379.699673 -289.722655) (xy 379.675108 -289.671363) (xy 379.658427 -289.616993)
			(xy 379.65 -289.56075) (xy 379.649482 -289.532314) (xy 379.649968 -289.505063) (xy 379.657724 -289.451115)
			(xy 379.673079 -289.39882) (xy 379.695721 -289.349243) (xy 379.725187 -289.303393) (xy 379.760878 -289.262202)
			(xy 379.802069 -289.226511) (xy 379.847919 -289.197045) (xy 379.897496 -289.174403) (xy 379.949791 -289.159048)
			(xy 380.003739 -289.151292) (xy 380.058241 -289.151292) (xy 380.112189 -289.159048) (xy 380.164484 -289.174403)
			(xy 380.214061 -289.197045) (xy 380.259911 -289.226511) (xy 380.301102 -289.262202) (xy 380.336793 -289.303393)
			(xy 380.366259 -289.349243) (xy 380.388901 -289.39882) (xy 380.404256 -289.451115) (xy 380.412012 -289.505063)
			(xy 380.412498 -289.532314) (xy 380.411971 -289.561697) (xy 380.402938 -289.619764) (xy 380.385103 -289.675759)
			(xy 380.360637 -289.724846) (xy 384.369068 -289.724846) (xy 384.373028 -289.675792) (xy 384.384805 -289.628008)
			(xy 384.404096 -289.582732) (xy 384.430399 -289.541136) (xy 384.463034 -289.504299) (xy 384.501155 -289.473174)
			(xy 384.543776 -289.448567) (xy 384.589792 -289.431115) (xy 384.638011 -289.421271) (xy 384.687186 -289.41929)
			(xy 384.736041 -289.425222) (xy 384.783312 -289.438914) (xy 384.827774 -289.460012) (xy 384.868277 -289.487968)
			(xy 384.90377 -289.52206) (xy 384.933335 -289.561404) (xy 384.956206 -289.604981) (xy 384.97179 -289.651662)
			(xy 384.979685 -289.700239) (xy 384.98018 -289.724846) (xy 385.319028 -289.724846) (xy 385.322988 -289.675792)
			(xy 385.334765 -289.628008) (xy 385.354056 -289.582732) (xy 385.380359 -289.541136) (xy 385.412994 -289.504299)
			(xy 385.451115 -289.473174) (xy 385.493736 -289.448567) (xy 385.539752 -289.431115) (xy 385.587971 -289.421271)
			(xy 385.637146 -289.41929) (xy 385.686001 -289.425222) (xy 385.733272 -289.438914) (xy 385.777734 -289.460012)
			(xy 385.818237 -289.487968) (xy 385.85373 -289.52206) (xy 385.883295 -289.561404) (xy 385.906166 -289.604981)
			(xy 385.92175 -289.651662) (xy 385.929645 -289.700239) (xy 385.93014 -289.724846) (xy 386.269242 -289.724846)
			(xy 386.273202 -289.675792) (xy 386.284979 -289.628008) (xy 386.30427 -289.582732) (xy 386.330573 -289.541136)
			(xy 386.363208 -289.504299) (xy 386.401329 -289.473174) (xy 386.44395 -289.448567) (xy 386.489966 -289.431115)
			(xy 386.538185 -289.421271) (xy 386.58736 -289.41929) (xy 386.636215 -289.425222) (xy 386.683486 -289.438914)
			(xy 386.727948 -289.460012) (xy 386.768451 -289.487968) (xy 386.803944 -289.52206) (xy 386.833509 -289.561404)
			(xy 386.85638 -289.604981) (xy 386.871964 -289.651662) (xy 386.879859 -289.700239) (xy 386.880354 -289.724846)
			(xy 387.219202 -289.724846) (xy 387.223162 -289.675792) (xy 387.234939 -289.628008) (xy 387.25423 -289.582732)
			(xy 387.280533 -289.541136) (xy 387.313168 -289.504299) (xy 387.351289 -289.473174) (xy 387.39391 -289.448567)
			(xy 387.439926 -289.431115) (xy 387.488145 -289.421271) (xy 387.53732 -289.41929) (xy 387.586175 -289.425222)
			(xy 387.633446 -289.438914) (xy 387.677908 -289.460012) (xy 387.718411 -289.487968) (xy 387.753904 -289.52206)
			(xy 387.783469 -289.561404) (xy 387.80634 -289.604981) (xy 387.821924 -289.651662) (xy 387.829819 -289.700239)
			(xy 387.830314 -289.724846) (xy 388.169162 -289.724846) (xy 388.173122 -289.675792) (xy 388.184899 -289.628008)
			(xy 388.20419 -289.582732) (xy 388.230493 -289.541136) (xy 388.263128 -289.504299) (xy 388.301249 -289.473174)
			(xy 388.34387 -289.448567) (xy 388.389886 -289.431115) (xy 388.438105 -289.421271) (xy 388.48728 -289.41929)
			(xy 388.536135 -289.425222) (xy 388.583406 -289.438914) (xy 388.627868 -289.460012) (xy 388.668371 -289.487968)
			(xy 388.703864 -289.52206) (xy 388.733429 -289.561404) (xy 388.7563 -289.604981) (xy 388.771884 -289.651662)
			(xy 388.779779 -289.700239) (xy 388.780274 -289.724846) (xy 389.119122 -289.724846) (xy 389.123082 -289.675792)
			(xy 389.134859 -289.628008) (xy 389.15415 -289.582732) (xy 389.180453 -289.541136) (xy 389.213088 -289.504299)
			(xy 389.251209 -289.473174) (xy 389.29383 -289.448567) (xy 389.339846 -289.431115) (xy 389.388065 -289.421271)
			(xy 389.43724 -289.41929) (xy 389.486095 -289.425222) (xy 389.533366 -289.438914) (xy 389.577828 -289.460012)
			(xy 389.618331 -289.487968) (xy 389.653824 -289.52206) (xy 389.683389 -289.561404) (xy 389.70626 -289.604981)
			(xy 389.721844 -289.651662) (xy 389.729739 -289.700239) (xy 389.730234 -289.724846) (xy 390.069082 -289.724846)
			(xy 390.073042 -289.675792) (xy 390.084819 -289.628008) (xy 390.10411 -289.582732) (xy 390.130413 -289.541136)
			(xy 390.163048 -289.504299) (xy 390.201169 -289.473174) (xy 390.24379 -289.448567) (xy 390.289806 -289.431115)
			(xy 390.338025 -289.421271) (xy 390.3872 -289.41929) (xy 390.436055 -289.425222) (xy 390.483326 -289.438914)
			(xy 390.527788 -289.460012) (xy 390.568291 -289.487968) (xy 390.603784 -289.52206) (xy 390.633349 -289.561404)
			(xy 390.65622 -289.604981) (xy 390.671804 -289.651662) (xy 390.679699 -289.700239) (xy 390.680194 -289.724846)
			(xy 391.019042 -289.724846) (xy 391.023002 -289.675792) (xy 391.034779 -289.628008) (xy 391.05407 -289.582732)
			(xy 391.080373 -289.541136) (xy 391.113008 -289.504299) (xy 391.151129 -289.473174) (xy 391.19375 -289.448567)
			(xy 391.239766 -289.431115) (xy 391.287985 -289.421271) (xy 391.33716 -289.41929) (xy 391.386015 -289.425222)
			(xy 391.433286 -289.438914) (xy 391.477748 -289.460012) (xy 391.518251 -289.487968) (xy 391.553744 -289.52206)
			(xy 391.583309 -289.561404) (xy 391.60618 -289.604981) (xy 391.621764 -289.651662) (xy 391.629659 -289.700239)
			(xy 391.630154 -289.724846) (xy 391.969002 -289.724846) (xy 391.972962 -289.675792) (xy 391.984739 -289.628008)
			(xy 392.00403 -289.582732) (xy 392.030333 -289.541136) (xy 392.062968 -289.504299) (xy 392.101089 -289.473174)
			(xy 392.14371 -289.448567) (xy 392.189726 -289.431115) (xy 392.237945 -289.421271) (xy 392.28712 -289.41929)
			(xy 392.335975 -289.425222) (xy 392.383246 -289.438914) (xy 392.427708 -289.460012) (xy 392.468211 -289.487968)
			(xy 392.503704 -289.52206) (xy 392.533269 -289.561404) (xy 392.55614 -289.604981) (xy 392.571724 -289.651662)
			(xy 392.579619 -289.700239) (xy 392.580114 -289.724846) (xy 392.919216 -289.724846) (xy 392.923176 -289.675792)
			(xy 392.934953 -289.628008) (xy 392.954244 -289.582732) (xy 392.980547 -289.541136) (xy 393.013182 -289.504299)
			(xy 393.051303 -289.473174) (xy 393.093924 -289.448567) (xy 393.13994 -289.431115) (xy 393.188159 -289.421271)
			(xy 393.237334 -289.41929) (xy 393.286189 -289.425222) (xy 393.33346 -289.438914) (xy 393.377922 -289.460012)
			(xy 393.418425 -289.487968) (xy 393.453918 -289.52206) (xy 393.483483 -289.561404) (xy 393.506354 -289.604981)
			(xy 393.521938 -289.651662) (xy 393.529833 -289.700239) (xy 393.530328 -289.724846) (xy 393.869176 -289.724846)
			(xy 393.873136 -289.675792) (xy 393.884913 -289.628008) (xy 393.904204 -289.582732) (xy 393.930507 -289.541136)
			(xy 393.963142 -289.504299) (xy 394.001263 -289.473174) (xy 394.043884 -289.448567) (xy 394.0899 -289.431115)
			(xy 394.138119 -289.421271) (xy 394.187294 -289.41929) (xy 394.236149 -289.425222) (xy 394.28342 -289.438914)
			(xy 394.327882 -289.460012) (xy 394.368385 -289.487968) (xy 394.403878 -289.52206) (xy 394.433443 -289.561404)
			(xy 394.456314 -289.604981) (xy 394.471898 -289.651662) (xy 394.479793 -289.700239) (xy 394.480288 -289.724846)
			(xy 394.819136 -289.724846) (xy 394.823096 -289.675792) (xy 394.834873 -289.628008) (xy 394.854164 -289.582732)
			(xy 394.880467 -289.541136) (xy 394.913102 -289.504299) (xy 394.951223 -289.473174) (xy 394.993844 -289.448567)
			(xy 395.03986 -289.431115) (xy 395.088079 -289.421271) (xy 395.137254 -289.41929) (xy 395.186109 -289.425222)
			(xy 395.23338 -289.438914) (xy 395.277842 -289.460012) (xy 395.318345 -289.487968) (xy 395.353838 -289.52206)
			(xy 395.383403 -289.561404) (xy 395.406274 -289.604981) (xy 395.421858 -289.651662) (xy 395.429753 -289.700239)
			(xy 395.430248 -289.724846) (xy 395.769096 -289.724846) (xy 395.773056 -289.675792) (xy 395.784833 -289.628008)
			(xy 395.804124 -289.582732) (xy 395.830427 -289.541136) (xy 395.863062 -289.504299) (xy 395.901183 -289.473174)
			(xy 395.943804 -289.448567) (xy 395.98982 -289.431115) (xy 396.038039 -289.421271) (xy 396.087214 -289.41929)
			(xy 396.136069 -289.425222) (xy 396.18334 -289.438914) (xy 396.227802 -289.460012) (xy 396.268305 -289.487968)
			(xy 396.303798 -289.52206) (xy 396.333363 -289.561404) (xy 396.356234 -289.604981) (xy 396.371818 -289.651662)
			(xy 396.379713 -289.700239) (xy 396.380208 -289.724846) (xy 396.719056 -289.724846) (xy 396.723016 -289.675792)
			(xy 396.734793 -289.628008) (xy 396.754084 -289.582732) (xy 396.780387 -289.541136) (xy 396.813022 -289.504299)
			(xy 396.851143 -289.473174) (xy 396.893764 -289.448567) (xy 396.93978 -289.431115) (xy 396.987999 -289.421271)
			(xy 397.037174 -289.41929) (xy 397.086029 -289.425222) (xy 397.1333 -289.438914) (xy 397.177762 -289.460012)
			(xy 397.218265 -289.487968) (xy 397.253758 -289.52206) (xy 397.283323 -289.561404) (xy 397.306194 -289.604981)
			(xy 397.321778 -289.651662) (xy 397.329673 -289.700239) (xy 397.330168 -289.724846) (xy 397.669016 -289.724846)
			(xy 397.672976 -289.675792) (xy 397.684753 -289.628008) (xy 397.704044 -289.582732) (xy 397.730347 -289.541136)
			(xy 397.762982 -289.504299) (xy 397.801103 -289.473174) (xy 397.843724 -289.448567) (xy 397.88974 -289.431115)
			(xy 397.937959 -289.421271) (xy 397.987134 -289.41929) (xy 398.035989 -289.425222) (xy 398.08326 -289.438914)
			(xy 398.127722 -289.460012) (xy 398.168225 -289.487968) (xy 398.203718 -289.52206) (xy 398.233283 -289.561404)
			(xy 398.256154 -289.604981) (xy 398.271738 -289.651662) (xy 398.279633 -289.700239) (xy 398.280128 -289.724846)
			(xy 398.61923 -289.724846) (xy 398.62319 -289.675792) (xy 398.634967 -289.628008) (xy 398.654258 -289.582732)
			(xy 398.680561 -289.541136) (xy 398.713196 -289.504299) (xy 398.751317 -289.473174) (xy 398.793938 -289.448567)
			(xy 398.839954 -289.431115) (xy 398.888173 -289.421271) (xy 398.937348 -289.41929) (xy 398.986203 -289.425222)
			(xy 399.033474 -289.438914) (xy 399.077936 -289.460012) (xy 399.118439 -289.487968) (xy 399.153932 -289.52206)
			(xy 399.183497 -289.561404) (xy 399.206368 -289.604981) (xy 399.221952 -289.651662) (xy 399.229847 -289.700239)
			(xy 399.230342 -289.724846) (xy 399.56919 -289.724846) (xy 399.57315 -289.675792) (xy 399.584927 -289.628008)
			(xy 399.604218 -289.582732) (xy 399.630521 -289.541136) (xy 399.663156 -289.504299) (xy 399.701277 -289.473174)
			(xy 399.743898 -289.448567) (xy 399.789914 -289.431115) (xy 399.838133 -289.421271) (xy 399.887308 -289.41929)
			(xy 399.936163 -289.425222) (xy 399.983434 -289.438914) (xy 400.027896 -289.460012) (xy 400.068399 -289.487968)
			(xy 400.103892 -289.52206) (xy 400.133457 -289.561404) (xy 400.156328 -289.604981) (xy 400.171912 -289.651662)
			(xy 400.179807 -289.700239) (xy 400.180302 -289.724846) (xy 400.51915 -289.724846) (xy 400.52311 -289.675792)
			(xy 400.534887 -289.628008) (xy 400.554178 -289.582732) (xy 400.580481 -289.541136) (xy 400.613116 -289.504299)
			(xy 400.651237 -289.473174) (xy 400.693858 -289.448567) (xy 400.739874 -289.431115) (xy 400.788093 -289.421271)
			(xy 400.837268 -289.41929) (xy 400.886123 -289.425222) (xy 400.933394 -289.438914) (xy 400.977856 -289.460012)
			(xy 401.018359 -289.487968) (xy 401.053852 -289.52206) (xy 401.083417 -289.561404) (xy 401.106288 -289.604981)
			(xy 401.121872 -289.651662) (xy 401.129767 -289.700239) (xy 401.130262 -289.724846) (xy 401.46911 -289.724846)
			(xy 401.47307 -289.675792) (xy 401.484847 -289.628008) (xy 401.504138 -289.582732) (xy 401.530441 -289.541136)
			(xy 401.563076 -289.504299) (xy 401.601197 -289.473174) (xy 401.643818 -289.448567) (xy 401.689834 -289.431115)
			(xy 401.738053 -289.421271) (xy 401.787228 -289.41929) (xy 401.836083 -289.425222) (xy 401.883354 -289.438914)
			(xy 401.927816 -289.460012) (xy 401.968319 -289.487968) (xy 402.003812 -289.52206) (xy 402.033377 -289.561404)
			(xy 402.056248 -289.604981) (xy 402.071832 -289.651662) (xy 402.079727 -289.700239) (xy 402.080222 -289.724846)
			(xy 402.41907 -289.724846) (xy 402.42303 -289.675792) (xy 402.434807 -289.628008) (xy 402.454098 -289.582732)
			(xy 402.480401 -289.541136) (xy 402.513036 -289.504299) (xy 402.551157 -289.473174) (xy 402.593778 -289.448567)
			(xy 402.639794 -289.431115) (xy 402.688013 -289.421271) (xy 402.737188 -289.41929) (xy 402.786043 -289.425222)
			(xy 402.833314 -289.438914) (xy 402.877776 -289.460012) (xy 402.918279 -289.487968) (xy 402.953772 -289.52206)
			(xy 402.983337 -289.561404) (xy 403.006208 -289.604981) (xy 403.021792 -289.651662) (xy 403.029687 -289.700239)
			(xy 403.030182 -289.724846) (xy 403.36903 -289.724846) (xy 403.37299 -289.675792) (xy 403.384767 -289.628008)
			(xy 403.404058 -289.582732) (xy 403.430361 -289.541136) (xy 403.462996 -289.504299) (xy 403.501117 -289.473174)
			(xy 403.543738 -289.448567) (xy 403.589754 -289.431115) (xy 403.637973 -289.421271) (xy 403.687148 -289.41929)
			(xy 403.736003 -289.425222) (xy 403.783274 -289.438914) (xy 403.827736 -289.460012) (xy 403.868239 -289.487968)
			(xy 403.903732 -289.52206) (xy 403.933297 -289.561404) (xy 403.956168 -289.604981) (xy 403.971752 -289.651662)
			(xy 403.979647 -289.700239) (xy 403.980142 -289.724846) (xy 404.31899 -289.724846) (xy 404.32295 -289.675792)
			(xy 404.334727 -289.628008) (xy 404.354018 -289.582732) (xy 404.380321 -289.541136) (xy 404.412956 -289.504299)
			(xy 404.451077 -289.473174) (xy 404.493698 -289.448567) (xy 404.539714 -289.431115) (xy 404.587933 -289.421271)
			(xy 404.637108 -289.41929) (xy 404.685963 -289.425222) (xy 404.733234 -289.438914) (xy 404.777696 -289.460012)
			(xy 404.818199 -289.487968) (xy 404.853692 -289.52206) (xy 404.883257 -289.561404) (xy 404.906128 -289.604981)
			(xy 404.921712 -289.651662) (xy 404.929607 -289.700239) (xy 404.930102 -289.724846) (xy 405.269204 -289.724846)
			(xy 405.273164 -289.675792) (xy 405.284941 -289.628008) (xy 405.304232 -289.582732) (xy 405.330535 -289.541136)
			(xy 405.36317 -289.504299) (xy 405.401291 -289.473174) (xy 405.443912 -289.448567) (xy 405.489928 -289.431115)
			(xy 405.538147 -289.421271) (xy 405.587322 -289.41929) (xy 405.636177 -289.425222) (xy 405.683448 -289.438914)
			(xy 405.72791 -289.460012) (xy 405.768413 -289.487968) (xy 405.803906 -289.52206) (xy 405.833471 -289.561404)
			(xy 405.856342 -289.604981) (xy 405.871926 -289.651662) (xy 405.879821 -289.700239) (xy 405.880316 -289.724846)
			(xy 406.219164 -289.724846) (xy 406.223124 -289.675792) (xy 406.234901 -289.628008) (xy 406.254192 -289.582732)
			(xy 406.280495 -289.541136) (xy 406.31313 -289.504299) (xy 406.351251 -289.473174) (xy 406.393872 -289.448567)
			(xy 406.439888 -289.431115) (xy 406.488107 -289.421271) (xy 406.537282 -289.41929) (xy 406.586137 -289.425222)
			(xy 406.633408 -289.438914) (xy 406.67787 -289.460012) (xy 406.718373 -289.487968) (xy 406.753866 -289.52206)
			(xy 406.783431 -289.561404) (xy 406.806302 -289.604981) (xy 406.821886 -289.651662) (xy 406.829781 -289.700239)
			(xy 406.830276 -289.724846) (xy 408.119084 -289.724846) (xy 408.123044 -289.675792) (xy 408.134821 -289.628008)
			(xy 408.154112 -289.582732) (xy 408.180415 -289.541136) (xy 408.21305 -289.504299) (xy 408.251171 -289.473174)
			(xy 408.293792 -289.448567) (xy 408.339808 -289.431115) (xy 408.388027 -289.421271) (xy 408.437202 -289.41929)
			(xy 408.486057 -289.425222) (xy 408.533328 -289.438914) (xy 408.57779 -289.460012) (xy 408.618293 -289.487968)
			(xy 408.653786 -289.52206) (xy 408.683351 -289.561404) (xy 408.706222 -289.604981) (xy 408.721806 -289.651662)
			(xy 408.729701 -289.700239) (xy 408.730196 -289.724846) (xy 409.069044 -289.724846) (xy 409.073004 -289.675792)
			(xy 409.084781 -289.628008) (xy 409.104072 -289.582732) (xy 409.130375 -289.541136) (xy 409.16301 -289.504299)
			(xy 409.201131 -289.473174) (xy 409.243752 -289.448567) (xy 409.289768 -289.431115) (xy 409.337987 -289.421271)
			(xy 409.387162 -289.41929) (xy 409.436017 -289.425222) (xy 409.483288 -289.438914) (xy 409.52775 -289.460012)
			(xy 409.568253 -289.487968) (xy 409.603746 -289.52206) (xy 409.633311 -289.561404) (xy 409.656182 -289.604981)
			(xy 409.671766 -289.651662) (xy 409.679661 -289.700239) (xy 409.680156 -289.724846) (xy 410.019004 -289.724846)
			(xy 410.022964 -289.675792) (xy 410.034741 -289.628008) (xy 410.054032 -289.582732) (xy 410.080335 -289.541136)
			(xy 410.11297 -289.504299) (xy 410.151091 -289.473174) (xy 410.193712 -289.448567) (xy 410.239728 -289.431115)
			(xy 410.287947 -289.421271) (xy 410.337122 -289.41929) (xy 410.385977 -289.425222) (xy 410.433248 -289.438914)
			(xy 410.47771 -289.460012) (xy 410.518213 -289.487968) (xy 410.553706 -289.52206) (xy 410.583271 -289.561404)
			(xy 410.606142 -289.604981) (xy 410.621726 -289.651662) (xy 410.629621 -289.700239) (xy 410.630116 -289.724846)
			(xy 410.969218 -289.724846) (xy 410.973178 -289.675792) (xy 410.984955 -289.628008) (xy 411.004246 -289.582732)
			(xy 411.030549 -289.541136) (xy 411.063184 -289.504299) (xy 411.101305 -289.473174) (xy 411.143926 -289.448567)
			(xy 411.189942 -289.431115) (xy 411.238161 -289.421271) (xy 411.287336 -289.41929) (xy 411.336191 -289.425222)
			(xy 411.383462 -289.438914) (xy 411.427924 -289.460012) (xy 411.468427 -289.487968) (xy 411.50392 -289.52206)
			(xy 411.533485 -289.561404) (xy 411.556356 -289.604981) (xy 411.57194 -289.651662) (xy 411.579835 -289.700239)
			(xy 411.58033 -289.724846) (xy 411.919178 -289.724846) (xy 411.923138 -289.675792) (xy 411.934915 -289.628008)
			(xy 411.954206 -289.582732) (xy 411.980509 -289.541136) (xy 412.013144 -289.504299) (xy 412.051265 -289.473174)
			(xy 412.093886 -289.448567) (xy 412.139902 -289.431115) (xy 412.188121 -289.421271) (xy 412.237296 -289.41929)
			(xy 412.286151 -289.425222) (xy 412.333422 -289.438914) (xy 412.377884 -289.460012) (xy 412.418387 -289.487968)
			(xy 412.45388 -289.52206) (xy 412.483445 -289.561404) (xy 412.506316 -289.604981) (xy 412.5219 -289.651662)
			(xy 412.529795 -289.700239) (xy 412.53029 -289.724846) (xy 412.869138 -289.724846) (xy 412.873098 -289.675792)
			(xy 412.884875 -289.628008) (xy 412.904166 -289.582732) (xy 412.930469 -289.541136) (xy 412.963104 -289.504299)
			(xy 413.001225 -289.473174) (xy 413.043846 -289.448567) (xy 413.089862 -289.431115) (xy 413.138081 -289.421271)
			(xy 413.187256 -289.41929) (xy 413.236111 -289.425222) (xy 413.283382 -289.438914) (xy 413.327844 -289.460012)
			(xy 413.368347 -289.487968) (xy 413.40384 -289.52206) (xy 413.433405 -289.561404) (xy 413.456276 -289.604981)
			(xy 413.47186 -289.651662) (xy 413.479755 -289.700239) (xy 413.48025 -289.724846) (xy 413.819098 -289.724846)
			(xy 413.823058 -289.675792) (xy 413.834835 -289.628008) (xy 413.854126 -289.582732) (xy 413.880429 -289.541136)
			(xy 413.913064 -289.504299) (xy 413.951185 -289.473174) (xy 413.993806 -289.448567) (xy 414.039822 -289.431115)
			(xy 414.088041 -289.421271) (xy 414.137216 -289.41929) (xy 414.186071 -289.425222) (xy 414.233342 -289.438914)
			(xy 414.277804 -289.460012) (xy 414.318307 -289.487968) (xy 414.3538 -289.52206) (xy 414.383365 -289.561404)
			(xy 414.406236 -289.604981) (xy 414.42182 -289.651662) (xy 414.429715 -289.700239) (xy 414.43021 -289.724846)
			(xy 414.769058 -289.724846) (xy 414.773018 -289.675792) (xy 414.784795 -289.628008) (xy 414.804086 -289.582732)
			(xy 414.830389 -289.541136) (xy 414.863024 -289.504299) (xy 414.901145 -289.473174) (xy 414.943766 -289.448567)
			(xy 414.989782 -289.431115) (xy 415.038001 -289.421271) (xy 415.087176 -289.41929) (xy 415.136031 -289.425222)
			(xy 415.183302 -289.438914) (xy 415.227764 -289.460012) (xy 415.268267 -289.487968) (xy 415.30376 -289.52206)
			(xy 415.333325 -289.561404) (xy 415.356196 -289.604981) (xy 415.37178 -289.651662) (xy 415.379675 -289.700239)
			(xy 415.38017 -289.724846) (xy 415.719018 -289.724846) (xy 415.722978 -289.675792) (xy 415.734755 -289.628008)
			(xy 415.754046 -289.582732) (xy 415.780349 -289.541136) (xy 415.812984 -289.504299) (xy 415.851105 -289.473174)
			(xy 415.893726 -289.448567) (xy 415.939742 -289.431115) (xy 415.987961 -289.421271) (xy 416.037136 -289.41929)
			(xy 416.085991 -289.425222) (xy 416.133262 -289.438914) (xy 416.177724 -289.460012) (xy 416.218227 -289.487968)
			(xy 416.25372 -289.52206) (xy 416.283285 -289.561404) (xy 416.306156 -289.604981) (xy 416.32174 -289.651662)
			(xy 416.329635 -289.700239) (xy 416.33013 -289.724846) (xy 416.329635 -289.749453) (xy 416.32174 -289.79803)
			(xy 416.306156 -289.844711) (xy 416.283285 -289.888288) (xy 416.25372 -289.927632) (xy 416.218227 -289.961724)
			(xy 416.177724 -289.98968) (xy 416.133262 -290.010778) (xy 416.085991 -290.02447) (xy 416.037136 -290.030402)
			(xy 415.987961 -290.028421) (xy 415.939742 -290.018577) (xy 415.893726 -290.001125) (xy 415.851105 -289.976518)
			(xy 415.812984 -289.945393) (xy 415.780349 -289.908556) (xy 415.754046 -289.86696) (xy 415.734755 -289.821684)
			(xy 415.722978 -289.7739) (xy 415.719018 -289.724846) (xy 415.38017 -289.724846) (xy 415.379675 -289.749453)
			(xy 415.37178 -289.79803) (xy 415.356196 -289.844711) (xy 415.333325 -289.888288) (xy 415.30376 -289.927632)
			(xy 415.268267 -289.961724) (xy 415.227764 -289.98968) (xy 415.183302 -290.010778) (xy 415.136031 -290.02447)
			(xy 415.087176 -290.030402) (xy 415.038001 -290.028421) (xy 414.989782 -290.018577) (xy 414.943766 -290.001125)
			(xy 414.901145 -289.976518) (xy 414.863024 -289.945393) (xy 414.830389 -289.908556) (xy 414.804086 -289.86696)
			(xy 414.784795 -289.821684) (xy 414.773018 -289.7739) (xy 414.769058 -289.724846) (xy 414.43021 -289.724846)
			(xy 414.429715 -289.749453) (xy 414.42182 -289.79803) (xy 414.406236 -289.844711) (xy 414.383365 -289.888288)
			(xy 414.3538 -289.927632) (xy 414.318307 -289.961724) (xy 414.277804 -289.98968) (xy 414.233342 -290.010778)
			(xy 414.186071 -290.02447) (xy 414.137216 -290.030402) (xy 414.088041 -290.028421) (xy 414.039822 -290.018577)
			(xy 413.993806 -290.001125) (xy 413.951185 -289.976518) (xy 413.913064 -289.945393) (xy 413.880429 -289.908556)
			(xy 413.854126 -289.86696) (xy 413.834835 -289.821684) (xy 413.823058 -289.7739) (xy 413.819098 -289.724846)
			(xy 413.48025 -289.724846) (xy 413.479755 -289.749453) (xy 413.47186 -289.79803) (xy 413.456276 -289.844711)
			(xy 413.433405 -289.888288) (xy 413.40384 -289.927632) (xy 413.368347 -289.961724) (xy 413.327844 -289.98968)
			(xy 413.283382 -290.010778) (xy 413.236111 -290.02447) (xy 413.187256 -290.030402) (xy 413.138081 -290.028421)
			(xy 413.089862 -290.018577) (xy 413.043846 -290.001125) (xy 413.001225 -289.976518) (xy 412.963104 -289.945393)
			(xy 412.930469 -289.908556) (xy 412.904166 -289.86696) (xy 412.884875 -289.821684) (xy 412.873098 -289.7739)
			(xy 412.869138 -289.724846) (xy 412.53029 -289.724846) (xy 412.529795 -289.749453) (xy 412.5219 -289.79803)
			(xy 412.506316 -289.844711) (xy 412.483445 -289.888288) (xy 412.45388 -289.927632) (xy 412.418387 -289.961724)
			(xy 412.377884 -289.98968) (xy 412.333422 -290.010778) (xy 412.286151 -290.02447) (xy 412.237296 -290.030402)
			(xy 412.188121 -290.028421) (xy 412.139902 -290.018577) (xy 412.093886 -290.001125) (xy 412.051265 -289.976518)
			(xy 412.013144 -289.945393) (xy 411.980509 -289.908556) (xy 411.954206 -289.86696) (xy 411.934915 -289.821684)
			(xy 411.923138 -289.7739) (xy 411.919178 -289.724846) (xy 411.58033 -289.724846) (xy 411.579835 -289.749453)
			(xy 411.57194 -289.79803) (xy 411.556356 -289.844711) (xy 411.533485 -289.888288) (xy 411.50392 -289.927632)
			(xy 411.468427 -289.961724) (xy 411.427924 -289.98968) (xy 411.383462 -290.010778) (xy 411.336191 -290.02447)
			(xy 411.287336 -290.030402) (xy 411.238161 -290.028421) (xy 411.189942 -290.018577) (xy 411.143926 -290.001125)
			(xy 411.101305 -289.976518) (xy 411.063184 -289.945393) (xy 411.030549 -289.908556) (xy 411.004246 -289.86696)
			(xy 410.984955 -289.821684) (xy 410.973178 -289.7739) (xy 410.969218 -289.724846) (xy 410.630116 -289.724846)
			(xy 410.629621 -289.749453) (xy 410.621726 -289.79803) (xy 410.606142 -289.844711) (xy 410.583271 -289.888288)
			(xy 410.553706 -289.927632) (xy 410.518213 -289.961724) (xy 410.47771 -289.98968) (xy 410.433248 -290.010778)
			(xy 410.385977 -290.02447) (xy 410.337122 -290.030402) (xy 410.287947 -290.028421) (xy 410.239728 -290.018577)
			(xy 410.193712 -290.001125) (xy 410.151091 -289.976518) (xy 410.11297 -289.945393) (xy 410.080335 -289.908556)
			(xy 410.054032 -289.86696) (xy 410.034741 -289.821684) (xy 410.022964 -289.7739) (xy 410.019004 -289.724846)
			(xy 409.680156 -289.724846) (xy 409.679661 -289.749453) (xy 409.671766 -289.79803) (xy 409.656182 -289.844711)
			(xy 409.633311 -289.888288) (xy 409.603746 -289.927632) (xy 409.568253 -289.961724) (xy 409.52775 -289.98968)
			(xy 409.483288 -290.010778) (xy 409.436017 -290.02447) (xy 409.387162 -290.030402) (xy 409.337987 -290.028421)
			(xy 409.289768 -290.018577) (xy 409.243752 -290.001125) (xy 409.201131 -289.976518) (xy 409.16301 -289.945393)
			(xy 409.130375 -289.908556) (xy 409.104072 -289.86696) (xy 409.084781 -289.821684) (xy 409.073004 -289.7739)
			(xy 409.069044 -289.724846) (xy 408.730196 -289.724846) (xy 408.729701 -289.749453) (xy 408.721806 -289.79803)
			(xy 408.706222 -289.844711) (xy 408.683351 -289.888288) (xy 408.653786 -289.927632) (xy 408.618293 -289.961724)
			(xy 408.57779 -289.98968) (xy 408.533328 -290.010778) (xy 408.486057 -290.02447) (xy 408.437202 -290.030402)
			(xy 408.388027 -290.028421) (xy 408.339808 -290.018577) (xy 408.293792 -290.001125) (xy 408.251171 -289.976518)
			(xy 408.21305 -289.945393) (xy 408.180415 -289.908556) (xy 408.154112 -289.86696) (xy 408.134821 -289.821684)
			(xy 408.123044 -289.7739) (xy 408.119084 -289.724846) (xy 406.830276 -289.724846) (xy 406.829781 -289.749453)
			(xy 406.821886 -289.79803) (xy 406.806302 -289.844711) (xy 406.783431 -289.888288) (xy 406.753866 -289.927632)
			(xy 406.718373 -289.961724) (xy 406.67787 -289.98968) (xy 406.633408 -290.010778) (xy 406.586137 -290.02447)
			(xy 406.537282 -290.030402) (xy 406.488107 -290.028421) (xy 406.439888 -290.018577) (xy 406.393872 -290.001125)
			(xy 406.351251 -289.976518) (xy 406.31313 -289.945393) (xy 406.280495 -289.908556) (xy 406.254192 -289.86696)
			(xy 406.234901 -289.821684) (xy 406.223124 -289.7739) (xy 406.219164 -289.724846) (xy 405.880316 -289.724846)
			(xy 405.879821 -289.749453) (xy 405.871926 -289.79803) (xy 405.856342 -289.844711) (xy 405.833471 -289.888288)
			(xy 405.803906 -289.927632) (xy 405.768413 -289.961724) (xy 405.72791 -289.98968) (xy 405.683448 -290.010778)
			(xy 405.636177 -290.02447) (xy 405.587322 -290.030402) (xy 405.538147 -290.028421) (xy 405.489928 -290.018577)
			(xy 405.443912 -290.001125) (xy 405.401291 -289.976518) (xy 405.36317 -289.945393) (xy 405.330535 -289.908556)
			(xy 405.304232 -289.86696) (xy 405.284941 -289.821684) (xy 405.273164 -289.7739) (xy 405.269204 -289.724846)
			(xy 404.930102 -289.724846) (xy 404.929607 -289.749453) (xy 404.921712 -289.79803) (xy 404.906128 -289.844711)
			(xy 404.883257 -289.888288) (xy 404.853692 -289.927632) (xy 404.818199 -289.961724) (xy 404.777696 -289.98968)
			(xy 404.733234 -290.010778) (xy 404.685963 -290.02447) (xy 404.637108 -290.030402) (xy 404.587933 -290.028421)
			(xy 404.539714 -290.018577) (xy 404.493698 -290.001125) (xy 404.451077 -289.976518) (xy 404.412956 -289.945393)
			(xy 404.380321 -289.908556) (xy 404.354018 -289.86696) (xy 404.334727 -289.821684) (xy 404.32295 -289.7739)
			(xy 404.31899 -289.724846) (xy 403.980142 -289.724846) (xy 403.979647 -289.749453) (xy 403.971752 -289.79803)
			(xy 403.956168 -289.844711) (xy 403.933297 -289.888288) (xy 403.903732 -289.927632) (xy 403.868239 -289.961724)
			(xy 403.827736 -289.98968) (xy 403.783274 -290.010778) (xy 403.736003 -290.02447) (xy 403.687148 -290.030402)
			(xy 403.637973 -290.028421) (xy 403.589754 -290.018577) (xy 403.543738 -290.001125) (xy 403.501117 -289.976518)
			(xy 403.462996 -289.945393) (xy 403.430361 -289.908556) (xy 403.404058 -289.86696) (xy 403.384767 -289.821684)
			(xy 403.37299 -289.7739) (xy 403.36903 -289.724846) (xy 403.030182 -289.724846) (xy 403.029687 -289.749453)
			(xy 403.021792 -289.79803) (xy 403.006208 -289.844711) (xy 402.983337 -289.888288) (xy 402.953772 -289.927632)
			(xy 402.918279 -289.961724) (xy 402.877776 -289.98968) (xy 402.833314 -290.010778) (xy 402.786043 -290.02447)
			(xy 402.737188 -290.030402) (xy 402.688013 -290.028421) (xy 402.639794 -290.018577) (xy 402.593778 -290.001125)
			(xy 402.551157 -289.976518) (xy 402.513036 -289.945393) (xy 402.480401 -289.908556) (xy 402.454098 -289.86696)
			(xy 402.434807 -289.821684) (xy 402.42303 -289.7739) (xy 402.41907 -289.724846) (xy 402.080222 -289.724846)
			(xy 402.079727 -289.749453) (xy 402.071832 -289.79803) (xy 402.056248 -289.844711) (xy 402.033377 -289.888288)
			(xy 402.003812 -289.927632) (xy 401.968319 -289.961724) (xy 401.927816 -289.98968) (xy 401.883354 -290.010778)
			(xy 401.836083 -290.02447) (xy 401.787228 -290.030402) (xy 401.738053 -290.028421) (xy 401.689834 -290.018577)
			(xy 401.643818 -290.001125) (xy 401.601197 -289.976518) (xy 401.563076 -289.945393) (xy 401.530441 -289.908556)
			(xy 401.504138 -289.86696) (xy 401.484847 -289.821684) (xy 401.47307 -289.7739) (xy 401.46911 -289.724846)
			(xy 401.130262 -289.724846) (xy 401.129767 -289.749453) (xy 401.121872 -289.79803) (xy 401.106288 -289.844711)
			(xy 401.083417 -289.888288) (xy 401.053852 -289.927632) (xy 401.018359 -289.961724) (xy 400.977856 -289.98968)
			(xy 400.933394 -290.010778) (xy 400.886123 -290.02447) (xy 400.837268 -290.030402) (xy 400.788093 -290.028421)
			(xy 400.739874 -290.018577) (xy 400.693858 -290.001125) (xy 400.651237 -289.976518) (xy 400.613116 -289.945393)
			(xy 400.580481 -289.908556) (xy 400.554178 -289.86696) (xy 400.534887 -289.821684) (xy 400.52311 -289.7739)
			(xy 400.51915 -289.724846) (xy 400.180302 -289.724846) (xy 400.179807 -289.749453) (xy 400.171912 -289.79803)
			(xy 400.156328 -289.844711) (xy 400.133457 -289.888288) (xy 400.103892 -289.927632) (xy 400.068399 -289.961724)
			(xy 400.027896 -289.98968) (xy 399.983434 -290.010778) (xy 399.936163 -290.02447) (xy 399.887308 -290.030402)
			(xy 399.838133 -290.028421) (xy 399.789914 -290.018577) (xy 399.743898 -290.001125) (xy 399.701277 -289.976518)
			(xy 399.663156 -289.945393) (xy 399.630521 -289.908556) (xy 399.604218 -289.86696) (xy 399.584927 -289.821684)
			(xy 399.57315 -289.7739) (xy 399.56919 -289.724846) (xy 399.230342 -289.724846) (xy 399.229847 -289.749453)
			(xy 399.221952 -289.79803) (xy 399.206368 -289.844711) (xy 399.183497 -289.888288) (xy 399.153932 -289.927632)
			(xy 399.118439 -289.961724) (xy 399.077936 -289.98968) (xy 399.033474 -290.010778) (xy 398.986203 -290.02447)
			(xy 398.937348 -290.030402) (xy 398.888173 -290.028421) (xy 398.839954 -290.018577) (xy 398.793938 -290.001125)
			(xy 398.751317 -289.976518) (xy 398.713196 -289.945393) (xy 398.680561 -289.908556) (xy 398.654258 -289.86696)
			(xy 398.634967 -289.821684) (xy 398.62319 -289.7739) (xy 398.61923 -289.724846) (xy 398.280128 -289.724846)
			(xy 398.279633 -289.749453) (xy 398.271738 -289.79803) (xy 398.256154 -289.844711) (xy 398.233283 -289.888288)
			(xy 398.203718 -289.927632) (xy 398.168225 -289.961724) (xy 398.127722 -289.98968) (xy 398.08326 -290.010778)
			(xy 398.035989 -290.02447) (xy 397.987134 -290.030402) (xy 397.937959 -290.028421) (xy 397.88974 -290.018577)
			(xy 397.843724 -290.001125) (xy 397.801103 -289.976518) (xy 397.762982 -289.945393) (xy 397.730347 -289.908556)
			(xy 397.704044 -289.86696) (xy 397.684753 -289.821684) (xy 397.672976 -289.7739) (xy 397.669016 -289.724846)
			(xy 397.330168 -289.724846) (xy 397.329673 -289.749453) (xy 397.321778 -289.79803) (xy 397.306194 -289.844711)
			(xy 397.283323 -289.888288) (xy 397.253758 -289.927632) (xy 397.218265 -289.961724) (xy 397.177762 -289.98968)
			(xy 397.1333 -290.010778) (xy 397.086029 -290.02447) (xy 397.037174 -290.030402) (xy 396.987999 -290.028421)
			(xy 396.93978 -290.018577) (xy 396.893764 -290.001125) (xy 396.851143 -289.976518) (xy 396.813022 -289.945393)
			(xy 396.780387 -289.908556) (xy 396.754084 -289.86696) (xy 396.734793 -289.821684) (xy 396.723016 -289.7739)
			(xy 396.719056 -289.724846) (xy 396.380208 -289.724846) (xy 396.379713 -289.749453) (xy 396.371818 -289.79803)
			(xy 396.356234 -289.844711) (xy 396.333363 -289.888288) (xy 396.303798 -289.927632) (xy 396.268305 -289.961724)
			(xy 396.227802 -289.98968) (xy 396.18334 -290.010778) (xy 396.136069 -290.02447) (xy 396.087214 -290.030402)
			(xy 396.038039 -290.028421) (xy 395.98982 -290.018577) (xy 395.943804 -290.001125) (xy 395.901183 -289.976518)
			(xy 395.863062 -289.945393) (xy 395.830427 -289.908556) (xy 395.804124 -289.86696) (xy 395.784833 -289.821684)
			(xy 395.773056 -289.7739) (xy 395.769096 -289.724846) (xy 395.430248 -289.724846) (xy 395.429753 -289.749453)
			(xy 395.421858 -289.79803) (xy 395.406274 -289.844711) (xy 395.383403 -289.888288) (xy 395.353838 -289.927632)
			(xy 395.318345 -289.961724) (xy 395.277842 -289.98968) (xy 395.23338 -290.010778) (xy 395.186109 -290.02447)
			(xy 395.137254 -290.030402) (xy 395.088079 -290.028421) (xy 395.03986 -290.018577) (xy 394.993844 -290.001125)
			(xy 394.951223 -289.976518) (xy 394.913102 -289.945393) (xy 394.880467 -289.908556) (xy 394.854164 -289.86696)
			(xy 394.834873 -289.821684) (xy 394.823096 -289.7739) (xy 394.819136 -289.724846) (xy 394.480288 -289.724846)
			(xy 394.479793 -289.749453) (xy 394.471898 -289.79803) (xy 394.456314 -289.844711) (xy 394.433443 -289.888288)
			(xy 394.403878 -289.927632) (xy 394.368385 -289.961724) (xy 394.327882 -289.98968) (xy 394.28342 -290.010778)
			(xy 394.236149 -290.02447) (xy 394.187294 -290.030402) (xy 394.138119 -290.028421) (xy 394.0899 -290.018577)
			(xy 394.043884 -290.001125) (xy 394.001263 -289.976518) (xy 393.963142 -289.945393) (xy 393.930507 -289.908556)
			(xy 393.904204 -289.86696) (xy 393.884913 -289.821684) (xy 393.873136 -289.7739) (xy 393.869176 -289.724846)
			(xy 393.530328 -289.724846) (xy 393.529833 -289.749453) (xy 393.521938 -289.79803) (xy 393.506354 -289.844711)
			(xy 393.483483 -289.888288) (xy 393.453918 -289.927632) (xy 393.418425 -289.961724) (xy 393.377922 -289.98968)
			(xy 393.33346 -290.010778) (xy 393.286189 -290.02447) (xy 393.237334 -290.030402) (xy 393.188159 -290.028421)
			(xy 393.13994 -290.018577) (xy 393.093924 -290.001125) (xy 393.051303 -289.976518) (xy 393.013182 -289.945393)
			(xy 392.980547 -289.908556) (xy 392.954244 -289.86696) (xy 392.934953 -289.821684) (xy 392.923176 -289.7739)
			(xy 392.919216 -289.724846) (xy 392.580114 -289.724846) (xy 392.579619 -289.749453) (xy 392.571724 -289.79803)
			(xy 392.55614 -289.844711) (xy 392.533269 -289.888288) (xy 392.503704 -289.927632) (xy 392.468211 -289.961724)
			(xy 392.427708 -289.98968) (xy 392.383246 -290.010778) (xy 392.335975 -290.02447) (xy 392.28712 -290.030402)
			(xy 392.237945 -290.028421) (xy 392.189726 -290.018577) (xy 392.14371 -290.001125) (xy 392.101089 -289.976518)
			(xy 392.062968 -289.945393) (xy 392.030333 -289.908556) (xy 392.00403 -289.86696) (xy 391.984739 -289.821684)
			(xy 391.972962 -289.7739) (xy 391.969002 -289.724846) (xy 391.630154 -289.724846) (xy 391.629659 -289.749453)
			(xy 391.621764 -289.79803) (xy 391.60618 -289.844711) (xy 391.583309 -289.888288) (xy 391.553744 -289.927632)
			(xy 391.518251 -289.961724) (xy 391.477748 -289.98968) (xy 391.433286 -290.010778) (xy 391.386015 -290.02447)
			(xy 391.33716 -290.030402) (xy 391.287985 -290.028421) (xy 391.239766 -290.018577) (xy 391.19375 -290.001125)
			(xy 391.151129 -289.976518) (xy 391.113008 -289.945393) (xy 391.080373 -289.908556) (xy 391.05407 -289.86696)
			(xy 391.034779 -289.821684) (xy 391.023002 -289.7739) (xy 391.019042 -289.724846) (xy 390.680194 -289.724846)
			(xy 390.679699 -289.749453) (xy 390.671804 -289.79803) (xy 390.65622 -289.844711) (xy 390.633349 -289.888288)
			(xy 390.603784 -289.927632) (xy 390.568291 -289.961724) (xy 390.527788 -289.98968) (xy 390.483326 -290.010778)
			(xy 390.436055 -290.02447) (xy 390.3872 -290.030402) (xy 390.338025 -290.028421) (xy 390.289806 -290.018577)
			(xy 390.24379 -290.001125) (xy 390.201169 -289.976518) (xy 390.163048 -289.945393) (xy 390.130413 -289.908556)
			(xy 390.10411 -289.86696) (xy 390.084819 -289.821684) (xy 390.073042 -289.7739) (xy 390.069082 -289.724846)
			(xy 389.730234 -289.724846) (xy 389.729739 -289.749453) (xy 389.721844 -289.79803) (xy 389.70626 -289.844711)
			(xy 389.683389 -289.888288) (xy 389.653824 -289.927632) (xy 389.618331 -289.961724) (xy 389.577828 -289.98968)
			(xy 389.533366 -290.010778) (xy 389.486095 -290.02447) (xy 389.43724 -290.030402) (xy 389.388065 -290.028421)
			(xy 389.339846 -290.018577) (xy 389.29383 -290.001125) (xy 389.251209 -289.976518) (xy 389.213088 -289.945393)
			(xy 389.180453 -289.908556) (xy 389.15415 -289.86696) (xy 389.134859 -289.821684) (xy 389.123082 -289.7739)
			(xy 389.119122 -289.724846) (xy 388.780274 -289.724846) (xy 388.779779 -289.749453) (xy 388.771884 -289.79803)
			(xy 388.7563 -289.844711) (xy 388.733429 -289.888288) (xy 388.703864 -289.927632) (xy 388.668371 -289.961724)
			(xy 388.627868 -289.98968) (xy 388.583406 -290.010778) (xy 388.536135 -290.02447) (xy 388.48728 -290.030402)
			(xy 388.438105 -290.028421) (xy 388.389886 -290.018577) (xy 388.34387 -290.001125) (xy 388.301249 -289.976518)
			(xy 388.263128 -289.945393) (xy 388.230493 -289.908556) (xy 388.20419 -289.86696) (xy 388.184899 -289.821684)
			(xy 388.173122 -289.7739) (xy 388.169162 -289.724846) (xy 387.830314 -289.724846) (xy 387.829819 -289.749453)
			(xy 387.821924 -289.79803) (xy 387.80634 -289.844711) (xy 387.783469 -289.888288) (xy 387.753904 -289.927632)
			(xy 387.718411 -289.961724) (xy 387.677908 -289.98968) (xy 387.633446 -290.010778) (xy 387.586175 -290.02447)
			(xy 387.53732 -290.030402) (xy 387.488145 -290.028421) (xy 387.439926 -290.018577) (xy 387.39391 -290.001125)
			(xy 387.351289 -289.976518) (xy 387.313168 -289.945393) (xy 387.280533 -289.908556) (xy 387.25423 -289.86696)
			(xy 387.234939 -289.821684) (xy 387.223162 -289.7739) (xy 387.219202 -289.724846) (xy 386.880354 -289.724846)
			(xy 386.879859 -289.749453) (xy 386.871964 -289.79803) (xy 386.85638 -289.844711) (xy 386.833509 -289.888288)
			(xy 386.803944 -289.927632) (xy 386.768451 -289.961724) (xy 386.727948 -289.98968) (xy 386.683486 -290.010778)
			(xy 386.636215 -290.02447) (xy 386.58736 -290.030402) (xy 386.538185 -290.028421) (xy 386.489966 -290.018577)
			(xy 386.44395 -290.001125) (xy 386.401329 -289.976518) (xy 386.363208 -289.945393) (xy 386.330573 -289.908556)
			(xy 386.30427 -289.86696) (xy 386.284979 -289.821684) (xy 386.273202 -289.7739) (xy 386.269242 -289.724846)
			(xy 385.93014 -289.724846) (xy 385.929645 -289.749453) (xy 385.92175 -289.79803) (xy 385.906166 -289.844711)
			(xy 385.883295 -289.888288) (xy 385.85373 -289.927632) (xy 385.818237 -289.961724) (xy 385.777734 -289.98968)
			(xy 385.733272 -290.010778) (xy 385.686001 -290.02447) (xy 385.637146 -290.030402) (xy 385.587971 -290.028421)
			(xy 385.539752 -290.018577) (xy 385.493736 -290.001125) (xy 385.451115 -289.976518) (xy 385.412994 -289.945393)
			(xy 385.380359 -289.908556) (xy 385.354056 -289.86696) (xy 385.334765 -289.821684) (xy 385.322988 -289.7739)
			(xy 385.319028 -289.724846) (xy 384.98018 -289.724846) (xy 384.979685 -289.749453) (xy 384.97179 -289.79803)
			(xy 384.956206 -289.844711) (xy 384.933335 -289.888288) (xy 384.90377 -289.927632) (xy 384.868277 -289.961724)
			(xy 384.827774 -289.98968) (xy 384.783312 -290.010778) (xy 384.736041 -290.02447) (xy 384.687186 -290.030402)
			(xy 384.638011 -290.028421) (xy 384.589792 -290.018577) (xy 384.543776 -290.001125) (xy 384.501155 -289.976518)
			(xy 384.463034 -289.945393) (xy 384.430399 -289.908556) (xy 384.404096 -289.86696) (xy 384.384805 -289.821684)
			(xy 384.373028 -289.7739) (xy 384.369068 -289.724846) (xy 380.360637 -289.724846) (xy 380.358889 -289.728354)
			(xy 380.324916 -289.776305) (xy 380.283989 -289.818476) (xy 380.26086 -289.836606) (xy 380.251462 -289.843972)
			(xy 380.241048 -289.864546) (xy 380.239524 -289.968432) (xy 380.24943 -289.989514) (xy 380.258574 -289.99688)
			(xy 380.280389 -290.015124) (xy 380.318933 -290.056934) (xy 380.350844 -290.104001) (xy 380.375417 -290.155284)
			(xy 380.392107 -290.209645) (xy 380.400545 -290.265881) (xy 380.401068 -290.294314) (xy 381.034542 -290.294314)
			(xy 381.038613 -290.238692) (xy 381.050739 -290.184255) (xy 381.070662 -290.132164) (xy 381.097958 -290.083529)
			(xy 381.132044 -290.039386) (xy 381.172193 -290.000677) (xy 381.217551 -289.968226) (xy 381.267151 -289.942725)
			(xy 381.319935 -289.924718) (xy 381.374778 -289.914588) (xy 381.430512 -289.912551) (xy 381.485949 -289.918651)
			(xy 381.539906 -289.932757) (xy 381.591235 -289.954569) (xy 381.638841 -289.983623) (xy 381.681709 -290.019298)
			(xy 381.718926 -290.060835) (xy 381.749699 -290.107348) (xy 381.773371 -290.157845) (xy 381.789439 -290.211252)
			(xy 381.797559 -290.266428) (xy 381.798068 -290.294314) (xy 381.921002 -290.294314) (xy 381.925073 -290.238692)
			(xy 381.937199 -290.184255) (xy 381.957122 -290.132164) (xy 381.984418 -290.083529) (xy 382.018504 -290.039386)
			(xy 382.058653 -290.000677) (xy 382.104011 -289.968226) (xy 382.153611 -289.942725) (xy 382.206395 -289.924718)
			(xy 382.261238 -289.914588) (xy 382.316972 -289.912551) (xy 382.372409 -289.918651) (xy 382.426366 -289.932757)
			(xy 382.477695 -289.954569) (xy 382.525301 -289.983623) (xy 382.568169 -290.019298) (xy 382.605386 -290.060835)
			(xy 382.636159 -290.107348) (xy 382.659831 -290.157845) (xy 382.675899 -290.211252) (xy 382.684019 -290.266428)
			(xy 382.684528 -290.294314) (xy 382.684019 -290.3222) (xy 382.675899 -290.377376) (xy 382.659831 -290.430783)
			(xy 382.636159 -290.48128) (xy 382.605386 -290.527793) (xy 382.568169 -290.56933) (xy 382.525301 -290.605005)
			(xy 382.477695 -290.634059) (xy 382.426366 -290.655871) (xy 382.372409 -290.669977) (xy 382.328523 -290.674806)
			(xy 384.369068 -290.674806) (xy 384.373028 -290.625752) (xy 384.384805 -290.577968) (xy 384.404096 -290.532692)
			(xy 384.430399 -290.491096) (xy 384.463034 -290.454259) (xy 384.501155 -290.423134) (xy 384.543776 -290.398527)
			(xy 384.589792 -290.381075) (xy 384.638011 -290.371231) (xy 384.687186 -290.36925) (xy 384.736041 -290.375182)
			(xy 384.783312 -290.388874) (xy 384.827774 -290.409972) (xy 384.868277 -290.437928) (xy 384.90377 -290.47202)
			(xy 384.933335 -290.511364) (xy 384.956206 -290.554941) (xy 384.97179 -290.601622) (xy 384.979685 -290.650199)
			(xy 384.98018 -290.674806) (xy 385.319028 -290.674806) (xy 385.322988 -290.625752) (xy 385.334765 -290.577968)
			(xy 385.354056 -290.532692) (xy 385.380359 -290.491096) (xy 385.412994 -290.454259) (xy 385.451115 -290.423134)
			(xy 385.493736 -290.398527) (xy 385.539752 -290.381075) (xy 385.587971 -290.371231) (xy 385.637146 -290.36925)
			(xy 385.686001 -290.375182) (xy 385.733272 -290.388874) (xy 385.777734 -290.409972) (xy 385.818237 -290.437928)
			(xy 385.85373 -290.47202) (xy 385.883295 -290.511364) (xy 385.906166 -290.554941) (xy 385.92175 -290.601622)
			(xy 385.929645 -290.650199) (xy 385.93014 -290.674806) (xy 386.269242 -290.674806) (xy 386.273202 -290.625752)
			(xy 386.284979 -290.577968) (xy 386.30427 -290.532692) (xy 386.330573 -290.491096) (xy 386.363208 -290.454259)
			(xy 386.401329 -290.423134) (xy 386.44395 -290.398527) (xy 386.489966 -290.381075) (xy 386.538185 -290.371231)
			(xy 386.58736 -290.36925) (xy 386.636215 -290.375182) (xy 386.683486 -290.388874) (xy 386.727948 -290.409972)
			(xy 386.768451 -290.437928) (xy 386.803944 -290.47202) (xy 386.833509 -290.511364) (xy 386.85638 -290.554941)
			(xy 386.871964 -290.601622) (xy 386.879859 -290.650199) (xy 386.880354 -290.674806) (xy 389.119122 -290.674806)
			(xy 389.123082 -290.625752) (xy 389.134859 -290.577968) (xy 389.15415 -290.532692) (xy 389.180453 -290.491096)
			(xy 389.213088 -290.454259) (xy 389.251209 -290.423134) (xy 389.29383 -290.398527) (xy 389.339846 -290.381075)
			(xy 389.388065 -290.371231) (xy 389.43724 -290.36925) (xy 389.486095 -290.375182) (xy 389.533366 -290.388874)
			(xy 389.577828 -290.409972) (xy 389.618331 -290.437928) (xy 389.653824 -290.47202) (xy 389.683389 -290.511364)
			(xy 389.70626 -290.554941) (xy 389.721844 -290.601622) (xy 389.729739 -290.650199) (xy 389.730234 -290.674806)
			(xy 390.069082 -290.674806) (xy 390.073042 -290.625752) (xy 390.084819 -290.577968) (xy 390.10411 -290.532692)
			(xy 390.130413 -290.491096) (xy 390.163048 -290.454259) (xy 390.201169 -290.423134) (xy 390.24379 -290.398527)
			(xy 390.289806 -290.381075) (xy 390.338025 -290.371231) (xy 390.3872 -290.36925) (xy 390.436055 -290.375182)
			(xy 390.483326 -290.388874) (xy 390.527788 -290.409972) (xy 390.568291 -290.437928) (xy 390.603784 -290.47202)
			(xy 390.633349 -290.511364) (xy 390.65622 -290.554941) (xy 390.671804 -290.601622) (xy 390.679699 -290.650199)
			(xy 390.680194 -290.674806) (xy 391.019042 -290.674806) (xy 391.023002 -290.625752) (xy 391.034779 -290.577968)
			(xy 391.05407 -290.532692) (xy 391.080373 -290.491096) (xy 391.113008 -290.454259) (xy 391.151129 -290.423134)
			(xy 391.19375 -290.398527) (xy 391.239766 -290.381075) (xy 391.287985 -290.371231) (xy 391.33716 -290.36925)
			(xy 391.386015 -290.375182) (xy 391.433286 -290.388874) (xy 391.477748 -290.409972) (xy 391.518251 -290.437928)
			(xy 391.553744 -290.47202) (xy 391.583309 -290.511364) (xy 391.60618 -290.554941) (xy 391.621764 -290.601622)
			(xy 391.629659 -290.650199) (xy 391.630154 -290.674806) (xy 391.969002 -290.674806) (xy 391.972962 -290.625752)
			(xy 391.984739 -290.577968) (xy 392.00403 -290.532692) (xy 392.030333 -290.491096) (xy 392.062968 -290.454259)
			(xy 392.101089 -290.423134) (xy 392.14371 -290.398527) (xy 392.189726 -290.381075) (xy 392.237945 -290.371231)
			(xy 392.28712 -290.36925) (xy 392.335975 -290.375182) (xy 392.383246 -290.388874) (xy 392.427708 -290.409972)
			(xy 392.468211 -290.437928) (xy 392.503704 -290.47202) (xy 392.533269 -290.511364) (xy 392.55614 -290.554941)
			(xy 392.571724 -290.601622) (xy 392.579619 -290.650199) (xy 392.580114 -290.674806) (xy 392.919216 -290.674806)
			(xy 392.923176 -290.625752) (xy 392.934953 -290.577968) (xy 392.954244 -290.532692) (xy 392.980547 -290.491096)
			(xy 393.013182 -290.454259) (xy 393.051303 -290.423134) (xy 393.093924 -290.398527) (xy 393.13994 -290.381075)
			(xy 393.188159 -290.371231) (xy 393.237334 -290.36925) (xy 393.286189 -290.375182) (xy 393.33346 -290.388874)
			(xy 393.377922 -290.409972) (xy 393.418425 -290.437928) (xy 393.453918 -290.47202) (xy 393.483483 -290.511364)
			(xy 393.506354 -290.554941) (xy 393.521938 -290.601622) (xy 393.529833 -290.650199) (xy 393.530328 -290.674806)
			(xy 393.869176 -290.674806) (xy 393.873136 -290.625752) (xy 393.884913 -290.577968) (xy 393.904204 -290.532692)
			(xy 393.930507 -290.491096) (xy 393.963142 -290.454259) (xy 394.001263 -290.423134) (xy 394.043884 -290.398527)
			(xy 394.0899 -290.381075) (xy 394.138119 -290.371231) (xy 394.187294 -290.36925) (xy 394.236149 -290.375182)
			(xy 394.28342 -290.388874) (xy 394.327882 -290.409972) (xy 394.368385 -290.437928) (xy 394.403878 -290.47202)
			(xy 394.433443 -290.511364) (xy 394.456314 -290.554941) (xy 394.471898 -290.601622) (xy 394.479793 -290.650199)
			(xy 394.480288 -290.674806) (xy 394.819136 -290.674806) (xy 394.823096 -290.625752) (xy 394.834873 -290.577968)
			(xy 394.854164 -290.532692) (xy 394.880467 -290.491096) (xy 394.913102 -290.454259) (xy 394.951223 -290.423134)
			(xy 394.993844 -290.398527) (xy 395.03986 -290.381075) (xy 395.088079 -290.371231) (xy 395.137254 -290.36925)
			(xy 395.186109 -290.375182) (xy 395.23338 -290.388874) (xy 395.277842 -290.409972) (xy 395.318345 -290.437928)
			(xy 395.353838 -290.47202) (xy 395.383403 -290.511364) (xy 395.406274 -290.554941) (xy 395.421858 -290.601622)
			(xy 395.429753 -290.650199) (xy 395.430248 -290.674806) (xy 395.769096 -290.674806) (xy 395.773056 -290.625752)
			(xy 395.784833 -290.577968) (xy 395.804124 -290.532692) (xy 395.830427 -290.491096) (xy 395.863062 -290.454259)
			(xy 395.901183 -290.423134) (xy 395.943804 -290.398527) (xy 395.98982 -290.381075) (xy 396.038039 -290.371231)
			(xy 396.087214 -290.36925) (xy 396.136069 -290.375182) (xy 396.18334 -290.388874) (xy 396.227802 -290.409972)
			(xy 396.268305 -290.437928) (xy 396.303798 -290.47202) (xy 396.333363 -290.511364) (xy 396.356234 -290.554941)
			(xy 396.371818 -290.601622) (xy 396.379713 -290.650199) (xy 396.380208 -290.674806) (xy 397.669016 -290.674806)
			(xy 397.672976 -290.625752) (xy 397.684753 -290.577968) (xy 397.704044 -290.532692) (xy 397.730347 -290.491096)
			(xy 397.762982 -290.454259) (xy 397.801103 -290.423134) (xy 397.843724 -290.398527) (xy 397.88974 -290.381075)
			(xy 397.937959 -290.371231) (xy 397.987134 -290.36925) (xy 398.035989 -290.375182) (xy 398.08326 -290.388874)
			(xy 398.127722 -290.409972) (xy 398.168225 -290.437928) (xy 398.203718 -290.47202) (xy 398.233283 -290.511364)
			(xy 398.256154 -290.554941) (xy 398.271738 -290.601622) (xy 398.279633 -290.650199) (xy 398.280128 -290.674806)
			(xy 398.61923 -290.674806) (xy 398.62319 -290.625752) (xy 398.634967 -290.577968) (xy 398.654258 -290.532692)
			(xy 398.680561 -290.491096) (xy 398.713196 -290.454259) (xy 398.751317 -290.423134) (xy 398.793938 -290.398527)
			(xy 398.839954 -290.381075) (xy 398.888173 -290.371231) (xy 398.937348 -290.36925) (xy 398.986203 -290.375182)
			(xy 399.033474 -290.388874) (xy 399.077936 -290.409972) (xy 399.118439 -290.437928) (xy 399.153932 -290.47202)
			(xy 399.183497 -290.511364) (xy 399.206368 -290.554941) (xy 399.221952 -290.601622) (xy 399.229847 -290.650199)
			(xy 399.230342 -290.674806) (xy 399.56919 -290.674806) (xy 399.57315 -290.625752) (xy 399.584927 -290.577968)
			(xy 399.604218 -290.532692) (xy 399.630521 -290.491096) (xy 399.663156 -290.454259) (xy 399.701277 -290.423134)
			(xy 399.743898 -290.398527) (xy 399.789914 -290.381075) (xy 399.838133 -290.371231) (xy 399.887308 -290.36925)
			(xy 399.936163 -290.375182) (xy 399.983434 -290.388874) (xy 400.027896 -290.409972) (xy 400.068399 -290.437928)
			(xy 400.103892 -290.47202) (xy 400.133457 -290.511364) (xy 400.156328 -290.554941) (xy 400.171912 -290.601622)
			(xy 400.179807 -290.650199) (xy 400.180302 -290.674806) (xy 400.51915 -290.674806) (xy 400.52311 -290.625752)
			(xy 400.534887 -290.577968) (xy 400.554178 -290.532692) (xy 400.580481 -290.491096) (xy 400.613116 -290.454259)
			(xy 400.651237 -290.423134) (xy 400.693858 -290.398527) (xy 400.739874 -290.381075) (xy 400.788093 -290.371231)
			(xy 400.837268 -290.36925) (xy 400.886123 -290.375182) (xy 400.933394 -290.388874) (xy 400.977856 -290.409972)
			(xy 401.018359 -290.437928) (xy 401.053852 -290.47202) (xy 401.083417 -290.511364) (xy 401.106288 -290.554941)
			(xy 401.121872 -290.601622) (xy 401.129767 -290.650199) (xy 401.130262 -290.674806) (xy 401.46911 -290.674806)
			(xy 401.47307 -290.625752) (xy 401.484847 -290.577968) (xy 401.504138 -290.532692) (xy 401.530441 -290.491096)
			(xy 401.563076 -290.454259) (xy 401.601197 -290.423134) (xy 401.643818 -290.398527) (xy 401.689834 -290.381075)
			(xy 401.738053 -290.371231) (xy 401.787228 -290.36925) (xy 401.836083 -290.375182) (xy 401.883354 -290.388874)
			(xy 401.927816 -290.409972) (xy 401.968319 -290.437928) (xy 402.003812 -290.47202) (xy 402.033377 -290.511364)
			(xy 402.056248 -290.554941) (xy 402.071832 -290.601622) (xy 402.079727 -290.650199) (xy 402.080222 -290.674806)
			(xy 402.41907 -290.674806) (xy 402.42303 -290.625752) (xy 402.434807 -290.577968) (xy 402.454098 -290.532692)
			(xy 402.480401 -290.491096) (xy 402.513036 -290.454259) (xy 402.551157 -290.423134) (xy 402.593778 -290.398527)
			(xy 402.639794 -290.381075) (xy 402.688013 -290.371231) (xy 402.737188 -290.36925) (xy 402.786043 -290.375182)
			(xy 402.833314 -290.388874) (xy 402.877776 -290.409972) (xy 402.918279 -290.437928) (xy 402.953772 -290.47202)
			(xy 402.983337 -290.511364) (xy 403.006208 -290.554941) (xy 403.021792 -290.601622) (xy 403.029687 -290.650199)
			(xy 403.030182 -290.674806) (xy 403.36903 -290.674806) (xy 403.37299 -290.625752) (xy 403.384767 -290.577968)
			(xy 403.404058 -290.532692) (xy 403.430361 -290.491096) (xy 403.462996 -290.454259) (xy 403.501117 -290.423134)
			(xy 403.543738 -290.398527) (xy 403.589754 -290.381075) (xy 403.637973 -290.371231) (xy 403.687148 -290.36925)
			(xy 403.736003 -290.375182) (xy 403.783274 -290.388874) (xy 403.827736 -290.409972) (xy 403.868239 -290.437928)
			(xy 403.903732 -290.47202) (xy 403.933297 -290.511364) (xy 403.956168 -290.554941) (xy 403.971752 -290.601622)
			(xy 403.979647 -290.650199) (xy 403.980142 -290.674806) (xy 404.31899 -290.674806) (xy 404.32295 -290.625752)
			(xy 404.334727 -290.577968) (xy 404.354018 -290.532692) (xy 404.380321 -290.491096) (xy 404.412956 -290.454259)
			(xy 404.451077 -290.423134) (xy 404.493698 -290.398527) (xy 404.539714 -290.381075) (xy 404.587933 -290.371231)
			(xy 404.637108 -290.36925) (xy 404.685963 -290.375182) (xy 404.733234 -290.388874) (xy 404.777696 -290.409972)
			(xy 404.818199 -290.437928) (xy 404.853692 -290.47202) (xy 404.883257 -290.511364) (xy 404.906128 -290.554941)
			(xy 404.921712 -290.601622) (xy 404.929607 -290.650199) (xy 404.930102 -290.674806) (xy 405.269204 -290.674806)
			(xy 405.273164 -290.625752) (xy 405.284941 -290.577968) (xy 405.304232 -290.532692) (xy 405.330535 -290.491096)
			(xy 405.36317 -290.454259) (xy 405.401291 -290.423134) (xy 405.443912 -290.398527) (xy 405.489928 -290.381075)
			(xy 405.538147 -290.371231) (xy 405.587322 -290.36925) (xy 405.636177 -290.375182) (xy 405.683448 -290.388874)
			(xy 405.72791 -290.409972) (xy 405.768413 -290.437928) (xy 405.803906 -290.47202) (xy 405.833471 -290.511364)
			(xy 405.856342 -290.554941) (xy 405.871926 -290.601622) (xy 405.879821 -290.650199) (xy 405.880316 -290.674806)
			(xy 406.219164 -290.674806) (xy 406.223124 -290.625752) (xy 406.234901 -290.577968) (xy 406.254192 -290.532692)
			(xy 406.280495 -290.491096) (xy 406.31313 -290.454259) (xy 406.351251 -290.423134) (xy 406.393872 -290.398527)
			(xy 406.439888 -290.381075) (xy 406.488107 -290.371231) (xy 406.537282 -290.36925) (xy 406.586137 -290.375182)
			(xy 406.633408 -290.388874) (xy 406.67787 -290.409972) (xy 406.718373 -290.437928) (xy 406.753866 -290.47202)
			(xy 406.783431 -290.511364) (xy 406.806302 -290.554941) (xy 406.821886 -290.601622) (xy 406.829781 -290.650199)
			(xy 406.830276 -290.674806) (xy 408.119084 -290.674806) (xy 408.123044 -290.625752) (xy 408.134821 -290.577968)
			(xy 408.154112 -290.532692) (xy 408.180415 -290.491096) (xy 408.21305 -290.454259) (xy 408.251171 -290.423134)
			(xy 408.293792 -290.398527) (xy 408.339808 -290.381075) (xy 408.388027 -290.371231) (xy 408.437202 -290.36925)
			(xy 408.486057 -290.375182) (xy 408.533328 -290.388874) (xy 408.57779 -290.409972) (xy 408.618293 -290.437928)
			(xy 408.653786 -290.47202) (xy 408.683351 -290.511364) (xy 408.706222 -290.554941) (xy 408.721806 -290.601622)
			(xy 408.729701 -290.650199) (xy 408.730196 -290.674806) (xy 409.069044 -290.674806) (xy 409.073004 -290.625752)
			(xy 409.084781 -290.577968) (xy 409.104072 -290.532692) (xy 409.130375 -290.491096) (xy 409.16301 -290.454259)
			(xy 409.201131 -290.423134) (xy 409.243752 -290.398527) (xy 409.289768 -290.381075) (xy 409.337987 -290.371231)
			(xy 409.387162 -290.36925) (xy 409.436017 -290.375182) (xy 409.483288 -290.388874) (xy 409.52775 -290.409972)
			(xy 409.568253 -290.437928) (xy 409.603746 -290.47202) (xy 409.633311 -290.511364) (xy 409.656182 -290.554941)
			(xy 409.671766 -290.601622) (xy 409.679661 -290.650199) (xy 409.680156 -290.674806) (xy 410.019004 -290.674806)
			(xy 410.022964 -290.625752) (xy 410.034741 -290.577968) (xy 410.054032 -290.532692) (xy 410.080335 -290.491096)
			(xy 410.11297 -290.454259) (xy 410.151091 -290.423134) (xy 410.193712 -290.398527) (xy 410.239728 -290.381075)
			(xy 410.287947 -290.371231) (xy 410.337122 -290.36925) (xy 410.385977 -290.375182) (xy 410.433248 -290.388874)
			(xy 410.47771 -290.409972) (xy 410.518213 -290.437928) (xy 410.553706 -290.47202) (xy 410.583271 -290.511364)
			(xy 410.606142 -290.554941) (xy 410.621726 -290.601622) (xy 410.629621 -290.650199) (xy 410.630116 -290.674806)
			(xy 410.969218 -290.674806) (xy 410.973178 -290.625752) (xy 410.984955 -290.577968) (xy 411.004246 -290.532692)
			(xy 411.030549 -290.491096) (xy 411.063184 -290.454259) (xy 411.101305 -290.423134) (xy 411.143926 -290.398527)
			(xy 411.189942 -290.381075) (xy 411.238161 -290.371231) (xy 411.287336 -290.36925) (xy 411.336191 -290.375182)
			(xy 411.383462 -290.388874) (xy 411.427924 -290.409972) (xy 411.468427 -290.437928) (xy 411.50392 -290.47202)
			(xy 411.533485 -290.511364) (xy 411.556356 -290.554941) (xy 411.57194 -290.601622) (xy 411.579835 -290.650199)
			(xy 411.58033 -290.674806) (xy 411.919178 -290.674806) (xy 411.923138 -290.625752) (xy 411.934915 -290.577968)
			(xy 411.954206 -290.532692) (xy 411.980509 -290.491096) (xy 412.013144 -290.454259) (xy 412.051265 -290.423134)
			(xy 412.093886 -290.398527) (xy 412.139902 -290.381075) (xy 412.188121 -290.371231) (xy 412.237296 -290.36925)
			(xy 412.286151 -290.375182) (xy 412.333422 -290.388874) (xy 412.377884 -290.409972) (xy 412.418387 -290.437928)
			(xy 412.45388 -290.47202) (xy 412.483445 -290.511364) (xy 412.506316 -290.554941) (xy 412.5219 -290.601622)
			(xy 412.529795 -290.650199) (xy 412.53029 -290.674806) (xy 412.869138 -290.674806) (xy 412.873098 -290.625752)
			(xy 412.884875 -290.577968) (xy 412.904166 -290.532692) (xy 412.930469 -290.491096) (xy 412.963104 -290.454259)
			(xy 413.001225 -290.423134) (xy 413.043846 -290.398527) (xy 413.089862 -290.381075) (xy 413.138081 -290.371231)
			(xy 413.187256 -290.36925) (xy 413.236111 -290.375182) (xy 413.283382 -290.388874) (xy 413.327844 -290.409972)
			(xy 413.368347 -290.437928) (xy 413.40384 -290.47202) (xy 413.433405 -290.511364) (xy 413.456276 -290.554941)
			(xy 413.47186 -290.601622) (xy 413.479755 -290.650199) (xy 413.48025 -290.674806) (xy 413.819098 -290.674806)
			(xy 413.823058 -290.625752) (xy 413.834835 -290.577968) (xy 413.854126 -290.532692) (xy 413.880429 -290.491096)
			(xy 413.913064 -290.454259) (xy 413.951185 -290.423134) (xy 413.993806 -290.398527) (xy 414.039822 -290.381075)
			(xy 414.088041 -290.371231) (xy 414.137216 -290.36925) (xy 414.186071 -290.375182) (xy 414.233342 -290.388874)
			(xy 414.277804 -290.409972) (xy 414.318307 -290.437928) (xy 414.3538 -290.47202) (xy 414.383365 -290.511364)
			(xy 414.406236 -290.554941) (xy 414.42182 -290.601622) (xy 414.429715 -290.650199) (xy 414.43021 -290.674806)
			(xy 414.769058 -290.674806) (xy 414.773018 -290.625752) (xy 414.784795 -290.577968) (xy 414.804086 -290.532692)
			(xy 414.830389 -290.491096) (xy 414.863024 -290.454259) (xy 414.901145 -290.423134) (xy 414.943766 -290.398527)
			(xy 414.989782 -290.381075) (xy 415.038001 -290.371231) (xy 415.087176 -290.36925) (xy 415.136031 -290.375182)
			(xy 415.183302 -290.388874) (xy 415.227764 -290.409972) (xy 415.268267 -290.437928) (xy 415.30376 -290.47202)
			(xy 415.333325 -290.511364) (xy 415.356196 -290.554941) (xy 415.37178 -290.601622) (xy 415.379675 -290.650199)
			(xy 415.38017 -290.674806) (xy 415.719018 -290.674806) (xy 415.722978 -290.625752) (xy 415.734755 -290.577968)
			(xy 415.754046 -290.532692) (xy 415.780349 -290.491096) (xy 415.812984 -290.454259) (xy 415.851105 -290.423134)
			(xy 415.893726 -290.398527) (xy 415.939742 -290.381075) (xy 415.987961 -290.371231) (xy 416.037136 -290.36925)
			(xy 416.085991 -290.375182) (xy 416.133262 -290.388874) (xy 416.177724 -290.409972) (xy 416.218227 -290.437928)
			(xy 416.25372 -290.47202) (xy 416.283285 -290.511364) (xy 416.306156 -290.554941) (xy 416.32174 -290.601622)
			(xy 416.329635 -290.650199) (xy 416.33013 -290.674806) (xy 416.329635 -290.699413) (xy 416.32174 -290.74799)
			(xy 416.306156 -290.794671) (xy 416.283285 -290.838248) (xy 416.25372 -290.877592) (xy 416.218227 -290.911684)
			(xy 416.177724 -290.93964) (xy 416.133262 -290.960738) (xy 416.085991 -290.97443) (xy 416.037136 -290.980362)
			(xy 415.987961 -290.978381) (xy 415.939742 -290.968537) (xy 415.893726 -290.951085) (xy 415.851105 -290.926478)
			(xy 415.812984 -290.895353) (xy 415.780349 -290.858516) (xy 415.754046 -290.81692) (xy 415.734755 -290.771644)
			(xy 415.722978 -290.72386) (xy 415.719018 -290.674806) (xy 415.38017 -290.674806) (xy 415.379675 -290.699413)
			(xy 415.37178 -290.74799) (xy 415.356196 -290.794671) (xy 415.333325 -290.838248) (xy 415.30376 -290.877592)
			(xy 415.268267 -290.911684) (xy 415.227764 -290.93964) (xy 415.183302 -290.960738) (xy 415.136031 -290.97443)
			(xy 415.087176 -290.980362) (xy 415.038001 -290.978381) (xy 414.989782 -290.968537) (xy 414.943766 -290.951085)
			(xy 414.901145 -290.926478) (xy 414.863024 -290.895353) (xy 414.830389 -290.858516) (xy 414.804086 -290.81692)
			(xy 414.784795 -290.771644) (xy 414.773018 -290.72386) (xy 414.769058 -290.674806) (xy 414.43021 -290.674806)
			(xy 414.429715 -290.699413) (xy 414.42182 -290.74799) (xy 414.406236 -290.794671) (xy 414.383365 -290.838248)
			(xy 414.3538 -290.877592) (xy 414.318307 -290.911684) (xy 414.277804 -290.93964) (xy 414.233342 -290.960738)
			(xy 414.186071 -290.97443) (xy 414.137216 -290.980362) (xy 414.088041 -290.978381) (xy 414.039822 -290.968537)
			(xy 413.993806 -290.951085) (xy 413.951185 -290.926478) (xy 413.913064 -290.895353) (xy 413.880429 -290.858516)
			(xy 413.854126 -290.81692) (xy 413.834835 -290.771644) (xy 413.823058 -290.72386) (xy 413.819098 -290.674806)
			(xy 413.48025 -290.674806) (xy 413.479755 -290.699413) (xy 413.47186 -290.74799) (xy 413.456276 -290.794671)
			(xy 413.433405 -290.838248) (xy 413.40384 -290.877592) (xy 413.368347 -290.911684) (xy 413.327844 -290.93964)
			(xy 413.283382 -290.960738) (xy 413.236111 -290.97443) (xy 413.187256 -290.980362) (xy 413.138081 -290.978381)
			(xy 413.089862 -290.968537) (xy 413.043846 -290.951085) (xy 413.001225 -290.926478) (xy 412.963104 -290.895353)
			(xy 412.930469 -290.858516) (xy 412.904166 -290.81692) (xy 412.884875 -290.771644) (xy 412.873098 -290.72386)
			(xy 412.869138 -290.674806) (xy 412.53029 -290.674806) (xy 412.529795 -290.699413) (xy 412.5219 -290.74799)
			(xy 412.506316 -290.794671) (xy 412.483445 -290.838248) (xy 412.45388 -290.877592) (xy 412.418387 -290.911684)
			(xy 412.377884 -290.93964) (xy 412.333422 -290.960738) (xy 412.286151 -290.97443) (xy 412.237296 -290.980362)
			(xy 412.188121 -290.978381) (xy 412.139902 -290.968537) (xy 412.093886 -290.951085) (xy 412.051265 -290.926478)
			(xy 412.013144 -290.895353) (xy 411.980509 -290.858516) (xy 411.954206 -290.81692) (xy 411.934915 -290.771644)
			(xy 411.923138 -290.72386) (xy 411.919178 -290.674806) (xy 411.58033 -290.674806) (xy 411.579835 -290.699413)
			(xy 411.57194 -290.74799) (xy 411.556356 -290.794671) (xy 411.533485 -290.838248) (xy 411.50392 -290.877592)
			(xy 411.468427 -290.911684) (xy 411.427924 -290.93964) (xy 411.383462 -290.960738) (xy 411.336191 -290.97443)
			(xy 411.287336 -290.980362) (xy 411.238161 -290.978381) (xy 411.189942 -290.968537) (xy 411.143926 -290.951085)
			(xy 411.101305 -290.926478) (xy 411.063184 -290.895353) (xy 411.030549 -290.858516) (xy 411.004246 -290.81692)
			(xy 410.984955 -290.771644) (xy 410.973178 -290.72386) (xy 410.969218 -290.674806) (xy 410.630116 -290.674806)
			(xy 410.629621 -290.699413) (xy 410.621726 -290.74799) (xy 410.606142 -290.794671) (xy 410.583271 -290.838248)
			(xy 410.553706 -290.877592) (xy 410.518213 -290.911684) (xy 410.47771 -290.93964) (xy 410.433248 -290.960738)
			(xy 410.385977 -290.97443) (xy 410.337122 -290.980362) (xy 410.287947 -290.978381) (xy 410.239728 -290.968537)
			(xy 410.193712 -290.951085) (xy 410.151091 -290.926478) (xy 410.11297 -290.895353) (xy 410.080335 -290.858516)
			(xy 410.054032 -290.81692) (xy 410.034741 -290.771644) (xy 410.022964 -290.72386) (xy 410.019004 -290.674806)
			(xy 409.680156 -290.674806) (xy 409.679661 -290.699413) (xy 409.671766 -290.74799) (xy 409.656182 -290.794671)
			(xy 409.633311 -290.838248) (xy 409.603746 -290.877592) (xy 409.568253 -290.911684) (xy 409.52775 -290.93964)
			(xy 409.483288 -290.960738) (xy 409.436017 -290.97443) (xy 409.387162 -290.980362) (xy 409.337987 -290.978381)
			(xy 409.289768 -290.968537) (xy 409.243752 -290.951085) (xy 409.201131 -290.926478) (xy 409.16301 -290.895353)
			(xy 409.130375 -290.858516) (xy 409.104072 -290.81692) (xy 409.084781 -290.771644) (xy 409.073004 -290.72386)
			(xy 409.069044 -290.674806) (xy 408.730196 -290.674806) (xy 408.729701 -290.699413) (xy 408.721806 -290.74799)
			(xy 408.706222 -290.794671) (xy 408.683351 -290.838248) (xy 408.653786 -290.877592) (xy 408.618293 -290.911684)
			(xy 408.57779 -290.93964) (xy 408.533328 -290.960738) (xy 408.486057 -290.97443) (xy 408.437202 -290.980362)
			(xy 408.388027 -290.978381) (xy 408.339808 -290.968537) (xy 408.293792 -290.951085) (xy 408.251171 -290.926478)
			(xy 408.21305 -290.895353) (xy 408.180415 -290.858516) (xy 408.154112 -290.81692) (xy 408.134821 -290.771644)
			(xy 408.123044 -290.72386) (xy 408.119084 -290.674806) (xy 406.830276 -290.674806) (xy 406.829781 -290.699413)
			(xy 406.821886 -290.74799) (xy 406.806302 -290.794671) (xy 406.783431 -290.838248) (xy 406.753866 -290.877592)
			(xy 406.718373 -290.911684) (xy 406.67787 -290.93964) (xy 406.633408 -290.960738) (xy 406.586137 -290.97443)
			(xy 406.537282 -290.980362) (xy 406.488107 -290.978381) (xy 406.439888 -290.968537) (xy 406.393872 -290.951085)
			(xy 406.351251 -290.926478) (xy 406.31313 -290.895353) (xy 406.280495 -290.858516) (xy 406.254192 -290.81692)
			(xy 406.234901 -290.771644) (xy 406.223124 -290.72386) (xy 406.219164 -290.674806) (xy 405.880316 -290.674806)
			(xy 405.879821 -290.699413) (xy 405.871926 -290.74799) (xy 405.856342 -290.794671) (xy 405.833471 -290.838248)
			(xy 405.803906 -290.877592) (xy 405.768413 -290.911684) (xy 405.72791 -290.93964) (xy 405.683448 -290.960738)
			(xy 405.636177 -290.97443) (xy 405.587322 -290.980362) (xy 405.538147 -290.978381) (xy 405.489928 -290.968537)
			(xy 405.443912 -290.951085) (xy 405.401291 -290.926478) (xy 405.36317 -290.895353) (xy 405.330535 -290.858516)
			(xy 405.304232 -290.81692) (xy 405.284941 -290.771644) (xy 405.273164 -290.72386) (xy 405.269204 -290.674806)
			(xy 404.930102 -290.674806) (xy 404.929607 -290.699413) (xy 404.921712 -290.74799) (xy 404.906128 -290.794671)
			(xy 404.883257 -290.838248) (xy 404.853692 -290.877592) (xy 404.818199 -290.911684) (xy 404.777696 -290.93964)
			(xy 404.733234 -290.960738) (xy 404.685963 -290.97443) (xy 404.637108 -290.980362) (xy 404.587933 -290.978381)
			(xy 404.539714 -290.968537) (xy 404.493698 -290.951085) (xy 404.451077 -290.926478) (xy 404.412956 -290.895353)
			(xy 404.380321 -290.858516) (xy 404.354018 -290.81692) (xy 404.334727 -290.771644) (xy 404.32295 -290.72386)
			(xy 404.31899 -290.674806) (xy 403.980142 -290.674806) (xy 403.979647 -290.699413) (xy 403.971752 -290.74799)
			(xy 403.956168 -290.794671) (xy 403.933297 -290.838248) (xy 403.903732 -290.877592) (xy 403.868239 -290.911684)
			(xy 403.827736 -290.93964) (xy 403.783274 -290.960738) (xy 403.736003 -290.97443) (xy 403.687148 -290.980362)
			(xy 403.637973 -290.978381) (xy 403.589754 -290.968537) (xy 403.543738 -290.951085) (xy 403.501117 -290.926478)
			(xy 403.462996 -290.895353) (xy 403.430361 -290.858516) (xy 403.404058 -290.81692) (xy 403.384767 -290.771644)
			(xy 403.37299 -290.72386) (xy 403.36903 -290.674806) (xy 403.030182 -290.674806) (xy 403.029687 -290.699413)
			(xy 403.021792 -290.74799) (xy 403.006208 -290.794671) (xy 402.983337 -290.838248) (xy 402.953772 -290.877592)
			(xy 402.918279 -290.911684) (xy 402.877776 -290.93964) (xy 402.833314 -290.960738) (xy 402.786043 -290.97443)
			(xy 402.737188 -290.980362) (xy 402.688013 -290.978381) (xy 402.639794 -290.968537) (xy 402.593778 -290.951085)
			(xy 402.551157 -290.926478) (xy 402.513036 -290.895353) (xy 402.480401 -290.858516) (xy 402.454098 -290.81692)
			(xy 402.434807 -290.771644) (xy 402.42303 -290.72386) (xy 402.41907 -290.674806) (xy 402.080222 -290.674806)
			(xy 402.079727 -290.699413) (xy 402.071832 -290.74799) (xy 402.056248 -290.794671) (xy 402.033377 -290.838248)
			(xy 402.003812 -290.877592) (xy 401.968319 -290.911684) (xy 401.927816 -290.93964) (xy 401.883354 -290.960738)
			(xy 401.836083 -290.97443) (xy 401.787228 -290.980362) (xy 401.738053 -290.978381) (xy 401.689834 -290.968537)
			(xy 401.643818 -290.951085) (xy 401.601197 -290.926478) (xy 401.563076 -290.895353) (xy 401.530441 -290.858516)
			(xy 401.504138 -290.81692) (xy 401.484847 -290.771644) (xy 401.47307 -290.72386) (xy 401.46911 -290.674806)
			(xy 401.130262 -290.674806) (xy 401.129767 -290.699413) (xy 401.121872 -290.74799) (xy 401.106288 -290.794671)
			(xy 401.083417 -290.838248) (xy 401.053852 -290.877592) (xy 401.018359 -290.911684) (xy 400.977856 -290.93964)
			(xy 400.933394 -290.960738) (xy 400.886123 -290.97443) (xy 400.837268 -290.980362) (xy 400.788093 -290.978381)
			(xy 400.739874 -290.968537) (xy 400.693858 -290.951085) (xy 400.651237 -290.926478) (xy 400.613116 -290.895353)
			(xy 400.580481 -290.858516) (xy 400.554178 -290.81692) (xy 400.534887 -290.771644) (xy 400.52311 -290.72386)
			(xy 400.51915 -290.674806) (xy 400.180302 -290.674806) (xy 400.179807 -290.699413) (xy 400.171912 -290.74799)
			(xy 400.156328 -290.794671) (xy 400.133457 -290.838248) (xy 400.103892 -290.877592) (xy 400.068399 -290.911684)
			(xy 400.027896 -290.93964) (xy 399.983434 -290.960738) (xy 399.936163 -290.97443) (xy 399.887308 -290.980362)
			(xy 399.838133 -290.978381) (xy 399.789914 -290.968537) (xy 399.743898 -290.951085) (xy 399.701277 -290.926478)
			(xy 399.663156 -290.895353) (xy 399.630521 -290.858516) (xy 399.604218 -290.81692) (xy 399.584927 -290.771644)
			(xy 399.57315 -290.72386) (xy 399.56919 -290.674806) (xy 399.230342 -290.674806) (xy 399.229847 -290.699413)
			(xy 399.221952 -290.74799) (xy 399.206368 -290.794671) (xy 399.183497 -290.838248) (xy 399.153932 -290.877592)
			(xy 399.118439 -290.911684) (xy 399.077936 -290.93964) (xy 399.033474 -290.960738) (xy 398.986203 -290.97443)
			(xy 398.937348 -290.980362) (xy 398.888173 -290.978381) (xy 398.839954 -290.968537) (xy 398.793938 -290.951085)
			(xy 398.751317 -290.926478) (xy 398.713196 -290.895353) (xy 398.680561 -290.858516) (xy 398.654258 -290.81692)
			(xy 398.634967 -290.771644) (xy 398.62319 -290.72386) (xy 398.61923 -290.674806) (xy 398.280128 -290.674806)
			(xy 398.279633 -290.699413) (xy 398.271738 -290.74799) (xy 398.256154 -290.794671) (xy 398.233283 -290.838248)
			(xy 398.203718 -290.877592) (xy 398.168225 -290.911684) (xy 398.127722 -290.93964) (xy 398.08326 -290.960738)
			(xy 398.035989 -290.97443) (xy 397.987134 -290.980362) (xy 397.937959 -290.978381) (xy 397.88974 -290.968537)
			(xy 397.843724 -290.951085) (xy 397.801103 -290.926478) (xy 397.762982 -290.895353) (xy 397.730347 -290.858516)
			(xy 397.704044 -290.81692) (xy 397.684753 -290.771644) (xy 397.672976 -290.72386) (xy 397.669016 -290.674806)
			(xy 396.380208 -290.674806) (xy 396.379713 -290.699413) (xy 396.371818 -290.74799) (xy 396.356234 -290.794671)
			(xy 396.333363 -290.838248) (xy 396.303798 -290.877592) (xy 396.268305 -290.911684) (xy 396.227802 -290.93964)
			(xy 396.18334 -290.960738) (xy 396.136069 -290.97443) (xy 396.087214 -290.980362) (xy 396.038039 -290.978381)
			(xy 395.98982 -290.968537) (xy 395.943804 -290.951085) (xy 395.901183 -290.926478) (xy 395.863062 -290.895353)
			(xy 395.830427 -290.858516) (xy 395.804124 -290.81692) (xy 395.784833 -290.771644) (xy 395.773056 -290.72386)
			(xy 395.769096 -290.674806) (xy 395.430248 -290.674806) (xy 395.429753 -290.699413) (xy 395.421858 -290.74799)
			(xy 395.406274 -290.794671) (xy 395.383403 -290.838248) (xy 395.353838 -290.877592) (xy 395.318345 -290.911684)
			(xy 395.277842 -290.93964) (xy 395.23338 -290.960738) (xy 395.186109 -290.97443) (xy 395.137254 -290.980362)
			(xy 395.088079 -290.978381) (xy 395.03986 -290.968537) (xy 394.993844 -290.951085) (xy 394.951223 -290.926478)
			(xy 394.913102 -290.895353) (xy 394.880467 -290.858516) (xy 394.854164 -290.81692) (xy 394.834873 -290.771644)
			(xy 394.823096 -290.72386) (xy 394.819136 -290.674806) (xy 394.480288 -290.674806) (xy 394.479793 -290.699413)
			(xy 394.471898 -290.74799) (xy 394.456314 -290.794671) (xy 394.433443 -290.838248) (xy 394.403878 -290.877592)
			(xy 394.368385 -290.911684) (xy 394.327882 -290.93964) (xy 394.28342 -290.960738) (xy 394.236149 -290.97443)
			(xy 394.187294 -290.980362) (xy 394.138119 -290.978381) (xy 394.0899 -290.968537) (xy 394.043884 -290.951085)
			(xy 394.001263 -290.926478) (xy 393.963142 -290.895353) (xy 393.930507 -290.858516) (xy 393.904204 -290.81692)
			(xy 393.884913 -290.771644) (xy 393.873136 -290.72386) (xy 393.869176 -290.674806) (xy 393.530328 -290.674806)
			(xy 393.529833 -290.699413) (xy 393.521938 -290.74799) (xy 393.506354 -290.794671) (xy 393.483483 -290.838248)
			(xy 393.453918 -290.877592) (xy 393.418425 -290.911684) (xy 393.377922 -290.93964) (xy 393.33346 -290.960738)
			(xy 393.286189 -290.97443) (xy 393.237334 -290.980362) (xy 393.188159 -290.978381) (xy 393.13994 -290.968537)
			(xy 393.093924 -290.951085) (xy 393.051303 -290.926478) (xy 393.013182 -290.895353) (xy 392.980547 -290.858516)
			(xy 392.954244 -290.81692) (xy 392.934953 -290.771644) (xy 392.923176 -290.72386) (xy 392.919216 -290.674806)
			(xy 392.580114 -290.674806) (xy 392.579619 -290.699413) (xy 392.571724 -290.74799) (xy 392.55614 -290.794671)
			(xy 392.533269 -290.838248) (xy 392.503704 -290.877592) (xy 392.468211 -290.911684) (xy 392.427708 -290.93964)
			(xy 392.383246 -290.960738) (xy 392.335975 -290.97443) (xy 392.28712 -290.980362) (xy 392.237945 -290.978381)
			(xy 392.189726 -290.968537) (xy 392.14371 -290.951085) (xy 392.101089 -290.926478) (xy 392.062968 -290.895353)
			(xy 392.030333 -290.858516) (xy 392.00403 -290.81692) (xy 391.984739 -290.771644) (xy 391.972962 -290.72386)
			(xy 391.969002 -290.674806) (xy 391.630154 -290.674806) (xy 391.629659 -290.699413) (xy 391.621764 -290.74799)
			(xy 391.60618 -290.794671) (xy 391.583309 -290.838248) (xy 391.553744 -290.877592) (xy 391.518251 -290.911684)
			(xy 391.477748 -290.93964) (xy 391.433286 -290.960738) (xy 391.386015 -290.97443) (xy 391.33716 -290.980362)
			(xy 391.287985 -290.978381) (xy 391.239766 -290.968537) (xy 391.19375 -290.951085) (xy 391.151129 -290.926478)
			(xy 391.113008 -290.895353) (xy 391.080373 -290.858516) (xy 391.05407 -290.81692) (xy 391.034779 -290.771644)
			(xy 391.023002 -290.72386) (xy 391.019042 -290.674806) (xy 390.680194 -290.674806) (xy 390.679699 -290.699413)
			(xy 390.671804 -290.74799) (xy 390.65622 -290.794671) (xy 390.633349 -290.838248) (xy 390.603784 -290.877592)
			(xy 390.568291 -290.911684) (xy 390.527788 -290.93964) (xy 390.483326 -290.960738) (xy 390.436055 -290.97443)
			(xy 390.3872 -290.980362) (xy 390.338025 -290.978381) (xy 390.289806 -290.968537) (xy 390.24379 -290.951085)
			(xy 390.201169 -290.926478) (xy 390.163048 -290.895353) (xy 390.130413 -290.858516) (xy 390.10411 -290.81692)
			(xy 390.084819 -290.771644) (xy 390.073042 -290.72386) (xy 390.069082 -290.674806) (xy 389.730234 -290.674806)
			(xy 389.729739 -290.699413) (xy 389.721844 -290.74799) (xy 389.70626 -290.794671) (xy 389.683389 -290.838248)
			(xy 389.653824 -290.877592) (xy 389.618331 -290.911684) (xy 389.577828 -290.93964) (xy 389.533366 -290.960738)
			(xy 389.486095 -290.97443) (xy 389.43724 -290.980362) (xy 389.388065 -290.978381) (xy 389.339846 -290.968537)
			(xy 389.29383 -290.951085) (xy 389.251209 -290.926478) (xy 389.213088 -290.895353) (xy 389.180453 -290.858516)
			(xy 389.15415 -290.81692) (xy 389.134859 -290.771644) (xy 389.123082 -290.72386) (xy 389.119122 -290.674806)
			(xy 386.880354 -290.674806) (xy 386.879859 -290.699413) (xy 386.871964 -290.74799) (xy 386.85638 -290.794671)
			(xy 386.833509 -290.838248) (xy 386.803944 -290.877592) (xy 386.768451 -290.911684) (xy 386.727948 -290.93964)
			(xy 386.683486 -290.960738) (xy 386.636215 -290.97443) (xy 386.58736 -290.980362) (xy 386.538185 -290.978381)
			(xy 386.489966 -290.968537) (xy 386.44395 -290.951085) (xy 386.401329 -290.926478) (xy 386.363208 -290.895353)
			(xy 386.330573 -290.858516) (xy 386.30427 -290.81692) (xy 386.284979 -290.771644) (xy 386.273202 -290.72386)
			(xy 386.269242 -290.674806) (xy 385.93014 -290.674806) (xy 385.929645 -290.699413) (xy 385.92175 -290.74799)
			(xy 385.906166 -290.794671) (xy 385.883295 -290.838248) (xy 385.85373 -290.877592) (xy 385.818237 -290.911684)
			(xy 385.777734 -290.93964) (xy 385.733272 -290.960738) (xy 385.686001 -290.97443) (xy 385.637146 -290.980362)
			(xy 385.587971 -290.978381) (xy 385.539752 -290.968537) (xy 385.493736 -290.951085) (xy 385.451115 -290.926478)
			(xy 385.412994 -290.895353) (xy 385.380359 -290.858516) (xy 385.354056 -290.81692) (xy 385.334765 -290.771644)
			(xy 385.322988 -290.72386) (xy 385.319028 -290.674806) (xy 384.98018 -290.674806) (xy 384.979685 -290.699413)
			(xy 384.97179 -290.74799) (xy 384.956206 -290.794671) (xy 384.933335 -290.838248) (xy 384.90377 -290.877592)
			(xy 384.868277 -290.911684) (xy 384.827774 -290.93964) (xy 384.783312 -290.960738) (xy 384.736041 -290.97443)
			(xy 384.687186 -290.980362) (xy 384.638011 -290.978381) (xy 384.589792 -290.968537) (xy 384.543776 -290.951085)
			(xy 384.501155 -290.926478) (xy 384.463034 -290.895353) (xy 384.430399 -290.858516) (xy 384.404096 -290.81692)
			(xy 384.384805 -290.771644) (xy 384.373028 -290.72386) (xy 384.369068 -290.674806) (xy 382.328523 -290.674806)
			(xy 382.316972 -290.676077) (xy 382.261238 -290.67404) (xy 382.206395 -290.66391) (xy 382.153611 -290.645903)
			(xy 382.104011 -290.620402) (xy 382.058653 -290.587951) (xy 382.018504 -290.549242) (xy 381.984418 -290.505099)
			(xy 381.957122 -290.456464) (xy 381.937199 -290.404373) (xy 381.925073 -290.349936) (xy 381.921002 -290.294314)
			(xy 381.798068 -290.294314) (xy 381.797559 -290.3222) (xy 381.789439 -290.377376) (xy 381.773371 -290.430783)
			(xy 381.749699 -290.48128) (xy 381.718926 -290.527793) (xy 381.681709 -290.56933) (xy 381.638841 -290.605005)
			(xy 381.591235 -290.634059) (xy 381.539906 -290.655871) (xy 381.485949 -290.669977) (xy 381.430512 -290.676077)
			(xy 381.374778 -290.67404) (xy 381.319935 -290.66391) (xy 381.267151 -290.645903) (xy 381.217551 -290.620402)
			(xy 381.172193 -290.587951) (xy 381.132044 -290.549242) (xy 381.097958 -290.505099) (xy 381.070662 -290.456464)
			(xy 381.050739 -290.404373) (xy 381.038613 -290.349936) (xy 381.034542 -290.294314) (xy 380.401068 -290.294314)
			(xy 380.400582 -290.321565) (xy 380.392826 -290.375513) (xy 380.377471 -290.427808) (xy 380.354829 -290.477385)
			(xy 380.325363 -290.523235) (xy 380.289672 -290.564426) (xy 380.248481 -290.600117) (xy 380.202631 -290.629583)
			(xy 380.153054 -290.652225) (xy 380.100759 -290.66758) (xy 380.046811 -290.675336) (xy 379.992309 -290.675336)
			(xy 379.938361 -290.66758) (xy 379.886066 -290.652225) (xy 379.836489 -290.629583) (xy 379.790639 -290.600117)
			(xy 379.749448 -290.564426) (xy 379.713757 -290.523235) (xy 379.684291 -290.477385) (xy 379.661649 -290.427808)
			(xy 379.646294 -290.375513) (xy 379.638538 -290.321565) (xy 379.638052 -290.294314) (xy 368.55019 -290.294314)
			(xy 368.55019 -291.430456) (xy 374.111518 -291.430456) (xy 374.115589 -291.374834) (xy 374.127715 -291.320397)
			(xy 374.147638 -291.268306) (xy 374.174934 -291.219671) (xy 374.20902 -291.175528) (xy 374.249169 -291.136819)
			(xy 374.294527 -291.104368) (xy 374.344127 -291.078867) (xy 374.396911 -291.06086) (xy 374.451754 -291.05073)
			(xy 374.507488 -291.048693) (xy 374.562925 -291.054793) (xy 374.616882 -291.068899) (xy 374.668211 -291.090711)
			(xy 374.715817 -291.119765) (xy 374.758685 -291.15544) (xy 374.795902 -291.196977) (xy 374.826675 -291.24349)
			(xy 374.850347 -291.293987) (xy 374.866415 -291.347394) (xy 374.874535 -291.40257) (xy 374.875044 -291.430456)
			(xy 375.596656 -291.430456) (xy 375.600727 -291.374834) (xy 375.612853 -291.320397) (xy 375.632776 -291.268306)
			(xy 375.660072 -291.219671) (xy 375.694158 -291.175528) (xy 375.734307 -291.136819) (xy 375.779665 -291.104368)
			(xy 375.829265 -291.078867) (xy 375.882049 -291.06086) (xy 375.936892 -291.05073) (xy 375.992626 -291.048693)
			(xy 376.048063 -291.054793) (xy 376.10202 -291.068899) (xy 376.153349 -291.090711) (xy 376.200955 -291.119765)
			(xy 376.243823 -291.15544) (xy 376.28104 -291.196977) (xy 376.311813 -291.24349) (xy 376.335485 -291.293987)
			(xy 376.351553 -291.347394) (xy 376.359673 -291.40257) (xy 376.360182 -291.430456) (xy 376.359673 -291.458342)
			(xy 376.351553 -291.513518) (xy 376.335485 -291.566925) (xy 376.311813 -291.617422) (xy 376.306954 -291.624766)
			(xy 384.369068 -291.624766) (xy 384.373028 -291.575712) (xy 384.384805 -291.527928) (xy 384.404096 -291.482652)
			(xy 384.430399 -291.441056) (xy 384.463034 -291.404219) (xy 384.501155 -291.373094) (xy 384.543776 -291.348487)
			(xy 384.589792 -291.331035) (xy 384.638011 -291.321191) (xy 384.687186 -291.31921) (xy 384.736041 -291.325142)
			(xy 384.783312 -291.338834) (xy 384.827774 -291.359932) (xy 384.868277 -291.387888) (xy 384.90377 -291.42198)
			(xy 384.933335 -291.461324) (xy 384.956206 -291.504901) (xy 384.97179 -291.551582) (xy 384.979685 -291.600159)
			(xy 384.98018 -291.624766) (xy 385.319028 -291.624766) (xy 385.322988 -291.575712) (xy 385.334765 -291.527928)
			(xy 385.354056 -291.482652) (xy 385.380359 -291.441056) (xy 385.412994 -291.404219) (xy 385.451115 -291.373094)
			(xy 385.493736 -291.348487) (xy 385.539752 -291.331035) (xy 385.587971 -291.321191) (xy 385.637146 -291.31921)
			(xy 385.686001 -291.325142) (xy 385.733272 -291.338834) (xy 385.777734 -291.359932) (xy 385.818237 -291.387888)
			(xy 385.85373 -291.42198) (xy 385.883295 -291.461324) (xy 385.906166 -291.504901) (xy 385.92175 -291.551582)
			(xy 385.929645 -291.600159) (xy 385.93014 -291.624766) (xy 386.269242 -291.624766) (xy 386.273202 -291.575712)
			(xy 386.284979 -291.527928) (xy 386.30427 -291.482652) (xy 386.330573 -291.441056) (xy 386.363208 -291.404219)
			(xy 386.401329 -291.373094) (xy 386.44395 -291.348487) (xy 386.489966 -291.331035) (xy 386.538185 -291.321191)
			(xy 386.58736 -291.31921) (xy 386.636215 -291.325142) (xy 386.683486 -291.338834) (xy 386.727948 -291.359932)
			(xy 386.768451 -291.387888) (xy 386.803944 -291.42198) (xy 386.833509 -291.461324) (xy 386.85638 -291.504901)
			(xy 386.871964 -291.551582) (xy 386.879859 -291.600159) (xy 386.880354 -291.624766) (xy 389.119122 -291.624766)
			(xy 389.123082 -291.575712) (xy 389.134859 -291.527928) (xy 389.15415 -291.482652) (xy 389.180453 -291.441056)
			(xy 389.213088 -291.404219) (xy 389.251209 -291.373094) (xy 389.29383 -291.348487) (xy 389.339846 -291.331035)
			(xy 389.388065 -291.321191) (xy 389.43724 -291.31921) (xy 389.486095 -291.325142) (xy 389.533366 -291.338834)
			(xy 389.577828 -291.359932) (xy 389.618331 -291.387888) (xy 389.653824 -291.42198) (xy 389.683389 -291.461324)
			(xy 389.70626 -291.504901) (xy 389.721844 -291.551582) (xy 389.729739 -291.600159) (xy 389.730234 -291.624766)
			(xy 390.069082 -291.624766) (xy 390.073042 -291.575712) (xy 390.084819 -291.527928) (xy 390.10411 -291.482652)
			(xy 390.130413 -291.441056) (xy 390.163048 -291.404219) (xy 390.201169 -291.373094) (xy 390.24379 -291.348487)
			(xy 390.289806 -291.331035) (xy 390.338025 -291.321191) (xy 390.3872 -291.31921) (xy 390.436055 -291.325142)
			(xy 390.483326 -291.338834) (xy 390.527788 -291.359932) (xy 390.568291 -291.387888) (xy 390.603784 -291.42198)
			(xy 390.633349 -291.461324) (xy 390.65622 -291.504901) (xy 390.671804 -291.551582) (xy 390.679699 -291.600159)
			(xy 390.680194 -291.624766) (xy 391.019042 -291.624766) (xy 391.023002 -291.575712) (xy 391.034779 -291.527928)
			(xy 391.05407 -291.482652) (xy 391.080373 -291.441056) (xy 391.113008 -291.404219) (xy 391.151129 -291.373094)
			(xy 391.19375 -291.348487) (xy 391.239766 -291.331035) (xy 391.287985 -291.321191) (xy 391.33716 -291.31921)
			(xy 391.386015 -291.325142) (xy 391.433286 -291.338834) (xy 391.477748 -291.359932) (xy 391.518251 -291.387888)
			(xy 391.553744 -291.42198) (xy 391.583309 -291.461324) (xy 391.60618 -291.504901) (xy 391.621764 -291.551582)
			(xy 391.629659 -291.600159) (xy 391.630154 -291.624766) (xy 391.969002 -291.624766) (xy 391.972962 -291.575712)
			(xy 391.984739 -291.527928) (xy 392.00403 -291.482652) (xy 392.030333 -291.441056) (xy 392.062968 -291.404219)
			(xy 392.101089 -291.373094) (xy 392.14371 -291.348487) (xy 392.189726 -291.331035) (xy 392.237945 -291.321191)
			(xy 392.28712 -291.31921) (xy 392.335975 -291.325142) (xy 392.383246 -291.338834) (xy 392.427708 -291.359932)
			(xy 392.468211 -291.387888) (xy 392.503704 -291.42198) (xy 392.533269 -291.461324) (xy 392.55614 -291.504901)
			(xy 392.571724 -291.551582) (xy 392.579619 -291.600159) (xy 392.580114 -291.624766) (xy 392.919216 -291.624766)
			(xy 392.923176 -291.575712) (xy 392.934953 -291.527928) (xy 392.954244 -291.482652) (xy 392.980547 -291.441056)
			(xy 393.013182 -291.404219) (xy 393.051303 -291.373094) (xy 393.093924 -291.348487) (xy 393.13994 -291.331035)
			(xy 393.188159 -291.321191) (xy 393.237334 -291.31921) (xy 393.286189 -291.325142) (xy 393.33346 -291.338834)
			(xy 393.377922 -291.359932) (xy 393.418425 -291.387888) (xy 393.453918 -291.42198) (xy 393.483483 -291.461324)
			(xy 393.506354 -291.504901) (xy 393.521938 -291.551582) (xy 393.529833 -291.600159) (xy 393.530328 -291.624766)
			(xy 393.869176 -291.624766) (xy 393.873136 -291.575712) (xy 393.884913 -291.527928) (xy 393.904204 -291.482652)
			(xy 393.930507 -291.441056) (xy 393.963142 -291.404219) (xy 394.001263 -291.373094) (xy 394.043884 -291.348487)
			(xy 394.0899 -291.331035) (xy 394.138119 -291.321191) (xy 394.187294 -291.31921) (xy 394.236149 -291.325142)
			(xy 394.28342 -291.338834) (xy 394.327882 -291.359932) (xy 394.368385 -291.387888) (xy 394.403878 -291.42198)
			(xy 394.433443 -291.461324) (xy 394.456314 -291.504901) (xy 394.471898 -291.551582) (xy 394.479793 -291.600159)
			(xy 394.480288 -291.624766) (xy 395.769096 -291.624766) (xy 395.773056 -291.575712) (xy 395.784833 -291.527928)
			(xy 395.804124 -291.482652) (xy 395.830427 -291.441056) (xy 395.863062 -291.404219) (xy 395.901183 -291.373094)
			(xy 395.943804 -291.348487) (xy 395.98982 -291.331035) (xy 396.038039 -291.321191) (xy 396.087214 -291.31921)
			(xy 396.136069 -291.325142) (xy 396.18334 -291.338834) (xy 396.227802 -291.359932) (xy 396.268305 -291.387888)
			(xy 396.303798 -291.42198) (xy 396.333363 -291.461324) (xy 396.356234 -291.504901) (xy 396.371818 -291.551582)
			(xy 396.379713 -291.600159) (xy 396.380208 -291.624766) (xy 396.719056 -291.624766) (xy 396.723016 -291.575712)
			(xy 396.734793 -291.527928) (xy 396.754084 -291.482652) (xy 396.780387 -291.441056) (xy 396.813022 -291.404219)
			(xy 396.851143 -291.373094) (xy 396.893764 -291.348487) (xy 396.93978 -291.331035) (xy 396.987999 -291.321191)
			(xy 397.037174 -291.31921) (xy 397.086029 -291.325142) (xy 397.1333 -291.338834) (xy 397.177762 -291.359932)
			(xy 397.218265 -291.387888) (xy 397.253758 -291.42198) (xy 397.283323 -291.461324) (xy 397.306194 -291.504901)
			(xy 397.321778 -291.551582) (xy 397.329673 -291.600159) (xy 397.330168 -291.624766) (xy 398.61923 -291.624766)
			(xy 398.62319 -291.575712) (xy 398.634967 -291.527928) (xy 398.654258 -291.482652) (xy 398.680561 -291.441056)
			(xy 398.713196 -291.404219) (xy 398.751317 -291.373094) (xy 398.793938 -291.348487) (xy 398.839954 -291.331035)
			(xy 398.888173 -291.321191) (xy 398.937348 -291.31921) (xy 398.986203 -291.325142) (xy 399.033474 -291.338834)
			(xy 399.077936 -291.359932) (xy 399.118439 -291.387888) (xy 399.153932 -291.42198) (xy 399.183497 -291.461324)
			(xy 399.206368 -291.504901) (xy 399.221952 -291.551582) (xy 399.229847 -291.600159) (xy 399.230342 -291.624766)
			(xy 399.56919 -291.624766) (xy 399.57315 -291.575712) (xy 399.584927 -291.527928) (xy 399.604218 -291.482652)
			(xy 399.630521 -291.441056) (xy 399.663156 -291.404219) (xy 399.701277 -291.373094) (xy 399.743898 -291.348487)
			(xy 399.789914 -291.331035) (xy 399.838133 -291.321191) (xy 399.887308 -291.31921) (xy 399.936163 -291.325142)
			(xy 399.983434 -291.338834) (xy 400.027896 -291.359932) (xy 400.068399 -291.387888) (xy 400.103892 -291.42198)
			(xy 400.133457 -291.461324) (xy 400.156328 -291.504901) (xy 400.171912 -291.551582) (xy 400.179807 -291.600159)
			(xy 400.180302 -291.624766) (xy 400.51915 -291.624766) (xy 400.52311 -291.575712) (xy 400.534887 -291.527928)
			(xy 400.554178 -291.482652) (xy 400.580481 -291.441056) (xy 400.613116 -291.404219) (xy 400.651237 -291.373094)
			(xy 400.693858 -291.348487) (xy 400.739874 -291.331035) (xy 400.788093 -291.321191) (xy 400.837268 -291.31921)
			(xy 400.886123 -291.325142) (xy 400.933394 -291.338834) (xy 400.977856 -291.359932) (xy 401.018359 -291.387888)
			(xy 401.053852 -291.42198) (xy 401.083417 -291.461324) (xy 401.106288 -291.504901) (xy 401.121872 -291.551582)
			(xy 401.129767 -291.600159) (xy 401.130262 -291.624766) (xy 401.46911 -291.624766) (xy 401.47307 -291.575712)
			(xy 401.484847 -291.527928) (xy 401.504138 -291.482652) (xy 401.530441 -291.441056) (xy 401.563076 -291.404219)
			(xy 401.601197 -291.373094) (xy 401.643818 -291.348487) (xy 401.689834 -291.331035) (xy 401.738053 -291.321191)
			(xy 401.787228 -291.31921) (xy 401.836083 -291.325142) (xy 401.883354 -291.338834) (xy 401.927816 -291.359932)
			(xy 401.968319 -291.387888) (xy 402.003812 -291.42198) (xy 402.033377 -291.461324) (xy 402.056248 -291.504901)
			(xy 402.071832 -291.551582) (xy 402.079727 -291.600159) (xy 402.080222 -291.624766) (xy 402.41907 -291.624766)
			(xy 402.42303 -291.575712) (xy 402.434807 -291.527928) (xy 402.454098 -291.482652) (xy 402.480401 -291.441056)
			(xy 402.513036 -291.404219) (xy 402.551157 -291.373094) (xy 402.593778 -291.348487) (xy 402.639794 -291.331035)
			(xy 402.688013 -291.321191) (xy 402.737188 -291.31921) (xy 402.786043 -291.325142) (xy 402.833314 -291.338834)
			(xy 402.877776 -291.359932) (xy 402.918279 -291.387888) (xy 402.953772 -291.42198) (xy 402.983337 -291.461324)
			(xy 403.006208 -291.504901) (xy 403.021792 -291.551582) (xy 403.029687 -291.600159) (xy 403.030182 -291.624766)
			(xy 403.36903 -291.624766) (xy 403.37299 -291.575712) (xy 403.384767 -291.527928) (xy 403.404058 -291.482652)
			(xy 403.430361 -291.441056) (xy 403.462996 -291.404219) (xy 403.501117 -291.373094) (xy 403.543738 -291.348487)
			(xy 403.589754 -291.331035) (xy 403.637973 -291.321191) (xy 403.687148 -291.31921) (xy 403.736003 -291.325142)
			(xy 403.783274 -291.338834) (xy 403.827736 -291.359932) (xy 403.868239 -291.387888) (xy 403.903732 -291.42198)
			(xy 403.933297 -291.461324) (xy 403.956168 -291.504901) (xy 403.971752 -291.551582) (xy 403.979647 -291.600159)
			(xy 403.980142 -291.624766) (xy 404.31899 -291.624766) (xy 404.32295 -291.575712) (xy 404.334727 -291.527928)
			(xy 404.354018 -291.482652) (xy 404.380321 -291.441056) (xy 404.412956 -291.404219) (xy 404.451077 -291.373094)
			(xy 404.493698 -291.348487) (xy 404.539714 -291.331035) (xy 404.587933 -291.321191) (xy 404.637108 -291.31921)
			(xy 404.685963 -291.325142) (xy 404.733234 -291.338834) (xy 404.777696 -291.359932) (xy 404.818199 -291.387888)
			(xy 404.853692 -291.42198) (xy 404.883257 -291.461324) (xy 404.906128 -291.504901) (xy 404.921712 -291.551582)
			(xy 404.929607 -291.600159) (xy 404.930102 -291.624766) (xy 405.269204 -291.624766) (xy 405.273164 -291.575712)
			(xy 405.284941 -291.527928) (xy 405.304232 -291.482652) (xy 405.330535 -291.441056) (xy 405.36317 -291.404219)
			(xy 405.401291 -291.373094) (xy 405.443912 -291.348487) (xy 405.489928 -291.331035) (xy 405.538147 -291.321191)
			(xy 405.587322 -291.31921) (xy 405.636177 -291.325142) (xy 405.683448 -291.338834) (xy 405.72791 -291.359932)
			(xy 405.768413 -291.387888) (xy 405.803906 -291.42198) (xy 405.833471 -291.461324) (xy 405.856342 -291.504901)
			(xy 405.871926 -291.551582) (xy 405.879821 -291.600159) (xy 405.880316 -291.624766) (xy 406.219164 -291.624766)
			(xy 406.223124 -291.575712) (xy 406.234901 -291.527928) (xy 406.254192 -291.482652) (xy 406.280495 -291.441056)
			(xy 406.31313 -291.404219) (xy 406.351251 -291.373094) (xy 406.393872 -291.348487) (xy 406.439888 -291.331035)
			(xy 406.488107 -291.321191) (xy 406.537282 -291.31921) (xy 406.586137 -291.325142) (xy 406.633408 -291.338834)
			(xy 406.67787 -291.359932) (xy 406.718373 -291.387888) (xy 406.753866 -291.42198) (xy 406.783431 -291.461324)
			(xy 406.806302 -291.504901) (xy 406.821886 -291.551582) (xy 406.829781 -291.600159) (xy 406.830276 -291.624766)
			(xy 408.119084 -291.624766) (xy 408.123044 -291.575712) (xy 408.134821 -291.527928) (xy 408.154112 -291.482652)
			(xy 408.180415 -291.441056) (xy 408.21305 -291.404219) (xy 408.251171 -291.373094) (xy 408.293792 -291.348487)
			(xy 408.339808 -291.331035) (xy 408.388027 -291.321191) (xy 408.437202 -291.31921) (xy 408.486057 -291.325142)
			(xy 408.533328 -291.338834) (xy 408.57779 -291.359932) (xy 408.618293 -291.387888) (xy 408.653786 -291.42198)
			(xy 408.683351 -291.461324) (xy 408.706222 -291.504901) (xy 408.721806 -291.551582) (xy 408.729701 -291.600159)
			(xy 408.730196 -291.624766) (xy 409.069044 -291.624766) (xy 409.073004 -291.575712) (xy 409.084781 -291.527928)
			(xy 409.104072 -291.482652) (xy 409.130375 -291.441056) (xy 409.16301 -291.404219) (xy 409.201131 -291.373094)
			(xy 409.243752 -291.348487) (xy 409.289768 -291.331035) (xy 409.337987 -291.321191) (xy 409.387162 -291.31921)
			(xy 409.436017 -291.325142) (xy 409.483288 -291.338834) (xy 409.52775 -291.359932) (xy 409.568253 -291.387888)
			(xy 409.603746 -291.42198) (xy 409.633311 -291.461324) (xy 409.656182 -291.504901) (xy 409.671766 -291.551582)
			(xy 409.679661 -291.600159) (xy 409.680156 -291.624766) (xy 410.019004 -291.624766) (xy 410.022964 -291.575712)
			(xy 410.034741 -291.527928) (xy 410.054032 -291.482652) (xy 410.080335 -291.441056) (xy 410.11297 -291.404219)
			(xy 410.151091 -291.373094) (xy 410.193712 -291.348487) (xy 410.239728 -291.331035) (xy 410.287947 -291.321191)
			(xy 410.337122 -291.31921) (xy 410.385977 -291.325142) (xy 410.433248 -291.338834) (xy 410.47771 -291.359932)
			(xy 410.518213 -291.387888) (xy 410.553706 -291.42198) (xy 410.583271 -291.461324) (xy 410.606142 -291.504901)
			(xy 410.621726 -291.551582) (xy 410.629621 -291.600159) (xy 410.630116 -291.624766) (xy 410.969218 -291.624766)
			(xy 410.973178 -291.575712) (xy 410.984955 -291.527928) (xy 411.004246 -291.482652) (xy 411.030549 -291.441056)
			(xy 411.063184 -291.404219) (xy 411.101305 -291.373094) (xy 411.143926 -291.348487) (xy 411.189942 -291.331035)
			(xy 411.238161 -291.321191) (xy 411.287336 -291.31921) (xy 411.336191 -291.325142) (xy 411.383462 -291.338834)
			(xy 411.427924 -291.359932) (xy 411.468427 -291.387888) (xy 411.50392 -291.42198) (xy 411.533485 -291.461324)
			(xy 411.556356 -291.504901) (xy 411.57194 -291.551582) (xy 411.579835 -291.600159) (xy 411.58033 -291.624766)
			(xy 411.919178 -291.624766) (xy 411.923138 -291.575712) (xy 411.934915 -291.527928) (xy 411.954206 -291.482652)
			(xy 411.980509 -291.441056) (xy 412.013144 -291.404219) (xy 412.051265 -291.373094) (xy 412.093886 -291.348487)
			(xy 412.139902 -291.331035) (xy 412.188121 -291.321191) (xy 412.237296 -291.31921) (xy 412.286151 -291.325142)
			(xy 412.333422 -291.338834) (xy 412.377884 -291.359932) (xy 412.418387 -291.387888) (xy 412.45388 -291.42198)
			(xy 412.483445 -291.461324) (xy 412.506316 -291.504901) (xy 412.5219 -291.551582) (xy 412.529795 -291.600159)
			(xy 412.53029 -291.624766) (xy 412.869138 -291.624766) (xy 412.873098 -291.575712) (xy 412.884875 -291.527928)
			(xy 412.904166 -291.482652) (xy 412.930469 -291.441056) (xy 412.963104 -291.404219) (xy 413.001225 -291.373094)
			(xy 413.043846 -291.348487) (xy 413.089862 -291.331035) (xy 413.138081 -291.321191) (xy 413.187256 -291.31921)
			(xy 413.236111 -291.325142) (xy 413.283382 -291.338834) (xy 413.327844 -291.359932) (xy 413.368347 -291.387888)
			(xy 413.40384 -291.42198) (xy 413.433405 -291.461324) (xy 413.456276 -291.504901) (xy 413.47186 -291.551582)
			(xy 413.479755 -291.600159) (xy 413.48025 -291.624766) (xy 413.819098 -291.624766) (xy 413.823058 -291.575712)
			(xy 413.834835 -291.527928) (xy 413.854126 -291.482652) (xy 413.880429 -291.441056) (xy 413.913064 -291.404219)
			(xy 413.951185 -291.373094) (xy 413.993806 -291.348487) (xy 414.039822 -291.331035) (xy 414.088041 -291.321191)
			(xy 414.137216 -291.31921) (xy 414.186071 -291.325142) (xy 414.233342 -291.338834) (xy 414.277804 -291.359932)
			(xy 414.318307 -291.387888) (xy 414.3538 -291.42198) (xy 414.383365 -291.461324) (xy 414.406236 -291.504901)
			(xy 414.42182 -291.551582) (xy 414.429715 -291.600159) (xy 414.43021 -291.624766) (xy 414.769058 -291.624766)
			(xy 414.773018 -291.575712) (xy 414.784795 -291.527928) (xy 414.804086 -291.482652) (xy 414.830389 -291.441056)
			(xy 414.863024 -291.404219) (xy 414.901145 -291.373094) (xy 414.943766 -291.348487) (xy 414.989782 -291.331035)
			(xy 415.038001 -291.321191) (xy 415.087176 -291.31921) (xy 415.136031 -291.325142) (xy 415.183302 -291.338834)
			(xy 415.227764 -291.359932) (xy 415.268267 -291.387888) (xy 415.30376 -291.42198) (xy 415.333325 -291.461324)
			(xy 415.356196 -291.504901) (xy 415.37178 -291.551582) (xy 415.379675 -291.600159) (xy 415.38017 -291.624766)
			(xy 415.719018 -291.624766) (xy 415.722978 -291.575712) (xy 415.734755 -291.527928) (xy 415.754046 -291.482652)
			(xy 415.780349 -291.441056) (xy 415.812984 -291.404219) (xy 415.851105 -291.373094) (xy 415.893726 -291.348487)
			(xy 415.939742 -291.331035) (xy 415.987961 -291.321191) (xy 416.037136 -291.31921) (xy 416.085991 -291.325142)
			(xy 416.133262 -291.338834) (xy 416.177724 -291.359932) (xy 416.218227 -291.387888) (xy 416.25372 -291.42198)
			(xy 416.283285 -291.461324) (xy 416.306156 -291.504901) (xy 416.32174 -291.551582) (xy 416.329635 -291.600159)
			(xy 416.33013 -291.624766) (xy 416.329635 -291.649373) (xy 416.32174 -291.69795) (xy 416.306156 -291.744631)
			(xy 416.283285 -291.788208) (xy 416.25372 -291.827552) (xy 416.218227 -291.861644) (xy 416.177724 -291.8896)
			(xy 416.133262 -291.910698) (xy 416.085991 -291.92439) (xy 416.037136 -291.930322) (xy 415.987961 -291.928341)
			(xy 415.939742 -291.918497) (xy 415.893726 -291.901045) (xy 415.851105 -291.876438) (xy 415.812984 -291.845313)
			(xy 415.780349 -291.808476) (xy 415.754046 -291.76688) (xy 415.734755 -291.721604) (xy 415.722978 -291.67382)
			(xy 415.719018 -291.624766) (xy 415.38017 -291.624766) (xy 415.379675 -291.649373) (xy 415.37178 -291.69795)
			(xy 415.356196 -291.744631) (xy 415.333325 -291.788208) (xy 415.30376 -291.827552) (xy 415.268267 -291.861644)
			(xy 415.227764 -291.8896) (xy 415.183302 -291.910698) (xy 415.136031 -291.92439) (xy 415.087176 -291.930322)
			(xy 415.038001 -291.928341) (xy 414.989782 -291.918497) (xy 414.943766 -291.901045) (xy 414.901145 -291.876438)
			(xy 414.863024 -291.845313) (xy 414.830389 -291.808476) (xy 414.804086 -291.76688) (xy 414.784795 -291.721604)
			(xy 414.773018 -291.67382) (xy 414.769058 -291.624766) (xy 414.43021 -291.624766) (xy 414.429715 -291.649373)
			(xy 414.42182 -291.69795) (xy 414.406236 -291.744631) (xy 414.383365 -291.788208) (xy 414.3538 -291.827552)
			(xy 414.318307 -291.861644) (xy 414.277804 -291.8896) (xy 414.233342 -291.910698) (xy 414.186071 -291.92439)
			(xy 414.137216 -291.930322) (xy 414.088041 -291.928341) (xy 414.039822 -291.918497) (xy 413.993806 -291.901045)
			(xy 413.951185 -291.876438) (xy 413.913064 -291.845313) (xy 413.880429 -291.808476) (xy 413.854126 -291.76688)
			(xy 413.834835 -291.721604) (xy 413.823058 -291.67382) (xy 413.819098 -291.624766) (xy 413.48025 -291.624766)
			(xy 413.479755 -291.649373) (xy 413.47186 -291.69795) (xy 413.456276 -291.744631) (xy 413.433405 -291.788208)
			(xy 413.40384 -291.827552) (xy 413.368347 -291.861644) (xy 413.327844 -291.8896) (xy 413.283382 -291.910698)
			(xy 413.236111 -291.92439) (xy 413.187256 -291.930322) (xy 413.138081 -291.928341) (xy 413.089862 -291.918497)
			(xy 413.043846 -291.901045) (xy 413.001225 -291.876438) (xy 412.963104 -291.845313) (xy 412.930469 -291.808476)
			(xy 412.904166 -291.76688) (xy 412.884875 -291.721604) (xy 412.873098 -291.67382) (xy 412.869138 -291.624766)
			(xy 412.53029 -291.624766) (xy 412.529795 -291.649373) (xy 412.5219 -291.69795) (xy 412.506316 -291.744631)
			(xy 412.483445 -291.788208) (xy 412.45388 -291.827552) (xy 412.418387 -291.861644) (xy 412.377884 -291.8896)
			(xy 412.333422 -291.910698) (xy 412.286151 -291.92439) (xy 412.237296 -291.930322) (xy 412.188121 -291.928341)
			(xy 412.139902 -291.918497) (xy 412.093886 -291.901045) (xy 412.051265 -291.876438) (xy 412.013144 -291.845313)
			(xy 411.980509 -291.808476) (xy 411.954206 -291.76688) (xy 411.934915 -291.721604) (xy 411.923138 -291.67382)
			(xy 411.919178 -291.624766) (xy 411.58033 -291.624766) (xy 411.579835 -291.649373) (xy 411.57194 -291.69795)
			(xy 411.556356 -291.744631) (xy 411.533485 -291.788208) (xy 411.50392 -291.827552) (xy 411.468427 -291.861644)
			(xy 411.427924 -291.8896) (xy 411.383462 -291.910698) (xy 411.336191 -291.92439) (xy 411.287336 -291.930322)
			(xy 411.238161 -291.928341) (xy 411.189942 -291.918497) (xy 411.143926 -291.901045) (xy 411.101305 -291.876438)
			(xy 411.063184 -291.845313) (xy 411.030549 -291.808476) (xy 411.004246 -291.76688) (xy 410.984955 -291.721604)
			(xy 410.973178 -291.67382) (xy 410.969218 -291.624766) (xy 410.630116 -291.624766) (xy 410.629621 -291.649373)
			(xy 410.621726 -291.69795) (xy 410.606142 -291.744631) (xy 410.583271 -291.788208) (xy 410.553706 -291.827552)
			(xy 410.518213 -291.861644) (xy 410.47771 -291.8896) (xy 410.433248 -291.910698) (xy 410.385977 -291.92439)
			(xy 410.337122 -291.930322) (xy 410.287947 -291.928341) (xy 410.239728 -291.918497) (xy 410.193712 -291.901045)
			(xy 410.151091 -291.876438) (xy 410.11297 -291.845313) (xy 410.080335 -291.808476) (xy 410.054032 -291.76688)
			(xy 410.034741 -291.721604) (xy 410.022964 -291.67382) (xy 410.019004 -291.624766) (xy 409.680156 -291.624766)
			(xy 409.679661 -291.649373) (xy 409.671766 -291.69795) (xy 409.656182 -291.744631) (xy 409.633311 -291.788208)
			(xy 409.603746 -291.827552) (xy 409.568253 -291.861644) (xy 409.52775 -291.8896) (xy 409.483288 -291.910698)
			(xy 409.436017 -291.92439) (xy 409.387162 -291.930322) (xy 409.337987 -291.928341) (xy 409.289768 -291.918497)
			(xy 409.243752 -291.901045) (xy 409.201131 -291.876438) (xy 409.16301 -291.845313) (xy 409.130375 -291.808476)
			(xy 409.104072 -291.76688) (xy 409.084781 -291.721604) (xy 409.073004 -291.67382) (xy 409.069044 -291.624766)
			(xy 408.730196 -291.624766) (xy 408.729701 -291.649373) (xy 408.721806 -291.69795) (xy 408.706222 -291.744631)
			(xy 408.683351 -291.788208) (xy 408.653786 -291.827552) (xy 408.618293 -291.861644) (xy 408.57779 -291.8896)
			(xy 408.533328 -291.910698) (xy 408.486057 -291.92439) (xy 408.437202 -291.930322) (xy 408.388027 -291.928341)
			(xy 408.339808 -291.918497) (xy 408.293792 -291.901045) (xy 408.251171 -291.876438) (xy 408.21305 -291.845313)
			(xy 408.180415 -291.808476) (xy 408.154112 -291.76688) (xy 408.134821 -291.721604) (xy 408.123044 -291.67382)
			(xy 408.119084 -291.624766) (xy 406.830276 -291.624766) (xy 406.829781 -291.649373) (xy 406.821886 -291.69795)
			(xy 406.806302 -291.744631) (xy 406.783431 -291.788208) (xy 406.753866 -291.827552) (xy 406.718373 -291.861644)
			(xy 406.67787 -291.8896) (xy 406.633408 -291.910698) (xy 406.586137 -291.92439) (xy 406.537282 -291.930322)
			(xy 406.488107 -291.928341) (xy 406.439888 -291.918497) (xy 406.393872 -291.901045) (xy 406.351251 -291.876438)
			(xy 406.31313 -291.845313) (xy 406.280495 -291.808476) (xy 406.254192 -291.76688) (xy 406.234901 -291.721604)
			(xy 406.223124 -291.67382) (xy 406.219164 -291.624766) (xy 405.880316 -291.624766) (xy 405.879821 -291.649373)
			(xy 405.871926 -291.69795) (xy 405.856342 -291.744631) (xy 405.833471 -291.788208) (xy 405.803906 -291.827552)
			(xy 405.768413 -291.861644) (xy 405.72791 -291.8896) (xy 405.683448 -291.910698) (xy 405.636177 -291.92439)
			(xy 405.587322 -291.930322) (xy 405.538147 -291.928341) (xy 405.489928 -291.918497) (xy 405.443912 -291.901045)
			(xy 405.401291 -291.876438) (xy 405.36317 -291.845313) (xy 405.330535 -291.808476) (xy 405.304232 -291.76688)
			(xy 405.284941 -291.721604) (xy 405.273164 -291.67382) (xy 405.269204 -291.624766) (xy 404.930102 -291.624766)
			(xy 404.929607 -291.649373) (xy 404.921712 -291.69795) (xy 404.906128 -291.744631) (xy 404.883257 -291.788208)
			(xy 404.853692 -291.827552) (xy 404.818199 -291.861644) (xy 404.777696 -291.8896) (xy 404.733234 -291.910698)
			(xy 404.685963 -291.92439) (xy 404.637108 -291.930322) (xy 404.587933 -291.928341) (xy 404.539714 -291.918497)
			(xy 404.493698 -291.901045) (xy 404.451077 -291.876438) (xy 404.412956 -291.845313) (xy 404.380321 -291.808476)
			(xy 404.354018 -291.76688) (xy 404.334727 -291.721604) (xy 404.32295 -291.67382) (xy 404.31899 -291.624766)
			(xy 403.980142 -291.624766) (xy 403.979647 -291.649373) (xy 403.971752 -291.69795) (xy 403.956168 -291.744631)
			(xy 403.933297 -291.788208) (xy 403.903732 -291.827552) (xy 403.868239 -291.861644) (xy 403.827736 -291.8896)
			(xy 403.783274 -291.910698) (xy 403.736003 -291.92439) (xy 403.687148 -291.930322) (xy 403.637973 -291.928341)
			(xy 403.589754 -291.918497) (xy 403.543738 -291.901045) (xy 403.501117 -291.876438) (xy 403.462996 -291.845313)
			(xy 403.430361 -291.808476) (xy 403.404058 -291.76688) (xy 403.384767 -291.721604) (xy 403.37299 -291.67382)
			(xy 403.36903 -291.624766) (xy 403.030182 -291.624766) (xy 403.029687 -291.649373) (xy 403.021792 -291.69795)
			(xy 403.006208 -291.744631) (xy 402.983337 -291.788208) (xy 402.953772 -291.827552) (xy 402.918279 -291.861644)
			(xy 402.877776 -291.8896) (xy 402.833314 -291.910698) (xy 402.786043 -291.92439) (xy 402.737188 -291.930322)
			(xy 402.688013 -291.928341) (xy 402.639794 -291.918497) (xy 402.593778 -291.901045) (xy 402.551157 -291.876438)
			(xy 402.513036 -291.845313) (xy 402.480401 -291.808476) (xy 402.454098 -291.76688) (xy 402.434807 -291.721604)
			(xy 402.42303 -291.67382) (xy 402.41907 -291.624766) (xy 402.080222 -291.624766) (xy 402.079727 -291.649373)
			(xy 402.071832 -291.69795) (xy 402.056248 -291.744631) (xy 402.033377 -291.788208) (xy 402.003812 -291.827552)
			(xy 401.968319 -291.861644) (xy 401.927816 -291.8896) (xy 401.883354 -291.910698) (xy 401.836083 -291.92439)
			(xy 401.787228 -291.930322) (xy 401.738053 -291.928341) (xy 401.689834 -291.918497) (xy 401.643818 -291.901045)
			(xy 401.601197 -291.876438) (xy 401.563076 -291.845313) (xy 401.530441 -291.808476) (xy 401.504138 -291.76688)
			(xy 401.484847 -291.721604) (xy 401.47307 -291.67382) (xy 401.46911 -291.624766) (xy 401.130262 -291.624766)
			(xy 401.129767 -291.649373) (xy 401.121872 -291.69795) (xy 401.106288 -291.744631) (xy 401.083417 -291.788208)
			(xy 401.053852 -291.827552) (xy 401.018359 -291.861644) (xy 400.977856 -291.8896) (xy 400.933394 -291.910698)
			(xy 400.886123 -291.92439) (xy 400.837268 -291.930322) (xy 400.788093 -291.928341) (xy 400.739874 -291.918497)
			(xy 400.693858 -291.901045) (xy 400.651237 -291.876438) (xy 400.613116 -291.845313) (xy 400.580481 -291.808476)
			(xy 400.554178 -291.76688) (xy 400.534887 -291.721604) (xy 400.52311 -291.67382) (xy 400.51915 -291.624766)
			(xy 400.180302 -291.624766) (xy 400.179807 -291.649373) (xy 400.171912 -291.69795) (xy 400.156328 -291.744631)
			(xy 400.133457 -291.788208) (xy 400.103892 -291.827552) (xy 400.068399 -291.861644) (xy 400.027896 -291.8896)
			(xy 399.983434 -291.910698) (xy 399.936163 -291.92439) (xy 399.887308 -291.930322) (xy 399.838133 -291.928341)
			(xy 399.789914 -291.918497) (xy 399.743898 -291.901045) (xy 399.701277 -291.876438) (xy 399.663156 -291.845313)
			(xy 399.630521 -291.808476) (xy 399.604218 -291.76688) (xy 399.584927 -291.721604) (xy 399.57315 -291.67382)
			(xy 399.56919 -291.624766) (xy 399.230342 -291.624766) (xy 399.229847 -291.649373) (xy 399.221952 -291.69795)
			(xy 399.206368 -291.744631) (xy 399.183497 -291.788208) (xy 399.153932 -291.827552) (xy 399.118439 -291.861644)
			(xy 399.077936 -291.8896) (xy 399.033474 -291.910698) (xy 398.986203 -291.92439) (xy 398.937348 -291.930322)
			(xy 398.888173 -291.928341) (xy 398.839954 -291.918497) (xy 398.793938 -291.901045) (xy 398.751317 -291.876438)
			(xy 398.713196 -291.845313) (xy 398.680561 -291.808476) (xy 398.654258 -291.76688) (xy 398.634967 -291.721604)
			(xy 398.62319 -291.67382) (xy 398.61923 -291.624766) (xy 397.330168 -291.624766) (xy 397.329673 -291.649373)
			(xy 397.321778 -291.69795) (xy 397.306194 -291.744631) (xy 397.283323 -291.788208) (xy 397.253758 -291.827552)
			(xy 397.218265 -291.861644) (xy 397.177762 -291.8896) (xy 397.1333 -291.910698) (xy 397.086029 -291.92439)
			(xy 397.037174 -291.930322) (xy 396.987999 -291.928341) (xy 396.93978 -291.918497) (xy 396.893764 -291.901045)
			(xy 396.851143 -291.876438) (xy 396.813022 -291.845313) (xy 396.780387 -291.808476) (xy 396.754084 -291.76688)
			(xy 396.734793 -291.721604) (xy 396.723016 -291.67382) (xy 396.719056 -291.624766) (xy 396.380208 -291.624766)
			(xy 396.379713 -291.649373) (xy 396.371818 -291.69795) (xy 396.356234 -291.744631) (xy 396.333363 -291.788208)
			(xy 396.303798 -291.827552) (xy 396.268305 -291.861644) (xy 396.227802 -291.8896) (xy 396.18334 -291.910698)
			(xy 396.136069 -291.92439) (xy 396.087214 -291.930322) (xy 396.038039 -291.928341) (xy 395.98982 -291.918497)
			(xy 395.943804 -291.901045) (xy 395.901183 -291.876438) (xy 395.863062 -291.845313) (xy 395.830427 -291.808476)
			(xy 395.804124 -291.76688) (xy 395.784833 -291.721604) (xy 395.773056 -291.67382) (xy 395.769096 -291.624766)
			(xy 394.480288 -291.624766) (xy 394.479793 -291.649373) (xy 394.471898 -291.69795) (xy 394.456314 -291.744631)
			(xy 394.433443 -291.788208) (xy 394.403878 -291.827552) (xy 394.368385 -291.861644) (xy 394.327882 -291.8896)
			(xy 394.28342 -291.910698) (xy 394.236149 -291.92439) (xy 394.187294 -291.930322) (xy 394.138119 -291.928341)
			(xy 394.0899 -291.918497) (xy 394.043884 -291.901045) (xy 394.001263 -291.876438) (xy 393.963142 -291.845313)
			(xy 393.930507 -291.808476) (xy 393.904204 -291.76688) (xy 393.884913 -291.721604) (xy 393.873136 -291.67382)
			(xy 393.869176 -291.624766) (xy 393.530328 -291.624766) (xy 393.529833 -291.649373) (xy 393.521938 -291.69795)
			(xy 393.506354 -291.744631) (xy 393.483483 -291.788208) (xy 393.453918 -291.827552) (xy 393.418425 -291.861644)
			(xy 393.377922 -291.8896) (xy 393.33346 -291.910698) (xy 393.286189 -291.92439) (xy 393.237334 -291.930322)
			(xy 393.188159 -291.928341) (xy 393.13994 -291.918497) (xy 393.093924 -291.901045) (xy 393.051303 -291.876438)
			(xy 393.013182 -291.845313) (xy 392.980547 -291.808476) (xy 392.954244 -291.76688) (xy 392.934953 -291.721604)
			(xy 392.923176 -291.67382) (xy 392.919216 -291.624766) (xy 392.580114 -291.624766) (xy 392.579619 -291.649373)
			(xy 392.571724 -291.69795) (xy 392.55614 -291.744631) (xy 392.533269 -291.788208) (xy 392.503704 -291.827552)
			(xy 392.468211 -291.861644) (xy 392.427708 -291.8896) (xy 392.383246 -291.910698) (xy 392.335975 -291.92439)
			(xy 392.28712 -291.930322) (xy 392.237945 -291.928341) (xy 392.189726 -291.918497) (xy 392.14371 -291.901045)
			(xy 392.101089 -291.876438) (xy 392.062968 -291.845313) (xy 392.030333 -291.808476) (xy 392.00403 -291.76688)
			(xy 391.984739 -291.721604) (xy 391.972962 -291.67382) (xy 391.969002 -291.624766) (xy 391.630154 -291.624766)
			(xy 391.629659 -291.649373) (xy 391.621764 -291.69795) (xy 391.60618 -291.744631) (xy 391.583309 -291.788208)
			(xy 391.553744 -291.827552) (xy 391.518251 -291.861644) (xy 391.477748 -291.8896) (xy 391.433286 -291.910698)
			(xy 391.386015 -291.92439) (xy 391.33716 -291.930322) (xy 391.287985 -291.928341) (xy 391.239766 -291.918497)
			(xy 391.19375 -291.901045) (xy 391.151129 -291.876438) (xy 391.113008 -291.845313) (xy 391.080373 -291.808476)
			(xy 391.05407 -291.76688) (xy 391.034779 -291.721604) (xy 391.023002 -291.67382) (xy 391.019042 -291.624766)
			(xy 390.680194 -291.624766) (xy 390.679699 -291.649373) (xy 390.671804 -291.69795) (xy 390.65622 -291.744631)
			(xy 390.633349 -291.788208) (xy 390.603784 -291.827552) (xy 390.568291 -291.861644) (xy 390.527788 -291.8896)
			(xy 390.483326 -291.910698) (xy 390.436055 -291.92439) (xy 390.3872 -291.930322) (xy 390.338025 -291.928341)
			(xy 390.289806 -291.918497) (xy 390.24379 -291.901045) (xy 390.201169 -291.876438) (xy 390.163048 -291.845313)
			(xy 390.130413 -291.808476) (xy 390.10411 -291.76688) (xy 390.084819 -291.721604) (xy 390.073042 -291.67382)
			(xy 390.069082 -291.624766) (xy 389.730234 -291.624766) (xy 389.729739 -291.649373) (xy 389.721844 -291.69795)
			(xy 389.70626 -291.744631) (xy 389.683389 -291.788208) (xy 389.653824 -291.827552) (xy 389.618331 -291.861644)
			(xy 389.577828 -291.8896) (xy 389.533366 -291.910698) (xy 389.486095 -291.92439) (xy 389.43724 -291.930322)
			(xy 389.388065 -291.928341) (xy 389.339846 -291.918497) (xy 389.29383 -291.901045) (xy 389.251209 -291.876438)
			(xy 389.213088 -291.845313) (xy 389.180453 -291.808476) (xy 389.15415 -291.76688) (xy 389.134859 -291.721604)
			(xy 389.123082 -291.67382) (xy 389.119122 -291.624766) (xy 386.880354 -291.624766) (xy 386.879859 -291.649373)
			(xy 386.871964 -291.69795) (xy 386.85638 -291.744631) (xy 386.833509 -291.788208) (xy 386.803944 -291.827552)
			(xy 386.768451 -291.861644) (xy 386.727948 -291.8896) (xy 386.683486 -291.910698) (xy 386.636215 -291.92439)
			(xy 386.58736 -291.930322) (xy 386.538185 -291.928341) (xy 386.489966 -291.918497) (xy 386.44395 -291.901045)
			(xy 386.401329 -291.876438) (xy 386.363208 -291.845313) (xy 386.330573 -291.808476) (xy 386.30427 -291.76688)
			(xy 386.284979 -291.721604) (xy 386.273202 -291.67382) (xy 386.269242 -291.624766) (xy 385.93014 -291.624766)
			(xy 385.929645 -291.649373) (xy 385.92175 -291.69795) (xy 385.906166 -291.744631) (xy 385.883295 -291.788208)
			(xy 385.85373 -291.827552) (xy 385.818237 -291.861644) (xy 385.777734 -291.8896) (xy 385.733272 -291.910698)
			(xy 385.686001 -291.92439) (xy 385.637146 -291.930322) (xy 385.587971 -291.928341) (xy 385.539752 -291.918497)
			(xy 385.493736 -291.901045) (xy 385.451115 -291.876438) (xy 385.412994 -291.845313) (xy 385.380359 -291.808476)
			(xy 385.354056 -291.76688) (xy 385.334765 -291.721604) (xy 385.322988 -291.67382) (xy 385.319028 -291.624766)
			(xy 384.98018 -291.624766) (xy 384.979685 -291.649373) (xy 384.97179 -291.69795) (xy 384.956206 -291.744631)
			(xy 384.933335 -291.788208) (xy 384.90377 -291.827552) (xy 384.868277 -291.861644) (xy 384.827774 -291.8896)
			(xy 384.783312 -291.910698) (xy 384.736041 -291.92439) (xy 384.687186 -291.930322) (xy 384.638011 -291.928341)
			(xy 384.589792 -291.918497) (xy 384.543776 -291.901045) (xy 384.501155 -291.876438) (xy 384.463034 -291.845313)
			(xy 384.430399 -291.808476) (xy 384.404096 -291.76688) (xy 384.384805 -291.721604) (xy 384.373028 -291.67382)
			(xy 384.369068 -291.624766) (xy 376.306954 -291.624766) (xy 376.28104 -291.663935) (xy 376.243823 -291.705472)
			(xy 376.200955 -291.741147) (xy 376.153349 -291.770201) (xy 376.10202 -291.792013) (xy 376.048063 -291.806119)
			(xy 375.992626 -291.812219) (xy 375.936892 -291.810182) (xy 375.882049 -291.800052) (xy 375.829265 -291.782045)
			(xy 375.779665 -291.756544) (xy 375.734307 -291.724093) (xy 375.694158 -291.685384) (xy 375.660072 -291.641241)
			(xy 375.632776 -291.592606) (xy 375.612853 -291.540515) (xy 375.600727 -291.486078) (xy 375.596656 -291.430456)
			(xy 374.875044 -291.430456) (xy 374.874535 -291.458342) (xy 374.866415 -291.513518) (xy 374.850347 -291.566925)
			(xy 374.826675 -291.617422) (xy 374.795902 -291.663935) (xy 374.758685 -291.705472) (xy 374.715817 -291.741147)
			(xy 374.668211 -291.770201) (xy 374.616882 -291.792013) (xy 374.562925 -291.806119) (xy 374.507488 -291.812219)
			(xy 374.451754 -291.810182) (xy 374.396911 -291.800052) (xy 374.344127 -291.782045) (xy 374.294527 -291.756544)
			(xy 374.249169 -291.724093) (xy 374.20902 -291.685384) (xy 374.174934 -291.641241) (xy 374.147638 -291.592606)
			(xy 374.127715 -291.540515) (xy 374.115589 -291.486078) (xy 374.111518 -291.430456) (xy 368.55019 -291.430456)
			(xy 368.55019 -292.732714) (xy 374.111518 -292.732714) (xy 374.115589 -292.677092) (xy 374.127715 -292.622655)
			(xy 374.147638 -292.570564) (xy 374.174934 -292.521929) (xy 374.20902 -292.477786) (xy 374.249169 -292.439077)
			(xy 374.294527 -292.406626) (xy 374.344127 -292.381125) (xy 374.396911 -292.363118) (xy 374.451754 -292.352988)
			(xy 374.507488 -292.350951) (xy 374.562925 -292.357051) (xy 374.616882 -292.371157) (xy 374.668211 -292.392969)
			(xy 374.715817 -292.422023) (xy 374.758685 -292.457698) (xy 374.795902 -292.499235) (xy 374.826675 -292.545748)
			(xy 374.850347 -292.596245) (xy 374.866415 -292.649652) (xy 374.874535 -292.704828) (xy 374.875044 -292.732714)
			(xy 375.587004 -292.732714) (xy 375.591075 -292.677092) (xy 375.603201 -292.622655) (xy 375.623124 -292.570564)
			(xy 375.65042 -292.521929) (xy 375.684506 -292.477786) (xy 375.724655 -292.439077) (xy 375.770013 -292.406626)
			(xy 375.819613 -292.381125) (xy 375.872397 -292.363118) (xy 375.92724 -292.352988) (xy 375.982974 -292.350951)
			(xy 376.038411 -292.357051) (xy 376.092368 -292.371157) (xy 376.143697 -292.392969) (xy 376.191303 -292.422023)
			(xy 376.234171 -292.457698) (xy 376.271388 -292.499235) (xy 376.302161 -292.545748) (xy 376.325833 -292.596245)
			(xy 376.341901 -292.649652) (xy 376.350021 -292.704828) (xy 376.35053 -292.732714) (xy 376.476004 -292.732714)
			(xy 376.480075 -292.677092) (xy 376.492201 -292.622655) (xy 376.512124 -292.570564) (xy 376.53942 -292.521929)
			(xy 376.573506 -292.477786) (xy 376.613655 -292.439077) (xy 376.659013 -292.406626) (xy 376.708613 -292.381125)
			(xy 376.761397 -292.363118) (xy 376.81624 -292.352988) (xy 376.871974 -292.350951) (xy 376.927411 -292.357051)
			(xy 376.981368 -292.371157) (xy 377.032697 -292.392969) (xy 377.080303 -292.422023) (xy 377.123171 -292.457698)
			(xy 377.160388 -292.499235) (xy 377.191161 -292.545748) (xy 377.214833 -292.596245) (xy 377.230901 -292.649652)
			(xy 377.239021 -292.704828) (xy 377.23953 -292.732714) (xy 377.239021 -292.7606) (xy 377.230901 -292.815776)
			(xy 377.214833 -292.869183) (xy 377.191161 -292.91968) (xy 377.160388 -292.966193) (xy 377.123171 -293.00773)
			(xy 377.080303 -293.043405) (xy 377.032697 -293.072459) (xy 376.981368 -293.094271) (xy 376.927411 -293.108377)
			(xy 376.871974 -293.114477) (xy 376.81624 -293.11244) (xy 376.761397 -293.10231) (xy 376.708613 -293.084303)
			(xy 376.659013 -293.058802) (xy 376.613655 -293.026351) (xy 376.573506 -292.987642) (xy 376.53942 -292.943499)
			(xy 376.512124 -292.894864) (xy 376.492201 -292.842773) (xy 376.480075 -292.788336) (xy 376.476004 -292.732714)
			(xy 376.35053 -292.732714) (xy 376.350021 -292.7606) (xy 376.341901 -292.815776) (xy 376.325833 -292.869183)
			(xy 376.302161 -292.91968) (xy 376.271388 -292.966193) (xy 376.234171 -293.00773) (xy 376.191303 -293.043405)
			(xy 376.143697 -293.072459) (xy 376.092368 -293.094271) (xy 376.038411 -293.108377) (xy 375.982974 -293.114477)
			(xy 375.92724 -293.11244) (xy 375.872397 -293.10231) (xy 375.819613 -293.084303) (xy 375.770013 -293.058802)
			(xy 375.724655 -293.026351) (xy 375.684506 -292.987642) (xy 375.65042 -292.943499) (xy 375.623124 -292.894864)
			(xy 375.603201 -292.842773) (xy 375.591075 -292.788336) (xy 375.587004 -292.732714) (xy 374.875044 -292.732714)
			(xy 374.874535 -292.7606) (xy 374.866415 -292.815776) (xy 374.850347 -292.869183) (xy 374.826675 -292.91968)
			(xy 374.795902 -292.966193) (xy 374.758685 -293.00773) (xy 374.715817 -293.043405) (xy 374.668211 -293.072459)
			(xy 374.616882 -293.094271) (xy 374.562925 -293.108377) (xy 374.507488 -293.114477) (xy 374.451754 -293.11244)
			(xy 374.396911 -293.10231) (xy 374.344127 -293.084303) (xy 374.294527 -293.058802) (xy 374.249169 -293.026351)
			(xy 374.20902 -292.987642) (xy 374.174934 -292.943499) (xy 374.147638 -292.894864) (xy 374.127715 -292.842773)
			(xy 374.115589 -292.788336) (xy 374.111518 -292.732714) (xy 368.55019 -292.732714) (xy 368.55019 -293.201852)
			(xy 368.549757 -293.211918) (xy 368.542028 -293.230508) (xy 368.535204 -293.23792) (xy 368.27841 -293.494714)
			(xy 379.638052 -293.494714) (xy 379.638619 -293.465333) (xy 379.647646 -293.407268) (xy 379.665474 -293.351275)
			(xy 379.691681 -293.29868) (xy 379.725646 -293.250728) (xy 379.766565 -293.208554) (xy 379.78969 -293.190422)
			(xy 379.799088 -293.183056) (xy 379.809502 -293.162482) (xy 379.811026 -293.058596) (xy 379.80112 -293.037514)
			(xy 379.791976 -293.030148) (xy 379.770116 -293.011956) (xy 379.731578 -292.970134) (xy 379.699673 -292.923055)
			(xy 379.675108 -292.871763) (xy 379.658427 -292.817393) (xy 379.65 -292.76115) (xy 379.649482 -292.732714)
			(xy 379.649968 -292.705463) (xy 379.657724 -292.651515) (xy 379.673079 -292.59922) (xy 379.695721 -292.549643)
			(xy 379.725187 -292.503793) (xy 379.760878 -292.462602) (xy 379.802069 -292.426911) (xy 379.847919 -292.397445)
			(xy 379.897496 -292.374803) (xy 379.949791 -292.359448) (xy 380.003739 -292.351692) (xy 380.058241 -292.351692)
			(xy 380.112189 -292.359448) (xy 380.164484 -292.374803) (xy 380.214061 -292.397445) (xy 380.259911 -292.426911)
			(xy 380.301102 -292.462602) (xy 380.336793 -292.503793) (xy 380.366259 -292.549643) (xy 380.377831 -292.57498)
			(xy 384.369068 -292.57498) (xy 384.373028 -292.525926) (xy 384.384805 -292.478142) (xy 384.404096 -292.432866)
			(xy 384.430399 -292.39127) (xy 384.463034 -292.354433) (xy 384.501155 -292.323308) (xy 384.543776 -292.298701)
			(xy 384.589792 -292.281249) (xy 384.638011 -292.271405) (xy 384.687186 -292.269424) (xy 384.736041 -292.275356)
			(xy 384.783312 -292.289048) (xy 384.827774 -292.310146) (xy 384.868277 -292.338102) (xy 384.90377 -292.372194)
			(xy 384.933335 -292.411538) (xy 384.956206 -292.455115) (xy 384.97179 -292.501796) (xy 384.979685 -292.550373)
			(xy 384.98018 -292.57498) (xy 385.319028 -292.57498) (xy 385.322988 -292.525926) (xy 385.334765 -292.478142)
			(xy 385.354056 -292.432866) (xy 385.380359 -292.39127) (xy 385.412994 -292.354433) (xy 385.451115 -292.323308)
			(xy 385.493736 -292.298701) (xy 385.539752 -292.281249) (xy 385.587971 -292.271405) (xy 385.637146 -292.269424)
			(xy 385.686001 -292.275356) (xy 385.733272 -292.289048) (xy 385.777734 -292.310146) (xy 385.818237 -292.338102)
			(xy 385.85373 -292.372194) (xy 385.883295 -292.411538) (xy 385.906166 -292.455115) (xy 385.92175 -292.501796)
			(xy 385.929645 -292.550373) (xy 385.93014 -292.57498) (xy 386.269242 -292.57498) (xy 386.273202 -292.525926)
			(xy 386.284979 -292.478142) (xy 386.30427 -292.432866) (xy 386.330573 -292.39127) (xy 386.363208 -292.354433)
			(xy 386.401329 -292.323308) (xy 386.44395 -292.298701) (xy 386.489966 -292.281249) (xy 386.538185 -292.271405)
			(xy 386.58736 -292.269424) (xy 386.636215 -292.275356) (xy 386.683486 -292.289048) (xy 386.727948 -292.310146)
			(xy 386.768451 -292.338102) (xy 386.803944 -292.372194) (xy 386.833509 -292.411538) (xy 386.85638 -292.455115)
			(xy 386.871964 -292.501796) (xy 386.879859 -292.550373) (xy 386.880349 -292.574726) (xy 387.219202 -292.574726)
			(xy 387.223162 -292.525672) (xy 387.234939 -292.477888) (xy 387.25423 -292.432612) (xy 387.280533 -292.391016)
			(xy 387.313168 -292.354179) (xy 387.351289 -292.323054) (xy 387.39391 -292.298447) (xy 387.439926 -292.280995)
			(xy 387.488145 -292.271151) (xy 387.53732 -292.26917) (xy 387.586175 -292.275102) (xy 387.633446 -292.288794)
			(xy 387.677908 -292.309892) (xy 387.718411 -292.337848) (xy 387.753904 -292.37194) (xy 387.783469 -292.411284)
			(xy 387.80634 -292.454861) (xy 387.821924 -292.501542) (xy 387.829819 -292.550119) (xy 387.830314 -292.574726)
			(xy 388.169162 -292.574726) (xy 388.173122 -292.525672) (xy 388.184899 -292.477888) (xy 388.20419 -292.432612)
			(xy 388.230493 -292.391016) (xy 388.263128 -292.354179) (xy 388.301249 -292.323054) (xy 388.34387 -292.298447)
			(xy 388.389886 -292.280995) (xy 388.438105 -292.271151) (xy 388.48728 -292.26917) (xy 388.536135 -292.275102)
			(xy 388.583406 -292.288794) (xy 388.627868 -292.309892) (xy 388.668371 -292.337848) (xy 388.703864 -292.37194)
			(xy 388.733429 -292.411284) (xy 388.7563 -292.454861) (xy 388.771884 -292.501542) (xy 388.779779 -292.550119)
			(xy 388.780274 -292.574726) (xy 388.780269 -292.57498) (xy 389.119122 -292.57498) (xy 389.123082 -292.525926)
			(xy 389.134859 -292.478142) (xy 389.15415 -292.432866) (xy 389.180453 -292.39127) (xy 389.213088 -292.354433)
			(xy 389.251209 -292.323308) (xy 389.29383 -292.298701) (xy 389.339846 -292.281249) (xy 389.388065 -292.271405)
			(xy 389.43724 -292.269424) (xy 389.486095 -292.275356) (xy 389.533366 -292.289048) (xy 389.577828 -292.310146)
			(xy 389.618331 -292.338102) (xy 389.653824 -292.372194) (xy 389.683389 -292.411538) (xy 389.70626 -292.455115)
			(xy 389.721844 -292.501796) (xy 389.729739 -292.550373) (xy 389.730234 -292.57498) (xy 389.729739 -292.599587)
			(xy 389.729407 -292.601629) (xy 390.019276 -292.601629) (xy 390.019276 -292.548331) (xy 390.027219 -292.495627)
			(xy 390.042929 -292.444697) (xy 390.066055 -292.396676) (xy 390.096079 -292.352639) (xy 390.132331 -292.313568)
			(xy 390.174002 -292.280337) (xy 390.22016 -292.253688) (xy 390.269774 -292.234216) (xy 390.321736 -292.222356)
			(xy 390.374886 -292.218373) (xy 390.428036 -292.222356) (xy 390.479998 -292.234216) (xy 390.529612 -292.253688)
			(xy 390.57577 -292.280337) (xy 390.617441 -292.313568) (xy 390.653693 -292.352639) (xy 390.683717 -292.396676)
			(xy 390.706843 -292.444697) (xy 390.722553 -292.495627) (xy 390.730496 -292.548331) (xy 390.730994 -292.57498)
			(xy 391.019042 -292.57498) (xy 391.023002 -292.525926) (xy 391.034779 -292.478142) (xy 391.05407 -292.432866)
			(xy 391.080373 -292.39127) (xy 391.113008 -292.354433) (xy 391.151129 -292.323308) (xy 391.19375 -292.298701)
			(xy 391.239766 -292.281249) (xy 391.287985 -292.271405) (xy 391.33716 -292.269424) (xy 391.386015 -292.275356)
			(xy 391.433286 -292.289048) (xy 391.477748 -292.310146) (xy 391.518251 -292.338102) (xy 391.553744 -292.372194)
			(xy 391.583309 -292.411538) (xy 391.60618 -292.455115) (xy 391.621764 -292.501796) (xy 391.629659 -292.550373)
			(xy 391.630154 -292.57498) (xy 391.969002 -292.57498) (xy 391.972962 -292.525926) (xy 391.984739 -292.478142)
			(xy 392.00403 -292.432866) (xy 392.030333 -292.39127) (xy 392.062968 -292.354433) (xy 392.101089 -292.323308)
			(xy 392.14371 -292.298701) (xy 392.189726 -292.281249) (xy 392.237945 -292.271405) (xy 392.28712 -292.269424)
			(xy 392.335975 -292.275356) (xy 392.383246 -292.289048) (xy 392.427708 -292.310146) (xy 392.468211 -292.338102)
			(xy 392.503704 -292.372194) (xy 392.533269 -292.411538) (xy 392.55614 -292.455115) (xy 392.571724 -292.501796)
			(xy 392.579619 -292.550373) (xy 392.580114 -292.57498) (xy 392.919216 -292.57498) (xy 392.923176 -292.525926)
			(xy 392.934953 -292.478142) (xy 392.954244 -292.432866) (xy 392.980547 -292.39127) (xy 393.013182 -292.354433)
			(xy 393.051303 -292.323308) (xy 393.093924 -292.298701) (xy 393.13994 -292.281249) (xy 393.188159 -292.271405)
			(xy 393.237334 -292.269424) (xy 393.286189 -292.275356) (xy 393.33346 -292.289048) (xy 393.377922 -292.310146)
			(xy 393.418425 -292.338102) (xy 393.453918 -292.372194) (xy 393.483483 -292.411538) (xy 393.506354 -292.455115)
			(xy 393.521938 -292.501796) (xy 393.529833 -292.550373) (xy 393.530328 -292.57498) (xy 393.869176 -292.57498)
			(xy 393.873136 -292.525926) (xy 393.884913 -292.478142) (xy 393.904204 -292.432866) (xy 393.930507 -292.39127)
			(xy 393.963142 -292.354433) (xy 394.001263 -292.323308) (xy 394.043884 -292.298701) (xy 394.0899 -292.281249)
			(xy 394.138119 -292.271405) (xy 394.187294 -292.269424) (xy 394.236149 -292.275356) (xy 394.28342 -292.289048)
			(xy 394.327882 -292.310146) (xy 394.368385 -292.338102) (xy 394.403878 -292.372194) (xy 394.433443 -292.411538)
			(xy 394.456314 -292.455115) (xy 394.471898 -292.501796) (xy 394.479793 -292.550373) (xy 394.480288 -292.57498)
			(xy 394.819136 -292.57498) (xy 394.823096 -292.525926) (xy 394.834873 -292.478142) (xy 394.854164 -292.432866)
			(xy 394.880467 -292.39127) (xy 394.913102 -292.354433) (xy 394.951223 -292.323308) (xy 394.993844 -292.298701)
			(xy 395.03986 -292.281249) (xy 395.088079 -292.271405) (xy 395.137254 -292.269424) (xy 395.186109 -292.275356)
			(xy 395.23338 -292.289048) (xy 395.277842 -292.310146) (xy 395.318345 -292.338102) (xy 395.353838 -292.372194)
			(xy 395.383403 -292.411538) (xy 395.406274 -292.455115) (xy 395.421858 -292.501796) (xy 395.429753 -292.550373)
			(xy 395.430248 -292.57498) (xy 395.769096 -292.57498) (xy 395.773056 -292.525926) (xy 395.784833 -292.478142)
			(xy 395.804124 -292.432866) (xy 395.830427 -292.39127) (xy 395.863062 -292.354433) (xy 395.901183 -292.323308)
			(xy 395.943804 -292.298701) (xy 395.98982 -292.281249) (xy 396.038039 -292.271405) (xy 396.087214 -292.269424)
			(xy 396.136069 -292.275356) (xy 396.18334 -292.289048) (xy 396.227802 -292.310146) (xy 396.268305 -292.338102)
			(xy 396.303798 -292.372194) (xy 396.333363 -292.411538) (xy 396.356234 -292.455115) (xy 396.371818 -292.501796)
			(xy 396.379713 -292.550373) (xy 396.380203 -292.574726) (xy 397.669016 -292.574726) (xy 397.672976 -292.525672)
			(xy 397.684753 -292.477888) (xy 397.704044 -292.432612) (xy 397.730347 -292.391016) (xy 397.762982 -292.354179)
			(xy 397.801103 -292.323054) (xy 397.843724 -292.298447) (xy 397.88974 -292.280995) (xy 397.937959 -292.271151)
			(xy 397.987134 -292.26917) (xy 398.035989 -292.275102) (xy 398.08326 -292.288794) (xy 398.127722 -292.309892)
			(xy 398.168225 -292.337848) (xy 398.203718 -292.37194) (xy 398.233283 -292.411284) (xy 398.256154 -292.454861)
			(xy 398.271738 -292.501542) (xy 398.279633 -292.550119) (xy 398.280128 -292.574726) (xy 398.280123 -292.57498)
			(xy 398.61923 -292.57498) (xy 398.62319 -292.525926) (xy 398.634967 -292.478142) (xy 398.654258 -292.432866)
			(xy 398.680561 -292.39127) (xy 398.713196 -292.354433) (xy 398.751317 -292.323308) (xy 398.793938 -292.298701)
			(xy 398.839954 -292.281249) (xy 398.888173 -292.271405) (xy 398.937348 -292.269424) (xy 398.986203 -292.275356)
			(xy 399.033474 -292.289048) (xy 399.077936 -292.310146) (xy 399.118439 -292.338102) (xy 399.153932 -292.372194)
			(xy 399.183497 -292.411538) (xy 399.206368 -292.455115) (xy 399.221952 -292.501796) (xy 399.229847 -292.550373)
			(xy 399.230342 -292.57498) (xy 399.56919 -292.57498) (xy 399.57315 -292.525926) (xy 399.584927 -292.478142)
			(xy 399.604218 -292.432866) (xy 399.630521 -292.39127) (xy 399.663156 -292.354433) (xy 399.701277 -292.323308)
			(xy 399.743898 -292.298701) (xy 399.789914 -292.281249) (xy 399.838133 -292.271405) (xy 399.887308 -292.269424)
			(xy 399.936163 -292.275356) (xy 399.983434 -292.289048) (xy 400.027896 -292.310146) (xy 400.068399 -292.338102)
			(xy 400.103892 -292.372194) (xy 400.133457 -292.411538) (xy 400.156328 -292.455115) (xy 400.171912 -292.501796)
			(xy 400.179807 -292.550373) (xy 400.180302 -292.57498) (xy 400.51915 -292.57498) (xy 400.52311 -292.525926)
			(xy 400.534887 -292.478142) (xy 400.554178 -292.432866) (xy 400.580481 -292.39127) (xy 400.613116 -292.354433)
			(xy 400.651237 -292.323308) (xy 400.693858 -292.298701) (xy 400.739874 -292.281249) (xy 400.788093 -292.271405)
			(xy 400.837268 -292.269424) (xy 400.886123 -292.275356) (xy 400.933394 -292.289048) (xy 400.977856 -292.310146)
			(xy 401.018359 -292.338102) (xy 401.053852 -292.372194) (xy 401.083417 -292.411538) (xy 401.106288 -292.455115)
			(xy 401.121872 -292.501796) (xy 401.129767 -292.550373) (xy 401.130262 -292.57498) (xy 401.46911 -292.57498)
			(xy 401.47307 -292.525926) (xy 401.484847 -292.478142) (xy 401.504138 -292.432866) (xy 401.530441 -292.39127)
			(xy 401.563076 -292.354433) (xy 401.601197 -292.323308) (xy 401.643818 -292.298701) (xy 401.689834 -292.281249)
			(xy 401.738053 -292.271405) (xy 401.787228 -292.269424) (xy 401.836083 -292.275356) (xy 401.883354 -292.289048)
			(xy 401.927816 -292.310146) (xy 401.968319 -292.338102) (xy 402.003812 -292.372194) (xy 402.033377 -292.411538)
			(xy 402.056248 -292.455115) (xy 402.071832 -292.501796) (xy 402.079727 -292.550373) (xy 402.080222 -292.57498)
			(xy 402.41907 -292.57498) (xy 402.42303 -292.525926) (xy 402.434807 -292.478142) (xy 402.454098 -292.432866)
			(xy 402.480401 -292.39127) (xy 402.513036 -292.354433) (xy 402.551157 -292.323308) (xy 402.593778 -292.298701)
			(xy 402.639794 -292.281249) (xy 402.688013 -292.271405) (xy 402.737188 -292.269424) (xy 402.786043 -292.275356)
			(xy 402.833314 -292.289048) (xy 402.877776 -292.310146) (xy 402.918279 -292.338102) (xy 402.953772 -292.372194)
			(xy 402.983337 -292.411538) (xy 403.006208 -292.455115) (xy 403.021792 -292.501796) (xy 403.029687 -292.550373)
			(xy 403.030182 -292.57498) (xy 403.36903 -292.57498) (xy 403.37299 -292.525926) (xy 403.384767 -292.478142)
			(xy 403.404058 -292.432866) (xy 403.430361 -292.39127) (xy 403.462996 -292.354433) (xy 403.501117 -292.323308)
			(xy 403.543738 -292.298701) (xy 403.589754 -292.281249) (xy 403.637973 -292.271405) (xy 403.687148 -292.269424)
			(xy 403.736003 -292.275356) (xy 403.783274 -292.289048) (xy 403.827736 -292.310146) (xy 403.868239 -292.338102)
			(xy 403.903732 -292.372194) (xy 403.933297 -292.411538) (xy 403.956168 -292.455115) (xy 403.971752 -292.501796)
			(xy 403.979647 -292.550373) (xy 403.980142 -292.57498) (xy 404.319244 -292.57498) (xy 404.323204 -292.525926)
			(xy 404.334981 -292.478142) (xy 404.354272 -292.432866) (xy 404.380575 -292.39127) (xy 404.41321 -292.354433)
			(xy 404.451331 -292.323308) (xy 404.493952 -292.298701) (xy 404.539968 -292.281249) (xy 404.588187 -292.271405)
			(xy 404.637362 -292.269424) (xy 404.686217 -292.275356) (xy 404.733488 -292.289048) (xy 404.77795 -292.310146)
			(xy 404.818453 -292.338102) (xy 404.853946 -292.372194) (xy 404.883511 -292.411538) (xy 404.906382 -292.455115)
			(xy 404.921966 -292.501796) (xy 404.929861 -292.550373) (xy 404.930356 -292.57498) (xy 405.269204 -292.57498)
			(xy 405.273164 -292.525926) (xy 405.284941 -292.478142) (xy 405.304232 -292.432866) (xy 405.330535 -292.39127)
			(xy 405.36317 -292.354433) (xy 405.401291 -292.323308) (xy 405.443912 -292.298701) (xy 405.489928 -292.281249)
			(xy 405.538147 -292.271405) (xy 405.587322 -292.269424) (xy 405.636177 -292.275356) (xy 405.683448 -292.289048)
			(xy 405.72791 -292.310146) (xy 405.768413 -292.338102) (xy 405.803906 -292.372194) (xy 405.833471 -292.411538)
			(xy 405.856342 -292.455115) (xy 405.871926 -292.501796) (xy 405.879821 -292.550373) (xy 405.880316 -292.57498)
			(xy 406.219164 -292.57498) (xy 406.223124 -292.525926) (xy 406.234901 -292.478142) (xy 406.254192 -292.432866)
			(xy 406.280495 -292.39127) (xy 406.31313 -292.354433) (xy 406.351251 -292.323308) (xy 406.393872 -292.298701)
			(xy 406.439888 -292.281249) (xy 406.488107 -292.271405) (xy 406.537282 -292.269424) (xy 406.586137 -292.275356)
			(xy 406.633408 -292.289048) (xy 406.67787 -292.310146) (xy 406.718373 -292.338102) (xy 406.753866 -292.372194)
			(xy 406.783431 -292.411538) (xy 406.806302 -292.455115) (xy 406.821886 -292.501796) (xy 406.829781 -292.550373)
			(xy 406.830271 -292.574726) (xy 408.119084 -292.574726) (xy 408.123044 -292.525672) (xy 408.134821 -292.477888)
			(xy 408.154112 -292.432612) (xy 408.180415 -292.391016) (xy 408.21305 -292.354179) (xy 408.251171 -292.323054)
			(xy 408.293792 -292.298447) (xy 408.339808 -292.280995) (xy 408.388027 -292.271151) (xy 408.437202 -292.26917)
			(xy 408.486057 -292.275102) (xy 408.533328 -292.288794) (xy 408.57779 -292.309892) (xy 408.618293 -292.337848)
			(xy 408.653786 -292.37194) (xy 408.683351 -292.411284) (xy 408.706222 -292.454861) (xy 408.721806 -292.501542)
			(xy 408.729701 -292.550119) (xy 408.730196 -292.574726) (xy 409.069044 -292.574726) (xy 409.073004 -292.525672)
			(xy 409.084781 -292.477888) (xy 409.104072 -292.432612) (xy 409.130375 -292.391016) (xy 409.16301 -292.354179)
			(xy 409.201131 -292.323054) (xy 409.243752 -292.298447) (xy 409.289768 -292.280995) (xy 409.337987 -292.271151)
			(xy 409.387162 -292.26917) (xy 409.436017 -292.275102) (xy 409.483288 -292.288794) (xy 409.52775 -292.309892)
			(xy 409.568253 -292.337848) (xy 409.603746 -292.37194) (xy 409.633311 -292.411284) (xy 409.656182 -292.454861)
			(xy 409.671766 -292.501542) (xy 409.679661 -292.550119) (xy 409.680156 -292.574726) (xy 410.019004 -292.574726)
			(xy 410.022964 -292.525672) (xy 410.034741 -292.477888) (xy 410.054032 -292.432612) (xy 410.080335 -292.391016)
			(xy 410.11297 -292.354179) (xy 410.151091 -292.323054) (xy 410.193712 -292.298447) (xy 410.239728 -292.280995)
			(xy 410.287947 -292.271151) (xy 410.337122 -292.26917) (xy 410.385977 -292.275102) (xy 410.433248 -292.288794)
			(xy 410.47771 -292.309892) (xy 410.518213 -292.337848) (xy 410.553706 -292.37194) (xy 410.583271 -292.411284)
			(xy 410.606142 -292.454861) (xy 410.621726 -292.501542) (xy 410.629621 -292.550119) (xy 410.630116 -292.574726)
			(xy 410.969218 -292.574726) (xy 410.973178 -292.525672) (xy 410.984955 -292.477888) (xy 411.004246 -292.432612)
			(xy 411.030549 -292.391016) (xy 411.063184 -292.354179) (xy 411.101305 -292.323054) (xy 411.143926 -292.298447)
			(xy 411.189942 -292.280995) (xy 411.238161 -292.271151) (xy 411.287336 -292.26917) (xy 411.336191 -292.275102)
			(xy 411.383462 -292.288794) (xy 411.427924 -292.309892) (xy 411.468427 -292.337848) (xy 411.50392 -292.37194)
			(xy 411.533485 -292.411284) (xy 411.556356 -292.454861) (xy 411.57194 -292.501542) (xy 411.579835 -292.550119)
			(xy 411.58033 -292.574726) (xy 411.919178 -292.574726) (xy 411.923138 -292.525672) (xy 411.934915 -292.477888)
			(xy 411.954206 -292.432612) (xy 411.980509 -292.391016) (xy 412.013144 -292.354179) (xy 412.051265 -292.323054)
			(xy 412.093886 -292.298447) (xy 412.139902 -292.280995) (xy 412.188121 -292.271151) (xy 412.237296 -292.26917)
			(xy 412.286151 -292.275102) (xy 412.333422 -292.288794) (xy 412.377884 -292.309892) (xy 412.418387 -292.337848)
			(xy 412.45388 -292.37194) (xy 412.483445 -292.411284) (xy 412.506316 -292.454861) (xy 412.5219 -292.501542)
			(xy 412.529795 -292.550119) (xy 412.53029 -292.574726) (xy 412.869138 -292.574726) (xy 412.873098 -292.525672)
			(xy 412.884875 -292.477888) (xy 412.904166 -292.432612) (xy 412.930469 -292.391016) (xy 412.963104 -292.354179)
			(xy 413.001225 -292.323054) (xy 413.043846 -292.298447) (xy 413.089862 -292.280995) (xy 413.138081 -292.271151)
			(xy 413.187256 -292.26917) (xy 413.236111 -292.275102) (xy 413.283382 -292.288794) (xy 413.327844 -292.309892)
			(xy 413.368347 -292.337848) (xy 413.40384 -292.37194) (xy 413.433405 -292.411284) (xy 413.456276 -292.454861)
			(xy 413.47186 -292.501542) (xy 413.479755 -292.550119) (xy 413.48025 -292.574726) (xy 413.819098 -292.574726)
			(xy 413.823058 -292.525672) (xy 413.834835 -292.477888) (xy 413.854126 -292.432612) (xy 413.880429 -292.391016)
			(xy 413.913064 -292.354179) (xy 413.951185 -292.323054) (xy 413.993806 -292.298447) (xy 414.039822 -292.280995)
			(xy 414.088041 -292.271151) (xy 414.137216 -292.26917) (xy 414.186071 -292.275102) (xy 414.233342 -292.288794)
			(xy 414.277804 -292.309892) (xy 414.318307 -292.337848) (xy 414.3538 -292.37194) (xy 414.383365 -292.411284)
			(xy 414.406236 -292.454861) (xy 414.42182 -292.501542) (xy 414.429715 -292.550119) (xy 414.43021 -292.574726)
			(xy 414.769058 -292.574726) (xy 414.773018 -292.525672) (xy 414.784795 -292.477888) (xy 414.804086 -292.432612)
			(xy 414.830389 -292.391016) (xy 414.863024 -292.354179) (xy 414.901145 -292.323054) (xy 414.943766 -292.298447)
			(xy 414.989782 -292.280995) (xy 415.038001 -292.271151) (xy 415.087176 -292.26917) (xy 415.136031 -292.275102)
			(xy 415.183302 -292.288794) (xy 415.227764 -292.309892) (xy 415.268267 -292.337848) (xy 415.30376 -292.37194)
			(xy 415.333325 -292.411284) (xy 415.356196 -292.454861) (xy 415.37178 -292.501542) (xy 415.379675 -292.550119)
			(xy 415.38017 -292.574726) (xy 415.719018 -292.574726) (xy 415.722978 -292.525672) (xy 415.734755 -292.477888)
			(xy 415.754046 -292.432612) (xy 415.780349 -292.391016) (xy 415.812984 -292.354179) (xy 415.851105 -292.323054)
			(xy 415.893726 -292.298447) (xy 415.939742 -292.280995) (xy 415.987961 -292.271151) (xy 416.037136 -292.26917)
			(xy 416.085991 -292.275102) (xy 416.133262 -292.288794) (xy 416.177724 -292.309892) (xy 416.218227 -292.337848)
			(xy 416.25372 -292.37194) (xy 416.283285 -292.411284) (xy 416.306156 -292.454861) (xy 416.32174 -292.501542)
			(xy 416.329635 -292.550119) (xy 416.33013 -292.574726) (xy 416.329635 -292.599333) (xy 416.32174 -292.64791)
			(xy 416.306156 -292.694591) (xy 416.283285 -292.738168) (xy 416.25372 -292.777512) (xy 416.218227 -292.811604)
			(xy 416.177724 -292.83956) (xy 416.133262 -292.860658) (xy 416.085991 -292.87435) (xy 416.037136 -292.880282)
			(xy 415.987961 -292.878301) (xy 415.939742 -292.868457) (xy 415.893726 -292.851005) (xy 415.851105 -292.826398)
			(xy 415.812984 -292.795273) (xy 415.780349 -292.758436) (xy 415.754046 -292.71684) (xy 415.734755 -292.671564)
			(xy 415.722978 -292.62378) (xy 415.719018 -292.574726) (xy 415.38017 -292.574726) (xy 415.379675 -292.599333)
			(xy 415.37178 -292.64791) (xy 415.356196 -292.694591) (xy 415.333325 -292.738168) (xy 415.30376 -292.777512)
			(xy 415.268267 -292.811604) (xy 415.227764 -292.83956) (xy 415.183302 -292.860658) (xy 415.136031 -292.87435)
			(xy 415.087176 -292.880282) (xy 415.038001 -292.878301) (xy 414.989782 -292.868457) (xy 414.943766 -292.851005)
			(xy 414.901145 -292.826398) (xy 414.863024 -292.795273) (xy 414.830389 -292.758436) (xy 414.804086 -292.71684)
			(xy 414.784795 -292.671564) (xy 414.773018 -292.62378) (xy 414.769058 -292.574726) (xy 414.43021 -292.574726)
			(xy 414.429715 -292.599333) (xy 414.42182 -292.64791) (xy 414.406236 -292.694591) (xy 414.383365 -292.738168)
			(xy 414.3538 -292.777512) (xy 414.318307 -292.811604) (xy 414.277804 -292.83956) (xy 414.233342 -292.860658)
			(xy 414.186071 -292.87435) (xy 414.137216 -292.880282) (xy 414.088041 -292.878301) (xy 414.039822 -292.868457)
			(xy 413.993806 -292.851005) (xy 413.951185 -292.826398) (xy 413.913064 -292.795273) (xy 413.880429 -292.758436)
			(xy 413.854126 -292.71684) (xy 413.834835 -292.671564) (xy 413.823058 -292.62378) (xy 413.819098 -292.574726)
			(xy 413.48025 -292.574726) (xy 413.479755 -292.599333) (xy 413.47186 -292.64791) (xy 413.456276 -292.694591)
			(xy 413.433405 -292.738168) (xy 413.40384 -292.777512) (xy 413.368347 -292.811604) (xy 413.327844 -292.83956)
			(xy 413.283382 -292.860658) (xy 413.236111 -292.87435) (xy 413.187256 -292.880282) (xy 413.138081 -292.878301)
			(xy 413.089862 -292.868457) (xy 413.043846 -292.851005) (xy 413.001225 -292.826398) (xy 412.963104 -292.795273)
			(xy 412.930469 -292.758436) (xy 412.904166 -292.71684) (xy 412.884875 -292.671564) (xy 412.873098 -292.62378)
			(xy 412.869138 -292.574726) (xy 412.53029 -292.574726) (xy 412.529795 -292.599333) (xy 412.5219 -292.64791)
			(xy 412.506316 -292.694591) (xy 412.483445 -292.738168) (xy 412.45388 -292.777512) (xy 412.418387 -292.811604)
			(xy 412.377884 -292.83956) (xy 412.333422 -292.860658) (xy 412.286151 -292.87435) (xy 412.237296 -292.880282)
			(xy 412.188121 -292.878301) (xy 412.139902 -292.868457) (xy 412.093886 -292.851005) (xy 412.051265 -292.826398)
			(xy 412.013144 -292.795273) (xy 411.980509 -292.758436) (xy 411.954206 -292.71684) (xy 411.934915 -292.671564)
			(xy 411.923138 -292.62378) (xy 411.919178 -292.574726) (xy 411.58033 -292.574726) (xy 411.579835 -292.599333)
			(xy 411.57194 -292.64791) (xy 411.556356 -292.694591) (xy 411.533485 -292.738168) (xy 411.50392 -292.777512)
			(xy 411.468427 -292.811604) (xy 411.427924 -292.83956) (xy 411.383462 -292.860658) (xy 411.336191 -292.87435)
			(xy 411.287336 -292.880282) (xy 411.238161 -292.878301) (xy 411.189942 -292.868457) (xy 411.143926 -292.851005)
			(xy 411.101305 -292.826398) (xy 411.063184 -292.795273) (xy 411.030549 -292.758436) (xy 411.004246 -292.71684)
			(xy 410.984955 -292.671564) (xy 410.973178 -292.62378) (xy 410.969218 -292.574726) (xy 410.630116 -292.574726)
			(xy 410.629621 -292.599333) (xy 410.621726 -292.64791) (xy 410.606142 -292.694591) (xy 410.583271 -292.738168)
			(xy 410.553706 -292.777512) (xy 410.518213 -292.811604) (xy 410.47771 -292.83956) (xy 410.433248 -292.860658)
			(xy 410.385977 -292.87435) (xy 410.337122 -292.880282) (xy 410.287947 -292.878301) (xy 410.239728 -292.868457)
			(xy 410.193712 -292.851005) (xy 410.151091 -292.826398) (xy 410.11297 -292.795273) (xy 410.080335 -292.758436)
			(xy 410.054032 -292.71684) (xy 410.034741 -292.671564) (xy 410.022964 -292.62378) (xy 410.019004 -292.574726)
			(xy 409.680156 -292.574726) (xy 409.679661 -292.599333) (xy 409.671766 -292.64791) (xy 409.656182 -292.694591)
			(xy 409.633311 -292.738168) (xy 409.603746 -292.777512) (xy 409.568253 -292.811604) (xy 409.52775 -292.83956)
			(xy 409.483288 -292.860658) (xy 409.436017 -292.87435) (xy 409.387162 -292.880282) (xy 409.337987 -292.878301)
			(xy 409.289768 -292.868457) (xy 409.243752 -292.851005) (xy 409.201131 -292.826398) (xy 409.16301 -292.795273)
			(xy 409.130375 -292.758436) (xy 409.104072 -292.71684) (xy 409.084781 -292.671564) (xy 409.073004 -292.62378)
			(xy 409.069044 -292.574726) (xy 408.730196 -292.574726) (xy 408.729701 -292.599333) (xy 408.721806 -292.64791)
			(xy 408.706222 -292.694591) (xy 408.683351 -292.738168) (xy 408.653786 -292.777512) (xy 408.618293 -292.811604)
			(xy 408.57779 -292.83956) (xy 408.533328 -292.860658) (xy 408.486057 -292.87435) (xy 408.437202 -292.880282)
			(xy 408.388027 -292.878301) (xy 408.339808 -292.868457) (xy 408.293792 -292.851005) (xy 408.251171 -292.826398)
			(xy 408.21305 -292.795273) (xy 408.180415 -292.758436) (xy 408.154112 -292.71684) (xy 408.134821 -292.671564)
			(xy 408.123044 -292.62378) (xy 408.119084 -292.574726) (xy 406.830271 -292.574726) (xy 406.830276 -292.57498)
			(xy 406.829781 -292.599587) (xy 406.821886 -292.648164) (xy 406.806302 -292.694845) (xy 406.783431 -292.738422)
			(xy 406.753866 -292.777766) (xy 406.718373 -292.811858) (xy 406.67787 -292.839814) (xy 406.633408 -292.860912)
			(xy 406.586137 -292.874604) (xy 406.537282 -292.880536) (xy 406.488107 -292.878555) (xy 406.439888 -292.868711)
			(xy 406.393872 -292.851259) (xy 406.351251 -292.826652) (xy 406.31313 -292.795527) (xy 406.280495 -292.75869)
			(xy 406.254192 -292.717094) (xy 406.234901 -292.671818) (xy 406.223124 -292.624034) (xy 406.219164 -292.57498)
			(xy 405.880316 -292.57498) (xy 405.879821 -292.599587) (xy 405.871926 -292.648164) (xy 405.856342 -292.694845)
			(xy 405.833471 -292.738422) (xy 405.803906 -292.777766) (xy 405.768413 -292.811858) (xy 405.72791 -292.839814)
			(xy 405.683448 -292.860912) (xy 405.636177 -292.874604) (xy 405.587322 -292.880536) (xy 405.538147 -292.878555)
			(xy 405.489928 -292.868711) (xy 405.443912 -292.851259) (xy 405.401291 -292.826652) (xy 405.36317 -292.795527)
			(xy 405.330535 -292.75869) (xy 405.304232 -292.717094) (xy 405.284941 -292.671818) (xy 405.273164 -292.624034)
			(xy 405.269204 -292.57498) (xy 404.930356 -292.57498) (xy 404.929861 -292.599587) (xy 404.921966 -292.648164)
			(xy 404.906382 -292.694845) (xy 404.883511 -292.738422) (xy 404.853946 -292.777766) (xy 404.818453 -292.811858)
			(xy 404.77795 -292.839814) (xy 404.733488 -292.860912) (xy 404.686217 -292.874604) (xy 404.637362 -292.880536)
			(xy 404.588187 -292.878555) (xy 404.539968 -292.868711) (xy 404.493952 -292.851259) (xy 404.451331 -292.826652)
			(xy 404.41321 -292.795527) (xy 404.380575 -292.75869) (xy 404.354272 -292.717094) (xy 404.334981 -292.671818)
			(xy 404.323204 -292.624034) (xy 404.319244 -292.57498) (xy 403.980142 -292.57498) (xy 403.979647 -292.599587)
			(xy 403.971752 -292.648164) (xy 403.956168 -292.694845) (xy 403.933297 -292.738422) (xy 403.903732 -292.777766)
			(xy 403.868239 -292.811858) (xy 403.827736 -292.839814) (xy 403.783274 -292.860912) (xy 403.736003 -292.874604)
			(xy 403.687148 -292.880536) (xy 403.637973 -292.878555) (xy 403.589754 -292.868711) (xy 403.543738 -292.851259)
			(xy 403.501117 -292.826652) (xy 403.462996 -292.795527) (xy 403.430361 -292.75869) (xy 403.404058 -292.717094)
			(xy 403.384767 -292.671818) (xy 403.37299 -292.624034) (xy 403.36903 -292.57498) (xy 403.030182 -292.57498)
			(xy 403.029687 -292.599587) (xy 403.021792 -292.648164) (xy 403.006208 -292.694845) (xy 402.983337 -292.738422)
			(xy 402.953772 -292.777766) (xy 402.918279 -292.811858) (xy 402.877776 -292.839814) (xy 402.833314 -292.860912)
			(xy 402.786043 -292.874604) (xy 402.737188 -292.880536) (xy 402.688013 -292.878555) (xy 402.639794 -292.868711)
			(xy 402.593778 -292.851259) (xy 402.551157 -292.826652) (xy 402.513036 -292.795527) (xy 402.480401 -292.75869)
			(xy 402.454098 -292.717094) (xy 402.434807 -292.671818) (xy 402.42303 -292.624034) (xy 402.41907 -292.57498)
			(xy 402.080222 -292.57498) (xy 402.079727 -292.599587) (xy 402.071832 -292.648164) (xy 402.056248 -292.694845)
			(xy 402.033377 -292.738422) (xy 402.003812 -292.777766) (xy 401.968319 -292.811858) (xy 401.927816 -292.839814)
			(xy 401.883354 -292.860912) (xy 401.836083 -292.874604) (xy 401.787228 -292.880536) (xy 401.738053 -292.878555)
			(xy 401.689834 -292.868711) (xy 401.643818 -292.851259) (xy 401.601197 -292.826652) (xy 401.563076 -292.795527)
			(xy 401.530441 -292.75869) (xy 401.504138 -292.717094) (xy 401.484847 -292.671818) (xy 401.47307 -292.624034)
			(xy 401.46911 -292.57498) (xy 401.130262 -292.57498) (xy 401.129767 -292.599587) (xy 401.121872 -292.648164)
			(xy 401.106288 -292.694845) (xy 401.083417 -292.738422) (xy 401.053852 -292.777766) (xy 401.018359 -292.811858)
			(xy 400.977856 -292.839814) (xy 400.933394 -292.860912) (xy 400.886123 -292.874604) (xy 400.837268 -292.880536)
			(xy 400.788093 -292.878555) (xy 400.739874 -292.868711) (xy 400.693858 -292.851259) (xy 400.651237 -292.826652)
			(xy 400.613116 -292.795527) (xy 400.580481 -292.75869) (xy 400.554178 -292.717094) (xy 400.534887 -292.671818)
			(xy 400.52311 -292.624034) (xy 400.51915 -292.57498) (xy 400.180302 -292.57498) (xy 400.179807 -292.599587)
			(xy 400.171912 -292.648164) (xy 400.156328 -292.694845) (xy 400.133457 -292.738422) (xy 400.103892 -292.777766)
			(xy 400.068399 -292.811858) (xy 400.027896 -292.839814) (xy 399.983434 -292.860912) (xy 399.936163 -292.874604)
			(xy 399.887308 -292.880536) (xy 399.838133 -292.878555) (xy 399.789914 -292.868711) (xy 399.743898 -292.851259)
			(xy 399.701277 -292.826652) (xy 399.663156 -292.795527) (xy 399.630521 -292.75869) (xy 399.604218 -292.717094)
			(xy 399.584927 -292.671818) (xy 399.57315 -292.624034) (xy 399.56919 -292.57498) (xy 399.230342 -292.57498)
			(xy 399.229847 -292.599587) (xy 399.221952 -292.648164) (xy 399.206368 -292.694845) (xy 399.183497 -292.738422)
			(xy 399.153932 -292.777766) (xy 399.118439 -292.811858) (xy 399.077936 -292.839814) (xy 399.033474 -292.860912)
			(xy 398.986203 -292.874604) (xy 398.937348 -292.880536) (xy 398.888173 -292.878555) (xy 398.839954 -292.868711)
			(xy 398.793938 -292.851259) (xy 398.751317 -292.826652) (xy 398.713196 -292.795527) (xy 398.680561 -292.75869)
			(xy 398.654258 -292.717094) (xy 398.634967 -292.671818) (xy 398.62319 -292.624034) (xy 398.61923 -292.57498)
			(xy 398.280123 -292.57498) (xy 398.279633 -292.599333) (xy 398.271738 -292.64791) (xy 398.256154 -292.694591)
			(xy 398.233283 -292.738168) (xy 398.203718 -292.777512) (xy 398.168225 -292.811604) (xy 398.127722 -292.83956)
			(xy 398.08326 -292.860658) (xy 398.035989 -292.87435) (xy 397.987134 -292.880282) (xy 397.937959 -292.878301)
			(xy 397.88974 -292.868457) (xy 397.843724 -292.851005) (xy 397.801103 -292.826398) (xy 397.762982 -292.795273)
			(xy 397.730347 -292.758436) (xy 397.704044 -292.71684) (xy 397.684753 -292.671564) (xy 397.672976 -292.62378)
			(xy 397.669016 -292.574726) (xy 396.380203 -292.574726) (xy 396.380208 -292.57498) (xy 396.379713 -292.599587)
			(xy 396.371818 -292.648164) (xy 396.356234 -292.694845) (xy 396.333363 -292.738422) (xy 396.303798 -292.777766)
			(xy 396.268305 -292.811858) (xy 396.227802 -292.839814) (xy 396.18334 -292.860912) (xy 396.136069 -292.874604)
			(xy 396.087214 -292.880536) (xy 396.038039 -292.878555) (xy 395.98982 -292.868711) (xy 395.943804 -292.851259)
			(xy 395.901183 -292.826652) (xy 395.863062 -292.795527) (xy 395.830427 -292.75869) (xy 395.804124 -292.717094)
			(xy 395.784833 -292.671818) (xy 395.773056 -292.624034) (xy 395.769096 -292.57498) (xy 395.430248 -292.57498)
			(xy 395.429753 -292.599587) (xy 395.421858 -292.648164) (xy 395.406274 -292.694845) (xy 395.383403 -292.738422)
			(xy 395.353838 -292.777766) (xy 395.318345 -292.811858) (xy 395.277842 -292.839814) (xy 395.23338 -292.860912)
			(xy 395.186109 -292.874604) (xy 395.137254 -292.880536) (xy 395.088079 -292.878555) (xy 395.03986 -292.868711)
			(xy 394.993844 -292.851259) (xy 394.951223 -292.826652) (xy 394.913102 -292.795527) (xy 394.880467 -292.75869)
			(xy 394.854164 -292.717094) (xy 394.834873 -292.671818) (xy 394.823096 -292.624034) (xy 394.819136 -292.57498)
			(xy 394.480288 -292.57498) (xy 394.479793 -292.599587) (xy 394.471898 -292.648164) (xy 394.456314 -292.694845)
			(xy 394.433443 -292.738422) (xy 394.403878 -292.777766) (xy 394.368385 -292.811858) (xy 394.327882 -292.839814)
			(xy 394.28342 -292.860912) (xy 394.236149 -292.874604) (xy 394.187294 -292.880536) (xy 394.138119 -292.878555)
			(xy 394.0899 -292.868711) (xy 394.043884 -292.851259) (xy 394.001263 -292.826652) (xy 393.963142 -292.795527)
			(xy 393.930507 -292.75869) (xy 393.904204 -292.717094) (xy 393.884913 -292.671818) (xy 393.873136 -292.624034)
			(xy 393.869176 -292.57498) (xy 393.530328 -292.57498) (xy 393.529833 -292.599587) (xy 393.521938 -292.648164)
			(xy 393.506354 -292.694845) (xy 393.483483 -292.738422) (xy 393.453918 -292.777766) (xy 393.418425 -292.811858)
			(xy 393.377922 -292.839814) (xy 393.33346 -292.860912) (xy 393.286189 -292.874604) (xy 393.237334 -292.880536)
			(xy 393.188159 -292.878555) (xy 393.13994 -292.868711) (xy 393.093924 -292.851259) (xy 393.051303 -292.826652)
			(xy 393.013182 -292.795527) (xy 392.980547 -292.75869) (xy 392.954244 -292.717094) (xy 392.934953 -292.671818)
			(xy 392.923176 -292.624034) (xy 392.919216 -292.57498) (xy 392.580114 -292.57498) (xy 392.579619 -292.599587)
			(xy 392.571724 -292.648164) (xy 392.55614 -292.694845) (xy 392.533269 -292.738422) (xy 392.503704 -292.777766)
			(xy 392.468211 -292.811858) (xy 392.427708 -292.839814) (xy 392.383246 -292.860912) (xy 392.335975 -292.874604)
			(xy 392.28712 -292.880536) (xy 392.237945 -292.878555) (xy 392.189726 -292.868711) (xy 392.14371 -292.851259)
			(xy 392.101089 -292.826652) (xy 392.062968 -292.795527) (xy 392.030333 -292.75869) (xy 392.00403 -292.717094)
			(xy 391.984739 -292.671818) (xy 391.972962 -292.624034) (xy 391.969002 -292.57498) (xy 391.630154 -292.57498)
			(xy 391.629659 -292.599587) (xy 391.621764 -292.648164) (xy 391.60618 -292.694845) (xy 391.583309 -292.738422)
			(xy 391.553744 -292.777766) (xy 391.518251 -292.811858) (xy 391.477748 -292.839814) (xy 391.433286 -292.860912)
			(xy 391.386015 -292.874604) (xy 391.33716 -292.880536) (xy 391.287985 -292.878555) (xy 391.239766 -292.868711)
			(xy 391.19375 -292.851259) (xy 391.151129 -292.826652) (xy 391.113008 -292.795527) (xy 391.080373 -292.75869)
			(xy 391.05407 -292.717094) (xy 391.034779 -292.671818) (xy 391.023002 -292.624034) (xy 391.019042 -292.57498)
			(xy 390.730994 -292.57498) (xy 390.730496 -292.601629) (xy 390.722553 -292.654333) (xy 390.706843 -292.705263)
			(xy 390.683717 -292.753284) (xy 390.653693 -292.797321) (xy 390.617441 -292.836392) (xy 390.57577 -292.869623)
			(xy 390.529612 -292.896272) (xy 390.479998 -292.915744) (xy 390.428036 -292.927604) (xy 390.374886 -292.931588)
			(xy 390.321736 -292.927604) (xy 390.269774 -292.915744) (xy 390.22016 -292.896272) (xy 390.174002 -292.869623)
			(xy 390.132331 -292.836392) (xy 390.096079 -292.797321) (xy 390.066055 -292.753284) (xy 390.042929 -292.705263)
			(xy 390.027219 -292.654333) (xy 390.019276 -292.601629) (xy 389.729407 -292.601629) (xy 389.721844 -292.648164)
			(xy 389.70626 -292.694845) (xy 389.683389 -292.738422) (xy 389.653824 -292.777766) (xy 389.618331 -292.811858)
			(xy 389.577828 -292.839814) (xy 389.533366 -292.860912) (xy 389.486095 -292.874604) (xy 389.43724 -292.880536)
			(xy 389.388065 -292.878555) (xy 389.339846 -292.868711) (xy 389.29383 -292.851259) (xy 389.251209 -292.826652)
			(xy 389.213088 -292.795527) (xy 389.180453 -292.75869) (xy 389.15415 -292.717094) (xy 389.134859 -292.671818)
			(xy 389.123082 -292.624034) (xy 389.119122 -292.57498) (xy 388.780269 -292.57498) (xy 388.779779 -292.599333)
			(xy 388.771884 -292.64791) (xy 388.7563 -292.694591) (xy 388.733429 -292.738168) (xy 388.703864 -292.777512)
			(xy 388.668371 -292.811604) (xy 388.627868 -292.83956) (xy 388.583406 -292.860658) (xy 388.536135 -292.87435)
			(xy 388.48728 -292.880282) (xy 388.438105 -292.878301) (xy 388.389886 -292.868457) (xy 388.34387 -292.851005)
			(xy 388.301249 -292.826398) (xy 388.263128 -292.795273) (xy 388.230493 -292.758436) (xy 388.20419 -292.71684)
			(xy 388.184899 -292.671564) (xy 388.173122 -292.62378) (xy 388.169162 -292.574726) (xy 387.830314 -292.574726)
			(xy 387.829819 -292.599333) (xy 387.821924 -292.64791) (xy 387.80634 -292.694591) (xy 387.783469 -292.738168)
			(xy 387.753904 -292.777512) (xy 387.718411 -292.811604) (xy 387.677908 -292.83956) (xy 387.633446 -292.860658)
			(xy 387.586175 -292.87435) (xy 387.53732 -292.880282) (xy 387.488145 -292.878301) (xy 387.439926 -292.868457)
			(xy 387.39391 -292.851005) (xy 387.351289 -292.826398) (xy 387.313168 -292.795273) (xy 387.280533 -292.758436)
			(xy 387.25423 -292.71684) (xy 387.234939 -292.671564) (xy 387.223162 -292.62378) (xy 387.219202 -292.574726)
			(xy 386.880349 -292.574726) (xy 386.880354 -292.57498) (xy 386.879859 -292.599587) (xy 386.871964 -292.648164)
			(xy 386.85638 -292.694845) (xy 386.833509 -292.738422) (xy 386.803944 -292.777766) (xy 386.768451 -292.811858)
			(xy 386.727948 -292.839814) (xy 386.683486 -292.860912) (xy 386.636215 -292.874604) (xy 386.58736 -292.880536)
			(xy 386.538185 -292.878555) (xy 386.489966 -292.868711) (xy 386.44395 -292.851259) (xy 386.401329 -292.826652)
			(xy 386.363208 -292.795527) (xy 386.330573 -292.75869) (xy 386.30427 -292.717094) (xy 386.284979 -292.671818)
			(xy 386.273202 -292.624034) (xy 386.269242 -292.57498) (xy 385.93014 -292.57498) (xy 385.929645 -292.599587)
			(xy 385.92175 -292.648164) (xy 385.906166 -292.694845) (xy 385.883295 -292.738422) (xy 385.85373 -292.777766)
			(xy 385.818237 -292.811858) (xy 385.777734 -292.839814) (xy 385.733272 -292.860912) (xy 385.686001 -292.874604)
			(xy 385.637146 -292.880536) (xy 385.587971 -292.878555) (xy 385.539752 -292.868711) (xy 385.493736 -292.851259)
			(xy 385.451115 -292.826652) (xy 385.412994 -292.795527) (xy 385.380359 -292.75869) (xy 385.354056 -292.717094)
			(xy 385.334765 -292.671818) (xy 385.322988 -292.624034) (xy 385.319028 -292.57498) (xy 384.98018 -292.57498)
			(xy 384.979685 -292.599587) (xy 384.97179 -292.648164) (xy 384.956206 -292.694845) (xy 384.933335 -292.738422)
			(xy 384.90377 -292.777766) (xy 384.868277 -292.811858) (xy 384.827774 -292.839814) (xy 384.783312 -292.860912)
			(xy 384.736041 -292.874604) (xy 384.687186 -292.880536) (xy 384.638011 -292.878555) (xy 384.589792 -292.868711)
			(xy 384.543776 -292.851259) (xy 384.501155 -292.826652) (xy 384.463034 -292.795527) (xy 384.430399 -292.75869)
			(xy 384.404096 -292.717094) (xy 384.384805 -292.671818) (xy 384.373028 -292.624034) (xy 384.369068 -292.57498)
			(xy 380.377831 -292.57498) (xy 380.388901 -292.59922) (xy 380.404256 -292.651515) (xy 380.412012 -292.705463)
			(xy 380.412498 -292.732714) (xy 380.411971 -292.762097) (xy 380.402938 -292.820164) (xy 380.385103 -292.876159)
			(xy 380.358889 -292.928754) (xy 380.324916 -292.976705) (xy 380.283989 -293.018876) (xy 380.26086 -293.037006)
			(xy 380.251462 -293.044372) (xy 380.241048 -293.064946) (xy 380.239524 -293.168832) (xy 380.24943 -293.189914)
			(xy 380.258574 -293.19728) (xy 380.280389 -293.215524) (xy 380.318933 -293.257334) (xy 380.350844 -293.304401)
			(xy 380.375417 -293.355684) (xy 380.392107 -293.410045) (xy 380.400545 -293.466281) (xy 380.401068 -293.494714)
			(xy 381.034542 -293.494714) (xy 381.038613 -293.439092) (xy 381.050739 -293.384655) (xy 381.070662 -293.332564)
			(xy 381.097958 -293.283929) (xy 381.132044 -293.239786) (xy 381.172193 -293.201077) (xy 381.217551 -293.168626)
			(xy 381.267151 -293.143125) (xy 381.319935 -293.125118) (xy 381.374778 -293.114988) (xy 381.430512 -293.112951)
			(xy 381.485949 -293.119051) (xy 381.539906 -293.133157) (xy 381.591235 -293.154969) (xy 381.638841 -293.184023)
			(xy 381.681709 -293.219698) (xy 381.718926 -293.261235) (xy 381.749699 -293.307748) (xy 381.773371 -293.358245)
			(xy 381.789439 -293.411652) (xy 381.797559 -293.466828) (xy 381.798068 -293.494714) (xy 381.921002 -293.494714)
			(xy 381.925073 -293.439092) (xy 381.937199 -293.384655) (xy 381.957122 -293.332564) (xy 381.984418 -293.283929)
			(xy 382.018504 -293.239786) (xy 382.058653 -293.201077) (xy 382.104011 -293.168626) (xy 382.153611 -293.143125)
			(xy 382.206395 -293.125118) (xy 382.261238 -293.114988) (xy 382.316972 -293.112951) (xy 382.372409 -293.119051)
			(xy 382.426366 -293.133157) (xy 382.477695 -293.154969) (xy 382.525301 -293.184023) (xy 382.568169 -293.219698)
			(xy 382.605386 -293.261235) (xy 382.636159 -293.307748) (xy 382.659831 -293.358245) (xy 382.675899 -293.411652)
			(xy 382.684019 -293.466828) (xy 382.684528 -293.494714) (xy 382.684019 -293.5226) (xy 382.683675 -293.52494)
			(xy 384.369068 -293.52494) (xy 384.373028 -293.475886) (xy 384.384805 -293.428102) (xy 384.404096 -293.382826)
			(xy 384.430399 -293.34123) (xy 384.463034 -293.304393) (xy 384.501155 -293.273268) (xy 384.543776 -293.248661)
			(xy 384.589792 -293.231209) (xy 384.638011 -293.221365) (xy 384.687186 -293.219384) (xy 384.736041 -293.225316)
			(xy 384.783312 -293.239008) (xy 384.827774 -293.260106) (xy 384.868277 -293.288062) (xy 384.90377 -293.322154)
			(xy 384.933335 -293.361498) (xy 384.956206 -293.405075) (xy 384.97179 -293.451756) (xy 384.979685 -293.500333)
			(xy 384.98018 -293.52494) (xy 385.319028 -293.52494) (xy 385.322988 -293.475886) (xy 385.334765 -293.428102)
			(xy 385.354056 -293.382826) (xy 385.380359 -293.34123) (xy 385.412994 -293.304393) (xy 385.451115 -293.273268)
			(xy 385.493736 -293.248661) (xy 385.539752 -293.231209) (xy 385.587971 -293.221365) (xy 385.637146 -293.219384)
			(xy 385.686001 -293.225316) (xy 385.733272 -293.239008) (xy 385.777734 -293.260106) (xy 385.818237 -293.288062)
			(xy 385.85373 -293.322154) (xy 385.883295 -293.361498) (xy 385.906166 -293.405075) (xy 385.92175 -293.451756)
			(xy 385.929645 -293.500333) (xy 385.93014 -293.52494) (xy 386.269242 -293.52494) (xy 386.273202 -293.475886)
			(xy 386.284979 -293.428102) (xy 386.30427 -293.382826) (xy 386.330573 -293.34123) (xy 386.363208 -293.304393)
			(xy 386.401329 -293.273268) (xy 386.44395 -293.248661) (xy 386.489966 -293.231209) (xy 386.538185 -293.221365)
			(xy 386.58736 -293.219384) (xy 386.636215 -293.225316) (xy 386.683486 -293.239008) (xy 386.727948 -293.260106)
			(xy 386.768451 -293.288062) (xy 386.803944 -293.322154) (xy 386.833509 -293.361498) (xy 386.85638 -293.405075)
			(xy 386.871964 -293.451756) (xy 386.879859 -293.500333) (xy 386.880354 -293.52494) (xy 387.219202 -293.52494)
			(xy 387.223162 -293.475886) (xy 387.234939 -293.428102) (xy 387.25423 -293.382826) (xy 387.280533 -293.34123)
			(xy 387.313168 -293.304393) (xy 387.351289 -293.273268) (xy 387.39391 -293.248661) (xy 387.439926 -293.231209)
			(xy 387.488145 -293.221365) (xy 387.53732 -293.219384) (xy 387.586175 -293.225316) (xy 387.633446 -293.239008)
			(xy 387.677908 -293.260106) (xy 387.718411 -293.288062) (xy 387.753904 -293.322154) (xy 387.783469 -293.361498)
			(xy 387.80634 -293.405075) (xy 387.821924 -293.451756) (xy 387.829819 -293.500333) (xy 387.830314 -293.52494)
			(xy 388.169162 -293.52494) (xy 388.173122 -293.475886) (xy 388.184899 -293.428102) (xy 388.20419 -293.382826)
			(xy 388.230493 -293.34123) (xy 388.263128 -293.304393) (xy 388.301249 -293.273268) (xy 388.34387 -293.248661)
			(xy 388.389886 -293.231209) (xy 388.438105 -293.221365) (xy 388.48728 -293.219384) (xy 388.536135 -293.225316)
			(xy 388.583406 -293.239008) (xy 388.627868 -293.260106) (xy 388.668371 -293.288062) (xy 388.703864 -293.322154)
			(xy 388.733429 -293.361498) (xy 388.7563 -293.405075) (xy 388.771884 -293.451756) (xy 388.779779 -293.500333)
			(xy 388.780274 -293.52494) (xy 389.119122 -293.52494) (xy 389.123082 -293.475886) (xy 389.134859 -293.428102)
			(xy 389.15415 -293.382826) (xy 389.180453 -293.34123) (xy 389.213088 -293.304393) (xy 389.251209 -293.273268)
			(xy 389.29383 -293.248661) (xy 389.339846 -293.231209) (xy 389.388065 -293.221365) (xy 389.43724 -293.219384)
			(xy 389.486095 -293.225316) (xy 389.533366 -293.239008) (xy 389.577828 -293.260106) (xy 389.618331 -293.288062)
			(xy 389.653824 -293.322154) (xy 389.683389 -293.361498) (xy 389.70626 -293.405075) (xy 389.721844 -293.451756)
			(xy 389.729739 -293.500333) (xy 389.730234 -293.52494) (xy 390.069082 -293.52494) (xy 390.073042 -293.475886)
			(xy 390.084819 -293.428102) (xy 390.10411 -293.382826) (xy 390.130413 -293.34123) (xy 390.163048 -293.304393)
			(xy 390.201169 -293.273268) (xy 390.24379 -293.248661) (xy 390.289806 -293.231209) (xy 390.338025 -293.221365)
			(xy 390.3872 -293.219384) (xy 390.436055 -293.225316) (xy 390.483326 -293.239008) (xy 390.527788 -293.260106)
			(xy 390.568291 -293.288062) (xy 390.603784 -293.322154) (xy 390.633349 -293.361498) (xy 390.65622 -293.405075)
			(xy 390.671804 -293.451756) (xy 390.679699 -293.500333) (xy 390.680194 -293.52494) (xy 390.679699 -293.549547)
			(xy 390.679367 -293.551589) (xy 390.969236 -293.551589) (xy 390.969236 -293.498291) (xy 390.977179 -293.445587)
			(xy 390.992889 -293.394657) (xy 391.016015 -293.346636) (xy 391.046039 -293.302599) (xy 391.082291 -293.263528)
			(xy 391.123962 -293.230297) (xy 391.17012 -293.203648) (xy 391.219734 -293.184176) (xy 391.271696 -293.172316)
			(xy 391.324846 -293.168333) (xy 391.377996 -293.172316) (xy 391.429958 -293.184176) (xy 391.479572 -293.203648)
			(xy 391.52573 -293.230297) (xy 391.567401 -293.263528) (xy 391.603653 -293.302599) (xy 391.633677 -293.346636)
			(xy 391.656803 -293.394657) (xy 391.672513 -293.445587) (xy 391.680456 -293.498291) (xy 391.680954 -293.52494)
			(xy 391.969002 -293.52494) (xy 391.972962 -293.475886) (xy 391.984739 -293.428102) (xy 392.00403 -293.382826)
			(xy 392.030333 -293.34123) (xy 392.062968 -293.304393) (xy 392.101089 -293.273268) (xy 392.14371 -293.248661)
			(xy 392.189726 -293.231209) (xy 392.237945 -293.221365) (xy 392.28712 -293.219384) (xy 392.335975 -293.225316)
			(xy 392.383246 -293.239008) (xy 392.427708 -293.260106) (xy 392.468211 -293.288062) (xy 392.503704 -293.322154)
			(xy 392.533269 -293.361498) (xy 392.55614 -293.405075) (xy 392.571724 -293.451756) (xy 392.579619 -293.500333)
			(xy 392.580114 -293.52494) (xy 393.869176 -293.52494) (xy 393.873136 -293.475886) (xy 393.884913 -293.428102)
			(xy 393.904204 -293.382826) (xy 393.930507 -293.34123) (xy 393.963142 -293.304393) (xy 394.001263 -293.273268)
			(xy 394.043884 -293.248661) (xy 394.0899 -293.231209) (xy 394.138119 -293.221365) (xy 394.187294 -293.219384)
			(xy 394.236149 -293.225316) (xy 394.28342 -293.239008) (xy 394.327882 -293.260106) (xy 394.368385 -293.288062)
			(xy 394.403878 -293.322154) (xy 394.433443 -293.361498) (xy 394.456314 -293.405075) (xy 394.471898 -293.451756)
			(xy 394.479793 -293.500333) (xy 394.480288 -293.52494) (xy 395.769096 -293.52494) (xy 395.773056 -293.475886)
			(xy 395.784833 -293.428102) (xy 395.804124 -293.382826) (xy 395.830427 -293.34123) (xy 395.863062 -293.304393)
			(xy 395.901183 -293.273268) (xy 395.943804 -293.248661) (xy 395.98982 -293.231209) (xy 396.038039 -293.221365)
			(xy 396.087214 -293.219384) (xy 396.136069 -293.225316) (xy 396.18334 -293.239008) (xy 396.227802 -293.260106)
			(xy 396.268305 -293.288062) (xy 396.303798 -293.322154) (xy 396.333363 -293.361498) (xy 396.356234 -293.405075)
			(xy 396.371818 -293.451756) (xy 396.379713 -293.500333) (xy 396.380208 -293.52494) (xy 396.719056 -293.52494)
			(xy 396.723016 -293.475886) (xy 396.734793 -293.428102) (xy 396.754084 -293.382826) (xy 396.780387 -293.34123)
			(xy 396.813022 -293.304393) (xy 396.851143 -293.273268) (xy 396.893764 -293.248661) (xy 396.93978 -293.231209)
			(xy 396.987999 -293.221365) (xy 397.037174 -293.219384) (xy 397.086029 -293.225316) (xy 397.1333 -293.239008)
			(xy 397.177762 -293.260106) (xy 397.218265 -293.288062) (xy 397.253758 -293.322154) (xy 397.283323 -293.361498)
			(xy 397.306194 -293.405075) (xy 397.321778 -293.451756) (xy 397.329673 -293.500333) (xy 397.330168 -293.52494)
			(xy 398.61923 -293.52494) (xy 398.62319 -293.475886) (xy 398.634967 -293.428102) (xy 398.654258 -293.382826)
			(xy 398.680561 -293.34123) (xy 398.713196 -293.304393) (xy 398.751317 -293.273268) (xy 398.793938 -293.248661)
			(xy 398.839954 -293.231209) (xy 398.888173 -293.221365) (xy 398.937348 -293.219384) (xy 398.986203 -293.225316)
			(xy 399.033474 -293.239008) (xy 399.077936 -293.260106) (xy 399.118439 -293.288062) (xy 399.153932 -293.322154)
			(xy 399.183497 -293.361498) (xy 399.206368 -293.405075) (xy 399.221952 -293.451756) (xy 399.229847 -293.500333)
			(xy 399.230342 -293.52494) (xy 400.51915 -293.52494) (xy 400.52311 -293.475886) (xy 400.534887 -293.428102)
			(xy 400.554178 -293.382826) (xy 400.580481 -293.34123) (xy 400.613116 -293.304393) (xy 400.651237 -293.273268)
			(xy 400.693858 -293.248661) (xy 400.739874 -293.231209) (xy 400.788093 -293.221365) (xy 400.837268 -293.219384)
			(xy 400.886123 -293.225316) (xy 400.933394 -293.239008) (xy 400.977856 -293.260106) (xy 401.018359 -293.288062)
			(xy 401.053852 -293.322154) (xy 401.083417 -293.361498) (xy 401.106288 -293.405075) (xy 401.121872 -293.451756)
			(xy 401.129767 -293.500333) (xy 401.130262 -293.52494) (xy 402.41907 -293.52494) (xy 402.42303 -293.475886)
			(xy 402.434807 -293.428102) (xy 402.454098 -293.382826) (xy 402.480401 -293.34123) (xy 402.513036 -293.304393)
			(xy 402.551157 -293.273268) (xy 402.593778 -293.248661) (xy 402.639794 -293.231209) (xy 402.688013 -293.221365)
			(xy 402.737188 -293.219384) (xy 402.786043 -293.225316) (xy 402.833314 -293.239008) (xy 402.877776 -293.260106)
			(xy 402.918279 -293.288062) (xy 402.953772 -293.322154) (xy 402.983337 -293.361498) (xy 403.006208 -293.405075)
			(xy 403.021792 -293.451756) (xy 403.029687 -293.500333) (xy 403.030182 -293.52494) (xy 404.31899 -293.52494)
			(xy 404.32295 -293.475886) (xy 404.334727 -293.428102) (xy 404.354018 -293.382826) (xy 404.380321 -293.34123)
			(xy 404.412956 -293.304393) (xy 404.451077 -293.273268) (xy 404.493698 -293.248661) (xy 404.539714 -293.231209)
			(xy 404.587933 -293.221365) (xy 404.637108 -293.219384) (xy 404.685963 -293.225316) (xy 404.733234 -293.239008)
			(xy 404.777696 -293.260106) (xy 404.818199 -293.288062) (xy 404.853692 -293.322154) (xy 404.883257 -293.361498)
			(xy 404.906128 -293.405075) (xy 404.921712 -293.451756) (xy 404.929607 -293.500333) (xy 404.930102 -293.52494)
			(xy 406.219164 -293.52494) (xy 406.223124 -293.475886) (xy 406.234901 -293.428102) (xy 406.254192 -293.382826)
			(xy 406.280495 -293.34123) (xy 406.31313 -293.304393) (xy 406.351251 -293.273268) (xy 406.393872 -293.248661)
			(xy 406.439888 -293.231209) (xy 406.488107 -293.221365) (xy 406.537282 -293.219384) (xy 406.586137 -293.225316)
			(xy 406.633408 -293.239008) (xy 406.67787 -293.260106) (xy 406.718373 -293.288062) (xy 406.753866 -293.322154)
			(xy 406.783431 -293.361498) (xy 406.806302 -293.405075) (xy 406.821886 -293.451756) (xy 406.829781 -293.500333)
			(xy 406.830276 -293.52494) (xy 409.069044 -293.52494) (xy 409.073004 -293.475886) (xy 409.084781 -293.428102)
			(xy 409.104072 -293.382826) (xy 409.130375 -293.34123) (xy 409.16301 -293.304393) (xy 409.201131 -293.273268)
			(xy 409.243752 -293.248661) (xy 409.289768 -293.231209) (xy 409.337987 -293.221365) (xy 409.387162 -293.219384)
			(xy 409.436017 -293.225316) (xy 409.483288 -293.239008) (xy 409.52775 -293.260106) (xy 409.568253 -293.288062)
			(xy 409.603746 -293.322154) (xy 409.633311 -293.361498) (xy 409.656182 -293.405075) (xy 409.671766 -293.451756)
			(xy 409.679661 -293.500333) (xy 409.680156 -293.52494) (xy 410.969218 -293.52494) (xy 410.973178 -293.475886)
			(xy 410.984955 -293.428102) (xy 411.004246 -293.382826) (xy 411.030549 -293.34123) (xy 411.063184 -293.304393)
			(xy 411.101305 -293.273268) (xy 411.143926 -293.248661) (xy 411.189942 -293.231209) (xy 411.238161 -293.221365)
			(xy 411.287336 -293.219384) (xy 411.336191 -293.225316) (xy 411.383462 -293.239008) (xy 411.427924 -293.260106)
			(xy 411.468427 -293.288062) (xy 411.50392 -293.322154) (xy 411.533485 -293.361498) (xy 411.556356 -293.405075)
			(xy 411.57194 -293.451756) (xy 411.579835 -293.500333) (xy 411.58033 -293.52494) (xy 412.869138 -293.52494)
			(xy 412.873098 -293.475886) (xy 412.884875 -293.428102) (xy 412.904166 -293.382826) (xy 412.930469 -293.34123)
			(xy 412.963104 -293.304393) (xy 413.001225 -293.273268) (xy 413.043846 -293.248661) (xy 413.089862 -293.231209)
			(xy 413.138081 -293.221365) (xy 413.187256 -293.219384) (xy 413.236111 -293.225316) (xy 413.283382 -293.239008)
			(xy 413.327844 -293.260106) (xy 413.368347 -293.288062) (xy 413.40384 -293.322154) (xy 413.433405 -293.361498)
			(xy 413.456276 -293.405075) (xy 413.47186 -293.451756) (xy 413.479755 -293.500333) (xy 413.48025 -293.52494)
			(xy 414.769058 -293.52494) (xy 414.773018 -293.475886) (xy 414.784795 -293.428102) (xy 414.804086 -293.382826)
			(xy 414.830389 -293.34123) (xy 414.863024 -293.304393) (xy 414.901145 -293.273268) (xy 414.943766 -293.248661)
			(xy 414.989782 -293.231209) (xy 415.038001 -293.221365) (xy 415.087176 -293.219384) (xy 415.136031 -293.225316)
			(xy 415.183302 -293.239008) (xy 415.227764 -293.260106) (xy 415.268267 -293.288062) (xy 415.30376 -293.322154)
			(xy 415.333325 -293.361498) (xy 415.356196 -293.405075) (xy 415.37178 -293.451756) (xy 415.379675 -293.500333)
			(xy 415.38017 -293.52494) (xy 415.379675 -293.549547) (xy 415.37178 -293.598124) (xy 415.356196 -293.644805)
			(xy 415.333325 -293.688382) (xy 415.30376 -293.727726) (xy 415.268267 -293.761818) (xy 415.227764 -293.789774)
			(xy 415.183302 -293.810872) (xy 415.136031 -293.824564) (xy 415.087176 -293.830496) (xy 415.038001 -293.828515)
			(xy 414.989782 -293.818671) (xy 414.943766 -293.801219) (xy 414.901145 -293.776612) (xy 414.863024 -293.745487)
			(xy 414.830389 -293.70865) (xy 414.804086 -293.667054) (xy 414.784795 -293.621778) (xy 414.773018 -293.573994)
			(xy 414.769058 -293.52494) (xy 413.48025 -293.52494) (xy 413.479755 -293.549547) (xy 413.47186 -293.598124)
			(xy 413.456276 -293.644805) (xy 413.433405 -293.688382) (xy 413.40384 -293.727726) (xy 413.368347 -293.761818)
			(xy 413.327844 -293.789774) (xy 413.283382 -293.810872) (xy 413.236111 -293.824564) (xy 413.187256 -293.830496)
			(xy 413.138081 -293.828515) (xy 413.089862 -293.818671) (xy 413.043846 -293.801219) (xy 413.001225 -293.776612)
			(xy 412.963104 -293.745487) (xy 412.930469 -293.70865) (xy 412.904166 -293.667054) (xy 412.884875 -293.621778)
			(xy 412.873098 -293.573994) (xy 412.869138 -293.52494) (xy 411.58033 -293.52494) (xy 411.579835 -293.549547)
			(xy 411.57194 -293.598124) (xy 411.556356 -293.644805) (xy 411.533485 -293.688382) (xy 411.50392 -293.727726)
			(xy 411.468427 -293.761818) (xy 411.427924 -293.789774) (xy 411.383462 -293.810872) (xy 411.336191 -293.824564)
			(xy 411.287336 -293.830496) (xy 411.238161 -293.828515) (xy 411.189942 -293.818671) (xy 411.143926 -293.801219)
			(xy 411.101305 -293.776612) (xy 411.063184 -293.745487) (xy 411.030549 -293.70865) (xy 411.004246 -293.667054)
			(xy 410.984955 -293.621778) (xy 410.973178 -293.573994) (xy 410.969218 -293.52494) (xy 409.680156 -293.52494)
			(xy 409.679661 -293.549547) (xy 409.671766 -293.598124) (xy 409.656182 -293.644805) (xy 409.633311 -293.688382)
			(xy 409.603746 -293.727726) (xy 409.568253 -293.761818) (xy 409.52775 -293.789774) (xy 409.483288 -293.810872)
			(xy 409.436017 -293.824564) (xy 409.387162 -293.830496) (xy 409.337987 -293.828515) (xy 409.289768 -293.818671)
			(xy 409.243752 -293.801219) (xy 409.201131 -293.776612) (xy 409.16301 -293.745487) (xy 409.130375 -293.70865)
			(xy 409.104072 -293.667054) (xy 409.084781 -293.621778) (xy 409.073004 -293.573994) (xy 409.069044 -293.52494)
			(xy 406.830276 -293.52494) (xy 406.829781 -293.549547) (xy 406.821886 -293.598124) (xy 406.806302 -293.644805)
			(xy 406.783431 -293.688382) (xy 406.753866 -293.727726) (xy 406.718373 -293.761818) (xy 406.67787 -293.789774)
			(xy 406.633408 -293.810872) (xy 406.586137 -293.824564) (xy 406.537282 -293.830496) (xy 406.488107 -293.828515)
			(xy 406.439888 -293.818671) (xy 406.393872 -293.801219) (xy 406.351251 -293.776612) (xy 406.31313 -293.745487)
			(xy 406.280495 -293.70865) (xy 406.254192 -293.667054) (xy 406.234901 -293.621778) (xy 406.223124 -293.573994)
			(xy 406.219164 -293.52494) (xy 404.930102 -293.52494) (xy 404.929607 -293.549547) (xy 404.921712 -293.598124)
			(xy 404.906128 -293.644805) (xy 404.883257 -293.688382) (xy 404.853692 -293.727726) (xy 404.818199 -293.761818)
			(xy 404.777696 -293.789774) (xy 404.733234 -293.810872) (xy 404.685963 -293.824564) (xy 404.637108 -293.830496)
			(xy 404.587933 -293.828515) (xy 404.539714 -293.818671) (xy 404.493698 -293.801219) (xy 404.451077 -293.776612)
			(xy 404.412956 -293.745487) (xy 404.380321 -293.70865) (xy 404.354018 -293.667054) (xy 404.334727 -293.621778)
			(xy 404.32295 -293.573994) (xy 404.31899 -293.52494) (xy 403.030182 -293.52494) (xy 403.029687 -293.549547)
			(xy 403.021792 -293.598124) (xy 403.006208 -293.644805) (xy 402.983337 -293.688382) (xy 402.953772 -293.727726)
			(xy 402.918279 -293.761818) (xy 402.877776 -293.789774) (xy 402.833314 -293.810872) (xy 402.786043 -293.824564)
			(xy 402.737188 -293.830496) (xy 402.688013 -293.828515) (xy 402.639794 -293.818671) (xy 402.593778 -293.801219)
			(xy 402.551157 -293.776612) (xy 402.513036 -293.745487) (xy 402.480401 -293.70865) (xy 402.454098 -293.667054)
			(xy 402.434807 -293.621778) (xy 402.42303 -293.573994) (xy 402.41907 -293.52494) (xy 401.130262 -293.52494)
			(xy 401.129767 -293.549547) (xy 401.121872 -293.598124) (xy 401.106288 -293.644805) (xy 401.083417 -293.688382)
			(xy 401.053852 -293.727726) (xy 401.018359 -293.761818) (xy 400.977856 -293.789774) (xy 400.933394 -293.810872)
			(xy 400.886123 -293.824564) (xy 400.837268 -293.830496) (xy 400.788093 -293.828515) (xy 400.739874 -293.818671)
			(xy 400.693858 -293.801219) (xy 400.651237 -293.776612) (xy 400.613116 -293.745487) (xy 400.580481 -293.70865)
			(xy 400.554178 -293.667054) (xy 400.534887 -293.621778) (xy 400.52311 -293.573994) (xy 400.51915 -293.52494)
			(xy 399.230342 -293.52494) (xy 399.229847 -293.549547) (xy 399.221952 -293.598124) (xy 399.206368 -293.644805)
			(xy 399.183497 -293.688382) (xy 399.153932 -293.727726) (xy 399.118439 -293.761818) (xy 399.077936 -293.789774)
			(xy 399.033474 -293.810872) (xy 398.986203 -293.824564) (xy 398.937348 -293.830496) (xy 398.888173 -293.828515)
			(xy 398.839954 -293.818671) (xy 398.793938 -293.801219) (xy 398.751317 -293.776612) (xy 398.713196 -293.745487)
			(xy 398.680561 -293.70865) (xy 398.654258 -293.667054) (xy 398.634967 -293.621778) (xy 398.62319 -293.573994)
			(xy 398.61923 -293.52494) (xy 397.330168 -293.52494) (xy 397.329673 -293.549547) (xy 397.321778 -293.598124)
			(xy 397.306194 -293.644805) (xy 397.283323 -293.688382) (xy 397.253758 -293.727726) (xy 397.218265 -293.761818)
			(xy 397.177762 -293.789774) (xy 397.1333 -293.810872) (xy 397.086029 -293.824564) (xy 397.037174 -293.830496)
			(xy 396.987999 -293.828515) (xy 396.93978 -293.818671) (xy 396.893764 -293.801219) (xy 396.851143 -293.776612)
			(xy 396.813022 -293.745487) (xy 396.780387 -293.70865) (xy 396.754084 -293.667054) (xy 396.734793 -293.621778)
			(xy 396.723016 -293.573994) (xy 396.719056 -293.52494) (xy 396.380208 -293.52494) (xy 396.379713 -293.549547)
			(xy 396.371818 -293.598124) (xy 396.356234 -293.644805) (xy 396.333363 -293.688382) (xy 396.303798 -293.727726)
			(xy 396.268305 -293.761818) (xy 396.227802 -293.789774) (xy 396.18334 -293.810872) (xy 396.136069 -293.824564)
			(xy 396.087214 -293.830496) (xy 396.038039 -293.828515) (xy 395.98982 -293.818671) (xy 395.943804 -293.801219)
			(xy 395.901183 -293.776612) (xy 395.863062 -293.745487) (xy 395.830427 -293.70865) (xy 395.804124 -293.667054)
			(xy 395.784833 -293.621778) (xy 395.773056 -293.573994) (xy 395.769096 -293.52494) (xy 394.480288 -293.52494)
			(xy 394.479793 -293.549547) (xy 394.471898 -293.598124) (xy 394.456314 -293.644805) (xy 394.433443 -293.688382)
			(xy 394.403878 -293.727726) (xy 394.368385 -293.761818) (xy 394.327882 -293.789774) (xy 394.28342 -293.810872)
			(xy 394.236149 -293.824564) (xy 394.187294 -293.830496) (xy 394.138119 -293.828515) (xy 394.0899 -293.818671)
			(xy 394.043884 -293.801219) (xy 394.001263 -293.776612) (xy 393.963142 -293.745487) (xy 393.930507 -293.70865)
			(xy 393.904204 -293.667054) (xy 393.884913 -293.621778) (xy 393.873136 -293.573994) (xy 393.869176 -293.52494)
			(xy 392.580114 -293.52494) (xy 392.579619 -293.549547) (xy 392.571724 -293.598124) (xy 392.55614 -293.644805)
			(xy 392.533269 -293.688382) (xy 392.503704 -293.727726) (xy 392.468211 -293.761818) (xy 392.427708 -293.789774)
			(xy 392.383246 -293.810872) (xy 392.335975 -293.824564) (xy 392.28712 -293.830496) (xy 392.237945 -293.828515)
			(xy 392.189726 -293.818671) (xy 392.14371 -293.801219) (xy 392.101089 -293.776612) (xy 392.062968 -293.745487)
			(xy 392.030333 -293.70865) (xy 392.00403 -293.667054) (xy 391.984739 -293.621778) (xy 391.972962 -293.573994)
			(xy 391.969002 -293.52494) (xy 391.680954 -293.52494) (xy 391.680456 -293.551589) (xy 391.672513 -293.604293)
			(xy 391.656803 -293.655223) (xy 391.633677 -293.703244) (xy 391.603653 -293.747281) (xy 391.567401 -293.786352)
			(xy 391.52573 -293.819583) (xy 391.479572 -293.846232) (xy 391.429958 -293.865704) (xy 391.377996 -293.877564)
			(xy 391.324846 -293.881548) (xy 391.271696 -293.877564) (xy 391.219734 -293.865704) (xy 391.17012 -293.846232)
			(xy 391.123962 -293.819583) (xy 391.082291 -293.786352) (xy 391.046039 -293.747281) (xy 391.016015 -293.703244)
			(xy 390.992889 -293.655223) (xy 390.977179 -293.604293) (xy 390.969236 -293.551589) (xy 390.679367 -293.551589)
			(xy 390.671804 -293.598124) (xy 390.65622 -293.644805) (xy 390.633349 -293.688382) (xy 390.603784 -293.727726)
			(xy 390.568291 -293.761818) (xy 390.527788 -293.789774) (xy 390.483326 -293.810872) (xy 390.436055 -293.824564)
			(xy 390.3872 -293.830496) (xy 390.338025 -293.828515) (xy 390.289806 -293.818671) (xy 390.24379 -293.801219)
			(xy 390.201169 -293.776612) (xy 390.163048 -293.745487) (xy 390.130413 -293.70865) (xy 390.10411 -293.667054)
			(xy 390.084819 -293.621778) (xy 390.073042 -293.573994) (xy 390.069082 -293.52494) (xy 389.730234 -293.52494)
			(xy 389.729739 -293.549547) (xy 389.721844 -293.598124) (xy 389.70626 -293.644805) (xy 389.683389 -293.688382)
			(xy 389.653824 -293.727726) (xy 389.618331 -293.761818) (xy 389.577828 -293.789774) (xy 389.533366 -293.810872)
			(xy 389.486095 -293.824564) (xy 389.43724 -293.830496) (xy 389.388065 -293.828515) (xy 389.339846 -293.818671)
			(xy 389.29383 -293.801219) (xy 389.251209 -293.776612) (xy 389.213088 -293.745487) (xy 389.180453 -293.70865)
			(xy 389.15415 -293.667054) (xy 389.134859 -293.621778) (xy 389.123082 -293.573994) (xy 389.119122 -293.52494)
			(xy 388.780274 -293.52494) (xy 388.779779 -293.549547) (xy 388.771884 -293.598124) (xy 388.7563 -293.644805)
			(xy 388.733429 -293.688382) (xy 388.703864 -293.727726) (xy 388.668371 -293.761818) (xy 388.627868 -293.789774)
			(xy 388.583406 -293.810872) (xy 388.536135 -293.824564) (xy 388.48728 -293.830496) (xy 388.438105 -293.828515)
			(xy 388.389886 -293.818671) (xy 388.34387 -293.801219) (xy 388.301249 -293.776612) (xy 388.263128 -293.745487)
			(xy 388.230493 -293.70865) (xy 388.20419 -293.667054) (xy 388.184899 -293.621778) (xy 388.173122 -293.573994)
			(xy 388.169162 -293.52494) (xy 387.830314 -293.52494) (xy 387.829819 -293.549547) (xy 387.821924 -293.598124)
			(xy 387.80634 -293.644805) (xy 387.783469 -293.688382) (xy 387.753904 -293.727726) (xy 387.718411 -293.761818)
			(xy 387.677908 -293.789774) (xy 387.633446 -293.810872) (xy 387.586175 -293.824564) (xy 387.53732 -293.830496)
			(xy 387.488145 -293.828515) (xy 387.439926 -293.818671) (xy 387.39391 -293.801219) (xy 387.351289 -293.776612)
			(xy 387.313168 -293.745487) (xy 387.280533 -293.70865) (xy 387.25423 -293.667054) (xy 387.234939 -293.621778)
			(xy 387.223162 -293.573994) (xy 387.219202 -293.52494) (xy 386.880354 -293.52494) (xy 386.879859 -293.549547)
			(xy 386.871964 -293.598124) (xy 386.85638 -293.644805) (xy 386.833509 -293.688382) (xy 386.803944 -293.727726)
			(xy 386.768451 -293.761818) (xy 386.727948 -293.789774) (xy 386.683486 -293.810872) (xy 386.636215 -293.824564)
			(xy 386.58736 -293.830496) (xy 386.538185 -293.828515) (xy 386.489966 -293.818671) (xy 386.44395 -293.801219)
			(xy 386.401329 -293.776612) (xy 386.363208 -293.745487) (xy 386.330573 -293.70865) (xy 386.30427 -293.667054)
			(xy 386.284979 -293.621778) (xy 386.273202 -293.573994) (xy 386.269242 -293.52494) (xy 385.93014 -293.52494)
			(xy 385.929645 -293.549547) (xy 385.92175 -293.598124) (xy 385.906166 -293.644805) (xy 385.883295 -293.688382)
			(xy 385.85373 -293.727726) (xy 385.818237 -293.761818) (xy 385.777734 -293.789774) (xy 385.733272 -293.810872)
			(xy 385.686001 -293.824564) (xy 385.637146 -293.830496) (xy 385.587971 -293.828515) (xy 385.539752 -293.818671)
			(xy 385.493736 -293.801219) (xy 385.451115 -293.776612) (xy 385.412994 -293.745487) (xy 385.380359 -293.70865)
			(xy 385.354056 -293.667054) (xy 385.334765 -293.621778) (xy 385.322988 -293.573994) (xy 385.319028 -293.52494)
			(xy 384.98018 -293.52494) (xy 384.979685 -293.549547) (xy 384.97179 -293.598124) (xy 384.956206 -293.644805)
			(xy 384.933335 -293.688382) (xy 384.90377 -293.727726) (xy 384.868277 -293.761818) (xy 384.827774 -293.789774)
			(xy 384.783312 -293.810872) (xy 384.736041 -293.824564) (xy 384.687186 -293.830496) (xy 384.638011 -293.828515)
			(xy 384.589792 -293.818671) (xy 384.543776 -293.801219) (xy 384.501155 -293.776612) (xy 384.463034 -293.745487)
			(xy 384.430399 -293.70865) (xy 384.404096 -293.667054) (xy 384.384805 -293.621778) (xy 384.373028 -293.573994)
			(xy 384.369068 -293.52494) (xy 382.683675 -293.52494) (xy 382.675899 -293.577776) (xy 382.659831 -293.631183)
			(xy 382.636159 -293.68168) (xy 382.605386 -293.728193) (xy 382.568169 -293.76973) (xy 382.525301 -293.805405)
			(xy 382.477695 -293.834459) (xy 382.426366 -293.856271) (xy 382.372409 -293.870377) (xy 382.316972 -293.876477)
			(xy 382.261238 -293.87444) (xy 382.206395 -293.86431) (xy 382.153611 -293.846303) (xy 382.104011 -293.820802)
			(xy 382.058653 -293.788351) (xy 382.018504 -293.749642) (xy 381.984418 -293.705499) (xy 381.957122 -293.656864)
			(xy 381.937199 -293.604773) (xy 381.925073 -293.550336) (xy 381.921002 -293.494714) (xy 381.798068 -293.494714)
			(xy 381.797559 -293.5226) (xy 381.789439 -293.577776) (xy 381.773371 -293.631183) (xy 381.749699 -293.68168)
			(xy 381.718926 -293.728193) (xy 381.681709 -293.76973) (xy 381.638841 -293.805405) (xy 381.591235 -293.834459)
			(xy 381.539906 -293.856271) (xy 381.485949 -293.870377) (xy 381.430512 -293.876477) (xy 381.374778 -293.87444)
			(xy 381.319935 -293.86431) (xy 381.267151 -293.846303) (xy 381.217551 -293.820802) (xy 381.172193 -293.788351)
			(xy 381.132044 -293.749642) (xy 381.097958 -293.705499) (xy 381.070662 -293.656864) (xy 381.050739 -293.604773)
			(xy 381.038613 -293.550336) (xy 381.034542 -293.494714) (xy 380.401068 -293.494714) (xy 380.400582 -293.521965)
			(xy 380.392826 -293.575913) (xy 380.377471 -293.628208) (xy 380.354829 -293.677785) (xy 380.325363 -293.723635)
			(xy 380.289672 -293.764826) (xy 380.248481 -293.800517) (xy 380.202631 -293.829983) (xy 380.153054 -293.852625)
			(xy 380.100759 -293.86798) (xy 380.046811 -293.875736) (xy 379.992309 -293.875736) (xy 379.938361 -293.86798)
			(xy 379.886066 -293.852625) (xy 379.836489 -293.829983) (xy 379.790639 -293.800517) (xy 379.749448 -293.764826)
			(xy 379.713757 -293.723635) (xy 379.684291 -293.677785) (xy 379.661649 -293.628208) (xy 379.646294 -293.575913)
			(xy 379.638538 -293.521965) (xy 379.638052 -293.494714) (xy 368.27841 -293.494714) (xy 367.82248 -293.950644)
			(xy 367.815083 -293.957493) (xy 367.796484 -293.965229) (xy 367.786412 -293.96563) (xy 351.312988 -293.96563)
			(xy 351.294192 -293.97325) (xy 351.28708 -293.980616) (xy 351.046034 -294.221662) (xy 351.039194 -294.229062)
			(xy 351.031476 -294.247661) (xy 351.031048 -294.25773) (xy 351.031048 -294.630856) (xy 374.111518 -294.630856)
			(xy 374.115589 -294.575234) (xy 374.127715 -294.520797) (xy 374.147638 -294.468706) (xy 374.174934 -294.420071)
			(xy 374.20902 -294.375928) (xy 374.249169 -294.337219) (xy 374.294527 -294.304768) (xy 374.344127 -294.279267)
			(xy 374.396911 -294.26126) (xy 374.451754 -294.25113) (xy 374.507488 -294.249093) (xy 374.562925 -294.255193)
			(xy 374.616882 -294.269299) (xy 374.668211 -294.291111) (xy 374.715817 -294.320165) (xy 374.758685 -294.35584)
			(xy 374.795902 -294.397377) (xy 374.826675 -294.44389) (xy 374.850347 -294.494387) (xy 374.866415 -294.547794)
			(xy 374.874535 -294.60297) (xy 374.875044 -294.630856) (xy 375.596656 -294.630856) (xy 375.600727 -294.575234)
			(xy 375.612853 -294.520797) (xy 375.632776 -294.468706) (xy 375.660072 -294.420071) (xy 375.694158 -294.375928)
			(xy 375.734307 -294.337219) (xy 375.779665 -294.304768) (xy 375.829265 -294.279267) (xy 375.882049 -294.26126)
			(xy 375.936892 -294.25113) (xy 375.992626 -294.249093) (xy 376.048063 -294.255193) (xy 376.10202 -294.269299)
			(xy 376.153349 -294.291111) (xy 376.200955 -294.320165) (xy 376.243823 -294.35584) (xy 376.28104 -294.397377)
			(xy 376.311813 -294.44389) (xy 376.32635 -294.4749) (xy 384.369068 -294.4749) (xy 384.373028 -294.425846)
			(xy 384.384805 -294.378062) (xy 384.404096 -294.332786) (xy 384.430399 -294.29119) (xy 384.463034 -294.254353)
			(xy 384.501155 -294.223228) (xy 384.543776 -294.198621) (xy 384.589792 -294.181169) (xy 384.638011 -294.171325)
			(xy 384.687186 -294.169344) (xy 384.736041 -294.175276) (xy 384.783312 -294.188968) (xy 384.827774 -294.210066)
			(xy 384.868277 -294.238022) (xy 384.90377 -294.272114) (xy 384.933335 -294.311458) (xy 384.956206 -294.355035)
			(xy 384.97179 -294.401716) (xy 384.979685 -294.450293) (xy 384.98018 -294.4749) (xy 385.319028 -294.4749)
			(xy 385.322988 -294.425846) (xy 385.334765 -294.378062) (xy 385.354056 -294.332786) (xy 385.380359 -294.29119)
			(xy 385.412994 -294.254353) (xy 385.451115 -294.223228) (xy 385.493736 -294.198621) (xy 385.539752 -294.181169)
			(xy 385.587971 -294.171325) (xy 385.637146 -294.169344) (xy 385.686001 -294.175276) (xy 385.733272 -294.188968)
			(xy 385.777734 -294.210066) (xy 385.818237 -294.238022) (xy 385.85373 -294.272114) (xy 385.883295 -294.311458)
			(xy 385.906166 -294.355035) (xy 385.92175 -294.401716) (xy 385.929645 -294.450293) (xy 385.93014 -294.4749)
			(xy 386.269242 -294.4749) (xy 386.273202 -294.425846) (xy 386.284979 -294.378062) (xy 386.30427 -294.332786)
			(xy 386.330573 -294.29119) (xy 386.363208 -294.254353) (xy 386.401329 -294.223228) (xy 386.44395 -294.198621)
			(xy 386.489966 -294.181169) (xy 386.538185 -294.171325) (xy 386.58736 -294.169344) (xy 386.636215 -294.175276)
			(xy 386.683486 -294.188968) (xy 386.727948 -294.210066) (xy 386.768451 -294.238022) (xy 386.803944 -294.272114)
			(xy 386.833509 -294.311458) (xy 386.85638 -294.355035) (xy 386.871964 -294.401716) (xy 386.879859 -294.450293)
			(xy 386.880354 -294.4749) (xy 389.119122 -294.4749) (xy 389.123082 -294.425846) (xy 389.134859 -294.378062)
			(xy 389.15415 -294.332786) (xy 389.180453 -294.29119) (xy 389.213088 -294.254353) (xy 389.251209 -294.223228)
			(xy 389.29383 -294.198621) (xy 389.339846 -294.181169) (xy 389.388065 -294.171325) (xy 389.43724 -294.169344)
			(xy 389.486095 -294.175276) (xy 389.533366 -294.188968) (xy 389.577828 -294.210066) (xy 389.618331 -294.238022)
			(xy 389.653824 -294.272114) (xy 389.683389 -294.311458) (xy 389.70626 -294.355035) (xy 389.721844 -294.401716)
			(xy 389.729739 -294.450293) (xy 389.730234 -294.4749) (xy 389.729739 -294.499507) (xy 389.729407 -294.501549)
			(xy 390.019276 -294.501549) (xy 390.019276 -294.448251) (xy 390.027219 -294.395547) (xy 390.042929 -294.344617)
			(xy 390.066055 -294.296596) (xy 390.096079 -294.252559) (xy 390.132331 -294.213488) (xy 390.174002 -294.180257)
			(xy 390.22016 -294.153608) (xy 390.269774 -294.134136) (xy 390.321736 -294.122276) (xy 390.374886 -294.118293)
			(xy 390.428036 -294.122276) (xy 390.479998 -294.134136) (xy 390.529612 -294.153608) (xy 390.57577 -294.180257)
			(xy 390.617441 -294.213488) (xy 390.653693 -294.252559) (xy 390.683717 -294.296596) (xy 390.706843 -294.344617)
			(xy 390.722553 -294.395547) (xy 390.730496 -294.448251) (xy 390.730994 -294.4749) (xy 391.019042 -294.4749)
			(xy 391.023002 -294.425846) (xy 391.034779 -294.378062) (xy 391.05407 -294.332786) (xy 391.080373 -294.29119)
			(xy 391.113008 -294.254353) (xy 391.151129 -294.223228) (xy 391.19375 -294.198621) (xy 391.239766 -294.181169)
			(xy 391.287985 -294.171325) (xy 391.33716 -294.169344) (xy 391.386015 -294.175276) (xy 391.433286 -294.188968)
			(xy 391.477748 -294.210066) (xy 391.518251 -294.238022) (xy 391.553744 -294.272114) (xy 391.583309 -294.311458)
			(xy 391.60618 -294.355035) (xy 391.621764 -294.401716) (xy 391.629659 -294.450293) (xy 391.630154 -294.4749)
			(xy 391.969002 -294.4749) (xy 391.972962 -294.425846) (xy 391.984739 -294.378062) (xy 392.00403 -294.332786)
			(xy 392.030333 -294.29119) (xy 392.062968 -294.254353) (xy 392.101089 -294.223228) (xy 392.14371 -294.198621)
			(xy 392.189726 -294.181169) (xy 392.237945 -294.171325) (xy 392.28712 -294.169344) (xy 392.335975 -294.175276)
			(xy 392.383246 -294.188968) (xy 392.427708 -294.210066) (xy 392.468211 -294.238022) (xy 392.503704 -294.272114)
			(xy 392.533269 -294.311458) (xy 392.55614 -294.355035) (xy 392.571724 -294.401716) (xy 392.579619 -294.450293)
			(xy 392.580114 -294.4749) (xy 392.919216 -294.4749) (xy 392.923176 -294.425846) (xy 392.934953 -294.378062)
			(xy 392.954244 -294.332786) (xy 392.980547 -294.29119) (xy 393.013182 -294.254353) (xy 393.051303 -294.223228)
			(xy 393.093924 -294.198621) (xy 393.13994 -294.181169) (xy 393.188159 -294.171325) (xy 393.237334 -294.169344)
			(xy 393.286189 -294.175276) (xy 393.33346 -294.188968) (xy 393.377922 -294.210066) (xy 393.418425 -294.238022)
			(xy 393.453918 -294.272114) (xy 393.483483 -294.311458) (xy 393.506354 -294.355035) (xy 393.521938 -294.401716)
			(xy 393.529833 -294.450293) (xy 393.530328 -294.4749) (xy 393.869176 -294.4749) (xy 393.873136 -294.425846)
			(xy 393.884913 -294.378062) (xy 393.904204 -294.332786) (xy 393.930507 -294.29119) (xy 393.963142 -294.254353)
			(xy 394.001263 -294.223228) (xy 394.043884 -294.198621) (xy 394.0899 -294.181169) (xy 394.138119 -294.171325)
			(xy 394.187294 -294.169344) (xy 394.236149 -294.175276) (xy 394.28342 -294.188968) (xy 394.327882 -294.210066)
			(xy 394.368385 -294.238022) (xy 394.403878 -294.272114) (xy 394.433443 -294.311458) (xy 394.456314 -294.355035)
			(xy 394.471898 -294.401716) (xy 394.479793 -294.450293) (xy 394.480288 -294.4749) (xy 394.819136 -294.4749)
			(xy 394.823096 -294.425846) (xy 394.834873 -294.378062) (xy 394.854164 -294.332786) (xy 394.880467 -294.29119)
			(xy 394.913102 -294.254353) (xy 394.951223 -294.223228) (xy 394.993844 -294.198621) (xy 395.03986 -294.181169)
			(xy 395.088079 -294.171325) (xy 395.137254 -294.169344) (xy 395.186109 -294.175276) (xy 395.23338 -294.188968)
			(xy 395.277842 -294.210066) (xy 395.318345 -294.238022) (xy 395.353838 -294.272114) (xy 395.383403 -294.311458)
			(xy 395.406274 -294.355035) (xy 395.421858 -294.401716) (xy 395.429753 -294.450293) (xy 395.430248 -294.4749)
			(xy 395.769096 -294.4749) (xy 395.773056 -294.425846) (xy 395.784833 -294.378062) (xy 395.804124 -294.332786)
			(xy 395.830427 -294.29119) (xy 395.863062 -294.254353) (xy 395.901183 -294.223228) (xy 395.943804 -294.198621)
			(xy 395.98982 -294.181169) (xy 396.038039 -294.171325) (xy 396.087214 -294.169344) (xy 396.136069 -294.175276)
			(xy 396.18334 -294.188968) (xy 396.227802 -294.210066) (xy 396.268305 -294.238022) (xy 396.303798 -294.272114)
			(xy 396.333363 -294.311458) (xy 396.356234 -294.355035) (xy 396.371818 -294.401716) (xy 396.379713 -294.450293)
			(xy 396.380208 -294.4749) (xy 397.669016 -294.4749) (xy 397.672976 -294.425846) (xy 397.684753 -294.378062)
			(xy 397.704044 -294.332786) (xy 397.730347 -294.29119) (xy 397.762982 -294.254353) (xy 397.801103 -294.223228)
			(xy 397.843724 -294.198621) (xy 397.88974 -294.181169) (xy 397.937959 -294.171325) (xy 397.987134 -294.169344)
			(xy 398.035989 -294.175276) (xy 398.08326 -294.188968) (xy 398.127722 -294.210066) (xy 398.168225 -294.238022)
			(xy 398.203718 -294.272114) (xy 398.233283 -294.311458) (xy 398.256154 -294.355035) (xy 398.271738 -294.401716)
			(xy 398.279633 -294.450293) (xy 398.280128 -294.4749) (xy 399.56919 -294.4749) (xy 399.57315 -294.425846)
			(xy 399.584927 -294.378062) (xy 399.604218 -294.332786) (xy 399.630521 -294.29119) (xy 399.663156 -294.254353)
			(xy 399.701277 -294.223228) (xy 399.743898 -294.198621) (xy 399.789914 -294.181169) (xy 399.838133 -294.171325)
			(xy 399.887308 -294.169344) (xy 399.936163 -294.175276) (xy 399.983434 -294.188968) (xy 400.027896 -294.210066)
			(xy 400.068399 -294.238022) (xy 400.103892 -294.272114) (xy 400.133457 -294.311458) (xy 400.156328 -294.355035)
			(xy 400.171912 -294.401716) (xy 400.179807 -294.450293) (xy 400.180302 -294.4749) (xy 401.46911 -294.4749)
			(xy 401.47307 -294.425846) (xy 401.484847 -294.378062) (xy 401.504138 -294.332786) (xy 401.530441 -294.29119)
			(xy 401.563076 -294.254353) (xy 401.601197 -294.223228) (xy 401.643818 -294.198621) (xy 401.689834 -294.181169)
			(xy 401.738053 -294.171325) (xy 401.787228 -294.169344) (xy 401.836083 -294.175276) (xy 401.883354 -294.188968)
			(xy 401.927816 -294.210066) (xy 401.968319 -294.238022) (xy 402.003812 -294.272114) (xy 402.033377 -294.311458)
			(xy 402.056248 -294.355035) (xy 402.071832 -294.401716) (xy 402.079727 -294.450293) (xy 402.080222 -294.4749)
			(xy 403.36903 -294.4749) (xy 403.37299 -294.425846) (xy 403.384767 -294.378062) (xy 403.404058 -294.332786)
			(xy 403.430361 -294.29119) (xy 403.462996 -294.254353) (xy 403.501117 -294.223228) (xy 403.543738 -294.198621)
			(xy 403.589754 -294.181169) (xy 403.637973 -294.171325) (xy 403.687148 -294.169344) (xy 403.736003 -294.175276)
			(xy 403.783274 -294.188968) (xy 403.827736 -294.210066) (xy 403.868239 -294.238022) (xy 403.903732 -294.272114)
			(xy 403.933297 -294.311458) (xy 403.956168 -294.355035) (xy 403.971752 -294.401716) (xy 403.979647 -294.450293)
			(xy 403.980142 -294.4749) (xy 405.269204 -294.4749) (xy 405.273164 -294.425846) (xy 405.284941 -294.378062)
			(xy 405.304232 -294.332786) (xy 405.330535 -294.29119) (xy 405.36317 -294.254353) (xy 405.401291 -294.223228)
			(xy 405.443912 -294.198621) (xy 405.489928 -294.181169) (xy 405.538147 -294.171325) (xy 405.587322 -294.169344)
			(xy 405.636177 -294.175276) (xy 405.683448 -294.188968) (xy 405.72791 -294.210066) (xy 405.768413 -294.238022)
			(xy 405.803906 -294.272114) (xy 405.833471 -294.311458) (xy 405.856342 -294.355035) (xy 405.871926 -294.401716)
			(xy 405.879821 -294.450293) (xy 405.880316 -294.4749) (xy 408.119084 -294.4749) (xy 408.123044 -294.425846)
			(xy 408.134821 -294.378062) (xy 408.154112 -294.332786) (xy 408.180415 -294.29119) (xy 408.21305 -294.254353)
			(xy 408.251171 -294.223228) (xy 408.293792 -294.198621) (xy 408.339808 -294.181169) (xy 408.388027 -294.171325)
			(xy 408.437202 -294.169344) (xy 408.486057 -294.175276) (xy 408.533328 -294.188968) (xy 408.57779 -294.210066)
			(xy 408.618293 -294.238022) (xy 408.653786 -294.272114) (xy 408.683351 -294.311458) (xy 408.706222 -294.355035)
			(xy 408.721806 -294.401716) (xy 408.729701 -294.450293) (xy 408.730196 -294.4749) (xy 410.019004 -294.4749)
			(xy 410.022964 -294.425846) (xy 410.034741 -294.378062) (xy 410.054032 -294.332786) (xy 410.080335 -294.29119)
			(xy 410.11297 -294.254353) (xy 410.151091 -294.223228) (xy 410.193712 -294.198621) (xy 410.239728 -294.181169)
			(xy 410.287947 -294.171325) (xy 410.337122 -294.169344) (xy 410.385977 -294.175276) (xy 410.433248 -294.188968)
			(xy 410.47771 -294.210066) (xy 410.518213 -294.238022) (xy 410.553706 -294.272114) (xy 410.583271 -294.311458)
			(xy 410.606142 -294.355035) (xy 410.621726 -294.401716) (xy 410.629621 -294.450293) (xy 410.630116 -294.4749)
			(xy 411.919178 -294.4749) (xy 411.923138 -294.425846) (xy 411.934915 -294.378062) (xy 411.954206 -294.332786)
			(xy 411.980509 -294.29119) (xy 412.013144 -294.254353) (xy 412.051265 -294.223228) (xy 412.093886 -294.198621)
			(xy 412.139902 -294.181169) (xy 412.188121 -294.171325) (xy 412.237296 -294.169344) (xy 412.286151 -294.175276)
			(xy 412.333422 -294.188968) (xy 412.377884 -294.210066) (xy 412.418387 -294.238022) (xy 412.45388 -294.272114)
			(xy 412.483445 -294.311458) (xy 412.506316 -294.355035) (xy 412.5219 -294.401716) (xy 412.529795 -294.450293)
			(xy 412.53029 -294.4749) (xy 413.819098 -294.4749) (xy 413.823058 -294.425846) (xy 413.834835 -294.378062)
			(xy 413.854126 -294.332786) (xy 413.880429 -294.29119) (xy 413.913064 -294.254353) (xy 413.951185 -294.223228)
			(xy 413.993806 -294.198621) (xy 414.039822 -294.181169) (xy 414.088041 -294.171325) (xy 414.137216 -294.169344)
			(xy 414.186071 -294.175276) (xy 414.233342 -294.188968) (xy 414.277804 -294.210066) (xy 414.318307 -294.238022)
			(xy 414.3538 -294.272114) (xy 414.383365 -294.311458) (xy 414.406236 -294.355035) (xy 414.42182 -294.401716)
			(xy 414.429715 -294.450293) (xy 414.43021 -294.4749) (xy 414.769058 -294.4749) (xy 414.773018 -294.425846)
			(xy 414.784795 -294.378062) (xy 414.804086 -294.332786) (xy 414.830389 -294.29119) (xy 414.863024 -294.254353)
			(xy 414.901145 -294.223228) (xy 414.943766 -294.198621) (xy 414.989782 -294.181169) (xy 415.038001 -294.171325)
			(xy 415.087176 -294.169344) (xy 415.136031 -294.175276) (xy 415.183302 -294.188968) (xy 415.227764 -294.210066)
			(xy 415.268267 -294.238022) (xy 415.30376 -294.272114) (xy 415.333325 -294.311458) (xy 415.356196 -294.355035)
			(xy 415.37178 -294.401716) (xy 415.379675 -294.450293) (xy 415.38017 -294.4749) (xy 415.719018 -294.4749)
			(xy 415.722978 -294.425846) (xy 415.734755 -294.378062) (xy 415.754046 -294.332786) (xy 415.780349 -294.29119)
			(xy 415.812984 -294.254353) (xy 415.851105 -294.223228) (xy 415.893726 -294.198621) (xy 415.939742 -294.181169)
			(xy 415.987961 -294.171325) (xy 416.037136 -294.169344) (xy 416.085991 -294.175276) (xy 416.133262 -294.188968)
			(xy 416.177724 -294.210066) (xy 416.218227 -294.238022) (xy 416.25372 -294.272114) (xy 416.283285 -294.311458)
			(xy 416.306156 -294.355035) (xy 416.32174 -294.401716) (xy 416.329635 -294.450293) (xy 416.33013 -294.4749)
			(xy 416.329635 -294.499507) (xy 416.32174 -294.548084) (xy 416.306156 -294.594765) (xy 416.283285 -294.638342)
			(xy 416.25372 -294.677686) (xy 416.218227 -294.711778) (xy 416.177724 -294.739734) (xy 416.133262 -294.760832)
			(xy 416.085991 -294.774524) (xy 416.037136 -294.780456) (xy 415.987961 -294.778475) (xy 415.939742 -294.768631)
			(xy 415.893726 -294.751179) (xy 415.851105 -294.726572) (xy 415.812984 -294.695447) (xy 415.780349 -294.65861)
			(xy 415.754046 -294.617014) (xy 415.734755 -294.571738) (xy 415.722978 -294.523954) (xy 415.719018 -294.4749)
			(xy 415.38017 -294.4749) (xy 415.379675 -294.499507) (xy 415.37178 -294.548084) (xy 415.356196 -294.594765)
			(xy 415.333325 -294.638342) (xy 415.30376 -294.677686) (xy 415.268267 -294.711778) (xy 415.227764 -294.739734)
			(xy 415.183302 -294.760832) (xy 415.136031 -294.774524) (xy 415.087176 -294.780456) (xy 415.038001 -294.778475)
			(xy 414.989782 -294.768631) (xy 414.943766 -294.751179) (xy 414.901145 -294.726572) (xy 414.863024 -294.695447)
			(xy 414.830389 -294.65861) (xy 414.804086 -294.617014) (xy 414.784795 -294.571738) (xy 414.773018 -294.523954)
			(xy 414.769058 -294.4749) (xy 414.43021 -294.4749) (xy 414.429715 -294.499507) (xy 414.42182 -294.548084)
			(xy 414.406236 -294.594765) (xy 414.383365 -294.638342) (xy 414.3538 -294.677686) (xy 414.318307 -294.711778)
			(xy 414.277804 -294.739734) (xy 414.233342 -294.760832) (xy 414.186071 -294.774524) (xy 414.137216 -294.780456)
			(xy 414.088041 -294.778475) (xy 414.039822 -294.768631) (xy 413.993806 -294.751179) (xy 413.951185 -294.726572)
			(xy 413.913064 -294.695447) (xy 413.880429 -294.65861) (xy 413.854126 -294.617014) (xy 413.834835 -294.571738)
			(xy 413.823058 -294.523954) (xy 413.819098 -294.4749) (xy 412.53029 -294.4749) (xy 412.529795 -294.499507)
			(xy 412.5219 -294.548084) (xy 412.506316 -294.594765) (xy 412.483445 -294.638342) (xy 412.45388 -294.677686)
			(xy 412.418387 -294.711778) (xy 412.377884 -294.739734) (xy 412.333422 -294.760832) (xy 412.286151 -294.774524)
			(xy 412.237296 -294.780456) (xy 412.188121 -294.778475) (xy 412.139902 -294.768631) (xy 412.093886 -294.751179)
			(xy 412.051265 -294.726572) (xy 412.013144 -294.695447) (xy 411.980509 -294.65861) (xy 411.954206 -294.617014)
			(xy 411.934915 -294.571738) (xy 411.923138 -294.523954) (xy 411.919178 -294.4749) (xy 410.630116 -294.4749)
			(xy 410.629621 -294.499507) (xy 410.621726 -294.548084) (xy 410.606142 -294.594765) (xy 410.583271 -294.638342)
			(xy 410.553706 -294.677686) (xy 410.518213 -294.711778) (xy 410.47771 -294.739734) (xy 410.433248 -294.760832)
			(xy 410.385977 -294.774524) (xy 410.337122 -294.780456) (xy 410.287947 -294.778475) (xy 410.239728 -294.768631)
			(xy 410.193712 -294.751179) (xy 410.151091 -294.726572) (xy 410.11297 -294.695447) (xy 410.080335 -294.65861)
			(xy 410.054032 -294.617014) (xy 410.034741 -294.571738) (xy 410.022964 -294.523954) (xy 410.019004 -294.4749)
			(xy 408.730196 -294.4749) (xy 408.729701 -294.499507) (xy 408.721806 -294.548084) (xy 408.706222 -294.594765)
			(xy 408.683351 -294.638342) (xy 408.653786 -294.677686) (xy 408.618293 -294.711778) (xy 408.57779 -294.739734)
			(xy 408.533328 -294.760832) (xy 408.486057 -294.774524) (xy 408.437202 -294.780456) (xy 408.388027 -294.778475)
			(xy 408.339808 -294.768631) (xy 408.293792 -294.751179) (xy 408.251171 -294.726572) (xy 408.21305 -294.695447)
			(xy 408.180415 -294.65861) (xy 408.154112 -294.617014) (xy 408.134821 -294.571738) (xy 408.123044 -294.523954)
			(xy 408.119084 -294.4749) (xy 405.880316 -294.4749) (xy 405.879821 -294.499507) (xy 405.871926 -294.548084)
			(xy 405.856342 -294.594765) (xy 405.833471 -294.638342) (xy 405.803906 -294.677686) (xy 405.768413 -294.711778)
			(xy 405.72791 -294.739734) (xy 405.683448 -294.760832) (xy 405.636177 -294.774524) (xy 405.587322 -294.780456)
			(xy 405.538147 -294.778475) (xy 405.489928 -294.768631) (xy 405.443912 -294.751179) (xy 405.401291 -294.726572)
			(xy 405.36317 -294.695447) (xy 405.330535 -294.65861) (xy 405.304232 -294.617014) (xy 405.284941 -294.571738)
			(xy 405.273164 -294.523954) (xy 405.269204 -294.4749) (xy 403.980142 -294.4749) (xy 403.979647 -294.499507)
			(xy 403.971752 -294.548084) (xy 403.956168 -294.594765) (xy 403.933297 -294.638342) (xy 403.903732 -294.677686)
			(xy 403.868239 -294.711778) (xy 403.827736 -294.739734) (xy 403.783274 -294.760832) (xy 403.736003 -294.774524)
			(xy 403.687148 -294.780456) (xy 403.637973 -294.778475) (xy 403.589754 -294.768631) (xy 403.543738 -294.751179)
			(xy 403.501117 -294.726572) (xy 403.462996 -294.695447) (xy 403.430361 -294.65861) (xy 403.404058 -294.617014)
			(xy 403.384767 -294.571738) (xy 403.37299 -294.523954) (xy 403.36903 -294.4749) (xy 402.080222 -294.4749)
			(xy 402.079727 -294.499507) (xy 402.071832 -294.548084) (xy 402.056248 -294.594765) (xy 402.033377 -294.638342)
			(xy 402.003812 -294.677686) (xy 401.968319 -294.711778) (xy 401.927816 -294.739734) (xy 401.883354 -294.760832)
			(xy 401.836083 -294.774524) (xy 401.787228 -294.780456) (xy 401.738053 -294.778475) (xy 401.689834 -294.768631)
			(xy 401.643818 -294.751179) (xy 401.601197 -294.726572) (xy 401.563076 -294.695447) (xy 401.530441 -294.65861)
			(xy 401.504138 -294.617014) (xy 401.484847 -294.571738) (xy 401.47307 -294.523954) (xy 401.46911 -294.4749)
			(xy 400.180302 -294.4749) (xy 400.179807 -294.499507) (xy 400.171912 -294.548084) (xy 400.156328 -294.594765)
			(xy 400.133457 -294.638342) (xy 400.103892 -294.677686) (xy 400.068399 -294.711778) (xy 400.027896 -294.739734)
			(xy 399.983434 -294.760832) (xy 399.936163 -294.774524) (xy 399.887308 -294.780456) (xy 399.838133 -294.778475)
			(xy 399.789914 -294.768631) (xy 399.743898 -294.751179) (xy 399.701277 -294.726572) (xy 399.663156 -294.695447)
			(xy 399.630521 -294.65861) (xy 399.604218 -294.617014) (xy 399.584927 -294.571738) (xy 399.57315 -294.523954)
			(xy 399.56919 -294.4749) (xy 398.280128 -294.4749) (xy 398.279633 -294.499507) (xy 398.271738 -294.548084)
			(xy 398.256154 -294.594765) (xy 398.233283 -294.638342) (xy 398.203718 -294.677686) (xy 398.168225 -294.711778)
			(xy 398.127722 -294.739734) (xy 398.08326 -294.760832) (xy 398.035989 -294.774524) (xy 397.987134 -294.780456)
			(xy 397.937959 -294.778475) (xy 397.88974 -294.768631) (xy 397.843724 -294.751179) (xy 397.801103 -294.726572)
			(xy 397.762982 -294.695447) (xy 397.730347 -294.65861) (xy 397.704044 -294.617014) (xy 397.684753 -294.571738)
			(xy 397.672976 -294.523954) (xy 397.669016 -294.4749) (xy 396.380208 -294.4749) (xy 396.379713 -294.499507)
			(xy 396.371818 -294.548084) (xy 396.356234 -294.594765) (xy 396.333363 -294.638342) (xy 396.303798 -294.677686)
			(xy 396.268305 -294.711778) (xy 396.227802 -294.739734) (xy 396.18334 -294.760832) (xy 396.136069 -294.774524)
			(xy 396.087214 -294.780456) (xy 396.038039 -294.778475) (xy 395.98982 -294.768631) (xy 395.943804 -294.751179)
			(xy 395.901183 -294.726572) (xy 395.863062 -294.695447) (xy 395.830427 -294.65861) (xy 395.804124 -294.617014)
			(xy 395.784833 -294.571738) (xy 395.773056 -294.523954) (xy 395.769096 -294.4749) (xy 395.430248 -294.4749)
			(xy 395.429753 -294.499507) (xy 395.421858 -294.548084) (xy 395.406274 -294.594765) (xy 395.383403 -294.638342)
			(xy 395.353838 -294.677686) (xy 395.318345 -294.711778) (xy 395.277842 -294.739734) (xy 395.23338 -294.760832)
			(xy 395.186109 -294.774524) (xy 395.137254 -294.780456) (xy 395.088079 -294.778475) (xy 395.03986 -294.768631)
			(xy 394.993844 -294.751179) (xy 394.951223 -294.726572) (xy 394.913102 -294.695447) (xy 394.880467 -294.65861)
			(xy 394.854164 -294.617014) (xy 394.834873 -294.571738) (xy 394.823096 -294.523954) (xy 394.819136 -294.4749)
			(xy 394.480288 -294.4749) (xy 394.479793 -294.499507) (xy 394.471898 -294.548084) (xy 394.456314 -294.594765)
			(xy 394.433443 -294.638342) (xy 394.403878 -294.677686) (xy 394.368385 -294.711778) (xy 394.327882 -294.739734)
			(xy 394.28342 -294.760832) (xy 394.236149 -294.774524) (xy 394.187294 -294.780456) (xy 394.138119 -294.778475)
			(xy 394.0899 -294.768631) (xy 394.043884 -294.751179) (xy 394.001263 -294.726572) (xy 393.963142 -294.695447)
			(xy 393.930507 -294.65861) (xy 393.904204 -294.617014) (xy 393.884913 -294.571738) (xy 393.873136 -294.523954)
			(xy 393.869176 -294.4749) (xy 393.530328 -294.4749) (xy 393.529833 -294.499507) (xy 393.521938 -294.548084)
			(xy 393.506354 -294.594765) (xy 393.483483 -294.638342) (xy 393.453918 -294.677686) (xy 393.418425 -294.711778)
			(xy 393.377922 -294.739734) (xy 393.33346 -294.760832) (xy 393.286189 -294.774524) (xy 393.237334 -294.780456)
			(xy 393.188159 -294.778475) (xy 393.13994 -294.768631) (xy 393.093924 -294.751179) (xy 393.051303 -294.726572)
			(xy 393.013182 -294.695447) (xy 392.980547 -294.65861) (xy 392.954244 -294.617014) (xy 392.934953 -294.571738)
			(xy 392.923176 -294.523954) (xy 392.919216 -294.4749) (xy 392.580114 -294.4749) (xy 392.579619 -294.499507)
			(xy 392.571724 -294.548084) (xy 392.55614 -294.594765) (xy 392.533269 -294.638342) (xy 392.503704 -294.677686)
			(xy 392.468211 -294.711778) (xy 392.427708 -294.739734) (xy 392.383246 -294.760832) (xy 392.335975 -294.774524)
			(xy 392.28712 -294.780456) (xy 392.237945 -294.778475) (xy 392.189726 -294.768631) (xy 392.14371 -294.751179)
			(xy 392.101089 -294.726572) (xy 392.062968 -294.695447) (xy 392.030333 -294.65861) (xy 392.00403 -294.617014)
			(xy 391.984739 -294.571738) (xy 391.972962 -294.523954) (xy 391.969002 -294.4749) (xy 391.630154 -294.4749)
			(xy 391.629659 -294.499507) (xy 391.621764 -294.548084) (xy 391.60618 -294.594765) (xy 391.583309 -294.638342)
			(xy 391.553744 -294.677686) (xy 391.518251 -294.711778) (xy 391.477748 -294.739734) (xy 391.433286 -294.760832)
			(xy 391.386015 -294.774524) (xy 391.33716 -294.780456) (xy 391.287985 -294.778475) (xy 391.239766 -294.768631)
			(xy 391.19375 -294.751179) (xy 391.151129 -294.726572) (xy 391.113008 -294.695447) (xy 391.080373 -294.65861)
			(xy 391.05407 -294.617014) (xy 391.034779 -294.571738) (xy 391.023002 -294.523954) (xy 391.019042 -294.4749)
			(xy 390.730994 -294.4749) (xy 390.730496 -294.501549) (xy 390.722553 -294.554253) (xy 390.706843 -294.605183)
			(xy 390.683717 -294.653204) (xy 390.653693 -294.697241) (xy 390.617441 -294.736312) (xy 390.57577 -294.769543)
			(xy 390.529612 -294.796192) (xy 390.479998 -294.815664) (xy 390.428036 -294.827524) (xy 390.374886 -294.831508)
			(xy 390.321736 -294.827524) (xy 390.269774 -294.815664) (xy 390.22016 -294.796192) (xy 390.174002 -294.769543)
			(xy 390.132331 -294.736312) (xy 390.096079 -294.697241) (xy 390.066055 -294.653204) (xy 390.042929 -294.605183)
			(xy 390.027219 -294.554253) (xy 390.019276 -294.501549) (xy 389.729407 -294.501549) (xy 389.721844 -294.548084)
			(xy 389.70626 -294.594765) (xy 389.683389 -294.638342) (xy 389.653824 -294.677686) (xy 389.618331 -294.711778)
			(xy 389.577828 -294.739734) (xy 389.533366 -294.760832) (xy 389.486095 -294.774524) (xy 389.43724 -294.780456)
			(xy 389.388065 -294.778475) (xy 389.339846 -294.768631) (xy 389.29383 -294.751179) (xy 389.251209 -294.726572)
			(xy 389.213088 -294.695447) (xy 389.180453 -294.65861) (xy 389.15415 -294.617014) (xy 389.134859 -294.571738)
			(xy 389.123082 -294.523954) (xy 389.119122 -294.4749) (xy 386.880354 -294.4749) (xy 386.879859 -294.499507)
			(xy 386.871964 -294.548084) (xy 386.85638 -294.594765) (xy 386.833509 -294.638342) (xy 386.803944 -294.677686)
			(xy 386.768451 -294.711778) (xy 386.727948 -294.739734) (xy 386.683486 -294.760832) (xy 386.636215 -294.774524)
			(xy 386.58736 -294.780456) (xy 386.538185 -294.778475) (xy 386.489966 -294.768631) (xy 386.44395 -294.751179)
			(xy 386.401329 -294.726572) (xy 386.363208 -294.695447) (xy 386.330573 -294.65861) (xy 386.30427 -294.617014)
			(xy 386.284979 -294.571738) (xy 386.273202 -294.523954) (xy 386.269242 -294.4749) (xy 385.93014 -294.4749)
			(xy 385.929645 -294.499507) (xy 385.92175 -294.548084) (xy 385.906166 -294.594765) (xy 385.883295 -294.638342)
			(xy 385.85373 -294.677686) (xy 385.818237 -294.711778) (xy 385.777734 -294.739734) (xy 385.733272 -294.760832)
			(xy 385.686001 -294.774524) (xy 385.637146 -294.780456) (xy 385.587971 -294.778475) (xy 385.539752 -294.768631)
			(xy 385.493736 -294.751179) (xy 385.451115 -294.726572) (xy 385.412994 -294.695447) (xy 385.380359 -294.65861)
			(xy 385.354056 -294.617014) (xy 385.334765 -294.571738) (xy 385.322988 -294.523954) (xy 385.319028 -294.4749)
			(xy 384.98018 -294.4749) (xy 384.979685 -294.499507) (xy 384.97179 -294.548084) (xy 384.956206 -294.594765)
			(xy 384.933335 -294.638342) (xy 384.90377 -294.677686) (xy 384.868277 -294.711778) (xy 384.827774 -294.739734)
			(xy 384.783312 -294.760832) (xy 384.736041 -294.774524) (xy 384.687186 -294.780456) (xy 384.638011 -294.778475)
			(xy 384.589792 -294.768631) (xy 384.543776 -294.751179) (xy 384.501155 -294.726572) (xy 384.463034 -294.695447)
			(xy 384.430399 -294.65861) (xy 384.404096 -294.617014) (xy 384.384805 -294.571738) (xy 384.373028 -294.523954)
			(xy 384.369068 -294.4749) (xy 376.32635 -294.4749) (xy 376.335485 -294.494387) (xy 376.351553 -294.547794)
			(xy 376.359673 -294.60297) (xy 376.360182 -294.630856) (xy 376.359673 -294.658742) (xy 376.351553 -294.713918)
			(xy 376.335485 -294.767325) (xy 376.311813 -294.817822) (xy 376.28104 -294.864335) (xy 376.243823 -294.905872)
			(xy 376.200955 -294.941547) (xy 376.153349 -294.970601) (xy 376.10202 -294.992413) (xy 376.048063 -295.006519)
			(xy 375.992626 -295.012619) (xy 375.936892 -295.010582) (xy 375.882049 -295.000452) (xy 375.829265 -294.982445)
			(xy 375.779665 -294.956944) (xy 375.734307 -294.924493) (xy 375.694158 -294.885784) (xy 375.660072 -294.841641)
			(xy 375.632776 -294.793006) (xy 375.612853 -294.740915) (xy 375.600727 -294.686478) (xy 375.596656 -294.630856)
			(xy 374.875044 -294.630856) (xy 374.874535 -294.658742) (xy 374.866415 -294.713918) (xy 374.850347 -294.767325)
			(xy 374.826675 -294.817822) (xy 374.795902 -294.864335) (xy 374.758685 -294.905872) (xy 374.715817 -294.941547)
			(xy 374.668211 -294.970601) (xy 374.616882 -294.992413) (xy 374.562925 -295.006519) (xy 374.507488 -295.012619)
			(xy 374.451754 -295.010582) (xy 374.396911 -295.000452) (xy 374.344127 -294.982445) (xy 374.294527 -294.956944)
			(xy 374.249169 -294.924493) (xy 374.20902 -294.885784) (xy 374.174934 -294.841641) (xy 374.147638 -294.793006)
			(xy 374.127715 -294.740915) (xy 374.115589 -294.686478) (xy 374.111518 -294.630856) (xy 351.031048 -294.630856)
			(xy 351.031048 -295.933114) (xy 374.111518 -295.933114) (xy 374.115589 -295.877492) (xy 374.127715 -295.823055)
			(xy 374.147638 -295.770964) (xy 374.174934 -295.722329) (xy 374.20902 -295.678186) (xy 374.249169 -295.639477)
			(xy 374.294527 -295.607026) (xy 374.344127 -295.581525) (xy 374.396911 -295.563518) (xy 374.451754 -295.553388)
			(xy 374.507488 -295.551351) (xy 374.562925 -295.557451) (xy 374.616882 -295.571557) (xy 374.668211 -295.593369)
			(xy 374.715817 -295.622423) (xy 374.758685 -295.658098) (xy 374.795902 -295.699635) (xy 374.826675 -295.746148)
			(xy 374.850347 -295.796645) (xy 374.866415 -295.850052) (xy 374.874535 -295.905228) (xy 374.875044 -295.933114)
			(xy 375.587004 -295.933114) (xy 375.591075 -295.877492) (xy 375.603201 -295.823055) (xy 375.623124 -295.770964)
			(xy 375.65042 -295.722329) (xy 375.684506 -295.678186) (xy 375.724655 -295.639477) (xy 375.770013 -295.607026)
			(xy 375.819613 -295.581525) (xy 375.872397 -295.563518) (xy 375.92724 -295.553388) (xy 375.982974 -295.551351)
			(xy 376.038411 -295.557451) (xy 376.092368 -295.571557) (xy 376.143697 -295.593369) (xy 376.191303 -295.622423)
			(xy 376.234171 -295.658098) (xy 376.271388 -295.699635) (xy 376.302161 -295.746148) (xy 376.325833 -295.796645)
			(xy 376.341901 -295.850052) (xy 376.350021 -295.905228) (xy 376.35053 -295.933114) (xy 376.476004 -295.933114)
			(xy 376.480075 -295.877492) (xy 376.492201 -295.823055) (xy 376.512124 -295.770964) (xy 376.53942 -295.722329)
			(xy 376.573506 -295.678186) (xy 376.613655 -295.639477) (xy 376.659013 -295.607026) (xy 376.708613 -295.581525)
			(xy 376.761397 -295.563518) (xy 376.81624 -295.553388) (xy 376.871974 -295.551351) (xy 376.927411 -295.557451)
			(xy 376.981368 -295.571557) (xy 377.032697 -295.593369) (xy 377.080303 -295.622423) (xy 377.123171 -295.658098)
			(xy 377.160388 -295.699635) (xy 377.191161 -295.746148) (xy 377.214833 -295.796645) (xy 377.230901 -295.850052)
			(xy 377.239021 -295.905228) (xy 377.23953 -295.933114) (xy 377.239021 -295.961) (xy 377.230901 -296.016176)
			(xy 377.214833 -296.069583) (xy 377.191161 -296.12008) (xy 377.160388 -296.166593) (xy 377.123171 -296.20813)
			(xy 377.080303 -296.243805) (xy 377.032697 -296.272859) (xy 376.981368 -296.294671) (xy 376.927411 -296.308777)
			(xy 376.871974 -296.314877) (xy 376.81624 -296.31284) (xy 376.761397 -296.30271) (xy 376.708613 -296.284703)
			(xy 376.659013 -296.259202) (xy 376.613655 -296.226751) (xy 376.573506 -296.188042) (xy 376.53942 -296.143899)
			(xy 376.512124 -296.095264) (xy 376.492201 -296.043173) (xy 376.480075 -295.988736) (xy 376.476004 -295.933114)
			(xy 376.35053 -295.933114) (xy 376.350021 -295.961) (xy 376.341901 -296.016176) (xy 376.325833 -296.069583)
			(xy 376.302161 -296.12008) (xy 376.271388 -296.166593) (xy 376.234171 -296.20813) (xy 376.191303 -296.243805)
			(xy 376.143697 -296.272859) (xy 376.092368 -296.294671) (xy 376.038411 -296.308777) (xy 375.982974 -296.314877)
			(xy 375.92724 -296.31284) (xy 375.872397 -296.30271) (xy 375.819613 -296.284703) (xy 375.770013 -296.259202)
			(xy 375.724655 -296.226751) (xy 375.684506 -296.188042) (xy 375.65042 -296.143899) (xy 375.623124 -296.095264)
			(xy 375.603201 -296.043173) (xy 375.591075 -295.988736) (xy 375.587004 -295.933114) (xy 374.875044 -295.933114)
			(xy 374.874535 -295.961) (xy 374.866415 -296.016176) (xy 374.850347 -296.069583) (xy 374.826675 -296.12008)
			(xy 374.795902 -296.166593) (xy 374.758685 -296.20813) (xy 374.715817 -296.243805) (xy 374.668211 -296.272859)
			(xy 374.616882 -296.294671) (xy 374.562925 -296.308777) (xy 374.507488 -296.314877) (xy 374.451754 -296.31284)
			(xy 374.396911 -296.30271) (xy 374.344127 -296.284703) (xy 374.294527 -296.259202) (xy 374.249169 -296.226751)
			(xy 374.20902 -296.188042) (xy 374.174934 -296.143899) (xy 374.147638 -296.095264) (xy 374.127715 -296.043173)
			(xy 374.115589 -295.988736) (xy 374.111518 -295.933114) (xy 351.031048 -295.933114) (xy 351.031048 -296.695114)
			(xy 379.638052 -296.695114) (xy 379.638619 -296.665733) (xy 379.647646 -296.607668) (xy 379.665474 -296.551675)
			(xy 379.691681 -296.49908) (xy 379.725646 -296.451128) (xy 379.766565 -296.408954) (xy 379.78969 -296.390822)
			(xy 379.799088 -296.383456) (xy 379.809502 -296.362882) (xy 379.811026 -296.258996) (xy 379.80112 -296.237914)
			(xy 379.791976 -296.230548) (xy 379.770116 -296.212356) (xy 379.731578 -296.170534) (xy 379.699673 -296.123455)
			(xy 379.675108 -296.072163) (xy 379.658427 -296.017793) (xy 379.65 -295.96155) (xy 379.649482 -295.933114)
			(xy 379.649968 -295.905863) (xy 379.657724 -295.851915) (xy 379.673079 -295.79962) (xy 379.695721 -295.750043)
			(xy 379.725187 -295.704193) (xy 379.760878 -295.663002) (xy 379.802069 -295.627311) (xy 379.847919 -295.597845)
			(xy 379.897496 -295.575203) (xy 379.949791 -295.559848) (xy 380.003739 -295.552092) (xy 380.058241 -295.552092)
			(xy 380.112189 -295.559848) (xy 380.164484 -295.575203) (xy 380.214061 -295.597845) (xy 380.259911 -295.627311)
			(xy 380.301102 -295.663002) (xy 380.336793 -295.704193) (xy 380.366259 -295.750043) (xy 380.388901 -295.79962)
			(xy 380.404256 -295.851915) (xy 380.412012 -295.905863) (xy 380.412498 -295.933114) (xy 380.411971 -295.962497)
			(xy 380.402938 -296.020564) (xy 380.385103 -296.076559) (xy 380.358889 -296.129154) (xy 380.324916 -296.177105)
			(xy 380.283989 -296.219276) (xy 380.26086 -296.237406) (xy 380.251462 -296.244772) (xy 380.241048 -296.265346)
			(xy 380.239524 -296.369232) (xy 380.24943 -296.390314) (xy 380.258574 -296.39768) (xy 380.280389 -296.415924)
			(xy 380.318933 -296.457734) (xy 380.350844 -296.504801) (xy 380.375417 -296.556084) (xy 380.392107 -296.610445)
			(xy 380.400545 -296.666681) (xy 380.401068 -296.695114) (xy 381.034542 -296.695114) (xy 381.038613 -296.639492)
			(xy 381.050739 -296.585055) (xy 381.070662 -296.532964) (xy 381.097958 -296.484329) (xy 381.132044 -296.440186)
			(xy 381.172193 -296.401477) (xy 381.217551 -296.369026) (xy 381.267151 -296.343525) (xy 381.319935 -296.325518)
			(xy 381.374778 -296.315388) (xy 381.430512 -296.313351) (xy 381.485949 -296.319451) (xy 381.539906 -296.333557)
			(xy 381.591235 -296.355369) (xy 381.638841 -296.384423) (xy 381.681709 -296.420098) (xy 381.718926 -296.461635)
			(xy 381.749699 -296.508148) (xy 381.773371 -296.558645) (xy 381.789439 -296.612052) (xy 381.797559 -296.667228)
			(xy 381.798068 -296.695114) (xy 381.921002 -296.695114) (xy 381.925073 -296.639492) (xy 381.937199 -296.585055)
			(xy 381.957122 -296.532964) (xy 381.984418 -296.484329) (xy 382.018504 -296.440186) (xy 382.058653 -296.401477)
			(xy 382.104011 -296.369026) (xy 382.153611 -296.343525) (xy 382.206395 -296.325518) (xy 382.261238 -296.315388)
			(xy 382.316972 -296.313351) (xy 382.372409 -296.319451) (xy 382.426366 -296.333557) (xy 382.477695 -296.355369)
			(xy 382.50915 -296.374566) (xy 384.369068 -296.374566) (xy 384.373028 -296.325512) (xy 384.384805 -296.277728)
			(xy 384.404096 -296.232452) (xy 384.430399 -296.190856) (xy 384.463034 -296.154019) (xy 384.501155 -296.122894)
			(xy 384.543776 -296.098287) (xy 384.589792 -296.080835) (xy 384.638011 -296.070991) (xy 384.687186 -296.06901)
			(xy 384.736041 -296.074942) (xy 384.783312 -296.088634) (xy 384.827774 -296.109732) (xy 384.868277 -296.137688)
			(xy 384.90377 -296.17178) (xy 384.933335 -296.211124) (xy 384.956206 -296.254701) (xy 384.97179 -296.301382)
			(xy 384.979685 -296.349959) (xy 384.98018 -296.374566) (xy 384.980175 -296.37482) (xy 385.319282 -296.37482)
			(xy 385.323242 -296.325766) (xy 385.335019 -296.277982) (xy 385.35431 -296.232706) (xy 385.380613 -296.19111)
			(xy 385.413248 -296.154273) (xy 385.451369 -296.123148) (xy 385.49399 -296.098541) (xy 385.540006 -296.081089)
			(xy 385.588225 -296.071245) (xy 385.6374 -296.069264) (xy 385.686255 -296.075196) (xy 385.733526 -296.088888)
			(xy 385.777988 -296.109986) (xy 385.818491 -296.137942) (xy 385.853984 -296.172034) (xy 385.883549 -296.211378)
			(xy 385.90642 -296.254955) (xy 385.922004 -296.301636) (xy 385.929899 -296.350213) (xy 385.930394 -296.37482)
			(xy 386.268988 -296.37482) (xy 386.272948 -296.325766) (xy 386.284725 -296.277982) (xy 386.304016 -296.232706)
			(xy 386.330319 -296.19111) (xy 386.362954 -296.154273) (xy 386.401075 -296.123148) (xy 386.443696 -296.098541)
			(xy 386.489712 -296.081089) (xy 386.537931 -296.071245) (xy 386.587106 -296.069264) (xy 386.635961 -296.075196)
			(xy 386.683232 -296.088888) (xy 386.727694 -296.109986) (xy 386.768197 -296.137942) (xy 386.80369 -296.172034)
			(xy 386.833255 -296.211378) (xy 386.856126 -296.254955) (xy 386.87171 -296.301636) (xy 386.879605 -296.350213)
			(xy 386.8801 -296.37482) (xy 387.219202 -296.37482) (xy 387.223162 -296.325766) (xy 387.234939 -296.277982)
			(xy 387.25423 -296.232706) (xy 387.280533 -296.19111) (xy 387.313168 -296.154273) (xy 387.351289 -296.123148)
			(xy 387.39391 -296.098541) (xy 387.439926 -296.081089) (xy 387.488145 -296.071245) (xy 387.53732 -296.069264)
			(xy 387.586175 -296.075196) (xy 387.633446 -296.088888) (xy 387.677908 -296.109986) (xy 387.718411 -296.137942)
			(xy 387.753904 -296.172034) (xy 387.783469 -296.211378) (xy 387.80634 -296.254955) (xy 387.821924 -296.301636)
			(xy 387.829819 -296.350213) (xy 387.830314 -296.37482) (xy 388.169162 -296.37482) (xy 388.173122 -296.325766)
			(xy 388.184899 -296.277982) (xy 388.20419 -296.232706) (xy 388.230493 -296.19111) (xy 388.263128 -296.154273)
			(xy 388.301249 -296.123148) (xy 388.34387 -296.098541) (xy 388.389886 -296.081089) (xy 388.438105 -296.071245)
			(xy 388.48728 -296.069264) (xy 388.536135 -296.075196) (xy 388.583406 -296.088888) (xy 388.627868 -296.109986)
			(xy 388.668371 -296.137942) (xy 388.703864 -296.172034) (xy 388.733429 -296.211378) (xy 388.7563 -296.254955)
			(xy 388.771884 -296.301636) (xy 388.779779 -296.350213) (xy 388.780274 -296.37482) (xy 390.069082 -296.37482)
			(xy 390.073042 -296.325766) (xy 390.084819 -296.277982) (xy 390.10411 -296.232706) (xy 390.130413 -296.19111)
			(xy 390.163048 -296.154273) (xy 390.201169 -296.123148) (xy 390.24379 -296.098541) (xy 390.289806 -296.081089)
			(xy 390.338025 -296.071245) (xy 390.3872 -296.069264) (xy 390.436055 -296.075196) (xy 390.483326 -296.088888)
			(xy 390.527788 -296.109986) (xy 390.568291 -296.137942) (xy 390.603784 -296.172034) (xy 390.633349 -296.211378)
			(xy 390.65622 -296.254955) (xy 390.671804 -296.301636) (xy 390.679699 -296.350213) (xy 390.680194 -296.37482)
			(xy 391.969002 -296.37482) (xy 391.972962 -296.325766) (xy 391.984739 -296.277982) (xy 392.00403 -296.232706)
			(xy 392.030333 -296.19111) (xy 392.062968 -296.154273) (xy 392.101089 -296.123148) (xy 392.14371 -296.098541)
			(xy 392.189726 -296.081089) (xy 392.237945 -296.071245) (xy 392.28712 -296.069264) (xy 392.335975 -296.075196)
			(xy 392.383246 -296.088888) (xy 392.427708 -296.109986) (xy 392.468211 -296.137942) (xy 392.503704 -296.172034)
			(xy 392.533269 -296.211378) (xy 392.55614 -296.254955) (xy 392.571724 -296.301636) (xy 392.579619 -296.350213)
			(xy 392.580114 -296.37482) (xy 392.919216 -296.37482) (xy 392.923176 -296.325766) (xy 392.934953 -296.277982)
			(xy 392.954244 -296.232706) (xy 392.980547 -296.19111) (xy 393.013182 -296.154273) (xy 393.051303 -296.123148)
			(xy 393.093924 -296.098541) (xy 393.13994 -296.081089) (xy 393.188159 -296.071245) (xy 393.237334 -296.069264)
			(xy 393.286189 -296.075196) (xy 393.33346 -296.088888) (xy 393.377922 -296.109986) (xy 393.418425 -296.137942)
			(xy 393.453918 -296.172034) (xy 393.483483 -296.211378) (xy 393.506354 -296.254955) (xy 393.521938 -296.301636)
			(xy 393.529833 -296.350213) (xy 393.530328 -296.37482) (xy 393.869176 -296.37482) (xy 393.873136 -296.325766)
			(xy 393.884913 -296.277982) (xy 393.904204 -296.232706) (xy 393.930507 -296.19111) (xy 393.963142 -296.154273)
			(xy 394.001263 -296.123148) (xy 394.043884 -296.098541) (xy 394.0899 -296.081089) (xy 394.138119 -296.071245)
			(xy 394.187294 -296.069264) (xy 394.236149 -296.075196) (xy 394.28342 -296.088888) (xy 394.327882 -296.109986)
			(xy 394.368385 -296.137942) (xy 394.403878 -296.172034) (xy 394.433443 -296.211378) (xy 394.456314 -296.254955)
			(xy 394.471898 -296.301636) (xy 394.479793 -296.350213) (xy 394.480288 -296.37482) (xy 395.769096 -296.37482)
			(xy 395.773056 -296.325766) (xy 395.784833 -296.277982) (xy 395.804124 -296.232706) (xy 395.830427 -296.19111)
			(xy 395.863062 -296.154273) (xy 395.901183 -296.123148) (xy 395.943804 -296.098541) (xy 395.98982 -296.081089)
			(xy 396.038039 -296.071245) (xy 396.087214 -296.069264) (xy 396.136069 -296.075196) (xy 396.18334 -296.088888)
			(xy 396.227802 -296.109986) (xy 396.268305 -296.137942) (xy 396.303798 -296.172034) (xy 396.333363 -296.211378)
			(xy 396.356234 -296.254955) (xy 396.371818 -296.301636) (xy 396.379713 -296.350213) (xy 396.380208 -296.37482)
			(xy 396.719056 -296.37482) (xy 396.723016 -296.325766) (xy 396.734793 -296.277982) (xy 396.754084 -296.232706)
			(xy 396.780387 -296.19111) (xy 396.813022 -296.154273) (xy 396.851143 -296.123148) (xy 396.893764 -296.098541)
			(xy 396.93978 -296.081089) (xy 396.987999 -296.071245) (xy 397.037174 -296.069264) (xy 397.086029 -296.075196)
			(xy 397.1333 -296.088888) (xy 397.177762 -296.109986) (xy 397.218265 -296.137942) (xy 397.253758 -296.172034)
			(xy 397.283323 -296.211378) (xy 397.306194 -296.254955) (xy 397.321778 -296.301636) (xy 397.329673 -296.350213)
			(xy 397.330168 -296.37482) (xy 398.61923 -296.37482) (xy 398.62319 -296.325766) (xy 398.634967 -296.277982)
			(xy 398.654258 -296.232706) (xy 398.680561 -296.19111) (xy 398.713196 -296.154273) (xy 398.751317 -296.123148)
			(xy 398.793938 -296.098541) (xy 398.839954 -296.081089) (xy 398.888173 -296.071245) (xy 398.937348 -296.069264)
			(xy 398.986203 -296.075196) (xy 399.033474 -296.088888) (xy 399.077936 -296.109986) (xy 399.118439 -296.137942)
			(xy 399.153932 -296.172034) (xy 399.183497 -296.211378) (xy 399.206368 -296.254955) (xy 399.221952 -296.301636)
			(xy 399.229847 -296.350213) (xy 399.230342 -296.37482) (xy 400.51915 -296.37482) (xy 400.52311 -296.325766)
			(xy 400.534887 -296.277982) (xy 400.554178 -296.232706) (xy 400.580481 -296.19111) (xy 400.613116 -296.154273)
			(xy 400.651237 -296.123148) (xy 400.693858 -296.098541) (xy 400.739874 -296.081089) (xy 400.788093 -296.071245)
			(xy 400.837268 -296.069264) (xy 400.886123 -296.075196) (xy 400.933394 -296.088888) (xy 400.977856 -296.109986)
			(xy 401.018359 -296.137942) (xy 401.053852 -296.172034) (xy 401.083417 -296.211378) (xy 401.106288 -296.254955)
			(xy 401.121872 -296.301636) (xy 401.129767 -296.350213) (xy 401.130262 -296.37482) (xy 402.41907 -296.37482)
			(xy 402.42303 -296.325766) (xy 402.434807 -296.277982) (xy 402.454098 -296.232706) (xy 402.480401 -296.19111)
			(xy 402.513036 -296.154273) (xy 402.551157 -296.123148) (xy 402.593778 -296.098541) (xy 402.639794 -296.081089)
			(xy 402.688013 -296.071245) (xy 402.737188 -296.069264) (xy 402.786043 -296.075196) (xy 402.833314 -296.088888)
			(xy 402.877776 -296.109986) (xy 402.918279 -296.137942) (xy 402.953772 -296.172034) (xy 402.983337 -296.211378)
			(xy 403.006208 -296.254955) (xy 403.021792 -296.301636) (xy 403.029687 -296.350213) (xy 403.030182 -296.37482)
			(xy 404.319244 -296.37482) (xy 404.323204 -296.325766) (xy 404.334981 -296.277982) (xy 404.354272 -296.232706)
			(xy 404.380575 -296.19111) (xy 404.41321 -296.154273) (xy 404.451331 -296.123148) (xy 404.493952 -296.098541)
			(xy 404.539968 -296.081089) (xy 404.588187 -296.071245) (xy 404.637362 -296.069264) (xy 404.686217 -296.075196)
			(xy 404.733488 -296.088888) (xy 404.77795 -296.109986) (xy 404.818453 -296.137942) (xy 404.853946 -296.172034)
			(xy 404.883511 -296.211378) (xy 404.906382 -296.254955) (xy 404.921966 -296.301636) (xy 404.929861 -296.350213)
			(xy 404.930356 -296.37482) (xy 406.219164 -296.37482) (xy 406.223124 -296.325766) (xy 406.234901 -296.277982)
			(xy 406.254192 -296.232706) (xy 406.280495 -296.19111) (xy 406.31313 -296.154273) (xy 406.351251 -296.123148)
			(xy 406.393872 -296.098541) (xy 406.439888 -296.081089) (xy 406.488107 -296.071245) (xy 406.537282 -296.069264)
			(xy 406.586137 -296.075196) (xy 406.633408 -296.088888) (xy 406.67787 -296.109986) (xy 406.718373 -296.137942)
			(xy 406.753866 -296.172034) (xy 406.783431 -296.211378) (xy 406.806302 -296.254955) (xy 406.821886 -296.301636)
			(xy 406.829781 -296.350213) (xy 406.830276 -296.37482) (xy 409.069044 -296.37482) (xy 409.073004 -296.325766)
			(xy 409.084781 -296.277982) (xy 409.104072 -296.232706) (xy 409.130375 -296.19111) (xy 409.16301 -296.154273)
			(xy 409.201131 -296.123148) (xy 409.243752 -296.098541) (xy 409.289768 -296.081089) (xy 409.337987 -296.071245)
			(xy 409.387162 -296.069264) (xy 409.436017 -296.075196) (xy 409.483288 -296.088888) (xy 409.52775 -296.109986)
			(xy 409.568253 -296.137942) (xy 409.603746 -296.172034) (xy 409.633311 -296.211378) (xy 409.656182 -296.254955)
			(xy 409.671766 -296.301636) (xy 409.679661 -296.350213) (xy 409.680156 -296.37482) (xy 410.969218 -296.37482)
			(xy 410.973178 -296.325766) (xy 410.984955 -296.277982) (xy 411.004246 -296.232706) (xy 411.030549 -296.19111)
			(xy 411.063184 -296.154273) (xy 411.101305 -296.123148) (xy 411.143926 -296.098541) (xy 411.189942 -296.081089)
			(xy 411.238161 -296.071245) (xy 411.287336 -296.069264) (xy 411.336191 -296.075196) (xy 411.383462 -296.088888)
			(xy 411.427924 -296.109986) (xy 411.468427 -296.137942) (xy 411.50392 -296.172034) (xy 411.533485 -296.211378)
			(xy 411.556356 -296.254955) (xy 411.57194 -296.301636) (xy 411.579835 -296.350213) (xy 411.58033 -296.37482)
			(xy 412.869138 -296.37482) (xy 412.873098 -296.325766) (xy 412.884875 -296.277982) (xy 412.904166 -296.232706)
			(xy 412.930469 -296.19111) (xy 412.963104 -296.154273) (xy 413.001225 -296.123148) (xy 413.043846 -296.098541)
			(xy 413.089862 -296.081089) (xy 413.138081 -296.071245) (xy 413.187256 -296.069264) (xy 413.236111 -296.075196)
			(xy 413.283382 -296.088888) (xy 413.327844 -296.109986) (xy 413.368347 -296.137942) (xy 413.40384 -296.172034)
			(xy 413.433405 -296.211378) (xy 413.456276 -296.254955) (xy 413.47186 -296.301636) (xy 413.479755 -296.350213)
			(xy 413.48025 -296.37482) (xy 414.769058 -296.37482) (xy 414.773018 -296.325766) (xy 414.784795 -296.277982)
			(xy 414.804086 -296.232706) (xy 414.830389 -296.19111) (xy 414.863024 -296.154273) (xy 414.901145 -296.123148)
			(xy 414.943766 -296.098541) (xy 414.989782 -296.081089) (xy 415.038001 -296.071245) (xy 415.087176 -296.069264)
			(xy 415.136031 -296.075196) (xy 415.183302 -296.088888) (xy 415.227764 -296.109986) (xy 415.268267 -296.137942)
			(xy 415.30376 -296.172034) (xy 415.333325 -296.211378) (xy 415.356196 -296.254955) (xy 415.37178 -296.301636)
			(xy 415.379675 -296.350213) (xy 415.38017 -296.37482) (xy 415.719018 -296.37482) (xy 415.722978 -296.325766)
			(xy 415.734755 -296.277982) (xy 415.754046 -296.232706) (xy 415.780349 -296.19111) (xy 415.812984 -296.154273)
			(xy 415.851105 -296.123148) (xy 415.893726 -296.098541) (xy 415.939742 -296.081089) (xy 415.987961 -296.071245)
			(xy 416.037136 -296.069264) (xy 416.085991 -296.075196) (xy 416.133262 -296.088888) (xy 416.177724 -296.109986)
			(xy 416.218227 -296.137942) (xy 416.25372 -296.172034) (xy 416.283285 -296.211378) (xy 416.306156 -296.254955)
			(xy 416.32174 -296.301636) (xy 416.329635 -296.350213) (xy 416.33013 -296.37482) (xy 416.329635 -296.399427)
			(xy 416.32174 -296.448004) (xy 416.306156 -296.494685) (xy 416.283285 -296.538262) (xy 416.25372 -296.577606)
			(xy 416.218227 -296.611698) (xy 416.177724 -296.639654) (xy 416.133262 -296.660752) (xy 416.085991 -296.674444)
			(xy 416.037136 -296.680376) (xy 415.987961 -296.678395) (xy 415.939742 -296.668551) (xy 415.893726 -296.651099)
			(xy 415.851105 -296.626492) (xy 415.812984 -296.595367) (xy 415.780349 -296.55853) (xy 415.754046 -296.516934)
			(xy 415.734755 -296.471658) (xy 415.722978 -296.423874) (xy 415.719018 -296.37482) (xy 415.38017 -296.37482)
			(xy 415.379675 -296.399427) (xy 415.37178 -296.448004) (xy 415.356196 -296.494685) (xy 415.333325 -296.538262)
			(xy 415.30376 -296.577606) (xy 415.268267 -296.611698) (xy 415.227764 -296.639654) (xy 415.183302 -296.660752)
			(xy 415.136031 -296.674444) (xy 415.087176 -296.680376) (xy 415.038001 -296.678395) (xy 414.989782 -296.668551)
			(xy 414.943766 -296.651099) (xy 414.901145 -296.626492) (xy 414.863024 -296.595367) (xy 414.830389 -296.55853)
			(xy 414.804086 -296.516934) (xy 414.784795 -296.471658) (xy 414.773018 -296.423874) (xy 414.769058 -296.37482)
			(xy 413.48025 -296.37482) (xy 413.479755 -296.399427) (xy 413.47186 -296.448004) (xy 413.456276 -296.494685)
			(xy 413.433405 -296.538262) (xy 413.40384 -296.577606) (xy 413.368347 -296.611698) (xy 413.327844 -296.639654)
			(xy 413.283382 -296.660752) (xy 413.236111 -296.674444) (xy 413.187256 -296.680376) (xy 413.138081 -296.678395)
			(xy 413.089862 -296.668551) (xy 413.043846 -296.651099) (xy 413.001225 -296.626492) (xy 412.963104 -296.595367)
			(xy 412.930469 -296.55853) (xy 412.904166 -296.516934) (xy 412.884875 -296.471658) (xy 412.873098 -296.423874)
			(xy 412.869138 -296.37482) (xy 411.58033 -296.37482) (xy 411.579835 -296.399427) (xy 411.57194 -296.448004)
			(xy 411.556356 -296.494685) (xy 411.533485 -296.538262) (xy 411.50392 -296.577606) (xy 411.468427 -296.611698)
			(xy 411.427924 -296.639654) (xy 411.383462 -296.660752) (xy 411.336191 -296.674444) (xy 411.287336 -296.680376)
			(xy 411.238161 -296.678395) (xy 411.189942 -296.668551) (xy 411.143926 -296.651099) (xy 411.101305 -296.626492)
			(xy 411.063184 -296.595367) (xy 411.030549 -296.55853) (xy 411.004246 -296.516934) (xy 410.984955 -296.471658)
			(xy 410.973178 -296.423874) (xy 410.969218 -296.37482) (xy 409.680156 -296.37482) (xy 409.679661 -296.399427)
			(xy 409.671766 -296.448004) (xy 409.656182 -296.494685) (xy 409.633311 -296.538262) (xy 409.603746 -296.577606)
			(xy 409.568253 -296.611698) (xy 409.52775 -296.639654) (xy 409.483288 -296.660752) (xy 409.436017 -296.674444)
			(xy 409.387162 -296.680376) (xy 409.337987 -296.678395) (xy 409.289768 -296.668551) (xy 409.243752 -296.651099)
			(xy 409.201131 -296.626492) (xy 409.16301 -296.595367) (xy 409.130375 -296.55853) (xy 409.104072 -296.516934)
			(xy 409.084781 -296.471658) (xy 409.073004 -296.423874) (xy 409.069044 -296.37482) (xy 406.830276 -296.37482)
			(xy 406.829781 -296.399427) (xy 406.821886 -296.448004) (xy 406.806302 -296.494685) (xy 406.783431 -296.538262)
			(xy 406.753866 -296.577606) (xy 406.718373 -296.611698) (xy 406.67787 -296.639654) (xy 406.633408 -296.660752)
			(xy 406.586137 -296.674444) (xy 406.537282 -296.680376) (xy 406.488107 -296.678395) (xy 406.439888 -296.668551)
			(xy 406.393872 -296.651099) (xy 406.351251 -296.626492) (xy 406.31313 -296.595367) (xy 406.280495 -296.55853)
			(xy 406.254192 -296.516934) (xy 406.234901 -296.471658) (xy 406.223124 -296.423874) (xy 406.219164 -296.37482)
			(xy 404.930356 -296.37482) (xy 404.929861 -296.399427) (xy 404.921966 -296.448004) (xy 404.906382 -296.494685)
			(xy 404.883511 -296.538262) (xy 404.853946 -296.577606) (xy 404.818453 -296.611698) (xy 404.77795 -296.639654)
			(xy 404.733488 -296.660752) (xy 404.686217 -296.674444) (xy 404.637362 -296.680376) (xy 404.588187 -296.678395)
			(xy 404.539968 -296.668551) (xy 404.493952 -296.651099) (xy 404.451331 -296.626492) (xy 404.41321 -296.595367)
			(xy 404.380575 -296.55853) (xy 404.354272 -296.516934) (xy 404.334981 -296.471658) (xy 404.323204 -296.423874)
			(xy 404.319244 -296.37482) (xy 403.030182 -296.37482) (xy 403.029687 -296.399427) (xy 403.021792 -296.448004)
			(xy 403.006208 -296.494685) (xy 402.983337 -296.538262) (xy 402.953772 -296.577606) (xy 402.918279 -296.611698)
			(xy 402.877776 -296.639654) (xy 402.833314 -296.660752) (xy 402.786043 -296.674444) (xy 402.737188 -296.680376)
			(xy 402.688013 -296.678395) (xy 402.639794 -296.668551) (xy 402.593778 -296.651099) (xy 402.551157 -296.626492)
			(xy 402.513036 -296.595367) (xy 402.480401 -296.55853) (xy 402.454098 -296.516934) (xy 402.434807 -296.471658)
			(xy 402.42303 -296.423874) (xy 402.41907 -296.37482) (xy 401.130262 -296.37482) (xy 401.129767 -296.399427)
			(xy 401.121872 -296.448004) (xy 401.106288 -296.494685) (xy 401.083417 -296.538262) (xy 401.053852 -296.577606)
			(xy 401.018359 -296.611698) (xy 400.977856 -296.639654) (xy 400.933394 -296.660752) (xy 400.886123 -296.674444)
			(xy 400.837268 -296.680376) (xy 400.788093 -296.678395) (xy 400.739874 -296.668551) (xy 400.693858 -296.651099)
			(xy 400.651237 -296.626492) (xy 400.613116 -296.595367) (xy 400.580481 -296.55853) (xy 400.554178 -296.516934)
			(xy 400.534887 -296.471658) (xy 400.52311 -296.423874) (xy 400.51915 -296.37482) (xy 399.230342 -296.37482)
			(xy 399.229847 -296.399427) (xy 399.221952 -296.448004) (xy 399.206368 -296.494685) (xy 399.183497 -296.538262)
			(xy 399.153932 -296.577606) (xy 399.118439 -296.611698) (xy 399.077936 -296.639654) (xy 399.033474 -296.660752)
			(xy 398.986203 -296.674444) (xy 398.937348 -296.680376) (xy 398.888173 -296.678395) (xy 398.839954 -296.668551)
			(xy 398.793938 -296.651099) (xy 398.751317 -296.626492) (xy 398.713196 -296.595367) (xy 398.680561 -296.55853)
			(xy 398.654258 -296.516934) (xy 398.634967 -296.471658) (xy 398.62319 -296.423874) (xy 398.61923 -296.37482)
			(xy 397.330168 -296.37482) (xy 397.329673 -296.399427) (xy 397.321778 -296.448004) (xy 397.306194 -296.494685)
			(xy 397.283323 -296.538262) (xy 397.253758 -296.577606) (xy 397.218265 -296.611698) (xy 397.177762 -296.639654)
			(xy 397.1333 -296.660752) (xy 397.086029 -296.674444) (xy 397.037174 -296.680376) (xy 396.987999 -296.678395)
			(xy 396.93978 -296.668551) (xy 396.893764 -296.651099) (xy 396.851143 -296.626492) (xy 396.813022 -296.595367)
			(xy 396.780387 -296.55853) (xy 396.754084 -296.516934) (xy 396.734793 -296.471658) (xy 396.723016 -296.423874)
			(xy 396.719056 -296.37482) (xy 396.380208 -296.37482) (xy 396.379713 -296.399427) (xy 396.371818 -296.448004)
			(xy 396.356234 -296.494685) (xy 396.333363 -296.538262) (xy 396.303798 -296.577606) (xy 396.268305 -296.611698)
			(xy 396.227802 -296.639654) (xy 396.18334 -296.660752) (xy 396.136069 -296.674444) (xy 396.087214 -296.680376)
			(xy 396.038039 -296.678395) (xy 395.98982 -296.668551) (xy 395.943804 -296.651099) (xy 395.901183 -296.626492)
			(xy 395.863062 -296.595367) (xy 395.830427 -296.55853) (xy 395.804124 -296.516934) (xy 395.784833 -296.471658)
			(xy 395.773056 -296.423874) (xy 395.769096 -296.37482) (xy 394.480288 -296.37482) (xy 394.479793 -296.399427)
			(xy 394.471898 -296.448004) (xy 394.456314 -296.494685) (xy 394.433443 -296.538262) (xy 394.403878 -296.577606)
			(xy 394.368385 -296.611698) (xy 394.327882 -296.639654) (xy 394.28342 -296.660752) (xy 394.236149 -296.674444)
			(xy 394.187294 -296.680376) (xy 394.138119 -296.678395) (xy 394.0899 -296.668551) (xy 394.043884 -296.651099)
			(xy 394.001263 -296.626492) (xy 393.963142 -296.595367) (xy 393.930507 -296.55853) (xy 393.904204 -296.516934)
			(xy 393.884913 -296.471658) (xy 393.873136 -296.423874) (xy 393.869176 -296.37482) (xy 393.530328 -296.37482)
			(xy 393.529833 -296.399427) (xy 393.521938 -296.448004) (xy 393.506354 -296.494685) (xy 393.483483 -296.538262)
			(xy 393.453918 -296.577606) (xy 393.418425 -296.611698) (xy 393.377922 -296.639654) (xy 393.33346 -296.660752)
			(xy 393.286189 -296.674444) (xy 393.237334 -296.680376) (xy 393.188159 -296.678395) (xy 393.13994 -296.668551)
			(xy 393.093924 -296.651099) (xy 393.051303 -296.626492) (xy 393.013182 -296.595367) (xy 392.980547 -296.55853)
			(xy 392.954244 -296.516934) (xy 392.934953 -296.471658) (xy 392.923176 -296.423874) (xy 392.919216 -296.37482)
			(xy 392.580114 -296.37482) (xy 392.579619 -296.399427) (xy 392.571724 -296.448004) (xy 392.55614 -296.494685)
			(xy 392.533269 -296.538262) (xy 392.503704 -296.577606) (xy 392.468211 -296.611698) (xy 392.427708 -296.639654)
			(xy 392.383246 -296.660752) (xy 392.335975 -296.674444) (xy 392.28712 -296.680376) (xy 392.237945 -296.678395)
			(xy 392.189726 -296.668551) (xy 392.14371 -296.651099) (xy 392.101089 -296.626492) (xy 392.062968 -296.595367)
			(xy 392.030333 -296.55853) (xy 392.00403 -296.516934) (xy 391.984739 -296.471658) (xy 391.972962 -296.423874)
			(xy 391.969002 -296.37482) (xy 390.680194 -296.37482) (xy 390.679699 -296.399427) (xy 390.671804 -296.448004)
			(xy 390.65622 -296.494685) (xy 390.633349 -296.538262) (xy 390.603784 -296.577606) (xy 390.568291 -296.611698)
			(xy 390.527788 -296.639654) (xy 390.483326 -296.660752) (xy 390.436055 -296.674444) (xy 390.3872 -296.680376)
			(xy 390.338025 -296.678395) (xy 390.289806 -296.668551) (xy 390.24379 -296.651099) (xy 390.201169 -296.626492)
			(xy 390.163048 -296.595367) (xy 390.130413 -296.55853) (xy 390.10411 -296.516934) (xy 390.084819 -296.471658)
			(xy 390.073042 -296.423874) (xy 390.069082 -296.37482) (xy 388.780274 -296.37482) (xy 388.779779 -296.399427)
			(xy 388.771884 -296.448004) (xy 388.7563 -296.494685) (xy 388.733429 -296.538262) (xy 388.703864 -296.577606)
			(xy 388.668371 -296.611698) (xy 388.627868 -296.639654) (xy 388.583406 -296.660752) (xy 388.536135 -296.674444)
			(xy 388.48728 -296.680376) (xy 388.438105 -296.678395) (xy 388.389886 -296.668551) (xy 388.34387 -296.651099)
			(xy 388.301249 -296.626492) (xy 388.263128 -296.595367) (xy 388.230493 -296.55853) (xy 388.20419 -296.516934)
			(xy 388.184899 -296.471658) (xy 388.173122 -296.423874) (xy 388.169162 -296.37482) (xy 387.830314 -296.37482)
			(xy 387.829819 -296.399427) (xy 387.821924 -296.448004) (xy 387.80634 -296.494685) (xy 387.783469 -296.538262)
			(xy 387.753904 -296.577606) (xy 387.718411 -296.611698) (xy 387.677908 -296.639654) (xy 387.633446 -296.660752)
			(xy 387.586175 -296.674444) (xy 387.53732 -296.680376) (xy 387.488145 -296.678395) (xy 387.439926 -296.668551)
			(xy 387.39391 -296.651099) (xy 387.351289 -296.626492) (xy 387.313168 -296.595367) (xy 387.280533 -296.55853)
			(xy 387.25423 -296.516934) (xy 387.234939 -296.471658) (xy 387.223162 -296.423874) (xy 387.219202 -296.37482)
			(xy 386.8801 -296.37482) (xy 386.879605 -296.399427) (xy 386.87171 -296.448004) (xy 386.856126 -296.494685)
			(xy 386.833255 -296.538262) (xy 386.80369 -296.577606) (xy 386.768197 -296.611698) (xy 386.727694 -296.639654)
			(xy 386.683232 -296.660752) (xy 386.635961 -296.674444) (xy 386.587106 -296.680376) (xy 386.537931 -296.678395)
			(xy 386.489712 -296.668551) (xy 386.443696 -296.651099) (xy 386.401075 -296.626492) (xy 386.362954 -296.595367)
			(xy 386.330319 -296.55853) (xy 386.304016 -296.516934) (xy 386.284725 -296.471658) (xy 386.272948 -296.423874)
			(xy 386.268988 -296.37482) (xy 385.930394 -296.37482) (xy 385.929899 -296.399427) (xy 385.922004 -296.448004)
			(xy 385.90642 -296.494685) (xy 385.883549 -296.538262) (xy 385.853984 -296.577606) (xy 385.818491 -296.611698)
			(xy 385.777988 -296.639654) (xy 385.733526 -296.660752) (xy 385.686255 -296.674444) (xy 385.6374 -296.680376)
			(xy 385.588225 -296.678395) (xy 385.540006 -296.668551) (xy 385.49399 -296.651099) (xy 385.451369 -296.626492)
			(xy 385.413248 -296.595367) (xy 385.380613 -296.55853) (xy 385.35431 -296.516934) (xy 385.335019 -296.471658)
			(xy 385.323242 -296.423874) (xy 385.319282 -296.37482) (xy 384.980175 -296.37482) (xy 384.979685 -296.399173)
			(xy 384.97179 -296.44775) (xy 384.956206 -296.494431) (xy 384.933335 -296.538008) (xy 384.90377 -296.577352)
			(xy 384.868277 -296.611444) (xy 384.827774 -296.6394) (xy 384.783312 -296.660498) (xy 384.736041 -296.67419)
			(xy 384.687186 -296.680122) (xy 384.638011 -296.678141) (xy 384.589792 -296.668297) (xy 384.543776 -296.650845)
			(xy 384.501155 -296.626238) (xy 384.463034 -296.595113) (xy 384.430399 -296.558276) (xy 384.404096 -296.51668)
			(xy 384.384805 -296.471404) (xy 384.373028 -296.42362) (xy 384.369068 -296.374566) (xy 382.50915 -296.374566)
			(xy 382.525301 -296.384423) (xy 382.568169 -296.420098) (xy 382.605386 -296.461635) (xy 382.636159 -296.508148)
			(xy 382.659831 -296.558645) (xy 382.675899 -296.612052) (xy 382.684019 -296.667228) (xy 382.684528 -296.695114)
			(xy 382.684019 -296.723) (xy 382.675899 -296.778176) (xy 382.659831 -296.831583) (xy 382.636159 -296.88208)
			(xy 382.605386 -296.928593) (xy 382.568169 -296.97013) (xy 382.525301 -297.005805) (xy 382.477695 -297.034859)
			(xy 382.426366 -297.056671) (xy 382.372409 -297.070777) (xy 382.316972 -297.076877) (xy 382.261238 -297.07484)
			(xy 382.206395 -297.06471) (xy 382.153611 -297.046703) (xy 382.104011 -297.021202) (xy 382.058653 -296.988751)
			(xy 382.018504 -296.950042) (xy 381.984418 -296.905899) (xy 381.957122 -296.857264) (xy 381.937199 -296.805173)
			(xy 381.925073 -296.750736) (xy 381.921002 -296.695114) (xy 381.798068 -296.695114) (xy 381.797559 -296.723)
			(xy 381.789439 -296.778176) (xy 381.773371 -296.831583) (xy 381.749699 -296.88208) (xy 381.718926 -296.928593)
			(xy 381.681709 -296.97013) (xy 381.638841 -297.005805) (xy 381.591235 -297.034859) (xy 381.539906 -297.056671)
			(xy 381.485949 -297.070777) (xy 381.430512 -297.076877) (xy 381.374778 -297.07484) (xy 381.319935 -297.06471)
			(xy 381.267151 -297.046703) (xy 381.217551 -297.021202) (xy 381.172193 -296.988751) (xy 381.132044 -296.950042)
			(xy 381.097958 -296.905899) (xy 381.070662 -296.857264) (xy 381.050739 -296.805173) (xy 381.038613 -296.750736)
			(xy 381.034542 -296.695114) (xy 380.401068 -296.695114) (xy 380.400582 -296.722365) (xy 380.392826 -296.776313)
			(xy 380.377471 -296.828608) (xy 380.354829 -296.878185) (xy 380.325363 -296.924035) (xy 380.289672 -296.965226)
			(xy 380.248481 -297.000917) (xy 380.202631 -297.030383) (xy 380.153054 -297.053025) (xy 380.100759 -297.06838)
			(xy 380.046811 -297.076136) (xy 379.992309 -297.076136) (xy 379.938361 -297.06838) (xy 379.886066 -297.053025)
			(xy 379.836489 -297.030383) (xy 379.790639 -297.000917) (xy 379.749448 -296.965226) (xy 379.713757 -296.924035)
			(xy 379.684291 -296.878185) (xy 379.661649 -296.828608) (xy 379.646294 -296.776313) (xy 379.638538 -296.722365)
			(xy 379.638052 -296.695114) (xy 351.031048 -296.695114) (xy 351.031048 -297.3248) (xy 383.734049 -297.3248)
			(xy 383.73822 -297.274461) (xy 383.750619 -297.225496) (xy 383.770908 -297.179239) (xy 383.798533 -297.136952)
			(xy 383.832742 -297.099788) (xy 383.872601 -297.068761) (xy 383.917022 -297.044718) (xy 383.964795 -297.028314)
			(xy 384.014617 -297.019996) (xy 384.039872 -297.019472) (xy 384.065267 -297.019985) (xy 384.115357 -297.028398)
			(xy 384.163364 -297.044982) (xy 384.207966 -297.069279) (xy 384.247935 -297.100619) (xy 384.265424 -297.11904)
			(xy 384.273044 -297.127168) (xy 384.292856 -297.135804) (xy 384.39217 -297.13301) (xy 384.411728 -297.123612)
			(xy 384.41884 -297.114976) (xy 384.43463 -297.096405) (xy 384.470763 -297.063686) (xy 384.511304 -297.036619)
			(xy 384.555376 -297.01579) (xy 384.602026 -297.00165) (xy 384.650245 -296.994504) (xy 384.674618 -296.994072)
			(xy 385.624578 -296.994072) (xy 385.650567 -296.994593) (xy 385.701905 -297.002721) (xy 385.751339 -297.018781)
			(xy 385.797653 -297.042376) (xy 385.839705 -297.072926) (xy 385.87646 -297.109678) (xy 385.907013 -297.151728)
			(xy 385.930611 -297.19804) (xy 385.946673 -297.247474) (xy 385.954805 -297.298811) (xy 385.954805 -297.32478)
			(xy 386.268988 -297.32478) (xy 386.272948 -297.275726) (xy 386.284725 -297.227942) (xy 386.304016 -297.182666)
			(xy 386.330319 -297.14107) (xy 386.362954 -297.104233) (xy 386.401075 -297.073108) (xy 386.443696 -297.048501)
			(xy 386.489712 -297.031049) (xy 386.537931 -297.021205) (xy 386.587106 -297.019224) (xy 386.635961 -297.025156)
			(xy 386.683232 -297.038848) (xy 386.727694 -297.059946) (xy 386.768197 -297.087902) (xy 386.80369 -297.121994)
			(xy 386.833255 -297.161338) (xy 386.856126 -297.204915) (xy 386.87171 -297.251596) (xy 386.879605 -297.300173)
			(xy 386.8801 -297.32478) (xy 387.219202 -297.32478) (xy 387.223162 -297.275726) (xy 387.234939 -297.227942)
			(xy 387.25423 -297.182666) (xy 387.280533 -297.14107) (xy 387.313168 -297.104233) (xy 387.351289 -297.073108)
			(xy 387.39391 -297.048501) (xy 387.439926 -297.031049) (xy 387.488145 -297.021205) (xy 387.53732 -297.019224)
			(xy 387.586175 -297.025156) (xy 387.633446 -297.038848) (xy 387.677908 -297.059946) (xy 387.718411 -297.087902)
			(xy 387.753904 -297.121994) (xy 387.783469 -297.161338) (xy 387.80634 -297.204915) (xy 387.821924 -297.251596)
			(xy 387.829819 -297.300173) (xy 387.830314 -297.32478) (xy 390.069082 -297.32478) (xy 390.073042 -297.275726)
			(xy 390.084819 -297.227942) (xy 390.10411 -297.182666) (xy 390.130413 -297.14107) (xy 390.163048 -297.104233)
			(xy 390.201169 -297.073108) (xy 390.24379 -297.048501) (xy 390.289806 -297.031049) (xy 390.338025 -297.021205)
			(xy 390.3872 -297.019224) (xy 390.436055 -297.025156) (xy 390.483326 -297.038848) (xy 390.527788 -297.059946)
			(xy 390.568291 -297.087902) (xy 390.603784 -297.121994) (xy 390.633349 -297.161338) (xy 390.65622 -297.204915)
			(xy 390.671804 -297.251596) (xy 390.679699 -297.300173) (xy 390.680194 -297.32478) (xy 391.019042 -297.32478)
			(xy 391.023002 -297.275726) (xy 391.034779 -297.227942) (xy 391.05407 -297.182666) (xy 391.080373 -297.14107)
			(xy 391.113008 -297.104233) (xy 391.151129 -297.073108) (xy 391.19375 -297.048501) (xy 391.239766 -297.031049)
			(xy 391.287985 -297.021205) (xy 391.33716 -297.019224) (xy 391.386015 -297.025156) (xy 391.433286 -297.038848)
			(xy 391.477748 -297.059946) (xy 391.518251 -297.087902) (xy 391.553744 -297.121994) (xy 391.583309 -297.161338)
			(xy 391.60618 -297.204915) (xy 391.621764 -297.251596) (xy 391.629659 -297.300173) (xy 391.630154 -297.32478)
			(xy 391.969002 -297.32478) (xy 391.972962 -297.275726) (xy 391.984739 -297.227942) (xy 392.00403 -297.182666)
			(xy 392.030333 -297.14107) (xy 392.062968 -297.104233) (xy 392.101089 -297.073108) (xy 392.14371 -297.048501)
			(xy 392.189726 -297.031049) (xy 392.237945 -297.021205) (xy 392.28712 -297.019224) (xy 392.335975 -297.025156)
			(xy 392.383246 -297.038848) (xy 392.427708 -297.059946) (xy 392.468211 -297.087902) (xy 392.503704 -297.121994)
			(xy 392.533269 -297.161338) (xy 392.55614 -297.204915) (xy 392.571724 -297.251596) (xy 392.579619 -297.300173)
			(xy 392.580114 -297.32478) (xy 392.919216 -297.32478) (xy 392.923176 -297.275726) (xy 392.934953 -297.227942)
			(xy 392.954244 -297.182666) (xy 392.980547 -297.14107) (xy 393.013182 -297.104233) (xy 393.051303 -297.073108)
			(xy 393.093924 -297.048501) (xy 393.13994 -297.031049) (xy 393.188159 -297.021205) (xy 393.237334 -297.019224)
			(xy 393.286189 -297.025156) (xy 393.33346 -297.038848) (xy 393.377922 -297.059946) (xy 393.418425 -297.087902)
			(xy 393.453918 -297.121994) (xy 393.483483 -297.161338) (xy 393.506354 -297.204915) (xy 393.521938 -297.251596)
			(xy 393.529833 -297.300173) (xy 393.530328 -297.32478) (xy 393.869176 -297.32478) (xy 393.873136 -297.275726)
			(xy 393.884913 -297.227942) (xy 393.904204 -297.182666) (xy 393.930507 -297.14107) (xy 393.963142 -297.104233)
			(xy 394.001263 -297.073108) (xy 394.043884 -297.048501) (xy 394.0899 -297.031049) (xy 394.138119 -297.021205)
			(xy 394.187294 -297.019224) (xy 394.236149 -297.025156) (xy 394.28342 -297.038848) (xy 394.327882 -297.059946)
			(xy 394.368385 -297.087902) (xy 394.403878 -297.121994) (xy 394.433443 -297.161338) (xy 394.456314 -297.204915)
			(xy 394.471898 -297.251596) (xy 394.479793 -297.300173) (xy 394.480288 -297.32478) (xy 394.819136 -297.32478)
			(xy 394.823096 -297.275726) (xy 394.834873 -297.227942) (xy 394.854164 -297.182666) (xy 394.880467 -297.14107)
			(xy 394.913102 -297.104233) (xy 394.951223 -297.073108) (xy 394.993844 -297.048501) (xy 395.03986 -297.031049)
			(xy 395.088079 -297.021205) (xy 395.137254 -297.019224) (xy 395.186109 -297.025156) (xy 395.23338 -297.038848)
			(xy 395.277842 -297.059946) (xy 395.318345 -297.087902) (xy 395.353838 -297.121994) (xy 395.383403 -297.161338)
			(xy 395.406274 -297.204915) (xy 395.421858 -297.251596) (xy 395.429753 -297.300173) (xy 395.430248 -297.32478)
			(xy 395.769096 -297.32478) (xy 395.773056 -297.275726) (xy 395.784833 -297.227942) (xy 395.804124 -297.182666)
			(xy 395.830427 -297.14107) (xy 395.863062 -297.104233) (xy 395.901183 -297.073108) (xy 395.943804 -297.048501)
			(xy 395.98982 -297.031049) (xy 396.038039 -297.021205) (xy 396.087214 -297.019224) (xy 396.136069 -297.025156)
			(xy 396.18334 -297.038848) (xy 396.227802 -297.059946) (xy 396.268305 -297.087902) (xy 396.303798 -297.121994)
			(xy 396.333363 -297.161338) (xy 396.356234 -297.204915) (xy 396.371818 -297.251596) (xy 396.379713 -297.300173)
			(xy 396.380208 -297.32478) (xy 397.669016 -297.32478) (xy 397.672976 -297.275726) (xy 397.684753 -297.227942)
			(xy 397.704044 -297.182666) (xy 397.730347 -297.14107) (xy 397.762982 -297.104233) (xy 397.801103 -297.073108)
			(xy 397.843724 -297.048501) (xy 397.88974 -297.031049) (xy 397.937959 -297.021205) (xy 397.987134 -297.019224)
			(xy 398.035989 -297.025156) (xy 398.08326 -297.038848) (xy 398.127722 -297.059946) (xy 398.168225 -297.087902)
			(xy 398.203718 -297.121994) (xy 398.233283 -297.161338) (xy 398.256154 -297.204915) (xy 398.271738 -297.251596)
			(xy 398.279633 -297.300173) (xy 398.280128 -297.32478) (xy 399.56919 -297.32478) (xy 399.57315 -297.275726)
			(xy 399.584927 -297.227942) (xy 399.604218 -297.182666) (xy 399.630521 -297.14107) (xy 399.663156 -297.104233)
			(xy 399.701277 -297.073108) (xy 399.743898 -297.048501) (xy 399.789914 -297.031049) (xy 399.838133 -297.021205)
			(xy 399.887308 -297.019224) (xy 399.936163 -297.025156) (xy 399.983434 -297.038848) (xy 400.027896 -297.059946)
			(xy 400.068399 -297.087902) (xy 400.103892 -297.121994) (xy 400.133457 -297.161338) (xy 400.156328 -297.204915)
			(xy 400.171912 -297.251596) (xy 400.179807 -297.300173) (xy 400.180302 -297.32478) (xy 401.46911 -297.32478)
			(xy 401.47307 -297.275726) (xy 401.484847 -297.227942) (xy 401.504138 -297.182666) (xy 401.530441 -297.14107)
			(xy 401.563076 -297.104233) (xy 401.601197 -297.073108) (xy 401.643818 -297.048501) (xy 401.689834 -297.031049)
			(xy 401.738053 -297.021205) (xy 401.787228 -297.019224) (xy 401.836083 -297.025156) (xy 401.883354 -297.038848)
			(xy 401.927816 -297.059946) (xy 401.968319 -297.087902) (xy 402.003812 -297.121994) (xy 402.033377 -297.161338)
			(xy 402.056248 -297.204915) (xy 402.071832 -297.251596) (xy 402.079727 -297.300173) (xy 402.080222 -297.32478)
			(xy 403.36903 -297.32478) (xy 403.37299 -297.275726) (xy 403.384767 -297.227942) (xy 403.404058 -297.182666)
			(xy 403.430361 -297.14107) (xy 403.462996 -297.104233) (xy 403.501117 -297.073108) (xy 403.543738 -297.048501)
			(xy 403.589754 -297.031049) (xy 403.637973 -297.021205) (xy 403.687148 -297.019224) (xy 403.736003 -297.025156)
			(xy 403.783274 -297.038848) (xy 403.827736 -297.059946) (xy 403.868239 -297.087902) (xy 403.903732 -297.121994)
			(xy 403.933297 -297.161338) (xy 403.956168 -297.204915) (xy 403.971752 -297.251596) (xy 403.979647 -297.300173)
			(xy 403.980142 -297.32478) (xy 405.269204 -297.32478) (xy 405.273164 -297.275726) (xy 405.284941 -297.227942)
			(xy 405.304232 -297.182666) (xy 405.330535 -297.14107) (xy 405.36317 -297.104233) (xy 405.401291 -297.073108)
			(xy 405.443912 -297.048501) (xy 405.489928 -297.031049) (xy 405.538147 -297.021205) (xy 405.587322 -297.019224)
			(xy 405.636177 -297.025156) (xy 405.683448 -297.038848) (xy 405.72791 -297.059946) (xy 405.768413 -297.087902)
			(xy 405.803906 -297.121994) (xy 405.833471 -297.161338) (xy 405.856342 -297.204915) (xy 405.871926 -297.251596)
			(xy 405.879821 -297.300173) (xy 405.880316 -297.32478) (xy 408.119084 -297.32478) (xy 408.123044 -297.275726)
			(xy 408.134821 -297.227942) (xy 408.154112 -297.182666) (xy 408.180415 -297.14107) (xy 408.21305 -297.104233)
			(xy 408.251171 -297.073108) (xy 408.293792 -297.048501) (xy 408.339808 -297.031049) (xy 408.388027 -297.021205)
			(xy 408.437202 -297.019224) (xy 408.486057 -297.025156) (xy 408.533328 -297.038848) (xy 408.57779 -297.059946)
			(xy 408.618293 -297.087902) (xy 408.653786 -297.121994) (xy 408.683351 -297.161338) (xy 408.706222 -297.204915)
			(xy 408.721806 -297.251596) (xy 408.729701 -297.300173) (xy 408.730196 -297.32478) (xy 410.019004 -297.32478)
			(xy 410.022964 -297.275726) (xy 410.034741 -297.227942) (xy 410.054032 -297.182666) (xy 410.080335 -297.14107)
			(xy 410.11297 -297.104233) (xy 410.151091 -297.073108) (xy 410.193712 -297.048501) (xy 410.239728 -297.031049)
			(xy 410.287947 -297.021205) (xy 410.337122 -297.019224) (xy 410.385977 -297.025156) (xy 410.433248 -297.038848)
			(xy 410.47771 -297.059946) (xy 410.518213 -297.087902) (xy 410.553706 -297.121994) (xy 410.583271 -297.161338)
			(xy 410.606142 -297.204915) (xy 410.621726 -297.251596) (xy 410.629621 -297.300173) (xy 410.630116 -297.32478)
			(xy 411.919178 -297.32478) (xy 411.923138 -297.275726) (xy 411.934915 -297.227942) (xy 411.954206 -297.182666)
			(xy 411.980509 -297.14107) (xy 412.013144 -297.104233) (xy 412.051265 -297.073108) (xy 412.093886 -297.048501)
			(xy 412.139902 -297.031049) (xy 412.188121 -297.021205) (xy 412.237296 -297.019224) (xy 412.286151 -297.025156)
			(xy 412.333422 -297.038848) (xy 412.377884 -297.059946) (xy 412.418387 -297.087902) (xy 412.45388 -297.121994)
			(xy 412.483445 -297.161338) (xy 412.506316 -297.204915) (xy 412.5219 -297.251596) (xy 412.529795 -297.300173)
			(xy 412.53029 -297.32478) (xy 413.819098 -297.32478) (xy 413.823058 -297.275726) (xy 413.834835 -297.227942)
			(xy 413.854126 -297.182666) (xy 413.880429 -297.14107) (xy 413.913064 -297.104233) (xy 413.951185 -297.073108)
			(xy 413.993806 -297.048501) (xy 414.039822 -297.031049) (xy 414.088041 -297.021205) (xy 414.137216 -297.019224)
			(xy 414.186071 -297.025156) (xy 414.233342 -297.038848) (xy 414.277804 -297.059946) (xy 414.318307 -297.087902)
			(xy 414.3538 -297.121994) (xy 414.383365 -297.161338) (xy 414.406236 -297.204915) (xy 414.42182 -297.251596)
			(xy 414.429715 -297.300173) (xy 414.43021 -297.32478) (xy 414.769058 -297.32478) (xy 414.773018 -297.275726)
			(xy 414.784795 -297.227942) (xy 414.804086 -297.182666) (xy 414.830389 -297.14107) (xy 414.863024 -297.104233)
			(xy 414.901145 -297.073108) (xy 414.943766 -297.048501) (xy 414.989782 -297.031049) (xy 415.038001 -297.021205)
			(xy 415.087176 -297.019224) (xy 415.136031 -297.025156) (xy 415.183302 -297.038848) (xy 415.227764 -297.059946)
			(xy 415.268267 -297.087902) (xy 415.30376 -297.121994) (xy 415.333325 -297.161338) (xy 415.356196 -297.204915)
			(xy 415.37178 -297.251596) (xy 415.379675 -297.300173) (xy 415.38017 -297.32478) (xy 415.719018 -297.32478)
			(xy 415.722978 -297.275726) (xy 415.734755 -297.227942) (xy 415.754046 -297.182666) (xy 415.780349 -297.14107)
			(xy 415.812984 -297.104233) (xy 415.851105 -297.073108) (xy 415.893726 -297.048501) (xy 415.939742 -297.031049)
			(xy 415.987961 -297.021205) (xy 416.037136 -297.019224) (xy 416.085991 -297.025156) (xy 416.133262 -297.038848)
			(xy 416.177724 -297.059946) (xy 416.218227 -297.087902) (xy 416.25372 -297.121994) (xy 416.283285 -297.161338)
			(xy 416.306156 -297.204915) (xy 416.32174 -297.251596) (xy 416.329635 -297.300173) (xy 416.33013 -297.32478)
			(xy 416.329635 -297.349387) (xy 416.32174 -297.397964) (xy 416.306156 -297.444645) (xy 416.283285 -297.488222)
			(xy 416.25372 -297.527566) (xy 416.218227 -297.561658) (xy 416.177724 -297.589614) (xy 416.133262 -297.610712)
			(xy 416.085991 -297.624404) (xy 416.037136 -297.630336) (xy 415.987961 -297.628355) (xy 415.939742 -297.618511)
			(xy 415.893726 -297.601059) (xy 415.851105 -297.576452) (xy 415.812984 -297.545327) (xy 415.780349 -297.50849)
			(xy 415.754046 -297.466894) (xy 415.734755 -297.421618) (xy 415.722978 -297.373834) (xy 415.719018 -297.32478)
			(xy 415.38017 -297.32478) (xy 415.379675 -297.349387) (xy 415.37178 -297.397964) (xy 415.356196 -297.444645)
			(xy 415.333325 -297.488222) (xy 415.30376 -297.527566) (xy 415.268267 -297.561658) (xy 415.227764 -297.589614)
			(xy 415.183302 -297.610712) (xy 415.136031 -297.624404) (xy 415.087176 -297.630336) (xy 415.038001 -297.628355)
			(xy 414.989782 -297.618511) (xy 414.943766 -297.601059) (xy 414.901145 -297.576452) (xy 414.863024 -297.545327)
			(xy 414.830389 -297.50849) (xy 414.804086 -297.466894) (xy 414.784795 -297.421618) (xy 414.773018 -297.373834)
			(xy 414.769058 -297.32478) (xy 414.43021 -297.32478) (xy 414.429715 -297.349387) (xy 414.42182 -297.397964)
			(xy 414.406236 -297.444645) (xy 414.383365 -297.488222) (xy 414.3538 -297.527566) (xy 414.318307 -297.561658)
			(xy 414.277804 -297.589614) (xy 414.233342 -297.610712) (xy 414.186071 -297.624404) (xy 414.137216 -297.630336)
			(xy 414.088041 -297.628355) (xy 414.039822 -297.618511) (xy 413.993806 -297.601059) (xy 413.951185 -297.576452)
			(xy 413.913064 -297.545327) (xy 413.880429 -297.50849) (xy 413.854126 -297.466894) (xy 413.834835 -297.421618)
			(xy 413.823058 -297.373834) (xy 413.819098 -297.32478) (xy 412.53029 -297.32478) (xy 412.529795 -297.349387)
			(xy 412.5219 -297.397964) (xy 412.506316 -297.444645) (xy 412.483445 -297.488222) (xy 412.45388 -297.527566)
			(xy 412.418387 -297.561658) (xy 412.377884 -297.589614) (xy 412.333422 -297.610712) (xy 412.286151 -297.624404)
			(xy 412.237296 -297.630336) (xy 412.188121 -297.628355) (xy 412.139902 -297.618511) (xy 412.093886 -297.601059)
			(xy 412.051265 -297.576452) (xy 412.013144 -297.545327) (xy 411.980509 -297.50849) (xy 411.954206 -297.466894)
			(xy 411.934915 -297.421618) (xy 411.923138 -297.373834) (xy 411.919178 -297.32478) (xy 410.630116 -297.32478)
			(xy 410.629621 -297.349387) (xy 410.621726 -297.397964) (xy 410.606142 -297.444645) (xy 410.583271 -297.488222)
			(xy 410.553706 -297.527566) (xy 410.518213 -297.561658) (xy 410.47771 -297.589614) (xy 410.433248 -297.610712)
			(xy 410.385977 -297.624404) (xy 410.337122 -297.630336) (xy 410.287947 -297.628355) (xy 410.239728 -297.618511)
			(xy 410.193712 -297.601059) (xy 410.151091 -297.576452) (xy 410.11297 -297.545327) (xy 410.080335 -297.50849)
			(xy 410.054032 -297.466894) (xy 410.034741 -297.421618) (xy 410.022964 -297.373834) (xy 410.019004 -297.32478)
			(xy 408.730196 -297.32478) (xy 408.729701 -297.349387) (xy 408.721806 -297.397964) (xy 408.706222 -297.444645)
			(xy 408.683351 -297.488222) (xy 408.653786 -297.527566) (xy 408.618293 -297.561658) (xy 408.57779 -297.589614)
			(xy 408.533328 -297.610712) (xy 408.486057 -297.624404) (xy 408.437202 -297.630336) (xy 408.388027 -297.628355)
			(xy 408.339808 -297.618511) (xy 408.293792 -297.601059) (xy 408.251171 -297.576452) (xy 408.21305 -297.545327)
			(xy 408.180415 -297.50849) (xy 408.154112 -297.466894) (xy 408.134821 -297.421618) (xy 408.123044 -297.373834)
			(xy 408.119084 -297.32478) (xy 405.880316 -297.32478) (xy 405.879821 -297.349387) (xy 405.871926 -297.397964)
			(xy 405.856342 -297.444645) (xy 405.833471 -297.488222) (xy 405.803906 -297.527566) (xy 405.768413 -297.561658)
			(xy 405.72791 -297.589614) (xy 405.683448 -297.610712) (xy 405.636177 -297.624404) (xy 405.587322 -297.630336)
			(xy 405.538147 -297.628355) (xy 405.489928 -297.618511) (xy 405.443912 -297.601059) (xy 405.401291 -297.576452)
			(xy 405.36317 -297.545327) (xy 405.330535 -297.50849) (xy 405.304232 -297.466894) (xy 405.284941 -297.421618)
			(xy 405.273164 -297.373834) (xy 405.269204 -297.32478) (xy 403.980142 -297.32478) (xy 403.979647 -297.349387)
			(xy 403.971752 -297.397964) (xy 403.956168 -297.444645) (xy 403.933297 -297.488222) (xy 403.903732 -297.527566)
			(xy 403.868239 -297.561658) (xy 403.827736 -297.589614) (xy 403.783274 -297.610712) (xy 403.736003 -297.624404)
			(xy 403.687148 -297.630336) (xy 403.637973 -297.628355) (xy 403.589754 -297.618511) (xy 403.543738 -297.601059)
			(xy 403.501117 -297.576452) (xy 403.462996 -297.545327) (xy 403.430361 -297.50849) (xy 403.404058 -297.466894)
			(xy 403.384767 -297.421618) (xy 403.37299 -297.373834) (xy 403.36903 -297.32478) (xy 402.080222 -297.32478)
			(xy 402.079727 -297.349387) (xy 402.071832 -297.397964) (xy 402.056248 -297.444645) (xy 402.033377 -297.488222)
			(xy 402.003812 -297.527566) (xy 401.968319 -297.561658) (xy 401.927816 -297.589614) (xy 401.883354 -297.610712)
			(xy 401.836083 -297.624404) (xy 401.787228 -297.630336) (xy 401.738053 -297.628355) (xy 401.689834 -297.618511)
			(xy 401.643818 -297.601059) (xy 401.601197 -297.576452) (xy 401.563076 -297.545327) (xy 401.530441 -297.50849)
			(xy 401.504138 -297.466894) (xy 401.484847 -297.421618) (xy 401.47307 -297.373834) (xy 401.46911 -297.32478)
			(xy 400.180302 -297.32478) (xy 400.179807 -297.349387) (xy 400.171912 -297.397964) (xy 400.156328 -297.444645)
			(xy 400.133457 -297.488222) (xy 400.103892 -297.527566) (xy 400.068399 -297.561658) (xy 400.027896 -297.589614)
			(xy 399.983434 -297.610712) (xy 399.936163 -297.624404) (xy 399.887308 -297.630336) (xy 399.838133 -297.628355)
			(xy 399.789914 -297.618511) (xy 399.743898 -297.601059) (xy 399.701277 -297.576452) (xy 399.663156 -297.545327)
			(xy 399.630521 -297.50849) (xy 399.604218 -297.466894) (xy 399.584927 -297.421618) (xy 399.57315 -297.373834)
			(xy 399.56919 -297.32478) (xy 398.280128 -297.32478) (xy 398.279633 -297.349387) (xy 398.271738 -297.397964)
			(xy 398.256154 -297.444645) (xy 398.233283 -297.488222) (xy 398.203718 -297.527566) (xy 398.168225 -297.561658)
			(xy 398.127722 -297.589614) (xy 398.08326 -297.610712) (xy 398.035989 -297.624404) (xy 397.987134 -297.630336)
			(xy 397.937959 -297.628355) (xy 397.88974 -297.618511) (xy 397.843724 -297.601059) (xy 397.801103 -297.576452)
			(xy 397.762982 -297.545327) (xy 397.730347 -297.50849) (xy 397.704044 -297.466894) (xy 397.684753 -297.421618)
			(xy 397.672976 -297.373834) (xy 397.669016 -297.32478) (xy 396.380208 -297.32478) (xy 396.379713 -297.349387)
			(xy 396.371818 -297.397964) (xy 396.356234 -297.444645) (xy 396.333363 -297.488222) (xy 396.303798 -297.527566)
			(xy 396.268305 -297.561658) (xy 396.227802 -297.589614) (xy 396.18334 -297.610712) (xy 396.136069 -297.624404)
			(xy 396.087214 -297.630336) (xy 396.038039 -297.628355) (xy 395.98982 -297.618511) (xy 395.943804 -297.601059)
			(xy 395.901183 -297.576452) (xy 395.863062 -297.545327) (xy 395.830427 -297.50849) (xy 395.804124 -297.466894)
			(xy 395.784833 -297.421618) (xy 395.773056 -297.373834) (xy 395.769096 -297.32478) (xy 395.430248 -297.32478)
			(xy 395.429753 -297.349387) (xy 395.421858 -297.397964) (xy 395.406274 -297.444645) (xy 395.383403 -297.488222)
			(xy 395.353838 -297.527566) (xy 395.318345 -297.561658) (xy 395.277842 -297.589614) (xy 395.23338 -297.610712)
			(xy 395.186109 -297.624404) (xy 395.137254 -297.630336) (xy 395.088079 -297.628355) (xy 395.03986 -297.618511)
			(xy 394.993844 -297.601059) (xy 394.951223 -297.576452) (xy 394.913102 -297.545327) (xy 394.880467 -297.50849)
			(xy 394.854164 -297.466894) (xy 394.834873 -297.421618) (xy 394.823096 -297.373834) (xy 394.819136 -297.32478)
			(xy 394.480288 -297.32478) (xy 394.479793 -297.349387) (xy 394.471898 -297.397964) (xy 394.456314 -297.444645)
			(xy 394.433443 -297.488222) (xy 394.403878 -297.527566) (xy 394.368385 -297.561658) (xy 394.327882 -297.589614)
			(xy 394.28342 -297.610712) (xy 394.236149 -297.624404) (xy 394.187294 -297.630336) (xy 394.138119 -297.628355)
			(xy 394.0899 -297.618511) (xy 394.043884 -297.601059) (xy 394.001263 -297.576452) (xy 393.963142 -297.545327)
			(xy 393.930507 -297.50849) (xy 393.904204 -297.466894) (xy 393.884913 -297.421618) (xy 393.873136 -297.373834)
			(xy 393.869176 -297.32478) (xy 393.530328 -297.32478) (xy 393.529833 -297.349387) (xy 393.521938 -297.397964)
			(xy 393.506354 -297.444645) (xy 393.483483 -297.488222) (xy 393.453918 -297.527566) (xy 393.418425 -297.561658)
			(xy 393.377922 -297.589614) (xy 393.33346 -297.610712) (xy 393.286189 -297.624404) (xy 393.237334 -297.630336)
			(xy 393.188159 -297.628355) (xy 393.13994 -297.618511) (xy 393.093924 -297.601059) (xy 393.051303 -297.576452)
			(xy 393.013182 -297.545327) (xy 392.980547 -297.50849) (xy 392.954244 -297.466894) (xy 392.934953 -297.421618)
			(xy 392.923176 -297.373834) (xy 392.919216 -297.32478) (xy 392.580114 -297.32478) (xy 392.579619 -297.349387)
			(xy 392.571724 -297.397964) (xy 392.55614 -297.444645) (xy 392.533269 -297.488222) (xy 392.503704 -297.527566)
			(xy 392.468211 -297.561658) (xy 392.427708 -297.589614) (xy 392.383246 -297.610712) (xy 392.335975 -297.624404)
			(xy 392.28712 -297.630336) (xy 392.237945 -297.628355) (xy 392.189726 -297.618511) (xy 392.14371 -297.601059)
			(xy 392.101089 -297.576452) (xy 392.062968 -297.545327) (xy 392.030333 -297.50849) (xy 392.00403 -297.466894)
			(xy 391.984739 -297.421618) (xy 391.972962 -297.373834) (xy 391.969002 -297.32478) (xy 391.630154 -297.32478)
			(xy 391.629659 -297.349387) (xy 391.621764 -297.397964) (xy 391.60618 -297.444645) (xy 391.583309 -297.488222)
			(xy 391.553744 -297.527566) (xy 391.518251 -297.561658) (xy 391.477748 -297.589614) (xy 391.433286 -297.610712)
			(xy 391.386015 -297.624404) (xy 391.33716 -297.630336) (xy 391.287985 -297.628355) (xy 391.239766 -297.618511)
			(xy 391.19375 -297.601059) (xy 391.151129 -297.576452) (xy 391.113008 -297.545327) (xy 391.080373 -297.50849)
			(xy 391.05407 -297.466894) (xy 391.034779 -297.421618) (xy 391.023002 -297.373834) (xy 391.019042 -297.32478)
			(xy 390.680194 -297.32478) (xy 390.679699 -297.349387) (xy 390.671804 -297.397964) (xy 390.65622 -297.444645)
			(xy 390.633349 -297.488222) (xy 390.603784 -297.527566) (xy 390.568291 -297.561658) (xy 390.527788 -297.589614)
			(xy 390.483326 -297.610712) (xy 390.436055 -297.624404) (xy 390.3872 -297.630336) (xy 390.338025 -297.628355)
			(xy 390.289806 -297.618511) (xy 390.24379 -297.601059) (xy 390.201169 -297.576452) (xy 390.163048 -297.545327)
			(xy 390.130413 -297.50849) (xy 390.10411 -297.466894) (xy 390.084819 -297.421618) (xy 390.073042 -297.373834)
			(xy 390.069082 -297.32478) (xy 387.830314 -297.32478) (xy 387.829819 -297.349387) (xy 387.821924 -297.397964)
			(xy 387.80634 -297.444645) (xy 387.783469 -297.488222) (xy 387.753904 -297.527566) (xy 387.718411 -297.561658)
			(xy 387.677908 -297.589614) (xy 387.633446 -297.610712) (xy 387.586175 -297.624404) (xy 387.53732 -297.630336)
			(xy 387.488145 -297.628355) (xy 387.439926 -297.618511) (xy 387.39391 -297.601059) (xy 387.351289 -297.576452)
			(xy 387.313168 -297.545327) (xy 387.280533 -297.50849) (xy 387.25423 -297.466894) (xy 387.234939 -297.421618)
			(xy 387.223162 -297.373834) (xy 387.219202 -297.32478) (xy 386.8801 -297.32478) (xy 386.879605 -297.349387)
			(xy 386.87171 -297.397964) (xy 386.856126 -297.444645) (xy 386.833255 -297.488222) (xy 386.80369 -297.527566)
			(xy 386.768197 -297.561658) (xy 386.727694 -297.589614) (xy 386.683232 -297.610712) (xy 386.635961 -297.624404)
			(xy 386.587106 -297.630336) (xy 386.537931 -297.628355) (xy 386.489712 -297.618511) (xy 386.443696 -297.601059)
			(xy 386.401075 -297.576452) (xy 386.362954 -297.545327) (xy 386.330319 -297.50849) (xy 386.304016 -297.466894)
			(xy 386.284725 -297.421618) (xy 386.272948 -297.373834) (xy 386.268988 -297.32478) (xy 385.954805 -297.32478)
			(xy 385.954805 -297.350789) (xy 385.946673 -297.402126) (xy 385.930611 -297.45156) (xy 385.907013 -297.497872)
			(xy 385.87646 -297.539922) (xy 385.839705 -297.576674) (xy 385.797653 -297.607224) (xy 385.751339 -297.630819)
			(xy 385.701905 -297.646879) (xy 385.650567 -297.655007) (xy 385.624578 -297.655488) (xy 384.674618 -297.655488)
			(xy 384.650244 -297.655085) (xy 384.602024 -297.647936) (xy 384.555373 -297.633791) (xy 384.511303 -297.612954)
			(xy 384.470767 -297.585877) (xy 384.434642 -297.553147) (xy 384.41884 -297.534584) (xy 384.411728 -297.525948)
			(xy 384.39217 -297.51655) (xy 384.292856 -297.513756) (xy 384.273044 -297.522392) (xy 384.265424 -297.53052)
			(xy 384.247939 -297.548946) (xy 384.207975 -297.580297) (xy 384.163372 -297.604598) (xy 384.115362 -297.621181)
			(xy 384.065269 -297.629585) (xy 384.039872 -297.630088) (xy 384.014617 -297.629604) (xy 383.964795 -297.621286)
			(xy 383.917022 -297.604882) (xy 383.872601 -297.580839) (xy 383.832742 -297.549812) (xy 383.798533 -297.512648)
			(xy 383.770908 -297.470361) (xy 383.750619 -297.424104) (xy 383.73822 -297.375139) (xy 383.734049 -297.3248)
			(xy 351.031048 -297.3248) (xy 351.031048 -297.831256) (xy 374.111518 -297.831256) (xy 374.115589 -297.775634)
			(xy 374.127715 -297.721197) (xy 374.147638 -297.669106) (xy 374.174934 -297.620471) (xy 374.20902 -297.576328)
			(xy 374.249169 -297.537619) (xy 374.294527 -297.505168) (xy 374.344127 -297.479667) (xy 374.396911 -297.46166)
			(xy 374.451754 -297.45153) (xy 374.507488 -297.449493) (xy 374.562925 -297.455593) (xy 374.616882 -297.469699)
			(xy 374.668211 -297.491511) (xy 374.715817 -297.520565) (xy 374.758685 -297.55624) (xy 374.795902 -297.597777)
			(xy 374.826675 -297.64429) (xy 374.850347 -297.694787) (xy 374.866415 -297.748194) (xy 374.874535 -297.80337)
			(xy 374.875044 -297.831256) (xy 375.596656 -297.831256) (xy 375.600727 -297.775634) (xy 375.612853 -297.721197)
			(xy 375.632776 -297.669106) (xy 375.660072 -297.620471) (xy 375.694158 -297.576328) (xy 375.734307 -297.537619)
			(xy 375.779665 -297.505168) (xy 375.829265 -297.479667) (xy 375.882049 -297.46166) (xy 375.936892 -297.45153)
			(xy 375.992626 -297.449493) (xy 376.048063 -297.455593) (xy 376.10202 -297.469699) (xy 376.153349 -297.491511)
			(xy 376.200955 -297.520565) (xy 376.243823 -297.55624) (xy 376.28104 -297.597777) (xy 376.311813 -297.64429)
			(xy 376.335485 -297.694787) (xy 376.351553 -297.748194) (xy 376.359673 -297.80337) (xy 376.360182 -297.831256)
			(xy 376.359673 -297.859142) (xy 376.351553 -297.914318) (xy 376.335485 -297.967725) (xy 376.311813 -298.018222)
			(xy 376.28104 -298.064735) (xy 376.243823 -298.106272) (xy 376.200955 -298.141947) (xy 376.153349 -298.171001)
			(xy 376.10202 -298.192813) (xy 376.048063 -298.206919) (xy 375.992626 -298.213019) (xy 375.936892 -298.210982)
			(xy 375.882049 -298.200852) (xy 375.829265 -298.182845) (xy 375.779665 -298.157344) (xy 375.734307 -298.124893)
			(xy 375.694158 -298.086184) (xy 375.660072 -298.042041) (xy 375.632776 -297.993406) (xy 375.612853 -297.941315)
			(xy 375.600727 -297.886878) (xy 375.596656 -297.831256) (xy 374.875044 -297.831256) (xy 374.874535 -297.859142)
			(xy 374.866415 -297.914318) (xy 374.850347 -297.967725) (xy 374.826675 -298.018222) (xy 374.795902 -298.064735)
			(xy 374.758685 -298.106272) (xy 374.715817 -298.141947) (xy 374.668211 -298.171001) (xy 374.616882 -298.192813)
			(xy 374.562925 -298.206919) (xy 374.507488 -298.213019) (xy 374.451754 -298.210982) (xy 374.396911 -298.200852)
			(xy 374.344127 -298.182845) (xy 374.294527 -298.157344) (xy 374.249169 -298.124893) (xy 374.20902 -298.086184)
			(xy 374.174934 -298.042041) (xy 374.147638 -297.993406) (xy 374.127715 -297.941315) (xy 374.115589 -297.886878)
			(xy 374.111518 -297.831256) (xy 351.031048 -297.831256) (xy 351.031048 -298.274486) (xy 384.369068 -298.274486)
			(xy 384.373028 -298.225432) (xy 384.384805 -298.177648) (xy 384.404096 -298.132372) (xy 384.430399 -298.090776)
			(xy 384.463034 -298.053939) (xy 384.501155 -298.022814) (xy 384.543776 -297.998207) (xy 384.589792 -297.980755)
			(xy 384.638011 -297.970911) (xy 384.687186 -297.96893) (xy 384.736041 -297.974862) (xy 384.783312 -297.988554)
			(xy 384.827774 -298.009652) (xy 384.868277 -298.037608) (xy 384.90377 -298.0717) (xy 384.933335 -298.111044)
			(xy 384.956206 -298.154621) (xy 384.97179 -298.201302) (xy 384.979685 -298.249879) (xy 384.98018 -298.274486)
			(xy 384.980175 -298.27474) (xy 385.318774 -298.27474) (xy 385.322734 -298.225686) (xy 385.334511 -298.177902)
			(xy 385.353802 -298.132626) (xy 385.380105 -298.09103) (xy 385.41274 -298.054193) (xy 385.450861 -298.023068)
			(xy 385.493482 -297.998461) (xy 385.539498 -297.981009) (xy 385.587717 -297.971165) (xy 385.636892 -297.969184)
			(xy 385.685747 -297.975116) (xy 385.733018 -297.988808) (xy 385.77748 -298.009906) (xy 385.817983 -298.037862)
			(xy 385.853476 -298.071954) (xy 385.883041 -298.111298) (xy 385.905912 -298.154875) (xy 385.921496 -298.201556)
			(xy 385.929391 -298.250133) (xy 385.929886 -298.27474) (xy 386.268988 -298.27474) (xy 386.272948 -298.225686)
			(xy 386.284725 -298.177902) (xy 386.304016 -298.132626) (xy 386.330319 -298.09103) (xy 386.362954 -298.054193)
			(xy 386.401075 -298.023068) (xy 386.443696 -297.998461) (xy 386.489712 -297.981009) (xy 386.537931 -297.971165)
			(xy 386.587106 -297.969184) (xy 386.635961 -297.975116) (xy 386.683232 -297.988808) (xy 386.727694 -298.009906)
			(xy 386.768197 -298.037862) (xy 386.80369 -298.071954) (xy 386.833255 -298.111298) (xy 386.856126 -298.154875)
			(xy 386.87171 -298.201556) (xy 386.879605 -298.250133) (xy 386.8801 -298.27474) (xy 386.879934 -298.282973)
			(xy 387.219275 -298.282973) (xy 387.221964 -298.233401) (xy 387.232638 -298.184918) (xy 387.251015 -298.138801)
			(xy 387.276612 -298.096264) (xy 387.308753 -298.058429) (xy 387.346591 -298.026292) (xy 387.389131 -298.0007)
			(xy 387.435251 -297.982328) (xy 387.483735 -297.97166) (xy 387.533307 -297.968976) (xy 387.58266 -297.974347)
			(xy 387.630493 -297.987633) (xy 387.675547 -298.008482) (xy 387.716634 -298.036346) (xy 387.752672 -298.07049)
			(xy 387.782711 -298.110015) (xy 387.80596 -298.153879) (xy 387.821806 -298.200927) (xy 387.829831 -298.249918)
			(xy 387.830314 -298.27474) (xy 387.830224 -298.283844) (xy 387.829078 -298.302018) (xy 387.828028 -298.311062)
			(xy 387.826758 -298.323254) (xy 387.834632 -298.345352) (xy 387.911086 -298.418504) (xy 387.933692 -298.425362)
			(xy 387.94563 -298.42333) (xy 387.959123 -298.42127) (xy 387.986336 -298.41911) (xy 387.999986 -298.419012)
			(xy 388.070344 -298.419012) (xy 388.081003 -298.418398) (xy 388.100426 -298.409585) (xy 388.107936 -298.401994)
			(xy 388.165848 -298.337732) (xy 388.172452 -298.317666) (xy 388.171436 -298.306744) (xy 388.169658 -298.27474)
			(xy 388.17018 -298.249485) (xy 388.178493 -298.199663) (xy 388.194894 -298.151889) (xy 388.218935 -298.107466)
			(xy 388.249959 -298.067606) (xy 388.287121 -298.033396) (xy 388.329407 -298.00577) (xy 388.375663 -297.98548)
			(xy 388.424628 -297.97308) (xy 388.474966 -297.968909) (xy 388.525304 -297.97308) (xy 388.574269 -297.98548)
			(xy 388.620525 -298.00577) (xy 388.662811 -298.033396) (xy 388.699973 -298.067606) (xy 388.730997 -298.107466)
			(xy 388.755038 -298.151889) (xy 388.771439 -298.199663) (xy 388.779752 -298.249485) (xy 388.780274 -298.27474)
			(xy 388.778496 -298.306744) (xy 388.77748 -298.317666) (xy 388.784084 -298.337732) (xy 388.841996 -298.401994)
			(xy 388.849451 -298.409662) (xy 388.868908 -298.418485) (xy 388.879588 -298.419012) (xy 388.949946 -298.419012)
			(xy 388.963596 -298.419096) (xy 388.990809 -298.421261) (xy 389.004302 -298.42333) (xy 389.01624 -298.425362)
			(xy 389.038846 -298.418504) (xy 389.1153 -298.345352) (xy 389.123174 -298.323254) (xy 389.121904 -298.311062)
			(xy 389.120859 -298.302017) (xy 389.119716 -298.283844) (xy 389.119618 -298.27474) (xy 389.12014 -298.249485)
			(xy 389.128453 -298.199663) (xy 389.144854 -298.151889) (xy 389.168895 -298.107466) (xy 389.199919 -298.067606)
			(xy 389.237081 -298.033396) (xy 389.279367 -298.00577) (xy 389.325623 -297.98548) (xy 389.374588 -297.97308)
			(xy 389.424926 -297.968909) (xy 389.475264 -297.97308) (xy 389.524229 -297.98548) (xy 389.570485 -298.00577)
			(xy 389.612771 -298.033396) (xy 389.649933 -298.067606) (xy 389.680957 -298.107466) (xy 389.704998 -298.151889)
			(xy 389.721399 -298.199663) (xy 389.729712 -298.249485) (xy 389.730234 -298.27474) (xy 389.730062 -298.288923)
			(xy 389.727387 -298.317163) (xy 389.7249 -298.331128) (xy 389.722614 -298.343574) (xy 389.72998 -298.367196)
			(xy 389.80745 -298.444666) (xy 389.831072 -298.452032) (xy 389.843518 -298.449746) (xy 389.857484 -298.447271)
			(xy 389.885724 -298.444598) (xy 389.899906 -298.444412) (xy 389.914089 -298.444587) (xy 389.942329 -298.44726)
			(xy 389.956294 -298.449746) (xy 389.96874 -298.452032) (xy 389.992362 -298.444666) (xy 390.069832 -298.367196)
			(xy 390.077198 -298.343574) (xy 390.074912 -298.331128) (xy 390.07243 -298.317163) (xy 390.069762 -298.288923)
			(xy 390.069578 -298.27474) (xy 390.070035 -298.249915) (xy 390.078061 -298.200918) (xy 390.093909 -298.153865)
			(xy 390.117161 -298.109996) (xy 390.147203 -298.070467) (xy 390.183246 -298.036319) (xy 390.224338 -298.008452)
			(xy 390.269397 -297.9876) (xy 390.317236 -297.974314) (xy 390.366595 -297.968942) (xy 390.416172 -297.971626)
			(xy 390.464662 -297.982296) (xy 390.510787 -298.000671) (xy 390.553331 -298.026266) (xy 390.591174 -298.058407)
			(xy 390.623319 -298.096247) (xy 390.648917 -298.13879) (xy 390.667296 -298.184913) (xy 390.67797 -298.233402)
			(xy 390.680212 -298.27474) (xy 391.019042 -298.27474) (xy 391.023002 -298.225686) (xy 391.034779 -298.177902)
			(xy 391.05407 -298.132626) (xy 391.080373 -298.09103) (xy 391.113008 -298.054193) (xy 391.151129 -298.023068)
			(xy 391.19375 -297.998461) (xy 391.239766 -297.981009) (xy 391.287985 -297.971165) (xy 391.33716 -297.969184)
			(xy 391.386015 -297.975116) (xy 391.433286 -297.988808) (xy 391.477748 -298.009906) (xy 391.518251 -298.037862)
			(xy 391.553744 -298.071954) (xy 391.583309 -298.111298) (xy 391.60618 -298.154875) (xy 391.621764 -298.201556)
			(xy 391.629659 -298.250133) (xy 391.630154 -298.27474) (xy 391.969002 -298.27474) (xy 391.972962 -298.225686)
			(xy 391.984739 -298.177902) (xy 392.00403 -298.132626) (xy 392.030333 -298.09103) (xy 392.062968 -298.054193)
			(xy 392.101089 -298.023068) (xy 392.14371 -297.998461) (xy 392.189726 -297.981009) (xy 392.237945 -297.971165)
			(xy 392.28712 -297.969184) (xy 392.335975 -297.975116) (xy 392.383246 -297.988808) (xy 392.427708 -298.009906)
			(xy 392.468211 -298.037862) (xy 392.503704 -298.071954) (xy 392.533269 -298.111298) (xy 392.55614 -298.154875)
			(xy 392.571724 -298.201556) (xy 392.579619 -298.250133) (xy 392.580114 -298.27474) (xy 392.919216 -298.27474)
			(xy 392.923176 -298.225686) (xy 392.934953 -298.177902) (xy 392.954244 -298.132626) (xy 392.980547 -298.09103)
			(xy 393.013182 -298.054193) (xy 393.051303 -298.023068) (xy 393.093924 -297.998461) (xy 393.13994 -297.981009)
			(xy 393.188159 -297.971165) (xy 393.237334 -297.969184) (xy 393.286189 -297.975116) (xy 393.33346 -297.988808)
			(xy 393.377922 -298.009906) (xy 393.418425 -298.037862) (xy 393.453918 -298.071954) (xy 393.483483 -298.111298)
			(xy 393.506354 -298.154875) (xy 393.521938 -298.201556) (xy 393.529833 -298.250133) (xy 393.530328 -298.27474)
			(xy 393.869176 -298.27474) (xy 393.873136 -298.225686) (xy 393.884913 -298.177902) (xy 393.904204 -298.132626)
			(xy 393.930507 -298.09103) (xy 393.963142 -298.054193) (xy 394.001263 -298.023068) (xy 394.043884 -297.998461)
			(xy 394.0899 -297.981009) (xy 394.138119 -297.971165) (xy 394.187294 -297.969184) (xy 394.236149 -297.975116)
			(xy 394.28342 -297.988808) (xy 394.327882 -298.009906) (xy 394.368385 -298.037862) (xy 394.403878 -298.071954)
			(xy 394.433443 -298.111298) (xy 394.456314 -298.154875) (xy 394.471898 -298.201556) (xy 394.479793 -298.250133)
			(xy 394.480288 -298.27474) (xy 395.769096 -298.27474) (xy 395.773056 -298.225686) (xy 395.784833 -298.177902)
			(xy 395.804124 -298.132626) (xy 395.830427 -298.09103) (xy 395.863062 -298.054193) (xy 395.901183 -298.023068)
			(xy 395.943804 -297.998461) (xy 395.98982 -297.981009) (xy 396.038039 -297.971165) (xy 396.087214 -297.969184)
			(xy 396.136069 -297.975116) (xy 396.18334 -297.988808) (xy 396.227802 -298.009906) (xy 396.268305 -298.037862)
			(xy 396.303798 -298.071954) (xy 396.333363 -298.111298) (xy 396.356234 -298.154875) (xy 396.371818 -298.201556)
			(xy 396.379713 -298.250133) (xy 396.380208 -298.27474) (xy 396.719056 -298.27474) (xy 396.723016 -298.225686)
			(xy 396.734793 -298.177902) (xy 396.754084 -298.132626) (xy 396.780387 -298.09103) (xy 396.813022 -298.054193)
			(xy 396.851143 -298.023068) (xy 396.893764 -297.998461) (xy 396.93978 -297.981009) (xy 396.987999 -297.971165)
			(xy 397.037174 -297.969184) (xy 397.086029 -297.975116) (xy 397.1333 -297.988808) (xy 397.177762 -298.009906)
			(xy 397.218265 -298.037862) (xy 397.253758 -298.071954) (xy 397.283323 -298.111298) (xy 397.306194 -298.154875)
			(xy 397.321778 -298.201556) (xy 397.329673 -298.250133) (xy 397.330168 -298.27474) (xy 397.329673 -298.299347)
			(xy 397.321778 -298.347924) (xy 397.306194 -298.394605) (xy 397.283323 -298.438182) (xy 397.253758 -298.477526)
			(xy 397.218265 -298.511618) (xy 397.177762 -298.539574) (xy 397.1333 -298.560672) (xy 397.086029 -298.574364)
			(xy 397.037174 -298.580296) (xy 396.987999 -298.578315) (xy 396.93978 -298.568471) (xy 396.893764 -298.551019)
			(xy 396.851143 -298.526412) (xy 396.813022 -298.495287) (xy 396.780387 -298.45845) (xy 396.754084 -298.416854)
			(xy 396.734793 -298.371578) (xy 396.723016 -298.323794) (xy 396.719056 -298.27474) (xy 396.380208 -298.27474)
			(xy 396.379713 -298.299347) (xy 396.371818 -298.347924) (xy 396.356234 -298.394605) (xy 396.333363 -298.438182)
			(xy 396.303798 -298.477526) (xy 396.268305 -298.511618) (xy 396.227802 -298.539574) (xy 396.18334 -298.560672)
			(xy 396.136069 -298.574364) (xy 396.087214 -298.580296) (xy 396.038039 -298.578315) (xy 395.98982 -298.568471)
			(xy 395.943804 -298.551019) (xy 395.901183 -298.526412) (xy 395.863062 -298.495287) (xy 395.830427 -298.45845)
			(xy 395.804124 -298.416854) (xy 395.784833 -298.371578) (xy 395.773056 -298.323794) (xy 395.769096 -298.27474)
			(xy 394.480288 -298.27474) (xy 394.479793 -298.299347) (xy 394.471898 -298.347924) (xy 394.456314 -298.394605)
			(xy 394.433443 -298.438182) (xy 394.403878 -298.477526) (xy 394.368385 -298.511618) (xy 394.327882 -298.539574)
			(xy 394.28342 -298.560672) (xy 394.236149 -298.574364) (xy 394.187294 -298.580296) (xy 394.138119 -298.578315)
			(xy 394.0899 -298.568471) (xy 394.043884 -298.551019) (xy 394.001263 -298.526412) (xy 393.963142 -298.495287)
			(xy 393.930507 -298.45845) (xy 393.904204 -298.416854) (xy 393.884913 -298.371578) (xy 393.873136 -298.323794)
			(xy 393.869176 -298.27474) (xy 393.530328 -298.27474) (xy 393.529833 -298.299347) (xy 393.521938 -298.347924)
			(xy 393.506354 -298.394605) (xy 393.483483 -298.438182) (xy 393.453918 -298.477526) (xy 393.418425 -298.511618)
			(xy 393.377922 -298.539574) (xy 393.33346 -298.560672) (xy 393.286189 -298.574364) (xy 393.237334 -298.580296)
			(xy 393.188159 -298.578315) (xy 393.13994 -298.568471) (xy 393.093924 -298.551019) (xy 393.051303 -298.526412)
			(xy 393.013182 -298.495287) (xy 392.980547 -298.45845) (xy 392.954244 -298.416854) (xy 392.934953 -298.371578)
			(xy 392.923176 -298.323794) (xy 392.919216 -298.27474) (xy 392.580114 -298.27474) (xy 392.579619 -298.299347)
			(xy 392.571724 -298.347924) (xy 392.55614 -298.394605) (xy 392.533269 -298.438182) (xy 392.503704 -298.477526)
			(xy 392.468211 -298.511618) (xy 392.427708 -298.539574) (xy 392.383246 -298.560672) (xy 392.335975 -298.574364)
			(xy 392.28712 -298.580296) (xy 392.237945 -298.578315) (xy 392.189726 -298.568471) (xy 392.14371 -298.551019)
			(xy 392.101089 -298.526412) (xy 392.062968 -298.495287) (xy 392.030333 -298.45845) (xy 392.00403 -298.416854)
			(xy 391.984739 -298.371578) (xy 391.972962 -298.323794) (xy 391.969002 -298.27474) (xy 391.630154 -298.27474)
			(xy 391.629659 -298.299347) (xy 391.621764 -298.347924) (xy 391.60618 -298.394605) (xy 391.583309 -298.438182)
			(xy 391.553744 -298.477526) (xy 391.518251 -298.511618) (xy 391.477748 -298.539574) (xy 391.433286 -298.560672)
			(xy 391.386015 -298.574364) (xy 391.33716 -298.580296) (xy 391.287985 -298.578315) (xy 391.239766 -298.568471)
			(xy 391.19375 -298.551019) (xy 391.151129 -298.526412) (xy 391.113008 -298.495287) (xy 391.080373 -298.45845)
			(xy 391.05407 -298.416854) (xy 391.034779 -298.371578) (xy 391.023002 -298.323794) (xy 391.019042 -298.27474)
			(xy 390.680212 -298.27474) (xy 390.680659 -298.282979) (xy 390.675291 -298.332338) (xy 390.662009 -298.380179)
			(xy 390.641161 -298.42524) (xy 390.613298 -298.466334) (xy 390.579153 -298.502379) (xy 390.539626 -298.532425)
			(xy 390.495759 -298.555681) (xy 390.448707 -298.571533) (xy 390.399711 -298.579563) (xy 390.374886 -298.580048)
			(xy 390.360703 -298.579873) (xy 390.332463 -298.5772) (xy 390.318498 -298.574714) (xy 390.306052 -298.572428)
			(xy 390.28243 -298.579794) (xy 390.20496 -298.657264) (xy 390.197594 -298.680886) (xy 390.19988 -298.693332)
			(xy 390.202357 -298.707298) (xy 390.205028 -298.735537) (xy 390.205214 -298.74972) (xy 390.204756 -298.773711)
			(xy 390.197247 -298.821103) (xy 390.182417 -298.866737) (xy 390.160632 -298.909489) (xy 390.132427 -298.948308)
			(xy 390.098497 -298.982236) (xy 390.059677 -299.010439) (xy 390.016924 -299.032223) (xy 389.97129 -299.04705)
			(xy 389.923897 -299.054557) (xy 389.899906 -299.055028) (xy 389.885723 -299.05485) (xy 389.857483 -299.052179)
			(xy 389.843518 -299.049694) (xy 389.831072 -299.047408) (xy 389.807196 -299.054774) (xy 389.72998 -299.13199)
			(xy 389.722614 -299.15612) (xy 389.7249 -299.168312) (xy 389.727384 -299.182341) (xy 389.730056 -299.210708)
			(xy 389.730234 -299.224954) (xy 389.729719 -299.248945) (xy 389.72222 -299.296336) (xy 389.7074 -299.341971)
			(xy 389.685622 -299.384725) (xy 389.657425 -299.423546) (xy 389.623501 -299.457478) (xy 389.584687 -299.485685)
			(xy 389.541937 -299.507472) (xy 389.496306 -299.522304) (xy 389.448916 -299.529814) (xy 389.424926 -299.530262)
			(xy 389.410743 -299.530082) (xy 389.382503 -299.527412) (xy 389.368538 -299.524928) (xy 389.356092 -299.522642)
			(xy 389.33247 -299.530008) (xy 389.255 -299.607478) (xy 389.247634 -299.6311) (xy 389.24992 -299.643546)
			(xy 389.252399 -299.657511) (xy 389.255069 -299.685751) (xy 389.255254 -299.6999) (xy 390.544103 -299.6999)
			(xy 390.548273 -299.649571) (xy 390.56067 -299.600615) (xy 390.580954 -299.554366) (xy 390.608574 -299.512087)
			(xy 390.642776 -299.47493) (xy 390.682627 -299.443909) (xy 390.72704 -299.419869) (xy 390.774803 -299.403467)
			(xy 390.824615 -299.39515) (xy 390.849866 -299.394626) (xy 390.864049 -299.394807) (xy 390.892289 -299.397476)
			(xy 390.906254 -299.39996) (xy 390.9187 -299.402246) (xy 390.942576 -299.39488) (xy 391.019792 -299.317664)
			(xy 391.027158 -299.293534) (xy 391.024872 -299.281342) (xy 391.022382 -299.267314) (xy 391.019714 -299.238946)
			(xy 391.019538 -299.2247) (xy 391.019978 -299.19988) (xy 391.028008 -299.150894) (xy 391.043858 -299.103852)
			(xy 391.067109 -299.059994) (xy 391.097149 -299.020475) (xy 391.133187 -298.986337) (xy 391.174273 -298.958478)
			(xy 391.219324 -298.937633) (xy 391.267154 -298.924351) (xy 391.316503 -298.918982) (xy 391.366071 -298.921666)
			(xy 391.414551 -298.932335) (xy 391.460667 -298.950706) (xy 391.503203 -298.976295) (xy 391.541039 -299.008429)
			(xy 391.573178 -299.04626) (xy 391.598774 -299.088792) (xy 391.617152 -299.134905) (xy 391.627827 -299.183384)
			(xy 391.630086 -299.224954) (xy 391.969002 -299.224954) (xy 391.972962 -299.1759) (xy 391.984739 -299.128116)
			(xy 392.00403 -299.08284) (xy 392.030333 -299.041244) (xy 392.062968 -299.004407) (xy 392.101089 -298.973282)
			(xy 392.14371 -298.948675) (xy 392.189726 -298.931223) (xy 392.237945 -298.921379) (xy 392.28712 -298.919398)
			(xy 392.335975 -298.92533) (xy 392.383246 -298.939022) (xy 392.427708 -298.96012) (xy 392.468211 -298.988076)
			(xy 392.503704 -299.022168) (xy 392.533269 -299.061512) (xy 392.55614 -299.105089) (xy 392.571724 -299.15177)
			(xy 392.579619 -299.200347) (xy 392.580114 -299.224954) (xy 392.919216 -299.224954) (xy 392.923176 -299.1759)
			(xy 392.934953 -299.128116) (xy 392.954244 -299.08284) (xy 392.980547 -299.041244) (xy 393.013182 -299.004407)
			(xy 393.051303 -298.973282) (xy 393.093924 -298.948675) (xy 393.13994 -298.931223) (xy 393.188159 -298.921379)
			(xy 393.237334 -298.919398) (xy 393.286189 -298.92533) (xy 393.33346 -298.939022) (xy 393.377922 -298.96012)
			(xy 393.418425 -298.988076) (xy 393.453918 -299.022168) (xy 393.483483 -299.061512) (xy 393.506354 -299.105089)
			(xy 393.521938 -299.15177) (xy 393.529833 -299.200347) (xy 393.530328 -299.224954) (xy 393.869176 -299.224954)
			(xy 393.873136 -299.1759) (xy 393.884913 -299.128116) (xy 393.904204 -299.08284) (xy 393.930507 -299.041244)
			(xy 393.963142 -299.004407) (xy 394.001263 -298.973282) (xy 394.043884 -298.948675) (xy 394.0899 -298.931223)
			(xy 394.138119 -298.921379) (xy 394.187294 -298.919398) (xy 394.236149 -298.92533) (xy 394.28342 -298.939022)
			(xy 394.327882 -298.96012) (xy 394.368385 -298.988076) (xy 394.403878 -299.022168) (xy 394.433443 -299.061512)
			(xy 394.456314 -299.105089) (xy 394.471898 -299.15177) (xy 394.479793 -299.200347) (xy 394.480288 -299.224954)
			(xy 394.819136 -299.224954) (xy 394.823096 -299.1759) (xy 394.834873 -299.128116) (xy 394.854164 -299.08284)
			(xy 394.880467 -299.041244) (xy 394.913102 -299.004407) (xy 394.951223 -298.973282) (xy 394.993844 -298.948675)
			(xy 395.03986 -298.931223) (xy 395.088079 -298.921379) (xy 395.137254 -298.919398) (xy 395.186109 -298.92533)
			(xy 395.23338 -298.939022) (xy 395.277842 -298.96012) (xy 395.318345 -298.988076) (xy 395.353838 -299.022168)
			(xy 395.383403 -299.061512) (xy 395.406274 -299.105089) (xy 395.421858 -299.15177) (xy 395.429753 -299.200347)
			(xy 395.430248 -299.224954) (xy 395.769096 -299.224954) (xy 395.773056 -299.1759) (xy 395.784833 -299.128116)
			(xy 395.804124 -299.08284) (xy 395.830427 -299.041244) (xy 395.863062 -299.004407) (xy 395.901183 -298.973282)
			(xy 395.943804 -298.948675) (xy 395.98982 -298.931223) (xy 396.038039 -298.921379) (xy 396.087214 -298.919398)
			(xy 396.136069 -298.92533) (xy 396.18334 -298.939022) (xy 396.227802 -298.96012) (xy 396.268305 -298.988076)
			(xy 396.303798 -299.022168) (xy 396.333363 -299.061512) (xy 396.356234 -299.105089) (xy 396.371818 -299.15177)
			(xy 396.379713 -299.200347) (xy 396.380208 -299.224954) (xy 396.379713 -299.249561) (xy 396.371818 -299.298138)
			(xy 396.356234 -299.344819) (xy 396.333363 -299.388396) (xy 396.303798 -299.42774) (xy 396.268305 -299.461832)
			(xy 396.227802 -299.489788) (xy 396.18334 -299.510886) (xy 396.136069 -299.524578) (xy 396.087214 -299.53051)
			(xy 396.038039 -299.528529) (xy 395.98982 -299.518685) (xy 395.943804 -299.501233) (xy 395.901183 -299.476626)
			(xy 395.863062 -299.445501) (xy 395.830427 -299.408664) (xy 395.804124 -299.367068) (xy 395.784833 -299.321792)
			(xy 395.773056 -299.274008) (xy 395.769096 -299.224954) (xy 395.430248 -299.224954) (xy 395.429753 -299.249561)
			(xy 395.421858 -299.298138) (xy 395.406274 -299.344819) (xy 395.383403 -299.388396) (xy 395.353838 -299.42774)
			(xy 395.318345 -299.461832) (xy 395.277842 -299.489788) (xy 395.23338 -299.510886) (xy 395.186109 -299.524578)
			(xy 395.137254 -299.53051) (xy 395.088079 -299.528529) (xy 395.03986 -299.518685) (xy 394.993844 -299.501233)
			(xy 394.951223 -299.476626) (xy 394.913102 -299.445501) (xy 394.880467 -299.408664) (xy 394.854164 -299.367068)
			(xy 394.834873 -299.321792) (xy 394.823096 -299.274008) (xy 394.819136 -299.224954) (xy 394.480288 -299.224954)
			(xy 394.479793 -299.249561) (xy 394.471898 -299.298138) (xy 394.456314 -299.344819) (xy 394.433443 -299.388396)
			(xy 394.403878 -299.42774) (xy 394.368385 -299.461832) (xy 394.327882 -299.489788) (xy 394.28342 -299.510886)
			(xy 394.236149 -299.524578) (xy 394.187294 -299.53051) (xy 394.138119 -299.528529) (xy 394.0899 -299.518685)
			(xy 394.043884 -299.501233) (xy 394.001263 -299.476626) (xy 393.963142 -299.445501) (xy 393.930507 -299.408664)
			(xy 393.904204 -299.367068) (xy 393.884913 -299.321792) (xy 393.873136 -299.274008) (xy 393.869176 -299.224954)
			(xy 393.530328 -299.224954) (xy 393.529833 -299.249561) (xy 393.521938 -299.298138) (xy 393.506354 -299.344819)
			(xy 393.483483 -299.388396) (xy 393.453918 -299.42774) (xy 393.418425 -299.461832) (xy 393.377922 -299.489788)
			(xy 393.33346 -299.510886) (xy 393.286189 -299.524578) (xy 393.237334 -299.53051) (xy 393.188159 -299.528529)
			(xy 393.13994 -299.518685) (xy 393.093924 -299.501233) (xy 393.051303 -299.476626) (xy 393.013182 -299.445501)
			(xy 392.980547 -299.408664) (xy 392.954244 -299.367068) (xy 392.934953 -299.321792) (xy 392.923176 -299.274008)
			(xy 392.919216 -299.224954) (xy 392.580114 -299.224954) (xy 392.579619 -299.249561) (xy 392.571724 -299.298138)
			(xy 392.55614 -299.344819) (xy 392.533269 -299.388396) (xy 392.503704 -299.42774) (xy 392.468211 -299.461832)
			(xy 392.427708 -299.489788) (xy 392.383246 -299.510886) (xy 392.335975 -299.524578) (xy 392.28712 -299.53051)
			(xy 392.237945 -299.528529) (xy 392.189726 -299.518685) (xy 392.14371 -299.501233) (xy 392.101089 -299.476626)
			(xy 392.062968 -299.445501) (xy 392.030333 -299.408664) (xy 392.00403 -299.367068) (xy 391.984739 -299.321792)
			(xy 391.972962 -299.274008) (xy 391.969002 -299.224954) (xy 391.630086 -299.224954) (xy 391.63052 -299.232951)
			(xy 391.625158 -299.2823) (xy 391.611883 -299.330133) (xy 391.591045 -299.375187) (xy 391.563192 -299.416277)
			(xy 391.529059 -299.45232) (xy 391.489545 -299.482366) (xy 391.44569 -299.505624) (xy 391.398651 -299.52148)
			(xy 391.349666 -299.529518) (xy 391.324846 -299.530008) (xy 391.310663 -299.529825) (xy 391.282423 -299.527157)
			(xy 391.268458 -299.524674) (xy 391.256012 -299.522388) (xy 391.232136 -299.529754) (xy 391.15492 -299.60697)
			(xy 391.147554 -299.6311) (xy 391.14984 -299.643292) (xy 391.152321 -299.657321) (xy 391.154995 -299.685688)
			(xy 391.155174 -299.699934) (xy 391.155003 -299.714117) (xy 391.152327 -299.742357) (xy 391.14984 -299.756322)
			(xy 391.147554 -299.768768) (xy 391.15492 -299.79239) (xy 391.23239 -299.86986) (xy 391.256012 -299.877226)
			(xy 391.268458 -299.87494) (xy 391.282423 -299.87246) (xy 391.310663 -299.86979) (xy 391.324846 -299.869606)
			(xy 391.348839 -299.87002) (xy 391.396234 -299.877534) (xy 391.44187 -299.892368) (xy 391.484623 -299.914159)
			(xy 391.523442 -299.942369) (xy 391.55737 -299.976304) (xy 391.585573 -300.015128) (xy 391.607355 -300.057886)
			(xy 391.62218 -300.103525) (xy 391.629684 -300.150921) (xy 391.630154 -300.174914) (xy 391.629979 -300.189097)
			(xy 391.627306 -300.217337) (xy 391.62482 -300.231302) (xy 391.622534 -300.243748) (xy 391.6299 -300.26737)
			(xy 391.70737 -300.34484) (xy 391.730992 -300.352206) (xy 391.743438 -300.34992) (xy 391.757404 -300.347442)
			(xy 391.785643 -300.344771) (xy 391.799826 -300.344586) (xy 391.814009 -300.344759) (xy 391.842249 -300.347434)
			(xy 391.856214 -300.34992) (xy 391.86866 -300.352206) (xy 391.892282 -300.34484) (xy 391.969752 -300.26737)
			(xy 391.977118 -300.243748) (xy 391.974832 -300.231302) (xy 391.97236 -300.217335) (xy 391.969685 -300.189096)
			(xy 391.969498 -300.174914) (xy 391.969963 -300.150092) (xy 391.977992 -300.101101) (xy 391.993842 -300.054055)
			(xy 392.017093 -300.010193) (xy 392.047135 -299.97067) (xy 392.083175 -299.936528) (xy 392.124264 -299.908667)
			(xy 392.169319 -299.88782) (xy 392.217153 -299.874537) (xy 392.266507 -299.869167) (xy 392.316078 -299.871853)
			(xy 392.364562 -299.882524) (xy 392.410681 -299.900897) (xy 392.45322 -299.92649) (xy 392.491058 -299.958628)
			(xy 392.523198 -299.996464) (xy 392.548794 -300.039001) (xy 392.56717 -300.085119) (xy 392.577844 -300.133602)
			(xy 392.580085 -300.174914) (xy 392.919216 -300.174914) (xy 392.923176 -300.12586) (xy 392.934953 -300.078076)
			(xy 392.954244 -300.0328) (xy 392.980547 -299.991204) (xy 393.013182 -299.954367) (xy 393.051303 -299.923242)
			(xy 393.093924 -299.898635) (xy 393.13994 -299.881183) (xy 393.188159 -299.871339) (xy 393.237334 -299.869358)
			(xy 393.286189 -299.87529) (xy 393.33346 -299.888982) (xy 393.377922 -299.91008) (xy 393.418425 -299.938036)
			(xy 393.453918 -299.972128) (xy 393.483483 -300.011472) (xy 393.506354 -300.055049) (xy 393.521938 -300.10173)
			(xy 393.529833 -300.150307) (xy 393.530328 -300.174914) (xy 393.869176 -300.174914) (xy 393.873136 -300.12586)
			(xy 393.884913 -300.078076) (xy 393.904204 -300.0328) (xy 393.930507 -299.991204) (xy 393.963142 -299.954367)
			(xy 394.001263 -299.923242) (xy 394.043884 -299.898635) (xy 394.0899 -299.881183) (xy 394.138119 -299.871339)
			(xy 394.187294 -299.869358) (xy 394.236149 -299.87529) (xy 394.28342 -299.888982) (xy 394.327882 -299.91008)
			(xy 394.368385 -299.938036) (xy 394.403878 -299.972128) (xy 394.433443 -300.011472) (xy 394.456314 -300.055049)
			(xy 394.471898 -300.10173) (xy 394.479793 -300.150307) (xy 394.480288 -300.174914) (xy 395.769096 -300.174914)
			(xy 395.773056 -300.12586) (xy 395.784833 -300.078076) (xy 395.804124 -300.0328) (xy 395.830427 -299.991204)
			(xy 395.863062 -299.954367) (xy 395.901183 -299.923242) (xy 395.943804 -299.898635) (xy 395.98982 -299.881183)
			(xy 396.038039 -299.871339) (xy 396.087214 -299.869358) (xy 396.136069 -299.87529) (xy 396.18334 -299.888982)
			(xy 396.227802 -299.91008) (xy 396.268305 -299.938036) (xy 396.303798 -299.972128) (xy 396.333363 -300.011472)
			(xy 396.356234 -300.055049) (xy 396.371818 -300.10173) (xy 396.379713 -300.150307) (xy 396.380208 -300.174914)
			(xy 396.719056 -300.174914) (xy 396.723016 -300.12586) (xy 396.734793 -300.078076) (xy 396.754084 -300.0328)
			(xy 396.780387 -299.991204) (xy 396.813022 -299.954367) (xy 396.851143 -299.923242) (xy 396.893764 -299.898635)
			(xy 396.93978 -299.881183) (xy 396.987999 -299.871339) (xy 397.037174 -299.869358) (xy 397.086029 -299.87529)
			(xy 397.1333 -299.888982) (xy 397.177762 -299.91008) (xy 397.218265 -299.938036) (xy 397.253758 -299.972128)
			(xy 397.283323 -300.011472) (xy 397.306194 -300.055049) (xy 397.321778 -300.10173) (xy 397.329673 -300.150307)
			(xy 397.330168 -300.174914) (xy 397.329673 -300.199521) (xy 397.321778 -300.248098) (xy 397.306194 -300.294779)
			(xy 397.283323 -300.338356) (xy 397.253758 -300.3777) (xy 397.218265 -300.411792) (xy 397.177762 -300.439748)
			(xy 397.1333 -300.460846) (xy 397.086029 -300.474538) (xy 397.037174 -300.48047) (xy 396.987999 -300.478489)
			(xy 396.93978 -300.468645) (xy 396.893764 -300.451193) (xy 396.851143 -300.426586) (xy 396.813022 -300.395461)
			(xy 396.780387 -300.358624) (xy 396.754084 -300.317028) (xy 396.734793 -300.271752) (xy 396.723016 -300.223968)
			(xy 396.719056 -300.174914) (xy 396.380208 -300.174914) (xy 396.379713 -300.199521) (xy 396.371818 -300.248098)
			(xy 396.356234 -300.294779) (xy 396.333363 -300.338356) (xy 396.303798 -300.3777) (xy 396.268305 -300.411792)
			(xy 396.227802 -300.439748) (xy 396.18334 -300.460846) (xy 396.136069 -300.474538) (xy 396.087214 -300.48047)
			(xy 396.038039 -300.478489) (xy 395.98982 -300.468645) (xy 395.943804 -300.451193) (xy 395.901183 -300.426586)
			(xy 395.863062 -300.395461) (xy 395.830427 -300.358624) (xy 395.804124 -300.317028) (xy 395.784833 -300.271752)
			(xy 395.773056 -300.223968) (xy 395.769096 -300.174914) (xy 394.480288 -300.174914) (xy 394.479793 -300.199521)
			(xy 394.471898 -300.248098) (xy 394.456314 -300.294779) (xy 394.433443 -300.338356) (xy 394.403878 -300.3777)
			(xy 394.368385 -300.411792) (xy 394.327882 -300.439748) (xy 394.28342 -300.460846) (xy 394.236149 -300.474538)
			(xy 394.187294 -300.48047) (xy 394.138119 -300.478489) (xy 394.0899 -300.468645) (xy 394.043884 -300.451193)
			(xy 394.001263 -300.426586) (xy 393.963142 -300.395461) (xy 393.930507 -300.358624) (xy 393.904204 -300.317028)
			(xy 393.884913 -300.271752) (xy 393.873136 -300.223968) (xy 393.869176 -300.174914) (xy 393.530328 -300.174914)
			(xy 393.529833 -300.199521) (xy 393.521938 -300.248098) (xy 393.506354 -300.294779) (xy 393.483483 -300.338356)
			(xy 393.453918 -300.3777) (xy 393.418425 -300.411792) (xy 393.377922 -300.439748) (xy 393.33346 -300.460846)
			(xy 393.286189 -300.474538) (xy 393.237334 -300.48047) (xy 393.188159 -300.478489) (xy 393.13994 -300.468645)
			(xy 393.093924 -300.451193) (xy 393.051303 -300.426586) (xy 393.013182 -300.395461) (xy 392.980547 -300.358624)
			(xy 392.954244 -300.317028) (xy 392.934953 -300.271752) (xy 392.923176 -300.223968) (xy 392.919216 -300.174914)
			(xy 392.580085 -300.174914) (xy 392.580533 -300.183173) (xy 392.575167 -300.232527) (xy 392.561887 -300.280362)
			(xy 392.541043 -300.325418) (xy 392.513184 -300.366509) (xy 392.479045 -300.402551) (xy 392.439524 -300.432596)
			(xy 392.395663 -300.455851) (xy 392.348618 -300.471703) (xy 392.299628 -300.479736) (xy 392.274806 -300.480222)
			(xy 392.260623 -300.480044) (xy 392.232383 -300.477373) (xy 392.218418 -300.474888) (xy 392.205972 -300.472602)
			(xy 392.18235 -300.479968) (xy 392.10488 -300.557438) (xy 392.097514 -300.58106) (xy 392.0998 -300.593506)
			(xy 392.102273 -300.607472) (xy 392.104947 -300.635712) (xy 392.105134 -300.649894) (xy 392.104612 -300.675149)
			(xy 392.096299 -300.724971) (xy 392.079898 -300.772745) (xy 392.055857 -300.817168) (xy 392.024833 -300.857028)
			(xy 391.987671 -300.891238) (xy 391.945385 -300.918864) (xy 391.899129 -300.939154) (xy 391.850164 -300.951554)
			(xy 391.799826 -300.955725) (xy 391.749488 -300.951554) (xy 391.700523 -300.939154) (xy 391.654267 -300.918864)
			(xy 391.611981 -300.891238) (xy 391.574819 -300.857028) (xy 391.543795 -300.817168) (xy 391.519754 -300.772745)
			(xy 391.503353 -300.724971) (xy 391.49504 -300.675149) (xy 391.494518 -300.649894) (xy 391.494693 -300.635711)
			(xy 391.497366 -300.607471) (xy 391.499852 -300.593506) (xy 391.502138 -300.58106) (xy 391.494772 -300.557438)
			(xy 391.417302 -300.479968) (xy 391.39368 -300.472602) (xy 391.381234 -300.474888) (xy 391.367269 -300.477369)
			(xy 391.339029 -300.480038) (xy 391.324846 -300.480222) (xy 391.310663 -300.480039) (xy 391.282423 -300.477371)
			(xy 391.268458 -300.474888) (xy 391.256012 -300.472602) (xy 391.23239 -300.479968) (xy 391.15492 -300.557438)
			(xy 391.147554 -300.58106) (xy 391.14984 -300.593506) (xy 391.152313 -300.607472) (xy 391.154987 -300.635712)
			(xy 391.155174 -300.649894) (xy 391.154729 -300.674715) (xy 391.146699 -300.723703) (xy 391.130849 -300.770746)
			(xy 391.107598 -300.814606) (xy 391.077557 -300.854126) (xy 391.041519 -300.888266) (xy 391.000432 -300.916126)
			(xy 390.955379 -300.936972) (xy 390.907548 -300.950255) (xy 390.858197 -300.955624) (xy 390.808628 -300.952939)
			(xy 390.760146 -300.942271) (xy 390.714029 -300.923899) (xy 390.671492 -300.898309) (xy 390.633655 -300.866174)
			(xy 390.601515 -300.828341) (xy 390.575919 -300.785807) (xy 390.557541 -300.739692) (xy 390.546866 -300.691212)
			(xy 390.544174 -300.641643) (xy 390.549538 -300.592292) (xy 390.562814 -300.544458) (xy 390.583654 -300.499403)
			(xy 390.611509 -300.458312) (xy 390.645644 -300.42227) (xy 390.68516 -300.392224) (xy 390.729017 -300.368967)
			(xy 390.776058 -300.353111) (xy 390.825045 -300.345075) (xy 390.849866 -300.344586) (xy 390.864049 -300.344767)
			(xy 390.892289 -300.347436) (xy 390.906254 -300.34992) (xy 390.9187 -300.352206) (xy 390.942322 -300.34484)
			(xy 391.019792 -300.26737) (xy 391.027158 -300.243748) (xy 391.024872 -300.231302) (xy 391.022399 -300.217335)
			(xy 391.019725 -300.189096) (xy 391.019538 -300.174914) (xy 391.019716 -300.160731) (xy 391.022387 -300.132491)
			(xy 391.024872 -300.118526) (xy 391.027158 -300.10608) (xy 391.019792 -300.082458) (xy 390.942322 -300.004988)
			(xy 390.9187 -299.997622) (xy 390.906254 -299.999908) (xy 390.892289 -300.002387) (xy 390.864049 -300.005057)
			(xy 390.849866 -300.005242) (xy 390.824615 -300.00465) (xy 390.774803 -299.996333) (xy 390.72704 -299.979931)
			(xy 390.682627 -299.955891) (xy 390.642776 -299.92487) (xy 390.608574 -299.887713) (xy 390.580954 -299.845434)
			(xy 390.56067 -299.799185) (xy 390.548273 -299.750229) (xy 390.544103 -299.6999) (xy 389.255254 -299.6999)
			(xy 389.255254 -299.699934) (xy 389.254685 -299.724752) (xy 389.24665 -299.773734) (xy 389.230795 -299.820771)
			(xy 389.20754 -299.864622) (xy 389.177497 -299.904134) (xy 389.141457 -299.938265) (xy 389.10037 -299.966116)
			(xy 389.055318 -299.986952) (xy 389.007489 -300.000225) (xy 388.958143 -300.005586) (xy 388.908579 -300.002892)
			(xy 388.860105 -299.992216) (xy 388.813996 -299.973838) (xy 388.771467 -299.948242) (xy 388.733641 -299.916103)
			(xy 388.701511 -299.878267) (xy 388.675927 -299.835733) (xy 388.657561 -299.789619) (xy 388.646897 -299.741141)
			(xy 388.644216 -299.691577) (xy 388.64959 -299.642232) (xy 388.662876 -299.594407) (xy 388.683724 -299.549361)
			(xy 388.711585 -299.508281) (xy 388.745725 -299.47225) (xy 388.785245 -299.442217) (xy 388.829103 -299.418973)
			(xy 388.876144 -299.403131) (xy 388.925128 -299.395108) (xy 388.949946 -299.394626) (xy 388.964129 -299.39481)
			(xy 388.992369 -299.397477) (xy 389.006334 -299.39996) (xy 389.01878 -299.402246) (xy 389.042402 -299.39488)
			(xy 389.119872 -299.31741) (xy 389.127238 -299.293788) (xy 389.124952 -299.281342) (xy 389.122472 -299.267377)
			(xy 389.119802 -299.239137) (xy 389.119618 -299.224954) (xy 389.119704 -299.215786) (xy 389.120849 -299.197486)
			(xy 389.121904 -299.188378) (xy 389.123174 -299.176186) (xy 389.1153 -299.154088) (xy 389.038846 -299.080936)
			(xy 389.01624 -299.074078) (xy 389.004302 -299.07611) (xy 388.990808 -299.078167) (xy 388.963595 -299.080329)
			(xy 388.949946 -299.080428) (xy 387.999986 -299.080428) (xy 387.973989 -299.079966) (xy 387.922636 -299.071833)
			(xy 387.873186 -299.055772) (xy 387.826856 -299.032175) (xy 387.784786 -299.001625) (xy 387.748009 -298.964871)
			(xy 387.717433 -298.92282) (xy 387.693807 -298.876504) (xy 387.677715 -298.827064) (xy 387.669551 -298.775716)
			(xy 387.669024 -298.74972) (xy 387.669178 -298.736066) (xy 387.671467 -298.708852) (xy 387.673596 -298.695364)
			(xy 387.675628 -298.683426) (xy 387.66877 -298.66082) (xy 387.595618 -298.584366) (xy 387.57352 -298.576492)
			(xy 387.561328 -298.577762) (xy 387.552284 -298.57881) (xy 387.53411 -298.579951) (xy 387.525006 -298.580048)
			(xy 387.500184 -298.579529) (xy 387.451193 -298.571498) (xy 387.404148 -298.555647) (xy 387.360286 -298.532393)
			(xy 387.320765 -298.50235) (xy 387.286625 -298.466308) (xy 387.258766 -298.425217) (xy 387.237921 -298.380161)
			(xy 387.224641 -298.332326) (xy 387.219275 -298.282973) (xy 386.879934 -298.282973) (xy 386.879605 -298.299347)
			(xy 386.87171 -298.347924) (xy 386.856126 -298.394605) (xy 386.833255 -298.438182) (xy 386.80369 -298.477526)
			(xy 386.768197 -298.511618) (xy 386.727694 -298.539574) (xy 386.683232 -298.560672) (xy 386.635961 -298.574364)
			(xy 386.587106 -298.580296) (xy 386.537931 -298.578315) (xy 386.489712 -298.568471) (xy 386.443696 -298.551019)
			(xy 386.401075 -298.526412) (xy 386.362954 -298.495287) (xy 386.330319 -298.45845) (xy 386.304016 -298.416854)
			(xy 386.284725 -298.371578) (xy 386.272948 -298.323794) (xy 386.268988 -298.27474) (xy 385.929886 -298.27474)
			(xy 385.929391 -298.299347) (xy 385.921496 -298.347924) (xy 385.905912 -298.394605) (xy 385.883041 -298.438182)
			(xy 385.853476 -298.477526) (xy 385.817983 -298.511618) (xy 385.77748 -298.539574) (xy 385.733018 -298.560672)
			(xy 385.685747 -298.574364) (xy 385.636892 -298.580296) (xy 385.587717 -298.578315) (xy 385.539498 -298.568471)
			(xy 385.493482 -298.551019) (xy 385.450861 -298.526412) (xy 385.41274 -298.495287) (xy 385.380105 -298.45845)
			(xy 385.353802 -298.416854) (xy 385.334511 -298.371578) (xy 385.322734 -298.323794) (xy 385.318774 -298.27474)
			(xy 384.980175 -298.27474) (xy 384.979685 -298.299093) (xy 384.97179 -298.34767) (xy 384.956206 -298.394351)
			(xy 384.933335 -298.437928) (xy 384.90377 -298.477272) (xy 384.868277 -298.511364) (xy 384.827774 -298.53932)
			(xy 384.783312 -298.560418) (xy 384.736041 -298.57411) (xy 384.687186 -298.580042) (xy 384.638011 -298.578061)
			(xy 384.589792 -298.568217) (xy 384.543776 -298.550765) (xy 384.501155 -298.526158) (xy 384.463034 -298.495033)
			(xy 384.430399 -298.458196) (xy 384.404096 -298.4166) (xy 384.384805 -298.371324) (xy 384.373028 -298.32354)
			(xy 384.369068 -298.274486) (xy 351.031048 -298.274486) (xy 351.031048 -299.133514) (xy 374.111518 -299.133514)
			(xy 374.115589 -299.077892) (xy 374.127715 -299.023455) (xy 374.147638 -298.971364) (xy 374.174934 -298.922729)
			(xy 374.20902 -298.878586) (xy 374.249169 -298.839877) (xy 374.294527 -298.807426) (xy 374.344127 -298.781925)
			(xy 374.396911 -298.763918) (xy 374.451754 -298.753788) (xy 374.507488 -298.751751) (xy 374.562925 -298.757851)
			(xy 374.616882 -298.771957) (xy 374.668211 -298.793769) (xy 374.715817 -298.822823) (xy 374.758685 -298.858498)
			(xy 374.795902 -298.900035) (xy 374.826675 -298.946548) (xy 374.850347 -298.997045) (xy 374.866415 -299.050452)
			(xy 374.874535 -299.105628) (xy 374.875044 -299.133514) (xy 375.587004 -299.133514) (xy 375.591075 -299.077892)
			(xy 375.603201 -299.023455) (xy 375.623124 -298.971364) (xy 375.65042 -298.922729) (xy 375.684506 -298.878586)
			(xy 375.724655 -298.839877) (xy 375.770013 -298.807426) (xy 375.819613 -298.781925) (xy 375.872397 -298.763918)
			(xy 375.92724 -298.753788) (xy 375.982974 -298.751751) (xy 376.038411 -298.757851) (xy 376.092368 -298.771957)
			(xy 376.143697 -298.793769) (xy 376.191303 -298.822823) (xy 376.234171 -298.858498) (xy 376.271388 -298.900035)
			(xy 376.302161 -298.946548) (xy 376.325833 -298.997045) (xy 376.341901 -299.050452) (xy 376.350021 -299.105628)
			(xy 376.35053 -299.133514) (xy 376.476004 -299.133514) (xy 376.480075 -299.077892) (xy 376.492201 -299.023455)
			(xy 376.512124 -298.971364) (xy 376.53942 -298.922729) (xy 376.573506 -298.878586) (xy 376.613655 -298.839877)
			(xy 376.659013 -298.807426) (xy 376.708613 -298.781925) (xy 376.761397 -298.763918) (xy 376.81624 -298.753788)
			(xy 376.871974 -298.751751) (xy 376.927411 -298.757851) (xy 376.981368 -298.771957) (xy 377.032697 -298.793769)
			(xy 377.080303 -298.822823) (xy 377.123171 -298.858498) (xy 377.160388 -298.900035) (xy 377.191161 -298.946548)
			(xy 377.214833 -298.997045) (xy 377.230901 -299.050452) (xy 377.239021 -299.105628) (xy 377.23953 -299.133514)
			(xy 377.239021 -299.1614) (xy 377.230901 -299.216576) (xy 377.214833 -299.269983) (xy 377.191161 -299.32048)
			(xy 377.160388 -299.366993) (xy 377.123171 -299.40853) (xy 377.080303 -299.444205) (xy 377.032697 -299.473259)
			(xy 376.981368 -299.495071) (xy 376.927411 -299.509177) (xy 376.871974 -299.515277) (xy 376.81624 -299.51324)
			(xy 376.761397 -299.50311) (xy 376.708613 -299.485103) (xy 376.659013 -299.459602) (xy 376.613655 -299.427151)
			(xy 376.573506 -299.388442) (xy 376.53942 -299.344299) (xy 376.512124 -299.295664) (xy 376.492201 -299.243573)
			(xy 376.480075 -299.189136) (xy 376.476004 -299.133514) (xy 376.35053 -299.133514) (xy 376.350021 -299.1614)
			(xy 376.341901 -299.216576) (xy 376.325833 -299.269983) (xy 376.302161 -299.32048) (xy 376.271388 -299.366993)
			(xy 376.234171 -299.40853) (xy 376.191303 -299.444205) (xy 376.143697 -299.473259) (xy 376.092368 -299.495071)
			(xy 376.038411 -299.509177) (xy 375.982974 -299.515277) (xy 375.92724 -299.51324) (xy 375.872397 -299.50311)
			(xy 375.819613 -299.485103) (xy 375.770013 -299.459602) (xy 375.724655 -299.427151) (xy 375.684506 -299.388442)
			(xy 375.65042 -299.344299) (xy 375.623124 -299.295664) (xy 375.603201 -299.243573) (xy 375.591075 -299.189136)
			(xy 375.587004 -299.133514) (xy 374.875044 -299.133514) (xy 374.874535 -299.1614) (xy 374.866415 -299.216576)
			(xy 374.850347 -299.269983) (xy 374.826675 -299.32048) (xy 374.795902 -299.366993) (xy 374.758685 -299.40853)
			(xy 374.715817 -299.444205) (xy 374.668211 -299.473259) (xy 374.616882 -299.495071) (xy 374.562925 -299.509177)
			(xy 374.507488 -299.515277) (xy 374.451754 -299.51324) (xy 374.396911 -299.50311) (xy 374.344127 -299.485103)
			(xy 374.294527 -299.459602) (xy 374.249169 -299.427151) (xy 374.20902 -299.388442) (xy 374.174934 -299.344299)
			(xy 374.147638 -299.295664) (xy 374.127715 -299.243573) (xy 374.115589 -299.189136) (xy 374.111518 -299.133514)
			(xy 351.031048 -299.133514) (xy 351.031048 -299.895514) (xy 379.638052 -299.895514) (xy 379.638619 -299.866133)
			(xy 379.647646 -299.808068) (xy 379.665474 -299.752075) (xy 379.691681 -299.69948) (xy 379.725646 -299.651528)
			(xy 379.766565 -299.609354) (xy 379.78969 -299.591222) (xy 379.799088 -299.583856) (xy 379.809502 -299.563282)
			(xy 379.811026 -299.459396) (xy 379.80112 -299.438314) (xy 379.791976 -299.430948) (xy 379.770116 -299.412756)
			(xy 379.731578 -299.370934) (xy 379.699673 -299.323855) (xy 379.675108 -299.272563) (xy 379.658427 -299.218193)
			(xy 379.65 -299.16195) (xy 379.649482 -299.133514) (xy 379.649968 -299.106263) (xy 379.657724 -299.052315)
			(xy 379.673079 -299.00002) (xy 379.695721 -298.950443) (xy 379.725187 -298.904593) (xy 379.760878 -298.863402)
			(xy 379.802069 -298.827711) (xy 379.847919 -298.798245) (xy 379.897496 -298.775603) (xy 379.949791 -298.760248)
			(xy 380.003739 -298.752492) (xy 380.058241 -298.752492) (xy 380.112189 -298.760248) (xy 380.164484 -298.775603)
			(xy 380.214061 -298.798245) (xy 380.259911 -298.827711) (xy 380.301102 -298.863402) (xy 380.336793 -298.904593)
			(xy 380.366259 -298.950443) (xy 380.388901 -299.00002) (xy 380.404256 -299.052315) (xy 380.412012 -299.106263)
			(xy 380.412498 -299.133514) (xy 380.411971 -299.162897) (xy 380.402938 -299.220964) (xy 380.401748 -299.2247)
			(xy 383.734069 -299.2247) (xy 383.73824 -299.174365) (xy 383.750638 -299.125402) (xy 383.770925 -299.079148)
			(xy 383.798549 -299.036864) (xy 383.832755 -298.999703) (xy 383.872611 -298.968678) (xy 383.91703 -298.944636)
			(xy 383.9648 -298.928233) (xy 384.014618 -298.919916) (xy 384.039872 -298.919392) (xy 384.065268 -298.919898)
			(xy 384.115358 -298.928313) (xy 384.163365 -298.944897) (xy 384.207968 -298.969196) (xy 384.247936 -299.000538)
			(xy 384.265424 -299.01896) (xy 384.273044 -299.027342) (xy 384.29311 -299.035724) (xy 384.392424 -299.033184)
			(xy 384.411728 -299.023786) (xy 384.419094 -299.014896) (xy 384.434899 -298.996367) (xy 384.47099 -298.963668)
			(xy 384.511482 -298.936611) (xy 384.555502 -298.915779) (xy 384.602099 -298.901621) (xy 384.650268 -298.894444)
			(xy 384.674618 -298.893992) (xy 385.624578 -298.893992) (xy 385.650585 -298.894566) (xy 385.701958 -298.902699)
			(xy 385.751427 -298.91877) (xy 385.797772 -298.942381) (xy 385.839853 -298.972952) (xy 385.876634 -299.00973)
			(xy 385.907207 -299.051809) (xy 385.930822 -299.098153) (xy 385.946896 -299.14762) (xy 385.955033 -299.198993)
			(xy 385.955033 -299.233291) (xy 386.269089 -299.233291) (xy 386.271775 -299.183725) (xy 386.282444 -299.135247)
			(xy 386.300815 -299.089133) (xy 386.326404 -299.046598) (xy 386.358537 -299.008764) (xy 386.396368 -298.976626)
			(xy 386.438899 -298.951032) (xy 386.485011 -298.932655) (xy 386.533488 -298.92198) (xy 386.583053 -298.919288)
			(xy 386.632401 -298.924651) (xy 386.680232 -298.937925) (xy 386.725285 -298.958763) (xy 386.766373 -298.986615)
			(xy 386.802415 -299.020747) (xy 386.83246 -299.06026) (xy 386.855717 -299.104113) (xy 386.871573 -299.151151)
			(xy 386.87961 -299.200135) (xy 386.8801 -299.224954) (xy 386.879917 -299.239137) (xy 386.877249 -299.267377)
			(xy 386.874766 -299.281342) (xy 386.872579 -299.295304) (xy 386.875168 -299.323435) (xy 386.885364 -299.349782)
			(xy 386.902388 -299.372327) (xy 386.924937 -299.389346) (xy 386.951285 -299.399537) (xy 386.979417 -299.40212)
			(xy 386.993384 -299.39996) (xy 387.007414 -299.39748) (xy 387.03578 -299.394805) (xy 387.050026 -299.394626)
			(xy 387.074844 -299.395106) (xy 387.123825 -299.40314) (xy 387.170861 -299.418992) (xy 387.214713 -299.442244)
			(xy 387.254225 -299.472285) (xy 387.288358 -299.508322) (xy 387.316211 -299.549405) (xy 387.33705 -299.594454)
			(xy 387.350328 -299.642281) (xy 387.355693 -299.691625) (xy 387.355242 -299.699934) (xy 387.694182 -299.699934)
			(xy 387.698142 -299.65088) (xy 387.709919 -299.603096) (xy 387.72921 -299.55782) (xy 387.755513 -299.516224)
			(xy 387.788148 -299.479387) (xy 387.826269 -299.448262) (xy 387.86889 -299.423655) (xy 387.914906 -299.406203)
			(xy 387.963125 -299.396359) (xy 388.0123 -299.394378) (xy 388.061155 -299.40031) (xy 388.108426 -299.414002)
			(xy 388.152888 -299.4351) (xy 388.193391 -299.463056) (xy 388.228884 -299.497148) (xy 388.258449 -299.536492)
			(xy 388.28132 -299.580069) (xy 388.296904 -299.62675) (xy 388.304799 -299.675327) (xy 388.305294 -299.699934)
			(xy 388.304799 -299.724541) (xy 388.296904 -299.773118) (xy 388.28132 -299.819799) (xy 388.258449 -299.863376)
			(xy 388.228884 -299.90272) (xy 388.193391 -299.936812) (xy 388.152888 -299.964768) (xy 388.108426 -299.985866)
			(xy 388.061155 -299.999558) (xy 388.0123 -300.00549) (xy 387.963125 -300.003509) (xy 387.914906 -299.993665)
			(xy 387.86889 -299.976213) (xy 387.826269 -299.951606) (xy 387.788148 -299.920481) (xy 387.755513 -299.883644)
			(xy 387.72921 -299.842048) (xy 387.709919 -299.796772) (xy 387.698142 -299.748988) (xy 387.694182 -299.699934)
			(xy 387.355242 -299.699934) (xy 387.353005 -299.741188) (xy 387.342334 -299.789663) (xy 387.323962 -299.835773)
			(xy 387.298373 -299.878303) (xy 387.26624 -299.916134) (xy 387.22841 -299.948268) (xy 387.18588 -299.973859)
			(xy 387.13977 -299.992232) (xy 387.091296 -300.002904) (xy 387.041733 -300.005593) (xy 386.992389 -300.000229)
			(xy 386.944562 -299.986953) (xy 386.899512 -299.966115) (xy 386.858428 -299.938263) (xy 386.82239 -299.904131)
			(xy 386.792349 -299.864619) (xy 386.769095 -299.820768) (xy 386.753242 -299.773732) (xy 386.745206 -299.724752)
			(xy 386.744718 -299.699934) (xy 386.744899 -299.685751) (xy 386.747568 -299.657511) (xy 386.750052 -299.643546)
			(xy 386.75223 -299.629584) (xy 386.749639 -299.601455) (xy 386.739442 -299.575112) (xy 386.72242 -299.552569)
			(xy 386.699874 -299.53555) (xy 386.673529 -299.525358) (xy 386.6454 -299.522771) (xy 386.631434 -299.524928)
			(xy 386.617406 -299.527419) (xy 386.589038 -299.530087) (xy 386.574792 -299.530262) (xy 386.549973 -299.529814)
			(xy 386.500988 -299.521782) (xy 386.453948 -299.505932) (xy 386.410092 -299.48268) (xy 386.370575 -299.45264)
			(xy 386.336439 -299.416603) (xy 386.308582 -299.375518) (xy 386.287738 -299.330468) (xy 386.274458 -299.282639)
			(xy 386.269089 -299.233291) (xy 385.955033 -299.233291) (xy 385.955033 -299.251007) (xy 385.946896 -299.30238)
			(xy 385.930822 -299.351847) (xy 385.907207 -299.398191) (xy 385.876634 -299.44027) (xy 385.839853 -299.477048)
			(xy 385.797772 -299.507619) (xy 385.751427 -299.53123) (xy 385.701958 -299.547301) (xy 385.650585 -299.555434)
			(xy 385.624578 -299.555916) (xy 384.674618 -299.555916) (xy 384.650234 -299.555483) (xy 384.601997 -299.54831)
			(xy 384.555336 -299.53413) (xy 384.511263 -299.513252) (xy 384.470734 -299.486128) (xy 384.434627 -299.453346)
			(xy 384.41884 -299.434758) (xy 384.411728 -299.426122) (xy 384.39217 -299.41647) (xy 384.292856 -299.41393)
			(xy 384.27279 -299.422312) (xy 384.26517 -299.430694) (xy 384.247686 -299.449071) (xy 384.207755 -299.480345)
			(xy 384.163203 -299.504586) (xy 384.115255 -299.521125) (xy 384.065232 -299.529508) (xy 384.039872 -299.530008)
			(xy 384.014618 -299.529484) (xy 383.9648 -299.521167) (xy 383.91703 -299.504764) (xy 383.872611 -299.480722)
			(xy 383.832755 -299.449697) (xy 383.798549 -299.412536) (xy 383.770925 -299.370252) (xy 383.750638 -299.323998)
			(xy 383.73824 -299.275035) (xy 383.734069 -299.2247) (xy 380.401748 -299.2247) (xy 380.385103 -299.276959)
			(xy 380.358889 -299.329554) (xy 380.324916 -299.377505) (xy 380.283989 -299.419676) (xy 380.26086 -299.437806)
			(xy 380.251462 -299.445172) (xy 380.241048 -299.465746) (xy 380.239524 -299.569632) (xy 380.24943 -299.590714)
			(xy 380.258574 -299.59808) (xy 380.280389 -299.616324) (xy 380.318933 -299.658134) (xy 380.350844 -299.705201)
			(xy 380.375417 -299.756484) (xy 380.392107 -299.810845) (xy 380.400545 -299.867081) (xy 380.401068 -299.895514)
			(xy 381.034542 -299.895514) (xy 381.038613 -299.839892) (xy 381.050739 -299.785455) (xy 381.070662 -299.733364)
			(xy 381.097958 -299.684729) (xy 381.132044 -299.640586) (xy 381.172193 -299.601877) (xy 381.217551 -299.569426)
			(xy 381.267151 -299.543925) (xy 381.319935 -299.525918) (xy 381.374778 -299.515788) (xy 381.430512 -299.513751)
			(xy 381.485949 -299.519851) (xy 381.539906 -299.533957) (xy 381.591235 -299.555769) (xy 381.638841 -299.584823)
			(xy 381.681709 -299.620498) (xy 381.718926 -299.662035) (xy 381.749699 -299.708548) (xy 381.773371 -299.759045)
			(xy 381.789439 -299.812452) (xy 381.797559 -299.867628) (xy 381.798068 -299.895514) (xy 381.921002 -299.895514)
			(xy 381.925073 -299.839892) (xy 381.937199 -299.785455) (xy 381.957122 -299.733364) (xy 381.984418 -299.684729)
			(xy 382.018504 -299.640586) (xy 382.058653 -299.601877) (xy 382.104011 -299.569426) (xy 382.153611 -299.543925)
			(xy 382.206395 -299.525918) (xy 382.261238 -299.515788) (xy 382.316972 -299.513751) (xy 382.372409 -299.519851)
			(xy 382.426366 -299.533957) (xy 382.477695 -299.555769) (xy 382.525301 -299.584823) (xy 382.568169 -299.620498)
			(xy 382.605386 -299.662035) (xy 382.636159 -299.708548) (xy 382.659831 -299.759045) (xy 382.675899 -299.812452)
			(xy 382.684019 -299.867628) (xy 382.684528 -299.895514) (xy 382.684019 -299.9234) (xy 382.675899 -299.978576)
			(xy 382.659831 -300.031983) (xy 382.636159 -300.08248) (xy 382.605386 -300.128993) (xy 382.568169 -300.17053)
			(xy 382.553215 -300.182975) (xy 384.369209 -300.182975) (xy 384.371897 -300.133413) (xy 384.382567 -300.084939)
			(xy 384.400939 -300.038829) (xy 384.426528 -299.996299) (xy 384.45866 -299.958469) (xy 384.496489 -299.926335)
			(xy 384.539019 -299.900744) (xy 384.585127 -299.882371) (xy 384.633601 -299.871699) (xy 384.683163 -299.869009)
			(xy 384.732507 -299.874372) (xy 384.780334 -299.887647) (xy 384.825383 -299.908485) (xy 384.866467 -299.936336)
			(xy 384.902505 -299.970467) (xy 384.932547 -300.009977) (xy 384.955801 -300.053828) (xy 384.971655 -300.100863)
			(xy 384.979691 -300.149843) (xy 384.98018 -300.17466) (xy 384.980015 -300.188907) (xy 384.977341 -300.217274)
			(xy 384.974846 -300.231302) (xy 384.97256 -300.243494) (xy 384.979926 -300.267624) (xy 385.057142 -300.34484)
			(xy 385.081018 -300.352206) (xy 385.093464 -300.34992) (xy 385.107429 -300.347439) (xy 385.135669 -300.34477)
			(xy 385.149852 -300.344586) (xy 385.163966 -300.34472) (xy 385.192077 -300.347267) (xy 385.205986 -300.349666)
			(xy 385.218686 -300.352206) (xy 385.242308 -300.34484) (xy 385.319524 -300.26737) (xy 385.32689 -300.243748)
			(xy 385.324604 -300.231302) (xy 385.322132 -300.217335) (xy 385.319457 -300.189096) (xy 385.31927 -300.174914)
			(xy 385.319792 -300.149659) (xy 385.328105 -300.099837) (xy 385.344506 -300.052063) (xy 385.368547 -300.00764)
			(xy 385.399571 -299.96778) (xy 385.436733 -299.93357) (xy 385.479019 -299.905944) (xy 385.525275 -299.885654)
			(xy 385.57424 -299.873254) (xy 385.624578 -299.869083) (xy 385.674916 -299.873254) (xy 385.723881 -299.885654)
			(xy 385.770137 -299.905944) (xy 385.812423 -299.93357) (xy 385.849585 -299.96778) (xy 385.880609 -300.00764)
			(xy 385.90465 -300.052063) (xy 385.921051 -300.099837) (xy 385.929364 -300.149659) (xy 385.929886 -300.174914)
			(xy 385.929712 -300.189097) (xy 385.927038 -300.217337) (xy 385.924552 -300.231302) (xy 385.922266 -300.243748)
			(xy 385.929632 -300.267624) (xy 386.006848 -300.34484) (xy 386.030978 -300.352206) (xy 386.04317 -300.34992)
			(xy 386.057198 -300.347428) (xy 386.085566 -300.344761) (xy 386.099812 -300.344586) (xy 386.124632 -300.345091)
			(xy 386.173617 -300.353123) (xy 386.220658 -300.368975) (xy 386.264514 -300.392228) (xy 386.30403 -300.422271)
			(xy 386.338166 -300.45831) (xy 386.366022 -300.499397) (xy 386.386863 -300.544449) (xy 386.400142 -300.59228)
			(xy 386.405507 -300.641629) (xy 386.405059 -300.649894) (xy 386.744222 -300.649894) (xy 386.748182 -300.60084)
			(xy 386.759959 -300.553056) (xy 386.77925 -300.50778) (xy 386.805553 -300.466184) (xy 386.838188 -300.429347)
			(xy 386.876309 -300.398222) (xy 386.91893 -300.373615) (xy 386.964946 -300.356163) (xy 387.013165 -300.346319)
			(xy 387.06234 -300.344338) (xy 387.111195 -300.35027) (xy 387.158466 -300.363962) (xy 387.202928 -300.38506)
			(xy 387.243431 -300.413016) (xy 387.278924 -300.447108) (xy 387.308489 -300.486452) (xy 387.33136 -300.530029)
			(xy 387.346944 -300.57671) (xy 387.354839 -300.625287) (xy 387.355334 -300.649894) (xy 387.694182 -300.649894)
			(xy 387.698142 -300.60084) (xy 387.709919 -300.553056) (xy 387.72921 -300.50778) (xy 387.755513 -300.466184)
			(xy 387.788148 -300.429347) (xy 387.826269 -300.398222) (xy 387.86889 -300.373615) (xy 387.914906 -300.356163)
			(xy 387.963125 -300.346319) (xy 388.0123 -300.344338) (xy 388.061155 -300.35027) (xy 388.108426 -300.363962)
			(xy 388.152888 -300.38506) (xy 388.193391 -300.413016) (xy 388.228884 -300.447108) (xy 388.258449 -300.486452)
			(xy 388.28132 -300.530029) (xy 388.296904 -300.57671) (xy 388.304799 -300.625287) (xy 388.305294 -300.649894)
			(xy 388.644142 -300.649894) (xy 388.648102 -300.60084) (xy 388.659879 -300.553056) (xy 388.67917 -300.50778)
			(xy 388.705473 -300.466184) (xy 388.738108 -300.429347) (xy 388.776229 -300.398222) (xy 388.81885 -300.373615)
			(xy 388.864866 -300.356163) (xy 388.913085 -300.346319) (xy 388.96226 -300.344338) (xy 389.011115 -300.35027)
			(xy 389.058386 -300.363962) (xy 389.102848 -300.38506) (xy 389.143351 -300.413016) (xy 389.178844 -300.447108)
			(xy 389.208409 -300.486452) (xy 389.23128 -300.530029) (xy 389.246864 -300.57671) (xy 389.254759 -300.625287)
			(xy 389.255254 -300.649894) (xy 389.594102 -300.649894) (xy 389.598062 -300.60084) (xy 389.609839 -300.553056)
			(xy 389.62913 -300.50778) (xy 389.655433 -300.466184) (xy 389.688068 -300.429347) (xy 389.726189 -300.398222)
			(xy 389.76881 -300.373615) (xy 389.814826 -300.356163) (xy 389.863045 -300.346319) (xy 389.91222 -300.344338)
			(xy 389.961075 -300.35027) (xy 390.008346 -300.363962) (xy 390.052808 -300.38506) (xy 390.093311 -300.413016)
			(xy 390.128804 -300.447108) (xy 390.158369 -300.486452) (xy 390.18124 -300.530029) (xy 390.196824 -300.57671)
			(xy 390.204719 -300.625287) (xy 390.205214 -300.649894) (xy 390.204719 -300.674501) (xy 390.196824 -300.723078)
			(xy 390.18124 -300.769759) (xy 390.158369 -300.813336) (xy 390.128804 -300.85268) (xy 390.093311 -300.886772)
			(xy 390.052808 -300.914728) (xy 390.008346 -300.935826) (xy 389.961075 -300.949518) (xy 389.91222 -300.95545)
			(xy 389.863045 -300.953469) (xy 389.814826 -300.943625) (xy 389.76881 -300.926173) (xy 389.726189 -300.901566)
			(xy 389.688068 -300.870441) (xy 389.655433 -300.833604) (xy 389.62913 -300.792008) (xy 389.609839 -300.746732)
			(xy 389.598062 -300.698948) (xy 389.594102 -300.649894) (xy 389.255254 -300.649894) (xy 389.254759 -300.674501)
			(xy 389.246864 -300.723078) (xy 389.23128 -300.769759) (xy 389.208409 -300.813336) (xy 389.178844 -300.85268)
			(xy 389.143351 -300.886772) (xy 389.102848 -300.914728) (xy 389.058386 -300.935826) (xy 389.011115 -300.949518)
			(xy 388.96226 -300.95545) (xy 388.913085 -300.953469) (xy 388.864866 -300.943625) (xy 388.81885 -300.926173)
			(xy 388.776229 -300.901566) (xy 388.738108 -300.870441) (xy 388.705473 -300.833604) (xy 388.67917 -300.792008)
			(xy 388.659879 -300.746732) (xy 388.648102 -300.698948) (xy 388.644142 -300.649894) (xy 388.305294 -300.649894)
			(xy 388.304799 -300.674501) (xy 388.296904 -300.723078) (xy 388.28132 -300.769759) (xy 388.258449 -300.813336)
			(xy 388.228884 -300.85268) (xy 388.193391 -300.886772) (xy 388.152888 -300.914728) (xy 388.108426 -300.935826)
			(xy 388.061155 -300.949518) (xy 388.0123 -300.95545) (xy 387.963125 -300.953469) (xy 387.914906 -300.943625)
			(xy 387.86889 -300.926173) (xy 387.826269 -300.901566) (xy 387.788148 -300.870441) (xy 387.755513 -300.833604)
			(xy 387.72921 -300.792008) (xy 387.709919 -300.746732) (xy 387.698142 -300.698948) (xy 387.694182 -300.649894)
			(xy 387.355334 -300.649894) (xy 387.354839 -300.674501) (xy 387.346944 -300.723078) (xy 387.33136 -300.769759)
			(xy 387.308489 -300.813336) (xy 387.278924 -300.85268) (xy 387.243431 -300.886772) (xy 387.202928 -300.914728)
			(xy 387.158466 -300.935826) (xy 387.111195 -300.949518) (xy 387.06234 -300.95545) (xy 387.013165 -300.953469)
			(xy 386.964946 -300.943625) (xy 386.91893 -300.926173) (xy 386.876309 -300.901566) (xy 386.838188 -300.870441)
			(xy 386.805553 -300.833604) (xy 386.77925 -300.792008) (xy 386.759959 -300.746732) (xy 386.748182 -300.698948)
			(xy 386.744222 -300.649894) (xy 386.405059 -300.649894) (xy 386.402818 -300.691195) (xy 386.392145 -300.739674)
			(xy 386.373771 -300.785787) (xy 386.348177 -300.828321) (xy 386.31604 -300.866153) (xy 386.278206 -300.898288)
			(xy 386.235671 -300.923879) (xy 386.189557 -300.942251) (xy 386.141077 -300.952921) (xy 386.091511 -300.955607)
			(xy 386.042162 -300.950238) (xy 385.994332 -300.936957) (xy 385.949281 -300.916113) (xy 385.908196 -300.888255)
			(xy 385.872158 -300.854117) (xy 385.842119 -300.814599) (xy 385.818868 -300.770741) (xy 385.803019 -300.7237)
			(xy 385.794989 -300.674714) (xy 385.794504 -300.649894) (xy 385.79468 -300.635711) (xy 385.797352 -300.607471)
			(xy 385.799838 -300.593506) (xy 385.802124 -300.58106) (xy 385.794758 -300.557184) (xy 385.717542 -300.479968)
			(xy 385.693412 -300.472602) (xy 385.68122 -300.474888) (xy 385.66719 -300.477368) (xy 385.638824 -300.480043)
			(xy 385.624578 -300.480222) (xy 385.610465 -300.480084) (xy 385.582353 -300.47754) (xy 385.568444 -300.475142)
			(xy 385.555744 -300.472602) (xy 385.532122 -300.479968) (xy 385.454906 -300.557438) (xy 385.44754 -300.58106)
			(xy 385.449826 -300.593506) (xy 385.4523 -300.607472) (xy 385.454973 -300.635712) (xy 385.45516 -300.649894)
			(xy 385.454638 -300.675149) (xy 385.446325 -300.724971) (xy 385.429924 -300.772745) (xy 385.405883 -300.817168)
			(xy 385.374859 -300.857028) (xy 385.337697 -300.891238) (xy 385.295411 -300.918864) (xy 385.249155 -300.939154)
			(xy 385.20019 -300.951554) (xy 385.149852 -300.955725) (xy 385.099514 -300.951554) (xy 385.050549 -300.939154)
			(xy 385.004293 -300.918864) (xy 384.962007 -300.891238) (xy 384.924845 -300.857028) (xy 384.893821 -300.817168)
			(xy 384.86978 -300.772745) (xy 384.853379 -300.724971) (xy 384.845066 -300.675149) (xy 384.844544 -300.649894)
			(xy 384.844711 -300.635647) (xy 384.84738 -300.607279) (xy 384.849878 -300.593252) (xy 384.852164 -300.58106)
			(xy 384.844798 -300.55693) (xy 384.767582 -300.479714) (xy 384.743706 -300.472348) (xy 384.73126 -300.474634)
			(xy 384.717294 -300.477111) (xy 384.689055 -300.479783) (xy 384.674872 -300.479968) (xy 384.650055 -300.479492)
			(xy 384.601074 -300.471458) (xy 384.554039 -300.455606) (xy 384.510188 -300.432353) (xy 384.470675 -300.402313)
			(xy 384.436544 -300.366277) (xy 384.408691 -300.325193) (xy 384.387852 -300.280145) (xy 384.374574 -300.232319)
			(xy 384.369209 -300.182975) (xy 382.553215 -300.182975) (xy 382.525301 -300.206205) (xy 382.477695 -300.235259)
			(xy 382.426366 -300.257071) (xy 382.372409 -300.271177) (xy 382.316972 -300.277277) (xy 382.261238 -300.27524)
			(xy 382.206395 -300.26511) (xy 382.153611 -300.247103) (xy 382.104011 -300.221602) (xy 382.058653 -300.189151)
			(xy 382.018504 -300.150442) (xy 381.984418 -300.106299) (xy 381.957122 -300.057664) (xy 381.937199 -300.005573)
			(xy 381.925073 -299.951136) (xy 381.921002 -299.895514) (xy 381.798068 -299.895514) (xy 381.797559 -299.9234)
			(xy 381.789439 -299.978576) (xy 381.773371 -300.031983) (xy 381.749699 -300.08248) (xy 381.718926 -300.128993)
			(xy 381.681709 -300.17053) (xy 381.638841 -300.206205) (xy 381.591235 -300.235259) (xy 381.539906 -300.257071)
			(xy 381.485949 -300.271177) (xy 381.430512 -300.277277) (xy 381.374778 -300.27524) (xy 381.319935 -300.26511)
			(xy 381.267151 -300.247103) (xy 381.217551 -300.221602) (xy 381.172193 -300.189151) (xy 381.132044 -300.150442)
			(xy 381.097958 -300.106299) (xy 381.070662 -300.057664) (xy 381.050739 -300.005573) (xy 381.038613 -299.951136)
			(xy 381.034542 -299.895514) (xy 380.401068 -299.895514) (xy 380.400582 -299.922765) (xy 380.392826 -299.976713)
			(xy 380.377471 -300.029008) (xy 380.354829 -300.078585) (xy 380.325363 -300.124435) (xy 380.289672 -300.165626)
			(xy 380.248481 -300.201317) (xy 380.202631 -300.230783) (xy 380.153054 -300.253425) (xy 380.100759 -300.26878)
			(xy 380.046811 -300.276536) (xy 379.992309 -300.276536) (xy 379.938361 -300.26878) (xy 379.886066 -300.253425)
			(xy 379.836489 -300.230783) (xy 379.790639 -300.201317) (xy 379.749448 -300.165626) (xy 379.713757 -300.124435)
			(xy 379.684291 -300.078585) (xy 379.661649 -300.029008) (xy 379.646294 -299.976713) (xy 379.638538 -299.922765)
			(xy 379.638052 -299.895514) (xy 351.031048 -299.895514) (xy 351.031048 -301.031656) (xy 374.111518 -301.031656)
			(xy 374.115589 -300.976034) (xy 374.127715 -300.921597) (xy 374.147638 -300.869506) (xy 374.174934 -300.820871)
			(xy 374.20902 -300.776728) (xy 374.249169 -300.738019) (xy 374.294527 -300.705568) (xy 374.344127 -300.680067)
			(xy 374.396911 -300.66206) (xy 374.451754 -300.65193) (xy 374.507488 -300.649893) (xy 374.562925 -300.655993)
			(xy 374.616882 -300.670099) (xy 374.668211 -300.691911) (xy 374.715817 -300.720965) (xy 374.758685 -300.75664)
			(xy 374.795902 -300.798177) (xy 374.826675 -300.84469) (xy 374.850347 -300.895187) (xy 374.866415 -300.948594)
			(xy 374.874535 -301.00377) (xy 374.875044 -301.031656) (xy 375.596656 -301.031656) (xy 375.600727 -300.976034)
			(xy 375.612853 -300.921597) (xy 375.632776 -300.869506) (xy 375.660072 -300.820871) (xy 375.694158 -300.776728)
			(xy 375.734307 -300.738019) (xy 375.779665 -300.705568) (xy 375.829265 -300.680067) (xy 375.882049 -300.66206)
			(xy 375.936892 -300.65193) (xy 375.992626 -300.649893) (xy 376.048063 -300.655993) (xy 376.10202 -300.670099)
			(xy 376.153349 -300.691911) (xy 376.200955 -300.720965) (xy 376.243823 -300.75664) (xy 376.28104 -300.798177)
			(xy 376.311813 -300.84469) (xy 376.335485 -300.895187) (xy 376.351553 -300.948594) (xy 376.359673 -301.00377)
			(xy 376.360182 -301.031656) (xy 376.359673 -301.059542) (xy 376.351553 -301.114718) (xy 376.335485 -301.168125)
			(xy 376.311813 -301.218622) (xy 376.28104 -301.265135) (xy 376.243823 -301.306672) (xy 376.200955 -301.342347)
			(xy 376.153349 -301.371401) (xy 376.10202 -301.393213) (xy 376.048063 -301.407319) (xy 375.992626 -301.413419)
			(xy 375.936892 -301.411382) (xy 375.882049 -301.401252) (xy 375.829265 -301.383245) (xy 375.779665 -301.357744)
			(xy 375.734307 -301.325293) (xy 375.694158 -301.286584) (xy 375.660072 -301.242441) (xy 375.632776 -301.193806)
			(xy 375.612853 -301.141715) (xy 375.600727 -301.087278) (xy 375.596656 -301.031656) (xy 374.875044 -301.031656)
			(xy 374.874535 -301.059542) (xy 374.866415 -301.114718) (xy 374.850347 -301.168125) (xy 374.826675 -301.218622)
			(xy 374.795902 -301.265135) (xy 374.758685 -301.306672) (xy 374.715817 -301.342347) (xy 374.668211 -301.371401)
			(xy 374.616882 -301.393213) (xy 374.562925 -301.407319) (xy 374.507488 -301.413419) (xy 374.451754 -301.411382)
			(xy 374.396911 -301.401252) (xy 374.344127 -301.383245) (xy 374.294527 -301.357744) (xy 374.249169 -301.325293)
			(xy 374.20902 -301.286584) (xy 374.174934 -301.242441) (xy 374.147638 -301.193806) (xy 374.127715 -301.141715)
			(xy 374.115589 -301.087278) (xy 374.111518 -301.031656) (xy 351.031048 -301.031656) (xy 351.031048 -301.599854)
			(xy 384.844048 -301.599854) (xy 384.848008 -301.5508) (xy 384.859785 -301.503016) (xy 384.879076 -301.45774)
			(xy 384.905379 -301.416144) (xy 384.938014 -301.379307) (xy 384.976135 -301.348182) (xy 385.018756 -301.323575)
			(xy 385.064772 -301.306123) (xy 385.112991 -301.296279) (xy 385.162166 -301.294298) (xy 385.211021 -301.30023)
			(xy 385.258292 -301.313922) (xy 385.302754 -301.33502) (xy 385.343257 -301.362976) (xy 385.37875 -301.397068)
			(xy 385.408315 -301.436412) (xy 385.431186 -301.479989) (xy 385.44677 -301.52667) (xy 385.454665 -301.575247)
			(xy 385.45516 -301.599854) (xy 385.794008 -301.599854) (xy 385.797968 -301.5508) (xy 385.809745 -301.503016)
			(xy 385.829036 -301.45774) (xy 385.855339 -301.416144) (xy 385.887974 -301.379307) (xy 385.926095 -301.348182)
			(xy 385.968716 -301.323575) (xy 386.014732 -301.306123) (xy 386.062951 -301.296279) (xy 386.112126 -301.294298)
			(xy 386.160981 -301.30023) (xy 386.208252 -301.313922) (xy 386.252714 -301.33502) (xy 386.293217 -301.362976)
			(xy 386.32871 -301.397068) (xy 386.358275 -301.436412) (xy 386.381146 -301.479989) (xy 386.39673 -301.52667)
			(xy 386.404625 -301.575247) (xy 386.40512 -301.599854) (xy 386.404625 -301.624461) (xy 386.404446 -301.625562)
			(xy 386.723378 -301.625562) (xy 386.723378 -301.574146) (xy 386.731421 -301.523364) (xy 386.747309 -301.474465)
			(xy 386.770652 -301.428653) (xy 386.800873 -301.387057) (xy 386.837229 -301.350701) (xy 386.878825 -301.32048)
			(xy 386.924637 -301.297137) (xy 386.973536 -301.281249) (xy 387.024318 -301.273206) (xy 387.075734 -301.273206)
			(xy 387.126516 -301.281249) (xy 387.175415 -301.297137) (xy 387.221227 -301.32048) (xy 387.262823 -301.350701)
			(xy 387.299179 -301.387057) (xy 387.3294 -301.428653) (xy 387.352743 -301.474465) (xy 387.368631 -301.523364)
			(xy 387.376674 -301.574146) (xy 387.377178 -301.599854) (xy 387.376674 -301.625562) (xy 387.673338 -301.625562)
			(xy 387.673338 -301.574146) (xy 387.681381 -301.523364) (xy 387.697269 -301.474465) (xy 387.720612 -301.428653)
			(xy 387.750833 -301.387057) (xy 387.787189 -301.350701) (xy 387.828785 -301.32048) (xy 387.874597 -301.297137)
			(xy 387.923496 -301.281249) (xy 387.974278 -301.273206) (xy 388.025694 -301.273206) (xy 388.076476 -301.281249)
			(xy 388.125375 -301.297137) (xy 388.171187 -301.32048) (xy 388.212783 -301.350701) (xy 388.249139 -301.387057)
			(xy 388.27936 -301.428653) (xy 388.302703 -301.474465) (xy 388.318591 -301.523364) (xy 388.326634 -301.574146)
			(xy 388.327138 -301.599854) (xy 388.644142 -301.599854) (xy 388.648102 -301.5508) (xy 388.659879 -301.503016)
			(xy 388.67917 -301.45774) (xy 388.705473 -301.416144) (xy 388.738108 -301.379307) (xy 388.776229 -301.348182)
			(xy 388.81885 -301.323575) (xy 388.864866 -301.306123) (xy 388.913085 -301.296279) (xy 388.96226 -301.294298)
			(xy 389.011115 -301.30023) (xy 389.058386 -301.313922) (xy 389.102848 -301.33502) (xy 389.143351 -301.362976)
			(xy 389.178844 -301.397068) (xy 389.208409 -301.436412) (xy 389.23128 -301.479989) (xy 389.246864 -301.52667)
			(xy 389.254759 -301.575247) (xy 389.255254 -301.599854) (xy 389.254759 -301.624461) (xy 389.25458 -301.625562)
			(xy 389.573258 -301.625562) (xy 389.573258 -301.574146) (xy 389.581301 -301.523364) (xy 389.597189 -301.474465)
			(xy 389.620532 -301.428653) (xy 389.650753 -301.387057) (xy 389.687109 -301.350701) (xy 389.728705 -301.32048)
			(xy 389.774517 -301.297137) (xy 389.823416 -301.281249) (xy 389.874198 -301.273206) (xy 389.925614 -301.273206)
			(xy 389.976396 -301.281249) (xy 390.025295 -301.297137) (xy 390.071107 -301.32048) (xy 390.112703 -301.350701)
			(xy 390.149059 -301.387057) (xy 390.17928 -301.428653) (xy 390.202623 -301.474465) (xy 390.218511 -301.523364)
			(xy 390.226554 -301.574146) (xy 390.227058 -301.599854) (xy 390.226554 -301.625562) (xy 390.523218 -301.625562)
			(xy 390.523218 -301.574146) (xy 390.531261 -301.523364) (xy 390.547149 -301.474465) (xy 390.570492 -301.428653)
			(xy 390.600713 -301.387057) (xy 390.637069 -301.350701) (xy 390.678665 -301.32048) (xy 390.724477 -301.297137)
			(xy 390.773376 -301.281249) (xy 390.824158 -301.273206) (xy 390.875574 -301.273206) (xy 390.926356 -301.281249)
			(xy 390.975255 -301.297137) (xy 391.021067 -301.32048) (xy 391.062663 -301.350701) (xy 391.099019 -301.387057)
			(xy 391.12924 -301.428653) (xy 391.152583 -301.474465) (xy 391.168471 -301.523364) (xy 391.176514 -301.574146)
			(xy 391.177018 -301.599854) (xy 391.494022 -301.599854) (xy 391.497982 -301.5508) (xy 391.509759 -301.503016)
			(xy 391.52905 -301.45774) (xy 391.555353 -301.416144) (xy 391.587988 -301.379307) (xy 391.626109 -301.348182)
			(xy 391.66873 -301.323575) (xy 391.714746 -301.306123) (xy 391.762965 -301.296279) (xy 391.81214 -301.294298)
			(xy 391.860995 -301.30023) (xy 391.908266 -301.313922) (xy 391.952728 -301.33502) (xy 391.993231 -301.362976)
			(xy 392.028724 -301.397068) (xy 392.058289 -301.436412) (xy 392.08116 -301.479989) (xy 392.096744 -301.52667)
			(xy 392.104639 -301.575247) (xy 392.104969 -301.591642) (xy 392.444034 -301.591642) (xy 392.449398 -301.542282)
			(xy 392.462678 -301.49444) (xy 392.483522 -301.449377) (xy 392.511382 -301.40828) (xy 392.545525 -301.372232)
			(xy 392.585049 -301.342183) (xy 392.628914 -301.318924) (xy 392.675965 -301.303068) (xy 392.724961 -301.295033)
			(xy 392.749786 -301.294546) (xy 392.764033 -301.294716) (xy 392.792401 -301.297383) (xy 392.806428 -301.29988)
			(xy 392.81862 -301.302166) (xy 392.84275 -301.2948) (xy 392.919966 -301.217584) (xy 392.927332 -301.193708)
			(xy 392.925046 -301.181262) (xy 392.922569 -301.167296) (xy 392.919897 -301.139057) (xy 392.919712 -301.124874)
			(xy 392.920234 -301.099619) (xy 392.928547 -301.049797) (xy 392.944948 -301.002023) (xy 392.968989 -300.9576)
			(xy 393.000013 -300.91774) (xy 393.037175 -300.88353) (xy 393.079461 -300.855904) (xy 393.125717 -300.835614)
			(xy 393.174682 -300.823214) (xy 393.22502 -300.819043) (xy 393.275358 -300.823214) (xy 393.324323 -300.835614)
			(xy 393.370579 -300.855904) (xy 393.412865 -300.88353) (xy 393.450027 -300.91774) (xy 393.481051 -300.9576)
			(xy 393.505092 -301.002023) (xy 393.521493 -301.049797) (xy 393.529806 -301.099619) (xy 393.530328 -301.124874)
			(xy 393.530147 -301.139057) (xy 393.527478 -301.167297) (xy 393.524994 -301.181262) (xy 393.522708 -301.193708)
			(xy 393.530074 -301.21733) (xy 393.607544 -301.2948) (xy 393.631166 -301.302166) (xy 393.643612 -301.29988)
			(xy 393.657578 -301.297406) (xy 393.685818 -301.294732) (xy 393.7 -301.294546) (xy 393.714183 -301.294723)
			(xy 393.742423 -301.297395) (xy 393.756388 -301.29988) (xy 393.768834 -301.302166) (xy 393.792456 -301.2948)
			(xy 393.869926 -301.21733) (xy 393.877292 -301.193708) (xy 393.875006 -301.181262) (xy 393.872528 -301.167296)
			(xy 393.869857 -301.139057) (xy 393.869672 -301.124874) (xy 393.870206 -301.100055) (xy 393.87824 -301.051073)
			(xy 393.894094 -301.004035) (xy 393.917348 -300.960182) (xy 393.94739 -300.920668) (xy 393.98343 -300.886536)
			(xy 394.024516 -300.858683) (xy 394.069567 -300.837845) (xy 394.117396 -300.824569) (xy 394.166743 -300.819206)
			(xy 394.216307 -300.821898) (xy 394.264783 -300.832572) (xy 394.310894 -300.850948) (xy 394.353424 -300.876542)
			(xy 394.391253 -300.90868) (xy 394.423385 -300.946514) (xy 394.448972 -300.989048) (xy 394.467342 -301.035161)
			(xy 394.478009 -301.083638) (xy 394.480241 -301.124874) (xy 394.819136 -301.124874) (xy 394.823096 -301.07582)
			(xy 394.834873 -301.028036) (xy 394.854164 -300.98276) (xy 394.880467 -300.941164) (xy 394.913102 -300.904327)
			(xy 394.951223 -300.873202) (xy 394.993844 -300.848595) (xy 395.03986 -300.831143) (xy 395.088079 -300.821299)
			(xy 395.137254 -300.819318) (xy 395.186109 -300.82525) (xy 395.23338 -300.838942) (xy 395.277842 -300.86004)
			(xy 395.318345 -300.887996) (xy 395.353838 -300.922088) (xy 395.383403 -300.961432) (xy 395.406274 -301.005009)
			(xy 395.421858 -301.05169) (xy 395.429753 -301.100267) (xy 395.430248 -301.124874) (xy 395.769096 -301.124874)
			(xy 395.773056 -301.07582) (xy 395.784833 -301.028036) (xy 395.804124 -300.98276) (xy 395.830427 -300.941164)
			(xy 395.863062 -300.904327) (xy 395.901183 -300.873202) (xy 395.943804 -300.848595) (xy 395.98982 -300.831143)
			(xy 396.038039 -300.821299) (xy 396.087214 -300.819318) (xy 396.136069 -300.82525) (xy 396.18334 -300.838942)
			(xy 396.227802 -300.86004) (xy 396.268305 -300.887996) (xy 396.303798 -300.922088) (xy 396.333363 -300.961432)
			(xy 396.356234 -301.005009) (xy 396.371818 -301.05169) (xy 396.379713 -301.100267) (xy 396.380208 -301.124874)
			(xy 396.379713 -301.149481) (xy 396.371818 -301.198058) (xy 396.356234 -301.244739) (xy 396.333363 -301.288316)
			(xy 396.303798 -301.32766) (xy 396.268305 -301.361752) (xy 396.227802 -301.389708) (xy 396.18334 -301.410806)
			(xy 396.136069 -301.424498) (xy 396.087214 -301.43043) (xy 396.038039 -301.428449) (xy 395.98982 -301.418605)
			(xy 395.943804 -301.401153) (xy 395.901183 -301.376546) (xy 395.863062 -301.345421) (xy 395.830427 -301.308584)
			(xy 395.804124 -301.266988) (xy 395.784833 -301.221712) (xy 395.773056 -301.173928) (xy 395.769096 -301.124874)
			(xy 395.430248 -301.124874) (xy 395.429753 -301.149481) (xy 395.421858 -301.198058) (xy 395.406274 -301.244739)
			(xy 395.383403 -301.288316) (xy 395.353838 -301.32766) (xy 395.318345 -301.361752) (xy 395.277842 -301.389708)
			(xy 395.23338 -301.410806) (xy 395.186109 -301.424498) (xy 395.137254 -301.43043) (xy 395.088079 -301.428449)
			(xy 395.03986 -301.418605) (xy 394.993844 -301.401153) (xy 394.951223 -301.376546) (xy 394.913102 -301.345421)
			(xy 394.880467 -301.308584) (xy 394.854164 -301.266988) (xy 394.834873 -301.221712) (xy 394.823096 -301.173928)
			(xy 394.819136 -301.124874) (xy 394.480241 -301.124874) (xy 394.480692 -301.133203) (xy 394.475322 -301.182549)
			(xy 394.462039 -301.230376) (xy 394.441194 -301.275424) (xy 394.413335 -301.316506) (xy 394.379197 -301.35254)
			(xy 394.339679 -301.382577) (xy 394.295823 -301.405825) (xy 394.248783 -301.421671) (xy 394.199799 -301.429698)
			(xy 394.17498 -301.430182) (xy 394.160797 -301.430009) (xy 394.132557 -301.427334) (xy 394.118592 -301.424848)
			(xy 394.106146 -301.422562) (xy 394.082524 -301.429928) (xy 394.005054 -301.507398) (xy 393.997688 -301.53102)
			(xy 393.999974 -301.543466) (xy 394.002455 -301.557431) (xy 394.005124 -301.585671) (xy 394.005308 -301.599854)
			(xy 394.005125 -301.614037) (xy 394.002457 -301.642277) (xy 393.999974 -301.656242) (xy 393.997688 -301.668688)
			(xy 394.005054 -301.69231) (xy 394.082524 -301.76978) (xy 394.106146 -301.777146) (xy 394.118592 -301.77486)
			(xy 394.132559 -301.772389) (xy 394.160798 -301.769714) (xy 394.17498 -301.769526) (xy 394.200242 -301.769949)
			(xy 394.250076 -301.778262) (xy 394.297863 -301.794665) (xy 394.342298 -301.818709) (xy 394.382169 -301.849739)
			(xy 394.416388 -301.886909) (xy 394.444023 -301.929205) (xy 394.464318 -301.975472) (xy 394.476722 -302.024449)
			(xy 394.480894 -302.0748) (xy 394.476722 -302.125151) (xy 394.464318 -302.174128) (xy 394.444023 -302.220395)
			(xy 394.416388 -302.262691) (xy 394.382169 -302.299861) (xy 394.342298 -302.330891) (xy 394.297863 -302.354935)
			(xy 394.250076 -302.371338) (xy 394.200242 -302.379651) (xy 394.17498 -302.380142) (xy 394.160797 -302.379968)
			(xy 394.132557 -302.377294) (xy 394.118592 -302.374808) (xy 394.106146 -302.372522) (xy 394.082524 -302.379888)
			(xy 394.005054 -302.457358) (xy 393.997688 -302.48098) (xy 393.999974 -302.493426) (xy 394.00245 -302.507392)
			(xy 394.005122 -302.535631) (xy 394.005308 -302.549814) (xy 394.005133 -302.563997) (xy 394.00246 -302.592237)
			(xy 393.999974 -302.606202) (xy 393.997688 -302.618648) (xy 394.005054 -302.64227) (xy 394.082524 -302.71974)
			(xy 394.106146 -302.727106) (xy 394.118592 -302.72482) (xy 394.132559 -302.722349) (xy 394.160798 -302.719673)
			(xy 394.17498 -302.719486) (xy 394.200238 -302.719989) (xy 394.250066 -302.728301) (xy 394.297847 -302.744701)
			(xy 394.342276 -302.768742) (xy 394.382142 -302.799769) (xy 394.416357 -302.836934) (xy 394.443988 -302.879224)
			(xy 394.464281 -302.925485) (xy 394.476682 -302.974456) (xy 394.480854 -303.024794) (xy 394.819136 -303.024794)
			(xy 394.823096 -302.97574) (xy 394.834873 -302.927956) (xy 394.854164 -302.88268) (xy 394.880467 -302.841084)
			(xy 394.913102 -302.804247) (xy 394.951223 -302.773122) (xy 394.993844 -302.748515) (xy 395.03986 -302.731063)
			(xy 395.088079 -302.721219) (xy 395.137254 -302.719238) (xy 395.186109 -302.72517) (xy 395.23338 -302.738862)
			(xy 395.277842 -302.75996) (xy 395.318345 -302.787916) (xy 395.353838 -302.822008) (xy 395.383403 -302.861352)
			(xy 395.406274 -302.904929) (xy 395.421858 -302.95161) (xy 395.429753 -303.000187) (xy 395.430248 -303.024794)
			(xy 395.769096 -303.024794) (xy 395.773056 -302.97574) (xy 395.784833 -302.927956) (xy 395.804124 -302.88268)
			(xy 395.830427 -302.841084) (xy 395.863062 -302.804247) (xy 395.901183 -302.773122) (xy 395.943804 -302.748515)
			(xy 395.98982 -302.731063) (xy 396.038039 -302.721219) (xy 396.087214 -302.719238) (xy 396.136069 -302.72517)
			(xy 396.18334 -302.738862) (xy 396.227802 -302.75996) (xy 396.268305 -302.787916) (xy 396.303798 -302.822008)
			(xy 396.333363 -302.861352) (xy 396.356234 -302.904929) (xy 396.371818 -302.95161) (xy 396.379713 -303.000187)
			(xy 396.380208 -303.024794) (xy 396.719056 -303.024794) (xy 396.723016 -302.97574) (xy 396.734793 -302.927956)
			(xy 396.754084 -302.88268) (xy 396.780387 -302.841084) (xy 396.813022 -302.804247) (xy 396.851143 -302.773122)
			(xy 396.893764 -302.748515) (xy 396.93978 -302.731063) (xy 396.987999 -302.721219) (xy 397.037174 -302.719238)
			(xy 397.086029 -302.72517) (xy 397.1333 -302.738862) (xy 397.177762 -302.75996) (xy 397.218265 -302.787916)
			(xy 397.253758 -302.822008) (xy 397.283323 -302.861352) (xy 397.306194 -302.904929) (xy 397.321778 -302.95161)
			(xy 397.329673 -303.000187) (xy 397.330168 -303.024794) (xy 397.329673 -303.049401) (xy 397.321778 -303.097978)
			(xy 397.306194 -303.144659) (xy 397.283323 -303.188236) (xy 397.253758 -303.22758) (xy 397.218265 -303.261672)
			(xy 397.177762 -303.289628) (xy 397.1333 -303.310726) (xy 397.086029 -303.324418) (xy 397.037174 -303.33035)
			(xy 396.987999 -303.328369) (xy 396.93978 -303.318525) (xy 396.893764 -303.301073) (xy 396.851143 -303.276466)
			(xy 396.813022 -303.245341) (xy 396.780387 -303.208504) (xy 396.754084 -303.166908) (xy 396.734793 -303.121632)
			(xy 396.723016 -303.073848) (xy 396.719056 -303.024794) (xy 396.380208 -303.024794) (xy 396.379713 -303.049401)
			(xy 396.371818 -303.097978) (xy 396.356234 -303.144659) (xy 396.333363 -303.188236) (xy 396.303798 -303.22758)
			(xy 396.268305 -303.261672) (xy 396.227802 -303.289628) (xy 396.18334 -303.310726) (xy 396.136069 -303.324418)
			(xy 396.087214 -303.33035) (xy 396.038039 -303.328369) (xy 395.98982 -303.318525) (xy 395.943804 -303.301073)
			(xy 395.901183 -303.276466) (xy 395.863062 -303.245341) (xy 395.830427 -303.208504) (xy 395.804124 -303.166908)
			(xy 395.784833 -303.121632) (xy 395.773056 -303.073848) (xy 395.769096 -303.024794) (xy 395.430248 -303.024794)
			(xy 395.429753 -303.049401) (xy 395.421858 -303.097978) (xy 395.406274 -303.144659) (xy 395.383403 -303.188236)
			(xy 395.353838 -303.22758) (xy 395.318345 -303.261672) (xy 395.277842 -303.289628) (xy 395.23338 -303.310726)
			(xy 395.186109 -303.324418) (xy 395.137254 -303.33035) (xy 395.088079 -303.328369) (xy 395.03986 -303.318525)
			(xy 394.993844 -303.301073) (xy 394.951223 -303.276466) (xy 394.913102 -303.245341) (xy 394.880467 -303.208504)
			(xy 394.854164 -303.166908) (xy 394.834873 -303.121632) (xy 394.823096 -303.073848) (xy 394.819136 -303.024794)
			(xy 394.480854 -303.024794) (xy 394.480854 -303.0248) (xy 394.476682 -303.075144) (xy 394.464281 -303.124115)
			(xy 394.443988 -303.170376) (xy 394.416357 -303.212666) (xy 394.382142 -303.249831) (xy 394.342276 -303.280858)
			(xy 394.297847 -303.304899) (xy 394.250066 -303.321299) (xy 394.200238 -303.329611) (xy 394.17498 -303.330102)
			(xy 394.160797 -303.329928) (xy 394.132557 -303.327254) (xy 394.118592 -303.324768) (xy 394.106146 -303.322482)
			(xy 394.082524 -303.329848) (xy 394.005054 -303.407318) (xy 393.997688 -303.43094) (xy 393.999974 -303.443386)
			(xy 394.002444 -303.457353) (xy 394.00512 -303.485592) (xy 394.005308 -303.499774) (xy 394.00485 -303.524597)
			(xy 393.996822 -303.573591) (xy 393.980974 -303.62064) (xy 393.957722 -303.664505) (xy 393.92768 -303.704031)
			(xy 393.891639 -303.738176) (xy 393.850549 -303.76604) (xy 393.805492 -303.786889) (xy 393.757655 -303.800174)
			(xy 393.7083 -303.805544) (xy 393.658726 -303.802859) (xy 393.610239 -303.792189) (xy 393.564117 -303.773815)
			(xy 393.521576 -303.748222) (xy 393.483736 -303.716083) (xy 393.451593 -303.678245) (xy 393.425996 -303.635706)
			(xy 393.407618 -303.589586) (xy 393.396944 -303.5411) (xy 393.394255 -303.491526) (xy 393.399621 -303.44217)
			(xy 393.412902 -303.394333) (xy 393.433747 -303.349274) (xy 393.461608 -303.308181) (xy 393.495749 -303.272138)
			(xy 393.535273 -303.242092) (xy 393.579136 -303.218837) (xy 393.626184 -303.202984) (xy 393.675177 -303.194952)
			(xy 393.7 -303.194466) (xy 393.714183 -303.194643) (xy 393.742423 -303.197315) (xy 393.756388 -303.1998)
			(xy 393.768834 -303.202086) (xy 393.792456 -303.19472) (xy 393.869926 -303.11725) (xy 393.877292 -303.093628)
			(xy 393.875006 -303.081182) (xy 393.872531 -303.067216) (xy 393.869858 -303.038976) (xy 393.869672 -303.024794)
			(xy 393.869848 -303.010611) (xy 393.872521 -302.982371) (xy 393.875006 -302.968406) (xy 393.877292 -302.95596)
			(xy 393.869926 -302.932338) (xy 393.792456 -302.854868) (xy 393.768834 -302.847502) (xy 393.756388 -302.849788)
			(xy 393.742422 -302.852262) (xy 393.714182 -302.854935) (xy 393.7 -302.855122) (xy 393.674746 -302.854572)
			(xy 393.624926 -302.846259) (xy 393.577155 -302.829859) (xy 393.532734 -302.80582) (xy 393.492876 -302.774797)
			(xy 393.458667 -302.737637) (xy 393.431042 -302.695353) (xy 393.410753 -302.649099) (xy 393.398354 -302.600136)
			(xy 393.394183 -302.5498) (xy 393.398354 -302.499464) (xy 393.410753 -302.450501) (xy 393.431042 -302.404247)
			(xy 393.458667 -302.361963) (xy 393.492876 -302.324803) (xy 393.532734 -302.29378) (xy 393.577155 -302.269741)
			(xy 393.624926 -302.253341) (xy 393.674746 -302.245028) (xy 393.7 -302.244506) (xy 393.714183 -302.244682)
			(xy 393.742423 -302.247355) (xy 393.756388 -302.24984) (xy 393.768834 -302.252126) (xy 393.792456 -302.24476)
			(xy 393.869926 -302.16729) (xy 393.877292 -302.143668) (xy 393.875006 -302.131222) (xy 393.872523 -302.117257)
			(xy 393.869855 -302.089017) (xy 393.869672 -302.074834) (xy 393.869854 -302.060651) (xy 393.872522 -302.032411)
			(xy 393.875006 -302.018446) (xy 393.877292 -302.006) (xy 393.869926 -301.982378) (xy 393.792456 -301.904908)
			(xy 393.768834 -301.897542) (xy 393.756388 -301.899828) (xy 393.742422 -301.902302) (xy 393.714182 -301.904976)
			(xy 393.7 -301.905162) (xy 393.676005 -301.904762) (xy 393.628605 -301.897253) (xy 393.582963 -301.882422)
			(xy 393.540204 -301.860633) (xy 393.50138 -301.832422) (xy 393.467448 -301.798485) (xy 393.439243 -301.759657)
			(xy 393.41746 -301.716894) (xy 393.402636 -301.671251) (xy 393.395135 -301.62385) (xy 393.394692 -301.599854)
			(xy 393.394876 -301.585671) (xy 393.397543 -301.557431) (xy 393.400026 -301.543466) (xy 393.402312 -301.53102)
			(xy 393.394946 -301.507398) (xy 393.317476 -301.429928) (xy 393.293854 -301.422562) (xy 393.281408 -301.424848)
			(xy 393.267441 -301.427319) (xy 393.239202 -301.429995) (xy 393.22502 -301.430182) (xy 393.210773 -301.43002)
			(xy 393.182405 -301.427344) (xy 393.168378 -301.424848) (xy 393.156186 -301.422562) (xy 393.132056 -301.429928)
			(xy 393.05484 -301.507144) (xy 393.047474 -301.53102) (xy 393.04976 -301.543466) (xy 393.052241 -301.557431)
			(xy 393.05491 -301.585671) (xy 393.055094 -301.599854) (xy 393.054672 -301.624679) (xy 393.046647 -301.673677)
			(xy 393.0308 -301.72073) (xy 393.00755 -301.7646) (xy 392.977508 -301.804131) (xy 392.941466 -301.83828)
			(xy 392.900375 -301.866148) (xy 392.855316 -301.887002) (xy 392.807477 -301.90029) (xy 392.758119 -301.905664)
			(xy 392.708541 -301.902982) (xy 392.66005 -301.892314) (xy 392.613924 -301.873942) (xy 392.571378 -301.848348)
			(xy 392.533533 -301.816209) (xy 392.501387 -301.778371) (xy 392.475785 -301.73583) (xy 392.457404 -301.689708)
			(xy 392.446726 -301.641219) (xy 392.444034 -301.591642) (xy 392.104969 -301.591642) (xy 392.105134 -301.599854)
			(xy 392.104639 -301.624461) (xy 392.096744 -301.673038) (xy 392.08116 -301.719719) (xy 392.058289 -301.763296)
			(xy 392.028724 -301.80264) (xy 391.993231 -301.836732) (xy 391.952728 -301.864688) (xy 391.908266 -301.885786)
			(xy 391.860995 -301.899478) (xy 391.81214 -301.90541) (xy 391.762965 -301.903429) (xy 391.714746 -301.893585)
			(xy 391.66873 -301.876133) (xy 391.626109 -301.851526) (xy 391.587988 -301.820401) (xy 391.555353 -301.783564)
			(xy 391.52905 -301.741968) (xy 391.509759 -301.696692) (xy 391.497982 -301.648908) (xy 391.494022 -301.599854)
			(xy 391.177018 -301.599854) (xy 391.176514 -301.625562) (xy 391.168471 -301.676344) (xy 391.152583 -301.725243)
			(xy 391.12924 -301.771055) (xy 391.099019 -301.812651) (xy 391.062663 -301.849007) (xy 391.021067 -301.879228)
			(xy 390.975255 -301.902571) (xy 390.926356 -301.918459) (xy 390.875574 -301.926502) (xy 390.824158 -301.926502)
			(xy 390.773376 -301.918459) (xy 390.724477 -301.902571) (xy 390.678665 -301.879228) (xy 390.637069 -301.849007)
			(xy 390.600713 -301.812651) (xy 390.570492 -301.771055) (xy 390.547149 -301.725243) (xy 390.531261 -301.676344)
			(xy 390.523218 -301.625562) (xy 390.226554 -301.625562) (xy 390.218511 -301.676344) (xy 390.202623 -301.725243)
			(xy 390.17928 -301.771055) (xy 390.149059 -301.812651) (xy 390.112703 -301.849007) (xy 390.071107 -301.879228)
			(xy 390.025295 -301.902571) (xy 389.976396 -301.918459) (xy 389.925614 -301.926502) (xy 389.874198 -301.926502)
			(xy 389.823416 -301.918459) (xy 389.774517 -301.902571) (xy 389.728705 -301.879228) (xy 389.687109 -301.849007)
			(xy 389.650753 -301.812651) (xy 389.620532 -301.771055) (xy 389.597189 -301.725243) (xy 389.581301 -301.676344)
			(xy 389.573258 -301.625562) (xy 389.25458 -301.625562) (xy 389.246864 -301.673038) (xy 389.23128 -301.719719)
			(xy 389.208409 -301.763296) (xy 389.178844 -301.80264) (xy 389.143351 -301.836732) (xy 389.102848 -301.864688)
			(xy 389.058386 -301.885786) (xy 389.011115 -301.899478) (xy 388.96226 -301.90541) (xy 388.913085 -301.903429)
			(xy 388.864866 -301.893585) (xy 388.81885 -301.876133) (xy 388.776229 -301.851526) (xy 388.738108 -301.820401)
			(xy 388.705473 -301.783564) (xy 388.67917 -301.741968) (xy 388.659879 -301.696692) (xy 388.648102 -301.648908)
			(xy 388.644142 -301.599854) (xy 388.327138 -301.599854) (xy 388.326634 -301.625562) (xy 388.318591 -301.676344)
			(xy 388.302703 -301.725243) (xy 388.27936 -301.771055) (xy 388.249139 -301.812651) (xy 388.212783 -301.849007)
			(xy 388.171187 -301.879228) (xy 388.125375 -301.902571) (xy 388.076476 -301.918459) (xy 388.025694 -301.926502)
			(xy 387.974278 -301.926502) (xy 387.923496 -301.918459) (xy 387.874597 -301.902571) (xy 387.828785 -301.879228)
			(xy 387.787189 -301.849007) (xy 387.750833 -301.812651) (xy 387.720612 -301.771055) (xy 387.697269 -301.725243)
			(xy 387.681381 -301.676344) (xy 387.673338 -301.625562) (xy 387.376674 -301.625562) (xy 387.368631 -301.676344)
			(xy 387.352743 -301.725243) (xy 387.3294 -301.771055) (xy 387.299179 -301.812651) (xy 387.262823 -301.849007)
			(xy 387.221227 -301.879228) (xy 387.175415 -301.902571) (xy 387.126516 -301.918459) (xy 387.075734 -301.926502)
			(xy 387.024318 -301.926502) (xy 386.973536 -301.918459) (xy 386.924637 -301.902571) (xy 386.878825 -301.879228)
			(xy 386.837229 -301.849007) (xy 386.800873 -301.812651) (xy 386.770652 -301.771055) (xy 386.747309 -301.725243)
			(xy 386.731421 -301.676344) (xy 386.723378 -301.625562) (xy 386.404446 -301.625562) (xy 386.39673 -301.673038)
			(xy 386.381146 -301.719719) (xy 386.358275 -301.763296) (xy 386.32871 -301.80264) (xy 386.293217 -301.836732)
			(xy 386.252714 -301.864688) (xy 386.208252 -301.885786) (xy 386.160981 -301.899478) (xy 386.112126 -301.90541)
			(xy 386.062951 -301.903429) (xy 386.014732 -301.893585) (xy 385.968716 -301.876133) (xy 385.926095 -301.851526)
			(xy 385.887974 -301.820401) (xy 385.855339 -301.783564) (xy 385.829036 -301.741968) (xy 385.809745 -301.696692)
			(xy 385.797968 -301.648908) (xy 385.794008 -301.599854) (xy 385.45516 -301.599854) (xy 385.454665 -301.624461)
			(xy 385.44677 -301.673038) (xy 385.431186 -301.719719) (xy 385.408315 -301.763296) (xy 385.37875 -301.80264)
			(xy 385.343257 -301.836732) (xy 385.302754 -301.864688) (xy 385.258292 -301.885786) (xy 385.211021 -301.899478)
			(xy 385.162166 -301.90541) (xy 385.112991 -301.903429) (xy 385.064772 -301.893585) (xy 385.018756 -301.876133)
			(xy 384.976135 -301.851526) (xy 384.938014 -301.820401) (xy 384.905379 -301.783564) (xy 384.879076 -301.741968)
			(xy 384.859785 -301.696692) (xy 384.848008 -301.648908) (xy 384.844048 -301.599854) (xy 351.031048 -301.599854)
			(xy 351.031048 -302.550068) (xy 383.893834 -302.550068) (xy 383.897794 -302.501014) (xy 383.909571 -302.45323)
			(xy 383.928862 -302.407954) (xy 383.955165 -302.366358) (xy 383.9878 -302.329521) (xy 384.025921 -302.298396)
			(xy 384.068542 -302.273789) (xy 384.114558 -302.256337) (xy 384.162777 -302.246493) (xy 384.211952 -302.244512)
			(xy 384.260807 -302.250444) (xy 384.308078 -302.264136) (xy 384.35254 -302.285234) (xy 384.393043 -302.31319)
			(xy 384.428536 -302.347282) (xy 384.458101 -302.386626) (xy 384.480972 -302.430203) (xy 384.496556 -302.476884)
			(xy 384.504451 -302.525461) (xy 384.504946 -302.550068) (xy 384.504451 -302.574675) (xy 384.504313 -302.575522)
			(xy 384.823204 -302.575522) (xy 384.823204 -302.524106) (xy 384.831247 -302.473324) (xy 384.847135 -302.424425)
			(xy 384.870478 -302.378613) (xy 384.900699 -302.337017) (xy 384.937055 -302.300661) (xy 384.978651 -302.27044)
			(xy 385.024463 -302.247097) (xy 385.073362 -302.231209) (xy 385.124144 -302.223166) (xy 385.17556 -302.223166)
			(xy 385.226342 -302.231209) (xy 385.275241 -302.247097) (xy 385.321053 -302.27044) (xy 385.362649 -302.300661)
			(xy 385.399005 -302.337017) (xy 385.429226 -302.378613) (xy 385.452569 -302.424425) (xy 385.468457 -302.473324)
			(xy 385.4765 -302.524106) (xy 385.477004 -302.549814) (xy 385.4765 -302.575522) (xy 385.773164 -302.575522)
			(xy 385.773164 -302.524106) (xy 385.781207 -302.473324) (xy 385.797095 -302.424425) (xy 385.820438 -302.378613)
			(xy 385.850659 -302.337017) (xy 385.887015 -302.300661) (xy 385.928611 -302.27044) (xy 385.974423 -302.247097)
			(xy 386.023322 -302.231209) (xy 386.074104 -302.223166) (xy 386.12552 -302.223166) (xy 386.176302 -302.231209)
			(xy 386.225201 -302.247097) (xy 386.271013 -302.27044) (xy 386.312609 -302.300661) (xy 386.348965 -302.337017)
			(xy 386.379186 -302.378613) (xy 386.402529 -302.424425) (xy 386.418417 -302.473324) (xy 386.42646 -302.524106)
			(xy 386.426964 -302.549814) (xy 386.744222 -302.549814) (xy 386.748182 -302.50076) (xy 386.759959 -302.452976)
			(xy 386.77925 -302.4077) (xy 386.805553 -302.366104) (xy 386.838188 -302.329267) (xy 386.876309 -302.298142)
			(xy 386.91893 -302.273535) (xy 386.964946 -302.256083) (xy 387.013165 -302.246239) (xy 387.06234 -302.244258)
			(xy 387.111195 -302.25019) (xy 387.158466 -302.263882) (xy 387.202928 -302.28498) (xy 387.243431 -302.312936)
			(xy 387.278924 -302.347028) (xy 387.308489 -302.386372) (xy 387.33136 -302.429949) (xy 387.346944 -302.47663)
			(xy 387.354839 -302.525207) (xy 387.355334 -302.549814) (xy 387.694182 -302.549814) (xy 387.698142 -302.50076)
			(xy 387.709919 -302.452976) (xy 387.72921 -302.4077) (xy 387.755513 -302.366104) (xy 387.788148 -302.329267)
			(xy 387.826269 -302.298142) (xy 387.86889 -302.273535) (xy 387.914906 -302.256083) (xy 387.963125 -302.246239)
			(xy 388.0123 -302.244258) (xy 388.061155 -302.25019) (xy 388.108426 -302.263882) (xy 388.152888 -302.28498)
			(xy 388.193391 -302.312936) (xy 388.228884 -302.347028) (xy 388.258449 -302.386372) (xy 388.28132 -302.429949)
			(xy 388.296904 -302.47663) (xy 388.304799 -302.525207) (xy 388.305294 -302.549814) (xy 388.644142 -302.549814)
			(xy 388.648102 -302.50076) (xy 388.659879 -302.452976) (xy 388.67917 -302.4077) (xy 388.705473 -302.366104)
			(xy 388.738108 -302.329267) (xy 388.776229 -302.298142) (xy 388.81885 -302.273535) (xy 388.864866 -302.256083)
			(xy 388.913085 -302.246239) (xy 388.96226 -302.244258) (xy 389.011115 -302.25019) (xy 389.058386 -302.263882)
			(xy 389.102848 -302.28498) (xy 389.143351 -302.312936) (xy 389.178844 -302.347028) (xy 389.208409 -302.386372)
			(xy 389.23128 -302.429949) (xy 389.246864 -302.47663) (xy 389.254759 -302.525207) (xy 389.255254 -302.549814)
			(xy 389.594102 -302.549814) (xy 389.598062 -302.50076) (xy 389.609839 -302.452976) (xy 389.62913 -302.4077)
			(xy 389.655433 -302.366104) (xy 389.688068 -302.329267) (xy 389.726189 -302.298142) (xy 389.76881 -302.273535)
			(xy 389.814826 -302.256083) (xy 389.863045 -302.246239) (xy 389.91222 -302.244258) (xy 389.961075 -302.25019)
			(xy 390.008346 -302.263882) (xy 390.052808 -302.28498) (xy 390.093311 -302.312936) (xy 390.128804 -302.347028)
			(xy 390.158369 -302.386372) (xy 390.18124 -302.429949) (xy 390.196824 -302.47663) (xy 390.204719 -302.525207)
			(xy 390.205214 -302.549814) (xy 390.544062 -302.549814) (xy 390.548022 -302.50076) (xy 390.559799 -302.452976)
			(xy 390.57909 -302.4077) (xy 390.605393 -302.366104) (xy 390.638028 -302.329267) (xy 390.676149 -302.298142)
			(xy 390.71877 -302.273535) (xy 390.764786 -302.256083) (xy 390.813005 -302.246239) (xy 390.86218 -302.244258)
			(xy 390.911035 -302.25019) (xy 390.958306 -302.263882) (xy 391.002768 -302.28498) (xy 391.043271 -302.312936)
			(xy 391.078764 -302.347028) (xy 391.108329 -302.386372) (xy 391.1312 -302.429949) (xy 391.146784 -302.47663)
			(xy 391.154679 -302.525207) (xy 391.155174 -302.549814) (xy 391.154679 -302.574421) (xy 391.1545 -302.575522)
			(xy 391.473178 -302.575522) (xy 391.473178 -302.524106) (xy 391.481221 -302.473324) (xy 391.497109 -302.424425)
			(xy 391.520452 -302.378613) (xy 391.550673 -302.337017) (xy 391.587029 -302.300661) (xy 391.628625 -302.27044)
			(xy 391.674437 -302.247097) (xy 391.723336 -302.231209) (xy 391.774118 -302.223166) (xy 391.825534 -302.223166)
			(xy 391.876316 -302.231209) (xy 391.925215 -302.247097) (xy 391.971027 -302.27044) (xy 392.012623 -302.300661)
			(xy 392.048979 -302.337017) (xy 392.0792 -302.378613) (xy 392.102543 -302.424425) (xy 392.118431 -302.473324)
			(xy 392.126474 -302.524106) (xy 392.126978 -302.549814) (xy 392.126474 -302.575522) (xy 392.423138 -302.575522)
			(xy 392.423138 -302.524106) (xy 392.431181 -302.473324) (xy 392.447069 -302.424425) (xy 392.470412 -302.378613)
			(xy 392.500633 -302.337017) (xy 392.536989 -302.300661) (xy 392.578585 -302.27044) (xy 392.624397 -302.247097)
			(xy 392.673296 -302.231209) (xy 392.724078 -302.223166) (xy 392.775494 -302.223166) (xy 392.826276 -302.231209)
			(xy 392.875175 -302.247097) (xy 392.920987 -302.27044) (xy 392.962583 -302.300661) (xy 392.998939 -302.337017)
			(xy 393.02916 -302.378613) (xy 393.052503 -302.424425) (xy 393.068391 -302.473324) (xy 393.076434 -302.524106)
			(xy 393.076938 -302.549814) (xy 393.076434 -302.575522) (xy 393.068391 -302.626304) (xy 393.052503 -302.675203)
			(xy 393.02916 -302.721015) (xy 392.998939 -302.762611) (xy 392.962583 -302.798967) (xy 392.920987 -302.829188)
			(xy 392.875175 -302.852531) (xy 392.826276 -302.868419) (xy 392.775494 -302.876462) (xy 392.724078 -302.876462)
			(xy 392.673296 -302.868419) (xy 392.624397 -302.852531) (xy 392.578585 -302.829188) (xy 392.536989 -302.798967)
			(xy 392.500633 -302.762611) (xy 392.470412 -302.721015) (xy 392.447069 -302.675203) (xy 392.431181 -302.626304)
			(xy 392.423138 -302.575522) (xy 392.126474 -302.575522) (xy 392.118431 -302.626304) (xy 392.102543 -302.675203)
			(xy 392.0792 -302.721015) (xy 392.048979 -302.762611) (xy 392.012623 -302.798967) (xy 391.971027 -302.829188)
			(xy 391.925215 -302.852531) (xy 391.876316 -302.868419) (xy 391.825534 -302.876462) (xy 391.774118 -302.876462)
			(xy 391.723336 -302.868419) (xy 391.674437 -302.852531) (xy 391.628625 -302.829188) (xy 391.587029 -302.798967)
			(xy 391.550673 -302.762611) (xy 391.520452 -302.721015) (xy 391.497109 -302.675203) (xy 391.481221 -302.626304)
			(xy 391.473178 -302.575522) (xy 391.1545 -302.575522) (xy 391.146784 -302.622998) (xy 391.1312 -302.669679)
			(xy 391.108329 -302.713256) (xy 391.078764 -302.7526) (xy 391.043271 -302.786692) (xy 391.002768 -302.814648)
			(xy 390.958306 -302.835746) (xy 390.911035 -302.849438) (xy 390.86218 -302.85537) (xy 390.813005 -302.853389)
			(xy 390.764786 -302.843545) (xy 390.71877 -302.826093) (xy 390.676149 -302.801486) (xy 390.638028 -302.770361)
			(xy 390.605393 -302.733524) (xy 390.57909 -302.691928) (xy 390.559799 -302.646652) (xy 390.548022 -302.598868)
			(xy 390.544062 -302.549814) (xy 390.205214 -302.549814) (xy 390.204719 -302.574421) (xy 390.196824 -302.622998)
			(xy 390.18124 -302.669679) (xy 390.158369 -302.713256) (xy 390.128804 -302.7526) (xy 390.093311 -302.786692)
			(xy 390.052808 -302.814648) (xy 390.008346 -302.835746) (xy 389.961075 -302.849438) (xy 389.91222 -302.85537)
			(xy 389.863045 -302.853389) (xy 389.814826 -302.843545) (xy 389.76881 -302.826093) (xy 389.726189 -302.801486)
			(xy 389.688068 -302.770361) (xy 389.655433 -302.733524) (xy 389.62913 -302.691928) (xy 389.609839 -302.646652)
			(xy 389.598062 -302.598868) (xy 389.594102 -302.549814) (xy 389.255254 -302.549814) (xy 389.254759 -302.574421)
			(xy 389.246864 -302.622998) (xy 389.23128 -302.669679) (xy 389.208409 -302.713256) (xy 389.178844 -302.7526)
			(xy 389.143351 -302.786692) (xy 389.102848 -302.814648) (xy 389.058386 -302.835746) (xy 389.011115 -302.849438)
			(xy 388.96226 -302.85537) (xy 388.913085 -302.853389) (xy 388.864866 -302.843545) (xy 388.81885 -302.826093)
			(xy 388.776229 -302.801486) (xy 388.738108 -302.770361) (xy 388.705473 -302.733524) (xy 388.67917 -302.691928)
			(xy 388.659879 -302.646652) (xy 388.648102 -302.598868) (xy 388.644142 -302.549814) (xy 388.305294 -302.549814)
			(xy 388.304799 -302.574421) (xy 388.296904 -302.622998) (xy 388.28132 -302.669679) (xy 388.258449 -302.713256)
			(xy 388.228884 -302.7526) (xy 388.193391 -302.786692) (xy 388.152888 -302.814648) (xy 388.108426 -302.835746)
			(xy 388.061155 -302.849438) (xy 388.0123 -302.85537) (xy 387.963125 -302.853389) (xy 387.914906 -302.843545)
			(xy 387.86889 -302.826093) (xy 387.826269 -302.801486) (xy 387.788148 -302.770361) (xy 387.755513 -302.733524)
			(xy 387.72921 -302.691928) (xy 387.709919 -302.646652) (xy 387.698142 -302.598868) (xy 387.694182 -302.549814)
			(xy 387.355334 -302.549814) (xy 387.354839 -302.574421) (xy 387.346944 -302.622998) (xy 387.33136 -302.669679)
			(xy 387.308489 -302.713256) (xy 387.278924 -302.7526) (xy 387.243431 -302.786692) (xy 387.202928 -302.814648)
			(xy 387.158466 -302.835746) (xy 387.111195 -302.849438) (xy 387.06234 -302.85537) (xy 387.013165 -302.853389)
			(xy 386.964946 -302.843545) (xy 386.91893 -302.826093) (xy 386.876309 -302.801486) (xy 386.838188 -302.770361)
			(xy 386.805553 -302.733524) (xy 386.77925 -302.691928) (xy 386.759959 -302.646652) (xy 386.748182 -302.598868)
			(xy 386.744222 -302.549814) (xy 386.426964 -302.549814) (xy 386.42646 -302.575522) (xy 386.418417 -302.626304)
			(xy 386.402529 -302.675203) (xy 386.379186 -302.721015) (xy 386.348965 -302.762611) (xy 386.312609 -302.798967)
			(xy 386.271013 -302.829188) (xy 386.225201 -302.852531) (xy 386.176302 -302.868419) (xy 386.12552 -302.876462)
			(xy 386.074104 -302.876462) (xy 386.023322 -302.868419) (xy 385.974423 -302.852531) (xy 385.928611 -302.829188)
			(xy 385.887015 -302.798967) (xy 385.850659 -302.762611) (xy 385.820438 -302.721015) (xy 385.797095 -302.675203)
			(xy 385.781207 -302.626304) (xy 385.773164 -302.575522) (xy 385.4765 -302.575522) (xy 385.468457 -302.626304)
			(xy 385.452569 -302.675203) (xy 385.429226 -302.721015) (xy 385.399005 -302.762611) (xy 385.362649 -302.798967)
			(xy 385.321053 -302.829188) (xy 385.275241 -302.852531) (xy 385.226342 -302.868419) (xy 385.17556 -302.876462)
			(xy 385.124144 -302.876462) (xy 385.073362 -302.868419) (xy 385.024463 -302.852531) (xy 384.978651 -302.829188)
			(xy 384.937055 -302.798967) (xy 384.900699 -302.762611) (xy 384.870478 -302.721015) (xy 384.847135 -302.675203)
			(xy 384.831247 -302.626304) (xy 384.823204 -302.575522) (xy 384.504313 -302.575522) (xy 384.496556 -302.623252)
			(xy 384.480972 -302.669933) (xy 384.458101 -302.71351) (xy 384.428536 -302.752854) (xy 384.393043 -302.786946)
			(xy 384.35254 -302.814902) (xy 384.308078 -302.836) (xy 384.260807 -302.849692) (xy 384.211952 -302.855624)
			(xy 384.162777 -302.853643) (xy 384.114558 -302.843799) (xy 384.068542 -302.826347) (xy 384.025921 -302.80174)
			(xy 383.9878 -302.770615) (xy 383.955165 -302.733778) (xy 383.928862 -302.692182) (xy 383.909571 -302.646906)
			(xy 383.897794 -302.599122) (xy 383.893834 -302.550068) (xy 351.031048 -302.550068) (xy 351.031048 -303.499774)
			(xy 384.844048 -303.499774) (xy 384.848008 -303.45072) (xy 384.859785 -303.402936) (xy 384.879076 -303.35766)
			(xy 384.905379 -303.316064) (xy 384.938014 -303.279227) (xy 384.976135 -303.248102) (xy 385.018756 -303.223495)
			(xy 385.064772 -303.206043) (xy 385.112991 -303.196199) (xy 385.162166 -303.194218) (xy 385.211021 -303.20015)
			(xy 385.258292 -303.213842) (xy 385.302754 -303.23494) (xy 385.343257 -303.262896) (xy 385.37875 -303.296988)
			(xy 385.408315 -303.336332) (xy 385.431186 -303.379909) (xy 385.44677 -303.42659) (xy 385.454665 -303.475167)
			(xy 385.45516 -303.499774) (xy 385.794008 -303.499774) (xy 385.797968 -303.45072) (xy 385.809745 -303.402936)
			(xy 385.829036 -303.35766) (xy 385.855339 -303.316064) (xy 385.887974 -303.279227) (xy 385.926095 -303.248102)
			(xy 385.968716 -303.223495) (xy 386.014732 -303.206043) (xy 386.062951 -303.196199) (xy 386.112126 -303.194218)
			(xy 386.160981 -303.20015) (xy 386.208252 -303.213842) (xy 386.252714 -303.23494) (xy 386.293217 -303.262896)
			(xy 386.32871 -303.296988) (xy 386.358275 -303.336332) (xy 386.381146 -303.379909) (xy 386.39673 -303.42659)
			(xy 386.404625 -303.475167) (xy 386.40512 -303.499774) (xy 386.404625 -303.524381) (xy 386.404446 -303.525482)
			(xy 386.723378 -303.525482) (xy 386.723378 -303.474066) (xy 386.731421 -303.423284) (xy 386.747309 -303.374385)
			(xy 386.770652 -303.328573) (xy 386.800873 -303.286977) (xy 386.837229 -303.250621) (xy 386.878825 -303.2204)
			(xy 386.924637 -303.197057) (xy 386.973536 -303.181169) (xy 387.024318 -303.173126) (xy 387.075734 -303.173126)
			(xy 387.126516 -303.181169) (xy 387.175415 -303.197057) (xy 387.221227 -303.2204) (xy 387.262823 -303.250621)
			(xy 387.299179 -303.286977) (xy 387.3294 -303.328573) (xy 387.352743 -303.374385) (xy 387.368631 -303.423284)
			(xy 387.376674 -303.474066) (xy 387.377178 -303.499774) (xy 387.376674 -303.525482) (xy 387.673338 -303.525482)
			(xy 387.673338 -303.474066) (xy 387.681381 -303.423284) (xy 387.697269 -303.374385) (xy 387.720612 -303.328573)
			(xy 387.750833 -303.286977) (xy 387.787189 -303.250621) (xy 387.828785 -303.2204) (xy 387.874597 -303.197057)
			(xy 387.923496 -303.181169) (xy 387.974278 -303.173126) (xy 388.025694 -303.173126) (xy 388.076476 -303.181169)
			(xy 388.125375 -303.197057) (xy 388.171187 -303.2204) (xy 388.212783 -303.250621) (xy 388.249139 -303.286977)
			(xy 388.27936 -303.328573) (xy 388.302703 -303.374385) (xy 388.318591 -303.423284) (xy 388.326634 -303.474066)
			(xy 388.327138 -303.499774) (xy 388.644142 -303.499774) (xy 388.648102 -303.45072) (xy 388.659879 -303.402936)
			(xy 388.67917 -303.35766) (xy 388.705473 -303.316064) (xy 388.738108 -303.279227) (xy 388.776229 -303.248102)
			(xy 388.81885 -303.223495) (xy 388.864866 -303.206043) (xy 388.913085 -303.196199) (xy 388.96226 -303.194218)
			(xy 389.011115 -303.20015) (xy 389.058386 -303.213842) (xy 389.102848 -303.23494) (xy 389.143351 -303.262896)
			(xy 389.178844 -303.296988) (xy 389.208409 -303.336332) (xy 389.23128 -303.379909) (xy 389.246864 -303.42659)
			(xy 389.254759 -303.475167) (xy 389.255254 -303.499774) (xy 389.254759 -303.524381) (xy 389.25458 -303.525482)
			(xy 389.573258 -303.525482) (xy 389.573258 -303.474066) (xy 389.581301 -303.423284) (xy 389.597189 -303.374385)
			(xy 389.620532 -303.328573) (xy 389.650753 -303.286977) (xy 389.687109 -303.250621) (xy 389.728705 -303.2204)
			(xy 389.774517 -303.197057) (xy 389.823416 -303.181169) (xy 389.874198 -303.173126) (xy 389.925614 -303.173126)
			(xy 389.976396 -303.181169) (xy 390.025295 -303.197057) (xy 390.071107 -303.2204) (xy 390.112703 -303.250621)
			(xy 390.149059 -303.286977) (xy 390.17928 -303.328573) (xy 390.202623 -303.374385) (xy 390.218511 -303.423284)
			(xy 390.226554 -303.474066) (xy 390.227058 -303.499774) (xy 390.226554 -303.525482) (xy 390.523218 -303.525482)
			(xy 390.523218 -303.474066) (xy 390.531261 -303.423284) (xy 390.547149 -303.374385) (xy 390.570492 -303.328573)
			(xy 390.600713 -303.286977) (xy 390.637069 -303.250621) (xy 390.678665 -303.2204) (xy 390.724477 -303.197057)
			(xy 390.773376 -303.181169) (xy 390.824158 -303.173126) (xy 390.875574 -303.173126) (xy 390.926356 -303.181169)
			(xy 390.975255 -303.197057) (xy 391.021067 -303.2204) (xy 391.062663 -303.250621) (xy 391.099019 -303.286977)
			(xy 391.12924 -303.328573) (xy 391.152583 -303.374385) (xy 391.168471 -303.423284) (xy 391.176514 -303.474066)
			(xy 391.177018 -303.499774) (xy 391.494022 -303.499774) (xy 391.497982 -303.45072) (xy 391.509759 -303.402936)
			(xy 391.52905 -303.35766) (xy 391.555353 -303.316064) (xy 391.587988 -303.279227) (xy 391.626109 -303.248102)
			(xy 391.66873 -303.223495) (xy 391.714746 -303.206043) (xy 391.762965 -303.196199) (xy 391.81214 -303.194218)
			(xy 391.860995 -303.20015) (xy 391.908266 -303.213842) (xy 391.952728 -303.23494) (xy 391.993231 -303.262896)
			(xy 392.028724 -303.296988) (xy 392.058289 -303.336332) (xy 392.08116 -303.379909) (xy 392.096744 -303.42659)
			(xy 392.104639 -303.475167) (xy 392.105134 -303.499774) (xy 392.443982 -303.499774) (xy 392.447942 -303.45072)
			(xy 392.459719 -303.402936) (xy 392.47901 -303.35766) (xy 392.505313 -303.316064) (xy 392.537948 -303.279227)
			(xy 392.576069 -303.248102) (xy 392.61869 -303.223495) (xy 392.664706 -303.206043) (xy 392.712925 -303.196199)
			(xy 392.7621 -303.194218) (xy 392.810955 -303.20015) (xy 392.858226 -303.213842) (xy 392.902688 -303.23494)
			(xy 392.943191 -303.262896) (xy 392.978684 -303.296988) (xy 393.008249 -303.336332) (xy 393.03112 -303.379909)
			(xy 393.046704 -303.42659) (xy 393.054599 -303.475167) (xy 393.055094 -303.499774) (xy 393.054599 -303.524381)
			(xy 393.046704 -303.572958) (xy 393.03112 -303.619639) (xy 393.008249 -303.663216) (xy 392.978684 -303.70256)
			(xy 392.943191 -303.736652) (xy 392.902688 -303.764608) (xy 392.858226 -303.785706) (xy 392.810955 -303.799398)
			(xy 392.7621 -303.80533) (xy 392.712925 -303.803349) (xy 392.664706 -303.793505) (xy 392.61869 -303.776053)
			(xy 392.576069 -303.751446) (xy 392.537948 -303.720321) (xy 392.505313 -303.683484) (xy 392.47901 -303.641888)
			(xy 392.459719 -303.596612) (xy 392.447942 -303.548828) (xy 392.443982 -303.499774) (xy 392.105134 -303.499774)
			(xy 392.104639 -303.524381) (xy 392.096744 -303.572958) (xy 392.08116 -303.619639) (xy 392.058289 -303.663216)
			(xy 392.028724 -303.70256) (xy 391.993231 -303.736652) (xy 391.952728 -303.764608) (xy 391.908266 -303.785706)
			(xy 391.860995 -303.799398) (xy 391.81214 -303.80533) (xy 391.762965 -303.803349) (xy 391.714746 -303.793505)
			(xy 391.66873 -303.776053) (xy 391.626109 -303.751446) (xy 391.587988 -303.720321) (xy 391.555353 -303.683484)
			(xy 391.52905 -303.641888) (xy 391.509759 -303.596612) (xy 391.497982 -303.548828) (xy 391.494022 -303.499774)
			(xy 391.177018 -303.499774) (xy 391.176514 -303.525482) (xy 391.168471 -303.576264) (xy 391.152583 -303.625163)
			(xy 391.12924 -303.670975) (xy 391.099019 -303.712571) (xy 391.062663 -303.748927) (xy 391.021067 -303.779148)
			(xy 390.975255 -303.802491) (xy 390.926356 -303.818379) (xy 390.875574 -303.826422) (xy 390.824158 -303.826422)
			(xy 390.773376 -303.818379) (xy 390.724477 -303.802491) (xy 390.678665 -303.779148) (xy 390.637069 -303.748927)
			(xy 390.600713 -303.712571) (xy 390.570492 -303.670975) (xy 390.547149 -303.625163) (xy 390.531261 -303.576264)
			(xy 390.523218 -303.525482) (xy 390.226554 -303.525482) (xy 390.218511 -303.576264) (xy 390.202623 -303.625163)
			(xy 390.17928 -303.670975) (xy 390.149059 -303.712571) (xy 390.112703 -303.748927) (xy 390.071107 -303.779148)
			(xy 390.025295 -303.802491) (xy 389.976396 -303.818379) (xy 389.925614 -303.826422) (xy 389.874198 -303.826422)
			(xy 389.823416 -303.818379) (xy 389.774517 -303.802491) (xy 389.728705 -303.779148) (xy 389.687109 -303.748927)
			(xy 389.650753 -303.712571) (xy 389.620532 -303.670975) (xy 389.597189 -303.625163) (xy 389.581301 -303.576264)
			(xy 389.573258 -303.525482) (xy 389.25458 -303.525482) (xy 389.246864 -303.572958) (xy 389.23128 -303.619639)
			(xy 389.208409 -303.663216) (xy 389.178844 -303.70256) (xy 389.143351 -303.736652) (xy 389.102848 -303.764608)
			(xy 389.058386 -303.785706) (xy 389.011115 -303.799398) (xy 388.96226 -303.80533) (xy 388.913085 -303.803349)
			(xy 388.864866 -303.793505) (xy 388.81885 -303.776053) (xy 388.776229 -303.751446) (xy 388.738108 -303.720321)
			(xy 388.705473 -303.683484) (xy 388.67917 -303.641888) (xy 388.659879 -303.596612) (xy 388.648102 -303.548828)
			(xy 388.644142 -303.499774) (xy 388.327138 -303.499774) (xy 388.326634 -303.525482) (xy 388.318591 -303.576264)
			(xy 388.302703 -303.625163) (xy 388.27936 -303.670975) (xy 388.249139 -303.712571) (xy 388.212783 -303.748927)
			(xy 388.171187 -303.779148) (xy 388.125375 -303.802491) (xy 388.076476 -303.818379) (xy 388.025694 -303.826422)
			(xy 387.974278 -303.826422) (xy 387.923496 -303.818379) (xy 387.874597 -303.802491) (xy 387.828785 -303.779148)
			(xy 387.787189 -303.748927) (xy 387.750833 -303.712571) (xy 387.720612 -303.670975) (xy 387.697269 -303.625163)
			(xy 387.681381 -303.576264) (xy 387.673338 -303.525482) (xy 387.376674 -303.525482) (xy 387.368631 -303.576264)
			(xy 387.352743 -303.625163) (xy 387.3294 -303.670975) (xy 387.299179 -303.712571) (xy 387.262823 -303.748927)
			(xy 387.221227 -303.779148) (xy 387.175415 -303.802491) (xy 387.126516 -303.818379) (xy 387.075734 -303.826422)
			(xy 387.024318 -303.826422) (xy 386.973536 -303.818379) (xy 386.924637 -303.802491) (xy 386.878825 -303.779148)
			(xy 386.837229 -303.748927) (xy 386.800873 -303.712571) (xy 386.770652 -303.670975) (xy 386.747309 -303.625163)
			(xy 386.731421 -303.576264) (xy 386.723378 -303.525482) (xy 386.404446 -303.525482) (xy 386.39673 -303.572958)
			(xy 386.381146 -303.619639) (xy 386.358275 -303.663216) (xy 386.32871 -303.70256) (xy 386.293217 -303.736652)
			(xy 386.252714 -303.764608) (xy 386.208252 -303.785706) (xy 386.160981 -303.799398) (xy 386.112126 -303.80533)
			(xy 386.062951 -303.803349) (xy 386.014732 -303.793505) (xy 385.968716 -303.776053) (xy 385.926095 -303.751446)
			(xy 385.887974 -303.720321) (xy 385.855339 -303.683484) (xy 385.829036 -303.641888) (xy 385.809745 -303.596612)
			(xy 385.797968 -303.548828) (xy 385.794008 -303.499774) (xy 385.45516 -303.499774) (xy 385.454665 -303.524381)
			(xy 385.44677 -303.572958) (xy 385.431186 -303.619639) (xy 385.408315 -303.663216) (xy 385.37875 -303.70256)
			(xy 385.343257 -303.736652) (xy 385.302754 -303.764608) (xy 385.258292 -303.785706) (xy 385.211021 -303.799398)
			(xy 385.162166 -303.80533) (xy 385.112991 -303.803349) (xy 385.064772 -303.793505) (xy 385.018756 -303.776053)
			(xy 384.976135 -303.751446) (xy 384.938014 -303.720321) (xy 384.905379 -303.683484) (xy 384.879076 -303.641888)
			(xy 384.859785 -303.596612) (xy 384.848008 -303.548828) (xy 384.844048 -303.499774) (xy 351.031048 -303.499774)
			(xy 351.031048 -303.974754) (xy 394.819136 -303.974754) (xy 394.823096 -303.9257) (xy 394.834873 -303.877916)
			(xy 394.854164 -303.83264) (xy 394.880467 -303.791044) (xy 394.913102 -303.754207) (xy 394.951223 -303.723082)
			(xy 394.993844 -303.698475) (xy 395.03986 -303.681023) (xy 395.088079 -303.671179) (xy 395.137254 -303.669198)
			(xy 395.186109 -303.67513) (xy 395.23338 -303.688822) (xy 395.277842 -303.70992) (xy 395.318345 -303.737876)
			(xy 395.353838 -303.771968) (xy 395.383403 -303.811312) (xy 395.406274 -303.854889) (xy 395.421858 -303.90157)
			(xy 395.429753 -303.950147) (xy 395.430248 -303.974754) (xy 395.769096 -303.974754) (xy 395.773056 -303.9257)
			(xy 395.784833 -303.877916) (xy 395.804124 -303.83264) (xy 395.830427 -303.791044) (xy 395.863062 -303.754207)
			(xy 395.901183 -303.723082) (xy 395.943804 -303.698475) (xy 395.98982 -303.681023) (xy 396.038039 -303.671179)
			(xy 396.087214 -303.669198) (xy 396.136069 -303.67513) (xy 396.18334 -303.688822) (xy 396.227802 -303.70992)
			(xy 396.268305 -303.737876) (xy 396.303798 -303.771968) (xy 396.333363 -303.811312) (xy 396.356234 -303.854889)
			(xy 396.371818 -303.90157) (xy 396.379713 -303.950147) (xy 396.380208 -303.974754) (xy 396.719056 -303.974754)
			(xy 396.723016 -303.9257) (xy 396.734793 -303.877916) (xy 396.754084 -303.83264) (xy 396.780387 -303.791044)
			(xy 396.813022 -303.754207) (xy 396.851143 -303.723082) (xy 396.893764 -303.698475) (xy 396.93978 -303.681023)
			(xy 396.987999 -303.671179) (xy 397.037174 -303.669198) (xy 397.086029 -303.67513) (xy 397.1333 -303.688822)
			(xy 397.177762 -303.70992) (xy 397.218265 -303.737876) (xy 397.253758 -303.771968) (xy 397.283323 -303.811312)
			(xy 397.306194 -303.854889) (xy 397.321778 -303.90157) (xy 397.329673 -303.950147) (xy 397.330168 -303.974754)
			(xy 397.329673 -303.999361) (xy 397.321778 -304.047938) (xy 397.306194 -304.094619) (xy 397.283323 -304.138196)
			(xy 397.253758 -304.17754) (xy 397.218265 -304.211632) (xy 397.177762 -304.239588) (xy 397.1333 -304.260686)
			(xy 397.086029 -304.274378) (xy 397.037174 -304.28031) (xy 396.987999 -304.278329) (xy 396.93978 -304.268485)
			(xy 396.893764 -304.251033) (xy 396.851143 -304.226426) (xy 396.813022 -304.195301) (xy 396.780387 -304.158464)
			(xy 396.754084 -304.116868) (xy 396.734793 -304.071592) (xy 396.723016 -304.023808) (xy 396.719056 -303.974754)
			(xy 396.380208 -303.974754) (xy 396.379713 -303.999361) (xy 396.371818 -304.047938) (xy 396.356234 -304.094619)
			(xy 396.333363 -304.138196) (xy 396.303798 -304.17754) (xy 396.268305 -304.211632) (xy 396.227802 -304.239588)
			(xy 396.18334 -304.260686) (xy 396.136069 -304.274378) (xy 396.087214 -304.28031) (xy 396.038039 -304.278329)
			(xy 395.98982 -304.268485) (xy 395.943804 -304.251033) (xy 395.901183 -304.226426) (xy 395.863062 -304.195301)
			(xy 395.830427 -304.158464) (xy 395.804124 -304.116868) (xy 395.784833 -304.071592) (xy 395.773056 -304.023808)
			(xy 395.769096 -303.974754) (xy 395.430248 -303.974754) (xy 395.429753 -303.999361) (xy 395.421858 -304.047938)
			(xy 395.406274 -304.094619) (xy 395.383403 -304.138196) (xy 395.353838 -304.17754) (xy 395.318345 -304.211632)
			(xy 395.277842 -304.239588) (xy 395.23338 -304.260686) (xy 395.186109 -304.274378) (xy 395.137254 -304.28031)
			(xy 395.088079 -304.278329) (xy 395.03986 -304.268485) (xy 394.993844 -304.251033) (xy 394.951223 -304.226426)
			(xy 394.913102 -304.195301) (xy 394.880467 -304.158464) (xy 394.854164 -304.116868) (xy 394.834873 -304.071592)
			(xy 394.823096 -304.023808) (xy 394.819136 -303.974754) (xy 351.031048 -303.974754) (xy 351.031048 -305.008534)
			(xy 353.029012 -305.008534) (xy 353.029495 -304.981164) (xy 353.037308 -304.926986) (xy 353.052793 -304.874483)
			(xy 353.075631 -304.824736) (xy 353.105352 -304.778768) (xy 353.122992 -304.757836) (xy 353.129088 -304.750724)
			(xy 353.135438 -304.733706) (xy 353.135438 -304.648362) (xy 353.129088 -304.631344) (xy 353.122992 -304.624232)
			(xy 353.105353 -304.6033) (xy 353.075642 -304.557327) (xy 353.052806 -304.507579) (xy 353.037315 -304.455079)
			(xy 353.029486 -304.400903) (xy 353.029012 -304.373534) (xy 353.029498 -304.346283) (xy 353.037254 -304.292335)
			(xy 353.052609 -304.24004) (xy 353.075251 -304.190463) (xy 353.104717 -304.144613) (xy 353.140408 -304.103422)
			(xy 353.181599 -304.067731) (xy 353.227449 -304.038265) (xy 353.277026 -304.015623) (xy 353.329321 -304.000268)
			(xy 353.383269 -303.992512) (xy 353.437771 -303.992512) (xy 353.491719 -304.000268) (xy 353.544014 -304.015623)
			(xy 353.593591 -304.038265) (xy 353.639441 -304.067731) (xy 353.680632 -304.103422) (xy 353.716323 -304.144613)
			(xy 353.745789 -304.190463) (xy 353.768431 -304.24004) (xy 353.783786 -304.292335) (xy 353.791542 -304.346283)
			(xy 353.792028 -304.373534) (xy 353.791599 -304.400906) (xy 353.783775 -304.455087) (xy 353.768278 -304.507591)
			(xy 353.745428 -304.557338) (xy 353.715694 -304.603302) (xy 353.698048 -304.624232) (xy 353.691952 -304.631344)
			(xy 353.685602 -304.648362) (xy 353.685602 -304.733706) (xy 353.691952 -304.750724) (xy 353.698048 -304.757836)
			(xy 353.715662 -304.778788) (xy 353.74538 -304.824755) (xy 353.768221 -304.874497) (xy 353.783718 -304.926993)
			(xy 353.791551 -304.981166) (xy 353.792028 -305.008534) (xy 356.449122 -305.008534) (xy 356.449603 -304.981164)
			(xy 356.457416 -304.926986) (xy 356.472902 -304.874482) (xy 356.49574 -304.824735) (xy 356.525462 -304.778768)
			(xy 356.543102 -304.757836) (xy 356.549198 -304.750724) (xy 356.555548 -304.733706) (xy 356.555548 -304.648362)
			(xy 356.549198 -304.631344) (xy 356.543102 -304.624232) (xy 356.525465 -304.603298) (xy 356.495753 -304.557326)
			(xy 356.472916 -304.507579) (xy 356.457425 -304.455079) (xy 356.449596 -304.400903) (xy 356.449122 -304.373534)
			(xy 356.449608 -304.346283) (xy 356.457364 -304.292335) (xy 356.472719 -304.24004) (xy 356.495361 -304.190463)
			(xy 356.524827 -304.144613) (xy 356.560518 -304.103422) (xy 356.601709 -304.067731) (xy 356.647559 -304.038265)
			(xy 356.697136 -304.015623) (xy 356.749431 -304.000268) (xy 356.803379 -303.992512) (xy 356.857881 -303.992512)
			(xy 356.911829 -304.000268) (xy 356.964124 -304.015623) (xy 357.013701 -304.038265) (xy 357.059551 -304.067731)
			(xy 357.100742 -304.103422) (xy 357.136433 -304.144613) (xy 357.165899 -304.190463) (xy 357.188541 -304.24004)
			(xy 357.203896 -304.292335) (xy 357.211652 -304.346283) (xy 357.212138 -304.373534) (xy 357.211707 -304.400906)
			(xy 357.203883 -304.455087) (xy 357.188387 -304.507591) (xy 357.165537 -304.557337) (xy 357.135804 -304.603302)
			(xy 357.118158 -304.624232) (xy 357.112062 -304.631344) (xy 357.105712 -304.648362) (xy 357.105712 -304.733706)
			(xy 357.112062 -304.750724) (xy 357.118158 -304.757836) (xy 357.135774 -304.778787) (xy 357.165491 -304.824754)
			(xy 357.188332 -304.874496) (xy 357.203828 -304.926993) (xy 357.211661 -304.981166) (xy 357.212138 -305.008534)
			(xy 357.837232 -305.008534) (xy 357.83771 -304.981164) (xy 357.845524 -304.926985) (xy 357.86101 -304.874482)
			(xy 357.883849 -304.824735) (xy 357.913572 -304.778768) (xy 357.931212 -304.757836) (xy 357.937308 -304.750724)
			(xy 357.943658 -304.733706) (xy 357.943658 -304.648362) (xy 357.937308 -304.631344) (xy 357.931212 -304.624232)
			(xy 357.913576 -304.603297) (xy 357.883864 -304.557325) (xy 357.861027 -304.507579) (xy 357.845535 -304.455078)
			(xy 357.837706 -304.400903) (xy 357.837232 -304.373534) (xy 357.837718 -304.346283) (xy 357.845474 -304.292335)
			(xy 357.860829 -304.24004) (xy 357.883471 -304.190463) (xy 357.912937 -304.144613) (xy 357.948628 -304.103422)
			(xy 357.989819 -304.067731) (xy 358.035669 -304.038265) (xy 358.085246 -304.015623) (xy 358.137541 -304.000268)
			(xy 358.191489 -303.992512) (xy 358.245991 -303.992512) (xy 358.299939 -304.000268) (xy 358.352234 -304.015623)
			(xy 358.401811 -304.038265) (xy 358.447661 -304.067731) (xy 358.488852 -304.103422) (xy 358.524543 -304.144613)
			(xy 358.554009 -304.190463) (xy 358.576651 -304.24004) (xy 358.592006 -304.292335) (xy 358.599762 -304.346283)
			(xy 358.600248 -304.373534) (xy 358.599815 -304.400906) (xy 358.591991 -304.455087) (xy 358.576495 -304.507591)
			(xy 358.553645 -304.557337) (xy 358.523913 -304.603302) (xy 358.506268 -304.624232) (xy 358.500172 -304.631344)
			(xy 358.493822 -304.648362) (xy 358.493822 -304.733706) (xy 358.500172 -304.750724) (xy 358.506268 -304.757836)
			(xy 358.523886 -304.778785) (xy 358.553602 -304.824753) (xy 358.576442 -304.874496) (xy 358.591938 -304.926993)
			(xy 358.599772 -304.981166) (xy 358.600248 -305.008534) (xy 359.869232 -305.008534) (xy 359.86971 -304.981164)
			(xy 359.877524 -304.926985) (xy 359.89301 -304.874482) (xy 359.915849 -304.824735) (xy 359.945572 -304.778768)
			(xy 359.963212 -304.757836) (xy 359.969308 -304.750724) (xy 359.975658 -304.733706) (xy 359.975658 -304.648362)
			(xy 359.969308 -304.631344) (xy 359.963212 -304.624232) (xy 359.945576 -304.603297) (xy 359.915864 -304.557325)
			(xy 359.893027 -304.507579) (xy 359.877535 -304.455078) (xy 359.869706 -304.400903) (xy 359.869232 -304.373534)
			(xy 359.869718 -304.346283) (xy 359.877474 -304.292335) (xy 359.892829 -304.24004) (xy 359.915471 -304.190463)
			(xy 359.944937 -304.144613) (xy 359.980628 -304.103422) (xy 360.021819 -304.067731) (xy 360.067669 -304.038265)
			(xy 360.117246 -304.015623) (xy 360.169541 -304.000268) (xy 360.223489 -303.992512) (xy 360.277991 -303.992512)
			(xy 360.331939 -304.000268) (xy 360.384234 -304.015623) (xy 360.433811 -304.038265) (xy 360.479661 -304.067731)
			(xy 360.520852 -304.103422) (xy 360.556543 -304.144613) (xy 360.586009 -304.190463) (xy 360.608651 -304.24004)
			(xy 360.624006 -304.292335) (xy 360.631762 -304.346283) (xy 360.632248 -304.373534) (xy 360.631815 -304.400906)
			(xy 360.623991 -304.455087) (xy 360.608495 -304.507591) (xy 360.585645 -304.557337) (xy 360.555913 -304.603302)
			(xy 360.538268 -304.624232) (xy 360.532172 -304.631344) (xy 360.525822 -304.648362) (xy 360.525822 -304.733706)
			(xy 360.532172 -304.750724) (xy 360.538268 -304.757836) (xy 360.555886 -304.778785) (xy 360.585602 -304.824753)
			(xy 360.608442 -304.874496) (xy 360.623938 -304.926993) (xy 360.631772 -304.981166) (xy 360.632248 -305.008534)
			(xy 364.677452 -305.008534) (xy 364.677925 -304.981164) (xy 364.685739 -304.926985) (xy 364.701226 -304.874481)
			(xy 364.724067 -304.824734) (xy 364.753791 -304.778767) (xy 364.771432 -304.757836) (xy 364.777528 -304.750724)
			(xy 364.783878 -304.733706) (xy 364.783878 -304.648362) (xy 364.777528 -304.631344) (xy 364.771432 -304.624232)
			(xy 364.753799 -304.603295) (xy 364.724086 -304.557324) (xy 364.701248 -304.507578) (xy 364.685755 -304.455078)
			(xy 364.677926 -304.400903) (xy 364.677452 -304.373534) (xy 364.677938 -304.346283) (xy 364.685694 -304.292335)
			(xy 364.701049 -304.24004) (xy 364.723691 -304.190463) (xy 364.753157 -304.144613) (xy 364.788848 -304.103422)
			(xy 364.830039 -304.067731) (xy 364.875889 -304.038265) (xy 364.925466 -304.015623) (xy 364.977761 -304.000268)
			(xy 365.031709 -303.992512) (xy 365.086211 -303.992512) (xy 365.140159 -304.000268) (xy 365.192454 -304.015623)
			(xy 365.242031 -304.038265) (xy 365.287881 -304.067731) (xy 365.329072 -304.103422) (xy 365.364763 -304.144613)
			(xy 365.394229 -304.190463) (xy 365.416871 -304.24004) (xy 365.432226 -304.292335) (xy 365.439982 -304.346283)
			(xy 365.440468 -304.373534) (xy 365.44003 -304.400905) (xy 365.432206 -304.455086) (xy 365.416711 -304.50759)
			(xy 365.393863 -304.557336) (xy 365.364132 -304.603301) (xy 365.346488 -304.624232) (xy 365.340392 -304.631344)
			(xy 365.334042 -304.648362) (xy 365.334042 -304.733706) (xy 365.340392 -304.750724) (xy 365.346488 -304.757836)
			(xy 365.364109 -304.778783) (xy 365.393824 -304.824751) (xy 365.416663 -304.874495) (xy 365.432159 -304.926993)
			(xy 365.439992 -304.981166) (xy 365.440468 -305.008534) (xy 365.439982 -305.035785) (xy 365.432226 -305.089733)
			(xy 365.416871 -305.142028) (xy 365.394229 -305.191605) (xy 365.364763 -305.237455) (xy 365.329072 -305.278646)
			(xy 365.287881 -305.314337) (xy 365.242031 -305.343803) (xy 365.203422 -305.361436) (xy 375.710316 -305.361436)
			(xy 375.710319 -305.306922) (xy 375.71808 -305.252964) (xy 375.733442 -305.200659) (xy 375.756091 -305.151073)
			(xy 375.785568 -305.105216) (xy 375.82127 -305.06402) (xy 375.862473 -305.028325) (xy 375.908336 -304.998858)
			(xy 375.957926 -304.976217) (xy 376.010233 -304.960865) (xy 376.064193 -304.953113) (xy 376.09145 -304.952654)
			(xy 376.11939 -304.95367) (xy 376.130566 -304.954432) (xy 376.151648 -304.946558) (xy 376.221752 -304.873914)
			(xy 376.229118 -304.852578) (xy 376.227848 -304.841402) (xy 376.226788 -304.831148) (xy 376.225643 -304.810562)
			(xy 376.225562 -304.800254) (xy 376.226127 -304.773006) (xy 376.233889 -304.719067) (xy 376.249249 -304.66678)
			(xy 376.271893 -304.617212) (xy 376.30136 -304.571371) (xy 376.337052 -304.530191) (xy 376.378241 -304.494508)
			(xy 376.424089 -304.465051) (xy 376.473662 -304.442418) (xy 376.525951 -304.427071) (xy 376.579893 -304.419321)
			(xy 376.634388 -304.419327) (xy 376.688328 -304.427088) (xy 376.740615 -304.442447) (xy 376.757123 -304.449988)
			(xy 383.893834 -304.449988) (xy 383.897794 -304.400934) (xy 383.909571 -304.35315) (xy 383.928862 -304.307874)
			(xy 383.955165 -304.266278) (xy 383.9878 -304.229441) (xy 384.025921 -304.198316) (xy 384.068542 -304.173709)
			(xy 384.114558 -304.156257) (xy 384.162777 -304.146413) (xy 384.211952 -304.144432) (xy 384.260807 -304.150364)
			(xy 384.308078 -304.164056) (xy 384.35254 -304.185154) (xy 384.393043 -304.21311) (xy 384.428536 -304.247202)
			(xy 384.458101 -304.286546) (xy 384.480972 -304.330123) (xy 384.496556 -304.376804) (xy 384.504451 -304.425381)
			(xy 384.504946 -304.449988) (xy 384.504451 -304.474595) (xy 384.504313 -304.475442) (xy 384.823204 -304.475442)
			(xy 384.823204 -304.424026) (xy 384.831247 -304.373244) (xy 384.847135 -304.324345) (xy 384.870478 -304.278533)
			(xy 384.900699 -304.236937) (xy 384.937055 -304.200581) (xy 384.978651 -304.17036) (xy 385.024463 -304.147017)
			(xy 385.073362 -304.131129) (xy 385.124144 -304.123086) (xy 385.17556 -304.123086) (xy 385.226342 -304.131129)
			(xy 385.275241 -304.147017) (xy 385.321053 -304.17036) (xy 385.362649 -304.200581) (xy 385.399005 -304.236937)
			(xy 385.429226 -304.278533) (xy 385.452569 -304.324345) (xy 385.468457 -304.373244) (xy 385.4765 -304.424026)
			(xy 385.477004 -304.449734) (xy 385.4765 -304.475442) (xy 385.773164 -304.475442) (xy 385.773164 -304.424026)
			(xy 385.781207 -304.373244) (xy 385.797095 -304.324345) (xy 385.820438 -304.278533) (xy 385.850659 -304.236937)
			(xy 385.887015 -304.200581) (xy 385.928611 -304.17036) (xy 385.974423 -304.147017) (xy 386.023322 -304.131129)
			(xy 386.074104 -304.123086) (xy 386.12552 -304.123086) (xy 386.176302 -304.131129) (xy 386.225201 -304.147017)
			(xy 386.271013 -304.17036) (xy 386.312609 -304.200581) (xy 386.348965 -304.236937) (xy 386.379186 -304.278533)
			(xy 386.402529 -304.324345) (xy 386.418417 -304.373244) (xy 386.42646 -304.424026) (xy 386.426964 -304.449734)
			(xy 386.744222 -304.449734) (xy 386.748182 -304.40068) (xy 386.759959 -304.352896) (xy 386.77925 -304.30762)
			(xy 386.805553 -304.266024) (xy 386.838188 -304.229187) (xy 386.876309 -304.198062) (xy 386.91893 -304.173455)
			(xy 386.964946 -304.156003) (xy 387.013165 -304.146159) (xy 387.06234 -304.144178) (xy 387.111195 -304.15011)
			(xy 387.158466 -304.163802) (xy 387.202928 -304.1849) (xy 387.243431 -304.212856) (xy 387.278924 -304.246948)
			(xy 387.308489 -304.286292) (xy 387.33136 -304.329869) (xy 387.346944 -304.37655) (xy 387.354839 -304.425127)
			(xy 387.355334 -304.449734) (xy 387.694182 -304.449734) (xy 387.698142 -304.40068) (xy 387.709919 -304.352896)
			(xy 387.72921 -304.30762) (xy 387.755513 -304.266024) (xy 387.788148 -304.229187) (xy 387.826269 -304.198062)
			(xy 387.86889 -304.173455) (xy 387.914906 -304.156003) (xy 387.963125 -304.146159) (xy 388.0123 -304.144178)
			(xy 388.061155 -304.15011) (xy 388.108426 -304.163802) (xy 388.152888 -304.1849) (xy 388.193391 -304.212856)
			(xy 388.228884 -304.246948) (xy 388.258449 -304.286292) (xy 388.28132 -304.329869) (xy 388.296904 -304.37655)
			(xy 388.304799 -304.425127) (xy 388.305294 -304.449734) (xy 388.644142 -304.449734) (xy 388.648102 -304.40068)
			(xy 388.659879 -304.352896) (xy 388.67917 -304.30762) (xy 388.705473 -304.266024) (xy 388.738108 -304.229187)
			(xy 388.776229 -304.198062) (xy 388.81885 -304.173455) (xy 388.864866 -304.156003) (xy 388.913085 -304.146159)
			(xy 388.96226 -304.144178) (xy 389.011115 -304.15011) (xy 389.058386 -304.163802) (xy 389.102848 -304.1849)
			(xy 389.143351 -304.212856) (xy 389.178844 -304.246948) (xy 389.208409 -304.286292) (xy 389.23128 -304.329869)
			(xy 389.246864 -304.37655) (xy 389.254759 -304.425127) (xy 389.255254 -304.449734) (xy 389.594102 -304.449734)
			(xy 389.598062 -304.40068) (xy 389.609839 -304.352896) (xy 389.62913 -304.30762) (xy 389.655433 -304.266024)
			(xy 389.688068 -304.229187) (xy 389.726189 -304.198062) (xy 389.76881 -304.173455) (xy 389.814826 -304.156003)
			(xy 389.863045 -304.146159) (xy 389.91222 -304.144178) (xy 389.961075 -304.15011) (xy 390.008346 -304.163802)
			(xy 390.052808 -304.1849) (xy 390.093311 -304.212856) (xy 390.128804 -304.246948) (xy 390.158369 -304.286292)
			(xy 390.18124 -304.329869) (xy 390.196824 -304.37655) (xy 390.204719 -304.425127) (xy 390.205214 -304.449734)
			(xy 390.544062 -304.449734) (xy 390.548022 -304.40068) (xy 390.559799 -304.352896) (xy 390.57909 -304.30762)
			(xy 390.605393 -304.266024) (xy 390.638028 -304.229187) (xy 390.676149 -304.198062) (xy 390.71877 -304.173455)
			(xy 390.764786 -304.156003) (xy 390.813005 -304.146159) (xy 390.86218 -304.144178) (xy 390.911035 -304.15011)
			(xy 390.958306 -304.163802) (xy 391.002768 -304.1849) (xy 391.043271 -304.212856) (xy 391.078764 -304.246948)
			(xy 391.108329 -304.286292) (xy 391.1312 -304.329869) (xy 391.146784 -304.37655) (xy 391.154679 -304.425127)
			(xy 391.155174 -304.449734) (xy 391.154679 -304.474341) (xy 391.1545 -304.475442) (xy 391.473178 -304.475442)
			(xy 391.473178 -304.424026) (xy 391.481221 -304.373244) (xy 391.497109 -304.324345) (xy 391.520452 -304.278533)
			(xy 391.550673 -304.236937) (xy 391.587029 -304.200581) (xy 391.628625 -304.17036) (xy 391.674437 -304.147017)
			(xy 391.723336 -304.131129) (xy 391.774118 -304.123086) (xy 391.825534 -304.123086) (xy 391.876316 -304.131129)
			(xy 391.925215 -304.147017) (xy 391.971027 -304.17036) (xy 392.012623 -304.200581) (xy 392.048979 -304.236937)
			(xy 392.0792 -304.278533) (xy 392.102543 -304.324345) (xy 392.118431 -304.373244) (xy 392.126474 -304.424026)
			(xy 392.126978 -304.449734) (xy 392.126474 -304.475442) (xy 392.423138 -304.475442) (xy 392.423138 -304.424026)
			(xy 392.431181 -304.373244) (xy 392.447069 -304.324345) (xy 392.470412 -304.278533) (xy 392.500633 -304.236937)
			(xy 392.536989 -304.200581) (xy 392.578585 -304.17036) (xy 392.624397 -304.147017) (xy 392.673296 -304.131129)
			(xy 392.724078 -304.123086) (xy 392.775494 -304.123086) (xy 392.826276 -304.131129) (xy 392.875175 -304.147017)
			(xy 392.920987 -304.17036) (xy 392.962583 -304.200581) (xy 392.998939 -304.236937) (xy 393.02916 -304.278533)
			(xy 393.052503 -304.324345) (xy 393.068391 -304.373244) (xy 393.076434 -304.424026) (xy 393.076938 -304.449734)
			(xy 393.394196 -304.449734) (xy 393.398156 -304.40068) (xy 393.409933 -304.352896) (xy 393.429224 -304.30762)
			(xy 393.455527 -304.266024) (xy 393.488162 -304.229187) (xy 393.526283 -304.198062) (xy 393.568904 -304.173455)
			(xy 393.61492 -304.156003) (xy 393.663139 -304.146159) (xy 393.712314 -304.144178) (xy 393.761169 -304.15011)
			(xy 393.80844 -304.163802) (xy 393.852902 -304.1849) (xy 393.893405 -304.212856) (xy 393.928898 -304.246948)
			(xy 393.958463 -304.286292) (xy 393.981334 -304.329869) (xy 393.996918 -304.37655) (xy 394.004813 -304.425127)
			(xy 394.005308 -304.449734) (xy 394.004813 -304.474341) (xy 393.996918 -304.522918) (xy 393.981334 -304.569599)
			(xy 393.958463 -304.613176) (xy 393.928898 -304.65252) (xy 393.893405 -304.686612) (xy 393.852902 -304.714568)
			(xy 393.80844 -304.735666) (xy 393.761169 -304.749358) (xy 393.712314 -304.75529) (xy 393.663139 -304.753309)
			(xy 393.61492 -304.743465) (xy 393.568904 -304.726013) (xy 393.526283 -304.701406) (xy 393.488162 -304.670281)
			(xy 393.455527 -304.633444) (xy 393.429224 -304.591848) (xy 393.409933 -304.546572) (xy 393.398156 -304.498788)
			(xy 393.394196 -304.449734) (xy 393.076938 -304.449734) (xy 393.076434 -304.475442) (xy 393.068391 -304.526224)
			(xy 393.052503 -304.575123) (xy 393.02916 -304.620935) (xy 392.998939 -304.662531) (xy 392.962583 -304.698887)
			(xy 392.920987 -304.729108) (xy 392.875175 -304.752451) (xy 392.826276 -304.768339) (xy 392.775494 -304.776382)
			(xy 392.724078 -304.776382) (xy 392.673296 -304.768339) (xy 392.624397 -304.752451) (xy 392.578585 -304.729108)
			(xy 392.536989 -304.698887) (xy 392.500633 -304.662531) (xy 392.470412 -304.620935) (xy 392.447069 -304.575123)
			(xy 392.431181 -304.526224) (xy 392.423138 -304.475442) (xy 392.126474 -304.475442) (xy 392.118431 -304.526224)
			(xy 392.102543 -304.575123) (xy 392.0792 -304.620935) (xy 392.048979 -304.662531) (xy 392.012623 -304.698887)
			(xy 391.971027 -304.729108) (xy 391.925215 -304.752451) (xy 391.876316 -304.768339) (xy 391.825534 -304.776382)
			(xy 391.774118 -304.776382) (xy 391.723336 -304.768339) (xy 391.674437 -304.752451) (xy 391.628625 -304.729108)
			(xy 391.587029 -304.698887) (xy 391.550673 -304.662531) (xy 391.520452 -304.620935) (xy 391.497109 -304.575123)
			(xy 391.481221 -304.526224) (xy 391.473178 -304.475442) (xy 391.1545 -304.475442) (xy 391.146784 -304.522918)
			(xy 391.1312 -304.569599) (xy 391.108329 -304.613176) (xy 391.078764 -304.65252) (xy 391.043271 -304.686612)
			(xy 391.002768 -304.714568) (xy 390.958306 -304.735666) (xy 390.911035 -304.749358) (xy 390.86218 -304.75529)
			(xy 390.813005 -304.753309) (xy 390.764786 -304.743465) (xy 390.71877 -304.726013) (xy 390.676149 -304.701406)
			(xy 390.638028 -304.670281) (xy 390.605393 -304.633444) (xy 390.57909 -304.591848) (xy 390.559799 -304.546572)
			(xy 390.548022 -304.498788) (xy 390.544062 -304.449734) (xy 390.205214 -304.449734) (xy 390.204719 -304.474341)
			(xy 390.196824 -304.522918) (xy 390.18124 -304.569599) (xy 390.158369 -304.613176) (xy 390.128804 -304.65252)
			(xy 390.093311 -304.686612) (xy 390.052808 -304.714568) (xy 390.008346 -304.735666) (xy 389.961075 -304.749358)
			(xy 389.91222 -304.75529) (xy 389.863045 -304.753309) (xy 389.814826 -304.743465) (xy 389.76881 -304.726013)
			(xy 389.726189 -304.701406) (xy 389.688068 -304.670281) (xy 389.655433 -304.633444) (xy 389.62913 -304.591848)
			(xy 389.609839 -304.546572) (xy 389.598062 -304.498788) (xy 389.594102 -304.449734) (xy 389.255254 -304.449734)
			(xy 389.254759 -304.474341) (xy 389.246864 -304.522918) (xy 389.23128 -304.569599) (xy 389.208409 -304.613176)
			(xy 389.178844 -304.65252) (xy 389.143351 -304.686612) (xy 389.102848 -304.714568) (xy 389.058386 -304.735666)
			(xy 389.011115 -304.749358) (xy 388.96226 -304.75529) (xy 388.913085 -304.753309) (xy 388.864866 -304.743465)
			(xy 388.81885 -304.726013) (xy 388.776229 -304.701406) (xy 388.738108 -304.670281) (xy 388.705473 -304.633444)
			(xy 388.67917 -304.591848) (xy 388.659879 -304.546572) (xy 388.648102 -304.498788) (xy 388.644142 -304.449734)
			(xy 388.305294 -304.449734) (xy 388.304799 -304.474341) (xy 388.296904 -304.522918) (xy 388.28132 -304.569599)
			(xy 388.258449 -304.613176) (xy 388.228884 -304.65252) (xy 388.193391 -304.686612) (xy 388.152888 -304.714568)
			(xy 388.108426 -304.735666) (xy 388.061155 -304.749358) (xy 388.0123 -304.75529) (xy 387.963125 -304.753309)
			(xy 387.914906 -304.743465) (xy 387.86889 -304.726013) (xy 387.826269 -304.701406) (xy 387.788148 -304.670281)
			(xy 387.755513 -304.633444) (xy 387.72921 -304.591848) (xy 387.709919 -304.546572) (xy 387.698142 -304.498788)
			(xy 387.694182 -304.449734) (xy 387.355334 -304.449734) (xy 387.354839 -304.474341) (xy 387.346944 -304.522918)
			(xy 387.33136 -304.569599) (xy 387.308489 -304.613176) (xy 387.278924 -304.65252) (xy 387.243431 -304.686612)
			(xy 387.202928 -304.714568) (xy 387.158466 -304.735666) (xy 387.111195 -304.749358) (xy 387.06234 -304.75529)
			(xy 387.013165 -304.753309) (xy 386.964946 -304.743465) (xy 386.91893 -304.726013) (xy 386.876309 -304.701406)
			(xy 386.838188 -304.670281) (xy 386.805553 -304.633444) (xy 386.77925 -304.591848) (xy 386.759959 -304.546572)
			(xy 386.748182 -304.498788) (xy 386.744222 -304.449734) (xy 386.426964 -304.449734) (xy 386.42646 -304.475442)
			(xy 386.418417 -304.526224) (xy 386.402529 -304.575123) (xy 386.379186 -304.620935) (xy 386.348965 -304.662531)
			(xy 386.312609 -304.698887) (xy 386.271013 -304.729108) (xy 386.225201 -304.752451) (xy 386.176302 -304.768339)
			(xy 386.12552 -304.776382) (xy 386.074104 -304.776382) (xy 386.023322 -304.768339) (xy 385.974423 -304.752451)
			(xy 385.928611 -304.729108) (xy 385.887015 -304.698887) (xy 385.850659 -304.662531) (xy 385.820438 -304.620935)
			(xy 385.797095 -304.575123) (xy 385.781207 -304.526224) (xy 385.773164 -304.475442) (xy 385.4765 -304.475442)
			(xy 385.468457 -304.526224) (xy 385.452569 -304.575123) (xy 385.429226 -304.620935) (xy 385.399005 -304.662531)
			(xy 385.362649 -304.698887) (xy 385.321053 -304.729108) (xy 385.275241 -304.752451) (xy 385.226342 -304.768339)
			(xy 385.17556 -304.776382) (xy 385.124144 -304.776382) (xy 385.073362 -304.768339) (xy 385.024463 -304.752451)
			(xy 384.978651 -304.729108) (xy 384.937055 -304.698887) (xy 384.900699 -304.662531) (xy 384.870478 -304.620935)
			(xy 384.847135 -304.575123) (xy 384.831247 -304.526224) (xy 384.823204 -304.475442) (xy 384.504313 -304.475442)
			(xy 384.496556 -304.523172) (xy 384.480972 -304.569853) (xy 384.458101 -304.61343) (xy 384.428536 -304.652774)
			(xy 384.393043 -304.686866) (xy 384.35254 -304.714822) (xy 384.308078 -304.73592) (xy 384.260807 -304.749612)
			(xy 384.211952 -304.755544) (xy 384.162777 -304.753563) (xy 384.114558 -304.743719) (xy 384.068542 -304.726267)
			(xy 384.025921 -304.70166) (xy 383.9878 -304.670535) (xy 383.955165 -304.633698) (xy 383.928862 -304.592102)
			(xy 383.909571 -304.546826) (xy 383.897794 -304.499042) (xy 383.893834 -304.449988) (xy 376.757123 -304.449988)
			(xy 376.790183 -304.46509) (xy 376.836024 -304.494557) (xy 376.877206 -304.530248) (xy 376.912888 -304.571437)
			(xy 376.942346 -304.617284) (xy 376.96498 -304.666857) (xy 376.980328 -304.719146) (xy 376.988078 -304.773088)
			(xy 376.988073 -304.827583) (xy 376.980313 -304.881523) (xy 376.967627 -304.924714) (xy 394.819136 -304.924714)
			(xy 394.823096 -304.87566) (xy 394.834873 -304.827876) (xy 394.854164 -304.7826) (xy 394.880467 -304.741004)
			(xy 394.913102 -304.704167) (xy 394.951223 -304.673042) (xy 394.993844 -304.648435) (xy 395.03986 -304.630983)
			(xy 395.088079 -304.621139) (xy 395.137254 -304.619158) (xy 395.186109 -304.62509) (xy 395.23338 -304.638782)
			(xy 395.277842 -304.65988) (xy 395.318345 -304.687836) (xy 395.353838 -304.721928) (xy 395.383403 -304.761272)
			(xy 395.406274 -304.804849) (xy 395.421858 -304.85153) (xy 395.429753 -304.900107) (xy 395.430248 -304.924714)
			(xy 395.769096 -304.924714) (xy 395.773056 -304.87566) (xy 395.784833 -304.827876) (xy 395.804124 -304.7826)
			(xy 395.830427 -304.741004) (xy 395.863062 -304.704167) (xy 395.901183 -304.673042) (xy 395.943804 -304.648435)
			(xy 395.98982 -304.630983) (xy 396.038039 -304.621139) (xy 396.087214 -304.619158) (xy 396.136069 -304.62509)
			(xy 396.18334 -304.638782) (xy 396.227802 -304.65988) (xy 396.268305 -304.687836) (xy 396.303798 -304.721928)
			(xy 396.333363 -304.761272) (xy 396.356234 -304.804849) (xy 396.371818 -304.85153) (xy 396.379713 -304.900107)
			(xy 396.380208 -304.924714) (xy 396.719056 -304.924714) (xy 396.723016 -304.87566) (xy 396.734793 -304.827876)
			(xy 396.754084 -304.7826) (xy 396.780387 -304.741004) (xy 396.813022 -304.704167) (xy 396.851143 -304.673042)
			(xy 396.893764 -304.648435) (xy 396.93978 -304.630983) (xy 396.987999 -304.621139) (xy 397.037174 -304.619158)
			(xy 397.086029 -304.62509) (xy 397.1333 -304.638782) (xy 397.177762 -304.65988) (xy 397.218265 -304.687836)
			(xy 397.253758 -304.721928) (xy 397.283323 -304.761272) (xy 397.306194 -304.804849) (xy 397.321778 -304.85153)
			(xy 397.329673 -304.900107) (xy 397.330168 -304.924714) (xy 397.329673 -304.949321) (xy 397.321778 -304.997898)
			(xy 397.306194 -305.044579) (xy 397.283323 -305.088156) (xy 397.253758 -305.1275) (xy 397.218265 -305.161592)
			(xy 397.177762 -305.189548) (xy 397.1333 -305.210646) (xy 397.086029 -305.224338) (xy 397.037174 -305.23027)
			(xy 396.987999 -305.228289) (xy 396.93978 -305.218445) (xy 396.893764 -305.200993) (xy 396.851143 -305.176386)
			(xy 396.813022 -305.145261) (xy 396.780387 -305.108424) (xy 396.754084 -305.066828) (xy 396.734793 -305.021552)
			(xy 396.723016 -304.973768) (xy 396.719056 -304.924714) (xy 396.380208 -304.924714) (xy 396.379713 -304.949321)
			(xy 396.371818 -304.997898) (xy 396.356234 -305.044579) (xy 396.333363 -305.088156) (xy 396.303798 -305.1275)
			(xy 396.268305 -305.161592) (xy 396.227802 -305.189548) (xy 396.18334 -305.210646) (xy 396.136069 -305.224338)
			(xy 396.087214 -305.23027) (xy 396.038039 -305.228289) (xy 395.98982 -305.218445) (xy 395.943804 -305.200993)
			(xy 395.901183 -305.176386) (xy 395.863062 -305.145261) (xy 395.830427 -305.108424) (xy 395.804124 -305.066828)
			(xy 395.784833 -305.021552) (xy 395.773056 -304.973768) (xy 395.769096 -304.924714) (xy 395.430248 -304.924714)
			(xy 395.429753 -304.949321) (xy 395.421858 -304.997898) (xy 395.406274 -305.044579) (xy 395.383403 -305.088156)
			(xy 395.353838 -305.1275) (xy 395.318345 -305.161592) (xy 395.277842 -305.189548) (xy 395.23338 -305.210646)
			(xy 395.186109 -305.224338) (xy 395.137254 -305.23027) (xy 395.088079 -305.228289) (xy 395.03986 -305.218445)
			(xy 394.993844 -305.200993) (xy 394.951223 -305.176386) (xy 394.913102 -305.145261) (xy 394.880467 -305.108424)
			(xy 394.854164 -305.066828) (xy 394.834873 -305.021552) (xy 394.823096 -304.973768) (xy 394.819136 -304.924714)
			(xy 376.967627 -304.924714) (xy 376.964955 -304.93381) (xy 376.942312 -304.983378) (xy 376.912846 -305.02922)
			(xy 376.877156 -305.070402) (xy 376.835968 -305.106085) (xy 376.790121 -305.135544) (xy 376.740548 -305.158178)
			(xy 376.688259 -305.173527) (xy 376.634318 -305.181278) (xy 376.60707 -305.181762) (xy 376.57913 -305.180746)
			(xy 376.567954 -305.179984) (xy 376.546872 -305.187858) (xy 376.476768 -305.260502) (xy 376.469402 -305.281838)
			(xy 376.470672 -305.293014) (xy 376.471734 -305.303268) (xy 376.472877 -305.323853) (xy 376.472958 -305.334162)
			(xy 376.472486 -305.361419) (xy 376.46695 -305.399948) (xy 384.844048 -305.399948) (xy 384.848008 -305.350894)
			(xy 384.859785 -305.30311) (xy 384.879076 -305.257834) (xy 384.905379 -305.216238) (xy 384.938014 -305.179401)
			(xy 384.976135 -305.148276) (xy 385.018756 -305.123669) (xy 385.064772 -305.106217) (xy 385.112991 -305.096373)
			(xy 385.162166 -305.094392) (xy 385.211021 -305.100324) (xy 385.258292 -305.114016) (xy 385.302754 -305.135114)
			(xy 385.343257 -305.16307) (xy 385.37875 -305.197162) (xy 385.408315 -305.236506) (xy 385.431186 -305.280083)
			(xy 385.44677 -305.326764) (xy 385.454665 -305.375341) (xy 385.45516 -305.399948) (xy 385.794008 -305.399948)
			(xy 385.797968 -305.350894) (xy 385.809745 -305.30311) (xy 385.829036 -305.257834) (xy 385.855339 -305.216238)
			(xy 385.887974 -305.179401) (xy 385.926095 -305.148276) (xy 385.968716 -305.123669) (xy 386.014732 -305.106217)
			(xy 386.062951 -305.096373) (xy 386.112126 -305.094392) (xy 386.160981 -305.100324) (xy 386.208252 -305.114016)
			(xy 386.252714 -305.135114) (xy 386.293217 -305.16307) (xy 386.32871 -305.197162) (xy 386.358275 -305.236506)
			(xy 386.381146 -305.280083) (xy 386.39673 -305.326764) (xy 386.404625 -305.375341) (xy 386.40512 -305.399948)
			(xy 386.404625 -305.424555) (xy 386.404446 -305.425656) (xy 386.723378 -305.425656) (xy 386.723378 -305.37424)
			(xy 386.731421 -305.323458) (xy 386.747309 -305.274559) (xy 386.770652 -305.228747) (xy 386.800873 -305.187151)
			(xy 386.837229 -305.150795) (xy 386.878825 -305.120574) (xy 386.924637 -305.097231) (xy 386.973536 -305.081343)
			(xy 387.024318 -305.0733) (xy 387.075734 -305.0733) (xy 387.126516 -305.081343) (xy 387.175415 -305.097231)
			(xy 387.221227 -305.120574) (xy 387.262823 -305.150795) (xy 387.299179 -305.187151) (xy 387.3294 -305.228747)
			(xy 387.352743 -305.274559) (xy 387.368631 -305.323458) (xy 387.376674 -305.37424) (xy 387.377178 -305.399948)
			(xy 387.376674 -305.425656) (xy 387.673338 -305.425656) (xy 387.673338 -305.37424) (xy 387.681381 -305.323458)
			(xy 387.697269 -305.274559) (xy 387.720612 -305.228747) (xy 387.750833 -305.187151) (xy 387.787189 -305.150795)
			(xy 387.828785 -305.120574) (xy 387.874597 -305.097231) (xy 387.923496 -305.081343) (xy 387.974278 -305.0733)
			(xy 388.025694 -305.0733) (xy 388.076476 -305.081343) (xy 388.125375 -305.097231) (xy 388.171187 -305.120574)
			(xy 388.212783 -305.150795) (xy 388.249139 -305.187151) (xy 388.27936 -305.228747) (xy 388.302703 -305.274559)
			(xy 388.318591 -305.323458) (xy 388.326634 -305.37424) (xy 388.327138 -305.399948) (xy 388.644142 -305.399948)
			(xy 388.648102 -305.350894) (xy 388.659879 -305.30311) (xy 388.67917 -305.257834) (xy 388.705473 -305.216238)
			(xy 388.738108 -305.179401) (xy 388.776229 -305.148276) (xy 388.81885 -305.123669) (xy 388.864866 -305.106217)
			(xy 388.913085 -305.096373) (xy 388.96226 -305.094392) (xy 389.011115 -305.100324) (xy 389.058386 -305.114016)
			(xy 389.102848 -305.135114) (xy 389.143351 -305.16307) (xy 389.178844 -305.197162) (xy 389.208409 -305.236506)
			(xy 389.23128 -305.280083) (xy 389.246864 -305.326764) (xy 389.254759 -305.375341) (xy 389.255254 -305.399948)
			(xy 389.254759 -305.424555) (xy 389.25458 -305.425656) (xy 389.573258 -305.425656) (xy 389.573258 -305.37424)
			(xy 389.581301 -305.323458) (xy 389.597189 -305.274559) (xy 389.620532 -305.228747) (xy 389.650753 -305.187151)
			(xy 389.687109 -305.150795) (xy 389.728705 -305.120574) (xy 389.774517 -305.097231) (xy 389.823416 -305.081343)
			(xy 389.874198 -305.0733) (xy 389.925614 -305.0733) (xy 389.976396 -305.081343) (xy 390.025295 -305.097231)
			(xy 390.071107 -305.120574) (xy 390.112703 -305.150795) (xy 390.149059 -305.187151) (xy 390.17928 -305.228747)
			(xy 390.202623 -305.274559) (xy 390.218511 -305.323458) (xy 390.226554 -305.37424) (xy 390.227058 -305.399948)
			(xy 390.226554 -305.425656) (xy 390.523218 -305.425656) (xy 390.523218 -305.37424) (xy 390.531261 -305.323458)
			(xy 390.547149 -305.274559) (xy 390.570492 -305.228747) (xy 390.600713 -305.187151) (xy 390.637069 -305.150795)
			(xy 390.678665 -305.120574) (xy 390.724477 -305.097231) (xy 390.773376 -305.081343) (xy 390.824158 -305.0733)
			(xy 390.875574 -305.0733) (xy 390.926356 -305.081343) (xy 390.975255 -305.097231) (xy 391.021067 -305.120574)
			(xy 391.062663 -305.150795) (xy 391.099019 -305.187151) (xy 391.12924 -305.228747) (xy 391.152583 -305.274559)
			(xy 391.168471 -305.323458) (xy 391.176514 -305.37424) (xy 391.177018 -305.399948) (xy 391.494022 -305.399948)
			(xy 391.497982 -305.350894) (xy 391.509759 -305.30311) (xy 391.52905 -305.257834) (xy 391.555353 -305.216238)
			(xy 391.587988 -305.179401) (xy 391.626109 -305.148276) (xy 391.66873 -305.123669) (xy 391.714746 -305.106217)
			(xy 391.762965 -305.096373) (xy 391.81214 -305.094392) (xy 391.860995 -305.100324) (xy 391.908266 -305.114016)
			(xy 391.952728 -305.135114) (xy 391.993231 -305.16307) (xy 392.028724 -305.197162) (xy 392.058289 -305.236506)
			(xy 392.08116 -305.280083) (xy 392.096744 -305.326764) (xy 392.104639 -305.375341) (xy 392.105134 -305.399948)
			(xy 392.443982 -305.399948) (xy 392.447942 -305.350894) (xy 392.459719 -305.30311) (xy 392.47901 -305.257834)
			(xy 392.505313 -305.216238) (xy 392.537948 -305.179401) (xy 392.576069 -305.148276) (xy 392.61869 -305.123669)
			(xy 392.664706 -305.106217) (xy 392.712925 -305.096373) (xy 392.7621 -305.094392) (xy 392.810955 -305.100324)
			(xy 392.858226 -305.114016) (xy 392.902688 -305.135114) (xy 392.943191 -305.16307) (xy 392.978684 -305.197162)
			(xy 393.008249 -305.236506) (xy 393.03112 -305.280083) (xy 393.046704 -305.326764) (xy 393.054599 -305.375341)
			(xy 393.055094 -305.399948) (xy 393.394196 -305.399948) (xy 393.398156 -305.350894) (xy 393.409933 -305.30311)
			(xy 393.429224 -305.257834) (xy 393.455527 -305.216238) (xy 393.488162 -305.179401) (xy 393.526283 -305.148276)
			(xy 393.568904 -305.123669) (xy 393.61492 -305.106217) (xy 393.663139 -305.096373) (xy 393.712314 -305.094392)
			(xy 393.761169 -305.100324) (xy 393.80844 -305.114016) (xy 393.852902 -305.135114) (xy 393.893405 -305.16307)
			(xy 393.928898 -305.197162) (xy 393.958463 -305.236506) (xy 393.981334 -305.280083) (xy 393.996918 -305.326764)
			(xy 394.004813 -305.375341) (xy 394.005308 -305.399948) (xy 394.004813 -305.424555) (xy 393.996918 -305.473132)
			(xy 393.981334 -305.519813) (xy 393.958463 -305.56339) (xy 393.928898 -305.602734) (xy 393.893405 -305.636826)
			(xy 393.852902 -305.664782) (xy 393.80844 -305.68588) (xy 393.761169 -305.699572) (xy 393.712314 -305.705504)
			(xy 393.663139 -305.703523) (xy 393.61492 -305.693679) (xy 393.568904 -305.676227) (xy 393.526283 -305.65162)
			(xy 393.488162 -305.620495) (xy 393.455527 -305.583658) (xy 393.429224 -305.542062) (xy 393.409933 -305.496786)
			(xy 393.398156 -305.449002) (xy 393.394196 -305.399948) (xy 393.055094 -305.399948) (xy 393.054599 -305.424555)
			(xy 393.046704 -305.473132) (xy 393.03112 -305.519813) (xy 393.008249 -305.56339) (xy 392.978684 -305.602734)
			(xy 392.943191 -305.636826) (xy 392.902688 -305.664782) (xy 392.858226 -305.68588) (xy 392.810955 -305.699572)
			(xy 392.7621 -305.705504) (xy 392.712925 -305.703523) (xy 392.664706 -305.693679) (xy 392.61869 -305.676227)
			(xy 392.576069 -305.65162) (xy 392.537948 -305.620495) (xy 392.505313 -305.583658) (xy 392.47901 -305.542062)
			(xy 392.459719 -305.496786) (xy 392.447942 -305.449002) (xy 392.443982 -305.399948) (xy 392.105134 -305.399948)
			(xy 392.104639 -305.424555) (xy 392.096744 -305.473132) (xy 392.08116 -305.519813) (xy 392.058289 -305.56339)
			(xy 392.028724 -305.602734) (xy 391.993231 -305.636826) (xy 391.952728 -305.664782) (xy 391.908266 -305.68588)
			(xy 391.860995 -305.699572) (xy 391.81214 -305.705504) (xy 391.762965 -305.703523) (xy 391.714746 -305.693679)
			(xy 391.66873 -305.676227) (xy 391.626109 -305.65162) (xy 391.587988 -305.620495) (xy 391.555353 -305.583658)
			(xy 391.52905 -305.542062) (xy 391.509759 -305.496786) (xy 391.497982 -305.449002) (xy 391.494022 -305.399948)
			(xy 391.177018 -305.399948) (xy 391.176514 -305.425656) (xy 391.168471 -305.476438) (xy 391.152583 -305.525337)
			(xy 391.12924 -305.571149) (xy 391.099019 -305.612745) (xy 391.062663 -305.649101) (xy 391.021067 -305.679322)
			(xy 390.975255 -305.702665) (xy 390.926356 -305.718553) (xy 390.875574 -305.726596) (xy 390.824158 -305.726596)
			(xy 390.773376 -305.718553) (xy 390.724477 -305.702665) (xy 390.678665 -305.679322) (xy 390.637069 -305.649101)
			(xy 390.600713 -305.612745) (xy 390.570492 -305.571149) (xy 390.547149 -305.525337) (xy 390.531261 -305.476438)
			(xy 390.523218 -305.425656) (xy 390.226554 -305.425656) (xy 390.218511 -305.476438) (xy 390.202623 -305.525337)
			(xy 390.17928 -305.571149) (xy 390.149059 -305.612745) (xy 390.112703 -305.649101) (xy 390.071107 -305.679322)
			(xy 390.025295 -305.702665) (xy 389.976396 -305.718553) (xy 389.925614 -305.726596) (xy 389.874198 -305.726596)
			(xy 389.823416 -305.718553) (xy 389.774517 -305.702665) (xy 389.728705 -305.679322) (xy 389.687109 -305.649101)
			(xy 389.650753 -305.612745) (xy 389.620532 -305.571149) (xy 389.597189 -305.525337) (xy 389.581301 -305.476438)
			(xy 389.573258 -305.425656) (xy 389.25458 -305.425656) (xy 389.246864 -305.473132) (xy 389.23128 -305.519813)
			(xy 389.208409 -305.56339) (xy 389.178844 -305.602734) (xy 389.143351 -305.636826) (xy 389.102848 -305.664782)
			(xy 389.058386 -305.68588) (xy 389.011115 -305.699572) (xy 388.96226 -305.705504) (xy 388.913085 -305.703523)
			(xy 388.864866 -305.693679) (xy 388.81885 -305.676227) (xy 388.776229 -305.65162) (xy 388.738108 -305.620495)
			(xy 388.705473 -305.583658) (xy 388.67917 -305.542062) (xy 388.659879 -305.496786) (xy 388.648102 -305.449002)
			(xy 388.644142 -305.399948) (xy 388.327138 -305.399948) (xy 388.326634 -305.425656) (xy 388.318591 -305.476438)
			(xy 388.302703 -305.525337) (xy 388.27936 -305.571149) (xy 388.249139 -305.612745) (xy 388.212783 -305.649101)
			(xy 388.171187 -305.679322) (xy 388.125375 -305.702665) (xy 388.076476 -305.718553) (xy 388.025694 -305.726596)
			(xy 387.974278 -305.726596) (xy 387.923496 -305.718553) (xy 387.874597 -305.702665) (xy 387.828785 -305.679322)
			(xy 387.787189 -305.649101) (xy 387.750833 -305.612745) (xy 387.720612 -305.571149) (xy 387.697269 -305.525337)
			(xy 387.681381 -305.476438) (xy 387.673338 -305.425656) (xy 387.376674 -305.425656) (xy 387.368631 -305.476438)
			(xy 387.352743 -305.525337) (xy 387.3294 -305.571149) (xy 387.299179 -305.612745) (xy 387.262823 -305.649101)
			(xy 387.221227 -305.679322) (xy 387.175415 -305.702665) (xy 387.126516 -305.718553) (xy 387.075734 -305.726596)
			(xy 387.024318 -305.726596) (xy 386.973536 -305.718553) (xy 386.924637 -305.702665) (xy 386.878825 -305.679322)
			(xy 386.837229 -305.649101) (xy 386.800873 -305.612745) (xy 386.770652 -305.571149) (xy 386.747309 -305.525337)
			(xy 386.731421 -305.476438) (xy 386.723378 -305.425656) (xy 386.404446 -305.425656) (xy 386.39673 -305.473132)
			(xy 386.381146 -305.519813) (xy 386.358275 -305.56339) (xy 386.32871 -305.602734) (xy 386.293217 -305.636826)
			(xy 386.252714 -305.664782) (xy 386.208252 -305.68588) (xy 386.160981 -305.699572) (xy 386.112126 -305.705504)
			(xy 386.062951 -305.703523) (xy 386.014732 -305.693679) (xy 385.968716 -305.676227) (xy 385.926095 -305.65162)
			(xy 385.887974 -305.620495) (xy 385.855339 -305.583658) (xy 385.829036 -305.542062) (xy 385.809745 -305.496786)
			(xy 385.797968 -305.449002) (xy 385.794008 -305.399948) (xy 385.45516 -305.399948) (xy 385.454665 -305.424555)
			(xy 385.44677 -305.473132) (xy 385.431186 -305.519813) (xy 385.408315 -305.56339) (xy 385.37875 -305.602734)
			(xy 385.343257 -305.636826) (xy 385.302754 -305.664782) (xy 385.258292 -305.68588) (xy 385.211021 -305.699572)
			(xy 385.162166 -305.705504) (xy 385.112991 -305.703523) (xy 385.064772 -305.693679) (xy 385.018756 -305.676227)
			(xy 384.976135 -305.65162) (xy 384.938014 -305.620495) (xy 384.905379 -305.583658) (xy 384.879076 -305.542062)
			(xy 384.859785 -305.496786) (xy 384.848008 -305.449002) (xy 384.844048 -305.399948) (xy 376.46695 -305.399948)
			(xy 376.464733 -305.415379) (xy 376.449379 -305.467686) (xy 376.426737 -305.517275) (xy 376.397268 -305.563137)
			(xy 376.361571 -305.604338) (xy 376.320374 -305.64004) (xy 376.274516 -305.669514) (xy 376.224929 -305.692162)
			(xy 376.172624 -305.707523) (xy 376.118666 -305.715282) (xy 376.064152 -305.715284) (xy 376.010193 -305.707526)
			(xy 375.957887 -305.692168) (xy 375.908299 -305.669523) (xy 375.862439 -305.64005) (xy 375.821241 -305.60435)
			(xy 375.785543 -305.563151) (xy 375.756072 -305.51729) (xy 375.733427 -305.467702) (xy 375.718071 -305.415396)
			(xy 375.710316 -305.361436) (xy 365.203422 -305.361436) (xy 365.192454 -305.366445) (xy 365.140159 -305.3818)
			(xy 365.086211 -305.389556) (xy 365.031709 -305.389556) (xy 364.977761 -305.3818) (xy 364.925466 -305.366445)
			(xy 364.875889 -305.343803) (xy 364.830039 -305.314337) (xy 364.788848 -305.278646) (xy 364.753157 -305.237455)
			(xy 364.723691 -305.191605) (xy 364.701049 -305.142028) (xy 364.685694 -305.089733) (xy 364.677938 -305.035785)
			(xy 364.677452 -305.008534) (xy 360.632248 -305.008534) (xy 360.631762 -305.035785) (xy 360.624006 -305.089733)
			(xy 360.608651 -305.142028) (xy 360.586009 -305.191605) (xy 360.556543 -305.237455) (xy 360.520852 -305.278646)
			(xy 360.479661 -305.314337) (xy 360.433811 -305.343803) (xy 360.384234 -305.366445) (xy 360.331939 -305.3818)
			(xy 360.277991 -305.389556) (xy 360.223489 -305.389556) (xy 360.169541 -305.3818) (xy 360.117246 -305.366445)
			(xy 360.067669 -305.343803) (xy 360.021819 -305.314337) (xy 359.980628 -305.278646) (xy 359.944937 -305.237455)
			(xy 359.915471 -305.191605) (xy 359.892829 -305.142028) (xy 359.877474 -305.089733) (xy 359.869718 -305.035785)
			(xy 359.869232 -305.008534) (xy 358.600248 -305.008534) (xy 358.599762 -305.035785) (xy 358.592006 -305.089733)
			(xy 358.576651 -305.142028) (xy 358.554009 -305.191605) (xy 358.524543 -305.237455) (xy 358.488852 -305.278646)
			(xy 358.447661 -305.314337) (xy 358.401811 -305.343803) (xy 358.352234 -305.366445) (xy 358.299939 -305.3818)
			(xy 358.245991 -305.389556) (xy 358.191489 -305.389556) (xy 358.137541 -305.3818) (xy 358.085246 -305.366445)
			(xy 358.035669 -305.343803) (xy 357.989819 -305.314337) (xy 357.948628 -305.278646) (xy 357.912937 -305.237455)
			(xy 357.883471 -305.191605) (xy 357.860829 -305.142028) (xy 357.845474 -305.089733) (xy 357.837718 -305.035785)
			(xy 357.837232 -305.008534) (xy 357.212138 -305.008534) (xy 357.211652 -305.035785) (xy 357.203896 -305.089733)
			(xy 357.188541 -305.142028) (xy 357.165899 -305.191605) (xy 357.136433 -305.237455) (xy 357.100742 -305.278646)
			(xy 357.059551 -305.314337) (xy 357.013701 -305.343803) (xy 356.964124 -305.366445) (xy 356.911829 -305.3818)
			(xy 356.857881 -305.389556) (xy 356.803379 -305.389556) (xy 356.749431 -305.3818) (xy 356.697136 -305.366445)
			(xy 356.647559 -305.343803) (xy 356.601709 -305.314337) (xy 356.560518 -305.278646) (xy 356.524827 -305.237455)
			(xy 356.495361 -305.191605) (xy 356.472719 -305.142028) (xy 356.457364 -305.089733) (xy 356.449608 -305.035785)
			(xy 356.449122 -305.008534) (xy 353.792028 -305.008534) (xy 353.791542 -305.035785) (xy 353.783786 -305.089733)
			(xy 353.768431 -305.142028) (xy 353.745789 -305.191605) (xy 353.716323 -305.237455) (xy 353.680632 -305.278646)
			(xy 353.639441 -305.314337) (xy 353.593591 -305.343803) (xy 353.544014 -305.366445) (xy 353.491719 -305.3818)
			(xy 353.437771 -305.389556) (xy 353.383269 -305.389556) (xy 353.329321 -305.3818) (xy 353.277026 -305.366445)
			(xy 353.227449 -305.343803) (xy 353.181599 -305.314337) (xy 353.140408 -305.278646) (xy 353.104717 -305.237455)
			(xy 353.075251 -305.191605) (xy 353.052609 -305.142028) (xy 353.037254 -305.089733) (xy 353.029498 -305.035785)
			(xy 353.029012 -305.008534) (xy 351.031048 -305.008534) (xy 351.031048 -307.82387) (xy 353.617022 -307.82387)
			(xy 353.617465 -307.796499) (xy 353.625288 -307.742319) (xy 353.640782 -307.689815) (xy 353.663629 -307.640069)
			(xy 353.693358 -307.594103) (xy 353.711002 -307.573172) (xy 353.717098 -307.56606) (xy 353.723448 -307.549042)
			(xy 353.723448 -307.463698) (xy 353.717098 -307.44668) (xy 353.711002 -307.439568) (xy 353.693333 -307.418659)
			(xy 353.663611 -307.372686) (xy 353.640769 -307.322936) (xy 353.625276 -307.27043) (xy 353.617451 -307.216249)
			(xy 353.617454 -307.161506) (xy 353.625286 -307.107325) (xy 353.640785 -307.054822) (xy 353.663633 -307.005074)
			(xy 353.69336 -306.959105) (xy 353.711002 -306.938172) (xy 353.717098 -306.93106) (xy 353.723448 -306.914042)
			(xy 353.723448 -306.828698) (xy 353.717098 -306.81168) (xy 353.711002 -306.804568) (xy 353.693333 -306.783659)
			(xy 353.663611 -306.737686) (xy 353.640769 -306.687936) (xy 353.625276 -306.63543) (xy 353.617451 -306.581249)
			(xy 353.617454 -306.526506) (xy 353.625286 -306.472325) (xy 353.640785 -306.419822) (xy 353.663633 -306.370074)
			(xy 353.69336 -306.324105) (xy 353.711002 -306.303172) (xy 353.717098 -306.29606) (xy 353.723448 -306.279042)
			(xy 353.723448 -306.193698) (xy 353.717098 -306.17668) (xy 353.711002 -306.169568) (xy 353.693382 -306.148621)
			(xy 353.663667 -306.102652) (xy 353.640827 -306.052909) (xy 353.625332 -306.000411) (xy 353.617499 -305.946238)
			(xy 353.617022 -305.91887) (xy 353.617508 -305.891619) (xy 353.625264 -305.837671) (xy 353.640619 -305.785376)
			(xy 353.663261 -305.735799) (xy 353.692727 -305.689949) (xy 353.728418 -305.648758) (xy 353.769609 -305.613067)
			(xy 353.815459 -305.583601) (xy 353.865036 -305.560959) (xy 353.917331 -305.545604) (xy 353.971279 -305.537848)
			(xy 354.025781 -305.537848) (xy 354.079729 -305.545604) (xy 354.132024 -305.560959) (xy 354.181601 -305.583601)
			(xy 354.227451 -305.613067) (xy 354.268642 -305.648758) (xy 354.304333 -305.689949) (xy 354.333799 -305.735799)
			(xy 354.356441 -305.785376) (xy 354.371796 -305.837671) (xy 354.379552 -305.891619) (xy 354.380038 -305.91887)
			(xy 354.379569 -305.94624) (xy 354.371755 -306.00042) (xy 354.356267 -306.052924) (xy 354.333425 -306.102671)
			(xy 354.3037 -306.148637) (xy 354.286058 -306.169568) (xy 354.279962 -306.17668) (xy 354.273612 -306.193698)
			(xy 354.273612 -306.279042) (xy 354.279962 -306.29606) (xy 354.286058 -306.303172) (xy 354.30367 -306.324128)
			(xy 354.333397 -306.370092) (xy 354.356245 -306.419834) (xy 354.371744 -306.472332) (xy 354.379576 -306.526508)
			(xy 354.379579 -306.581247) (xy 354.371754 -306.635423) (xy 354.356261 -306.687924) (xy 354.333419 -306.737669)
			(xy 354.303697 -306.783636) (xy 354.286058 -306.804568) (xy 354.279962 -306.81168) (xy 354.273612 -306.828698)
			(xy 354.273612 -306.914042) (xy 354.279962 -306.93106) (xy 354.286058 -306.938172) (xy 354.30367 -306.959128)
			(xy 354.333397 -307.005092) (xy 354.356245 -307.054834) (xy 354.371744 -307.107332) (xy 354.379576 -307.161508)
			(xy 354.379579 -307.216247) (xy 354.371754 -307.270423) (xy 354.356261 -307.322924) (xy 354.333419 -307.372669)
			(xy 354.303697 -307.418636) (xy 354.286058 -307.439568) (xy 354.279962 -307.44668) (xy 354.273612 -307.463698)
			(xy 354.273612 -307.549042) (xy 354.279962 -307.56606) (xy 354.286058 -307.573172) (xy 354.303691 -307.594109)
			(xy 354.333405 -307.64008) (xy 354.356243 -307.689826) (xy 354.371735 -307.742326) (xy 354.379564 -307.796501)
			(xy 354.380038 -307.82387) (xy 354.379552 -307.851121) (xy 354.375728 -307.877718) (xy 357.249222 -307.877718)
			(xy 357.249693 -307.850348) (xy 357.257509 -307.796169) (xy 357.272997 -307.743666) (xy 357.295837 -307.693919)
			(xy 357.325561 -307.647952) (xy 357.343202 -307.62702) (xy 357.349298 -307.619908) (xy 357.355648 -307.60289)
			(xy 357.355648 -307.517546) (xy 357.349298 -307.500528) (xy 357.343202 -307.493416) (xy 357.32558 -307.472468)
			(xy 357.295856 -307.426503) (xy 357.273011 -307.376759) (xy 357.257515 -307.324259) (xy 357.249685 -307.270083)
			(xy 357.249683 -307.215344) (xy 357.257509 -307.161167) (xy 357.273002 -307.108667) (xy 357.295843 -307.058921)
			(xy 357.325564 -307.012953) (xy 357.343202 -306.99202) (xy 357.349298 -306.984908) (xy 357.355648 -306.96789)
			(xy 357.355648 -306.882546) (xy 357.349298 -306.865528) (xy 357.343202 -306.858416) (xy 357.32558 -306.837468)
			(xy 357.295856 -306.791503) (xy 357.273011 -306.741759) (xy 357.257515 -306.689259) (xy 357.249685 -306.635083)
			(xy 357.249683 -306.580344) (xy 357.257509 -306.526167) (xy 357.273002 -306.473667) (xy 357.295843 -306.423921)
			(xy 357.325564 -306.377953) (xy 357.343202 -306.35702) (xy 357.349298 -306.349908) (xy 357.355648 -306.33289)
			(xy 357.355648 -306.247546) (xy 357.349298 -306.230528) (xy 357.343202 -306.223416) (xy 357.325557 -306.202488)
			(xy 357.295846 -306.156514) (xy 357.273011 -306.106766) (xy 357.257522 -306.054264) (xy 357.249695 -306.000087)
			(xy 357.249222 -305.972718) (xy 357.249708 -305.945467) (xy 357.257464 -305.891519) (xy 357.272819 -305.839224)
			(xy 357.295461 -305.789647) (xy 357.324927 -305.743797) (xy 357.360618 -305.702606) (xy 357.401809 -305.666915)
			(xy 357.447659 -305.637449) (xy 357.497236 -305.614807) (xy 357.549531 -305.599452) (xy 357.603479 -305.591696)
			(xy 357.657981 -305.591696) (xy 357.711929 -305.599452) (xy 357.764224 -305.614807) (xy 357.813801 -305.637449)
			(xy 357.859651 -305.666915) (xy 357.900842 -305.702606) (xy 357.936533 -305.743797) (xy 357.965999 -305.789647)
			(xy 357.988641 -305.839224) (xy 358.003996 -305.891519) (xy 358.011752 -305.945467) (xy 358.012238 -305.972718)
			(xy 358.011798 -306.000089) (xy 358.003976 -306.05427) (xy 357.988482 -306.106774) (xy 357.965634 -306.156521)
			(xy 357.935903 -306.202486) (xy 357.918258 -306.223416) (xy 357.912162 -306.230528) (xy 357.905812 -306.247546)
			(xy 357.905812 -306.33289) (xy 357.912162 -306.349908) (xy 357.918258 -306.35702) (xy 357.935917 -306.377938)
			(xy 357.965642 -306.423908) (xy 357.988487 -306.473657) (xy 358.003983 -306.526161) (xy 358.01181 -306.580342)
			(xy 358.011808 -306.635085) (xy 358.003977 -306.689265) (xy 357.988478 -306.741769) (xy 357.965629 -306.791516)
			(xy 357.935901 -306.837484) (xy 357.918258 -306.858416) (xy 357.912162 -306.865528) (xy 357.905812 -306.882546)
			(xy 357.905812 -306.96789) (xy 357.912162 -306.984908) (xy 357.918258 -306.99202) (xy 357.935917 -307.012938)
			(xy 357.965642 -307.058908) (xy 357.988487 -307.108657) (xy 358.003983 -307.161161) (xy 358.007986 -307.18887)
			(xy 360.457242 -307.18887) (xy 360.45768 -307.161499) (xy 360.465503 -307.107318) (xy 360.480998 -307.054814)
			(xy 360.503846 -307.005068) (xy 360.533578 -306.959102) (xy 360.551222 -306.938172) (xy 360.557318 -306.93106)
			(xy 360.563668 -306.914042) (xy 360.563668 -306.828698) (xy 360.557318 -306.81168) (xy 360.551222 -306.804568)
			(xy 360.533552 -306.783659) (xy 360.503829 -306.737687) (xy 360.480986 -306.687937) (xy 360.465492 -306.635431)
			(xy 360.457666 -306.581249) (xy 360.457669 -306.526505) (xy 360.465502 -306.472325) (xy 360.481002 -306.419821)
			(xy 360.503851 -306.370073) (xy 360.533579 -306.324105) (xy 360.551222 -306.303172) (xy 360.557318 -306.29606)
			(xy 360.563668 -306.279042) (xy 360.563668 -306.193698) (xy 360.557318 -306.17668) (xy 360.551222 -306.169568)
			(xy 360.533605 -306.148618) (xy 360.503889 -306.102651) (xy 360.481048 -306.052908) (xy 360.465552 -306.000411)
			(xy 360.457719 -305.946238) (xy 360.457242 -305.91887) (xy 360.457728 -305.891619) (xy 360.465484 -305.837671)
			(xy 360.480839 -305.785376) (xy 360.503481 -305.735799) (xy 360.532947 -305.689949) (xy 360.568638 -305.648758)
			(xy 360.609829 -305.613067) (xy 360.655679 -305.583601) (xy 360.705256 -305.560959) (xy 360.757551 -305.545604)
			(xy 360.811499 -305.537848) (xy 360.866001 -305.537848) (xy 360.919949 -305.545604) (xy 360.972244 -305.560959)
			(xy 361.021821 -305.583601) (xy 361.067671 -305.613067) (xy 361.108862 -305.648758) (xy 361.144553 -305.689949)
			(xy 361.174019 -305.735799) (xy 361.196661 -305.785376) (xy 361.212016 -305.837671) (xy 361.219772 -305.891619)
			(xy 361.220258 -305.91887) (xy 361.219785 -305.94624) (xy 361.21197 -306.000419) (xy 361.196483 -306.052923)
			(xy 361.173643 -306.10267) (xy 361.143919 -306.148636) (xy 361.126278 -306.169568) (xy 361.120182 -306.17668)
			(xy 361.113832 -306.193698) (xy 361.113832 -306.279042) (xy 361.120182 -306.29606) (xy 361.126278 -306.303172)
			(xy 361.143889 -306.324129) (xy 361.173615 -306.370092) (xy 361.196462 -306.419835) (xy 361.21196 -306.472333)
			(xy 361.219791 -306.526508) (xy 361.219794 -306.581247) (xy 361.21197 -306.635423) (xy 361.196477 -306.687923)
			(xy 361.173637 -306.737668) (xy 361.143916 -306.783635) (xy 361.126278 -306.804568) (xy 361.120182 -306.81168)
			(xy 361.113832 -306.828698) (xy 361.113832 -306.914042) (xy 361.120182 -306.93106) (xy 361.126278 -306.938172)
			(xy 361.143914 -306.959107) (xy 361.173627 -307.005078) (xy 361.196464 -307.054825) (xy 361.211956 -307.107325)
			(xy 361.219784 -307.161501) (xy 361.220258 -307.18887) (xy 361.219772 -307.216121) (xy 361.212016 -307.270069)
			(xy 361.196661 -307.322364) (xy 361.174019 -307.371941) (xy 361.144553 -307.417791) (xy 361.108862 -307.458982)
			(xy 361.067671 -307.494673) (xy 361.021821 -307.524139) (xy 360.972244 -307.546781) (xy 360.919949 -307.562136)
			(xy 360.866001 -307.569892) (xy 360.811499 -307.569892) (xy 360.757551 -307.562136) (xy 360.705256 -307.546781)
			(xy 360.655679 -307.524139) (xy 360.609829 -307.494673) (xy 360.568638 -307.458982) (xy 360.532947 -307.417791)
			(xy 360.503481 -307.371941) (xy 360.480839 -307.322364) (xy 360.465484 -307.270069) (xy 360.457728 -307.216121)
			(xy 360.457242 -307.18887) (xy 358.007986 -307.18887) (xy 358.01181 -307.215342) (xy 358.011808 -307.270085)
			(xy 358.003977 -307.324265) (xy 357.988478 -307.376769) (xy 357.965629 -307.426516) (xy 357.935901 -307.472484)
			(xy 357.918258 -307.493416) (xy 357.912162 -307.500528) (xy 357.905812 -307.517546) (xy 357.905812 -307.60289)
			(xy 357.912162 -307.619908) (xy 357.918258 -307.62702) (xy 357.935867 -307.647977) (xy 357.965584 -307.693942)
			(xy 357.988427 -307.743683) (xy 358.003925 -307.796179) (xy 358.01176 -307.85035) (xy 358.012238 -307.877718)
			(xy 364.089442 -307.877718) (xy 364.089908 -307.850348) (xy 364.097725 -307.796168) (xy 364.113213 -307.743665)
			(xy 364.136055 -307.693918) (xy 364.16578 -307.647951) (xy 364.183422 -307.62702) (xy 364.189518 -307.619908)
			(xy 364.195868 -307.60289) (xy 364.195868 -307.517546) (xy 364.189518 -307.500528) (xy 364.183422 -307.493416)
			(xy 364.165799 -307.472469) (xy 364.136074 -307.426503) (xy 364.113228 -307.37676) (xy 364.09773 -307.32426)
			(xy 364.0899 -307.270083) (xy 364.089898 -307.215344) (xy 364.097725 -307.161167) (xy 364.113218 -307.108666)
			(xy 364.136061 -307.05892) (xy 364.165783 -307.012953) (xy 364.183422 -306.99202) (xy 364.189518 -306.984908)
			(xy 364.195868 -306.96789) (xy 364.195868 -306.882546) (xy 364.189518 -306.865528) (xy 364.183422 -306.858416)
			(xy 364.165799 -306.837469) (xy 364.136074 -306.791503) (xy 364.113228 -306.74176) (xy 364.09773 -306.68926)
			(xy 364.0899 -306.635083) (xy 364.089898 -306.580344) (xy 364.097725 -306.526167) (xy 364.113218 -306.473666)
			(xy 364.136061 -306.42392) (xy 364.165783 -306.377953) (xy 364.183422 -306.35702) (xy 364.189518 -306.349908)
			(xy 364.195868 -306.33289) (xy 364.195868 -306.247546) (xy 364.189518 -306.230528) (xy 364.183422 -306.223416)
			(xy 364.16578 -306.202486) (xy 364.136068 -306.156513) (xy 364.113232 -306.106765) (xy 364.097742 -306.054264)
			(xy 364.089915 -306.000087) (xy 364.089442 -305.972718) (xy 364.089928 -305.945467) (xy 364.097684 -305.891519)
			(xy 364.113039 -305.839224) (xy 364.135681 -305.789647) (xy 364.165147 -305.743797) (xy 364.200838 -305.702606)
			(xy 364.242029 -305.666915) (xy 364.287879 -305.637449) (xy 364.337456 -305.614807) (xy 364.389751 -305.599452)
			(xy 364.443699 -305.591696) (xy 364.498201 -305.591696) (xy 364.552149 -305.599452) (xy 364.604444 -305.614807)
			(xy 364.654021 -305.637449) (xy 364.699871 -305.666915) (xy 364.741062 -305.702606) (xy 364.776753 -305.743797)
			(xy 364.806219 -305.789647) (xy 364.828861 -305.839224) (xy 364.844216 -305.891519) (xy 364.851972 -305.945467)
			(xy 364.852458 -305.972718) (xy 364.852013 -306.000089) (xy 364.844413 -306.052728) (xy 374.990866 -306.052728)
			(xy 374.994937 -305.997106) (xy 375.007063 -305.942669) (xy 375.026986 -305.890578) (xy 375.054282 -305.841943)
			(xy 375.088368 -305.7978) (xy 375.128517 -305.759091) (xy 375.173875 -305.72664) (xy 375.223475 -305.701139)
			(xy 375.276259 -305.683132) (xy 375.331102 -305.673002) (xy 375.386836 -305.670965) (xy 375.442273 -305.677065)
			(xy 375.49623 -305.691171) (xy 375.547559 -305.712983) (xy 375.595165 -305.742037) (xy 375.638033 -305.777712)
			(xy 375.67525 -305.819249) (xy 375.706023 -305.865762) (xy 375.71032 -305.874928) (xy 394.819136 -305.874928)
			(xy 394.823096 -305.825874) (xy 394.834873 -305.77809) (xy 394.854164 -305.732814) (xy 394.880467 -305.691218)
			(xy 394.913102 -305.654381) (xy 394.951223 -305.623256) (xy 394.993844 -305.598649) (xy 395.03986 -305.581197)
			(xy 395.088079 -305.571353) (xy 395.137254 -305.569372) (xy 395.186109 -305.575304) (xy 395.23338 -305.588996)
			(xy 395.277842 -305.610094) (xy 395.318345 -305.63805) (xy 395.353838 -305.672142) (xy 395.383403 -305.711486)
			(xy 395.406274 -305.755063) (xy 395.421858 -305.801744) (xy 395.429753 -305.850321) (xy 395.430248 -305.874928)
			(xy 395.769096 -305.874928) (xy 395.773056 -305.825874) (xy 395.784833 -305.77809) (xy 395.804124 -305.732814)
			(xy 395.830427 -305.691218) (xy 395.863062 -305.654381) (xy 395.901183 -305.623256) (xy 395.943804 -305.598649)
			(xy 395.98982 -305.581197) (xy 396.038039 -305.571353) (xy 396.087214 -305.569372) (xy 396.136069 -305.575304)
			(xy 396.18334 -305.588996) (xy 396.227802 -305.610094) (xy 396.268305 -305.63805) (xy 396.303798 -305.672142)
			(xy 396.333363 -305.711486) (xy 396.356234 -305.755063) (xy 396.371818 -305.801744) (xy 396.379713 -305.850321)
			(xy 396.380208 -305.874928) (xy 396.719056 -305.874928) (xy 396.723016 -305.825874) (xy 396.734793 -305.77809)
			(xy 396.754084 -305.732814) (xy 396.780387 -305.691218) (xy 396.813022 -305.654381) (xy 396.851143 -305.623256)
			(xy 396.893764 -305.598649) (xy 396.93978 -305.581197) (xy 396.987999 -305.571353) (xy 397.037174 -305.569372)
			(xy 397.086029 -305.575304) (xy 397.1333 -305.588996) (xy 397.177762 -305.610094) (xy 397.218265 -305.63805)
			(xy 397.253758 -305.672142) (xy 397.283323 -305.711486) (xy 397.306194 -305.755063) (xy 397.321778 -305.801744)
			(xy 397.329673 -305.850321) (xy 397.330168 -305.874928) (xy 397.329673 -305.899535) (xy 397.321778 -305.948112)
			(xy 397.306194 -305.994793) (xy 397.283323 -306.03837) (xy 397.253758 -306.077714) (xy 397.218265 -306.111806)
			(xy 397.177762 -306.139762) (xy 397.1333 -306.16086) (xy 397.086029 -306.174552) (xy 397.037174 -306.180484)
			(xy 396.987999 -306.178503) (xy 396.93978 -306.168659) (xy 396.893764 -306.151207) (xy 396.851143 -306.1266)
			(xy 396.813022 -306.095475) (xy 396.780387 -306.058638) (xy 396.754084 -306.017042) (xy 396.734793 -305.971766)
			(xy 396.723016 -305.923982) (xy 396.719056 -305.874928) (xy 396.380208 -305.874928) (xy 396.379713 -305.899535)
			(xy 396.371818 -305.948112) (xy 396.356234 -305.994793) (xy 396.333363 -306.03837) (xy 396.303798 -306.077714)
			(xy 396.268305 -306.111806) (xy 396.227802 -306.139762) (xy 396.18334 -306.16086) (xy 396.136069 -306.174552)
			(xy 396.087214 -306.180484) (xy 396.038039 -306.178503) (xy 395.98982 -306.168659) (xy 395.943804 -306.151207)
			(xy 395.901183 -306.1266) (xy 395.863062 -306.095475) (xy 395.830427 -306.058638) (xy 395.804124 -306.017042)
			(xy 395.784833 -305.971766) (xy 395.773056 -305.923982) (xy 395.769096 -305.874928) (xy 395.430248 -305.874928)
			(xy 395.429753 -305.899535) (xy 395.421858 -305.948112) (xy 395.406274 -305.994793) (xy 395.383403 -306.03837)
			(xy 395.353838 -306.077714) (xy 395.318345 -306.111806) (xy 395.277842 -306.139762) (xy 395.23338 -306.16086)
			(xy 395.186109 -306.174552) (xy 395.137254 -306.180484) (xy 395.088079 -306.178503) (xy 395.03986 -306.168659)
			(xy 394.993844 -306.151207) (xy 394.951223 -306.1266) (xy 394.913102 -306.095475) (xy 394.880467 -306.058638)
			(xy 394.854164 -306.017042) (xy 394.834873 -305.971766) (xy 394.823096 -305.923982) (xy 394.819136 -305.874928)
			(xy 375.71032 -305.874928) (xy 375.729695 -305.916259) (xy 375.745763 -305.969666) (xy 375.753883 -306.024842)
			(xy 375.754392 -306.052728) (xy 375.753883 -306.080614) (xy 375.745763 -306.13579) (xy 375.729695 -306.189197)
			(xy 375.706023 -306.239694) (xy 375.67525 -306.286207) (xy 375.638033 -306.327744) (xy 375.611095 -306.350162)
			(xy 383.893834 -306.350162) (xy 383.897794 -306.301108) (xy 383.909571 -306.253324) (xy 383.928862 -306.208048)
			(xy 383.955165 -306.166452) (xy 383.9878 -306.129615) (xy 384.025921 -306.09849) (xy 384.068542 -306.073883)
			(xy 384.114558 -306.056431) (xy 384.162777 -306.046587) (xy 384.211952 -306.044606) (xy 384.260807 -306.050538)
			(xy 384.308078 -306.06423) (xy 384.35254 -306.085328) (xy 384.393043 -306.113284) (xy 384.428536 -306.147376)
			(xy 384.458101 -306.18672) (xy 384.480972 -306.230297) (xy 384.496556 -306.276978) (xy 384.504451 -306.325555)
			(xy 384.504946 -306.350162) (xy 384.504451 -306.374769) (xy 384.504313 -306.375616) (xy 384.823204 -306.375616)
			(xy 384.823204 -306.3242) (xy 384.831247 -306.273418) (xy 384.847135 -306.224519) (xy 384.870478 -306.178707)
			(xy 384.900699 -306.137111) (xy 384.937055 -306.100755) (xy 384.978651 -306.070534) (xy 385.024463 -306.047191)
			(xy 385.073362 -306.031303) (xy 385.124144 -306.02326) (xy 385.17556 -306.02326) (xy 385.226342 -306.031303)
			(xy 385.275241 -306.047191) (xy 385.321053 -306.070534) (xy 385.362649 -306.100755) (xy 385.399005 -306.137111)
			(xy 385.429226 -306.178707) (xy 385.452569 -306.224519) (xy 385.468457 -306.273418) (xy 385.4765 -306.3242)
			(xy 385.477004 -306.349908) (xy 385.4765 -306.375616) (xy 385.773164 -306.375616) (xy 385.773164 -306.3242)
			(xy 385.781207 -306.273418) (xy 385.797095 -306.224519) (xy 385.820438 -306.178707) (xy 385.850659 -306.137111)
			(xy 385.887015 -306.100755) (xy 385.928611 -306.070534) (xy 385.974423 -306.047191) (xy 386.023322 -306.031303)
			(xy 386.074104 -306.02326) (xy 386.12552 -306.02326) (xy 386.176302 -306.031303) (xy 386.225201 -306.047191)
			(xy 386.271013 -306.070534) (xy 386.312609 -306.100755) (xy 386.348965 -306.137111) (xy 386.379186 -306.178707)
			(xy 386.402529 -306.224519) (xy 386.418417 -306.273418) (xy 386.42646 -306.3242) (xy 386.426964 -306.349908)
			(xy 386.744222 -306.349908) (xy 386.748182 -306.300854) (xy 386.759959 -306.25307) (xy 386.77925 -306.207794)
			(xy 386.805553 -306.166198) (xy 386.838188 -306.129361) (xy 386.876309 -306.098236) (xy 386.91893 -306.073629)
			(xy 386.964946 -306.056177) (xy 387.013165 -306.046333) (xy 387.06234 -306.044352) (xy 387.111195 -306.050284)
			(xy 387.158466 -306.063976) (xy 387.202928 -306.085074) (xy 387.243431 -306.11303) (xy 387.278924 -306.147122)
			(xy 387.308489 -306.186466) (xy 387.33136 -306.230043) (xy 387.346944 -306.276724) (xy 387.354839 -306.325301)
			(xy 387.355334 -306.349908) (xy 387.694182 -306.349908) (xy 387.698142 -306.300854) (xy 387.709919 -306.25307)
			(xy 387.72921 -306.207794) (xy 387.755513 -306.166198) (xy 387.788148 -306.129361) (xy 387.826269 -306.098236)
			(xy 387.86889 -306.073629) (xy 387.914906 -306.056177) (xy 387.963125 -306.046333) (xy 388.0123 -306.044352)
			(xy 388.061155 -306.050284) (xy 388.108426 -306.063976) (xy 388.152888 -306.085074) (xy 388.193391 -306.11303)
			(xy 388.228884 -306.147122) (xy 388.258449 -306.186466) (xy 388.28132 -306.230043) (xy 388.296904 -306.276724)
			(xy 388.304799 -306.325301) (xy 388.305294 -306.349908) (xy 388.644142 -306.349908) (xy 388.648102 -306.300854)
			(xy 388.659879 -306.25307) (xy 388.67917 -306.207794) (xy 388.705473 -306.166198) (xy 388.738108 -306.129361)
			(xy 388.776229 -306.098236) (xy 388.81885 -306.073629) (xy 388.864866 -306.056177) (xy 388.913085 -306.046333)
			(xy 388.96226 -306.044352) (xy 389.011115 -306.050284) (xy 389.058386 -306.063976) (xy 389.102848 -306.085074)
			(xy 389.143351 -306.11303) (xy 389.178844 -306.147122) (xy 389.208409 -306.186466) (xy 389.23128 -306.230043)
			(xy 389.246864 -306.276724) (xy 389.254759 -306.325301) (xy 389.255254 -306.349908) (xy 389.594102 -306.349908)
			(xy 389.598062 -306.300854) (xy 389.609839 -306.25307) (xy 389.62913 -306.207794) (xy 389.655433 -306.166198)
			(xy 389.688068 -306.129361) (xy 389.726189 -306.098236) (xy 389.76881 -306.073629) (xy 389.814826 -306.056177)
			(xy 389.863045 -306.046333) (xy 389.91222 -306.044352) (xy 389.961075 -306.050284) (xy 390.008346 -306.063976)
			(xy 390.052808 -306.085074) (xy 390.093311 -306.11303) (xy 390.128804 -306.147122) (xy 390.158369 -306.186466)
			(xy 390.18124 -306.230043) (xy 390.196824 -306.276724) (xy 390.204719 -306.325301) (xy 390.205214 -306.349908)
			(xy 390.544062 -306.349908) (xy 390.548022 -306.300854) (xy 390.559799 -306.25307) (xy 390.57909 -306.207794)
			(xy 390.605393 -306.166198) (xy 390.638028 -306.129361) (xy 390.676149 -306.098236) (xy 390.71877 -306.073629)
			(xy 390.764786 -306.056177) (xy 390.813005 -306.046333) (xy 390.86218 -306.044352) (xy 390.911035 -306.050284)
			(xy 390.958306 -306.063976) (xy 391.002768 -306.085074) (xy 391.043271 -306.11303) (xy 391.078764 -306.147122)
			(xy 391.108329 -306.186466) (xy 391.1312 -306.230043) (xy 391.146784 -306.276724) (xy 391.154679 -306.325301)
			(xy 391.155174 -306.349908) (xy 391.154679 -306.374515) (xy 391.1545 -306.375616) (xy 391.473178 -306.375616)
			(xy 391.473178 -306.3242) (xy 391.481221 -306.273418) (xy 391.497109 -306.224519) (xy 391.520452 -306.178707)
			(xy 391.550673 -306.137111) (xy 391.587029 -306.100755) (xy 391.628625 -306.070534) (xy 391.674437 -306.047191)
			(xy 391.723336 -306.031303) (xy 391.774118 -306.02326) (xy 391.825534 -306.02326) (xy 391.876316 -306.031303)
			(xy 391.925215 -306.047191) (xy 391.971027 -306.070534) (xy 392.012623 -306.100755) (xy 392.048979 -306.137111)
			(xy 392.0792 -306.178707) (xy 392.102543 -306.224519) (xy 392.118431 -306.273418) (xy 392.126474 -306.3242)
			(xy 392.126978 -306.349908) (xy 392.126474 -306.375616) (xy 392.423138 -306.375616) (xy 392.423138 -306.3242)
			(xy 392.431181 -306.273418) (xy 392.447069 -306.224519) (xy 392.470412 -306.178707) (xy 392.500633 -306.137111)
			(xy 392.536989 -306.100755) (xy 392.578585 -306.070534) (xy 392.624397 -306.047191) (xy 392.673296 -306.031303)
			(xy 392.724078 -306.02326) (xy 392.775494 -306.02326) (xy 392.826276 -306.031303) (xy 392.875175 -306.047191)
			(xy 392.920987 -306.070534) (xy 392.962583 -306.100755) (xy 392.998939 -306.137111) (xy 393.02916 -306.178707)
			(xy 393.052503 -306.224519) (xy 393.068391 -306.273418) (xy 393.076434 -306.3242) (xy 393.076938 -306.349908)
			(xy 393.394196 -306.349908) (xy 393.398156 -306.300854) (xy 393.409933 -306.25307) (xy 393.429224 -306.207794)
			(xy 393.455527 -306.166198) (xy 393.488162 -306.129361) (xy 393.526283 -306.098236) (xy 393.568904 -306.073629)
			(xy 393.61492 -306.056177) (xy 393.663139 -306.046333) (xy 393.712314 -306.044352) (xy 393.761169 -306.050284)
			(xy 393.80844 -306.063976) (xy 393.852902 -306.085074) (xy 393.893405 -306.11303) (xy 393.928898 -306.147122)
			(xy 393.958463 -306.186466) (xy 393.981334 -306.230043) (xy 393.996918 -306.276724) (xy 394.004813 -306.325301)
			(xy 394.005308 -306.349908) (xy 394.004813 -306.374515) (xy 393.996918 -306.423092) (xy 393.981334 -306.469773)
			(xy 393.958463 -306.51335) (xy 393.928898 -306.552694) (xy 393.893405 -306.586786) (xy 393.852902 -306.614742)
			(xy 393.80844 -306.63584) (xy 393.761169 -306.649532) (xy 393.712314 -306.655464) (xy 393.663139 -306.653483)
			(xy 393.61492 -306.643639) (xy 393.568904 -306.626187) (xy 393.526283 -306.60158) (xy 393.488162 -306.570455)
			(xy 393.455527 -306.533618) (xy 393.429224 -306.492022) (xy 393.409933 -306.446746) (xy 393.398156 -306.398962)
			(xy 393.394196 -306.349908) (xy 393.076938 -306.349908) (xy 393.076434 -306.375616) (xy 393.068391 -306.426398)
			(xy 393.052503 -306.475297) (xy 393.02916 -306.521109) (xy 392.998939 -306.562705) (xy 392.962583 -306.599061)
			(xy 392.920987 -306.629282) (xy 392.875175 -306.652625) (xy 392.826276 -306.668513) (xy 392.775494 -306.676556)
			(xy 392.724078 -306.676556) (xy 392.673296 -306.668513) (xy 392.624397 -306.652625) (xy 392.578585 -306.629282)
			(xy 392.536989 -306.599061) (xy 392.500633 -306.562705) (xy 392.470412 -306.521109) (xy 392.447069 -306.475297)
			(xy 392.431181 -306.426398) (xy 392.423138 -306.375616) (xy 392.126474 -306.375616) (xy 392.118431 -306.426398)
			(xy 392.102543 -306.475297) (xy 392.0792 -306.521109) (xy 392.048979 -306.562705) (xy 392.012623 -306.599061)
			(xy 391.971027 -306.629282) (xy 391.925215 -306.652625) (xy 391.876316 -306.668513) (xy 391.825534 -306.676556)
			(xy 391.774118 -306.676556) (xy 391.723336 -306.668513) (xy 391.674437 -306.652625) (xy 391.628625 -306.629282)
			(xy 391.587029 -306.599061) (xy 391.550673 -306.562705) (xy 391.520452 -306.521109) (xy 391.497109 -306.475297)
			(xy 391.481221 -306.426398) (xy 391.473178 -306.375616) (xy 391.1545 -306.375616) (xy 391.146784 -306.423092)
			(xy 391.1312 -306.469773) (xy 391.108329 -306.51335) (xy 391.078764 -306.552694) (xy 391.043271 -306.586786)
			(xy 391.002768 -306.614742) (xy 390.958306 -306.63584) (xy 390.911035 -306.649532) (xy 390.86218 -306.655464)
			(xy 390.813005 -306.653483) (xy 390.764786 -306.643639) (xy 390.71877 -306.626187) (xy 390.676149 -306.60158)
			(xy 390.638028 -306.570455) (xy 390.605393 -306.533618) (xy 390.57909 -306.492022) (xy 390.559799 -306.446746)
			(xy 390.548022 -306.398962) (xy 390.544062 -306.349908) (xy 390.205214 -306.349908) (xy 390.204719 -306.374515)
			(xy 390.196824 -306.423092) (xy 390.18124 -306.469773) (xy 390.158369 -306.51335) (xy 390.128804 -306.552694)
			(xy 390.093311 -306.586786) (xy 390.052808 -306.614742) (xy 390.008346 -306.63584) (xy 389.961075 -306.649532)
			(xy 389.91222 -306.655464) (xy 389.863045 -306.653483) (xy 389.814826 -306.643639) (xy 389.76881 -306.626187)
			(xy 389.726189 -306.60158) (xy 389.688068 -306.570455) (xy 389.655433 -306.533618) (xy 389.62913 -306.492022)
			(xy 389.609839 -306.446746) (xy 389.598062 -306.398962) (xy 389.594102 -306.349908) (xy 389.255254 -306.349908)
			(xy 389.254759 -306.374515) (xy 389.246864 -306.423092) (xy 389.23128 -306.469773) (xy 389.208409 -306.51335)
			(xy 389.178844 -306.552694) (xy 389.143351 -306.586786) (xy 389.102848 -306.614742) (xy 389.058386 -306.63584)
			(xy 389.011115 -306.649532) (xy 388.96226 -306.655464) (xy 388.913085 -306.653483) (xy 388.864866 -306.643639)
			(xy 388.81885 -306.626187) (xy 388.776229 -306.60158) (xy 388.738108 -306.570455) (xy 388.705473 -306.533618)
			(xy 388.67917 -306.492022) (xy 388.659879 -306.446746) (xy 388.648102 -306.398962) (xy 388.644142 -306.349908)
			(xy 388.305294 -306.349908) (xy 388.304799 -306.374515) (xy 388.296904 -306.423092) (xy 388.28132 -306.469773)
			(xy 388.258449 -306.51335) (xy 388.228884 -306.552694) (xy 388.193391 -306.586786) (xy 388.152888 -306.614742)
			(xy 388.108426 -306.63584) (xy 388.061155 -306.649532) (xy 388.0123 -306.655464) (xy 387.963125 -306.653483)
			(xy 387.914906 -306.643639) (xy 387.86889 -306.626187) (xy 387.826269 -306.60158) (xy 387.788148 -306.570455)
			(xy 387.755513 -306.533618) (xy 387.72921 -306.492022) (xy 387.709919 -306.446746) (xy 387.698142 -306.398962)
			(xy 387.694182 -306.349908) (xy 387.355334 -306.349908) (xy 387.354839 -306.374515) (xy 387.346944 -306.423092)
			(xy 387.33136 -306.469773) (xy 387.308489 -306.51335) (xy 387.278924 -306.552694) (xy 387.243431 -306.586786)
			(xy 387.202928 -306.614742) (xy 387.158466 -306.63584) (xy 387.111195 -306.649532) (xy 387.06234 -306.655464)
			(xy 387.013165 -306.653483) (xy 386.964946 -306.643639) (xy 386.91893 -306.626187) (xy 386.876309 -306.60158)
			(xy 386.838188 -306.570455) (xy 386.805553 -306.533618) (xy 386.77925 -306.492022) (xy 386.759959 -306.446746)
			(xy 386.748182 -306.398962) (xy 386.744222 -306.349908) (xy 386.426964 -306.349908) (xy 386.42646 -306.375616)
			(xy 386.418417 -306.426398) (xy 386.402529 -306.475297) (xy 386.379186 -306.521109) (xy 386.348965 -306.562705)
			(xy 386.312609 -306.599061) (xy 386.271013 -306.629282) (xy 386.225201 -306.652625) (xy 386.176302 -306.668513)
			(xy 386.12552 -306.676556) (xy 386.074104 -306.676556) (xy 386.023322 -306.668513) (xy 385.974423 -306.652625)
			(xy 385.928611 -306.629282) (xy 385.887015 -306.599061) (xy 385.850659 -306.562705) (xy 385.820438 -306.521109)
			(xy 385.797095 -306.475297) (xy 385.781207 -306.426398) (xy 385.773164 -306.375616) (xy 385.4765 -306.375616)
			(xy 385.468457 -306.426398) (xy 385.452569 -306.475297) (xy 385.429226 -306.521109) (xy 385.399005 -306.562705)
			(xy 385.362649 -306.599061) (xy 385.321053 -306.629282) (xy 385.275241 -306.652625) (xy 385.226342 -306.668513)
			(xy 385.17556 -306.676556) (xy 385.124144 -306.676556) (xy 385.073362 -306.668513) (xy 385.024463 -306.652625)
			(xy 384.978651 -306.629282) (xy 384.937055 -306.599061) (xy 384.900699 -306.562705) (xy 384.870478 -306.521109)
			(xy 384.847135 -306.475297) (xy 384.831247 -306.426398) (xy 384.823204 -306.375616) (xy 384.504313 -306.375616)
			(xy 384.496556 -306.423346) (xy 384.480972 -306.470027) (xy 384.458101 -306.513604) (xy 384.428536 -306.552948)
			(xy 384.393043 -306.58704) (xy 384.35254 -306.614996) (xy 384.308078 -306.636094) (xy 384.260807 -306.649786)
			(xy 384.211952 -306.655718) (xy 384.162777 -306.653737) (xy 384.114558 -306.643893) (xy 384.068542 -306.626441)
			(xy 384.025921 -306.601834) (xy 383.9878 -306.570709) (xy 383.955165 -306.533872) (xy 383.928862 -306.492276)
			(xy 383.909571 -306.447) (xy 383.897794 -306.399216) (xy 383.893834 -306.350162) (xy 375.611095 -306.350162)
			(xy 375.595165 -306.363419) (xy 375.547559 -306.392473) (xy 375.49623 -306.414285) (xy 375.442273 -306.428391)
			(xy 375.386836 -306.434491) (xy 375.331102 -306.432454) (xy 375.276259 -306.422324) (xy 375.223475 -306.404317)
			(xy 375.173875 -306.378816) (xy 375.128517 -306.346365) (xy 375.088368 -306.307656) (xy 375.054282 -306.263513)
			(xy 375.026986 -306.214878) (xy 375.007063 -306.162787) (xy 374.994937 -306.10835) (xy 374.990866 -306.052728)
			(xy 364.844413 -306.052728) (xy 364.844191 -306.054269) (xy 364.828698 -306.106773) (xy 364.805851 -306.15652)
			(xy 364.776122 -306.202485) (xy 364.758478 -306.223416) (xy 364.752382 -306.230528) (xy 364.746032 -306.247546)
			(xy 364.746032 -306.33289) (xy 364.752382 -306.349908) (xy 364.758478 -306.35702) (xy 364.776136 -306.377939)
			(xy 364.80586 -306.423909) (xy 364.828704 -306.473658) (xy 364.844198 -306.526162) (xy 364.852025 -306.580342)
			(xy 364.852023 -306.635085) (xy 364.844193 -306.689265) (xy 364.828694 -306.741768) (xy 364.817933 -306.765198)
			(xy 378.025404 -306.765198) (xy 378.029475 -306.709576) (xy 378.041601 -306.655139) (xy 378.061524 -306.603048)
			(xy 378.08882 -306.554413) (xy 378.122906 -306.51027) (xy 378.163055 -306.471561) (xy 378.208413 -306.43911)
			(xy 378.258013 -306.413609) (xy 378.310797 -306.395602) (xy 378.36564 -306.385472) (xy 378.421374 -306.383435)
			(xy 378.476811 -306.389535) (xy 378.530768 -306.403641) (xy 378.582097 -306.425453) (xy 378.629703 -306.454507)
			(xy 378.672571 -306.490182) (xy 378.709788 -306.531719) (xy 378.740561 -306.578232) (xy 378.764233 -306.628729)
			(xy 378.780301 -306.682136) (xy 378.788421 -306.737312) (xy 378.78893 -306.765198) (xy 378.788421 -306.793084)
			(xy 378.783741 -306.824888) (xy 394.819136 -306.824888) (xy 394.823096 -306.775834) (xy 394.834873 -306.72805)
			(xy 394.854164 -306.682774) (xy 394.880467 -306.641178) (xy 394.913102 -306.604341) (xy 394.951223 -306.573216)
			(xy 394.993844 -306.548609) (xy 395.03986 -306.531157) (xy 395.088079 -306.521313) (xy 395.137254 -306.519332)
			(xy 395.186109 -306.525264) (xy 395.23338 -306.538956) (xy 395.277842 -306.560054) (xy 395.318345 -306.58801)
			(xy 395.353838 -306.622102) (xy 395.383403 -306.661446) (xy 395.406274 -306.705023) (xy 395.421858 -306.751704)
			(xy 395.429753 -306.800281) (xy 395.430248 -306.824888) (xy 395.769096 -306.824888) (xy 395.773056 -306.775834)
			(xy 395.784833 -306.72805) (xy 395.804124 -306.682774) (xy 395.830427 -306.641178) (xy 395.863062 -306.604341)
			(xy 395.901183 -306.573216) (xy 395.943804 -306.548609) (xy 395.98982 -306.531157) (xy 396.038039 -306.521313)
			(xy 396.087214 -306.519332) (xy 396.136069 -306.525264) (xy 396.18334 -306.538956) (xy 396.227802 -306.560054)
			(xy 396.268305 -306.58801) (xy 396.303798 -306.622102) (xy 396.333363 -306.661446) (xy 396.356234 -306.705023)
			(xy 396.371818 -306.751704) (xy 396.379713 -306.800281) (xy 396.380208 -306.824888) (xy 396.719056 -306.824888)
			(xy 396.723016 -306.775834) (xy 396.734793 -306.72805) (xy 396.754084 -306.682774) (xy 396.780387 -306.641178)
			(xy 396.813022 -306.604341) (xy 396.851143 -306.573216) (xy 396.893764 -306.548609) (xy 396.93978 -306.531157)
			(xy 396.987999 -306.521313) (xy 397.037174 -306.519332) (xy 397.086029 -306.525264) (xy 397.1333 -306.538956)
			(xy 397.177762 -306.560054) (xy 397.218265 -306.58801) (xy 397.253758 -306.622102) (xy 397.283323 -306.661446)
			(xy 397.306194 -306.705023) (xy 397.321778 -306.751704) (xy 397.329673 -306.800281) (xy 397.330168 -306.824888)
			(xy 397.329673 -306.849495) (xy 397.321778 -306.898072) (xy 397.306194 -306.944753) (xy 397.283323 -306.98833)
			(xy 397.253758 -307.027674) (xy 397.218265 -307.061766) (xy 397.177762 -307.089722) (xy 397.1333 -307.11082)
			(xy 397.086029 -307.124512) (xy 397.037174 -307.130444) (xy 396.987999 -307.128463) (xy 396.93978 -307.118619)
			(xy 396.893764 -307.101167) (xy 396.851143 -307.07656) (xy 396.813022 -307.045435) (xy 396.780387 -307.008598)
			(xy 396.754084 -306.967002) (xy 396.734793 -306.921726) (xy 396.723016 -306.873942) (xy 396.719056 -306.824888)
			(xy 396.380208 -306.824888) (xy 396.379713 -306.849495) (xy 396.371818 -306.898072) (xy 396.356234 -306.944753)
			(xy 396.333363 -306.98833) (xy 396.303798 -307.027674) (xy 396.268305 -307.061766) (xy 396.227802 -307.089722)
			(xy 396.18334 -307.11082) (xy 396.136069 -307.124512) (xy 396.087214 -307.130444) (xy 396.038039 -307.128463)
			(xy 395.98982 -307.118619) (xy 395.943804 -307.101167) (xy 395.901183 -307.07656) (xy 395.863062 -307.045435)
			(xy 395.830427 -307.008598) (xy 395.804124 -306.967002) (xy 395.784833 -306.921726) (xy 395.773056 -306.873942)
			(xy 395.769096 -306.824888) (xy 395.430248 -306.824888) (xy 395.429753 -306.849495) (xy 395.421858 -306.898072)
			(xy 395.406274 -306.944753) (xy 395.383403 -306.98833) (xy 395.353838 -307.027674) (xy 395.318345 -307.061766)
			(xy 395.277842 -307.089722) (xy 395.23338 -307.11082) (xy 395.186109 -307.124512) (xy 395.137254 -307.130444)
			(xy 395.088079 -307.128463) (xy 395.03986 -307.118619) (xy 394.993844 -307.101167) (xy 394.951223 -307.07656)
			(xy 394.913102 -307.045435) (xy 394.880467 -307.008598) (xy 394.854164 -306.967002) (xy 394.834873 -306.921726)
			(xy 394.823096 -306.873942) (xy 394.819136 -306.824888) (xy 378.783741 -306.824888) (xy 378.780301 -306.84826)
			(xy 378.764233 -306.901667) (xy 378.740561 -306.952164) (xy 378.709788 -306.998677) (xy 378.672571 -307.040214)
			(xy 378.629703 -307.075889) (xy 378.582097 -307.104943) (xy 378.530768 -307.126755) (xy 378.476811 -307.140861)
			(xy 378.421374 -307.146961) (xy 378.36564 -307.144924) (xy 378.310797 -307.134794) (xy 378.258013 -307.116787)
			(xy 378.208413 -307.091286) (xy 378.163055 -307.058835) (xy 378.122906 -307.020126) (xy 378.08882 -306.975983)
			(xy 378.061524 -306.927348) (xy 378.041601 -306.875257) (xy 378.029475 -306.82082) (xy 378.025404 -306.765198)
			(xy 364.817933 -306.765198) (xy 364.805847 -306.791515) (xy 364.77612 -306.837483) (xy 364.758478 -306.858416)
			(xy 364.752382 -306.865528) (xy 364.746032 -306.882546) (xy 364.746032 -306.96789) (xy 364.752382 -306.984908)
			(xy 364.758478 -306.99202) (xy 364.776136 -307.012939) (xy 364.80586 -307.058909) (xy 364.828704 -307.108658)
			(xy 364.844198 -307.161162) (xy 364.852025 -307.215342) (xy 364.852024 -307.240178) (xy 380.16002 -307.240178)
			(xy 380.164091 -307.184556) (xy 380.176217 -307.130119) (xy 380.19614 -307.078028) (xy 380.223436 -307.029393)
			(xy 380.257522 -306.98525) (xy 380.297671 -306.946541) (xy 380.343029 -306.91409) (xy 380.392629 -306.888589)
			(xy 380.445413 -306.870582) (xy 380.500256 -306.860452) (xy 380.55599 -306.858415) (xy 380.611427 -306.864515)
			(xy 380.665384 -306.878621) (xy 380.716713 -306.900433) (xy 380.764319 -306.929487) (xy 380.807187 -306.965162)
			(xy 380.844404 -307.006699) (xy 380.875177 -307.053212) (xy 380.898849 -307.103709) (xy 380.914917 -307.157116)
			(xy 380.923037 -307.212292) (xy 380.923546 -307.240178) (xy 380.923037 -307.268064) (xy 380.918357 -307.299868)
			(xy 384.844048 -307.299868) (xy 384.848008 -307.250814) (xy 384.859785 -307.20303) (xy 384.879076 -307.157754)
			(xy 384.905379 -307.116158) (xy 384.938014 -307.079321) (xy 384.976135 -307.048196) (xy 385.018756 -307.023589)
			(xy 385.064772 -307.006137) (xy 385.112991 -306.996293) (xy 385.162166 -306.994312) (xy 385.211021 -307.000244)
			(xy 385.258292 -307.013936) (xy 385.302754 -307.035034) (xy 385.343257 -307.06299) (xy 385.37875 -307.097082)
			(xy 385.408315 -307.136426) (xy 385.431186 -307.180003) (xy 385.44677 -307.226684) (xy 385.454665 -307.275261)
			(xy 385.45516 -307.299868) (xy 385.794008 -307.299868) (xy 385.797968 -307.250814) (xy 385.809745 -307.20303)
			(xy 385.829036 -307.157754) (xy 385.855339 -307.116158) (xy 385.887974 -307.079321) (xy 385.926095 -307.048196)
			(xy 385.968716 -307.023589) (xy 386.014732 -307.006137) (xy 386.062951 -306.996293) (xy 386.112126 -306.994312)
			(xy 386.160981 -307.000244) (xy 386.208252 -307.013936) (xy 386.252714 -307.035034) (xy 386.293217 -307.06299)
			(xy 386.32871 -307.097082) (xy 386.358275 -307.136426) (xy 386.381146 -307.180003) (xy 386.39673 -307.226684)
			(xy 386.404625 -307.275261) (xy 386.40512 -307.299868) (xy 386.404625 -307.324475) (xy 386.404446 -307.325576)
			(xy 386.723378 -307.325576) (xy 386.723378 -307.27416) (xy 386.731421 -307.223378) (xy 386.747309 -307.174479)
			(xy 386.770652 -307.128667) (xy 386.800873 -307.087071) (xy 386.837229 -307.050715) (xy 386.878825 -307.020494)
			(xy 386.924637 -306.997151) (xy 386.973536 -306.981263) (xy 387.024318 -306.97322) (xy 387.075734 -306.97322)
			(xy 387.126516 -306.981263) (xy 387.175415 -306.997151) (xy 387.221227 -307.020494) (xy 387.262823 -307.050715)
			(xy 387.299179 -307.087071) (xy 387.3294 -307.128667) (xy 387.352743 -307.174479) (xy 387.368631 -307.223378)
			(xy 387.376674 -307.27416) (xy 387.377178 -307.299868) (xy 387.376674 -307.325576) (xy 387.673338 -307.325576)
			(xy 387.673338 -307.27416) (xy 387.681381 -307.223378) (xy 387.697269 -307.174479) (xy 387.720612 -307.128667)
			(xy 387.750833 -307.087071) (xy 387.787189 -307.050715) (xy 387.828785 -307.020494) (xy 387.874597 -306.997151)
			(xy 387.923496 -306.981263) (xy 387.974278 -306.97322) (xy 388.025694 -306.97322) (xy 388.076476 -306.981263)
			(xy 388.125375 -306.997151) (xy 388.171187 -307.020494) (xy 388.212783 -307.050715) (xy 388.249139 -307.087071)
			(xy 388.27936 -307.128667) (xy 388.302703 -307.174479) (xy 388.318591 -307.223378) (xy 388.326634 -307.27416)
			(xy 388.327138 -307.299868) (xy 388.644142 -307.299868) (xy 388.648102 -307.250814) (xy 388.659879 -307.20303)
			(xy 388.67917 -307.157754) (xy 388.705473 -307.116158) (xy 388.738108 -307.079321) (xy 388.776229 -307.048196)
			(xy 388.81885 -307.023589) (xy 388.864866 -307.006137) (xy 388.913085 -306.996293) (xy 388.96226 -306.994312)
			(xy 389.011115 -307.000244) (xy 389.058386 -307.013936) (xy 389.102848 -307.035034) (xy 389.143351 -307.06299)
			(xy 389.178844 -307.097082) (xy 389.208409 -307.136426) (xy 389.23128 -307.180003) (xy 389.246864 -307.226684)
			(xy 389.254759 -307.275261) (xy 389.255254 -307.299868) (xy 389.254759 -307.324475) (xy 389.25458 -307.325576)
			(xy 389.573258 -307.325576) (xy 389.573258 -307.27416) (xy 389.581301 -307.223378) (xy 389.597189 -307.174479)
			(xy 389.620532 -307.128667) (xy 389.650753 -307.087071) (xy 389.687109 -307.050715) (xy 389.728705 -307.020494)
			(xy 389.774517 -306.997151) (xy 389.823416 -306.981263) (xy 389.874198 -306.97322) (xy 389.925614 -306.97322)
			(xy 389.976396 -306.981263) (xy 390.025295 -306.997151) (xy 390.071107 -307.020494) (xy 390.112703 -307.050715)
			(xy 390.149059 -307.087071) (xy 390.17928 -307.128667) (xy 390.202623 -307.174479) (xy 390.218511 -307.223378)
			(xy 390.226554 -307.27416) (xy 390.227058 -307.299868) (xy 390.226554 -307.325576) (xy 390.523218 -307.325576)
			(xy 390.523218 -307.27416) (xy 390.531261 -307.223378) (xy 390.547149 -307.174479) (xy 390.570492 -307.128667)
			(xy 390.600713 -307.087071) (xy 390.637069 -307.050715) (xy 390.678665 -307.020494) (xy 390.724477 -306.997151)
			(xy 390.773376 -306.981263) (xy 390.824158 -306.97322) (xy 390.875574 -306.97322) (xy 390.926356 -306.981263)
			(xy 390.975255 -306.997151) (xy 391.021067 -307.020494) (xy 391.062663 -307.050715) (xy 391.099019 -307.087071)
			(xy 391.12924 -307.128667) (xy 391.152583 -307.174479) (xy 391.168471 -307.223378) (xy 391.176514 -307.27416)
			(xy 391.177018 -307.299868) (xy 391.494022 -307.299868) (xy 391.497982 -307.250814) (xy 391.509759 -307.20303)
			(xy 391.52905 -307.157754) (xy 391.555353 -307.116158) (xy 391.587988 -307.079321) (xy 391.626109 -307.048196)
			(xy 391.66873 -307.023589) (xy 391.714746 -307.006137) (xy 391.762965 -306.996293) (xy 391.81214 -306.994312)
			(xy 391.860995 -307.000244) (xy 391.908266 -307.013936) (xy 391.952728 -307.035034) (xy 391.993231 -307.06299)
			(xy 392.028724 -307.097082) (xy 392.058289 -307.136426) (xy 392.08116 -307.180003) (xy 392.096744 -307.226684)
			(xy 392.104639 -307.275261) (xy 392.105134 -307.299868) (xy 392.443982 -307.299868) (xy 392.447942 -307.250814)
			(xy 392.459719 -307.20303) (xy 392.47901 -307.157754) (xy 392.505313 -307.116158) (xy 392.537948 -307.079321)
			(xy 392.576069 -307.048196) (xy 392.61869 -307.023589) (xy 392.664706 -307.006137) (xy 392.712925 -306.996293)
			(xy 392.7621 -306.994312) (xy 392.810955 -307.000244) (xy 392.858226 -307.013936) (xy 392.902688 -307.035034)
			(xy 392.943191 -307.06299) (xy 392.978684 -307.097082) (xy 393.008249 -307.136426) (xy 393.03112 -307.180003)
			(xy 393.046704 -307.226684) (xy 393.054599 -307.275261) (xy 393.055094 -307.299868) (xy 393.394196 -307.299868)
			(xy 393.398156 -307.250814) (xy 393.409933 -307.20303) (xy 393.429224 -307.157754) (xy 393.455527 -307.116158)
			(xy 393.488162 -307.079321) (xy 393.526283 -307.048196) (xy 393.568904 -307.023589) (xy 393.61492 -307.006137)
			(xy 393.663139 -306.996293) (xy 393.712314 -306.994312) (xy 393.761169 -307.000244) (xy 393.80844 -307.013936)
			(xy 393.852902 -307.035034) (xy 393.893405 -307.06299) (xy 393.928898 -307.097082) (xy 393.958463 -307.136426)
			(xy 393.981334 -307.180003) (xy 393.996918 -307.226684) (xy 394.004813 -307.275261) (xy 394.005308 -307.299868)
			(xy 394.004813 -307.324475) (xy 393.996918 -307.373052) (xy 393.981334 -307.419733) (xy 393.958463 -307.46331)
			(xy 393.928898 -307.502654) (xy 393.893405 -307.536746) (xy 393.852902 -307.564702) (xy 393.80844 -307.5858)
			(xy 393.761169 -307.599492) (xy 393.712314 -307.605424) (xy 393.663139 -307.603443) (xy 393.61492 -307.593599)
			(xy 393.568904 -307.576147) (xy 393.526283 -307.55154) (xy 393.488162 -307.520415) (xy 393.455527 -307.483578)
			(xy 393.429224 -307.441982) (xy 393.409933 -307.396706) (xy 393.398156 -307.348922) (xy 393.394196 -307.299868)
			(xy 393.055094 -307.299868) (xy 393.054599 -307.324475) (xy 393.046704 -307.373052) (xy 393.03112 -307.419733)
			(xy 393.008249 -307.46331) (xy 392.978684 -307.502654) (xy 392.943191 -307.536746) (xy 392.902688 -307.564702)
			(xy 392.858226 -307.5858) (xy 392.810955 -307.599492) (xy 392.7621 -307.605424) (xy 392.712925 -307.603443)
			(xy 392.664706 -307.593599) (xy 392.61869 -307.576147) (xy 392.576069 -307.55154) (xy 392.537948 -307.520415)
			(xy 392.505313 -307.483578) (xy 392.47901 -307.441982) (xy 392.459719 -307.396706) (xy 392.447942 -307.348922)
			(xy 392.443982 -307.299868) (xy 392.105134 -307.299868) (xy 392.104639 -307.324475) (xy 392.096744 -307.373052)
			(xy 392.08116 -307.419733) (xy 392.058289 -307.46331) (xy 392.028724 -307.502654) (xy 391.993231 -307.536746)
			(xy 391.952728 -307.564702) (xy 391.908266 -307.5858) (xy 391.860995 -307.599492) (xy 391.81214 -307.605424)
			(xy 391.762965 -307.603443) (xy 391.714746 -307.593599) (xy 391.66873 -307.576147) (xy 391.626109 -307.55154)
			(xy 391.587988 -307.520415) (xy 391.555353 -307.483578) (xy 391.52905 -307.441982) (xy 391.509759 -307.396706)
			(xy 391.497982 -307.348922) (xy 391.494022 -307.299868) (xy 391.177018 -307.299868) (xy 391.176514 -307.325576)
			(xy 391.168471 -307.376358) (xy 391.152583 -307.425257) (xy 391.12924 -307.471069) (xy 391.099019 -307.512665)
			(xy 391.062663 -307.549021) (xy 391.021067 -307.579242) (xy 390.975255 -307.602585) (xy 390.926356 -307.618473)
			(xy 390.875574 -307.626516) (xy 390.824158 -307.626516) (xy 390.773376 -307.618473) (xy 390.724477 -307.602585)
			(xy 390.678665 -307.579242) (xy 390.637069 -307.549021) (xy 390.600713 -307.512665) (xy 390.570492 -307.471069)
			(xy 390.547149 -307.425257) (xy 390.531261 -307.376358) (xy 390.523218 -307.325576) (xy 390.226554 -307.325576)
			(xy 390.218511 -307.376358) (xy 390.202623 -307.425257) (xy 390.17928 -307.471069) (xy 390.149059 -307.512665)
			(xy 390.112703 -307.549021) (xy 390.071107 -307.579242) (xy 390.025295 -307.602585) (xy 389.976396 -307.618473)
			(xy 389.925614 -307.626516) (xy 389.874198 -307.626516) (xy 389.823416 -307.618473) (xy 389.774517 -307.602585)
			(xy 389.728705 -307.579242) (xy 389.687109 -307.549021) (xy 389.650753 -307.512665) (xy 389.620532 -307.471069)
			(xy 389.597189 -307.425257) (xy 389.581301 -307.376358) (xy 389.573258 -307.325576) (xy 389.25458 -307.325576)
			(xy 389.246864 -307.373052) (xy 389.23128 -307.419733) (xy 389.208409 -307.46331) (xy 389.178844 -307.502654)
			(xy 389.143351 -307.536746) (xy 389.102848 -307.564702) (xy 389.058386 -307.5858) (xy 389.011115 -307.599492)
			(xy 388.96226 -307.605424) (xy 388.913085 -307.603443) (xy 388.864866 -307.593599) (xy 388.81885 -307.576147)
			(xy 388.776229 -307.55154) (xy 388.738108 -307.520415) (xy 388.705473 -307.483578) (xy 388.67917 -307.441982)
			(xy 388.659879 -307.396706) (xy 388.648102 -307.348922) (xy 388.644142 -307.299868) (xy 388.327138 -307.299868)
			(xy 388.326634 -307.325576) (xy 388.318591 -307.376358) (xy 388.302703 -307.425257) (xy 388.27936 -307.471069)
			(xy 388.249139 -307.512665) (xy 388.212783 -307.549021) (xy 388.171187 -307.579242) (xy 388.125375 -307.602585)
			(xy 388.076476 -307.618473) (xy 388.025694 -307.626516) (xy 387.974278 -307.626516) (xy 387.923496 -307.618473)
			(xy 387.874597 -307.602585) (xy 387.828785 -307.579242) (xy 387.787189 -307.549021) (xy 387.750833 -307.512665)
			(xy 387.720612 -307.471069) (xy 387.697269 -307.425257) (xy 387.681381 -307.376358) (xy 387.673338 -307.325576)
			(xy 387.376674 -307.325576) (xy 387.368631 -307.376358) (xy 387.352743 -307.425257) (xy 387.3294 -307.471069)
			(xy 387.299179 -307.512665) (xy 387.262823 -307.549021) (xy 387.221227 -307.579242) (xy 387.175415 -307.602585)
			(xy 387.126516 -307.618473) (xy 387.075734 -307.626516) (xy 387.024318 -307.626516) (xy 386.973536 -307.618473)
			(xy 386.924637 -307.602585) (xy 386.878825 -307.579242) (xy 386.837229 -307.549021) (xy 386.800873 -307.512665)
			(xy 386.770652 -307.471069) (xy 386.747309 -307.425257) (xy 386.731421 -307.376358) (xy 386.723378 -307.325576)
			(xy 386.404446 -307.325576) (xy 386.39673 -307.373052) (xy 386.381146 -307.419733) (xy 386.358275 -307.46331)
			(xy 386.32871 -307.502654) (xy 386.293217 -307.536746) (xy 386.252714 -307.564702) (xy 386.208252 -307.5858)
			(xy 386.160981 -307.599492) (xy 386.112126 -307.605424) (xy 386.062951 -307.603443) (xy 386.014732 -307.593599)
			(xy 385.968716 -307.576147) (xy 385.926095 -307.55154) (xy 385.887974 -307.520415) (xy 385.855339 -307.483578)
			(xy 385.829036 -307.441982) (xy 385.809745 -307.396706) (xy 385.797968 -307.348922) (xy 385.794008 -307.299868)
			(xy 385.45516 -307.299868) (xy 385.454665 -307.324475) (xy 385.44677 -307.373052) (xy 385.431186 -307.419733)
			(xy 385.408315 -307.46331) (xy 385.37875 -307.502654) (xy 385.343257 -307.536746) (xy 385.302754 -307.564702)
			(xy 385.258292 -307.5858) (xy 385.211021 -307.599492) (xy 385.162166 -307.605424) (xy 385.112991 -307.603443)
			(xy 385.064772 -307.593599) (xy 385.018756 -307.576147) (xy 384.976135 -307.55154) (xy 384.938014 -307.520415)
			(xy 384.905379 -307.483578) (xy 384.879076 -307.441982) (xy 384.859785 -307.396706) (xy 384.848008 -307.348922)
			(xy 384.844048 -307.299868) (xy 380.918357 -307.299868) (xy 380.914917 -307.32324) (xy 380.898849 -307.376647)
			(xy 380.875177 -307.427144) (xy 380.844404 -307.473657) (xy 380.807187 -307.515194) (xy 380.764319 -307.550869)
			(xy 380.716713 -307.579923) (xy 380.665384 -307.601735) (xy 380.611427 -307.615841) (xy 380.55599 -307.621941)
			(xy 380.500256 -307.619904) (xy 380.445413 -307.609774) (xy 380.392629 -307.591767) (xy 380.343029 -307.566266)
			(xy 380.297671 -307.533815) (xy 380.257522 -307.495106) (xy 380.223436 -307.450963) (xy 380.19614 -307.402328)
			(xy 380.176217 -307.350237) (xy 380.164091 -307.2958) (xy 380.16002 -307.240178) (xy 364.852024 -307.240178)
			(xy 364.852023 -307.270085) (xy 364.844193 -307.324265) (xy 364.828694 -307.376768) (xy 364.805847 -307.426515)
			(xy 364.77612 -307.472483) (xy 364.758478 -307.493416) (xy 364.752382 -307.500528) (xy 364.746032 -307.517546)
			(xy 364.746032 -307.60289) (xy 364.752382 -307.619908) (xy 364.758478 -307.62702) (xy 364.77609 -307.647974)
			(xy 364.805806 -307.693941) (xy 364.828648 -307.743682) (xy 364.837848 -307.774848) (xy 394.819136 -307.774848)
			(xy 394.823096 -307.725794) (xy 394.834873 -307.67801) (xy 394.854164 -307.632734) (xy 394.880467 -307.591138)
			(xy 394.913102 -307.554301) (xy 394.951223 -307.523176) (xy 394.993844 -307.498569) (xy 395.03986 -307.481117)
			(xy 395.088079 -307.471273) (xy 395.137254 -307.469292) (xy 395.186109 -307.475224) (xy 395.23338 -307.488916)
			(xy 395.277842 -307.510014) (xy 395.318345 -307.53797) (xy 395.353838 -307.572062) (xy 395.383403 -307.611406)
			(xy 395.406274 -307.654983) (xy 395.421858 -307.701664) (xy 395.429753 -307.750241) (xy 395.430248 -307.774848)
			(xy 395.769096 -307.774848) (xy 395.773056 -307.725794) (xy 395.784833 -307.67801) (xy 395.804124 -307.632734)
			(xy 395.830427 -307.591138) (xy 395.863062 -307.554301) (xy 395.901183 -307.523176) (xy 395.943804 -307.498569)
			(xy 395.98982 -307.481117) (xy 396.038039 -307.471273) (xy 396.087214 -307.469292) (xy 396.136069 -307.475224)
			(xy 396.18334 -307.488916) (xy 396.227802 -307.510014) (xy 396.268305 -307.53797) (xy 396.303798 -307.572062)
			(xy 396.333363 -307.611406) (xy 396.356234 -307.654983) (xy 396.371818 -307.701664) (xy 396.379713 -307.750241)
			(xy 396.380208 -307.774848) (xy 396.719056 -307.774848) (xy 396.723016 -307.725794) (xy 396.734793 -307.67801)
			(xy 396.754084 -307.632734) (xy 396.780387 -307.591138) (xy 396.813022 -307.554301) (xy 396.851143 -307.523176)
			(xy 396.893764 -307.498569) (xy 396.93978 -307.481117) (xy 396.987999 -307.471273) (xy 397.037174 -307.469292)
			(xy 397.086029 -307.475224) (xy 397.1333 -307.488916) (xy 397.177762 -307.510014) (xy 397.218265 -307.53797)
			(xy 397.253758 -307.572062) (xy 397.283323 -307.611406) (xy 397.306194 -307.654983) (xy 397.321778 -307.701664)
			(xy 397.329673 -307.750241) (xy 397.330168 -307.774848) (xy 397.329673 -307.799455) (xy 397.321778 -307.848032)
			(xy 397.306194 -307.894713) (xy 397.283323 -307.93829) (xy 397.253758 -307.977634) (xy 397.218265 -308.011726)
			(xy 397.177762 -308.039682) (xy 397.1333 -308.06078) (xy 397.086029 -308.074472) (xy 397.037174 -308.080404)
			(xy 396.987999 -308.078423) (xy 396.93978 -308.068579) (xy 396.893764 -308.051127) (xy 396.851143 -308.02652)
			(xy 396.813022 -307.995395) (xy 396.780387 -307.958558) (xy 396.754084 -307.916962) (xy 396.734793 -307.871686)
			(xy 396.723016 -307.823902) (xy 396.719056 -307.774848) (xy 396.380208 -307.774848) (xy 396.379713 -307.799455)
			(xy 396.371818 -307.848032) (xy 396.356234 -307.894713) (xy 396.333363 -307.93829) (xy 396.303798 -307.977634)
			(xy 396.268305 -308.011726) (xy 396.227802 -308.039682) (xy 396.18334 -308.06078) (xy 396.136069 -308.074472)
			(xy 396.087214 -308.080404) (xy 396.038039 -308.078423) (xy 395.98982 -308.068579) (xy 395.943804 -308.051127)
			(xy 395.901183 -308.02652) (xy 395.863062 -307.995395) (xy 395.830427 -307.958558) (xy 395.804124 -307.916962)
			(xy 395.784833 -307.871686) (xy 395.773056 -307.823902) (xy 395.769096 -307.774848) (xy 395.430248 -307.774848)
			(xy 395.429753 -307.799455) (xy 395.421858 -307.848032) (xy 395.406274 -307.894713) (xy 395.383403 -307.93829)
			(xy 395.353838 -307.977634) (xy 395.318345 -308.011726) (xy 395.277842 -308.039682) (xy 395.23338 -308.06078)
			(xy 395.186109 -308.074472) (xy 395.137254 -308.080404) (xy 395.088079 -308.078423) (xy 395.03986 -308.068579)
			(xy 394.993844 -308.051127) (xy 394.951223 -308.02652) (xy 394.913102 -307.995395) (xy 394.880467 -307.958558)
			(xy 394.854164 -307.916962) (xy 394.834873 -307.871686) (xy 394.823096 -307.823902) (xy 394.819136 -307.774848)
			(xy 364.837848 -307.774848) (xy 364.844145 -307.796178) (xy 364.85198 -307.85035) (xy 364.852458 -307.877718)
			(xy 364.851972 -307.904969) (xy 364.844216 -307.958917) (xy 364.828861 -308.011212) (xy 364.806219 -308.060789)
			(xy 364.776753 -308.106639) (xy 364.741062 -308.14783) (xy 364.699871 -308.183521) (xy 364.654021 -308.212987)
			(xy 364.604444 -308.235629) (xy 364.552149 -308.250984) (xy 364.498201 -308.25874) (xy 364.443699 -308.25874)
			(xy 364.389751 -308.250984) (xy 364.337456 -308.235629) (xy 364.287879 -308.212987) (xy 364.242029 -308.183521)
			(xy 364.200838 -308.14783) (xy 364.165147 -308.106639) (xy 364.135681 -308.060789) (xy 364.113039 -308.011212)
			(xy 364.097684 -307.958917) (xy 364.089928 -307.904969) (xy 364.089442 -307.877718) (xy 358.012238 -307.877718)
			(xy 358.011752 -307.904969) (xy 358.003996 -307.958917) (xy 357.988641 -308.011212) (xy 357.965999 -308.060789)
			(xy 357.936533 -308.106639) (xy 357.900842 -308.14783) (xy 357.859651 -308.183521) (xy 357.813801 -308.212987)
			(xy 357.764224 -308.235629) (xy 357.711929 -308.250984) (xy 357.657981 -308.25874) (xy 357.603479 -308.25874)
			(xy 357.549531 -308.250984) (xy 357.497236 -308.235629) (xy 357.447659 -308.212987) (xy 357.401809 -308.183521)
			(xy 357.360618 -308.14783) (xy 357.324927 -308.106639) (xy 357.295461 -308.060789) (xy 357.272819 -308.011212)
			(xy 357.257464 -307.958917) (xy 357.249708 -307.904969) (xy 357.249222 -307.877718) (xy 354.375728 -307.877718)
			(xy 354.371796 -307.905069) (xy 354.356441 -307.957364) (xy 354.333799 -308.006941) (xy 354.304333 -308.052791)
			(xy 354.268642 -308.093982) (xy 354.227451 -308.129673) (xy 354.181601 -308.159139) (xy 354.132024 -308.181781)
			(xy 354.079729 -308.197136) (xy 354.025781 -308.204892) (xy 353.971279 -308.204892) (xy 353.917331 -308.197136)
			(xy 353.865036 -308.181781) (xy 353.815459 -308.159139) (xy 353.769609 -308.129673) (xy 353.728418 -308.093982)
			(xy 353.692727 -308.052791) (xy 353.663261 -308.006941) (xy 353.640619 -307.957364) (xy 353.625264 -307.905069)
			(xy 353.617508 -307.851121) (xy 353.617022 -307.82387) (xy 351.031048 -307.82387) (xy 351.031048 -308.450488)
			(xy 376.378214 -308.450488) (xy 376.382285 -308.394866) (xy 376.394411 -308.340429) (xy 376.414334 -308.288338)
			(xy 376.44163 -308.239703) (xy 376.475716 -308.19556) (xy 376.515865 -308.156851) (xy 376.561223 -308.1244)
			(xy 376.610823 -308.098899) (xy 376.663607 -308.080892) (xy 376.71845 -308.070762) (xy 376.774184 -308.068725)
			(xy 376.829621 -308.074825) (xy 376.883578 -308.088931) (xy 376.934907 -308.110743) (xy 376.982513 -308.139797)
			(xy 377.025381 -308.175472) (xy 377.062598 -308.217009) (xy 377.084479 -308.250082) (xy 383.893834 -308.250082)
			(xy 383.897794 -308.201028) (xy 383.909571 -308.153244) (xy 383.928862 -308.107968) (xy 383.955165 -308.066372)
			(xy 383.9878 -308.029535) (xy 384.025921 -307.99841) (xy 384.068542 -307.973803) (xy 384.114558 -307.956351)
			(xy 384.162777 -307.946507) (xy 384.211952 -307.944526) (xy 384.260807 -307.950458) (xy 384.308078 -307.96415)
			(xy 384.35254 -307.985248) (xy 384.393043 -308.013204) (xy 384.428536 -308.047296) (xy 384.458101 -308.08664)
			(xy 384.480972 -308.130217) (xy 384.496556 -308.176898) (xy 384.504451 -308.225475) (xy 384.504946 -308.250082)
			(xy 384.504451 -308.274689) (xy 384.504313 -308.275536) (xy 384.823204 -308.275536) (xy 384.823204 -308.22412)
			(xy 384.831247 -308.173338) (xy 384.847135 -308.124439) (xy 384.870478 -308.078627) (xy 384.900699 -308.037031)
			(xy 384.937055 -308.000675) (xy 384.978651 -307.970454) (xy 385.024463 -307.947111) (xy 385.073362 -307.931223)
			(xy 385.124144 -307.92318) (xy 385.17556 -307.92318) (xy 385.226342 -307.931223) (xy 385.275241 -307.947111)
			(xy 385.321053 -307.970454) (xy 385.362649 -308.000675) (xy 385.399005 -308.037031) (xy 385.429226 -308.078627)
			(xy 385.452569 -308.124439) (xy 385.468457 -308.173338) (xy 385.4765 -308.22412) (xy 385.477004 -308.249828)
			(xy 385.4765 -308.275536) (xy 385.773164 -308.275536) (xy 385.773164 -308.22412) (xy 385.781207 -308.173338)
			(xy 385.797095 -308.124439) (xy 385.820438 -308.078627) (xy 385.850659 -308.037031) (xy 385.887015 -308.000675)
			(xy 385.928611 -307.970454) (xy 385.974423 -307.947111) (xy 386.023322 -307.931223) (xy 386.074104 -307.92318)
			(xy 386.12552 -307.92318) (xy 386.176302 -307.931223) (xy 386.225201 -307.947111) (xy 386.271013 -307.970454)
			(xy 386.312609 -308.000675) (xy 386.348965 -308.037031) (xy 386.379186 -308.078627) (xy 386.402529 -308.124439)
			(xy 386.418417 -308.173338) (xy 386.42646 -308.22412) (xy 386.426964 -308.249828) (xy 386.744222 -308.249828)
			(xy 386.748182 -308.200774) (xy 386.759959 -308.15299) (xy 386.77925 -308.107714) (xy 386.805553 -308.066118)
			(xy 386.838188 -308.029281) (xy 386.876309 -307.998156) (xy 386.91893 -307.973549) (xy 386.964946 -307.956097)
			(xy 387.013165 -307.946253) (xy 387.06234 -307.944272) (xy 387.111195 -307.950204) (xy 387.158466 -307.963896)
			(xy 387.202928 -307.984994) (xy 387.243431 -308.01295) (xy 387.278924 -308.047042) (xy 387.308489 -308.086386)
			(xy 387.33136 -308.129963) (xy 387.346944 -308.176644) (xy 387.354839 -308.225221) (xy 387.355334 -308.249828)
			(xy 387.694182 -308.249828) (xy 387.698142 -308.200774) (xy 387.709919 -308.15299) (xy 387.72921 -308.107714)
			(xy 387.755513 -308.066118) (xy 387.788148 -308.029281) (xy 387.826269 -307.998156) (xy 387.86889 -307.973549)
			(xy 387.914906 -307.956097) (xy 387.963125 -307.946253) (xy 388.0123 -307.944272) (xy 388.061155 -307.950204)
			(xy 388.108426 -307.963896) (xy 388.152888 -307.984994) (xy 388.193391 -308.01295) (xy 388.228884 -308.047042)
			(xy 388.258449 -308.086386) (xy 388.28132 -308.129963) (xy 388.296904 -308.176644) (xy 388.304799 -308.225221)
			(xy 388.305294 -308.249828) (xy 388.644142 -308.249828) (xy 388.648102 -308.200774) (xy 388.659879 -308.15299)
			(xy 388.67917 -308.107714) (xy 388.705473 -308.066118) (xy 388.738108 -308.029281) (xy 388.776229 -307.998156)
			(xy 388.81885 -307.973549) (xy 388.864866 -307.956097) (xy 388.913085 -307.946253) (xy 388.96226 -307.944272)
			(xy 389.011115 -307.950204) (xy 389.058386 -307.963896) (xy 389.102848 -307.984994) (xy 389.143351 -308.01295)
			(xy 389.178844 -308.047042) (xy 389.208409 -308.086386) (xy 389.23128 -308.129963) (xy 389.246864 -308.176644)
			(xy 389.254759 -308.225221) (xy 389.255254 -308.249828) (xy 389.594102 -308.249828) (xy 389.598062 -308.200774)
			(xy 389.609839 -308.15299) (xy 389.62913 -308.107714) (xy 389.655433 -308.066118) (xy 389.688068 -308.029281)
			(xy 389.726189 -307.998156) (xy 389.76881 -307.973549) (xy 389.814826 -307.956097) (xy 389.863045 -307.946253)
			(xy 389.91222 -307.944272) (xy 389.961075 -307.950204) (xy 390.008346 -307.963896) (xy 390.052808 -307.984994)
			(xy 390.093311 -308.01295) (xy 390.128804 -308.047042) (xy 390.158369 -308.086386) (xy 390.18124 -308.129963)
			(xy 390.196824 -308.176644) (xy 390.204719 -308.225221) (xy 390.205214 -308.249828) (xy 390.544062 -308.249828)
			(xy 390.548022 -308.200774) (xy 390.559799 -308.15299) (xy 390.57909 -308.107714) (xy 390.605393 -308.066118)
			(xy 390.638028 -308.029281) (xy 390.676149 -307.998156) (xy 390.71877 -307.973549) (xy 390.764786 -307.956097)
			(xy 390.813005 -307.946253) (xy 390.86218 -307.944272) (xy 390.911035 -307.950204) (xy 390.958306 -307.963896)
			(xy 391.002768 -307.984994) (xy 391.043271 -308.01295) (xy 391.078764 -308.047042) (xy 391.108329 -308.086386)
			(xy 391.1312 -308.129963) (xy 391.146784 -308.176644) (xy 391.154679 -308.225221) (xy 391.155174 -308.249828)
			(xy 391.154679 -308.274435) (xy 391.1545 -308.275536) (xy 391.473178 -308.275536) (xy 391.473178 -308.22412)
			(xy 391.481221 -308.173338) (xy 391.497109 -308.124439) (xy 391.520452 -308.078627) (xy 391.550673 -308.037031)
			(xy 391.587029 -308.000675) (xy 391.628625 -307.970454) (xy 391.674437 -307.947111) (xy 391.723336 -307.931223)
			(xy 391.774118 -307.92318) (xy 391.825534 -307.92318) (xy 391.876316 -307.931223) (xy 391.925215 -307.947111)
			(xy 391.971027 -307.970454) (xy 392.012623 -308.000675) (xy 392.048979 -308.037031) (xy 392.0792 -308.078627)
			(xy 392.102543 -308.124439) (xy 392.118431 -308.173338) (xy 392.126474 -308.22412) (xy 392.126978 -308.249828)
			(xy 392.126474 -308.275536) (xy 392.423138 -308.275536) (xy 392.423138 -308.22412) (xy 392.431181 -308.173338)
			(xy 392.447069 -308.124439) (xy 392.470412 -308.078627) (xy 392.500633 -308.037031) (xy 392.536989 -308.000675)
			(xy 392.578585 -307.970454) (xy 392.624397 -307.947111) (xy 392.673296 -307.931223) (xy 392.724078 -307.92318)
			(xy 392.775494 -307.92318) (xy 392.826276 -307.931223) (xy 392.875175 -307.947111) (xy 392.920987 -307.970454)
			(xy 392.962583 -308.000675) (xy 392.998939 -308.037031) (xy 393.02916 -308.078627) (xy 393.052503 -308.124439)
			(xy 393.068391 -308.173338) (xy 393.076434 -308.22412) (xy 393.076938 -308.249828) (xy 393.394196 -308.249828)
			(xy 393.398156 -308.200774) (xy 393.409933 -308.15299) (xy 393.429224 -308.107714) (xy 393.455527 -308.066118)
			(xy 393.488162 -308.029281) (xy 393.526283 -307.998156) (xy 393.568904 -307.973549) (xy 393.61492 -307.956097)
			(xy 393.663139 -307.946253) (xy 393.712314 -307.944272) (xy 393.761169 -307.950204) (xy 393.80844 -307.963896)
			(xy 393.852902 -307.984994) (xy 393.893405 -308.01295) (xy 393.928898 -308.047042) (xy 393.958463 -308.086386)
			(xy 393.981334 -308.129963) (xy 393.996918 -308.176644) (xy 394.004813 -308.225221) (xy 394.005308 -308.249828)
			(xy 394.004813 -308.274435) (xy 393.996918 -308.323012) (xy 393.981334 -308.369693) (xy 393.958463 -308.41327)
			(xy 393.928898 -308.452614) (xy 393.893405 -308.486706) (xy 393.852902 -308.514662) (xy 393.80844 -308.53576)
			(xy 393.761169 -308.549452) (xy 393.712314 -308.555384) (xy 393.663139 -308.553403) (xy 393.61492 -308.543559)
			(xy 393.568904 -308.526107) (xy 393.526283 -308.5015) (xy 393.488162 -308.470375) (xy 393.455527 -308.433538)
			(xy 393.429224 -308.391942) (xy 393.409933 -308.346666) (xy 393.398156 -308.298882) (xy 393.394196 -308.249828)
			(xy 393.076938 -308.249828) (xy 393.076434 -308.275536) (xy 393.068391 -308.326318) (xy 393.052503 -308.375217)
			(xy 393.02916 -308.421029) (xy 392.998939 -308.462625) (xy 392.962583 -308.498981) (xy 392.920987 -308.529202)
			(xy 392.875175 -308.552545) (xy 392.826276 -308.568433) (xy 392.775494 -308.576476) (xy 392.724078 -308.576476)
			(xy 392.673296 -308.568433) (xy 392.624397 -308.552545) (xy 392.578585 -308.529202) (xy 392.536989 -308.498981)
			(xy 392.500633 -308.462625) (xy 392.470412 -308.421029) (xy 392.447069 -308.375217) (xy 392.431181 -308.326318)
			(xy 392.423138 -308.275536) (xy 392.126474 -308.275536) (xy 392.118431 -308.326318) (xy 392.102543 -308.375217)
			(xy 392.0792 -308.421029) (xy 392.048979 -308.462625) (xy 392.012623 -308.498981) (xy 391.971027 -308.529202)
			(xy 391.925215 -308.552545) (xy 391.876316 -308.568433) (xy 391.825534 -308.576476) (xy 391.774118 -308.576476)
			(xy 391.723336 -308.568433) (xy 391.674437 -308.552545) (xy 391.628625 -308.529202) (xy 391.587029 -308.498981)
			(xy 391.550673 -308.462625) (xy 391.520452 -308.421029) (xy 391.497109 -308.375217) (xy 391.481221 -308.326318)
			(xy 391.473178 -308.275536) (xy 391.1545 -308.275536) (xy 391.146784 -308.323012) (xy 391.1312 -308.369693)
			(xy 391.108329 -308.41327) (xy 391.078764 -308.452614) (xy 391.043271 -308.486706) (xy 391.002768 -308.514662)
			(xy 390.958306 -308.53576) (xy 390.911035 -308.549452) (xy 390.86218 -308.555384) (xy 390.813005 -308.553403)
			(xy 390.764786 -308.543559) (xy 390.71877 -308.526107) (xy 390.676149 -308.5015) (xy 390.638028 -308.470375)
			(xy 390.605393 -308.433538) (xy 390.57909 -308.391942) (xy 390.559799 -308.346666) (xy 390.548022 -308.298882)
			(xy 390.544062 -308.249828) (xy 390.205214 -308.249828) (xy 390.204719 -308.274435) (xy 390.196824 -308.323012)
			(xy 390.18124 -308.369693) (xy 390.158369 -308.41327) (xy 390.128804 -308.452614) (xy 390.093311 -308.486706)
			(xy 390.052808 -308.514662) (xy 390.008346 -308.53576) (xy 389.961075 -308.549452) (xy 389.91222 -308.555384)
			(xy 389.863045 -308.553403) (xy 389.814826 -308.543559) (xy 389.76881 -308.526107) (xy 389.726189 -308.5015)
			(xy 389.688068 -308.470375) (xy 389.655433 -308.433538) (xy 389.62913 -308.391942) (xy 389.609839 -308.346666)
			(xy 389.598062 -308.298882) (xy 389.594102 -308.249828) (xy 389.255254 -308.249828) (xy 389.254759 -308.274435)
			(xy 389.246864 -308.323012) (xy 389.23128 -308.369693) (xy 389.208409 -308.41327) (xy 389.178844 -308.452614)
			(xy 389.143351 -308.486706) (xy 389.102848 -308.514662) (xy 389.058386 -308.53576) (xy 389.011115 -308.549452)
			(xy 388.96226 -308.555384) (xy 388.913085 -308.553403) (xy 388.864866 -308.543559) (xy 388.81885 -308.526107)
			(xy 388.776229 -308.5015) (xy 388.738108 -308.470375) (xy 388.705473 -308.433538) (xy 388.67917 -308.391942)
			(xy 388.659879 -308.346666) (xy 388.648102 -308.298882) (xy 388.644142 -308.249828) (xy 388.305294 -308.249828)
			(xy 388.304799 -308.274435) (xy 388.296904 -308.323012) (xy 388.28132 -308.369693) (xy 388.258449 -308.41327)
			(xy 388.228884 -308.452614) (xy 388.193391 -308.486706) (xy 388.152888 -308.514662) (xy 388.108426 -308.53576)
			(xy 388.061155 -308.549452) (xy 388.0123 -308.555384) (xy 387.963125 -308.553403) (xy 387.914906 -308.543559)
			(xy 387.86889 -308.526107) (xy 387.826269 -308.5015) (xy 387.788148 -308.470375) (xy 387.755513 -308.433538)
			(xy 387.72921 -308.391942) (xy 387.709919 -308.346666) (xy 387.698142 -308.298882) (xy 387.694182 -308.249828)
			(xy 387.355334 -308.249828) (xy 387.354839 -308.274435) (xy 387.346944 -308.323012) (xy 387.33136 -308.369693)
			(xy 387.308489 -308.41327) (xy 387.278924 -308.452614) (xy 387.243431 -308.486706) (xy 387.202928 -308.514662)
			(xy 387.158466 -308.53576) (xy 387.111195 -308.549452) (xy 387.06234 -308.555384) (xy 387.013165 -308.553403)
			(xy 386.964946 -308.543559) (xy 386.91893 -308.526107) (xy 386.876309 -308.5015) (xy 386.838188 -308.470375)
			(xy 386.805553 -308.433538) (xy 386.77925 -308.391942) (xy 386.759959 -308.346666) (xy 386.748182 -308.298882)
			(xy 386.744222 -308.249828) (xy 386.426964 -308.249828) (xy 386.42646 -308.275536) (xy 386.418417 -308.326318)
			(xy 386.402529 -308.375217) (xy 386.379186 -308.421029) (xy 386.348965 -308.462625) (xy 386.312609 -308.498981)
			(xy 386.271013 -308.529202) (xy 386.225201 -308.552545) (xy 386.176302 -308.568433) (xy 386.12552 -308.576476)
			(xy 386.074104 -308.576476) (xy 386.023322 -308.568433) (xy 385.974423 -308.552545) (xy 385.928611 -308.529202)
			(xy 385.887015 -308.498981) (xy 385.850659 -308.462625) (xy 385.820438 -308.421029) (xy 385.797095 -308.375217)
			(xy 385.781207 -308.326318) (xy 385.773164 -308.275536) (xy 385.4765 -308.275536) (xy 385.468457 -308.326318)
			(xy 385.452569 -308.375217) (xy 385.429226 -308.421029) (xy 385.399005 -308.462625) (xy 385.362649 -308.498981)
			(xy 385.321053 -308.529202) (xy 385.275241 -308.552545) (xy 385.226342 -308.568433) (xy 385.17556 -308.576476)
			(xy 385.124144 -308.576476) (xy 385.073362 -308.568433) (xy 385.024463 -308.552545) (xy 384.978651 -308.529202)
			(xy 384.937055 -308.498981) (xy 384.900699 -308.462625) (xy 384.870478 -308.421029) (xy 384.847135 -308.375217)
			(xy 384.831247 -308.326318) (xy 384.823204 -308.275536) (xy 384.504313 -308.275536) (xy 384.496556 -308.323266)
			(xy 384.480972 -308.369947) (xy 384.458101 -308.413524) (xy 384.428536 -308.452868) (xy 384.393043 -308.48696)
			(xy 384.35254 -308.514916) (xy 384.308078 -308.536014) (xy 384.260807 -308.549706) (xy 384.211952 -308.555638)
			(xy 384.162777 -308.553657) (xy 384.114558 -308.543813) (xy 384.068542 -308.526361) (xy 384.025921 -308.501754)
			(xy 383.9878 -308.470629) (xy 383.955165 -308.433792) (xy 383.928862 -308.392196) (xy 383.909571 -308.34692)
			(xy 383.897794 -308.299136) (xy 383.893834 -308.250082) (xy 377.084479 -308.250082) (xy 377.093371 -308.263522)
			(xy 377.117043 -308.314019) (xy 377.133111 -308.367426) (xy 377.141231 -308.422602) (xy 377.14174 -308.450488)
			(xy 377.141231 -308.478374) (xy 377.133111 -308.53355) (xy 377.117043 -308.586957) (xy 377.093371 -308.637454)
			(xy 377.078766 -308.65953) (xy 378.705616 -308.65953) (xy 378.709687 -308.603908) (xy 378.721813 -308.549471)
			(xy 378.741736 -308.49738) (xy 378.769032 -308.448745) (xy 378.803118 -308.404602) (xy 378.843267 -308.365893)
			(xy 378.888625 -308.333442) (xy 378.938225 -308.307941) (xy 378.991009 -308.289934) (xy 379.045852 -308.279804)
			(xy 379.101586 -308.277767) (xy 379.157023 -308.283867) (xy 379.21098 -308.297973) (xy 379.262309 -308.319785)
			(xy 379.309915 -308.348839) (xy 379.352783 -308.384514) (xy 379.39 -308.426051) (xy 379.420773 -308.472564)
			(xy 379.444445 -308.523061) (xy 379.460513 -308.576468) (xy 379.468633 -308.631644) (xy 379.469142 -308.65953)
			(xy 379.468633 -308.687416) (xy 379.460513 -308.742592) (xy 379.444445 -308.795999) (xy 379.420773 -308.846496)
			(xy 379.39 -308.893009) (xy 379.352783 -308.934546) (xy 379.309915 -308.970221) (xy 379.262309 -308.999275)
			(xy 379.21098 -309.021087) (xy 379.157023 -309.035193) (xy 379.101586 -309.041293) (xy 379.045852 -309.039256)
			(xy 378.991009 -309.029126) (xy 378.938225 -309.011119) (xy 378.888625 -308.985618) (xy 378.843267 -308.953167)
			(xy 378.803118 -308.914458) (xy 378.769032 -308.870315) (xy 378.741736 -308.82168) (xy 378.721813 -308.769589)
			(xy 378.709687 -308.715152) (xy 378.705616 -308.65953) (xy 377.078766 -308.65953) (xy 377.062598 -308.683967)
			(xy 377.025381 -308.725504) (xy 376.982513 -308.761179) (xy 376.934907 -308.790233) (xy 376.883578 -308.812045)
			(xy 376.829621 -308.826151) (xy 376.774184 -308.832251) (xy 376.71845 -308.830214) (xy 376.663607 -308.820084)
			(xy 376.610823 -308.802077) (xy 376.561223 -308.776576) (xy 376.515865 -308.744125) (xy 376.475716 -308.705416)
			(xy 376.44163 -308.661273) (xy 376.414334 -308.612638) (xy 376.394411 -308.560547) (xy 376.382285 -308.50611)
			(xy 376.378214 -308.450488) (xy 351.031048 -308.450488) (xy 351.031048 -309.414926) (xy 375.299984 -309.414926)
			(xy 375.304055 -309.359304) (xy 375.316181 -309.304867) (xy 375.336104 -309.252776) (xy 375.3634 -309.204141)
			(xy 375.397486 -309.159998) (xy 375.437635 -309.121289) (xy 375.482993 -309.088838) (xy 375.532593 -309.063337)
			(xy 375.585377 -309.04533) (xy 375.64022 -309.0352) (xy 375.695954 -309.033163) (xy 375.751391 -309.039263)
			(xy 375.805348 -309.053369) (xy 375.856677 -309.075181) (xy 375.904283 -309.104235) (xy 375.947151 -309.13991)
			(xy 375.984368 -309.181447) (xy 375.996502 -309.199788) (xy 384.844048 -309.199788) (xy 384.848008 -309.150734)
			(xy 384.859785 -309.10295) (xy 384.879076 -309.057674) (xy 384.905379 -309.016078) (xy 384.938014 -308.979241)
			(xy 384.976135 -308.948116) (xy 385.018756 -308.923509) (xy 385.064772 -308.906057) (xy 385.112991 -308.896213)
			(xy 385.162166 -308.894232) (xy 385.211021 -308.900164) (xy 385.258292 -308.913856) (xy 385.302754 -308.934954)
			(xy 385.343257 -308.96291) (xy 385.37875 -308.997002) (xy 385.408315 -309.036346) (xy 385.431186 -309.079923)
			(xy 385.44677 -309.126604) (xy 385.454665 -309.175181) (xy 385.45516 -309.199788) (xy 385.794008 -309.199788)
			(xy 385.797968 -309.150734) (xy 385.809745 -309.10295) (xy 385.829036 -309.057674) (xy 385.855339 -309.016078)
			(xy 385.887974 -308.979241) (xy 385.926095 -308.948116) (xy 385.968716 -308.923509) (xy 386.014732 -308.906057)
			(xy 386.062951 -308.896213) (xy 386.112126 -308.894232) (xy 386.160981 -308.900164) (xy 386.208252 -308.913856)
			(xy 386.252714 -308.934954) (xy 386.293217 -308.96291) (xy 386.32871 -308.997002) (xy 386.358275 -309.036346)
			(xy 386.381146 -309.079923) (xy 386.39673 -309.126604) (xy 386.404625 -309.175181) (xy 386.40512 -309.199788)
			(xy 386.404625 -309.224395) (xy 386.404446 -309.225496) (xy 386.723378 -309.225496) (xy 386.723378 -309.17408)
			(xy 386.731421 -309.123298) (xy 386.747309 -309.074399) (xy 386.770652 -309.028587) (xy 386.800873 -308.986991)
			(xy 386.837229 -308.950635) (xy 386.878825 -308.920414) (xy 386.924637 -308.897071) (xy 386.973536 -308.881183)
			(xy 387.024318 -308.87314) (xy 387.075734 -308.87314) (xy 387.126516 -308.881183) (xy 387.175415 -308.897071)
			(xy 387.221227 -308.920414) (xy 387.262823 -308.950635) (xy 387.299179 -308.986991) (xy 387.3294 -309.028587)
			(xy 387.352743 -309.074399) (xy 387.368631 -309.123298) (xy 387.376674 -309.17408) (xy 387.377178 -309.199788)
			(xy 387.376674 -309.225496) (xy 387.673338 -309.225496) (xy 387.673338 -309.17408) (xy 387.681381 -309.123298)
			(xy 387.697269 -309.074399) (xy 387.720612 -309.028587) (xy 387.750833 -308.986991) (xy 387.787189 -308.950635)
			(xy 387.828785 -308.920414) (xy 387.874597 -308.897071) (xy 387.923496 -308.881183) (xy 387.974278 -308.87314)
			(xy 388.025694 -308.87314) (xy 388.076476 -308.881183) (xy 388.125375 -308.897071) (xy 388.171187 -308.920414)
			(xy 388.212783 -308.950635) (xy 388.249139 -308.986991) (xy 388.27936 -309.028587) (xy 388.302703 -309.074399)
			(xy 388.318591 -309.123298) (xy 388.326634 -309.17408) (xy 388.327138 -309.199788) (xy 388.644142 -309.199788)
			(xy 388.648102 -309.150734) (xy 388.659879 -309.10295) (xy 388.67917 -309.057674) (xy 388.705473 -309.016078)
			(xy 388.738108 -308.979241) (xy 388.776229 -308.948116) (xy 388.81885 -308.923509) (xy 388.864866 -308.906057)
			(xy 388.913085 -308.896213) (xy 388.96226 -308.894232) (xy 389.011115 -308.900164) (xy 389.058386 -308.913856)
			(xy 389.102848 -308.934954) (xy 389.143351 -308.96291) (xy 389.178844 -308.997002) (xy 389.208409 -309.036346)
			(xy 389.23128 -309.079923) (xy 389.246864 -309.126604) (xy 389.254759 -309.175181) (xy 389.255254 -309.199788)
			(xy 389.254759 -309.224395) (xy 389.246864 -309.272972) (xy 389.23128 -309.319653) (xy 389.208409 -309.36323)
			(xy 389.178844 -309.402574) (xy 389.143351 -309.436666) (xy 389.102848 -309.464622) (xy 389.058386 -309.48572)
			(xy 389.011115 -309.499412) (xy 388.96226 -309.505344) (xy 388.913085 -309.503363) (xy 388.864866 -309.493519)
			(xy 388.81885 -309.476067) (xy 388.776229 -309.45146) (xy 388.738108 -309.420335) (xy 388.705473 -309.383498)
			(xy 388.67917 -309.341902) (xy 388.659879 -309.296626) (xy 388.648102 -309.248842) (xy 388.644142 -309.199788)
			(xy 388.327138 -309.199788) (xy 388.326634 -309.225496) (xy 388.318591 -309.276278) (xy 388.302703 -309.325177)
			(xy 388.27936 -309.370989) (xy 388.249139 -309.412585) (xy 388.212783 -309.448941) (xy 388.171187 -309.479162)
			(xy 388.125375 -309.502505) (xy 388.076476 -309.518393) (xy 388.025694 -309.526436) (xy 387.974278 -309.526436)
			(xy 387.923496 -309.518393) (xy 387.874597 -309.502505) (xy 387.828785 -309.479162) (xy 387.787189 -309.448941)
			(xy 387.750833 -309.412585) (xy 387.720612 -309.370989) (xy 387.697269 -309.325177) (xy 387.681381 -309.276278)
			(xy 387.673338 -309.225496) (xy 387.376674 -309.225496) (xy 387.368631 -309.276278) (xy 387.352743 -309.325177)
			(xy 387.3294 -309.370989) (xy 387.299179 -309.412585) (xy 387.262823 -309.448941) (xy 387.221227 -309.479162)
			(xy 387.175415 -309.502505) (xy 387.126516 -309.518393) (xy 387.075734 -309.526436) (xy 387.024318 -309.526436)
			(xy 386.973536 -309.518393) (xy 386.924637 -309.502505) (xy 386.878825 -309.479162) (xy 386.837229 -309.448941)
			(xy 386.800873 -309.412585) (xy 386.770652 -309.370989) (xy 386.747309 -309.325177) (xy 386.731421 -309.276278)
			(xy 386.723378 -309.225496) (xy 386.404446 -309.225496) (xy 386.39673 -309.272972) (xy 386.381146 -309.319653)
			(xy 386.358275 -309.36323) (xy 386.32871 -309.402574) (xy 386.293217 -309.436666) (xy 386.252714 -309.464622)
			(xy 386.208252 -309.48572) (xy 386.160981 -309.499412) (xy 386.112126 -309.505344) (xy 386.062951 -309.503363)
			(xy 386.014732 -309.493519) (xy 385.968716 -309.476067) (xy 385.926095 -309.45146) (xy 385.887974 -309.420335)
			(xy 385.855339 -309.383498) (xy 385.829036 -309.341902) (xy 385.809745 -309.296626) (xy 385.797968 -309.248842)
			(xy 385.794008 -309.199788) (xy 385.45516 -309.199788) (xy 385.454665 -309.224395) (xy 385.44677 -309.272972)
			(xy 385.431186 -309.319653) (xy 385.408315 -309.36323) (xy 385.37875 -309.402574) (xy 385.343257 -309.436666)
			(xy 385.302754 -309.464622) (xy 385.258292 -309.48572) (xy 385.211021 -309.499412) (xy 385.162166 -309.505344)
			(xy 385.112991 -309.503363) (xy 385.064772 -309.493519) (xy 385.018756 -309.476067) (xy 384.976135 -309.45146)
			(xy 384.938014 -309.420335) (xy 384.905379 -309.383498) (xy 384.879076 -309.341902) (xy 384.859785 -309.296626)
			(xy 384.848008 -309.248842) (xy 384.844048 -309.199788) (xy 375.996502 -309.199788) (xy 376.015141 -309.22796)
			(xy 376.038813 -309.278457) (xy 376.054881 -309.331864) (xy 376.063001 -309.38704) (xy 376.06351 -309.414926)
			(xy 376.063001 -309.442812) (xy 376.054881 -309.497988) (xy 376.038813 -309.551395) (xy 376.015141 -309.601892)
			(xy 375.984368 -309.648405) (xy 375.947151 -309.689942) (xy 375.904283 -309.725617) (xy 375.856677 -309.754671)
			(xy 375.805348 -309.776483) (xy 375.751391 -309.790589) (xy 375.695954 -309.796689) (xy 375.64022 -309.794652)
			(xy 375.585377 -309.784522) (xy 375.532593 -309.766515) (xy 375.482993 -309.741014) (xy 375.437635 -309.708563)
			(xy 375.397486 -309.669854) (xy 375.3634 -309.625711) (xy 375.336104 -309.577076) (xy 375.316181 -309.524985)
			(xy 375.304055 -309.470548) (xy 375.299984 -309.414926) (xy 351.031048 -309.414926) (xy 351.031048 -309.897272)
			(xy 382.740406 -309.897272) (xy 382.744477 -309.84165) (xy 382.756603 -309.787213) (xy 382.776526 -309.735122)
			(xy 382.803822 -309.686487) (xy 382.837908 -309.642344) (xy 382.878057 -309.603635) (xy 382.923415 -309.571184)
			(xy 382.973015 -309.545683) (xy 383.025799 -309.527676) (xy 383.080642 -309.517546) (xy 383.136376 -309.515509)
			(xy 383.191813 -309.521609) (xy 383.24577 -309.535715) (xy 383.297099 -309.557527) (xy 383.344705 -309.586581)
			(xy 383.387573 -309.622256) (xy 383.42479 -309.663793) (xy 383.455563 -309.710306) (xy 383.479235 -309.760803)
			(xy 383.495303 -309.81421) (xy 383.503423 -309.869386) (xy 383.503932 -309.897272) (xy 383.503423 -309.925158)
			(xy 383.495303 -309.980334) (xy 383.479235 -310.033741) (xy 383.455563 -310.084238) (xy 383.42479 -310.130751)
			(xy 383.407541 -310.150002) (xy 383.893834 -310.150002) (xy 383.897794 -310.100948) (xy 383.909571 -310.053164)
			(xy 383.928862 -310.007888) (xy 383.955165 -309.966292) (xy 383.9878 -309.929455) (xy 384.025921 -309.89833)
			(xy 384.068542 -309.873723) (xy 384.114558 -309.856271) (xy 384.162777 -309.846427) (xy 384.211952 -309.844446)
			(xy 384.260807 -309.850378) (xy 384.308078 -309.86407) (xy 384.35254 -309.885168) (xy 384.393043 -309.913124)
			(xy 384.428536 -309.947216) (xy 384.458101 -309.98656) (xy 384.480972 -310.030137) (xy 384.496556 -310.076818)
			(xy 384.504451 -310.125395) (xy 384.504946 -310.150002) (xy 384.504451 -310.174609) (xy 384.504313 -310.175456)
			(xy 384.823204 -310.175456) (xy 384.823204 -310.12404) (xy 384.831247 -310.073258) (xy 384.847135 -310.024359)
			(xy 384.870478 -309.978547) (xy 384.900699 -309.936951) (xy 384.937055 -309.900595) (xy 384.978651 -309.870374)
			(xy 385.024463 -309.847031) (xy 385.073362 -309.831143) (xy 385.124144 -309.8231) (xy 385.17556 -309.8231)
			(xy 385.226342 -309.831143) (xy 385.275241 -309.847031) (xy 385.321053 -309.870374) (xy 385.362649 -309.900595)
			(xy 385.399005 -309.936951) (xy 385.429226 -309.978547) (xy 385.452569 -310.024359) (xy 385.468457 -310.073258)
			(xy 385.4765 -310.12404) (xy 385.477004 -310.149748) (xy 385.4765 -310.175456) (xy 385.773164 -310.175456)
			(xy 385.773164 -310.12404) (xy 385.781207 -310.073258) (xy 385.797095 -310.024359) (xy 385.820438 -309.978547)
			(xy 385.850659 -309.936951) (xy 385.887015 -309.900595) (xy 385.928611 -309.870374) (xy 385.974423 -309.847031)
			(xy 386.023322 -309.831143) (xy 386.074104 -309.8231) (xy 386.12552 -309.8231) (xy 386.176302 -309.831143)
			(xy 386.225201 -309.847031) (xy 386.271013 -309.870374) (xy 386.312609 -309.900595) (xy 386.348965 -309.936951)
			(xy 386.379186 -309.978547) (xy 386.402529 -310.024359) (xy 386.418417 -310.073258) (xy 386.42646 -310.12404)
			(xy 386.426964 -310.149748) (xy 386.744222 -310.149748) (xy 386.748182 -310.100694) (xy 386.759959 -310.05291)
			(xy 386.77925 -310.007634) (xy 386.805553 -309.966038) (xy 386.838188 -309.929201) (xy 386.876309 -309.898076)
			(xy 386.91893 -309.873469) (xy 386.964946 -309.856017) (xy 387.013165 -309.846173) (xy 387.06234 -309.844192)
			(xy 387.111195 -309.850124) (xy 387.158466 -309.863816) (xy 387.202928 -309.884914) (xy 387.243431 -309.91287)
			(xy 387.278924 -309.946962) (xy 387.308489 -309.986306) (xy 387.33136 -310.029883) (xy 387.346944 -310.076564)
			(xy 387.354839 -310.125141) (xy 387.355334 -310.149748) (xy 387.694182 -310.149748) (xy 387.698142 -310.100694)
			(xy 387.709919 -310.05291) (xy 387.72921 -310.007634) (xy 387.755513 -309.966038) (xy 387.788148 -309.929201)
			(xy 387.826269 -309.898076) (xy 387.86889 -309.873469) (xy 387.914906 -309.856017) (xy 387.963125 -309.846173)
			(xy 388.0123 -309.844192) (xy 388.061155 -309.850124) (xy 388.108426 -309.863816) (xy 388.152888 -309.884914)
			(xy 388.193391 -309.91287) (xy 388.228884 -309.946962) (xy 388.258449 -309.986306) (xy 388.28132 -310.029883)
			(xy 388.296904 -310.076564) (xy 388.304799 -310.125141) (xy 388.305294 -310.149748) (xy 388.304799 -310.174355)
			(xy 388.296904 -310.222932) (xy 388.28132 -310.269613) (xy 388.258449 -310.31319) (xy 388.228884 -310.352534)
			(xy 388.193391 -310.386626) (xy 388.152888 -310.414582) (xy 388.108426 -310.43568) (xy 388.061155 -310.449372)
			(xy 388.0123 -310.455304) (xy 387.963125 -310.453323) (xy 387.914906 -310.443479) (xy 387.86889 -310.426027)
			(xy 387.826269 -310.40142) (xy 387.788148 -310.370295) (xy 387.755513 -310.333458) (xy 387.72921 -310.291862)
			(xy 387.709919 -310.246586) (xy 387.698142 -310.198802) (xy 387.694182 -310.149748) (xy 387.355334 -310.149748)
			(xy 387.354839 -310.174355) (xy 387.346944 -310.222932) (xy 387.33136 -310.269613) (xy 387.308489 -310.31319)
			(xy 387.278924 -310.352534) (xy 387.243431 -310.386626) (xy 387.202928 -310.414582) (xy 387.158466 -310.43568)
			(xy 387.111195 -310.449372) (xy 387.06234 -310.455304) (xy 387.013165 -310.453323) (xy 386.964946 -310.443479)
			(xy 386.91893 -310.426027) (xy 386.876309 -310.40142) (xy 386.838188 -310.370295) (xy 386.805553 -310.333458)
			(xy 386.77925 -310.291862) (xy 386.759959 -310.246586) (xy 386.748182 -310.198802) (xy 386.744222 -310.149748)
			(xy 386.426964 -310.149748) (xy 386.42646 -310.175456) (xy 386.418417 -310.226238) (xy 386.402529 -310.275137)
			(xy 386.379186 -310.320949) (xy 386.348965 -310.362545) (xy 386.312609 -310.398901) (xy 386.271013 -310.429122)
			(xy 386.225201 -310.452465) (xy 386.176302 -310.468353) (xy 386.12552 -310.476396) (xy 386.074104 -310.476396)
			(xy 386.023322 -310.468353) (xy 385.974423 -310.452465) (xy 385.928611 -310.429122) (xy 385.887015 -310.398901)
			(xy 385.850659 -310.362545) (xy 385.820438 -310.320949) (xy 385.797095 -310.275137) (xy 385.781207 -310.226238)
			(xy 385.773164 -310.175456) (xy 385.4765 -310.175456) (xy 385.468457 -310.226238) (xy 385.452569 -310.275137)
			(xy 385.429226 -310.320949) (xy 385.399005 -310.362545) (xy 385.362649 -310.398901) (xy 385.321053 -310.429122)
			(xy 385.275241 -310.452465) (xy 385.226342 -310.468353) (xy 385.17556 -310.476396) (xy 385.124144 -310.476396)
			(xy 385.073362 -310.468353) (xy 385.024463 -310.452465) (xy 384.978651 -310.429122) (xy 384.937055 -310.398901)
			(xy 384.900699 -310.362545) (xy 384.870478 -310.320949) (xy 384.847135 -310.275137) (xy 384.831247 -310.226238)
			(xy 384.823204 -310.175456) (xy 384.504313 -310.175456) (xy 384.496556 -310.223186) (xy 384.480972 -310.269867)
			(xy 384.458101 -310.313444) (xy 384.428536 -310.352788) (xy 384.393043 -310.38688) (xy 384.35254 -310.414836)
			(xy 384.308078 -310.435934) (xy 384.260807 -310.449626) (xy 384.211952 -310.455558) (xy 384.162777 -310.453577)
			(xy 384.114558 -310.443733) (xy 384.068542 -310.426281) (xy 384.025921 -310.401674) (xy 383.9878 -310.370549)
			(xy 383.955165 -310.333712) (xy 383.928862 -310.292116) (xy 383.909571 -310.24684) (xy 383.897794 -310.199056)
			(xy 383.893834 -310.150002) (xy 383.407541 -310.150002) (xy 383.387573 -310.172288) (xy 383.344705 -310.207963)
			(xy 383.297099 -310.237017) (xy 383.24577 -310.258829) (xy 383.191813 -310.272935) (xy 383.136376 -310.279035)
			(xy 383.080642 -310.276998) (xy 383.025799 -310.266868) (xy 382.973015 -310.248861) (xy 382.923415 -310.22336)
			(xy 382.878057 -310.190909) (xy 382.837908 -310.1522) (xy 382.803822 -310.108057) (xy 382.776526 -310.059422)
			(xy 382.756603 -310.007331) (xy 382.744477 -309.952894) (xy 382.740406 -309.897272) (xy 351.031048 -309.897272)
			(xy 351.031048 -310.832246) (xy 376.567952 -310.832246) (xy 376.572023 -310.776624) (xy 376.584149 -310.722187)
			(xy 376.604072 -310.670096) (xy 376.631368 -310.621461) (xy 376.665454 -310.577318) (xy 376.705603 -310.538609)
			(xy 376.750961 -310.506158) (xy 376.800561 -310.480657) (xy 376.853345 -310.46265) (xy 376.908188 -310.45252)
			(xy 376.963922 -310.450483) (xy 377.019359 -310.456583) (xy 377.073316 -310.470689) (xy 377.124645 -310.492501)
			(xy 377.172251 -310.521555) (xy 377.215119 -310.55723) (xy 377.252336 -310.598767) (xy 377.283109 -310.64528)
			(xy 377.306781 -310.695777) (xy 377.322849 -310.749184) (xy 377.330969 -310.80436) (xy 377.331478 -310.832246)
			(xy 377.330969 -310.860132) (xy 377.322849 -310.915308) (xy 377.306781 -310.968715) (xy 377.284667 -311.015888)
			(xy 382.57175 -311.015888) (xy 382.575821 -310.960266) (xy 382.587947 -310.905829) (xy 382.60787 -310.853738)
			(xy 382.635166 -310.805103) (xy 382.669252 -310.76096) (xy 382.709401 -310.722251) (xy 382.754759 -310.6898)
			(xy 382.804359 -310.664299) (xy 382.857143 -310.646292) (xy 382.911986 -310.636162) (xy 382.96772 -310.634125)
			(xy 383.023157 -310.640225) (xy 383.077114 -310.654331) (xy 383.128443 -310.676143) (xy 383.176049 -310.705197)
			(xy 383.218917 -310.740872) (xy 383.256134 -310.782409) (xy 383.286907 -310.828922) (xy 383.310579 -310.879419)
			(xy 383.326647 -310.932826) (xy 383.334767 -310.988002) (xy 383.335276 -311.015888) (xy 383.334767 -311.043774)
			(xy 383.326647 -311.09895) (xy 383.326343 -311.099962) (xy 384.844048 -311.099962) (xy 384.848008 -311.050908)
			(xy 384.859785 -311.003124) (xy 384.879076 -310.957848) (xy 384.905379 -310.916252) (xy 384.938014 -310.879415)
			(xy 384.976135 -310.84829) (xy 385.018756 -310.823683) (xy 385.064772 -310.806231) (xy 385.112991 -310.796387)
			(xy 385.162166 -310.794406) (xy 385.211021 -310.800338) (xy 385.258292 -310.81403) (xy 385.302754 -310.835128)
			(xy 385.343257 -310.863084) (xy 385.37875 -310.897176) (xy 385.408315 -310.93652) (xy 385.431186 -310.980097)
			(xy 385.44677 -311.026778) (xy 385.454665 -311.075355) (xy 385.45516 -311.099962) (xy 385.794008 -311.099962)
			(xy 385.797968 -311.050908) (xy 385.809745 -311.003124) (xy 385.829036 -310.957848) (xy 385.855339 -310.916252)
			(xy 385.887974 -310.879415) (xy 385.926095 -310.84829) (xy 385.968716 -310.823683) (xy 386.014732 -310.806231)
			(xy 386.062951 -310.796387) (xy 386.112126 -310.794406) (xy 386.160981 -310.800338) (xy 386.208252 -310.81403)
			(xy 386.252714 -310.835128) (xy 386.293217 -310.863084) (xy 386.32871 -310.897176) (xy 386.358275 -310.93652)
			(xy 386.381146 -310.980097) (xy 386.39673 -311.026778) (xy 386.404625 -311.075355) (xy 386.40512 -311.099962)
			(xy 386.744222 -311.099962) (xy 386.748182 -311.050908) (xy 386.759959 -311.003124) (xy 386.77925 -310.957848)
			(xy 386.805553 -310.916252) (xy 386.838188 -310.879415) (xy 386.876309 -310.84829) (xy 386.91893 -310.823683)
			(xy 386.964946 -310.806231) (xy 387.013165 -310.796387) (xy 387.06234 -310.794406) (xy 387.111195 -310.800338)
			(xy 387.158466 -310.81403) (xy 387.202928 -310.835128) (xy 387.243431 -310.863084) (xy 387.278924 -310.897176)
			(xy 387.308489 -310.93652) (xy 387.33136 -310.980097) (xy 387.346944 -311.026778) (xy 387.354839 -311.075355)
			(xy 387.355334 -311.099962) (xy 387.354839 -311.124569) (xy 387.35466 -311.12567) (xy 387.673338 -311.12567)
			(xy 387.673338 -311.074254) (xy 387.681381 -311.023472) (xy 387.697269 -310.974573) (xy 387.720612 -310.928761)
			(xy 387.750833 -310.887165) (xy 387.787189 -310.850809) (xy 387.828785 -310.820588) (xy 387.874597 -310.797245)
			(xy 387.923496 -310.781357) (xy 387.974278 -310.773314) (xy 388.025694 -310.773314) (xy 388.076476 -310.781357)
			(xy 388.125375 -310.797245) (xy 388.171187 -310.820588) (xy 388.212783 -310.850809) (xy 388.249139 -310.887165)
			(xy 388.27936 -310.928761) (xy 388.302703 -310.974573) (xy 388.318591 -311.023472) (xy 388.326634 -311.074254)
			(xy 388.327138 -311.099962) (xy 388.326634 -311.12567) (xy 388.318591 -311.176452) (xy 388.302703 -311.225351)
			(xy 388.27936 -311.271163) (xy 388.249139 -311.312759) (xy 388.212783 -311.349115) (xy 388.171187 -311.379336)
			(xy 388.125375 -311.402679) (xy 388.076476 -311.418567) (xy 388.025694 -311.42661) (xy 387.974278 -311.42661)
			(xy 387.923496 -311.418567) (xy 387.874597 -311.402679) (xy 387.828785 -311.379336) (xy 387.787189 -311.349115)
			(xy 387.750833 -311.312759) (xy 387.720612 -311.271163) (xy 387.697269 -311.225351) (xy 387.681381 -311.176452)
			(xy 387.673338 -311.12567) (xy 387.35466 -311.12567) (xy 387.346944 -311.173146) (xy 387.33136 -311.219827)
			(xy 387.308489 -311.263404) (xy 387.278924 -311.302748) (xy 387.243431 -311.33684) (xy 387.202928 -311.364796)
			(xy 387.158466 -311.385894) (xy 387.111195 -311.399586) (xy 387.06234 -311.405518) (xy 387.013165 -311.403537)
			(xy 386.964946 -311.393693) (xy 386.91893 -311.376241) (xy 386.876309 -311.351634) (xy 386.838188 -311.320509)
			(xy 386.805553 -311.283672) (xy 386.77925 -311.242076) (xy 386.759959 -311.1968) (xy 386.748182 -311.149016)
			(xy 386.744222 -311.099962) (xy 386.40512 -311.099962) (xy 386.404625 -311.124569) (xy 386.39673 -311.173146)
			(xy 386.381146 -311.219827) (xy 386.358275 -311.263404) (xy 386.32871 -311.302748) (xy 386.293217 -311.33684)
			(xy 386.252714 -311.364796) (xy 386.208252 -311.385894) (xy 386.160981 -311.399586) (xy 386.112126 -311.405518)
			(xy 386.062951 -311.403537) (xy 386.014732 -311.393693) (xy 385.968716 -311.376241) (xy 385.926095 -311.351634)
			(xy 385.887974 -311.320509) (xy 385.855339 -311.283672) (xy 385.829036 -311.242076) (xy 385.809745 -311.1968)
			(xy 385.797968 -311.149016) (xy 385.794008 -311.099962) (xy 385.45516 -311.099962) (xy 385.454665 -311.124569)
			(xy 385.44677 -311.173146) (xy 385.431186 -311.219827) (xy 385.408315 -311.263404) (xy 385.37875 -311.302748)
			(xy 385.343257 -311.33684) (xy 385.302754 -311.364796) (xy 385.258292 -311.385894) (xy 385.211021 -311.399586)
			(xy 385.162166 -311.405518) (xy 385.112991 -311.403537) (xy 385.064772 -311.393693) (xy 385.018756 -311.376241)
			(xy 384.976135 -311.351634) (xy 384.938014 -311.320509) (xy 384.905379 -311.283672) (xy 384.879076 -311.242076)
			(xy 384.859785 -311.1968) (xy 384.848008 -311.149016) (xy 384.844048 -311.099962) (xy 383.326343 -311.099962)
			(xy 383.310579 -311.152357) (xy 383.286907 -311.202854) (xy 383.256134 -311.249367) (xy 383.218917 -311.290904)
			(xy 383.176049 -311.326579) (xy 383.128443 -311.355633) (xy 383.077114 -311.377445) (xy 383.023157 -311.391551)
			(xy 382.96772 -311.397651) (xy 382.911986 -311.395614) (xy 382.857143 -311.385484) (xy 382.804359 -311.367477)
			(xy 382.754759 -311.341976) (xy 382.709401 -311.309525) (xy 382.669252 -311.270816) (xy 382.635166 -311.226673)
			(xy 382.60787 -311.178038) (xy 382.587947 -311.125947) (xy 382.575821 -311.07151) (xy 382.57175 -311.015888)
			(xy 377.284667 -311.015888) (xy 377.283109 -311.019212) (xy 377.252336 -311.065725) (xy 377.215119 -311.107262)
			(xy 377.172251 -311.142937) (xy 377.124645 -311.171991) (xy 377.073316 -311.193803) (xy 377.019359 -311.207909)
			(xy 376.963922 -311.214009) (xy 376.908188 -311.211972) (xy 376.853345 -311.201842) (xy 376.800561 -311.183835)
			(xy 376.750961 -311.158334) (xy 376.705603 -311.125883) (xy 376.665454 -311.087174) (xy 376.631368 -311.043031)
			(xy 376.604072 -310.994396) (xy 376.584149 -310.942305) (xy 376.572023 -310.887868) (xy 376.567952 -310.832246)
			(xy 351.031048 -310.832246) (xy 351.031048 -311.7342) (xy 380.789432 -311.7342) (xy 380.793503 -311.678578)
			(xy 380.805629 -311.624141) (xy 380.825552 -311.57205) (xy 380.852848 -311.523415) (xy 380.886934 -311.479272)
			(xy 380.927083 -311.440563) (xy 380.972441 -311.408112) (xy 381.022041 -311.382611) (xy 381.074825 -311.364604)
			(xy 381.129668 -311.354474) (xy 381.185402 -311.352437) (xy 381.240839 -311.358537) (xy 381.294796 -311.372643)
			(xy 381.346125 -311.394455) (xy 381.393731 -311.423509) (xy 381.436599 -311.459184) (xy 381.473816 -311.500721)
			(xy 381.504589 -311.547234) (xy 381.528261 -311.597731) (xy 381.544329 -311.651138) (xy 381.552449 -311.706314)
			(xy 381.552958 -311.7342) (xy 381.552449 -311.762086) (xy 381.544329 -311.817262) (xy 381.528261 -311.870669)
			(xy 381.504589 -311.921166) (xy 381.473816 -311.967679) (xy 381.436599 -312.009216) (xy 381.393731 -312.044891)
			(xy 381.346125 -312.073945) (xy 381.294796 -312.095757) (xy 381.240839 -312.109863) (xy 381.185402 -312.115963)
			(xy 381.129668 -312.113926) (xy 381.074825 -312.103796) (xy 381.022041 -312.085789) (xy 380.972441 -312.060288)
			(xy 380.927083 -312.027837) (xy 380.886934 -311.989128) (xy 380.852848 -311.944985) (xy 380.825552 -311.89635)
			(xy 380.805629 -311.844259) (xy 380.793503 -311.789822) (xy 380.789432 -311.7342) (xy 351.031048 -311.7342)
			(xy 351.031048 -312.523378) (xy 380.032004 -312.523378) (xy 380.036075 -312.467756) (xy 380.048201 -312.413319)
			(xy 380.068124 -312.361228) (xy 380.09542 -312.312593) (xy 380.129506 -312.26845) (xy 380.169655 -312.229741)
			(xy 380.215013 -312.19729) (xy 380.264613 -312.171789) (xy 380.317397 -312.153782) (xy 380.37224 -312.143652)
			(xy 380.427974 -312.141615) (xy 380.483411 -312.147715) (xy 380.537368 -312.161821) (xy 380.588697 -312.183633)
			(xy 380.636303 -312.212687) (xy 380.679171 -312.248362) (xy 380.696863 -312.268108) (xy 382.410714 -312.268108)
			(xy 382.414785 -312.212486) (xy 382.426911 -312.158049) (xy 382.446834 -312.105958) (xy 382.47413 -312.057323)
			(xy 382.508216 -312.01318) (xy 382.548365 -311.974471) (xy 382.593723 -311.94202) (xy 382.643323 -311.916519)
			(xy 382.696107 -311.898512) (xy 382.75095 -311.888382) (xy 382.806684 -311.886345) (xy 382.862121 -311.892445)
			(xy 382.916078 -311.906551) (xy 382.967407 -311.928363) (xy 383.015013 -311.957417) (xy 383.057881 -311.993092)
			(xy 383.095098 -312.034629) (xy 383.105048 -312.049668) (xy 383.893834 -312.049668) (xy 383.897794 -312.000614)
			(xy 383.909571 -311.95283) (xy 383.928862 -311.907554) (xy 383.955165 -311.865958) (xy 383.9878 -311.829121)
			(xy 384.025921 -311.797996) (xy 384.068542 -311.773389) (xy 384.114558 -311.755937) (xy 384.162777 -311.746093)
			(xy 384.211952 -311.744112) (xy 384.260807 -311.750044) (xy 384.308078 -311.763736) (xy 384.35254 -311.784834)
			(xy 384.393043 -311.81279) (xy 384.428536 -311.846882) (xy 384.458101 -311.886226) (xy 384.480972 -311.929803)
			(xy 384.496556 -311.976484) (xy 384.504451 -312.025061) (xy 384.504946 -312.049668) (xy 384.504451 -312.074275)
			(xy 384.504231 -312.07563) (xy 384.823204 -312.07563) (xy 384.823204 -312.024214) (xy 384.831247 -311.973432)
			(xy 384.847135 -311.924533) (xy 384.870478 -311.878721) (xy 384.900699 -311.837125) (xy 384.937055 -311.800769)
			(xy 384.978651 -311.770548) (xy 385.024463 -311.747205) (xy 385.073362 -311.731317) (xy 385.124144 -311.723274)
			(xy 385.17556 -311.723274) (xy 385.226342 -311.731317) (xy 385.275241 -311.747205) (xy 385.321053 -311.770548)
			(xy 385.362649 -311.800769) (xy 385.399005 -311.837125) (xy 385.429226 -311.878721) (xy 385.452569 -311.924533)
			(xy 385.468457 -311.973432) (xy 385.4765 -312.024214) (xy 385.477004 -312.049922) (xy 385.4765 -312.07563)
			(xy 385.773164 -312.07563) (xy 385.773164 -312.024214) (xy 385.781207 -311.973432) (xy 385.797095 -311.924533)
			(xy 385.820438 -311.878721) (xy 385.850659 -311.837125) (xy 385.887015 -311.800769) (xy 385.928611 -311.770548)
			(xy 385.974423 -311.747205) (xy 386.023322 -311.731317) (xy 386.074104 -311.723274) (xy 386.12552 -311.723274)
			(xy 386.176302 -311.731317) (xy 386.225201 -311.747205) (xy 386.271013 -311.770548) (xy 386.312609 -311.800769)
			(xy 386.348965 -311.837125) (xy 386.379186 -311.878721) (xy 386.402529 -311.924533) (xy 386.418417 -311.973432)
			(xy 386.42646 -312.024214) (xy 386.426964 -312.049922) (xy 386.744222 -312.049922) (xy 386.748182 -312.000868)
			(xy 386.759959 -311.953084) (xy 386.77925 -311.907808) (xy 386.805553 -311.866212) (xy 386.838188 -311.829375)
			(xy 386.876309 -311.79825) (xy 386.91893 -311.773643) (xy 386.964946 -311.756191) (xy 387.013165 -311.746347)
			(xy 387.06234 -311.744366) (xy 387.111195 -311.750298) (xy 387.158466 -311.76399) (xy 387.202928 -311.785088)
			(xy 387.243431 -311.813044) (xy 387.278924 -311.847136) (xy 387.308489 -311.88648) (xy 387.33136 -311.930057)
			(xy 387.346944 -311.976738) (xy 387.354839 -312.025315) (xy 387.355334 -312.049922) (xy 387.354839 -312.074529)
			(xy 387.35466 -312.07563) (xy 387.673338 -312.07563) (xy 387.673338 -312.024214) (xy 387.681381 -311.973432)
			(xy 387.697269 -311.924533) (xy 387.720612 -311.878721) (xy 387.750833 -311.837125) (xy 387.787189 -311.800769)
			(xy 387.828785 -311.770548) (xy 387.874597 -311.747205) (xy 387.923496 -311.731317) (xy 387.974278 -311.723274)
			(xy 388.025694 -311.723274) (xy 388.076476 -311.731317) (xy 388.125375 -311.747205) (xy 388.171187 -311.770548)
			(xy 388.212783 -311.800769) (xy 388.249139 -311.837125) (xy 388.27936 -311.878721) (xy 388.302703 -311.924533)
			(xy 388.318591 -311.973432) (xy 388.326634 -312.024214) (xy 388.327138 -312.049922) (xy 388.326634 -312.07563)
			(xy 388.318591 -312.126412) (xy 388.302703 -312.175311) (xy 388.27936 -312.221123) (xy 388.249139 -312.262719)
			(xy 388.212783 -312.299075) (xy 388.171187 -312.329296) (xy 388.125375 -312.352639) (xy 388.076476 -312.368527)
			(xy 388.025694 -312.37657) (xy 387.974278 -312.37657) (xy 387.923496 -312.368527) (xy 387.874597 -312.352639)
			(xy 387.828785 -312.329296) (xy 387.787189 -312.299075) (xy 387.750833 -312.262719) (xy 387.720612 -312.221123)
			(xy 387.697269 -312.175311) (xy 387.681381 -312.126412) (xy 387.673338 -312.07563) (xy 387.35466 -312.07563)
			(xy 387.346944 -312.123106) (xy 387.33136 -312.169787) (xy 387.308489 -312.213364) (xy 387.278924 -312.252708)
			(xy 387.243431 -312.2868) (xy 387.202928 -312.314756) (xy 387.158466 -312.335854) (xy 387.111195 -312.349546)
			(xy 387.06234 -312.355478) (xy 387.013165 -312.353497) (xy 386.964946 -312.343653) (xy 386.91893 -312.326201)
			(xy 386.876309 -312.301594) (xy 386.838188 -312.270469) (xy 386.805553 -312.233632) (xy 386.77925 -312.192036)
			(xy 386.759959 -312.14676) (xy 386.748182 -312.098976) (xy 386.744222 -312.049922) (xy 386.426964 -312.049922)
			(xy 386.42646 -312.07563) (xy 386.418417 -312.126412) (xy 386.402529 -312.175311) (xy 386.379186 -312.221123)
			(xy 386.348965 -312.262719) (xy 386.312609 -312.299075) (xy 386.271013 -312.329296) (xy 386.225201 -312.352639)
			(xy 386.176302 -312.368527) (xy 386.12552 -312.37657) (xy 386.074104 -312.37657) (xy 386.023322 -312.368527)
			(xy 385.974423 -312.352639) (xy 385.928611 -312.329296) (xy 385.887015 -312.299075) (xy 385.850659 -312.262719)
			(xy 385.820438 -312.221123) (xy 385.797095 -312.175311) (xy 385.781207 -312.126412) (xy 385.773164 -312.07563)
			(xy 385.4765 -312.07563) (xy 385.468457 -312.126412) (xy 385.452569 -312.175311) (xy 385.429226 -312.221123)
			(xy 385.399005 -312.262719) (xy 385.362649 -312.299075) (xy 385.321053 -312.329296) (xy 385.275241 -312.352639)
			(xy 385.226342 -312.368527) (xy 385.17556 -312.37657) (xy 385.124144 -312.37657) (xy 385.073362 -312.368527)
			(xy 385.024463 -312.352639) (xy 384.978651 -312.329296) (xy 384.937055 -312.299075) (xy 384.900699 -312.262719)
			(xy 384.870478 -312.221123) (xy 384.847135 -312.175311) (xy 384.831247 -312.126412) (xy 384.823204 -312.07563)
			(xy 384.504231 -312.07563) (xy 384.496556 -312.122852) (xy 384.480972 -312.169533) (xy 384.458101 -312.21311)
			(xy 384.428536 -312.252454) (xy 384.393043 -312.286546) (xy 384.35254 -312.314502) (xy 384.308078 -312.3356)
			(xy 384.260807 -312.349292) (xy 384.211952 -312.355224) (xy 384.162777 -312.353243) (xy 384.114558 -312.343399)
			(xy 384.068542 -312.325947) (xy 384.025921 -312.30134) (xy 383.9878 -312.270215) (xy 383.955165 -312.233378)
			(xy 383.928862 -312.191782) (xy 383.909571 -312.146506) (xy 383.897794 -312.098722) (xy 383.893834 -312.049668)
			(xy 383.105048 -312.049668) (xy 383.125871 -312.081142) (xy 383.149543 -312.131639) (xy 383.165611 -312.185046)
			(xy 383.173731 -312.240222) (xy 383.17424 -312.268108) (xy 383.173731 -312.295994) (xy 383.165611 -312.35117)
			(xy 383.149543 -312.404577) (xy 383.125871 -312.455074) (xy 383.095098 -312.501587) (xy 383.057881 -312.543124)
			(xy 383.015013 -312.578799) (xy 382.967407 -312.607853) (xy 382.916078 -312.629665) (xy 382.862121 -312.643771)
			(xy 382.806684 -312.649871) (xy 382.75095 -312.647834) (xy 382.696107 -312.637704) (xy 382.643323 -312.619697)
			(xy 382.593723 -312.594196) (xy 382.548365 -312.561745) (xy 382.508216 -312.523036) (xy 382.47413 -312.478893)
			(xy 382.446834 -312.430258) (xy 382.426911 -312.378167) (xy 382.414785 -312.32373) (xy 382.410714 -312.268108)
			(xy 380.696863 -312.268108) (xy 380.716388 -312.289899) (xy 380.747161 -312.336412) (xy 380.770833 -312.386909)
			(xy 380.786901 -312.440316) (xy 380.795021 -312.495492) (xy 380.79553 -312.523378) (xy 380.795021 -312.551264)
			(xy 380.786901 -312.60644) (xy 380.770833 -312.659847) (xy 380.747161 -312.710344) (xy 380.716388 -312.756857)
			(xy 380.679171 -312.798394) (xy 380.636303 -312.834069) (xy 380.588697 -312.863123) (xy 380.537368 -312.884935)
			(xy 380.483411 -312.899041) (xy 380.427974 -312.905141) (xy 380.37224 -312.903104) (xy 380.317397 -312.892974)
			(xy 380.264613 -312.874967) (xy 380.215013 -312.849466) (xy 380.169655 -312.817015) (xy 380.129506 -312.778306)
			(xy 380.09542 -312.734163) (xy 380.068124 -312.685528) (xy 380.048201 -312.633437) (xy 380.036075 -312.579)
			(xy 380.032004 -312.523378) (xy 351.031048 -312.523378) (xy 351.031048 -312.999882) (xy 384.844048 -312.999882)
			(xy 384.848008 -312.950828) (xy 384.859785 -312.903044) (xy 384.879076 -312.857768) (xy 384.905379 -312.816172)
			(xy 384.938014 -312.779335) (xy 384.976135 -312.74821) (xy 385.018756 -312.723603) (xy 385.064772 -312.706151)
			(xy 385.112991 -312.696307) (xy 385.162166 -312.694326) (xy 385.211021 -312.700258) (xy 385.258292 -312.71395)
			(xy 385.302754 -312.735048) (xy 385.343257 -312.763004) (xy 385.37875 -312.797096) (xy 385.408315 -312.83644)
			(xy 385.431186 -312.880017) (xy 385.44677 -312.926698) (xy 385.454665 -312.975275) (xy 385.45516 -312.999882)
			(xy 385.794008 -312.999882) (xy 385.797968 -312.950828) (xy 385.809745 -312.903044) (xy 385.829036 -312.857768)
			(xy 385.855339 -312.816172) (xy 385.887974 -312.779335) (xy 385.926095 -312.74821) (xy 385.968716 -312.723603)
			(xy 386.014732 -312.706151) (xy 386.062951 -312.696307) (xy 386.112126 -312.694326) (xy 386.160981 -312.700258)
			(xy 386.208252 -312.71395) (xy 386.252714 -312.735048) (xy 386.293217 -312.763004) (xy 386.32871 -312.797096)
			(xy 386.358275 -312.83644) (xy 386.381146 -312.880017) (xy 386.39673 -312.926698) (xy 386.404625 -312.975275)
			(xy 386.40512 -312.999882) (xy 386.404625 -313.024489) (xy 386.404446 -313.02559) (xy 386.723378 -313.02559)
			(xy 386.723378 -312.974174) (xy 386.731421 -312.923392) (xy 386.747309 -312.874493) (xy 386.770652 -312.828681)
			(xy 386.800873 -312.787085) (xy 386.837229 -312.750729) (xy 386.878825 -312.720508) (xy 386.924637 -312.697165)
			(xy 386.973536 -312.681277) (xy 387.024318 -312.673234) (xy 387.075734 -312.673234) (xy 387.126516 -312.681277)
			(xy 387.175415 -312.697165) (xy 387.221227 -312.720508) (xy 387.262823 -312.750729) (xy 387.299179 -312.787085)
			(xy 387.3294 -312.828681) (xy 387.352743 -312.874493) (xy 387.368631 -312.923392) (xy 387.376674 -312.974174)
			(xy 387.377178 -312.999882) (xy 387.694182 -312.999882) (xy 387.698142 -312.950828) (xy 387.709919 -312.903044)
			(xy 387.72921 -312.857768) (xy 387.755513 -312.816172) (xy 387.788148 -312.779335) (xy 387.826269 -312.74821)
			(xy 387.86889 -312.723603) (xy 387.914906 -312.706151) (xy 387.963125 -312.696307) (xy 388.0123 -312.694326)
			(xy 388.061155 -312.700258) (xy 388.108426 -312.71395) (xy 388.152888 -312.735048) (xy 388.193391 -312.763004)
			(xy 388.228884 -312.797096) (xy 388.258449 -312.83644) (xy 388.28132 -312.880017) (xy 388.296904 -312.926698)
			(xy 388.304799 -312.975275) (xy 388.305294 -312.999882) (xy 388.304799 -313.024489) (xy 388.296904 -313.073066)
			(xy 388.28132 -313.119747) (xy 388.258449 -313.163324) (xy 388.228884 -313.202668) (xy 388.193391 -313.23676)
			(xy 388.152888 -313.264716) (xy 388.108426 -313.285814) (xy 388.061155 -313.299506) (xy 388.0123 -313.305438)
			(xy 387.963125 -313.303457) (xy 387.914906 -313.293613) (xy 387.86889 -313.276161) (xy 387.826269 -313.251554)
			(xy 387.788148 -313.220429) (xy 387.755513 -313.183592) (xy 387.72921 -313.141996) (xy 387.709919 -313.09672)
			(xy 387.698142 -313.048936) (xy 387.694182 -312.999882) (xy 387.377178 -312.999882) (xy 387.376674 -313.02559)
			(xy 387.368631 -313.076372) (xy 387.352743 -313.125271) (xy 387.3294 -313.171083) (xy 387.299179 -313.212679)
			(xy 387.262823 -313.249035) (xy 387.221227 -313.279256) (xy 387.175415 -313.302599) (xy 387.126516 -313.318487)
			(xy 387.075734 -313.32653) (xy 387.024318 -313.32653) (xy 386.973536 -313.318487) (xy 386.924637 -313.302599)
			(xy 386.878825 -313.279256) (xy 386.837229 -313.249035) (xy 386.800873 -313.212679) (xy 386.770652 -313.171083)
			(xy 386.747309 -313.125271) (xy 386.731421 -313.076372) (xy 386.723378 -313.02559) (xy 386.404446 -313.02559)
			(xy 386.39673 -313.073066) (xy 386.381146 -313.119747) (xy 386.358275 -313.163324) (xy 386.32871 -313.202668)
			(xy 386.293217 -313.23676) (xy 386.252714 -313.264716) (xy 386.208252 -313.285814) (xy 386.160981 -313.299506)
			(xy 386.112126 -313.305438) (xy 386.062951 -313.303457) (xy 386.014732 -313.293613) (xy 385.968716 -313.276161)
			(xy 385.926095 -313.251554) (xy 385.887974 -313.220429) (xy 385.855339 -313.183592) (xy 385.829036 -313.141996)
			(xy 385.809745 -313.09672) (xy 385.797968 -313.048936) (xy 385.794008 -312.999882) (xy 385.45516 -312.999882)
			(xy 385.454665 -313.024489) (xy 385.44677 -313.073066) (xy 385.431186 -313.119747) (xy 385.408315 -313.163324)
			(xy 385.37875 -313.202668) (xy 385.343257 -313.23676) (xy 385.302754 -313.264716) (xy 385.258292 -313.285814)
			(xy 385.211021 -313.299506) (xy 385.162166 -313.305438) (xy 385.112991 -313.303457) (xy 385.064772 -313.293613)
			(xy 385.018756 -313.276161) (xy 384.976135 -313.251554) (xy 384.938014 -313.220429) (xy 384.905379 -313.183592)
			(xy 384.879076 -313.141996) (xy 384.859785 -313.09672) (xy 384.848008 -313.048936) (xy 384.844048 -312.999882)
			(xy 351.031048 -312.999882) (xy 351.031048 -313.386724) (xy 351.038668 -313.40552) (xy 351.046034 -313.412632)
			(xy 351.03562 -313.440826) (xy 351.03562 -313.669934) (xy 382.34696 -313.669934) (xy 382.351031 -313.614312)
			(xy 382.363157 -313.559875) (xy 382.38308 -313.507784) (xy 382.410376 -313.459149) (xy 382.444462 -313.415006)
			(xy 382.484611 -313.376297) (xy 382.529969 -313.343846) (xy 382.579569 -313.318345) (xy 382.632353 -313.300338)
			(xy 382.687196 -313.290208) (xy 382.74293 -313.288171) (xy 382.798367 -313.294271) (xy 382.852324 -313.308377)
			(xy 382.903653 -313.330189) (xy 382.951259 -313.359243) (xy 382.994127 -313.394918) (xy 383.031344 -313.436455)
			(xy 383.062117 -313.482968) (xy 383.085789 -313.533465) (xy 383.101857 -313.586872) (xy 383.109977 -313.642048)
			(xy 383.110486 -313.669934) (xy 383.109977 -313.69782) (xy 383.101857 -313.752996) (xy 383.085789 -313.806403)
			(xy 383.062117 -313.8569) (xy 383.031344 -313.903413) (xy 382.994127 -313.94495) (xy 382.988249 -313.949842)
			(xy 384.844048 -313.949842) (xy 384.848008 -313.900788) (xy 384.859785 -313.853004) (xy 384.879076 -313.807728)
			(xy 384.905379 -313.766132) (xy 384.938014 -313.729295) (xy 384.976135 -313.69817) (xy 385.018756 -313.673563)
			(xy 385.064772 -313.656111) (xy 385.112991 -313.646267) (xy 385.162166 -313.644286) (xy 385.211021 -313.650218)
			(xy 385.258292 -313.66391) (xy 385.302754 -313.685008) (xy 385.343257 -313.712964) (xy 385.37875 -313.747056)
			(xy 385.408315 -313.7864) (xy 385.431186 -313.829977) (xy 385.44677 -313.876658) (xy 385.454665 -313.925235)
			(xy 385.45516 -313.949842) (xy 385.794008 -313.949842) (xy 385.797968 -313.900788) (xy 385.809745 -313.853004)
			(xy 385.829036 -313.807728) (xy 385.855339 -313.766132) (xy 385.887974 -313.729295) (xy 385.926095 -313.69817)
			(xy 385.968716 -313.673563) (xy 386.014732 -313.656111) (xy 386.062951 -313.646267) (xy 386.112126 -313.644286)
			(xy 386.160981 -313.650218) (xy 386.208252 -313.66391) (xy 386.252714 -313.685008) (xy 386.293217 -313.712964)
			(xy 386.32871 -313.747056) (xy 386.358275 -313.7864) (xy 386.381146 -313.829977) (xy 386.39673 -313.876658)
			(xy 386.404625 -313.925235) (xy 386.40512 -313.949842) (xy 386.404625 -313.974449) (xy 386.404446 -313.97555)
			(xy 386.723378 -313.97555) (xy 386.723378 -313.924134) (xy 386.731421 -313.873352) (xy 386.747309 -313.824453)
			(xy 386.770652 -313.778641) (xy 386.800873 -313.737045) (xy 386.837229 -313.700689) (xy 386.878825 -313.670468)
			(xy 386.924637 -313.647125) (xy 386.973536 -313.631237) (xy 387.024318 -313.623194) (xy 387.075734 -313.623194)
			(xy 387.126516 -313.631237) (xy 387.175415 -313.647125) (xy 387.221227 -313.670468) (xy 387.262823 -313.700689)
			(xy 387.299179 -313.737045) (xy 387.3294 -313.778641) (xy 387.352743 -313.824453) (xy 387.368631 -313.873352)
			(xy 387.376674 -313.924134) (xy 387.377178 -313.949842) (xy 387.694182 -313.949842) (xy 387.698142 -313.900788)
			(xy 387.709919 -313.853004) (xy 387.72921 -313.807728) (xy 387.755513 -313.766132) (xy 387.788148 -313.729295)
			(xy 387.826269 -313.69817) (xy 387.86889 -313.673563) (xy 387.914906 -313.656111) (xy 387.963125 -313.646267)
			(xy 388.0123 -313.644286) (xy 388.061155 -313.650218) (xy 388.108426 -313.66391) (xy 388.152888 -313.685008)
			(xy 388.193391 -313.712964) (xy 388.228884 -313.747056) (xy 388.258449 -313.7864) (xy 388.28132 -313.829977)
			(xy 388.296904 -313.876658) (xy 388.304799 -313.925235) (xy 388.305294 -313.949842) (xy 388.304799 -313.974449)
			(xy 388.296904 -314.023026) (xy 388.28132 -314.069707) (xy 388.258449 -314.113284) (xy 388.228884 -314.152628)
			(xy 388.193391 -314.18672) (xy 388.152888 -314.214676) (xy 388.108426 -314.235774) (xy 388.061155 -314.249466)
			(xy 388.0123 -314.255398) (xy 387.963125 -314.253417) (xy 387.914906 -314.243573) (xy 387.86889 -314.226121)
			(xy 387.826269 -314.201514) (xy 387.788148 -314.170389) (xy 387.755513 -314.133552) (xy 387.72921 -314.091956)
			(xy 387.709919 -314.04668) (xy 387.698142 -313.998896) (xy 387.694182 -313.949842) (xy 387.377178 -313.949842)
			(xy 387.376674 -313.97555) (xy 387.368631 -314.026332) (xy 387.352743 -314.075231) (xy 387.3294 -314.121043)
			(xy 387.299179 -314.162639) (xy 387.262823 -314.198995) (xy 387.221227 -314.229216) (xy 387.175415 -314.252559)
			(xy 387.126516 -314.268447) (xy 387.075734 -314.27649) (xy 387.024318 -314.27649) (xy 386.973536 -314.268447)
			(xy 386.924637 -314.252559) (xy 386.878825 -314.229216) (xy 386.837229 -314.198995) (xy 386.800873 -314.162639)
			(xy 386.770652 -314.121043) (xy 386.747309 -314.075231) (xy 386.731421 -314.026332) (xy 386.723378 -313.97555)
			(xy 386.404446 -313.97555) (xy 386.39673 -314.023026) (xy 386.381146 -314.069707) (xy 386.358275 -314.113284)
			(xy 386.32871 -314.152628) (xy 386.293217 -314.18672) (xy 386.252714 -314.214676) (xy 386.208252 -314.235774)
			(xy 386.160981 -314.249466) (xy 386.112126 -314.255398) (xy 386.062951 -314.253417) (xy 386.014732 -314.243573)
			(xy 385.968716 -314.226121) (xy 385.926095 -314.201514) (xy 385.887974 -314.170389) (xy 385.855339 -314.133552)
			(xy 385.829036 -314.091956) (xy 385.809745 -314.04668) (xy 385.797968 -313.998896) (xy 385.794008 -313.949842)
			(xy 385.45516 -313.949842) (xy 385.454665 -313.974449) (xy 385.44677 -314.023026) (xy 385.431186 -314.069707)
			(xy 385.408315 -314.113284) (xy 385.37875 -314.152628) (xy 385.343257 -314.18672) (xy 385.302754 -314.214676)
			(xy 385.258292 -314.235774) (xy 385.211021 -314.249466) (xy 385.162166 -314.255398) (xy 385.112991 -314.253417)
			(xy 385.064772 -314.243573) (xy 385.018756 -314.226121) (xy 384.976135 -314.201514) (xy 384.938014 -314.170389)
			(xy 384.905379 -314.133552) (xy 384.879076 -314.091956) (xy 384.859785 -314.04668) (xy 384.848008 -313.998896)
			(xy 384.844048 -313.949842) (xy 382.988249 -313.949842) (xy 382.951259 -313.980625) (xy 382.903653 -314.009679)
			(xy 382.852324 -314.031491) (xy 382.798367 -314.045597) (xy 382.74293 -314.051697) (xy 382.687196 -314.04966)
			(xy 382.632353 -314.03953) (xy 382.579569 -314.021523) (xy 382.529969 -313.996022) (xy 382.484611 -313.963571)
			(xy 382.444462 -313.924862) (xy 382.410376 -313.880719) (xy 382.38308 -313.832084) (xy 382.363157 -313.779993)
			(xy 382.351031 -313.725556) (xy 382.34696 -313.669934) (xy 351.03562 -313.669934) (xy 351.03562 -314.899548)
			(xy 383.89358 -314.899548) (xy 383.89754 -314.850494) (xy 383.909317 -314.80271) (xy 383.928608 -314.757434)
			(xy 383.954911 -314.715838) (xy 383.987546 -314.679001) (xy 384.025667 -314.647876) (xy 384.068288 -314.623269)
			(xy 384.114304 -314.605817) (xy 384.162523 -314.595973) (xy 384.211698 -314.593992) (xy 384.260553 -314.599924)
			(xy 384.307824 -314.613616) (xy 384.352286 -314.634714) (xy 384.392789 -314.66267) (xy 384.428282 -314.696762)
			(xy 384.457847 -314.736106) (xy 384.480718 -314.779683) (xy 384.496302 -314.826364) (xy 384.504197 -314.874941)
			(xy 384.504692 -314.899548) (xy 384.504197 -314.924155) (xy 384.503977 -314.92551) (xy 384.823204 -314.92551)
			(xy 384.823204 -314.874094) (xy 384.831247 -314.823312) (xy 384.847135 -314.774413) (xy 384.870478 -314.728601)
			(xy 384.900699 -314.687005) (xy 384.937055 -314.650649) (xy 384.978651 -314.620428) (xy 385.024463 -314.597085)
			(xy 385.073362 -314.581197) (xy 385.124144 -314.573154) (xy 385.17556 -314.573154) (xy 385.226342 -314.581197)
			(xy 385.275241 -314.597085) (xy 385.321053 -314.620428) (xy 385.362649 -314.650649) (xy 385.399005 -314.687005)
			(xy 385.429226 -314.728601) (xy 385.452569 -314.774413) (xy 385.468457 -314.823312) (xy 385.4765 -314.874094)
			(xy 385.477004 -314.899802) (xy 385.4765 -314.92551) (xy 385.773164 -314.92551) (xy 385.773164 -314.874094)
			(xy 385.781207 -314.823312) (xy 385.797095 -314.774413) (xy 385.820438 -314.728601) (xy 385.850659 -314.687005)
			(xy 385.887015 -314.650649) (xy 385.928611 -314.620428) (xy 385.974423 -314.597085) (xy 386.023322 -314.581197)
			(xy 386.074104 -314.573154) (xy 386.12552 -314.573154) (xy 386.176302 -314.581197) (xy 386.225201 -314.597085)
			(xy 386.271013 -314.620428) (xy 386.312609 -314.650649) (xy 386.348965 -314.687005) (xy 386.379186 -314.728601)
			(xy 386.402529 -314.774413) (xy 386.418417 -314.823312) (xy 386.42646 -314.874094) (xy 386.426964 -314.899802)
			(xy 386.744222 -314.899802) (xy 386.748182 -314.850748) (xy 386.759959 -314.802964) (xy 386.77925 -314.757688)
			(xy 386.805553 -314.716092) (xy 386.838188 -314.679255) (xy 386.876309 -314.64813) (xy 386.91893 -314.623523)
			(xy 386.964946 -314.606071) (xy 387.013165 -314.596227) (xy 387.06234 -314.594246) (xy 387.111195 -314.600178)
			(xy 387.158466 -314.61387) (xy 387.202928 -314.634968) (xy 387.243431 -314.662924) (xy 387.278924 -314.697016)
			(xy 387.308489 -314.73636) (xy 387.33136 -314.779937) (xy 387.346944 -314.826618) (xy 387.354839 -314.875195)
			(xy 387.355334 -314.899802) (xy 387.694182 -314.899802) (xy 387.698142 -314.850748) (xy 387.709919 -314.802964)
			(xy 387.72921 -314.757688) (xy 387.755513 -314.716092) (xy 387.788148 -314.679255) (xy 387.826269 -314.64813)
			(xy 387.86889 -314.623523) (xy 387.914906 -314.606071) (xy 387.963125 -314.596227) (xy 388.0123 -314.594246)
			(xy 388.061155 -314.600178) (xy 388.108426 -314.61387) (xy 388.152888 -314.634968) (xy 388.193391 -314.662924)
			(xy 388.228884 -314.697016) (xy 388.258449 -314.73636) (xy 388.28132 -314.779937) (xy 388.296904 -314.826618)
			(xy 388.304799 -314.875195) (xy 388.305294 -314.899802) (xy 388.304799 -314.924409) (xy 388.296904 -314.972986)
			(xy 388.28132 -315.019667) (xy 388.258449 -315.063244) (xy 388.228884 -315.102588) (xy 388.193391 -315.13668)
			(xy 388.152888 -315.164636) (xy 388.108426 -315.185734) (xy 388.061155 -315.199426) (xy 388.0123 -315.205358)
			(xy 387.963125 -315.203377) (xy 387.914906 -315.193533) (xy 387.86889 -315.176081) (xy 387.826269 -315.151474)
			(xy 387.788148 -315.120349) (xy 387.755513 -315.083512) (xy 387.72921 -315.041916) (xy 387.709919 -314.99664)
			(xy 387.698142 -314.948856) (xy 387.694182 -314.899802) (xy 387.355334 -314.899802) (xy 387.354839 -314.924409)
			(xy 387.346944 -314.972986) (xy 387.33136 -315.019667) (xy 387.308489 -315.063244) (xy 387.278924 -315.102588)
			(xy 387.243431 -315.13668) (xy 387.202928 -315.164636) (xy 387.158466 -315.185734) (xy 387.111195 -315.199426)
			(xy 387.06234 -315.205358) (xy 387.013165 -315.203377) (xy 386.964946 -315.193533) (xy 386.91893 -315.176081)
			(xy 386.876309 -315.151474) (xy 386.838188 -315.120349) (xy 386.805553 -315.083512) (xy 386.77925 -315.041916)
			(xy 386.759959 -314.99664) (xy 386.748182 -314.948856) (xy 386.744222 -314.899802) (xy 386.426964 -314.899802)
			(xy 386.42646 -314.92551) (xy 386.418417 -314.976292) (xy 386.402529 -315.025191) (xy 386.379186 -315.071003)
			(xy 386.348965 -315.112599) (xy 386.312609 -315.148955) (xy 386.271013 -315.179176) (xy 386.225201 -315.202519)
			(xy 386.176302 -315.218407) (xy 386.12552 -315.22645) (xy 386.074104 -315.22645) (xy 386.023322 -315.218407)
			(xy 385.974423 -315.202519) (xy 385.928611 -315.179176) (xy 385.887015 -315.148955) (xy 385.850659 -315.112599)
			(xy 385.820438 -315.071003) (xy 385.797095 -315.025191) (xy 385.781207 -314.976292) (xy 385.773164 -314.92551)
			(xy 385.4765 -314.92551) (xy 385.468457 -314.976292) (xy 385.452569 -315.025191) (xy 385.429226 -315.071003)
			(xy 385.399005 -315.112599) (xy 385.362649 -315.148955) (xy 385.321053 -315.179176) (xy 385.275241 -315.202519)
			(xy 385.226342 -315.218407) (xy 385.17556 -315.22645) (xy 385.124144 -315.22645) (xy 385.073362 -315.218407)
			(xy 385.024463 -315.202519) (xy 384.978651 -315.179176) (xy 384.937055 -315.148955) (xy 384.900699 -315.112599)
			(xy 384.870478 -315.071003) (xy 384.847135 -315.025191) (xy 384.831247 -314.976292) (xy 384.823204 -314.92551)
			(xy 384.503977 -314.92551) (xy 384.496302 -314.972732) (xy 384.480718 -315.019413) (xy 384.457847 -315.06299)
			(xy 384.428282 -315.102334) (xy 384.392789 -315.136426) (xy 384.352286 -315.164382) (xy 384.307824 -315.18548)
			(xy 384.260553 -315.199172) (xy 384.211698 -315.205104) (xy 384.162523 -315.203123) (xy 384.114304 -315.193279)
			(xy 384.068288 -315.175827) (xy 384.025667 -315.15122) (xy 383.987546 -315.120095) (xy 383.954911 -315.083258)
			(xy 383.928608 -315.041662) (xy 383.909317 -314.996386) (xy 383.89754 -314.948602) (xy 383.89358 -314.899548)
			(xy 351.03562 -314.899548) (xy 351.03562 -315.849762) (xy 384.844048 -315.849762) (xy 384.848008 -315.800708)
			(xy 384.859785 -315.752924) (xy 384.879076 -315.707648) (xy 384.905379 -315.666052) (xy 384.938014 -315.629215)
			(xy 384.976135 -315.59809) (xy 385.018756 -315.573483) (xy 385.064772 -315.556031) (xy 385.112991 -315.546187)
			(xy 385.162166 -315.544206) (xy 385.211021 -315.550138) (xy 385.258292 -315.56383) (xy 385.302754 -315.584928)
			(xy 385.343257 -315.612884) (xy 385.37875 -315.646976) (xy 385.408315 -315.68632) (xy 385.431186 -315.729897)
			(xy 385.44677 -315.776578) (xy 385.454665 -315.825155) (xy 385.45516 -315.849762) (xy 385.794008 -315.849762)
			(xy 385.797968 -315.800708) (xy 385.809745 -315.752924) (xy 385.829036 -315.707648) (xy 385.855339 -315.666052)
			(xy 385.887974 -315.629215) (xy 385.926095 -315.59809) (xy 385.968716 -315.573483) (xy 386.014732 -315.556031)
			(xy 386.062951 -315.546187) (xy 386.112126 -315.544206) (xy 386.160981 -315.550138) (xy 386.208252 -315.56383)
			(xy 386.252714 -315.584928) (xy 386.293217 -315.612884) (xy 386.32871 -315.646976) (xy 386.358275 -315.68632)
			(xy 386.381146 -315.729897) (xy 386.39673 -315.776578) (xy 386.404625 -315.825155) (xy 386.40512 -315.849762)
			(xy 386.744222 -315.849762) (xy 386.748182 -315.800708) (xy 386.759959 -315.752924) (xy 386.77925 -315.707648)
			(xy 386.805553 -315.666052) (xy 386.838188 -315.629215) (xy 386.876309 -315.59809) (xy 386.91893 -315.573483)
			(xy 386.964946 -315.556031) (xy 387.013165 -315.546187) (xy 387.06234 -315.544206) (xy 387.111195 -315.550138)
			(xy 387.158466 -315.56383) (xy 387.202928 -315.584928) (xy 387.243431 -315.612884) (xy 387.278924 -315.646976)
			(xy 387.308489 -315.68632) (xy 387.33136 -315.729897) (xy 387.346944 -315.776578) (xy 387.354839 -315.825155)
			(xy 387.355334 -315.849762) (xy 387.354839 -315.874369) (xy 387.35466 -315.87547) (xy 387.673338 -315.87547)
			(xy 387.673338 -315.824054) (xy 387.681381 -315.773272) (xy 387.697269 -315.724373) (xy 387.720612 -315.678561)
			(xy 387.750833 -315.636965) (xy 387.787189 -315.600609) (xy 387.828785 -315.570388) (xy 387.874597 -315.547045)
			(xy 387.923496 -315.531157) (xy 387.974278 -315.523114) (xy 388.025694 -315.523114) (xy 388.076476 -315.531157)
			(xy 388.125375 -315.547045) (xy 388.171187 -315.570388) (xy 388.212783 -315.600609) (xy 388.249139 -315.636965)
			(xy 388.27936 -315.678561) (xy 388.302703 -315.724373) (xy 388.318591 -315.773272) (xy 388.326634 -315.824054)
			(xy 388.327138 -315.849762) (xy 388.326634 -315.87547) (xy 388.318591 -315.926252) (xy 388.302703 -315.975151)
			(xy 388.27936 -316.020963) (xy 388.249139 -316.062559) (xy 388.212783 -316.098915) (xy 388.171187 -316.129136)
			(xy 388.125375 -316.152479) (xy 388.076476 -316.168367) (xy 388.025694 -316.17641) (xy 387.974278 -316.17641)
			(xy 387.923496 -316.168367) (xy 387.874597 -316.152479) (xy 387.828785 -316.129136) (xy 387.787189 -316.098915)
			(xy 387.750833 -316.062559) (xy 387.720612 -316.020963) (xy 387.697269 -315.975151) (xy 387.681381 -315.926252)
			(xy 387.673338 -315.87547) (xy 387.35466 -315.87547) (xy 387.346944 -315.922946) (xy 387.33136 -315.969627)
			(xy 387.308489 -316.013204) (xy 387.278924 -316.052548) (xy 387.243431 -316.08664) (xy 387.202928 -316.114596)
			(xy 387.158466 -316.135694) (xy 387.111195 -316.149386) (xy 387.06234 -316.155318) (xy 387.013165 -316.153337)
			(xy 386.964946 -316.143493) (xy 386.91893 -316.126041) (xy 386.876309 -316.101434) (xy 386.838188 -316.070309)
			(xy 386.805553 -316.033472) (xy 386.77925 -315.991876) (xy 386.759959 -315.9466) (xy 386.748182 -315.898816)
			(xy 386.744222 -315.849762) (xy 386.40512 -315.849762) (xy 386.404625 -315.874369) (xy 386.39673 -315.922946)
			(xy 386.381146 -315.969627) (xy 386.358275 -316.013204) (xy 386.32871 -316.052548) (xy 386.293217 -316.08664)
			(xy 386.252714 -316.114596) (xy 386.208252 -316.135694) (xy 386.160981 -316.149386) (xy 386.112126 -316.155318)
			(xy 386.062951 -316.153337) (xy 386.014732 -316.143493) (xy 385.968716 -316.126041) (xy 385.926095 -316.101434)
			(xy 385.887974 -316.070309) (xy 385.855339 -316.033472) (xy 385.829036 -315.991876) (xy 385.809745 -315.9466)
			(xy 385.797968 -315.898816) (xy 385.794008 -315.849762) (xy 385.45516 -315.849762) (xy 385.454665 -315.874369)
			(xy 385.44677 -315.922946) (xy 385.431186 -315.969627) (xy 385.408315 -316.013204) (xy 385.37875 -316.052548)
			(xy 385.343257 -316.08664) (xy 385.302754 -316.114596) (xy 385.258292 -316.135694) (xy 385.211021 -316.149386)
			(xy 385.162166 -316.155318) (xy 385.112991 -316.153337) (xy 385.064772 -316.143493) (xy 385.018756 -316.126041)
			(xy 384.976135 -316.101434) (xy 384.938014 -316.070309) (xy 384.905379 -316.033472) (xy 384.879076 -315.991876)
			(xy 384.859785 -315.9466) (xy 384.848008 -315.898816) (xy 384.844048 -315.849762) (xy 351.03562 -315.849762)
			(xy 351.03562 -320.08064) (xy 351.617026 -320.08064) (xy 351.617563 -320.051724) (xy 351.626287 -319.994553)
			(xy 351.64354 -319.939354) (xy 351.668928 -319.887392) (xy 351.701869 -319.839858) (xy 351.741608 -319.79784)
			(xy 351.764092 -319.77965) (xy 351.772826 -319.772061) (xy 351.783025 -319.751323) (xy 351.78365 -319.739772)
			(xy 351.78365 -319.659508) (xy 351.783092 -319.647938) (xy 351.772891 -319.627166) (xy 351.764092 -319.61963)
			(xy 351.741621 -319.601424) (xy 351.701886 -319.559407) (xy 351.668945 -319.511875) (xy 351.643555 -319.459917)
			(xy 351.626296 -319.404722) (xy 351.617563 -319.347555) (xy 351.617026 -319.31864) (xy 351.617493 -319.291387)
			(xy 351.625245 -319.237434) (xy 351.640598 -319.185134) (xy 351.663238 -319.135552) (xy 351.692705 -319.089697)
			(xy 351.728399 -319.048503) (xy 351.769592 -319.012809) (xy 351.815447 -318.983341) (xy 351.865028 -318.9607)
			(xy 351.917328 -318.945346) (xy 351.971281 -318.937593) (xy 351.998534 -318.937132) (xy 352.02745 -318.937685)
			(xy 352.08462 -318.946405) (xy 352.139819 -318.963656) (xy 352.191781 -318.989041) (xy 352.239315 -319.021979)
			(xy 352.281333 -319.061715) (xy 352.299524 -319.084198) (xy 352.30708 -319.092966) (xy 352.327843 -319.103146)
			(xy 352.339402 -319.103756) (xy 352.419666 -319.103756) (xy 352.431234 -319.103181) (xy 352.452006 -319.092991)
			(xy 352.459544 -319.084198) (xy 352.476297 -319.063415) (xy 352.514651 -319.026285) (xy 352.557805 -318.994863)
			(xy 352.604919 -318.969764) (xy 352.655071 -318.951478) (xy 352.707282 -318.940361) (xy 352.760534 -318.936631)
			(xy 352.813786 -318.940361) (xy 352.865997 -318.951478) (xy 352.916149 -318.969764) (xy 352.963263 -318.994863)
			(xy 353.006417 -319.026285) (xy 353.044771 -319.063415) (xy 353.061524 -319.084198) (xy 353.06908 -319.092966)
			(xy 353.089843 -319.103146) (xy 353.101402 -319.103756) (xy 353.181666 -319.103756) (xy 353.193234 -319.103181)
			(xy 353.214006 -319.092991) (xy 353.221544 -319.084198) (xy 353.238297 -319.063415) (xy 353.276651 -319.026285)
			(xy 353.319805 -318.994863) (xy 353.366919 -318.969764) (xy 353.417071 -318.951478) (xy 353.469282 -318.940361)
			(xy 353.522534 -318.936631) (xy 353.575786 -318.940361) (xy 353.627997 -318.951478) (xy 353.678149 -318.969764)
			(xy 353.725263 -318.994863) (xy 353.768417 -319.026285) (xy 353.806771 -319.063415) (xy 353.823524 -319.084198)
			(xy 353.83108 -319.092966) (xy 353.851843 -319.103146) (xy 353.863402 -319.103756) (xy 353.943666 -319.103756)
			(xy 353.955234 -319.103181) (xy 353.976006 -319.092991) (xy 353.983544 -319.084198) (xy 354.000297 -319.063415)
			(xy 354.038651 -319.026285) (xy 354.081805 -318.994863) (xy 354.128919 -318.969764) (xy 354.179071 -318.951478)
			(xy 354.231282 -318.940361) (xy 354.284534 -318.936631) (xy 354.337786 -318.940361) (xy 354.389997 -318.951478)
			(xy 354.440149 -318.969764) (xy 354.487263 -318.994863) (xy 354.530417 -319.026285) (xy 354.568771 -319.063415)
			(xy 354.585524 -319.084198) (xy 354.59308 -319.092966) (xy 354.613843 -319.103146) (xy 354.625402 -319.103756)
			(xy 354.705666 -319.103756) (xy 354.717234 -319.103181) (xy 354.738006 -319.092991) (xy 354.745544 -319.084198)
			(xy 354.762297 -319.063415) (xy 354.800651 -319.026285) (xy 354.843805 -318.994863) (xy 354.890919 -318.969764)
			(xy 354.941071 -318.951478) (xy 354.993282 -318.940361) (xy 355.046534 -318.936631) (xy 355.099786 -318.940361)
			(xy 355.151997 -318.951478) (xy 355.202149 -318.969764) (xy 355.249263 -318.994863) (xy 355.292417 -319.026285)
			(xy 355.330771 -319.063415) (xy 355.347524 -319.084198) (xy 355.35508 -319.092966) (xy 355.375843 -319.103146)
			(xy 355.387402 -319.103756) (xy 355.467666 -319.103756) (xy 355.479234 -319.103181) (xy 355.500006 -319.092991)
			(xy 355.507544 -319.084198) (xy 355.524297 -319.063415) (xy 355.562651 -319.026285) (xy 355.605805 -318.994863)
			(xy 355.652919 -318.969764) (xy 355.703071 -318.951478) (xy 355.755282 -318.940361) (xy 355.808534 -318.936631)
			(xy 355.861786 -318.940361) (xy 355.913997 -318.951478) (xy 355.964149 -318.969764) (xy 356.011263 -318.994863)
			(xy 356.054417 -319.026285) (xy 356.092771 -319.063415) (xy 356.109524 -319.084198) (xy 356.11708 -319.092966)
			(xy 356.137843 -319.103146) (xy 356.149402 -319.103756) (xy 356.229666 -319.103756) (xy 356.241234 -319.103181)
			(xy 356.262006 -319.092991) (xy 356.269544 -319.084198) (xy 356.286297 -319.063415) (xy 356.324651 -319.026285)
			(xy 356.367805 -318.994863) (xy 356.414919 -318.969764) (xy 356.465071 -318.951478) (xy 356.517282 -318.940361)
			(xy 356.570534 -318.936631) (xy 356.623786 -318.940361) (xy 356.675997 -318.951478) (xy 356.726149 -318.969764)
			(xy 356.773263 -318.994863) (xy 356.816417 -319.026285) (xy 356.854771 -319.063415) (xy 356.871524 -319.084198)
			(xy 356.87908 -319.092966) (xy 356.899843 -319.103146) (xy 356.911402 -319.103756) (xy 356.991666 -319.103756)
			(xy 357.003234 -319.103181) (xy 357.024006 -319.092991) (xy 357.031544 -319.084198) (xy 357.048297 -319.063415)
			(xy 357.086651 -319.026285) (xy 357.129805 -318.994863) (xy 357.176919 -318.969764) (xy 357.227071 -318.951478)
			(xy 357.279282 -318.940361) (xy 357.332534 -318.936631) (xy 357.385786 -318.940361) (xy 357.437997 -318.951478)
			(xy 357.488149 -318.969764) (xy 357.535263 -318.994863) (xy 357.578417 -319.026285) (xy 357.616771 -319.063415)
			(xy 357.633524 -319.084198) (xy 357.64108 -319.092966) (xy 357.661843 -319.103146) (xy 357.673402 -319.103756)
			(xy 357.753666 -319.103756) (xy 357.765234 -319.103181) (xy 357.786006 -319.092991) (xy 357.793544 -319.084198)
			(xy 357.810297 -319.063415) (xy 357.848651 -319.026285) (xy 357.891805 -318.994863) (xy 357.938919 -318.969764)
			(xy 357.989071 -318.951478) (xy 358.041282 -318.940361) (xy 358.094534 -318.936631) (xy 358.147786 -318.940361)
			(xy 358.199997 -318.951478) (xy 358.250149 -318.969764) (xy 358.297263 -318.994863) (xy 358.340417 -319.026285)
			(xy 358.378771 -319.063415) (xy 358.395524 -319.084198) (xy 358.40308 -319.092966) (xy 358.423843 -319.103146)
			(xy 358.435402 -319.103756) (xy 358.515666 -319.103756) (xy 358.527234 -319.103181) (xy 358.548006 -319.092991)
			(xy 358.555544 -319.084198) (xy 358.572297 -319.063415) (xy 358.610651 -319.026285) (xy 358.653805 -318.994863)
			(xy 358.700919 -318.969764) (xy 358.751071 -318.951478) (xy 358.803282 -318.940361) (xy 358.856534 -318.936631)
			(xy 358.909786 -318.940361) (xy 358.961997 -318.951478) (xy 359.012149 -318.969764) (xy 359.059263 -318.994863)
			(xy 359.102417 -319.026285) (xy 359.140771 -319.063415) (xy 359.157524 -319.084198) (xy 359.16508 -319.092966)
			(xy 359.185843 -319.103146) (xy 359.197402 -319.103756) (xy 359.277666 -319.103756) (xy 359.289234 -319.103181)
			(xy 359.310006 -319.092991) (xy 359.317544 -319.084198) (xy 359.334297 -319.063415) (xy 359.372651 -319.026285)
			(xy 359.415805 -318.994863) (xy 359.462919 -318.969764) (xy 359.513071 -318.951478) (xy 359.565282 -318.940361)
			(xy 359.618534 -318.936631) (xy 359.671786 -318.940361) (xy 359.723997 -318.951478) (xy 359.774149 -318.969764)
			(xy 359.821263 -318.994863) (xy 359.864417 -319.026285) (xy 359.902771 -319.063415) (xy 359.919524 -319.084198)
			(xy 359.92708 -319.092966) (xy 359.947843 -319.103146) (xy 359.959402 -319.103756) (xy 360.039666 -319.103756)
			(xy 360.051234 -319.103181) (xy 360.072006 -319.092991) (xy 360.079544 -319.084198) (xy 360.096297 -319.063415)
			(xy 360.134651 -319.026285) (xy 360.177805 -318.994863) (xy 360.224919 -318.969764) (xy 360.275071 -318.951478)
			(xy 360.327282 -318.940361) (xy 360.380534 -318.936631) (xy 360.433786 -318.940361) (xy 360.485997 -318.951478)
			(xy 360.536149 -318.969764) (xy 360.583263 -318.994863) (xy 360.626417 -319.026285) (xy 360.664771 -319.063415)
			(xy 360.681524 -319.084198) (xy 360.68908 -319.092966) (xy 360.709843 -319.103146) (xy 360.721402 -319.103756)
			(xy 360.801666 -319.103756) (xy 360.813234 -319.103181) (xy 360.834006 -319.092991) (xy 360.841544 -319.084198)
			(xy 360.85971 -319.061693) (xy 360.901735 -319.021959) (xy 360.949275 -318.989023) (xy 361.001241 -318.963638)
			(xy 361.056443 -318.946387) (xy 361.113617 -318.937664) (xy 361.142534 -318.937132) (xy 361.16979 -318.937523)
			(xy 361.223745 -318.945286) (xy 361.276047 -318.960648) (xy 361.32563 -318.983298) (xy 361.371485 -319.012773)
			(xy 361.412678 -319.048474) (xy 361.448371 -319.089675) (xy 361.477838 -319.135535) (xy 361.500478 -319.185123)
			(xy 361.51583 -319.237427) (xy 361.523582 -319.291384) (xy 361.524042 -319.31864) (xy 361.523502 -319.347556)
			(xy 361.514781 -319.404728) (xy 361.497528 -319.459927) (xy 361.472141 -319.511889) (xy 361.4392 -319.559423)
			(xy 361.399461 -319.60144) (xy 361.376976 -319.61963) (xy 361.368201 -319.627179) (xy 361.358026 -319.647948)
			(xy 361.357418 -319.659508) (xy 361.357418 -319.739772) (xy 361.357998 -319.751339) (xy 361.368185 -319.77211)
			(xy 361.376976 -319.77965) (xy 361.399431 -319.797875) (xy 361.439169 -319.839887) (xy 361.472112 -319.887415)
			(xy 361.497505 -319.939369) (xy 361.514768 -319.994561) (xy 361.523503 -320.051726) (xy 361.524042 -320.08064)
			(xy 361.52356 -320.107891) (xy 361.515798 -320.161837) (xy 361.50044 -320.214129) (xy 361.477797 -320.263705)
			(xy 361.448329 -320.309553) (xy 361.412638 -320.350742) (xy 361.371448 -320.386433) (xy 361.325599 -320.4159)
			(xy 361.276024 -320.438542) (xy 361.223731 -320.4539) (xy 361.169785 -320.46166) (xy 361.142534 -320.462148)
			(xy 361.113617 -320.461625) (xy 361.056445 -320.4529) (xy 361.001246 -320.435644) (xy 360.949283 -320.410253)
			(xy 360.901749 -320.37731) (xy 360.859733 -320.337568) (xy 360.841544 -320.315082) (xy 360.833962 -320.306341)
			(xy 360.813218 -320.296147) (xy 360.801666 -320.295524) (xy 360.721402 -320.295524) (xy 360.709833 -320.296087)
			(xy 360.689062 -320.306286) (xy 360.681524 -320.315082) (xy 360.664771 -320.335865) (xy 360.626417 -320.372995)
			(xy 360.583263 -320.404417) (xy 360.536149 -320.429516) (xy 360.485997 -320.447802) (xy 360.433786 -320.458919)
			(xy 360.380534 -320.462649) (xy 360.327282 -320.458919) (xy 360.275071 -320.447802) (xy 360.224919 -320.429516)
			(xy 360.177805 -320.404417) (xy 360.134651 -320.372995) (xy 360.096297 -320.335865) (xy 360.079544 -320.315082)
			(xy 360.071962 -320.306341) (xy 360.051218 -320.296147) (xy 360.039666 -320.295524) (xy 359.959402 -320.295524)
			(xy 359.947833 -320.296087) (xy 359.927062 -320.306286) (xy 359.919524 -320.315082) (xy 359.902771 -320.335865)
			(xy 359.864417 -320.372995) (xy 359.821263 -320.404417) (xy 359.774149 -320.429516) (xy 359.723997 -320.447802)
			(xy 359.671786 -320.458919) (xy 359.618534 -320.462649) (xy 359.565282 -320.458919) (xy 359.513071 -320.447802)
			(xy 359.462919 -320.429516) (xy 359.415805 -320.404417) (xy 359.372651 -320.372995) (xy 359.334297 -320.335865)
			(xy 359.317544 -320.315082) (xy 359.309962 -320.306341) (xy 359.289218 -320.296147) (xy 359.277666 -320.295524)
			(xy 359.197402 -320.295524) (xy 359.185833 -320.296087) (xy 359.165062 -320.306286) (xy 359.157524 -320.315082)
			(xy 359.140771 -320.335865) (xy 359.102417 -320.372995) (xy 359.059263 -320.404417) (xy 359.012149 -320.429516)
			(xy 358.961997 -320.447802) (xy 358.909786 -320.458919) (xy 358.856534 -320.462649) (xy 358.803282 -320.458919)
			(xy 358.751071 -320.447802) (xy 358.700919 -320.429516) (xy 358.653805 -320.404417) (xy 358.610651 -320.372995)
			(xy 358.572297 -320.335865) (xy 358.555544 -320.315082) (xy 358.547962 -320.306341) (xy 358.527218 -320.296147)
			(xy 358.515666 -320.295524) (xy 358.435402 -320.295524) (xy 358.423833 -320.296087) (xy 358.403062 -320.306286)
			(xy 358.395524 -320.315082) (xy 358.378771 -320.335865) (xy 358.340417 -320.372995) (xy 358.297263 -320.404417)
			(xy 358.250149 -320.429516) (xy 358.199997 -320.447802) (xy 358.147786 -320.458919) (xy 358.094534 -320.462649)
			(xy 358.041282 -320.458919) (xy 357.989071 -320.447802) (xy 357.938919 -320.429516) (xy 357.891805 -320.404417)
			(xy 357.848651 -320.372995) (xy 357.810297 -320.335865) (xy 357.793544 -320.315082) (xy 357.785962 -320.306341)
			(xy 357.765218 -320.296147) (xy 357.753666 -320.295524) (xy 357.673402 -320.295524) (xy 357.661833 -320.296087)
			(xy 357.641062 -320.306286) (xy 357.633524 -320.315082) (xy 357.616771 -320.335865) (xy 357.578417 -320.372995)
			(xy 357.535263 -320.404417) (xy 357.488149 -320.429516) (xy 357.437997 -320.447802) (xy 357.385786 -320.458919)
			(xy 357.332534 -320.462649) (xy 357.279282 -320.458919) (xy 357.227071 -320.447802) (xy 357.176919 -320.429516)
			(xy 357.129805 -320.404417) (xy 357.086651 -320.372995) (xy 357.048297 -320.335865) (xy 357.031544 -320.315082)
			(xy 357.023962 -320.306341) (xy 357.003218 -320.296147) (xy 356.991666 -320.295524) (xy 356.911402 -320.295524)
			(xy 356.899833 -320.296087) (xy 356.879062 -320.306286) (xy 356.871524 -320.315082) (xy 356.854771 -320.335865)
			(xy 356.816417 -320.372995) (xy 356.773263 -320.404417) (xy 356.726149 -320.429516) (xy 356.675997 -320.447802)
			(xy 356.623786 -320.458919) (xy 356.570534 -320.462649) (xy 356.517282 -320.458919) (xy 356.465071 -320.447802)
			(xy 356.414919 -320.429516) (xy 356.367805 -320.404417) (xy 356.324651 -320.372995) (xy 356.286297 -320.335865)
			(xy 356.269544 -320.315082) (xy 356.261962 -320.306341) (xy 356.241218 -320.296147) (xy 356.229666 -320.295524)
			(xy 356.149402 -320.295524) (xy 356.137833 -320.296087) (xy 356.117062 -320.306286) (xy 356.109524 -320.315082)
			(xy 356.092771 -320.335865) (xy 356.054417 -320.372995) (xy 356.011263 -320.404417) (xy 355.964149 -320.429516)
			(xy 355.913997 -320.447802) (xy 355.861786 -320.458919) (xy 355.808534 -320.462649) (xy 355.755282 -320.458919)
			(xy 355.703071 -320.447802) (xy 355.652919 -320.429516) (xy 355.605805 -320.404417) (xy 355.562651 -320.372995)
			(xy 355.524297 -320.335865) (xy 355.507544 -320.315082) (xy 355.499962 -320.306341) (xy 355.479218 -320.296147)
			(xy 355.467666 -320.295524) (xy 355.387402 -320.295524) (xy 355.375833 -320.296087) (xy 355.355062 -320.306286)
			(xy 355.347524 -320.315082) (xy 355.330771 -320.335865) (xy 355.292417 -320.372995) (xy 355.249263 -320.404417)
			(xy 355.202149 -320.429516) (xy 355.151997 -320.447802) (xy 355.099786 -320.458919) (xy 355.046534 -320.462649)
			(xy 354.993282 -320.458919) (xy 354.941071 -320.447802) (xy 354.890919 -320.429516) (xy 354.843805 -320.404417)
			(xy 354.800651 -320.372995) (xy 354.762297 -320.335865) (xy 354.745544 -320.315082) (xy 354.737962 -320.306341)
			(xy 354.717218 -320.296147) (xy 354.705666 -320.295524) (xy 354.625402 -320.295524) (xy 354.613833 -320.296087)
			(xy 354.593062 -320.306286) (xy 354.585524 -320.315082) (xy 354.568771 -320.335865) (xy 354.530417 -320.372995)
			(xy 354.487263 -320.404417) (xy 354.440149 -320.429516) (xy 354.389997 -320.447802) (xy 354.337786 -320.458919)
			(xy 354.284534 -320.462649) (xy 354.231282 -320.458919) (xy 354.179071 -320.447802) (xy 354.128919 -320.429516)
			(xy 354.081805 -320.404417) (xy 354.038651 -320.372995) (xy 354.000297 -320.335865) (xy 353.983544 -320.315082)
			(xy 353.975962 -320.306341) (xy 353.955218 -320.296147) (xy 353.943666 -320.295524) (xy 353.863402 -320.295524)
			(xy 353.851833 -320.296087) (xy 353.831062 -320.306286) (xy 353.823524 -320.315082) (xy 353.806771 -320.335865)
			(xy 353.768417 -320.372995) (xy 353.725263 -320.404417) (xy 353.678149 -320.429516) (xy 353.627997 -320.447802)
			(xy 353.575786 -320.458919) (xy 353.522534 -320.462649) (xy 353.469282 -320.458919) (xy 353.417071 -320.447802)
			(xy 353.366919 -320.429516) (xy 353.319805 -320.404417) (xy 353.276651 -320.372995) (xy 353.238297 -320.335865)
			(xy 353.221544 -320.315082) (xy 353.213962 -320.306341) (xy 353.193218 -320.296147) (xy 353.181666 -320.295524)
			(xy 353.101402 -320.295524) (xy 353.089833 -320.296087) (xy 353.069062 -320.306286) (xy 353.061524 -320.315082)
			(xy 353.044771 -320.335865) (xy 353.006417 -320.372995) (xy 352.963263 -320.404417) (xy 352.916149 -320.429516)
			(xy 352.865997 -320.447802) (xy 352.813786 -320.458919) (xy 352.760534 -320.462649) (xy 352.707282 -320.458919)
			(xy 352.655071 -320.447802) (xy 352.604919 -320.429516) (xy 352.557805 -320.404417) (xy 352.514651 -320.372995)
			(xy 352.476297 -320.335865) (xy 352.459544 -320.315082) (xy 352.451962 -320.306341) (xy 352.431218 -320.296147)
			(xy 352.419666 -320.295524) (xy 352.339402 -320.295524) (xy 352.327833 -320.296087) (xy 352.307062 -320.306286)
			(xy 352.299524 -320.315082) (xy 352.281315 -320.33755) (xy 352.239299 -320.377287) (xy 352.191768 -320.410229)
			(xy 352.139811 -320.43562) (xy 352.084616 -320.452879) (xy 352.027449 -320.461611) (xy 351.998534 -320.462148)
			(xy 351.971285 -320.46159) (xy 351.917342 -320.453839) (xy 351.865051 -320.438491) (xy 351.815477 -320.415856)
			(xy 351.769629 -320.386397) (xy 351.728439 -320.350713) (xy 351.692747 -320.309531) (xy 351.663279 -320.263688)
			(xy 351.640635 -320.214118) (xy 351.625276 -320.16183) (xy 351.617515 -320.107888) (xy 351.617026 -320.08064)
			(xy 351.03562 -320.08064) (xy 351.03562 -320.900044) (xy 373.198651 -320.900044) (xy 373.202657 -320.704989)
			(xy 373.214667 -320.510263) (xy 373.234662 -320.316194) (xy 373.262607 -320.12311) (xy 373.298456 -319.931335)
			(xy 373.342148 -319.741195) (xy 373.393609 -319.553008) (xy 373.452753 -319.367093) (xy 373.51948 -319.183762)
			(xy 373.593677 -319.003326) (xy 373.675219 -318.826088) (xy 373.76397 -318.652347) (xy 373.859778 -318.482396)
			(xy 373.962483 -318.316522) (xy 374.071911 -318.155004) (xy 374.187878 -317.998115) (xy 374.310189 -317.84612)
			(xy 374.438636 -317.699274) (xy 374.573004 -317.557825) (xy 374.713066 -317.422012) (xy 374.858585 -317.292063)
			(xy 375.009317 -317.168199) (xy 375.165007 -317.050627) (xy 375.325393 -316.939547) (xy 375.490204 -316.835144)
			(xy 375.659162 -316.737596) (xy 375.831983 -316.647067) (xy 376.008375 -316.563709) (xy 376.18804 -316.487663)
			(xy 376.370675 -316.419058) (xy 376.555974 -316.358008) (xy 376.743622 -316.304618) (xy 376.933304 -316.258976)
			(xy 377.124701 -316.22116) (xy 377.317488 -316.191234) (xy 377.511341 -316.169248) (xy 377.705934 -316.155239)
			(xy 377.900937 -316.149231) (xy 378.096023 -316.151234) (xy 378.290862 -316.161245) (xy 378.485126 -316.179246)
			(xy 378.678487 -316.205208) (xy 378.87062 -316.239086) (xy 379.061199 -316.280823) (xy 379.249904 -316.33035)
			(xy 379.436417 -316.387582) (xy 379.620423 -316.452423) (xy 379.801611 -316.524764) (xy 379.979677 -316.604482)
			(xy 380.15432 -316.691444) (xy 380.325246 -316.785503) (xy 380.348326 -316.799468) (xy 383.89358 -316.799468)
			(xy 383.89754 -316.750414) (xy 383.909317 -316.70263) (xy 383.928608 -316.657354) (xy 383.954911 -316.615758)
			(xy 383.987546 -316.578921) (xy 384.025667 -316.547796) (xy 384.068288 -316.523189) (xy 384.114304 -316.505737)
			(xy 384.162523 -316.495893) (xy 384.211698 -316.493912) (xy 384.260553 -316.499844) (xy 384.307824 -316.513536)
			(xy 384.352286 -316.534634) (xy 384.392789 -316.56259) (xy 384.428282 -316.596682) (xy 384.457847 -316.636026)
			(xy 384.480718 -316.679603) (xy 384.496302 -316.726284) (xy 384.504197 -316.774861) (xy 384.504692 -316.799468)
			(xy 384.504197 -316.824075) (xy 384.503977 -316.82543) (xy 384.823204 -316.82543) (xy 384.823204 -316.774014)
			(xy 384.831247 -316.723232) (xy 384.847135 -316.674333) (xy 384.870478 -316.628521) (xy 384.900699 -316.586925)
			(xy 384.937055 -316.550569) (xy 384.978651 -316.520348) (xy 385.024463 -316.497005) (xy 385.073362 -316.481117)
			(xy 385.124144 -316.473074) (xy 385.17556 -316.473074) (xy 385.226342 -316.481117) (xy 385.275241 -316.497005)
			(xy 385.321053 -316.520348) (xy 385.362649 -316.550569) (xy 385.399005 -316.586925) (xy 385.429226 -316.628521)
			(xy 385.452569 -316.674333) (xy 385.468457 -316.723232) (xy 385.4765 -316.774014) (xy 385.477004 -316.799722)
			(xy 385.4765 -316.82543) (xy 385.773164 -316.82543) (xy 385.773164 -316.774014) (xy 385.781207 -316.723232)
			(xy 385.797095 -316.674333) (xy 385.820438 -316.628521) (xy 385.850659 -316.586925) (xy 385.887015 -316.550569)
			(xy 385.928611 -316.520348) (xy 385.974423 -316.497005) (xy 386.023322 -316.481117) (xy 386.074104 -316.473074)
			(xy 386.12552 -316.473074) (xy 386.176302 -316.481117) (xy 386.225201 -316.497005) (xy 386.271013 -316.520348)
			(xy 386.312609 -316.550569) (xy 386.348965 -316.586925) (xy 386.379186 -316.628521) (xy 386.402529 -316.674333)
			(xy 386.418417 -316.723232) (xy 386.42646 -316.774014) (xy 386.426964 -316.799722) (xy 386.744222 -316.799722)
			(xy 386.748182 -316.750668) (xy 386.759959 -316.702884) (xy 386.77925 -316.657608) (xy 386.805553 -316.616012)
			(xy 386.838188 -316.579175) (xy 386.876309 -316.54805) (xy 386.91893 -316.523443) (xy 386.964946 -316.505991)
			(xy 387.013165 -316.496147) (xy 387.06234 -316.494166) (xy 387.111195 -316.500098) (xy 387.158466 -316.51379)
			(xy 387.202928 -316.534888) (xy 387.243431 -316.562844) (xy 387.278924 -316.596936) (xy 387.308489 -316.63628)
			(xy 387.33136 -316.679857) (xy 387.346944 -316.726538) (xy 387.354839 -316.775115) (xy 387.355334 -316.799722)
			(xy 387.354839 -316.824329) (xy 387.35466 -316.82543) (xy 387.673338 -316.82543) (xy 387.673338 -316.774014)
			(xy 387.681381 -316.723232) (xy 387.697269 -316.674333) (xy 387.720612 -316.628521) (xy 387.750833 -316.586925)
			(xy 387.787189 -316.550569) (xy 387.828785 -316.520348) (xy 387.874597 -316.497005) (xy 387.923496 -316.481117)
			(xy 387.974278 -316.473074) (xy 388.025694 -316.473074) (xy 388.076476 -316.481117) (xy 388.125375 -316.497005)
			(xy 388.171187 -316.520348) (xy 388.212783 -316.550569) (xy 388.249139 -316.586925) (xy 388.27936 -316.628521)
			(xy 388.302703 -316.674333) (xy 388.318591 -316.723232) (xy 388.326634 -316.774014) (xy 388.327138 -316.799722)
			(xy 388.326634 -316.82543) (xy 388.318591 -316.876212) (xy 388.302703 -316.925111) (xy 388.27936 -316.970923)
			(xy 388.249139 -317.012519) (xy 388.212783 -317.048875) (xy 388.171187 -317.079096) (xy 388.125375 -317.102439)
			(xy 388.076476 -317.118327) (xy 388.025694 -317.12637) (xy 387.974278 -317.12637) (xy 387.923496 -317.118327)
			(xy 387.874597 -317.102439) (xy 387.828785 -317.079096) (xy 387.787189 -317.048875) (xy 387.750833 -317.012519)
			(xy 387.720612 -316.970923) (xy 387.697269 -316.925111) (xy 387.681381 -316.876212) (xy 387.673338 -316.82543)
			(xy 387.35466 -316.82543) (xy 387.346944 -316.872906) (xy 387.33136 -316.919587) (xy 387.308489 -316.963164)
			(xy 387.278924 -317.002508) (xy 387.243431 -317.0366) (xy 387.202928 -317.064556) (xy 387.158466 -317.085654)
			(xy 387.111195 -317.099346) (xy 387.06234 -317.105278) (xy 387.013165 -317.103297) (xy 386.964946 -317.093453)
			(xy 386.91893 -317.076001) (xy 386.876309 -317.051394) (xy 386.838188 -317.020269) (xy 386.805553 -316.983432)
			(xy 386.77925 -316.941836) (xy 386.759959 -316.89656) (xy 386.748182 -316.848776) (xy 386.744222 -316.799722)
			(xy 386.426964 -316.799722) (xy 386.42646 -316.82543) (xy 386.418417 -316.876212) (xy 386.402529 -316.925111)
			(xy 386.379186 -316.970923) (xy 386.348965 -317.012519) (xy 386.312609 -317.048875) (xy 386.271013 -317.079096)
			(xy 386.225201 -317.102439) (xy 386.176302 -317.118327) (xy 386.12552 -317.12637) (xy 386.074104 -317.12637)
			(xy 386.023322 -317.118327) (xy 385.974423 -317.102439) (xy 385.928611 -317.079096) (xy 385.887015 -317.048875)
			(xy 385.850659 -317.012519) (xy 385.820438 -316.970923) (xy 385.797095 -316.925111) (xy 385.781207 -316.876212)
			(xy 385.773164 -316.82543) (xy 385.4765 -316.82543) (xy 385.468457 -316.876212) (xy 385.452569 -316.925111)
			(xy 385.429226 -316.970923) (xy 385.399005 -317.012519) (xy 385.362649 -317.048875) (xy 385.321053 -317.079096)
			(xy 385.275241 -317.102439) (xy 385.226342 -317.118327) (xy 385.17556 -317.12637) (xy 385.124144 -317.12637)
			(xy 385.073362 -317.118327) (xy 385.024463 -317.102439) (xy 384.978651 -317.079096) (xy 384.937055 -317.048875)
			(xy 384.900699 -317.012519) (xy 384.870478 -316.970923) (xy 384.847135 -316.925111) (xy 384.831247 -316.876212)
			(xy 384.823204 -316.82543) (xy 384.503977 -316.82543) (xy 384.496302 -316.872652) (xy 384.480718 -316.919333)
			(xy 384.457847 -316.96291) (xy 384.428282 -317.002254) (xy 384.392789 -317.036346) (xy 384.352286 -317.064302)
			(xy 384.307824 -317.0854) (xy 384.260553 -317.099092) (xy 384.211698 -317.105024) (xy 384.162523 -317.103043)
			(xy 384.114304 -317.093199) (xy 384.068288 -317.075747) (xy 384.025667 -317.05114) (xy 383.987546 -317.020015)
			(xy 383.954911 -316.983178) (xy 383.928608 -316.941582) (xy 383.909317 -316.896306) (xy 383.89754 -316.848522)
			(xy 383.89358 -316.799468) (xy 380.348326 -316.799468) (xy 380.492165 -316.886499) (xy 380.654798 -316.994264)
			(xy 380.812869 -317.108614) (xy 380.966112 -317.229357) (xy 381.114269 -317.356291) (xy 381.25709 -317.489199)
			(xy 381.394334 -317.627859) (xy 381.505622 -317.749936) (xy 384.844048 -317.749936) (xy 384.848008 -317.700882)
			(xy 384.859785 -317.653098) (xy 384.879076 -317.607822) (xy 384.905379 -317.566226) (xy 384.938014 -317.529389)
			(xy 384.976135 -317.498264) (xy 385.018756 -317.473657) (xy 385.064772 -317.456205) (xy 385.112991 -317.446361)
			(xy 385.162166 -317.44438) (xy 385.211021 -317.450312) (xy 385.258292 -317.464004) (xy 385.302754 -317.485102)
			(xy 385.343257 -317.513058) (xy 385.37875 -317.54715) (xy 385.408315 -317.586494) (xy 385.431186 -317.630071)
			(xy 385.44677 -317.676752) (xy 385.454665 -317.725329) (xy 385.45516 -317.749936) (xy 385.794008 -317.749936)
			(xy 385.797968 -317.700882) (xy 385.809745 -317.653098) (xy 385.829036 -317.607822) (xy 385.855339 -317.566226)
			(xy 385.887974 -317.529389) (xy 385.926095 -317.498264) (xy 385.968716 -317.473657) (xy 386.014732 -317.456205)
			(xy 386.062951 -317.446361) (xy 386.112126 -317.44438) (xy 386.160981 -317.450312) (xy 386.208252 -317.464004)
			(xy 386.252714 -317.485102) (xy 386.293217 -317.513058) (xy 386.32871 -317.54715) (xy 386.358275 -317.586494)
			(xy 386.381146 -317.630071) (xy 386.39673 -317.676752) (xy 386.404625 -317.725329) (xy 386.40512 -317.749936)
			(xy 386.404625 -317.774543) (xy 386.404446 -317.775644) (xy 386.723378 -317.775644) (xy 386.723378 -317.724228)
			(xy 386.731421 -317.673446) (xy 386.747309 -317.624547) (xy 386.770652 -317.578735) (xy 386.800873 -317.537139)
			(xy 386.837229 -317.500783) (xy 386.878825 -317.470562) (xy 386.924637 -317.447219) (xy 386.973536 -317.431331)
			(xy 387.024318 -317.423288) (xy 387.075734 -317.423288) (xy 387.126516 -317.431331) (xy 387.175415 -317.447219)
			(xy 387.221227 -317.470562) (xy 387.262823 -317.500783) (xy 387.299179 -317.537139) (xy 387.3294 -317.578735)
			(xy 387.352743 -317.624547) (xy 387.368631 -317.673446) (xy 387.376674 -317.724228) (xy 387.377178 -317.749936)
			(xy 387.694182 -317.749936) (xy 387.698142 -317.700882) (xy 387.709919 -317.653098) (xy 387.72921 -317.607822)
			(xy 387.755513 -317.566226) (xy 387.788148 -317.529389) (xy 387.826269 -317.498264) (xy 387.86889 -317.473657)
			(xy 387.914906 -317.456205) (xy 387.963125 -317.446361) (xy 388.0123 -317.44438) (xy 388.061155 -317.450312)
			(xy 388.108426 -317.464004) (xy 388.152888 -317.485102) (xy 388.193391 -317.513058) (xy 388.228884 -317.54715)
			(xy 388.258449 -317.586494) (xy 388.28132 -317.630071) (xy 388.296904 -317.676752) (xy 388.304799 -317.725329)
			(xy 388.305294 -317.749936) (xy 388.304799 -317.774543) (xy 388.296904 -317.82312) (xy 388.28132 -317.869801)
			(xy 388.258449 -317.913378) (xy 388.228884 -317.952722) (xy 388.193391 -317.986814) (xy 388.152888 -318.01477)
			(xy 388.108426 -318.035868) (xy 388.061155 -318.04956) (xy 388.0123 -318.055492) (xy 387.963125 -318.053511)
			(xy 387.914906 -318.043667) (xy 387.86889 -318.026215) (xy 387.826269 -318.001608) (xy 387.788148 -317.970483)
			(xy 387.755513 -317.933646) (xy 387.72921 -317.89205) (xy 387.709919 -317.846774) (xy 387.698142 -317.79899)
			(xy 387.694182 -317.749936) (xy 387.377178 -317.749936) (xy 387.376674 -317.775644) (xy 387.368631 -317.826426)
			(xy 387.352743 -317.875325) (xy 387.3294 -317.921137) (xy 387.299179 -317.962733) (xy 387.262823 -317.999089)
			(xy 387.221227 -318.02931) (xy 387.175415 -318.052653) (xy 387.126516 -318.068541) (xy 387.075734 -318.076584)
			(xy 387.024318 -318.076584) (xy 386.973536 -318.068541) (xy 386.924637 -318.052653) (xy 386.878825 -318.02931)
			(xy 386.837229 -317.999089) (xy 386.800873 -317.962733) (xy 386.770652 -317.921137) (xy 386.747309 -317.875325)
			(xy 386.731421 -317.826426) (xy 386.723378 -317.775644) (xy 386.404446 -317.775644) (xy 386.39673 -317.82312)
			(xy 386.381146 -317.869801) (xy 386.358275 -317.913378) (xy 386.32871 -317.952722) (xy 386.293217 -317.986814)
			(xy 386.252714 -318.01477) (xy 386.208252 -318.035868) (xy 386.160981 -318.04956) (xy 386.112126 -318.055492)
			(xy 386.062951 -318.053511) (xy 386.014732 -318.043667) (xy 385.968716 -318.026215) (xy 385.926095 -318.001608)
			(xy 385.887974 -317.970483) (xy 385.855339 -317.933646) (xy 385.829036 -317.89205) (xy 385.809745 -317.846774)
			(xy 385.797968 -317.79899) (xy 385.794008 -317.749936) (xy 385.45516 -317.749936) (xy 385.454665 -317.774543)
			(xy 385.44677 -317.82312) (xy 385.431186 -317.869801) (xy 385.408315 -317.913378) (xy 385.37875 -317.952722)
			(xy 385.343257 -317.986814) (xy 385.302754 -318.01477) (xy 385.258292 -318.035868) (xy 385.211021 -318.04956)
			(xy 385.162166 -318.055492) (xy 385.112991 -318.053511) (xy 385.064772 -318.043667) (xy 385.018756 -318.026215)
			(xy 384.976135 -318.001608) (xy 384.938014 -317.970483) (xy 384.905379 -317.933646) (xy 384.879076 -317.89205)
			(xy 384.859785 -317.846774) (xy 384.848008 -317.79899) (xy 384.844048 -317.749936) (xy 381.505622 -317.749936)
			(xy 381.52577 -317.772037) (xy 381.651175 -317.92149) (xy 381.770339 -318.075964) (xy 381.88306 -318.235201)
			(xy 381.989149 -318.398932) (xy 382.088427 -318.566879) (xy 382.159855 -318.699896) (xy 385.794008 -318.699896)
			(xy 385.797968 -318.650842) (xy 385.809745 -318.603058) (xy 385.829036 -318.557782) (xy 385.855339 -318.516186)
			(xy 385.887974 -318.479349) (xy 385.926095 -318.448224) (xy 385.968716 -318.423617) (xy 386.014732 -318.406165)
			(xy 386.062951 -318.396321) (xy 386.112126 -318.39434) (xy 386.160981 -318.400272) (xy 386.208252 -318.413964)
			(xy 386.252714 -318.435062) (xy 386.293217 -318.463018) (xy 386.32871 -318.49711) (xy 386.358275 -318.536454)
			(xy 386.381146 -318.580031) (xy 386.39673 -318.626712) (xy 386.404625 -318.675289) (xy 386.40512 -318.699896)
			(xy 386.404625 -318.724503) (xy 386.404446 -318.725604) (xy 386.723378 -318.725604) (xy 386.723378 -318.674188)
			(xy 386.731421 -318.623406) (xy 386.747309 -318.574507) (xy 386.770652 -318.528695) (xy 386.800873 -318.487099)
			(xy 386.837229 -318.450743) (xy 386.878825 -318.420522) (xy 386.924637 -318.397179) (xy 386.973536 -318.381291)
			(xy 387.024318 -318.373248) (xy 387.075734 -318.373248) (xy 387.126516 -318.381291) (xy 387.175415 -318.397179)
			(xy 387.221227 -318.420522) (xy 387.262823 -318.450743) (xy 387.299179 -318.487099) (xy 387.3294 -318.528695)
			(xy 387.352743 -318.574507) (xy 387.368631 -318.623406) (xy 387.376674 -318.674188) (xy 387.377178 -318.699896)
			(xy 387.694182 -318.699896) (xy 387.698142 -318.650842) (xy 387.709919 -318.603058) (xy 387.72921 -318.557782)
			(xy 387.755513 -318.516186) (xy 387.788148 -318.479349) (xy 387.826269 -318.448224) (xy 387.86889 -318.423617)
			(xy 387.914906 -318.406165) (xy 387.963125 -318.396321) (xy 388.0123 -318.39434) (xy 388.061155 -318.400272)
			(xy 388.108426 -318.413964) (xy 388.152888 -318.435062) (xy 388.193391 -318.463018) (xy 388.228884 -318.49711)
			(xy 388.258449 -318.536454) (xy 388.28132 -318.580031) (xy 388.296904 -318.626712) (xy 388.304799 -318.675289)
			(xy 388.305294 -318.699896) (xy 388.304799 -318.724503) (xy 388.296904 -318.77308) (xy 388.28132 -318.819761)
			(xy 388.258449 -318.863338) (xy 388.228884 -318.902682) (xy 388.193391 -318.936774) (xy 388.152888 -318.96473)
			(xy 388.108426 -318.985828) (xy 388.061155 -318.99952) (xy 388.0123 -319.005452) (xy 387.963125 -319.003471)
			(xy 387.914906 -318.993627) (xy 387.86889 -318.976175) (xy 387.826269 -318.951568) (xy 387.788148 -318.920443)
			(xy 387.755513 -318.883606) (xy 387.72921 -318.84201) (xy 387.709919 -318.796734) (xy 387.698142 -318.74895)
			(xy 387.694182 -318.699896) (xy 387.377178 -318.699896) (xy 387.376674 -318.725604) (xy 387.368631 -318.776386)
			(xy 387.352743 -318.825285) (xy 387.3294 -318.871097) (xy 387.299179 -318.912693) (xy 387.262823 -318.949049)
			(xy 387.221227 -318.97927) (xy 387.175415 -319.002613) (xy 387.126516 -319.018501) (xy 387.075734 -319.026544)
			(xy 387.024318 -319.026544) (xy 386.973536 -319.018501) (xy 386.924637 -319.002613) (xy 386.878825 -318.97927)
			(xy 386.837229 -318.949049) (xy 386.800873 -318.912693) (xy 386.770652 -318.871097) (xy 386.747309 -318.825285)
			(xy 386.731421 -318.776386) (xy 386.723378 -318.725604) (xy 386.404446 -318.725604) (xy 386.39673 -318.77308)
			(xy 386.381146 -318.819761) (xy 386.358275 -318.863338) (xy 386.32871 -318.902682) (xy 386.293217 -318.936774)
			(xy 386.252714 -318.96473) (xy 386.208252 -318.985828) (xy 386.160981 -318.99952) (xy 386.112126 -319.005452)
			(xy 386.062951 -319.003471) (xy 386.014732 -318.993627) (xy 385.968716 -318.976175) (xy 385.926095 -318.951568)
			(xy 385.887974 -318.920443) (xy 385.855339 -318.883606) (xy 385.829036 -318.84201) (xy 385.809745 -318.796734)
			(xy 385.797968 -318.74895) (xy 385.794008 -318.699896) (xy 382.159855 -318.699896) (xy 382.180725 -318.738762)
			(xy 382.26589 -318.914288) (xy 382.343776 -319.093163) (xy 382.414253 -319.275085) (xy 382.477201 -319.459747)
			(xy 382.532516 -319.646837) (xy 382.533339 -319.65011) (xy 386.744222 -319.65011) (xy 386.748182 -319.601056)
			(xy 386.759959 -319.553272) (xy 386.77925 -319.507996) (xy 386.805553 -319.4664) (xy 386.838188 -319.429563)
			(xy 386.876309 -319.398438) (xy 386.91893 -319.373831) (xy 386.964946 -319.356379) (xy 387.013165 -319.346535)
			(xy 387.06234 -319.344554) (xy 387.111195 -319.350486) (xy 387.158466 -319.364178) (xy 387.202928 -319.385276)
			(xy 387.243431 -319.413232) (xy 387.278924 -319.447324) (xy 387.308489 -319.486668) (xy 387.33136 -319.530245)
			(xy 387.346944 -319.576926) (xy 387.354839 -319.625503) (xy 387.355334 -319.65011) (xy 387.354839 -319.674717)
			(xy 387.346944 -319.723294) (xy 387.33136 -319.769975) (xy 387.308489 -319.813552) (xy 387.278924 -319.852896)
			(xy 387.243431 -319.886988) (xy 387.202928 -319.914944) (xy 387.158466 -319.936042) (xy 387.111195 -319.949734)
			(xy 387.06234 -319.955666) (xy 387.013165 -319.953685) (xy 386.964946 -319.943841) (xy 386.91893 -319.926389)
			(xy 386.876309 -319.901782) (xy 386.838188 -319.870657) (xy 386.805553 -319.83382) (xy 386.77925 -319.792224)
			(xy 386.759959 -319.746948) (xy 386.748182 -319.699164) (xy 386.744222 -319.65011) (xy 382.533339 -319.65011)
			(xy 382.580102 -319.836041) (xy 382.619881 -320.027038) (xy 382.651785 -320.219508) (xy 382.67576 -320.413126)
			(xy 382.691766 -320.607564) (xy 382.699775 -320.802496) (xy 382.700276 -320.900044) (xy 382.699775 -320.997592)
			(xy 382.691766 -321.192524) (xy 382.67576 -321.386962) (xy 382.651785 -321.58058) (xy 382.619881 -321.77305)
			(xy 382.580102 -321.964047) (xy 382.532516 -322.153251) (xy 382.477201 -322.340341) (xy 382.414253 -322.525003)
			(xy 382.343776 -322.706925) (xy 382.26589 -322.8858) (xy 382.180725 -323.061326) (xy 382.088427 -323.233209)
			(xy 381.989149 -323.401156) (xy 381.88306 -323.564887) (xy 381.770339 -323.724124) (xy 381.651175 -323.878598)
			(xy 381.52577 -324.028051) (xy 381.394334 -324.172229) (xy 381.25709 -324.310889) (xy 381.114269 -324.443797)
			(xy 380.966112 -324.570731) (xy 380.812869 -324.691474) (xy 380.654798 -324.805824) (xy 380.492165 -324.913589)
			(xy 380.325246 -325.014585) (xy 380.15432 -325.108644) (xy 379.979677 -325.195606) (xy 379.801611 -325.275324)
			(xy 379.620423 -325.347665) (xy 379.436417 -325.412506) (xy 379.249904 -325.469738) (xy 379.061199 -325.519265)
			(xy 378.87062 -325.561002) (xy 378.678487 -325.59488) (xy 378.485126 -325.620842) (xy 378.290862 -325.638843)
			(xy 378.096023 -325.648854) (xy 377.900937 -325.650857) (xy 377.705934 -325.644849) (xy 377.511341 -325.63084)
			(xy 377.317488 -325.608854) (xy 377.124701 -325.578928) (xy 376.933304 -325.541112) (xy 376.743622 -325.49547)
			(xy 376.555974 -325.44208) (xy 376.370675 -325.38103) (xy 376.18804 -325.312425) (xy 376.008375 -325.236379)
			(xy 375.831983 -325.153021) (xy 375.659162 -325.062492) (xy 375.490204 -324.964944) (xy 375.325393 -324.860541)
			(xy 375.165007 -324.749461) (xy 375.009317 -324.631889) (xy 374.858585 -324.508025) (xy 374.713066 -324.378076)
			(xy 374.573004 -324.242263) (xy 374.438636 -324.100814) (xy 374.310189 -323.953968) (xy 374.187878 -323.801973)
			(xy 374.071911 -323.645084) (xy 373.962483 -323.483566) (xy 373.859778 -323.317692) (xy 373.76397 -323.147741)
			(xy 373.675219 -322.974) (xy 373.593677 -322.796762) (xy 373.51948 -322.616326) (xy 373.452753 -322.432995)
			(xy 373.393609 -322.24708) (xy 373.342148 -322.058893) (xy 373.298456 -321.868753) (xy 373.262607 -321.676978)
			(xy 373.234662 -321.483894) (xy 373.214667 -321.289825) (xy 373.202657 -321.095099) (xy 373.198651 -320.900044)
			(xy 351.03562 -320.900044) (xy 351.03562 -325.77786) (xy 359.257344 -325.77786) (xy 359.261415 -325.722238)
			(xy 359.273541 -325.667801) (xy 359.293464 -325.61571) (xy 359.32076 -325.567075) (xy 359.354846 -325.522932)
			(xy 359.394995 -325.484223) (xy 359.440353 -325.451772) (xy 359.489953 -325.426271) (xy 359.542737 -325.408264)
			(xy 359.59758 -325.398134) (xy 359.653314 -325.396097) (xy 359.708751 -325.402197) (xy 359.762708 -325.416303)
			(xy 359.814037 -325.438115) (xy 359.861643 -325.467169) (xy 359.904511 -325.502844) (xy 359.941728 -325.544381)
			(xy 359.972501 -325.590894) (xy 359.996173 -325.641391) (xy 360.012241 -325.694798) (xy 360.020361 -325.749974)
			(xy 360.02087 -325.77786) (xy 360.020361 -325.805746) (xy 360.012241 -325.860922) (xy 359.996173 -325.914329)
			(xy 359.972501 -325.964826) (xy 359.941728 -326.011339) (xy 359.904511 -326.052876) (xy 359.861643 -326.088551)
			(xy 359.814037 -326.117605) (xy 359.762708 -326.139417) (xy 359.708751 -326.153523) (xy 359.653314 -326.159623)
			(xy 359.59758 -326.157586) (xy 359.542737 -326.147456) (xy 359.489953 -326.129449) (xy 359.440353 -326.103948)
			(xy 359.394995 -326.071497) (xy 359.354846 -326.032788) (xy 359.32076 -325.988645) (xy 359.293464 -325.94001)
			(xy 359.273541 -325.887919) (xy 359.261415 -325.833482) (xy 359.257344 -325.77786) (xy 351.03562 -325.77786)
			(xy 351.03562 -326.508364) (xy 351.65995 -326.508364) (xy 351.664021 -326.452742) (xy 351.676147 -326.398305)
			(xy 351.69607 -326.346214) (xy 351.723366 -326.297579) (xy 351.757452 -326.253436) (xy 351.797601 -326.214727)
			(xy 351.842959 -326.182276) (xy 351.892559 -326.156775) (xy 351.945343 -326.138768) (xy 352.000186 -326.128638)
			(xy 352.05592 -326.126601) (xy 352.111357 -326.132701) (xy 352.165314 -326.146807) (xy 352.216643 -326.168619)
			(xy 352.264249 -326.197673) (xy 352.307117 -326.233348) (xy 352.344334 -326.274885) (xy 352.375107 -326.321398)
			(xy 352.398779 -326.371895) (xy 352.414847 -326.425302) (xy 352.422967 -326.480478) (xy 352.423476 -326.508364)
			(xy 352.80295 -326.508364) (xy 352.807021 -326.452742) (xy 352.819147 -326.398305) (xy 352.83907 -326.346214)
			(xy 352.866366 -326.297579) (xy 352.900452 -326.253436) (xy 352.940601 -326.214727) (xy 352.985959 -326.182276)
			(xy 353.035559 -326.156775) (xy 353.088343 -326.138768) (xy 353.143186 -326.128638) (xy 353.19892 -326.126601)
			(xy 353.254357 -326.132701) (xy 353.308314 -326.146807) (xy 353.359643 -326.168619) (xy 353.407249 -326.197673)
			(xy 353.450117 -326.233348) (xy 353.487334 -326.274885) (xy 353.518107 -326.321398) (xy 353.541779 -326.371895)
			(xy 353.557847 -326.425302) (xy 353.563492 -326.46366) (xy 356.238808 -326.46366) (xy 356.242879 -326.408038)
			(xy 356.255005 -326.353601) (xy 356.274928 -326.30151) (xy 356.302224 -326.252875) (xy 356.33631 -326.208732)
			(xy 356.376459 -326.170023) (xy 356.421817 -326.137572) (xy 356.471417 -326.112071) (xy 356.524201 -326.094064)
			(xy 356.579044 -326.083934) (xy 356.634778 -326.081897) (xy 356.690215 -326.087997) (xy 356.744172 -326.102103)
			(xy 356.795501 -326.123915) (xy 356.843107 -326.152969) (xy 356.885975 -326.188644) (xy 356.923192 -326.230181)
			(xy 356.953965 -326.276694) (xy 356.977637 -326.327191) (xy 356.993705 -326.380598) (xy 357.001825 -326.435774)
			(xy 357.002334 -326.46366) (xy 357.001825 -326.491546) (xy 356.993705 -326.546722) (xy 356.977637 -326.600129)
			(xy 356.953965 -326.650626) (xy 356.923192 -326.697139) (xy 356.885975 -326.738676) (xy 356.843107 -326.774351)
			(xy 356.795501 -326.803405) (xy 356.744172 -326.825217) (xy 356.690215 -326.839323) (xy 356.634778 -326.845423)
			(xy 356.579044 -326.843386) (xy 356.524201 -326.833256) (xy 356.471417 -326.815249) (xy 356.421817 -326.789748)
			(xy 356.376459 -326.757297) (xy 356.33631 -326.718588) (xy 356.302224 -326.674445) (xy 356.274928 -326.62581)
			(xy 356.255005 -326.573719) (xy 356.242879 -326.519282) (xy 356.238808 -326.46366) (xy 353.563492 -326.46366)
			(xy 353.565967 -326.480478) (xy 353.566476 -326.508364) (xy 353.565967 -326.53625) (xy 353.557847 -326.591426)
			(xy 353.541779 -326.644833) (xy 353.518107 -326.69533) (xy 353.487334 -326.741843) (xy 353.450117 -326.78338)
			(xy 353.407249 -326.819055) (xy 353.359643 -326.848109) (xy 353.308314 -326.869921) (xy 353.254357 -326.884027)
			(xy 353.19892 -326.890127) (xy 353.143186 -326.88809) (xy 353.088343 -326.87796) (xy 353.035559 -326.859953)
			(xy 352.985959 -326.834452) (xy 352.940601 -326.802001) (xy 352.900452 -326.763292) (xy 352.866366 -326.719149)
			(xy 352.83907 -326.670514) (xy 352.819147 -326.618423) (xy 352.807021 -326.563986) (xy 352.80295 -326.508364)
			(xy 352.423476 -326.508364) (xy 352.422967 -326.53625) (xy 352.414847 -326.591426) (xy 352.398779 -326.644833)
			(xy 352.375107 -326.69533) (xy 352.344334 -326.741843) (xy 352.307117 -326.78338) (xy 352.264249 -326.819055)
			(xy 352.216643 -326.848109) (xy 352.165314 -326.869921) (xy 352.111357 -326.884027) (xy 352.05592 -326.890127)
			(xy 352.000186 -326.88809) (xy 351.945343 -326.87796) (xy 351.892559 -326.859953) (xy 351.842959 -326.834452)
			(xy 351.797601 -326.802001) (xy 351.757452 -326.763292) (xy 351.723366 -326.719149) (xy 351.69607 -326.670514)
			(xy 351.676147 -326.618423) (xy 351.664021 -326.563986) (xy 351.65995 -326.508364) (xy 351.03562 -326.508364)
			(xy 351.03562 -327.471024) (xy 351.036048 -327.481092) (xy 351.043771 -327.499688) (xy 351.050606 -327.507092)
			(xy 353.085908 -329.542394) (xy 361.73359 -329.542394) (xy 361.737661 -329.486772) (xy 361.749787 -329.432335)
			(xy 361.76971 -329.380244) (xy 361.797006 -329.331609) (xy 361.831092 -329.287466) (xy 361.871241 -329.248757)
			(xy 361.916599 -329.216306) (xy 361.966199 -329.190805) (xy 362.018983 -329.172798) (xy 362.073826 -329.162668)
			(xy 362.12956 -329.160631) (xy 362.184997 -329.166731) (xy 362.238954 -329.180837) (xy 362.290283 -329.202649)
			(xy 362.337889 -329.231703) (xy 362.380757 -329.267378) (xy 362.417974 -329.308915) (xy 362.448747 -329.355428)
			(xy 362.472419 -329.405925) (xy 362.488487 -329.459332) (xy 362.496607 -329.514508) (xy 362.497116 -329.542394)
			(xy 362.496607 -329.57028) (xy 362.488487 -329.625456) (xy 362.472419 -329.678863) (xy 362.448747 -329.72936)
			(xy 362.417974 -329.775873) (xy 362.380757 -329.81741) (xy 362.337889 -329.853085) (xy 362.290283 -329.882139)
			(xy 362.238954 -329.903951) (xy 362.184997 -329.918057) (xy 362.12956 -329.924157) (xy 362.073826 -329.92212)
			(xy 362.018983 -329.91199) (xy 361.966199 -329.893983) (xy 361.916599 -329.868482) (xy 361.871241 -329.836031)
			(xy 361.831092 -329.797322) (xy 361.797006 -329.753179) (xy 361.76971 -329.704544) (xy 361.749787 -329.652453)
			(xy 361.737661 -329.598016) (xy 361.73359 -329.542394) (xy 353.085908 -329.542394) (xy 354.127816 -330.584302)
			(xy 354.135216 -330.591145) (xy 354.153813 -330.598874) (xy 354.163884 -330.599288) (xy 357.97744 -330.599288)
		)
		(stroke
			(width 0)
			(type solid)
		)
		(fill yes)
		(layer "In13.Cu")
		(net "P0V8_PEX3")
	)
	(gr_poly
		(pts
			(xy 321.8688 -417.971732) (xy 321.876406 -417.970219) (xy 321.890242 -417.963235) (xy 321.895978 -417.958016)
			(xy 322.019422 -417.834572) (xy 322.026116 -417.82713) (xy 322.033711 -417.808633) (xy 322.033685 -417.788637)
			(xy 322.030344 -417.7792) (xy 322.024502 -417.764976) (xy 321.999102 -417.747958) (xy 313.116722 -417.747958)
			(xy 313.106701 -417.747542) (xy 313.088184 -417.739874) (xy 313.074015 -417.7257) (xy 313.066354 -417.707179)
			(xy 313.065922 -417.697158) (xy 313.065922 -417.378642) (xy 313.073796 -417.378642) (xy 313.073796 -394.32992)
			(xy 313.073796 -394.27912) (xy 322.758308 -394.27912) (xy 322.767818 -394.277998) (xy 322.785059 -394.269692)
			(xy 322.798094 -394.255681) (xy 322.805135 -394.237887) (xy 322.805552 -394.22832) (xy 322.805552 -389.621014)
			(xy 322.803774 -389.608314) (xy 321.934332 -386.282692) (xy 321.93357 -386.27939) (xy 315.387228 -369.650772)
			(xy 315.379862 -369.643152) (xy 307.776372 -362.039662) (xy 307.769524 -362.032265) (xy 307.761792 -362.013666)
			(xy 307.761386 -362.003594) (xy 307.761386 -341.999824) (xy 307.760782 -341.988262) (xy 307.750611 -341.967487)
			(xy 307.741828 -341.959946) (xy 307.659024 -341.89543) (xy 307.65587 -341.893067) (xy 307.648982 -341.889237)
			(xy 307.645308 -341.88781) (xy 307.641498 -341.88654) (xy 301.042578 -340.039198) (xy 301.041308 -340.038944)
			(xy 297.665902 -339.259418) (xy 295.161208 -339.259418) (xy 295.157401 -339.259354) (xy 295.149874 -339.258209)
			(xy 295.146222 -339.257132) (xy 288.643568 -337.19897) (xy 288.640774 -337.198462) (xy 281.656282 -335.7372)
			(xy 281.609286 -335.726763) (xy 281.517396 -335.698036) (xy 281.4287 -335.660591) (xy 281.344023 -335.614778)
			(xy 281.264153 -335.561021) (xy 281.189832 -335.499821) (xy 281.155394 -335.466182) (xy 275.774404 -330.085192)
			(xy 275.739209 -330.049154) (xy 275.675461 -329.971154) (xy 275.64715 -329.92949) (xy 275.637752 -329.915012)
			(xy 275.61493 -329.878292) (xy 275.574998 -329.801601) (xy 275.557996 -329.76185) (xy 274.162266 -326.392286)
			(xy 274.144055 -326.346813) (xy 274.11561 -326.253072) (xy 274.096492 -326.156994) (xy 274.086886 -326.059505)
			(xy 274.08632 -326.010524) (xy 274.08632 -324.598284) (xy 274.086249 -324.594276) (xy 274.084966 -324.586365)
			(xy 274.08378 -324.582536) (xy 273.675094 -323.356732) (xy 273.662813 -323.318794) (xy 273.643686 -323.241372)
			(xy 273.630868 -323.16266) (xy 273.624442 -323.083171) (xy 273.62404 -323.043296) (xy 273.62404 -320.06286)
			(xy 273.624548 -320.018093) (xy 273.632665 -319.928928) (xy 273.648819 -319.840863) (xy 273.672877 -319.754622)
			(xy 273.688302 -319.712594) (xy 273.691604 -319.703958) (xy 273.694144 -319.690242) (xy 273.69516 -319.68059)
			(xy 273.69516 -319.048384) (xy 273.69473 -319.038638) (xy 273.687443 -319.020562) (xy 273.673902 -319.006544)
			(xy 273.665188 -319.002156) (xy 273.664934 -319.001902) (xy 273.66468 -319.001902) (xy 273.641728 -318.991078)
			(xy 273.599139 -318.963493) (xy 273.56126 -318.92973) (xy 273.528978 -318.890581) (xy 273.50305 -318.846964)
			(xy 273.484083 -318.799899) (xy 273.472523 -318.750492) (xy 273.468639 -318.699898) (xy 273.472523 -318.649305)
			(xy 273.484084 -318.599897) (xy 273.503051 -318.552834) (xy 273.52898 -318.509216) (xy 273.561262 -318.470067)
			(xy 273.599142 -318.436305) (xy 273.641731 -318.40872) (xy 273.66468 -318.39789) (xy 273.664934 -318.39789)
			(xy 273.665188 -318.397636) (xy 273.673883 -318.393233) (xy 273.687378 -318.379193) (xy 273.694688 -318.361143)
			(xy 273.69516 -318.351408) (xy 273.69516 -318.098424) (xy 273.694735 -318.088706) (xy 273.687522 -318.07066)
			(xy 273.67412 -318.056586) (xy 273.665442 -318.052196) (xy 273.664934 -318.051942) (xy 273.66468 -318.051942)
			(xy 273.640239 -318.040428) (xy 273.59516 -318.010654) (xy 273.555526 -317.973942) (xy 273.522393 -317.931271)
			(xy 273.496643 -317.883778) (xy 273.478963 -317.832729) (xy 273.469823 -317.779484) (xy 273.4691 -317.752476)
			(xy 273.4691 -317.746888) (xy 273.470878 -317.715392) (xy 273.471132 -317.710058) (xy 273.470702 -317.69999)
			(xy 273.462981 -317.681394) (xy 273.456146 -317.67399) (xy 273.392138 -317.610236) (xy 273.370802 -317.602616)
			(xy 273.359118 -317.603886) (xy 273.32432 -317.605664) (xy 273.29003 -317.603886) (xy 273.2786 -317.602616)
			(xy 273.25701 -317.61049) (xy 273.193256 -317.674244) (xy 273.189362 -317.6783) (xy 273.183332 -317.68779)
			(xy 273.181318 -317.69304) (xy 273.177508 -317.703962) (xy 273.178524 -317.715392) (xy 273.180556 -317.749936)
			(xy 273.180556 -318.699896) (xy 273.180046 -318.725903) (xy 273.171909 -318.777277) (xy 273.155836 -318.826745)
			(xy 273.132222 -318.87309) (xy 273.101648 -318.915171) (xy 273.064869 -318.95195) (xy 273.022788 -318.982524)
			(xy 272.976443 -319.006138) (xy 272.926975 -319.022211) (xy 272.875601 -319.030348) (xy 272.823587 -319.030348)
			(xy 272.772213 -319.022211) (xy 272.722745 -319.006138) (xy 272.6764 -318.982524) (xy 272.634319 -318.95195)
			(xy 272.59754 -318.915171) (xy 272.566966 -318.87309) (xy 272.543352 -318.826745) (xy 272.527279 -318.777277)
			(xy 272.519142 -318.725903) (xy 272.518632 -318.699896) (xy 272.518632 -317.749936) (xy 272.519112 -317.723946)
			(xy 272.527239 -317.672605) (xy 272.543299 -317.623169) (xy 272.566896 -317.576853) (xy 272.597448 -317.5348)
			(xy 272.634203 -317.498045) (xy 272.676257 -317.467493) (xy 272.722572 -317.443898) (xy 272.772009 -317.427839)
			(xy 272.82335 -317.419712) (xy 272.84934 -317.419228) (xy 272.849848 -317.419228) (xy 272.883376 -317.420752)
			(xy 272.89487 -317.421489) (xy 272.916567 -317.413829) (xy 272.925032 -317.40602) (xy 272.988532 -317.342266)
			(xy 272.996152 -317.32093) (xy 272.994882 -317.309246) (xy 272.993104 -317.27521) (xy 272.993104 -316.324742)
			(xy 272.993584 -316.29873) (xy 273.001716 -316.247345) (xy 273.017787 -316.197864) (xy 273.0414 -316.151507)
			(xy 273.071974 -316.109415) (xy 273.108757 -316.072624) (xy 273.150842 -316.04204) (xy 273.197194 -316.018416)
			(xy 273.246671 -316.002334) (xy 273.298054 -315.99419) (xy 273.324066 -315.99378) (xy 273.324574 -315.99378)
			(xy 273.357086 -315.995304) (xy 273.35734 -315.995304) (xy 273.367908 -315.995844) (xy 273.388 -315.989288)
			(xy 273.396202 -315.982604) (xy 273.451828 -315.932312) (xy 273.459343 -315.92477) (xy 273.468012 -315.90535)
			(xy 273.468592 -315.89472) (xy 273.468592 -315.849762) (xy 273.469149 -315.82252) (xy 273.478081 -315.768773)
			(xy 273.495696 -315.717216) (xy 273.521518 -315.66924) (xy 273.554851 -315.626142) (xy 273.594794 -315.589087)
			(xy 273.640267 -315.559076) (xy 273.664934 -315.547502) (xy 273.678904 -315.541406) (xy 273.69516 -315.51626)
			(xy 273.69516 -315.24829) (xy 273.694731 -315.238544) (xy 273.687445 -315.220465) (xy 273.673905 -315.206445)
			(xy 273.665188 -315.202062) (xy 273.664934 -315.201808) (xy 273.66468 -315.201808) (xy 273.641728 -315.190984)
			(xy 273.599138 -315.163399) (xy 273.561258 -315.129636) (xy 273.528975 -315.090486) (xy 273.503046 -315.046868)
			(xy 273.484079 -314.999803) (xy 273.472518 -314.950395) (xy 273.468634 -314.899801) (xy 273.472517 -314.849207)
			(xy 273.484078 -314.799798) (xy 273.503045 -314.752733) (xy 273.528974 -314.709115) (xy 273.561257 -314.669965)
			(xy 273.599137 -314.636202) (xy 273.641726 -314.608616) (xy 273.66468 -314.597796) (xy 273.664934 -314.597796)
			(xy 273.665188 -314.597542) (xy 273.673884 -314.59314) (xy 273.68738 -314.579099) (xy 273.694692 -314.56105)
			(xy 273.69516 -314.551314) (xy 273.69516 -314.29833) (xy 273.694738 -314.288579) (xy 273.687461 -314.270489)
			(xy 273.673922 -314.256457) (xy 273.665188 -314.252102) (xy 273.664934 -314.251848) (xy 273.66468 -314.251848)
			(xy 273.641725 -314.241024) (xy 273.599129 -314.213438) (xy 273.561243 -314.179673) (xy 273.528955 -314.140521)
			(xy 273.503021 -314.096899) (xy 273.484049 -314.04983) (xy 273.472484 -314.000417) (xy 273.468597 -313.949817)
			(xy 273.472479 -313.899217) (xy 273.484039 -313.849803) (xy 273.503005 -313.802732) (xy 273.528935 -313.759107)
			(xy 273.561219 -313.719952) (xy 273.599102 -313.686183) (xy 273.641695 -313.658592) (xy 273.66468 -313.647836)
			(xy 273.664934 -313.647836) (xy 273.665188 -313.647582) (xy 273.673889 -313.643182) (xy 273.687395 -313.629143)
			(xy 273.694722 -313.611092) (xy 273.69516 -313.601354) (xy 273.69516 -313.34837) (xy 273.694728 -313.338626)
			(xy 273.687438 -313.320554) (xy 273.673896 -313.30654) (xy 273.665188 -313.302142) (xy 273.664934 -313.301888)
			(xy 273.66468 -313.301888) (xy 273.641729 -313.291064) (xy 273.599143 -313.263479) (xy 273.561265 -313.229717)
			(xy 273.528985 -313.190569) (xy 273.503059 -313.146953) (xy 273.484094 -313.09989) (xy 273.472534 -313.050484)
			(xy 273.468652 -312.999893) (xy 273.472537 -312.949301) (xy 273.484098 -312.899896) (xy 273.503065 -312.852834)
			(xy 273.528994 -312.809219) (xy 273.561276 -312.770072) (xy 273.599154 -312.736312) (xy 273.641742 -312.708729)
			(xy 273.66468 -312.697876) (xy 273.664934 -312.697876) (xy 273.665188 -312.697622) (xy 273.673882 -312.693219)
			(xy 273.687372 -312.679177) (xy 273.694678 -312.661128) (xy 273.69516 -312.651394) (xy 273.69516 -312.383424)
			(xy 273.678904 -312.358278) (xy 273.664934 -312.352182) (xy 273.640265 -312.340609) (xy 273.594778 -312.310614)
			(xy 273.554825 -312.273565) (xy 273.521489 -312.230467) (xy 273.495671 -312.182485) (xy 273.478071 -312.130919)
			(xy 273.469165 -312.077166) (xy 273.468592 -312.049922) (xy 273.468592 -312.004964) (xy 273.468013 -311.994425)
			(xy 273.459494 -311.975138) (xy 273.452082 -311.967626) (xy 273.39671 -311.91708) (xy 273.389538 -311.911024)
			(xy 273.372053 -311.90423) (xy 273.362674 -311.903872) (xy 273.357086 -311.903872) (xy 273.3548 -311.904126)
			(xy 273.324828 -311.905396) (xy 273.309842 -311.905396) (xy 273.284625 -311.9038) (xy 273.235076 -311.893915)
			(xy 273.187605 -311.876613) (xy 273.143316 -311.852295) (xy 273.103239 -311.821528) (xy 273.068304 -311.785025)
			(xy 273.039324 -311.743637) (xy 273.016973 -311.698324) (xy 273.001769 -311.65014) (xy 272.994067 -311.600205)
			(xy 272.993612 -311.574942) (xy 272.993612 -310.624728) (xy 272.994122 -310.598721) (xy 273.002259 -310.547347)
			(xy 273.018332 -310.497879) (xy 273.041946 -310.451534) (xy 273.07252 -310.409453) (xy 273.109299 -310.372674)
			(xy 273.15138 -310.3421) (xy 273.197725 -310.318486) (xy 273.247193 -310.302413) (xy 273.298567 -310.294276)
			(xy 273.350581 -310.294276) (xy 273.401955 -310.302413) (xy 273.451423 -310.318486) (xy 273.497768 -310.3421)
			(xy 273.539849 -310.372674) (xy 273.576628 -310.409453) (xy 273.607202 -310.451534) (xy 273.630816 -310.497879)
			(xy 273.646889 -310.547347) (xy 273.655026 -310.598721) (xy 273.655536 -310.624728) (xy 273.655536 -310.68645)
			(xy 273.656005 -310.696121) (xy 273.66325 -310.714061) (xy 273.676618 -310.728047) (xy 273.685254 -310.732424)
			(xy 273.691604 -310.735218) (xy 273.791934 -310.764682) (xy 273.80057 -310.764682) (xy 273.80923 -310.764157)
			(xy 273.825456 -310.75805) (xy 273.83232 -310.752744) (xy 273.838924 -310.747156) (xy 273.843242 -310.740298)
			(xy 273.855193 -310.721501) (xy 273.880602 -310.684909) (xy 273.894042 -310.667146) (xy 273.897852 -310.662574)
			(xy 273.89836 -310.661812) (xy 273.922744 -310.63184) (xy 273.922998 -310.631586) (xy 273.925538 -310.628538)
			(xy 273.9263 -310.627522) (xy 273.926554 -310.627268) (xy 273.933412 -310.619394) (xy 273.943318 -310.595264)
			(xy 273.94408 -310.591708) (xy 273.94662 -310.581802) (xy 273.947128 -310.579008) (xy 273.951099 -310.553996)
			(xy 273.965654 -310.505491) (xy 273.987437 -310.459773) (xy 274.015939 -310.417913) (xy 274.050493 -310.380891)
			(xy 274.09029 -310.349573) (xy 274.134398 -310.324693) (xy 274.181786 -310.306831) (xy 274.206462 -310.301132)
			(xy 274.208748 -310.300624) (xy 274.215352 -310.298592) (xy 274.221956 -310.296306) (xy 274.227053 -310.294214)
			(xy 274.236283 -310.288198) (xy 274.240244 -310.284368) (xy 274.41652 -310.108092) (xy 274.423632 -310.094884)
			(xy 274.424902 -310.087264) (xy 274.429938 -310.063365) (xy 274.446107 -310.017279) (xy 274.468881 -309.974075)
			(xy 274.497765 -309.934692) (xy 274.53213 -309.899988) (xy 274.571227 -309.870718) (xy 274.614206 -309.847521)
			(xy 274.660131 -309.8309) (xy 274.683982 -309.825644) (xy 274.688808 -309.824628) (xy 274.70608 -309.817516)
			(xy 274.70989 -309.814976) (xy 274.74404 -309.79379) (xy 274.815254 -309.756531) (xy 274.85213 -309.740554)
			(xy 274.853654 -309.740046) (xy 274.865592 -309.734204) (xy 274.867116 -309.733442) (xy 274.877642 -309.727019)
			(xy 274.891556 -309.70671) (xy 274.893786 -309.69458) (xy 274.894294 -309.690262) (xy 274.894294 -309.687722)
			(xy 274.89404 -309.674768) (xy 274.89404 -309.674514) (xy 274.895818 -309.640478) (xy 274.897088 -309.629048)
			(xy 274.889468 -309.607458) (xy 274.82546 -309.54345) (xy 274.821403 -309.539556) (xy 274.811914 -309.533526)
			(xy 274.806664 -309.531512) (xy 274.795742 -309.527702) (xy 274.784312 -309.528718) (xy 274.750276 -309.530496)
			(xy 273.799808 -309.530496) (xy 273.773819 -309.530014) (xy 273.722482 -309.521884) (xy 273.673048 -309.505823)
			(xy 273.626735 -309.482226) (xy 273.584684 -309.451675) (xy 273.54793 -309.414922) (xy 273.517378 -309.372872)
			(xy 273.49378 -309.32656) (xy 273.477718 -309.277126) (xy 273.469587 -309.225789) (xy 273.469587 -309.173811)
			(xy 273.477718 -309.122474) (xy 273.49378 -309.07304) (xy 273.517378 -309.026728) (xy 273.54793 -308.984678)
			(xy 273.584684 -308.947925) (xy 273.626735 -308.917374) (xy 273.673048 -308.893777) (xy 273.722482 -308.877716)
			(xy 273.773819 -308.869586) (xy 273.799808 -308.86908) (xy 274.749768 -308.86908) (xy 274.775759 -308.869561)
			(xy 274.827102 -308.877688) (xy 274.876542 -308.893747) (xy 274.92286 -308.917343) (xy 274.964917 -308.947894)
			(xy 275.001677 -308.984649) (xy 275.032234 -309.026702) (xy 275.055836 -309.073017) (xy 275.071902 -309.122455)
			(xy 275.080036 -309.173797) (xy 275.080476 -309.199788) (xy 275.080476 -309.200296) (xy 275.078698 -309.233824)
			(xy 275.077428 -309.245254) (xy 275.081492 -309.256684) (xy 275.083551 -309.261912) (xy 275.089565 -309.271402)
			(xy 275.09343 -309.27548) (xy 275.157438 -309.339488) (xy 275.179028 -309.347108) (xy 275.190458 -309.345838)
			(xy 275.224748 -309.34406) (xy 275.250734 -309.344573) (xy 275.302064 -309.352709) (xy 275.35149 -309.368774)
			(xy 275.397796 -309.392372) (xy 275.43984 -309.422922) (xy 275.476588 -309.459672) (xy 275.507136 -309.501718)
			(xy 275.530732 -309.548024) (xy 275.546794 -309.597451) (xy 275.554928 -309.648782) (xy 275.555456 -309.674768)
			(xy 275.555456 -309.684166) (xy 275.555893 -309.69423) (xy 275.56363 -309.712811) (xy 275.570442 -309.720234)
			(xy 275.586444 -309.736236) (xy 275.595588 -309.740046) (xy 275.634809 -309.757006) (xy 275.710359 -309.796947)
			(xy 275.746464 -309.819802) (xy 275.751544 -309.823104) (xy 275.780864 -309.828394) (xy 275.837076 -309.848118)
			(xy 275.888839 -309.877605) (xy 275.912072 -309.896256) (xy 275.918676 -309.901844) (xy 275.943568 -309.911242)
			(xy 275.947915 -309.912789) (xy 275.956989 -309.914458) (xy 275.961602 -309.914544) (xy 276.387814 -309.914544)
			(xy 276.392426 -309.914444) (xy 276.4015 -309.912785) (xy 276.405848 -309.911242) (xy 276.43074 -309.901844)
			(xy 276.437344 -309.896256) (xy 276.460616 -309.877592) (xy 276.512468 -309.848102) (xy 276.568764 -309.82838)
			(xy 276.598126 -309.823104) (xy 276.603206 -309.819802) (xy 276.640366 -309.796324) (xy 276.718213 -309.755491)
			(xy 276.758654 -309.738268) (xy 276.762464 -309.73649) (xy 276.771695 -309.732357) (xy 276.78614 -309.718224)
			(xy 276.793993 -309.699604) (xy 276.794468 -309.6895) (xy 276.794468 -309.686452) (xy 276.794214 -309.674768)
			(xy 276.794724 -309.648781) (xy 276.802854 -309.597446) (xy 276.818915 -309.548016) (xy 276.842511 -309.501706)
			(xy 276.873061 -309.459658) (xy 276.909812 -309.422907) (xy 276.95186 -309.392357) (xy 276.99817 -309.368761)
			(xy 277.0476 -309.3527) (xy 277.098935 -309.34457) (xy 277.150909 -309.34457) (xy 277.202244 -309.3527)
			(xy 277.251674 -309.368761) (xy 277.297984 -309.392357) (xy 277.340032 -309.422907) (xy 277.376783 -309.459658)
			(xy 277.407333 -309.501706) (xy 277.430929 -309.548016) (xy 277.44699 -309.597446) (xy 277.45512 -309.648781)
			(xy 277.45563 -309.674768) (xy 277.45563 -309.684166) (xy 277.456066 -309.69423) (xy 277.4638 -309.712815)
			(xy 277.470616 -309.720234) (xy 277.486618 -309.736236) (xy 277.495762 -309.740046) (xy 277.534984 -309.757005)
			(xy 277.610534 -309.796944) (xy 277.646638 -309.819802) (xy 277.651718 -309.823104) (xy 277.681039 -309.828392)
			(xy 277.737254 -309.848112) (xy 277.78902 -309.877596) (xy 277.812246 -309.896256) (xy 277.81885 -309.901844)
			(xy 277.843742 -309.911242) (xy 277.84809 -309.912783) (xy 277.857164 -309.914439) (xy 277.861776 -309.914544)
			(xy 278.287988 -309.914544) (xy 278.292601 -309.914446) (xy 278.301676 -309.912791) (xy 278.306022 -309.911242)
			(xy 278.330914 -309.901844) (xy 278.337518 -309.896256) (xy 278.360759 -309.877619) (xy 278.412531 -309.848158)
			(xy 278.468734 -309.828421) (xy 278.498046 -309.823104) (xy 278.503126 -309.819802) (xy 278.541281 -309.795712)
			(xy 278.6213 -309.753991) (xy 278.662892 -309.73649) (xy 278.672307 -309.732085) (xy 278.686824 -309.717236)
			(xy 278.694296 -309.697862) (xy 278.694388 -309.687468) (xy 278.694134 -309.674768) (xy 278.694644 -309.648781)
			(xy 278.702774 -309.597446) (xy 278.718835 -309.548016) (xy 278.742431 -309.501706) (xy 278.772981 -309.459658)
			(xy 278.809732 -309.422907) (xy 278.85178 -309.392357) (xy 278.89809 -309.368761) (xy 278.94752 -309.3527)
			(xy 278.998855 -309.34457) (xy 279.050829 -309.34457) (xy 279.102164 -309.3527) (xy 279.151594 -309.368761)
			(xy 279.197904 -309.392357) (xy 279.239952 -309.422907) (xy 279.276703 -309.459658) (xy 279.307253 -309.501706)
			(xy 279.330849 -309.548016) (xy 279.34691 -309.597446) (xy 279.35504 -309.648781) (xy 279.35555 -309.674768)
			(xy 279.35555 -309.684166) (xy 279.355987 -309.69423) (xy 279.363723 -309.712812) (xy 279.370536 -309.720234)
			(xy 279.386538 -309.736236) (xy 279.395682 -309.740046) (xy 279.434903 -309.757006) (xy 279.510453 -309.796946)
			(xy 279.546558 -309.819802) (xy 279.551638 -309.823104) (xy 279.580958 -309.828393) (xy 279.637171 -309.848116)
			(xy 279.688935 -309.877603) (xy 279.712166 -309.896256) (xy 279.71877 -309.901844) (xy 279.743662 -309.911242)
			(xy 279.74801 -309.912781) (xy 279.757084 -309.914434) (xy 279.761696 -309.914544) (xy 280.187908 -309.914544)
			(xy 280.19252 -309.914444) (xy 280.201595 -309.912786) (xy 280.205942 -309.911242) (xy 280.230834 -309.901844)
			(xy 280.237438 -309.896256) (xy 280.260677 -309.877614) (xy 280.312445 -309.84814) (xy 280.368647 -309.82839)
			(xy 280.397966 -309.823104) (xy 280.403046 -309.819802) (xy 280.4412 -309.795709) (xy 280.521216 -309.753982)
			(xy 280.562812 -309.73649) (xy 280.572224 -309.732082) (xy 280.586735 -309.717233) (xy 280.594204 -309.697861)
			(xy 280.594308 -309.687468) (xy 280.594054 -309.674768) (xy 280.594553 -309.648946) (xy 280.602585 -309.597931)
			(xy 280.618448 -309.548784) (xy 280.641757 -309.5027) (xy 280.671946 -309.460799) (xy 280.708281 -309.424099)
			(xy 280.749878 -309.393493) (xy 280.795726 -309.369724) (xy 280.844712 -309.35337) (xy 280.895645 -309.344828)
			(xy 280.92146 -309.34406) (xy 280.924762 -309.34406) (xy 280.952405 -309.344622) (xy 281.006919 -309.353822)
			(xy 281.03322 -309.362348) (xy 281.037538 -309.363872) (xy 281.04211 -309.364634) (xy 281.050746 -309.367428)
			(xy 281.074876 -309.363872) (xy 281.084782 -309.35676) (xy 281.094203 -309.349098) (xy 281.105199 -309.327485)
			(xy 281.105864 -309.315358) (xy 281.105864 -309.113936) (xy 281.098244 -309.09514) (xy 281.090878 -309.088028)
			(xy 281.087322 -309.084472) (xy 281.027886 -309.035704) (xy 281.020922 -309.030504) (xy 281.004565 -309.024664)
			(xy 280.995882 -309.024274) (xy 280.986992 -309.024274) (xy 280.982166 -309.02529) (xy 280.96795 -309.027814)
			(xy 280.9392 -309.030486) (xy 280.924762 -309.030624) (xy 280.900733 -309.03015) (xy 280.853266 -309.022627)
			(xy 280.807561 -309.007771) (xy 280.764742 -308.98595) (xy 280.725863 -308.957699) (xy 280.691882 -308.923714)
			(xy 280.663635 -308.884833) (xy 280.641817 -308.842012) (xy 280.626966 -308.796305) (xy 280.619448 -308.748837)
			(xy 280.618946 -308.724808) (xy 280.619416 -308.700788) (xy 280.626925 -308.653339) (xy 280.64176 -308.607647)
			(xy 280.663557 -308.564836) (xy 280.691779 -308.52596) (xy 280.725731 -308.491974) (xy 280.76458 -308.463714)
			(xy 280.807369 -308.441876) (xy 280.853046 -308.426995) (xy 280.900488 -308.419439) (xy 280.924508 -308.418992)
			(xy 280.926794 -308.418992) (xy 280.941486 -308.419094) (xy 280.970746 -308.421768) (xy 280.985214 -308.424326)
			(xy 280.989024 -308.425088) (xy 280.992834 -308.425342) (xy 281.002436 -308.425553) (xy 281.020703 -308.419667)
			(xy 281.028394 -308.413912) (xy 281.087322 -308.365398) (xy 281.095659 -308.357832) (xy 281.10531 -308.337524)
			(xy 281.105864 -308.326282) (xy 281.105864 -304.78095) (xy 281.105431 -304.770885) (xy 281.0977 -304.752297)
			(xy 281.090878 -304.744882) (xy 280.87955 -304.533554) (xy 280.872438 -304.526188) (xy 280.853642 -304.518568)
			(xy 277.945596 -304.518568) (xy 277.91918 -304.537618) (xy 277.913846 -304.553366) (xy 277.90527 -304.577801)
			(xy 277.881602 -304.623859) (xy 277.851041 -304.665662) (xy 277.814335 -304.702188) (xy 277.772381 -304.732543)
			(xy 277.726208 -304.755983) (xy 277.676943 -304.771937) (xy 277.625794 -304.780012) (xy 277.57401 -304.780012)
			(xy 277.522861 -304.771937) (xy 277.473596 -304.755983) (xy 277.427423 -304.732543) (xy 277.385469 -304.702188)
			(xy 277.348763 -304.665662) (xy 277.318202 -304.623859) (xy 277.294534 -304.577801) (xy 277.285958 -304.553366)
			(xy 277.280624 -304.537618) (xy 277.254208 -304.518568) (xy 277.012146 -304.518568) (xy 277.005796 -304.518822)
			(xy 276.996954 -304.520281) (xy 276.981035 -304.528488) (xy 276.968916 -304.541674) (xy 276.965156 -304.54981)
			(xy 276.956774 -304.574587) (xy 276.933309 -304.621331) (xy 276.902784 -304.663802) (xy 276.865958 -304.700944)
			(xy 276.823749 -304.731831) (xy 276.777208 -304.755695) (xy 276.727492 -304.771942) (xy 276.67584 -304.780166)
			(xy 276.649688 -304.780696) (xy 275.699728 -304.780696) (xy 275.673817 -304.780187) (xy 275.62263 -304.772098)
			(xy 275.57333 -304.756127) (xy 275.527122 -304.732666) (xy 275.485137 -304.702289) (xy 275.4484 -304.665738)
			(xy 275.417811 -304.623907) (xy 275.394117 -304.577818) (xy 275.38553 -304.553366) (xy 275.380196 -304.537618)
			(xy 275.35378 -304.518568) (xy 275.095462 -304.518568) (xy 275.069046 -304.537618) (xy 275.063712 -304.553366)
			(xy 275.055141 -304.577802) (xy 275.031478 -304.623863) (xy 275.000919 -304.665667) (xy 274.964212 -304.702191)
			(xy 274.922256 -304.732541) (xy 274.876079 -304.755974) (xy 274.826811 -304.771914) (xy 274.775659 -304.779973)
			(xy 274.749768 -304.780442) (xy 274.749514 -304.780442) (xy 274.715224 -304.778664) (xy 274.703794 -304.777394)
			(xy 274.682204 -304.785014) (xy 274.610068 -304.85715) (xy 274.602448 -304.87874) (xy 274.603718 -304.89017)
			(xy 274.605496 -304.92446) (xy 274.605496 -304.924968) (xy 274.603972 -304.95748) (xy 274.603972 -304.957734)
			(xy 274.603431 -304.968303) (xy 274.609982 -304.988398) (xy 274.616672 -304.996596) (xy 274.667218 -305.052476)
			(xy 274.671888 -305.057348) (xy 274.683217 -305.064674) (xy 274.68957 -305.066954) (xy 274.69719 -305.06924)
			(xy 274.749768 -305.06924) (xy 274.775755 -305.069721) (xy 274.82709 -305.077847) (xy 274.876522 -305.093904)
			(xy 274.922833 -305.117496) (xy 274.964882 -305.148044) (xy 275.001636 -305.184793) (xy 275.032187 -305.22684)
			(xy 275.055784 -305.273149) (xy 275.071846 -305.322579) (xy 275.079977 -305.373913) (xy 275.079977 -305.425887)
			(xy 275.071846 -305.477221) (xy 275.055784 -305.526651) (xy 275.032187 -305.57296) (xy 275.001636 -305.615007)
			(xy 274.964882 -305.651756) (xy 274.922833 -305.682304) (xy 274.876522 -305.705896) (xy 274.82709 -305.721953)
			(xy 274.775755 -305.730079) (xy 274.749768 -305.730656) (xy 273.799808 -305.730656) (xy 273.773819 -305.730147)
			(xy 273.722481 -305.722018) (xy 273.673046 -305.705958) (xy 273.626732 -305.682363) (xy 273.584679 -305.651815)
			(xy 273.547922 -305.615064) (xy 273.517366 -305.573016) (xy 273.493763 -305.526706) (xy 273.477695 -305.477274)
			(xy 273.469557 -305.425937) (xy 273.4691 -305.399948) (xy 273.470624 -305.367182) (xy 273.47164 -305.35626)
			(xy 273.465036 -305.33594) (xy 273.407124 -305.27244) (xy 273.399758 -305.264312) (xy 273.3802 -305.255676)
			(xy 273.324828 -305.255676) (xy 273.298838 -305.255195) (xy 273.247498 -305.247067) (xy 273.198062 -305.231007)
			(xy 273.151747 -305.20741) (xy 273.109694 -305.176858) (xy 273.07294 -305.140102) (xy 273.042388 -305.098049)
			(xy 273.018792 -305.051734) (xy 273.002732 -305.002298) (xy 272.994605 -304.950958) (xy 272.99412 -304.924968)
			(xy 272.99412 -304.92446) (xy 272.995898 -304.89017) (xy 272.997168 -304.87874) (xy 272.989548 -304.85715)
			(xy 272.92554 -304.793142) (xy 272.91737 -304.785727) (xy 272.896692 -304.7781) (xy 272.885662 -304.77841)
			(xy 272.8849 -304.778664) (xy 272.848578 -304.780442) (xy 272.822771 -304.77985) (xy 272.771812 -304.771635)
			(xy 272.72275 -304.755597) (xy 272.676778 -304.732125) (xy 272.635015 -304.701791) (xy 272.598476 -304.665332)
			(xy 272.568051 -304.623635) (xy 272.54448 -304.577714) (xy 272.535904 -304.553366) (xy 272.53057 -304.537618)
			(xy 272.504154 -304.518568) (xy 272.245582 -304.518568) (xy 272.219166 -304.537618) (xy 272.213832 -304.553366)
			(xy 272.205261 -304.577803) (xy 272.181599 -304.623865) (xy 272.151041 -304.665671) (xy 272.114334 -304.702198)
			(xy 272.072378 -304.73255) (xy 272.026201 -304.755985) (xy 271.976932 -304.771929) (xy 271.92578 -304.77999)
			(xy 271.899888 -304.780442) (xy 271.899634 -304.780442) (xy 271.865344 -304.778664) (xy 271.853914 -304.777394)
			(xy 271.832324 -304.785014) (xy 271.760188 -304.85715) (xy 271.752568 -304.87874) (xy 271.753838 -304.89017)
			(xy 271.755616 -304.92446) (xy 271.755616 -304.932334) (xy 271.75587 -304.934366) (xy 271.754346 -304.95748)
			(xy 271.75333 -304.968402) (xy 271.759934 -304.988722) (xy 271.817592 -305.052476) (xy 271.821656 -305.05654)
			(xy 271.828813 -305.062315) (xy 271.845997 -305.068829) (xy 271.855184 -305.06924) (xy 271.899888 -305.06924)
			(xy 271.925898 -305.069723) (xy 271.977277 -305.077858) (xy 272.026751 -305.093932) (xy 272.073101 -305.117547)
			(xy 272.115186 -305.148122) (xy 272.15197 -305.184905) (xy 272.182547 -305.226989) (xy 272.206164 -305.273338)
			(xy 272.222239 -305.322811) (xy 272.230377 -305.37419) (xy 272.230377 -305.42621) (xy 272.222239 -305.477589)
			(xy 272.206164 -305.527062) (xy 272.182547 -305.573411) (xy 272.15197 -305.615495) (xy 272.115186 -305.652278)
			(xy 272.073101 -305.682853) (xy 272.026751 -305.706468) (xy 271.977277 -305.722542) (xy 271.925898 -305.730677)
			(xy 271.899888 -305.731164) (xy 270.949928 -305.731164) (xy 270.923939 -305.730683) (xy 270.872599 -305.722555)
			(xy 270.823164 -305.706495) (xy 270.77685 -305.682898) (xy 270.734798 -305.652345) (xy 270.698044 -305.61559)
			(xy 270.667494 -305.573537) (xy 270.643899 -305.527221) (xy 270.627841 -305.477785) (xy 270.619716 -305.426445)
			(xy 270.61922 -305.400456) (xy 270.61922 -305.400202) (xy 270.620744 -305.36769) (xy 270.62176 -305.356768)
			(xy 270.615156 -305.336448) (xy 270.557244 -305.272948) (xy 270.549878 -305.26482) (xy 270.53032 -305.256184)
			(xy 270.474948 -305.256184) (xy 270.450191 -305.255725) (xy 270.40123 -305.248355) (xy 270.353914 -305.23377)
			(xy 270.309299 -305.212298) (xy 270.268382 -305.184418) (xy 270.232077 -305.150751) (xy 270.201193 -305.112051)
			(xy 270.188436 -305.09083) (xy 270.174547 -305.065461) (xy 270.154816 -305.0111) (xy 270.144822 -304.954138)
			(xy 270.14424 -304.925222) (xy 270.146018 -304.890424) (xy 270.147288 -304.878994) (xy 270.139668 -304.857404)
			(xy 270.07566 -304.793396) (xy 270.071605 -304.789499) (xy 270.062118 -304.783464) (xy 270.056864 -304.781458)
			(xy 270.045942 -304.777648) (xy 270.034512 -304.778664) (xy 269.999714 -304.780696) (xy 269.049754 -304.780696)
			(xy 269.023842 -304.780189) (xy 268.972652 -304.772103) (xy 268.923349 -304.756135) (xy 268.877138 -304.732676)
			(xy 268.835149 -304.702299) (xy 268.798409 -304.665748) (xy 268.767817 -304.623916) (xy 268.74412 -304.577827)
			(xy 268.735556 -304.553366) (xy 268.730476 -304.537618) (xy 268.70406 -304.518568) (xy 268.461744 -304.518568)
			(xy 268.451194 -304.519159) (xy 268.431904 -304.52773) (xy 268.417647 -304.543295) (xy 268.413738 -304.553112)
			(xy 268.413738 -304.55362) (xy 268.405132 -304.578051) (xy 268.381409 -304.624094) (xy 268.350802 -304.66588)
			(xy 268.314059 -304.702386) (xy 268.272077 -304.732722) (xy 268.225882 -304.756148) (xy 268.176601 -304.77209)
			(xy 268.125438 -304.780159) (xy 268.073642 -304.780159) (xy 268.022479 -304.77209) (xy 267.973198 -304.756148)
			(xy 267.927003 -304.732722) (xy 267.885021 -304.702386) (xy 267.848278 -304.66588) (xy 267.817671 -304.624094)
			(xy 267.793948 -304.578051) (xy 267.785342 -304.55362) (xy 267.785342 -304.553112) (xy 267.781472 -304.54327)
			(xy 267.767231 -304.527669) (xy 267.747899 -304.519155) (xy 267.737336 -304.518568) (xy 263.312148 -304.518568)
			(xy 263.302081 -304.519) (xy 263.283488 -304.526724) (xy 263.27608 -304.533554) (xy 262.422386 -305.387248)
			(xy 262.41502 -305.39436) (xy 262.4074 -305.413156) (xy 262.4074 -306.375616) (xy 268.723106 -306.375616)
			(xy 268.723106 -306.3242) (xy 268.731149 -306.273418) (xy 268.747037 -306.224519) (xy 268.77038 -306.178707)
			(xy 268.800601 -306.137111) (xy 268.836957 -306.100755) (xy 268.878553 -306.070534) (xy 268.924365 -306.047191)
			(xy 268.973264 -306.031303) (xy 269.024046 -306.02326) (xy 269.075462 -306.02326) (xy 269.126244 -306.031303)
			(xy 269.175143 -306.047191) (xy 269.220955 -306.070534) (xy 269.262551 -306.100755) (xy 269.298907 -306.137111)
			(xy 269.329128 -306.178707) (xy 269.352471 -306.224519) (xy 269.368359 -306.273418) (xy 269.376402 -306.3242)
			(xy 269.376906 -306.349908) (xy 269.376402 -306.375616) (xy 269.673066 -306.375616) (xy 269.673066 -306.3242)
			(xy 269.681109 -306.273418) (xy 269.696997 -306.224519) (xy 269.72034 -306.178707) (xy 269.750561 -306.137111)
			(xy 269.786917 -306.100755) (xy 269.828513 -306.070534) (xy 269.874325 -306.047191) (xy 269.923224 -306.031303)
			(xy 269.974006 -306.02326) (xy 270.025422 -306.02326) (xy 270.076204 -306.031303) (xy 270.125103 -306.047191)
			(xy 270.170915 -306.070534) (xy 270.212511 -306.100755) (xy 270.248867 -306.137111) (xy 270.279088 -306.178707)
			(xy 270.302431 -306.224519) (xy 270.318319 -306.273418) (xy 270.326362 -306.3242) (xy 270.326866 -306.349908)
			(xy 270.326362 -306.375616) (xy 275.37308 -306.375616) (xy 275.37308 -306.3242) (xy 275.381123 -306.273418)
			(xy 275.397011 -306.224519) (xy 275.420354 -306.178707) (xy 275.450575 -306.137111) (xy 275.486931 -306.100755)
			(xy 275.528527 -306.070534) (xy 275.574339 -306.047191) (xy 275.623238 -306.031303) (xy 275.67402 -306.02326)
			(xy 275.725436 -306.02326) (xy 275.776218 -306.031303) (xy 275.825117 -306.047191) (xy 275.870929 -306.070534)
			(xy 275.912525 -306.100755) (xy 275.948881 -306.137111) (xy 275.979102 -306.178707) (xy 276.002445 -306.224519)
			(xy 276.018333 -306.273418) (xy 276.026376 -306.3242) (xy 276.02688 -306.349908) (xy 276.026376 -306.375616)
			(xy 276.32304 -306.375616) (xy 276.32304 -306.3242) (xy 276.331083 -306.273418) (xy 276.346971 -306.224519)
			(xy 276.370314 -306.178707) (xy 276.400535 -306.137111) (xy 276.436891 -306.100755) (xy 276.478487 -306.070534)
			(xy 276.524299 -306.047191) (xy 276.573198 -306.031303) (xy 276.62398 -306.02326) (xy 276.675396 -306.02326)
			(xy 276.726178 -306.031303) (xy 276.775077 -306.047191) (xy 276.820889 -306.070534) (xy 276.862485 -306.100755)
			(xy 276.898841 -306.137111) (xy 276.929062 -306.178707) (xy 276.952405 -306.224519) (xy 276.968293 -306.273418)
			(xy 276.976336 -306.3242) (xy 276.97684 -306.349908) (xy 276.976336 -306.375616) (xy 276.968293 -306.426398)
			(xy 276.952405 -306.475297) (xy 276.929062 -306.521109) (xy 276.898841 -306.562705) (xy 276.862485 -306.599061)
			(xy 276.820889 -306.629282) (xy 276.775077 -306.652625) (xy 276.726178 -306.668513) (xy 276.675396 -306.676556)
			(xy 276.62398 -306.676556) (xy 276.573198 -306.668513) (xy 276.524299 -306.652625) (xy 276.478487 -306.629282)
			(xy 276.436891 -306.599061) (xy 276.400535 -306.562705) (xy 276.370314 -306.521109) (xy 276.346971 -306.475297)
			(xy 276.331083 -306.426398) (xy 276.32304 -306.375616) (xy 276.026376 -306.375616) (xy 276.018333 -306.426398)
			(xy 276.002445 -306.475297) (xy 275.979102 -306.521109) (xy 275.948881 -306.562705) (xy 275.912525 -306.599061)
			(xy 275.870929 -306.629282) (xy 275.825117 -306.652625) (xy 275.776218 -306.668513) (xy 275.725436 -306.676556)
			(xy 275.67402 -306.676556) (xy 275.623238 -306.668513) (xy 275.574339 -306.652625) (xy 275.528527 -306.629282)
			(xy 275.486931 -306.599061) (xy 275.450575 -306.562705) (xy 275.420354 -306.521109) (xy 275.397011 -306.475297)
			(xy 275.381123 -306.426398) (xy 275.37308 -306.375616) (xy 270.326362 -306.375616) (xy 270.318319 -306.426398)
			(xy 270.302431 -306.475297) (xy 270.279088 -306.521109) (xy 270.248867 -306.562705) (xy 270.212511 -306.599061)
			(xy 270.170915 -306.629282) (xy 270.125103 -306.652625) (xy 270.076204 -306.668513) (xy 270.025422 -306.676556)
			(xy 269.974006 -306.676556) (xy 269.923224 -306.668513) (xy 269.874325 -306.652625) (xy 269.828513 -306.629282)
			(xy 269.786917 -306.599061) (xy 269.750561 -306.562705) (xy 269.72034 -306.521109) (xy 269.696997 -306.475297)
			(xy 269.681109 -306.426398) (xy 269.673066 -306.375616) (xy 269.376402 -306.375616) (xy 269.368359 -306.426398)
			(xy 269.352471 -306.475297) (xy 269.329128 -306.521109) (xy 269.298907 -306.562705) (xy 269.262551 -306.599061)
			(xy 269.220955 -306.629282) (xy 269.175143 -306.652625) (xy 269.126244 -306.668513) (xy 269.075462 -306.676556)
			(xy 269.024046 -306.676556) (xy 268.973264 -306.668513) (xy 268.924365 -306.652625) (xy 268.878553 -306.629282)
			(xy 268.836957 -306.599061) (xy 268.800601 -306.562705) (xy 268.77038 -306.521109) (xy 268.747037 -306.475297)
			(xy 268.731149 -306.426398) (xy 268.723106 -306.375616) (xy 262.4074 -306.375616) (xy 262.4074 -306.399438)
			(xy 262.407892 -306.410465) (xy 262.417051 -306.43052) (xy 262.433788 -306.444872) (xy 262.44423 -306.44846)
			(xy 262.470792 -306.456478) (xy 262.521461 -306.479083) (xy 262.568365 -306.508721) (xy 262.610535 -306.544779)
			(xy 262.647097 -306.58651) (xy 262.677298 -306.633054) (xy 262.700512 -306.683447) (xy 262.71626 -306.736649)
			(xy 262.724216 -306.791558) (xy 262.724216 -306.847042) (xy 262.71626 -306.901951) (xy 262.700512 -306.955153)
			(xy 262.677298 -307.005546) (xy 262.647097 -307.05209) (xy 262.610535 -307.093821) (xy 262.568365 -307.129879)
			(xy 262.521461 -307.159517) (xy 262.470792 -307.182122) (xy 262.44423 -307.19014) (xy 262.427974 -307.194712)
			(xy 262.4074 -307.22189) (xy 262.4074 -307.325576) (xy 270.62328 -307.325576) (xy 270.62328 -307.27416)
			(xy 270.631323 -307.223378) (xy 270.647211 -307.174479) (xy 270.670554 -307.128667) (xy 270.700775 -307.087071)
			(xy 270.737131 -307.050715) (xy 270.778727 -307.020494) (xy 270.824539 -306.997151) (xy 270.873438 -306.981263)
			(xy 270.92422 -306.97322) (xy 270.975636 -306.97322) (xy 271.026418 -306.981263) (xy 271.075317 -306.997151)
			(xy 271.121129 -307.020494) (xy 271.162725 -307.050715) (xy 271.199081 -307.087071) (xy 271.229302 -307.128667)
			(xy 271.252645 -307.174479) (xy 271.268533 -307.223378) (xy 271.276576 -307.27416) (xy 271.27708 -307.299868)
			(xy 271.276576 -307.325576) (xy 271.57324 -307.325576) (xy 271.57324 -307.27416) (xy 271.581283 -307.223378)
			(xy 271.597171 -307.174479) (xy 271.620514 -307.128667) (xy 271.650735 -307.087071) (xy 271.687091 -307.050715)
			(xy 271.728687 -307.020494) (xy 271.774499 -306.997151) (xy 271.823398 -306.981263) (xy 271.87418 -306.97322)
			(xy 271.925596 -306.97322) (xy 271.976378 -306.981263) (xy 272.025277 -306.997151) (xy 272.071089 -307.020494)
			(xy 272.112685 -307.050715) (xy 272.149041 -307.087071) (xy 272.179262 -307.128667) (xy 272.202605 -307.174479)
			(xy 272.218493 -307.223378) (xy 272.226536 -307.27416) (xy 272.22704 -307.299868) (xy 272.226536 -307.325576)
			(xy 273.47316 -307.325576) (xy 273.47316 -307.27416) (xy 273.481203 -307.223378) (xy 273.497091 -307.174479)
			(xy 273.520434 -307.128667) (xy 273.550655 -307.087071) (xy 273.587011 -307.050715) (xy 273.628607 -307.020494)
			(xy 273.674419 -306.997151) (xy 273.723318 -306.981263) (xy 273.7741 -306.97322) (xy 273.825516 -306.97322)
			(xy 273.876298 -306.981263) (xy 273.925197 -306.997151) (xy 273.971009 -307.020494) (xy 274.012605 -307.050715)
			(xy 274.048961 -307.087071) (xy 274.079182 -307.128667) (xy 274.102525 -307.174479) (xy 274.118413 -307.223378)
			(xy 274.126456 -307.27416) (xy 274.12696 -307.299868) (xy 274.126456 -307.325576) (xy 274.42312 -307.325576)
			(xy 274.42312 -307.27416) (xy 274.431163 -307.223378) (xy 274.447051 -307.174479) (xy 274.470394 -307.128667)
			(xy 274.500615 -307.087071) (xy 274.536971 -307.050715) (xy 274.578567 -307.020494) (xy 274.624379 -306.997151)
			(xy 274.673278 -306.981263) (xy 274.72406 -306.97322) (xy 274.775476 -306.97322) (xy 274.826258 -306.981263)
			(xy 274.875157 -306.997151) (xy 274.920969 -307.020494) (xy 274.962565 -307.050715) (xy 274.998921 -307.087071)
			(xy 275.029142 -307.128667) (xy 275.052485 -307.174479) (xy 275.068373 -307.223378) (xy 275.076416 -307.27416)
			(xy 275.07692 -307.299868) (xy 275.076416 -307.325576) (xy 275.068373 -307.376358) (xy 275.052485 -307.425257)
			(xy 275.029142 -307.471069) (xy 274.998921 -307.512665) (xy 274.962565 -307.549021) (xy 274.920969 -307.579242)
			(xy 274.875157 -307.602585) (xy 274.826258 -307.618473) (xy 274.775476 -307.626516) (xy 274.72406 -307.626516)
			(xy 274.673278 -307.618473) (xy 274.624379 -307.602585) (xy 274.578567 -307.579242) (xy 274.536971 -307.549021)
			(xy 274.500615 -307.512665) (xy 274.470394 -307.471069) (xy 274.447051 -307.425257) (xy 274.431163 -307.376358)
			(xy 274.42312 -307.325576) (xy 274.126456 -307.325576) (xy 274.118413 -307.376358) (xy 274.102525 -307.425257)
			(xy 274.079182 -307.471069) (xy 274.048961 -307.512665) (xy 274.012605 -307.549021) (xy 273.971009 -307.579242)
			(xy 273.925197 -307.602585) (xy 273.876298 -307.618473) (xy 273.825516 -307.626516) (xy 273.7741 -307.626516)
			(xy 273.723318 -307.618473) (xy 273.674419 -307.602585) (xy 273.628607 -307.579242) (xy 273.587011 -307.549021)
			(xy 273.550655 -307.512665) (xy 273.520434 -307.471069) (xy 273.497091 -307.425257) (xy 273.481203 -307.376358)
			(xy 273.47316 -307.325576) (xy 272.226536 -307.325576) (xy 272.218493 -307.376358) (xy 272.202605 -307.425257)
			(xy 272.179262 -307.471069) (xy 272.149041 -307.512665) (xy 272.112685 -307.549021) (xy 272.071089 -307.579242)
			(xy 272.025277 -307.602585) (xy 271.976378 -307.618473) (xy 271.925596 -307.626516) (xy 271.87418 -307.626516)
			(xy 271.823398 -307.618473) (xy 271.774499 -307.602585) (xy 271.728687 -307.579242) (xy 271.687091 -307.549021)
			(xy 271.650735 -307.512665) (xy 271.620514 -307.471069) (xy 271.597171 -307.425257) (xy 271.581283 -307.376358)
			(xy 271.57324 -307.325576) (xy 271.276576 -307.325576) (xy 271.268533 -307.376358) (xy 271.252645 -307.425257)
			(xy 271.229302 -307.471069) (xy 271.199081 -307.512665) (xy 271.162725 -307.549021) (xy 271.121129 -307.579242)
			(xy 271.075317 -307.602585) (xy 271.026418 -307.618473) (xy 270.975636 -307.626516) (xy 270.92422 -307.626516)
			(xy 270.873438 -307.618473) (xy 270.824539 -307.602585) (xy 270.778727 -307.579242) (xy 270.737131 -307.549021)
			(xy 270.700775 -307.512665) (xy 270.670554 -307.471069) (xy 270.647211 -307.425257) (xy 270.631323 -307.376358)
			(xy 270.62328 -307.325576) (xy 262.4074 -307.325576) (xy 262.4074 -308.275536) (xy 268.723106 -308.275536)
			(xy 268.723106 -308.22412) (xy 268.731149 -308.173338) (xy 268.747037 -308.124439) (xy 268.77038 -308.078627)
			(xy 268.800601 -308.037031) (xy 268.836957 -308.000675) (xy 268.878553 -307.970454) (xy 268.924365 -307.947111)
			(xy 268.973264 -307.931223) (xy 269.024046 -307.92318) (xy 269.075462 -307.92318) (xy 269.126244 -307.931223)
			(xy 269.175143 -307.947111) (xy 269.220955 -307.970454) (xy 269.262551 -308.000675) (xy 269.298907 -308.037031)
			(xy 269.329128 -308.078627) (xy 269.352471 -308.124439) (xy 269.368359 -308.173338) (xy 269.376402 -308.22412)
			(xy 269.376906 -308.249828) (xy 269.376402 -308.275536) (xy 269.673066 -308.275536) (xy 269.673066 -308.22412)
			(xy 269.681109 -308.173338) (xy 269.696997 -308.124439) (xy 269.72034 -308.078627) (xy 269.750561 -308.037031)
			(xy 269.786917 -308.000675) (xy 269.828513 -307.970454) (xy 269.874325 -307.947111) (xy 269.923224 -307.931223)
			(xy 269.974006 -307.92318) (xy 270.025422 -307.92318) (xy 270.076204 -307.931223) (xy 270.125103 -307.947111)
			(xy 270.170915 -307.970454) (xy 270.212511 -308.000675) (xy 270.248867 -308.037031) (xy 270.279088 -308.078627)
			(xy 270.302431 -308.124439) (xy 270.318319 -308.173338) (xy 270.326362 -308.22412) (xy 270.326866 -308.249828)
			(xy 270.326362 -308.275536) (xy 275.37308 -308.275536) (xy 275.37308 -308.22412) (xy 275.381123 -308.173338)
			(xy 275.397011 -308.124439) (xy 275.420354 -308.078627) (xy 275.450575 -308.037031) (xy 275.486931 -308.000675)
			(xy 275.528527 -307.970454) (xy 275.574339 -307.947111) (xy 275.623238 -307.931223) (xy 275.67402 -307.92318)
			(xy 275.725436 -307.92318) (xy 275.776218 -307.931223) (xy 275.825117 -307.947111) (xy 275.870929 -307.970454)
			(xy 275.912525 -308.000675) (xy 275.948881 -308.037031) (xy 275.979102 -308.078627) (xy 276.002445 -308.124439)
			(xy 276.018333 -308.173338) (xy 276.026376 -308.22412) (xy 276.02688 -308.249828) (xy 276.026376 -308.275536)
			(xy 276.32304 -308.275536) (xy 276.32304 -308.22412) (xy 276.331083 -308.173338) (xy 276.346971 -308.124439)
			(xy 276.370314 -308.078627) (xy 276.400535 -308.037031) (xy 276.436891 -308.000675) (xy 276.478487 -307.970454)
			(xy 276.524299 -307.947111) (xy 276.573198 -307.931223) (xy 276.62398 -307.92318) (xy 276.675396 -307.92318)
			(xy 276.726178 -307.931223) (xy 276.775077 -307.947111) (xy 276.820889 -307.970454) (xy 276.862485 -308.000675)
			(xy 276.898841 -308.037031) (xy 276.929062 -308.078627) (xy 276.952405 -308.124439) (xy 276.968293 -308.173338)
			(xy 276.976336 -308.22412) (xy 276.97684 -308.249828) (xy 276.976336 -308.275536) (xy 276.968293 -308.326318)
			(xy 276.952405 -308.375217) (xy 276.929062 -308.421029) (xy 276.898841 -308.462625) (xy 276.862485 -308.498981)
			(xy 276.820889 -308.529202) (xy 276.775077 -308.552545) (xy 276.726178 -308.568433) (xy 276.675396 -308.576476)
			(xy 276.62398 -308.576476) (xy 276.573198 -308.568433) (xy 276.524299 -308.552545) (xy 276.478487 -308.529202)
			(xy 276.436891 -308.498981) (xy 276.400535 -308.462625) (xy 276.370314 -308.421029) (xy 276.346971 -308.375217)
			(xy 276.331083 -308.326318) (xy 276.32304 -308.275536) (xy 276.026376 -308.275536) (xy 276.018333 -308.326318)
			(xy 276.002445 -308.375217) (xy 275.979102 -308.421029) (xy 275.948881 -308.462625) (xy 275.912525 -308.498981)
			(xy 275.870929 -308.529202) (xy 275.825117 -308.552545) (xy 275.776218 -308.568433) (xy 275.725436 -308.576476)
			(xy 275.67402 -308.576476) (xy 275.623238 -308.568433) (xy 275.574339 -308.552545) (xy 275.528527 -308.529202)
			(xy 275.486931 -308.498981) (xy 275.450575 -308.462625) (xy 275.420354 -308.421029) (xy 275.397011 -308.375217)
			(xy 275.381123 -308.326318) (xy 275.37308 -308.275536) (xy 270.326362 -308.275536) (xy 270.318319 -308.326318)
			(xy 270.302431 -308.375217) (xy 270.279088 -308.421029) (xy 270.248867 -308.462625) (xy 270.212511 -308.498981)
			(xy 270.170915 -308.529202) (xy 270.125103 -308.552545) (xy 270.076204 -308.568433) (xy 270.025422 -308.576476)
			(xy 269.974006 -308.576476) (xy 269.923224 -308.568433) (xy 269.874325 -308.552545) (xy 269.828513 -308.529202)
			(xy 269.786917 -308.498981) (xy 269.750561 -308.462625) (xy 269.72034 -308.421029) (xy 269.696997 -308.375217)
			(xy 269.681109 -308.326318) (xy 269.673066 -308.275536) (xy 269.376402 -308.275536) (xy 269.368359 -308.326318)
			(xy 269.352471 -308.375217) (xy 269.329128 -308.421029) (xy 269.298907 -308.462625) (xy 269.262551 -308.498981)
			(xy 269.220955 -308.529202) (xy 269.175143 -308.552545) (xy 269.126244 -308.568433) (xy 269.075462 -308.576476)
			(xy 269.024046 -308.576476) (xy 268.973264 -308.568433) (xy 268.924365 -308.552545) (xy 268.878553 -308.529202)
			(xy 268.836957 -308.498981) (xy 268.800601 -308.462625) (xy 268.77038 -308.421029) (xy 268.747037 -308.375217)
			(xy 268.731149 -308.326318) (xy 268.723106 -308.275536) (xy 262.4074 -308.275536) (xy 262.4074 -308.724808)
			(xy 278.719038 -308.724808) (xy 278.722998 -308.675754) (xy 278.734775 -308.62797) (xy 278.754066 -308.582694)
			(xy 278.780369 -308.541098) (xy 278.813004 -308.504261) (xy 278.851125 -308.473136) (xy 278.893746 -308.448529)
			(xy 278.939762 -308.431077) (xy 278.987981 -308.421233) (xy 279.037156 -308.419252) (xy 279.086011 -308.425184)
			(xy 279.133282 -308.438876) (xy 279.177744 -308.459974) (xy 279.218247 -308.48793) (xy 279.25374 -308.522022)
			(xy 279.283305 -308.561366) (xy 279.306176 -308.604943) (xy 279.32176 -308.651624) (xy 279.329655 -308.700201)
			(xy 279.33015 -308.724808) (xy 279.668998 -308.724808) (xy 279.672958 -308.675754) (xy 279.684735 -308.62797)
			(xy 279.704026 -308.582694) (xy 279.730329 -308.541098) (xy 279.762964 -308.504261) (xy 279.801085 -308.473136)
			(xy 279.843706 -308.448529) (xy 279.889722 -308.431077) (xy 279.937941 -308.421233) (xy 279.987116 -308.419252)
			(xy 280.035971 -308.425184) (xy 280.083242 -308.438876) (xy 280.127704 -308.459974) (xy 280.168207 -308.48793)
			(xy 280.2037 -308.522022) (xy 280.233265 -308.561366) (xy 280.256136 -308.604943) (xy 280.27172 -308.651624)
			(xy 280.279615 -308.700201) (xy 280.28011 -308.724808) (xy 280.279615 -308.749415) (xy 280.27172 -308.797992)
			(xy 280.256136 -308.844673) (xy 280.233265 -308.88825) (xy 280.2037 -308.927594) (xy 280.168207 -308.961686)
			(xy 280.127704 -308.989642) (xy 280.083242 -309.01074) (xy 280.035971 -309.024432) (xy 279.987116 -309.030364)
			(xy 279.937941 -309.028383) (xy 279.889722 -309.018539) (xy 279.843706 -309.001087) (xy 279.801085 -308.97648)
			(xy 279.762964 -308.945355) (xy 279.730329 -308.908518) (xy 279.704026 -308.866922) (xy 279.684735 -308.821646)
			(xy 279.672958 -308.773862) (xy 279.668998 -308.724808) (xy 279.33015 -308.724808) (xy 279.329655 -308.749415)
			(xy 279.32176 -308.797992) (xy 279.306176 -308.844673) (xy 279.283305 -308.88825) (xy 279.25374 -308.927594)
			(xy 279.218247 -308.961686) (xy 279.177744 -308.989642) (xy 279.133282 -309.01074) (xy 279.086011 -309.024432)
			(xy 279.037156 -309.030364) (xy 278.987981 -309.028383) (xy 278.939762 -309.018539) (xy 278.893746 -309.001087)
			(xy 278.851125 -308.97648) (xy 278.813004 -308.945355) (xy 278.780369 -308.908518) (xy 278.754066 -308.866922)
			(xy 278.734775 -308.821646) (xy 278.722998 -308.773862) (xy 278.719038 -308.724808) (xy 262.4074 -308.724808)
			(xy 262.4074 -309.225496) (xy 270.62328 -309.225496) (xy 270.62328 -309.17408) (xy 270.631323 -309.123298)
			(xy 270.647211 -309.074399) (xy 270.670554 -309.028587) (xy 270.700775 -308.986991) (xy 270.737131 -308.950635)
			(xy 270.778727 -308.920414) (xy 270.824539 -308.897071) (xy 270.873438 -308.881183) (xy 270.92422 -308.87314)
			(xy 270.975636 -308.87314) (xy 271.026418 -308.881183) (xy 271.075317 -308.897071) (xy 271.121129 -308.920414)
			(xy 271.162725 -308.950635) (xy 271.199081 -308.986991) (xy 271.229302 -309.028587) (xy 271.252645 -309.074399)
			(xy 271.268533 -309.123298) (xy 271.276576 -309.17408) (xy 271.27708 -309.199788) (xy 271.276576 -309.225496)
			(xy 271.57324 -309.225496) (xy 271.57324 -309.17408) (xy 271.581283 -309.123298) (xy 271.597171 -309.074399)
			(xy 271.620514 -309.028587) (xy 271.650735 -308.986991) (xy 271.687091 -308.950635) (xy 271.728687 -308.920414)
			(xy 271.774499 -308.897071) (xy 271.823398 -308.881183) (xy 271.87418 -308.87314) (xy 271.925596 -308.87314)
			(xy 271.976378 -308.881183) (xy 272.025277 -308.897071) (xy 272.071089 -308.920414) (xy 272.112685 -308.950635)
			(xy 272.149041 -308.986991) (xy 272.179262 -309.028587) (xy 272.202605 -309.074399) (xy 272.218493 -309.123298)
			(xy 272.226536 -309.17408) (xy 272.22704 -309.199788) (xy 272.226536 -309.225496) (xy 272.218493 -309.276278)
			(xy 272.202605 -309.325177) (xy 272.179262 -309.370989) (xy 272.149041 -309.412585) (xy 272.112685 -309.448941)
			(xy 272.071089 -309.479162) (xy 272.025277 -309.502505) (xy 271.976378 -309.518393) (xy 271.925596 -309.526436)
			(xy 271.87418 -309.526436) (xy 271.823398 -309.518393) (xy 271.774499 -309.502505) (xy 271.728687 -309.479162)
			(xy 271.687091 -309.448941) (xy 271.650735 -309.412585) (xy 271.620514 -309.370989) (xy 271.597171 -309.325177)
			(xy 271.581283 -309.276278) (xy 271.57324 -309.225496) (xy 271.276576 -309.225496) (xy 271.268533 -309.276278)
			(xy 271.252645 -309.325177) (xy 271.229302 -309.370989) (xy 271.199081 -309.412585) (xy 271.162725 -309.448941)
			(xy 271.121129 -309.479162) (xy 271.075317 -309.502505) (xy 271.026418 -309.518393) (xy 270.975636 -309.526436)
			(xy 270.92422 -309.526436) (xy 270.873438 -309.518393) (xy 270.824539 -309.502505) (xy 270.778727 -309.479162)
			(xy 270.737131 -309.448941) (xy 270.700775 -309.412585) (xy 270.670554 -309.370989) (xy 270.647211 -309.325177)
			(xy 270.631323 -309.276278) (xy 270.62328 -309.225496) (xy 262.4074 -309.225496) (xy 262.4074 -310.237378)
			(xy 266.300712 -310.237378) (xy 266.301198 -310.210127) (xy 266.308954 -310.156179) (xy 266.324309 -310.103884)
			(xy 266.346951 -310.054307) (xy 266.376417 -310.008457) (xy 266.412108 -309.967266) (xy 266.453299 -309.931575)
			(xy 266.499149 -309.902109) (xy 266.548726 -309.879467) (xy 266.601021 -309.864112) (xy 266.654969 -309.856356)
			(xy 266.709471 -309.856356) (xy 266.763419 -309.864112) (xy 266.815714 -309.879467) (xy 266.865291 -309.902109)
			(xy 266.911141 -309.931575) (xy 266.952332 -309.967266) (xy 266.988023 -310.008457) (xy 267.017489 -310.054307)
			(xy 267.040131 -310.103884) (xy 267.055486 -310.156179) (xy 267.058257 -310.175456) (xy 268.723106 -310.175456)
			(xy 268.723106 -310.12404) (xy 268.731149 -310.073258) (xy 268.747037 -310.024359) (xy 268.77038 -309.978547)
			(xy 268.800601 -309.936951) (xy 268.836957 -309.900595) (xy 268.878553 -309.870374) (xy 268.924365 -309.847031)
			(xy 268.973264 -309.831143) (xy 269.024046 -309.8231) (xy 269.075462 -309.8231) (xy 269.126244 -309.831143)
			(xy 269.175143 -309.847031) (xy 269.220955 -309.870374) (xy 269.262551 -309.900595) (xy 269.298907 -309.936951)
			(xy 269.329128 -309.978547) (xy 269.352471 -310.024359) (xy 269.368359 -310.073258) (xy 269.376402 -310.12404)
			(xy 269.376906 -310.149748) (xy 269.376402 -310.175456) (xy 269.673066 -310.175456) (xy 269.673066 -310.12404)
			(xy 269.681109 -310.073258) (xy 269.696997 -310.024359) (xy 269.72034 -309.978547) (xy 269.750561 -309.936951)
			(xy 269.786917 -309.900595) (xy 269.828513 -309.870374) (xy 269.874325 -309.847031) (xy 269.923224 -309.831143)
			(xy 269.974006 -309.8231) (xy 270.025422 -309.8231) (xy 270.076204 -309.831143) (xy 270.125103 -309.847031)
			(xy 270.170915 -309.870374) (xy 270.212511 -309.900595) (xy 270.248867 -309.936951) (xy 270.279088 -309.978547)
			(xy 270.302431 -310.024359) (xy 270.318319 -310.073258) (xy 270.326362 -310.12404) (xy 270.326866 -310.149748)
			(xy 270.326362 -310.175456) (xy 270.318319 -310.226238) (xy 270.302431 -310.275137) (xy 270.279088 -310.320949)
			(xy 270.248867 -310.362545) (xy 270.212511 -310.398901) (xy 270.170915 -310.429122) (xy 270.125103 -310.452465)
			(xy 270.076204 -310.468353) (xy 270.025422 -310.476396) (xy 269.974006 -310.476396) (xy 269.923224 -310.468353)
			(xy 269.874325 -310.452465) (xy 269.828513 -310.429122) (xy 269.786917 -310.398901) (xy 269.750561 -310.362545)
			(xy 269.72034 -310.320949) (xy 269.696997 -310.275137) (xy 269.681109 -310.226238) (xy 269.673066 -310.175456)
			(xy 269.376402 -310.175456) (xy 269.368359 -310.226238) (xy 269.352471 -310.275137) (xy 269.329128 -310.320949)
			(xy 269.298907 -310.362545) (xy 269.262551 -310.398901) (xy 269.220955 -310.429122) (xy 269.175143 -310.452465)
			(xy 269.126244 -310.468353) (xy 269.075462 -310.476396) (xy 269.024046 -310.476396) (xy 268.973264 -310.468353)
			(xy 268.924365 -310.452465) (xy 268.878553 -310.429122) (xy 268.836957 -310.398901) (xy 268.800601 -310.362545)
			(xy 268.77038 -310.320949) (xy 268.747037 -310.275137) (xy 268.731149 -310.226238) (xy 268.723106 -310.175456)
			(xy 267.058257 -310.175456) (xy 267.063242 -310.210127) (xy 267.063728 -310.237378) (xy 267.063203 -310.266152)
			(xy 267.054551 -310.323046) (xy 267.037455 -310.377996) (xy 267.012301 -310.429756) (xy 266.979662 -310.477153)
			(xy 266.96035 -310.49849) (xy 266.951009 -310.509061) (xy 266.93809 -310.534129) (xy 266.932524 -310.561776)
			(xy 266.934738 -310.58989) (xy 266.944561 -310.616326) (xy 266.961243 -310.639064) (xy 266.983512 -310.656368)
			(xy 266.996418 -310.662066) (xy 267.022494 -310.673139) (xy 267.071314 -310.701876) (xy 267.115349 -310.737516)
			(xy 267.153631 -310.779275) (xy 267.185318 -310.826234) (xy 267.209715 -310.877362) (xy 267.226283 -310.931535)
			(xy 267.234661 -310.987563) (xy 267.235178 -311.015888) (xy 267.234692 -311.043139) (xy 267.226936 -311.097087)
			(xy 267.218543 -311.12567) (xy 271.57324 -311.12567) (xy 271.57324 -311.074254) (xy 271.581283 -311.023472)
			(xy 271.597171 -310.974573) (xy 271.620514 -310.928761) (xy 271.650735 -310.887165) (xy 271.687091 -310.850809)
			(xy 271.728687 -310.820588) (xy 271.774499 -310.797245) (xy 271.823398 -310.781357) (xy 271.87418 -310.773314)
			(xy 271.925596 -310.773314) (xy 271.976378 -310.781357) (xy 272.025277 -310.797245) (xy 272.071089 -310.820588)
			(xy 272.112685 -310.850809) (xy 272.149041 -310.887165) (xy 272.179262 -310.928761) (xy 272.202605 -310.974573)
			(xy 272.218493 -311.023472) (xy 272.226536 -311.074254) (xy 272.22704 -311.099962) (xy 272.226536 -311.12567)
			(xy 272.218493 -311.176452) (xy 272.202605 -311.225351) (xy 272.179262 -311.271163) (xy 272.149041 -311.312759)
			(xy 272.112685 -311.349115) (xy 272.071089 -311.379336) (xy 272.025277 -311.402679) (xy 271.976378 -311.418567)
			(xy 271.925596 -311.42661) (xy 271.87418 -311.42661) (xy 271.823398 -311.418567) (xy 271.774499 -311.402679)
			(xy 271.728687 -311.379336) (xy 271.687091 -311.349115) (xy 271.650735 -311.312759) (xy 271.620514 -311.271163)
			(xy 271.597171 -311.225351) (xy 271.581283 -311.176452) (xy 271.57324 -311.12567) (xy 267.218543 -311.12567)
			(xy 267.211581 -311.149382) (xy 267.188939 -311.198959) (xy 267.159473 -311.244809) (xy 267.123782 -311.286)
			(xy 267.082591 -311.321691) (xy 267.036741 -311.351157) (xy 266.987164 -311.373799) (xy 266.934869 -311.389154)
			(xy 266.880921 -311.39691) (xy 266.826419 -311.39691) (xy 266.772471 -311.389154) (xy 266.720176 -311.373799)
			(xy 266.670599 -311.351157) (xy 266.624749 -311.321691) (xy 266.583558 -311.286) (xy 266.547867 -311.244809)
			(xy 266.518401 -311.198959) (xy 266.495759 -311.149382) (xy 266.480404 -311.097087) (xy 266.472648 -311.043139)
			(xy 266.472162 -311.015888) (xy 266.472669 -310.987113) (xy 266.481326 -310.930219) (xy 266.498427 -310.875269)
			(xy 266.523584 -310.823509) (xy 266.556227 -310.776113) (xy 266.57554 -310.754776) (xy 266.584808 -310.744144)
			(xy 266.597733 -310.719093) (xy 266.603308 -310.691461) (xy 266.601106 -310.663358) (xy 266.591296 -310.636931)
			(xy 266.574626 -310.614199) (xy 266.552371 -310.596898) (xy 266.539472 -310.5912) (xy 266.513381 -310.58016)
			(xy 266.46456 -310.551418) (xy 266.420525 -310.515774) (xy 266.382244 -310.47401) (xy 266.350559 -310.427046)
			(xy 266.326165 -310.375913) (xy 266.3096 -310.321736) (xy 266.301227 -310.265705) (xy 266.300712 -310.237378)
			(xy 262.4074 -310.237378) (xy 262.4074 -311.7342) (xy 264.689334 -311.7342) (xy 264.693405 -311.678578)
			(xy 264.705531 -311.624141) (xy 264.725454 -311.57205) (xy 264.75275 -311.523415) (xy 264.786836 -311.479272)
			(xy 264.826985 -311.440563) (xy 264.872343 -311.408112) (xy 264.921943 -311.382611) (xy 264.974727 -311.364604)
			(xy 265.02957 -311.354474) (xy 265.085304 -311.352437) (xy 265.140741 -311.358537) (xy 265.194698 -311.372643)
			(xy 265.246027 -311.394455) (xy 265.293633 -311.423509) (xy 265.336501 -311.459184) (xy 265.373718 -311.500721)
			(xy 265.404491 -311.547234) (xy 265.428163 -311.597731) (xy 265.444231 -311.651138) (xy 265.452351 -311.706314)
			(xy 265.45286 -311.7342) (xy 265.452351 -311.762086) (xy 265.444231 -311.817262) (xy 265.428163 -311.870669)
			(xy 265.404491 -311.921166) (xy 265.373718 -311.967679) (xy 265.336501 -312.009216) (xy 265.293633 -312.044891)
			(xy 265.246027 -312.073945) (xy 265.194698 -312.095757) (xy 265.140741 -312.109863) (xy 265.085304 -312.115963)
			(xy 265.02957 -312.113926) (xy 264.974727 -312.103796) (xy 264.921943 -312.085789) (xy 264.872343 -312.060288)
			(xy 264.826985 -312.027837) (xy 264.786836 -311.989128) (xy 264.75275 -311.944985) (xy 264.725454 -311.89635)
			(xy 264.705531 -311.844259) (xy 264.693405 -311.789822) (xy 264.689334 -311.7342) (xy 262.4074 -311.7342)
			(xy 262.4074 -312.523378) (xy 263.931906 -312.523378) (xy 263.935977 -312.467756) (xy 263.948103 -312.413319)
			(xy 263.968026 -312.361228) (xy 263.995322 -312.312593) (xy 264.029408 -312.26845) (xy 264.069557 -312.229741)
			(xy 264.114915 -312.19729) (xy 264.164515 -312.171789) (xy 264.217299 -312.153782) (xy 264.272142 -312.143652)
			(xy 264.327876 -312.141615) (xy 264.383313 -312.147715) (xy 264.43727 -312.161821) (xy 264.488599 -312.183633)
			(xy 264.536205 -312.212687) (xy 264.579073 -312.248362) (xy 264.596765 -312.268108) (xy 266.259562 -312.268108)
			(xy 266.263633 -312.212486) (xy 266.275759 -312.158049) (xy 266.295682 -312.105958) (xy 266.322978 -312.057323)
			(xy 266.357064 -312.01318) (xy 266.397213 -311.974471) (xy 266.442571 -311.94202) (xy 266.492171 -311.916519)
			(xy 266.544955 -311.898512) (xy 266.599798 -311.888382) (xy 266.655532 -311.886345) (xy 266.710969 -311.892445)
			(xy 266.764926 -311.906551) (xy 266.816255 -311.928363) (xy 266.863861 -311.957417) (xy 266.906729 -311.993092)
			(xy 266.943946 -312.034629) (xy 266.971072 -312.07563) (xy 268.723106 -312.07563) (xy 268.723106 -312.024214)
			(xy 268.731149 -311.973432) (xy 268.747037 -311.924533) (xy 268.77038 -311.878721) (xy 268.800601 -311.837125)
			(xy 268.836957 -311.800769) (xy 268.878553 -311.770548) (xy 268.924365 -311.747205) (xy 268.973264 -311.731317)
			(xy 269.024046 -311.723274) (xy 269.075462 -311.723274) (xy 269.126244 -311.731317) (xy 269.175143 -311.747205)
			(xy 269.220955 -311.770548) (xy 269.262551 -311.800769) (xy 269.298907 -311.837125) (xy 269.329128 -311.878721)
			(xy 269.352471 -311.924533) (xy 269.368359 -311.973432) (xy 269.376402 -312.024214) (xy 269.376906 -312.049922)
			(xy 269.376402 -312.07563) (xy 269.673066 -312.07563) (xy 269.673066 -312.024214) (xy 269.681109 -311.973432)
			(xy 269.696997 -311.924533) (xy 269.72034 -311.878721) (xy 269.750561 -311.837125) (xy 269.786917 -311.800769)
			(xy 269.828513 -311.770548) (xy 269.874325 -311.747205) (xy 269.923224 -311.731317) (xy 269.974006 -311.723274)
			(xy 270.025422 -311.723274) (xy 270.076204 -311.731317) (xy 270.125103 -311.747205) (xy 270.170915 -311.770548)
			(xy 270.212511 -311.800769) (xy 270.248867 -311.837125) (xy 270.279088 -311.878721) (xy 270.302431 -311.924533)
			(xy 270.318319 -311.973432) (xy 270.326362 -312.024214) (xy 270.326866 -312.049922) (xy 270.326362 -312.07563)
			(xy 271.57324 -312.07563) (xy 271.57324 -312.024214) (xy 271.581283 -311.973432) (xy 271.597171 -311.924533)
			(xy 271.620514 -311.878721) (xy 271.650735 -311.837125) (xy 271.687091 -311.800769) (xy 271.728687 -311.770548)
			(xy 271.774499 -311.747205) (xy 271.823398 -311.731317) (xy 271.87418 -311.723274) (xy 271.925596 -311.723274)
			(xy 271.976378 -311.731317) (xy 272.025277 -311.747205) (xy 272.071089 -311.770548) (xy 272.112685 -311.800769)
			(xy 272.149041 -311.837125) (xy 272.179262 -311.878721) (xy 272.202605 -311.924533) (xy 272.218493 -311.973432)
			(xy 272.226536 -312.024214) (xy 272.22704 -312.049922) (xy 272.226536 -312.07563) (xy 272.218493 -312.126412)
			(xy 272.202605 -312.175311) (xy 272.179262 -312.221123) (xy 272.149041 -312.262719) (xy 272.112685 -312.299075)
			(xy 272.071089 -312.329296) (xy 272.025277 -312.352639) (xy 271.976378 -312.368527) (xy 271.925596 -312.37657)
			(xy 271.87418 -312.37657) (xy 271.823398 -312.368527) (xy 271.774499 -312.352639) (xy 271.728687 -312.329296)
			(xy 271.687091 -312.299075) (xy 271.650735 -312.262719) (xy 271.620514 -312.221123) (xy 271.597171 -312.175311)
			(xy 271.581283 -312.126412) (xy 271.57324 -312.07563) (xy 270.326362 -312.07563) (xy 270.318319 -312.126412)
			(xy 270.302431 -312.175311) (xy 270.279088 -312.221123) (xy 270.248867 -312.262719) (xy 270.212511 -312.299075)
			(xy 270.170915 -312.329296) (xy 270.125103 -312.352639) (xy 270.076204 -312.368527) (xy 270.025422 -312.37657)
			(xy 269.974006 -312.37657) (xy 269.923224 -312.368527) (xy 269.874325 -312.352639) (xy 269.828513 -312.329296)
			(xy 269.786917 -312.299075) (xy 269.750561 -312.262719) (xy 269.72034 -312.221123) (xy 269.696997 -312.175311)
			(xy 269.681109 -312.126412) (xy 269.673066 -312.07563) (xy 269.376402 -312.07563) (xy 269.368359 -312.126412)
			(xy 269.352471 -312.175311) (xy 269.329128 -312.221123) (xy 269.298907 -312.262719) (xy 269.262551 -312.299075)
			(xy 269.220955 -312.329296) (xy 269.175143 -312.352639) (xy 269.126244 -312.368527) (xy 269.075462 -312.37657)
			(xy 269.024046 -312.37657) (xy 268.973264 -312.368527) (xy 268.924365 -312.352639) (xy 268.878553 -312.329296)
			(xy 268.836957 -312.299075) (xy 268.800601 -312.262719) (xy 268.77038 -312.221123) (xy 268.747037 -312.175311)
			(xy 268.731149 -312.126412) (xy 268.723106 -312.07563) (xy 266.971072 -312.07563) (xy 266.974719 -312.081142)
			(xy 266.998391 -312.131639) (xy 267.014459 -312.185046) (xy 267.022579 -312.240222) (xy 267.023088 -312.268108)
			(xy 267.022579 -312.295994) (xy 267.014459 -312.35117) (xy 266.998391 -312.404577) (xy 266.974719 -312.455074)
			(xy 266.943946 -312.501587) (xy 266.906729 -312.543124) (xy 266.863861 -312.578799) (xy 266.816255 -312.607853)
			(xy 266.764926 -312.629665) (xy 266.710969 -312.643771) (xy 266.655532 -312.649871) (xy 266.599798 -312.647834)
			(xy 266.544955 -312.637704) (xy 266.492171 -312.619697) (xy 266.442571 -312.594196) (xy 266.397213 -312.561745)
			(xy 266.357064 -312.523036) (xy 266.322978 -312.478893) (xy 266.295682 -312.430258) (xy 266.275759 -312.378167)
			(xy 266.263633 -312.32373) (xy 266.259562 -312.268108) (xy 264.596765 -312.268108) (xy 264.61629 -312.289899)
			(xy 264.647063 -312.336412) (xy 264.670735 -312.386909) (xy 264.686803 -312.440316) (xy 264.694923 -312.495492)
			(xy 264.695432 -312.523378) (xy 264.694923 -312.551264) (xy 264.686803 -312.60644) (xy 264.670735 -312.659847)
			(xy 264.647063 -312.710344) (xy 264.61629 -312.756857) (xy 264.579073 -312.798394) (xy 264.536205 -312.834069)
			(xy 264.488599 -312.863123) (xy 264.43727 -312.884935) (xy 264.383313 -312.899041) (xy 264.327876 -312.905141)
			(xy 264.272142 -312.903104) (xy 264.217299 -312.892974) (xy 264.164515 -312.874967) (xy 264.114915 -312.849466)
			(xy 264.069557 -312.817015) (xy 264.029408 -312.778306) (xy 263.995322 -312.734163) (xy 263.968026 -312.685528)
			(xy 263.948103 -312.633437) (xy 263.935977 -312.579) (xy 263.931906 -312.523378) (xy 262.4074 -312.523378)
			(xy 262.4074 -313.02559) (xy 270.62328 -313.02559) (xy 270.62328 -312.974174) (xy 270.631323 -312.923392)
			(xy 270.647211 -312.874493) (xy 270.670554 -312.828681) (xy 270.700775 -312.787085) (xy 270.737131 -312.750729)
			(xy 270.778727 -312.720508) (xy 270.824539 -312.697165) (xy 270.873438 -312.681277) (xy 270.92422 -312.673234)
			(xy 270.975636 -312.673234) (xy 271.026418 -312.681277) (xy 271.075317 -312.697165) (xy 271.121129 -312.720508)
			(xy 271.162725 -312.750729) (xy 271.199081 -312.787085) (xy 271.229302 -312.828681) (xy 271.252645 -312.874493)
			(xy 271.268533 -312.923392) (xy 271.276576 -312.974174) (xy 271.27708 -312.999882) (xy 271.276576 -313.02559)
			(xy 272.5232 -313.02559) (xy 272.5232 -312.974174) (xy 272.531243 -312.923392) (xy 272.547131 -312.874493)
			(xy 272.570474 -312.828681) (xy 272.600695 -312.787085) (xy 272.637051 -312.750729) (xy 272.678647 -312.720508)
			(xy 272.724459 -312.697165) (xy 272.773358 -312.681277) (xy 272.82414 -312.673234) (xy 272.875556 -312.673234)
			(xy 272.926338 -312.681277) (xy 272.975237 -312.697165) (xy 273.021049 -312.720508) (xy 273.062645 -312.750729)
			(xy 273.099001 -312.787085) (xy 273.129222 -312.828681) (xy 273.152565 -312.874493) (xy 273.168453 -312.923392)
			(xy 273.176496 -312.974174) (xy 273.177 -312.999882) (xy 273.176496 -313.02559) (xy 273.168453 -313.076372)
			(xy 273.152565 -313.125271) (xy 273.129222 -313.171083) (xy 273.099001 -313.212679) (xy 273.062645 -313.249035)
			(xy 273.021049 -313.279256) (xy 272.975237 -313.302599) (xy 272.926338 -313.318487) (xy 272.875556 -313.32653)
			(xy 272.82414 -313.32653) (xy 272.773358 -313.318487) (xy 272.724459 -313.302599) (xy 272.678647 -313.279256)
			(xy 272.637051 -313.249035) (xy 272.600695 -313.212679) (xy 272.570474 -313.171083) (xy 272.547131 -313.125271)
			(xy 272.531243 -313.076372) (xy 272.5232 -313.02559) (xy 271.276576 -313.02559) (xy 271.268533 -313.076372)
			(xy 271.252645 -313.125271) (xy 271.229302 -313.171083) (xy 271.199081 -313.212679) (xy 271.162725 -313.249035)
			(xy 271.121129 -313.279256) (xy 271.075317 -313.302599) (xy 271.026418 -313.318487) (xy 270.975636 -313.32653)
			(xy 270.92422 -313.32653) (xy 270.873438 -313.318487) (xy 270.824539 -313.302599) (xy 270.778727 -313.279256)
			(xy 270.737131 -313.249035) (xy 270.700775 -313.212679) (xy 270.670554 -313.171083) (xy 270.647211 -313.125271)
			(xy 270.631323 -313.076372) (xy 270.62328 -313.02559) (xy 262.4074 -313.02559) (xy 262.4074 -313.669934)
			(xy 266.246862 -313.669934) (xy 266.250933 -313.614312) (xy 266.263059 -313.559875) (xy 266.282982 -313.507784)
			(xy 266.310278 -313.459149) (xy 266.344364 -313.415006) (xy 266.384513 -313.376297) (xy 266.429871 -313.343846)
			(xy 266.479471 -313.318345) (xy 266.532255 -313.300338) (xy 266.587098 -313.290208) (xy 266.642832 -313.288171)
			(xy 266.698269 -313.294271) (xy 266.752226 -313.308377) (xy 266.803555 -313.330189) (xy 266.851161 -313.359243)
			(xy 266.894029 -313.394918) (xy 266.931246 -313.436455) (xy 266.962019 -313.482968) (xy 266.985691 -313.533465)
			(xy 267.001759 -313.586872) (xy 267.009879 -313.642048) (xy 267.010388 -313.669934) (xy 267.009879 -313.69782)
			(xy 267.001759 -313.752996) (xy 266.985691 -313.806403) (xy 266.962019 -313.8569) (xy 266.931246 -313.903413)
			(xy 266.894029 -313.94495) (xy 266.857259 -313.97555) (xy 270.62328 -313.97555) (xy 270.62328 -313.924134)
			(xy 270.631323 -313.873352) (xy 270.647211 -313.824453) (xy 270.670554 -313.778641) (xy 270.700775 -313.737045)
			(xy 270.737131 -313.700689) (xy 270.778727 -313.670468) (xy 270.824539 -313.647125) (xy 270.873438 -313.631237)
			(xy 270.92422 -313.623194) (xy 270.975636 -313.623194) (xy 271.026418 -313.631237) (xy 271.075317 -313.647125)
			(xy 271.121129 -313.670468) (xy 271.162725 -313.700689) (xy 271.199081 -313.737045) (xy 271.229302 -313.778641)
			(xy 271.252645 -313.824453) (xy 271.268533 -313.873352) (xy 271.276576 -313.924134) (xy 271.27708 -313.949842)
			(xy 271.276576 -313.97555) (xy 272.5232 -313.97555) (xy 272.5232 -313.924134) (xy 272.531243 -313.873352)
			(xy 272.547131 -313.824453) (xy 272.570474 -313.778641) (xy 272.600695 -313.737045) (xy 272.637051 -313.700689)
			(xy 272.678647 -313.670468) (xy 272.724459 -313.647125) (xy 272.773358 -313.631237) (xy 272.82414 -313.623194)
			(xy 272.875556 -313.623194) (xy 272.926338 -313.631237) (xy 272.975237 -313.647125) (xy 273.021049 -313.670468)
			(xy 273.062645 -313.700689) (xy 273.099001 -313.737045) (xy 273.129222 -313.778641) (xy 273.152565 -313.824453)
			(xy 273.168453 -313.873352) (xy 273.176496 -313.924134) (xy 273.177 -313.949842) (xy 273.176496 -313.97555)
			(xy 273.168453 -314.026332) (xy 273.152565 -314.075231) (xy 273.129222 -314.121043) (xy 273.099001 -314.162639)
			(xy 273.062645 -314.198995) (xy 273.021049 -314.229216) (xy 272.975237 -314.252559) (xy 272.926338 -314.268447)
			(xy 272.875556 -314.27649) (xy 272.82414 -314.27649) (xy 272.773358 -314.268447) (xy 272.724459 -314.252559)
			(xy 272.678647 -314.229216) (xy 272.637051 -314.198995) (xy 272.600695 -314.162639) (xy 272.570474 -314.121043)
			(xy 272.547131 -314.075231) (xy 272.531243 -314.026332) (xy 272.5232 -313.97555) (xy 271.276576 -313.97555)
			(xy 271.268533 -314.026332) (xy 271.252645 -314.075231) (xy 271.229302 -314.121043) (xy 271.199081 -314.162639)
			(xy 271.162725 -314.198995) (xy 271.121129 -314.229216) (xy 271.075317 -314.252559) (xy 271.026418 -314.268447)
			(xy 270.975636 -314.27649) (xy 270.92422 -314.27649) (xy 270.873438 -314.268447) (xy 270.824539 -314.252559)
			(xy 270.778727 -314.229216) (xy 270.737131 -314.198995) (xy 270.700775 -314.162639) (xy 270.670554 -314.121043)
			(xy 270.647211 -314.075231) (xy 270.631323 -314.026332) (xy 270.62328 -313.97555) (xy 266.857259 -313.97555)
			(xy 266.851161 -313.980625) (xy 266.803555 -314.009679) (xy 266.752226 -314.031491) (xy 266.698269 -314.045597)
			(xy 266.642832 -314.051697) (xy 266.587098 -314.04966) (xy 266.532255 -314.03953) (xy 266.479471 -314.021523)
			(xy 266.429871 -313.996022) (xy 266.384513 -313.963571) (xy 266.344364 -313.924862) (xy 266.310278 -313.880719)
			(xy 266.282982 -313.832084) (xy 266.263059 -313.779993) (xy 266.250933 -313.725556) (xy 266.246862 -313.669934)
			(xy 262.4074 -313.669934) (xy 262.4074 -314.099956) (xy 262.406966 -314.110022) (xy 262.399238 -314.128611)
			(xy 262.392414 -314.136024) (xy 261.602928 -314.92551) (xy 268.723106 -314.92551) (xy 268.723106 -314.874094)
			(xy 268.731149 -314.823312) (xy 268.747037 -314.774413) (xy 268.77038 -314.728601) (xy 268.800601 -314.687005)
			(xy 268.836957 -314.650649) (xy 268.878553 -314.620428) (xy 268.924365 -314.597085) (xy 268.973264 -314.581197)
			(xy 269.024046 -314.573154) (xy 269.075462 -314.573154) (xy 269.126244 -314.581197) (xy 269.175143 -314.597085)
			(xy 269.220955 -314.620428) (xy 269.262551 -314.650649) (xy 269.298907 -314.687005) (xy 269.329128 -314.728601)
			(xy 269.352471 -314.774413) (xy 269.368359 -314.823312) (xy 269.376402 -314.874094) (xy 269.376906 -314.899802)
			(xy 269.376402 -314.92551) (xy 269.673066 -314.92551) (xy 269.673066 -314.874094) (xy 269.681109 -314.823312)
			(xy 269.696997 -314.774413) (xy 269.72034 -314.728601) (xy 269.750561 -314.687005) (xy 269.786917 -314.650649)
			(xy 269.828513 -314.620428) (xy 269.874325 -314.597085) (xy 269.923224 -314.581197) (xy 269.974006 -314.573154)
			(xy 270.025422 -314.573154) (xy 270.076204 -314.581197) (xy 270.125103 -314.597085) (xy 270.170915 -314.620428)
			(xy 270.212511 -314.650649) (xy 270.248867 -314.687005) (xy 270.279088 -314.728601) (xy 270.302431 -314.774413)
			(xy 270.318319 -314.823312) (xy 270.326362 -314.874094) (xy 270.326866 -314.899802) (xy 270.326362 -314.92551)
			(xy 270.318319 -314.976292) (xy 270.302431 -315.025191) (xy 270.279088 -315.071003) (xy 270.248867 -315.112599)
			(xy 270.212511 -315.148955) (xy 270.170915 -315.179176) (xy 270.125103 -315.202519) (xy 270.076204 -315.218407)
			(xy 270.025422 -315.22645) (xy 269.974006 -315.22645) (xy 269.923224 -315.218407) (xy 269.874325 -315.202519)
			(xy 269.828513 -315.179176) (xy 269.786917 -315.148955) (xy 269.750561 -315.112599) (xy 269.72034 -315.071003)
			(xy 269.696997 -315.025191) (xy 269.681109 -314.976292) (xy 269.673066 -314.92551) (xy 269.376402 -314.92551)
			(xy 269.368359 -314.976292) (xy 269.352471 -315.025191) (xy 269.329128 -315.071003) (xy 269.298907 -315.112599)
			(xy 269.262551 -315.148955) (xy 269.220955 -315.179176) (xy 269.175143 -315.202519) (xy 269.126244 -315.218407)
			(xy 269.075462 -315.22645) (xy 269.024046 -315.22645) (xy 268.973264 -315.218407) (xy 268.924365 -315.202519)
			(xy 268.878553 -315.179176) (xy 268.836957 -315.148955) (xy 268.800601 -315.112599) (xy 268.77038 -315.071003)
			(xy 268.747037 -315.025191) (xy 268.731149 -314.976292) (xy 268.723106 -314.92551) (xy 261.602928 -314.92551)
			(xy 260.652968 -315.87547) (xy 271.57324 -315.87547) (xy 271.57324 -315.824054) (xy 271.581283 -315.773272)
			(xy 271.597171 -315.724373) (xy 271.620514 -315.678561) (xy 271.650735 -315.636965) (xy 271.687091 -315.600609)
			(xy 271.728687 -315.570388) (xy 271.774499 -315.547045) (xy 271.823398 -315.531157) (xy 271.87418 -315.523114)
			(xy 271.925596 -315.523114) (xy 271.976378 -315.531157) (xy 272.025277 -315.547045) (xy 272.071089 -315.570388)
			(xy 272.112685 -315.600609) (xy 272.149041 -315.636965) (xy 272.179262 -315.678561) (xy 272.202605 -315.724373)
			(xy 272.218493 -315.773272) (xy 272.226536 -315.824054) (xy 272.22704 -315.849762) (xy 272.226536 -315.87547)
			(xy 272.218493 -315.926252) (xy 272.202605 -315.975151) (xy 272.179262 -316.020963) (xy 272.149041 -316.062559)
			(xy 272.112685 -316.098915) (xy 272.071089 -316.129136) (xy 272.025277 -316.152479) (xy 271.976378 -316.168367)
			(xy 271.925596 -316.17641) (xy 271.87418 -316.17641) (xy 271.823398 -316.168367) (xy 271.774499 -316.152479)
			(xy 271.728687 -316.129136) (xy 271.687091 -316.098915) (xy 271.650735 -316.062559) (xy 271.620514 -316.020963)
			(xy 271.597171 -315.975151) (xy 271.581283 -315.926252) (xy 271.57324 -315.87547) (xy 260.652968 -315.87547)
			(xy 260.369812 -316.158626) (xy 260.357112 -316.171072) (xy 260.353048 -316.205616) (xy 260.413246 -316.305184)
			(xy 260.419552 -316.314504) (xy 260.438258 -316.326962) (xy 260.460491 -316.330246) (xy 260.471412 -316.327536)
			(xy 260.567128 -316.299229) (xy 260.760501 -316.249658) (xy 260.955776 -316.20821) (xy 261.152612 -316.174957)
			(xy 261.350666 -316.149958) (xy 261.549592 -316.133256) (xy 261.749041 -316.12488) (xy 261.848854 -316.124336)
			(xy 261.84987 -316.124336) (xy 261.947298 -316.124833) (xy 262.14199 -316.132781) (xy 262.336197 -316.148663)
			(xy 262.529594 -316.172454) (xy 262.72186 -316.204113) (xy 262.912675 -316.243588) (xy 263.10172 -316.290814)
			(xy 263.288682 -316.345711) (xy 263.47325 -316.408188) (xy 263.655115 -316.478141) (xy 263.833976 -316.555455)
			(xy 264.009534 -316.639999) (xy 264.181498 -316.731634) (xy 264.341435 -316.82543) (xy 268.723106 -316.82543)
			(xy 268.723106 -316.774014) (xy 268.731149 -316.723232) (xy 268.747037 -316.674333) (xy 268.77038 -316.628521)
			(xy 268.800601 -316.586925) (xy 268.836957 -316.550569) (xy 268.878553 -316.520348) (xy 268.924365 -316.497005)
			(xy 268.973264 -316.481117) (xy 269.024046 -316.473074) (xy 269.075462 -316.473074) (xy 269.126244 -316.481117)
			(xy 269.175143 -316.497005) (xy 269.220955 -316.520348) (xy 269.262551 -316.550569) (xy 269.298907 -316.586925)
			(xy 269.329128 -316.628521) (xy 269.352471 -316.674333) (xy 269.368359 -316.723232) (xy 269.376402 -316.774014)
			(xy 269.376906 -316.799722) (xy 269.376402 -316.82543) (xy 269.673066 -316.82543) (xy 269.673066 -316.774014)
			(xy 269.681109 -316.723232) (xy 269.696997 -316.674333) (xy 269.72034 -316.628521) (xy 269.750561 -316.586925)
			(xy 269.786917 -316.550569) (xy 269.828513 -316.520348) (xy 269.874325 -316.497005) (xy 269.923224 -316.481117)
			(xy 269.974006 -316.473074) (xy 270.025422 -316.473074) (xy 270.076204 -316.481117) (xy 270.125103 -316.497005)
			(xy 270.170915 -316.520348) (xy 270.212511 -316.550569) (xy 270.248867 -316.586925) (xy 270.279088 -316.628521)
			(xy 270.302431 -316.674333) (xy 270.318319 -316.723232) (xy 270.326362 -316.774014) (xy 270.326866 -316.799722)
			(xy 270.326362 -316.82543) (xy 271.57324 -316.82543) (xy 271.57324 -316.774014) (xy 271.581283 -316.723232)
			(xy 271.597171 -316.674333) (xy 271.620514 -316.628521) (xy 271.650735 -316.586925) (xy 271.687091 -316.550569)
			(xy 271.728687 -316.520348) (xy 271.774499 -316.497005) (xy 271.823398 -316.481117) (xy 271.87418 -316.473074)
			(xy 271.925596 -316.473074) (xy 271.976378 -316.481117) (xy 272.025277 -316.497005) (xy 272.071089 -316.520348)
			(xy 272.112685 -316.550569) (xy 272.149041 -316.586925) (xy 272.179262 -316.628521) (xy 272.202605 -316.674333)
			(xy 272.218493 -316.723232) (xy 272.226536 -316.774014) (xy 272.22704 -316.799722) (xy 272.226536 -316.82543)
			(xy 272.218493 -316.876212) (xy 272.202605 -316.925111) (xy 272.179262 -316.970923) (xy 272.149041 -317.012519)
			(xy 272.112685 -317.048875) (xy 272.071089 -317.079096) (xy 272.025277 -317.102439) (xy 271.976378 -317.118327)
			(xy 271.925596 -317.12637) (xy 271.87418 -317.12637) (xy 271.823398 -317.118327) (xy 271.774499 -317.102439)
			(xy 271.728687 -317.079096) (xy 271.687091 -317.048875) (xy 271.650735 -317.012519) (xy 271.620514 -316.970923)
			(xy 271.597171 -316.925111) (xy 271.581283 -316.876212) (xy 271.57324 -316.82543) (xy 270.326362 -316.82543)
			(xy 270.318319 -316.876212) (xy 270.302431 -316.925111) (xy 270.279088 -316.970923) (xy 270.248867 -317.012519)
			(xy 270.212511 -317.048875) (xy 270.170915 -317.079096) (xy 270.125103 -317.102439) (xy 270.076204 -317.118327)
			(xy 270.025422 -317.12637) (xy 269.974006 -317.12637) (xy 269.923224 -317.118327) (xy 269.874325 -317.102439)
			(xy 269.828513 -317.079096) (xy 269.786917 -317.048875) (xy 269.750561 -317.012519) (xy 269.72034 -316.970923)
			(xy 269.696997 -316.925111) (xy 269.681109 -316.876212) (xy 269.673066 -316.82543) (xy 269.376402 -316.82543)
			(xy 269.368359 -316.876212) (xy 269.352471 -316.925111) (xy 269.329128 -316.970923) (xy 269.298907 -317.012519)
			(xy 269.262551 -317.048875) (xy 269.220955 -317.079096) (xy 269.175143 -317.102439) (xy 269.126244 -317.118327)
			(xy 269.075462 -317.12637) (xy 269.024046 -317.12637) (xy 268.973264 -317.118327) (xy 268.924365 -317.102439)
			(xy 268.878553 -317.079096) (xy 268.836957 -317.048875) (xy 268.800601 -317.012519) (xy 268.77038 -316.970923)
			(xy 268.747037 -316.925111) (xy 268.731149 -316.876212) (xy 268.723106 -316.82543) (xy 264.341435 -316.82543)
			(xy 264.349581 -316.830207) (xy 264.513503 -316.935553) (xy 264.672992 -317.047498) (xy 264.827783 -317.165856)
			(xy 264.977616 -317.290428) (xy 265.122245 -317.421008) (xy 265.261426 -317.557379) (xy 265.394929 -317.699314)
			(xy 265.46107 -317.775644) (xy 270.62328 -317.775644) (xy 270.62328 -317.724228) (xy 270.631323 -317.673446)
			(xy 270.647211 -317.624547) (xy 270.670554 -317.578735) (xy 270.700775 -317.537139) (xy 270.737131 -317.500783)
			(xy 270.778727 -317.470562) (xy 270.824539 -317.447219) (xy 270.873438 -317.431331) (xy 270.92422 -317.423288)
			(xy 270.975636 -317.423288) (xy 271.026418 -317.431331) (xy 271.075317 -317.447219) (xy 271.121129 -317.470562)
			(xy 271.162725 -317.500783) (xy 271.199081 -317.537139) (xy 271.229302 -317.578735) (xy 271.252645 -317.624547)
			(xy 271.268533 -317.673446) (xy 271.276576 -317.724228) (xy 271.27708 -317.749936) (xy 271.276576 -317.775644)
			(xy 271.268533 -317.826426) (xy 271.252645 -317.875325) (xy 271.229302 -317.921137) (xy 271.199081 -317.962733)
			(xy 271.162725 -317.999089) (xy 271.121129 -318.02931) (xy 271.075317 -318.052653) (xy 271.026418 -318.068541)
			(xy 270.975636 -318.076584) (xy 270.92422 -318.076584) (xy 270.873438 -318.068541) (xy 270.824539 -318.052653)
			(xy 270.778727 -318.02931) (xy 270.737131 -317.999089) (xy 270.700775 -317.962733) (xy 270.670554 -317.921137)
			(xy 270.647211 -317.875325) (xy 270.631323 -317.826426) (xy 270.62328 -317.775644) (xy 265.46107 -317.775644)
			(xy 265.522532 -317.846575) (xy 265.644022 -317.998919) (xy 265.759198 -318.156091) (xy 265.867866 -318.317831)
			(xy 265.969847 -318.483868) (xy 266.06497 -318.653927) (xy 266.101307 -318.725604) (xy 270.62328 -318.725604)
			(xy 270.62328 -318.674188) (xy 270.631323 -318.623406) (xy 270.647211 -318.574507) (xy 270.670554 -318.528695)
			(xy 270.700775 -318.487099) (xy 270.737131 -318.450743) (xy 270.778727 -318.420522) (xy 270.824539 -318.397179)
			(xy 270.873438 -318.381291) (xy 270.92422 -318.373248) (xy 270.975636 -318.373248) (xy 271.026418 -318.381291)
			(xy 271.075317 -318.397179) (xy 271.121129 -318.420522) (xy 271.162725 -318.450743) (xy 271.199081 -318.487099)
			(xy 271.229302 -318.528695) (xy 271.252645 -318.574507) (xy 271.268533 -318.623406) (xy 271.276576 -318.674188)
			(xy 271.27708 -318.699896) (xy 271.276576 -318.725604) (xy 271.268533 -318.776386) (xy 271.252645 -318.825285)
			(xy 271.229302 -318.871097) (xy 271.199081 -318.912693) (xy 271.162725 -318.949049) (xy 271.121129 -318.97927)
			(xy 271.075317 -319.002613) (xy 271.026418 -319.018501) (xy 270.975636 -319.026544) (xy 270.92422 -319.026544)
			(xy 270.873438 -319.018501) (xy 270.824539 -319.002613) (xy 270.778727 -318.97927) (xy 270.737131 -318.949049)
			(xy 270.700775 -318.912693) (xy 270.670554 -318.871097) (xy 270.647211 -318.825285) (xy 270.631323 -318.776386)
			(xy 270.62328 -318.725604) (xy 266.101307 -318.725604) (xy 266.153078 -318.827724) (xy 266.234024 -319.00497)
			(xy 266.307673 -319.185371) (xy 266.373902 -319.368625) (xy 266.432601 -319.554429) (xy 266.483673 -319.742472)
			(xy 266.527032 -319.932441) (xy 266.562607 -320.124021) (xy 266.590338 -320.316893) (xy 266.610179 -320.510735)
			(xy 266.622096 -320.705226) (xy 266.626071 -320.90004) (xy 266.622096 -321.094854) (xy 266.610179 -321.289345)
			(xy 266.590338 -321.483187) (xy 266.562607 -321.676059) (xy 266.527032 -321.867639) (xy 266.483673 -322.057608)
			(xy 266.432601 -322.245651) (xy 266.373902 -322.431455) (xy 266.307673 -322.614709) (xy 266.234024 -322.79511)
			(xy 266.153078 -322.972356) (xy 266.06497 -323.146153) (xy 265.969847 -323.316212) (xy 265.867866 -323.482249)
			(xy 265.759198 -323.643989) (xy 265.644022 -323.801161) (xy 265.522532 -323.953505) (xy 265.394929 -324.100766)
			(xy 265.261426 -324.242701) (xy 265.122245 -324.379072) (xy 264.977616 -324.509652) (xy 264.827783 -324.634224)
			(xy 264.672992 -324.752582) (xy 264.513503 -324.864527) (xy 264.349581 -324.969873) (xy 264.181498 -325.068446)
			(xy 264.009534 -325.160081) (xy 263.833976 -325.244625) (xy 263.655115 -325.321939) (xy 263.47325 -325.391892)
			(xy 263.288682 -325.454369) (xy 263.10172 -325.509266) (xy 262.912675 -325.556492) (xy 262.72186 -325.595967)
			(xy 262.529594 -325.627626) (xy 262.336197 -325.651417) (xy 262.14199 -325.667299) (xy 261.947298 -325.675247)
			(xy 261.84987 -325.675752) (xy 261.849616 -325.675752) (xy 261.752424 -325.675248) (xy 261.558202 -325.667315)
			(xy 261.364464 -325.651486) (xy 261.17153 -325.627787) (xy 260.979721 -325.596258) (xy 260.789353 -325.55695)
			(xy 260.600742 -325.509929) (xy 260.4142 -325.455272) (xy 260.230037 -325.393071) (xy 260.048557 -325.323427)
			(xy 259.870062 -325.246458) (xy 259.694846 -325.162289) (xy 259.523199 -325.07106) (xy 259.355407 -324.972923)
			(xy 259.191747 -324.86804) (xy 259.03249 -324.756585) (xy 258.8779 -324.638742) (xy 258.728232 -324.514707)
			(xy 258.583736 -324.384684) (xy 258.44465 -324.24889) (xy 258.311204 -324.107549) (xy 258.183619 -323.960896)
			(xy 258.062108 -323.809172) (xy 257.94687 -323.65263) (xy 257.892042 -323.572378) (xy 257.892042 -323.572124)
			(xy 257.885455 -323.563429) (xy 257.866815 -323.552139) (xy 257.84518 -323.549515) (xy 257.834638 -323.552312)
			(xy 257.778758 -323.569838) (xy 257.77825 -323.569838) (xy 257.742182 -323.58076) (xy 257.731961 -323.584407)
			(xy 257.715662 -323.598705) (xy 257.706672 -323.618435) (xy 257.706114 -323.629274) (xy 257.706114 -328.521155)
			(xy 266.319437 -328.521155) (xy 266.319437 -328.466645) (xy 266.327194 -328.412691) (xy 266.342552 -328.36039)
			(xy 266.365196 -328.310807) (xy 266.394666 -328.264951) (xy 266.430362 -328.223757) (xy 266.471558 -328.188061)
			(xy 266.517414 -328.158592) (xy 266.566998 -328.135949) (xy 266.619299 -328.120593) (xy 266.673253 -328.112836)
			(xy 266.700508 -328.112374) (xy 266.729661 -328.112946) (xy 266.787288 -328.121812) (xy 266.842897 -328.139336)
			(xy 266.895195 -328.165112) (xy 266.942966 -328.198539) (xy 266.964414 -328.218292) (xy 266.97178 -328.225404)
			(xy 266.990068 -328.232516) (xy 267.081 -328.231754) (xy 267.099288 -328.224134) (xy 267.1064 -328.217022)
			(xy 267.127992 -328.19632) (xy 267.176429 -328.161227) (xy 267.229752 -328.134126) (xy 267.286651 -328.115683)
			(xy 267.345733 -328.10635) (xy 267.37564 -328.10577) (xy 267.402888 -328.106303) (xy 267.456828 -328.114064)
			(xy 267.509115 -328.129421) (xy 267.558684 -328.152063) (xy 267.604527 -328.181529) (xy 267.64571 -328.217218)
			(xy 267.681395 -328.258405) (xy 267.710856 -328.304251) (xy 267.733493 -328.353823) (xy 267.748845 -328.406111)
			(xy 267.7566 -328.460052) (xy 267.7566 -328.514548) (xy 267.748845 -328.568489) (xy 267.733493 -328.620777)
			(xy 267.710856 -328.670349) (xy 267.681395 -328.716195) (xy 267.64571 -328.757382) (xy 267.604527 -328.793071)
			(xy 267.558684 -328.822537) (xy 267.509115 -328.845179) (xy 267.456828 -328.860536) (xy 267.402888 -328.868297)
			(xy 267.37564 -328.868786) (xy 267.346486 -328.868257) (xy 267.288856 -328.859383) (xy 267.233246 -328.841849)
			(xy 267.180949 -328.816063) (xy 267.13318 -328.782626) (xy 267.111734 -328.762868) (xy 267.104368 -328.755756)
			(xy 267.08608 -328.748644) (xy 266.995148 -328.749406) (xy 266.97686 -328.757026) (xy 266.969748 -328.764138)
			(xy 266.948128 -328.78481) (xy 266.8997 -328.819909) (xy 266.846384 -328.847016) (xy 266.78949 -328.865466)
			(xy 266.730413 -328.874806) (xy 266.700508 -328.87539) (xy 266.673253 -328.874964) (xy 266.619299 -328.867207)
			(xy 266.566998 -328.851851) (xy 266.517414 -328.829208) (xy 266.471558 -328.799739) (xy 266.430362 -328.764043)
			(xy 266.394666 -328.722849) (xy 266.365196 -328.676993) (xy 266.342552 -328.62741) (xy 266.327194 -328.575109)
			(xy 266.319437 -328.521155) (xy 257.706114 -328.521155) (xy 257.706114 -339.622384) (xy 257.705676 -339.632448)
			(xy 257.697942 -339.651031) (xy 257.691128 -339.658452) (xy 257.655822 -339.693758) (xy 266.115798 -339.693758)
			(xy 266.119869 -339.638136) (xy 266.131995 -339.583699) (xy 266.151918 -339.531608) (xy 266.179214 -339.482973)
			(xy 266.2133 -339.43883) (xy 266.253449 -339.400121) (xy 266.298807 -339.36767) (xy 266.348407 -339.342169)
			(xy 266.401191 -339.324162) (xy 266.456034 -339.314032) (xy 266.511768 -339.311995) (xy 266.567205 -339.318095)
			(xy 266.621162 -339.332201) (xy 266.672491 -339.354013) (xy 266.720097 -339.383067) (xy 266.762965 -339.418742)
			(xy 266.800182 -339.460279) (xy 266.830955 -339.506792) (xy 266.854627 -339.557289) (xy 266.870695 -339.610696)
			(xy 266.878815 -339.665872) (xy 266.879324 -339.693758) (xy 266.878815 -339.721644) (xy 266.870695 -339.77682)
			(xy 266.854627 -339.830227) (xy 266.830955 -339.880724) (xy 266.800182 -339.927237) (xy 266.762965 -339.968774)
			(xy 266.720097 -340.004449) (xy 266.672491 -340.033503) (xy 266.621162 -340.055315) (xy 266.567205 -340.069421)
			(xy 266.511768 -340.075521) (xy 266.456034 -340.073484) (xy 266.401191 -340.063354) (xy 266.348407 -340.045347)
			(xy 266.298807 -340.019846) (xy 266.253449 -339.987395) (xy 266.2133 -339.948686) (xy 266.179214 -339.904543)
			(xy 266.151918 -339.855908) (xy 266.131995 -339.803817) (xy 266.119869 -339.74938) (xy 266.115798 -339.693758)
			(xy 257.655822 -339.693758) (xy 256.780792 -340.568788) (xy 256.773393 -340.575634) (xy 256.754795 -340.583368)
			(xy 256.744724 -340.583774) (xy 229.013004 -340.583774) (xy 229.002934 -340.583351) (xy 228.984331 -340.575635)
			(xy 228.976936 -340.568788) (xy 227.032312 -338.624164) (xy 227.02547 -338.616764) (xy 227.017747 -338.598166)
			(xy 227.017326 -338.588096) (xy 227.017326 -326.9742) (xy 227.01775 -326.96413) (xy 227.025467 -326.945528)
			(xy 227.032312 -326.938132) (xy 228.416104 -325.55434) (xy 228.423501 -325.54749) (xy 228.442099 -325.539751)
			(xy 228.452172 -325.539354) (xy 230.84663 -325.539354) (xy 230.858077 -325.538838) (xy 230.878713 -325.528929)
			(xy 230.886254 -325.520304) (xy 230.890064 -325.515478) (xy 230.933498 -325.440802) (xy 230.933752 -325.440548)
			(xy 230.933752 -325.440294) (xy 230.938208 -325.431536) (xy 230.940807 -325.412075) (xy 230.938832 -325.402448)
			(xy 230.935022 -325.387716) (xy 230.931974 -325.382128) (xy 230.917196 -325.353843) (xy 230.896247 -325.293568)
			(xy 230.885621 -325.230646) (xy 230.884984 -325.19874) (xy 230.884984 -325.198486) (xy 230.88547 -325.171235)
			(xy 230.893226 -325.117287) (xy 230.908581 -325.064992) (xy 230.931223 -325.015415) (xy 230.960689 -324.969565)
			(xy 230.99638 -324.928374) (xy 231.037571 -324.892683) (xy 231.083421 -324.863217) (xy 231.132998 -324.840575)
			(xy 231.185293 -324.82522) (xy 231.239241 -324.817464) (xy 231.293743 -324.817464) (xy 231.347691 -324.82522)
			(xy 231.399986 -324.840575) (xy 231.449563 -324.863217) (xy 231.495413 -324.892683) (xy 231.536604 -324.928374)
			(xy 231.572295 -324.969565) (xy 231.601761 -325.015415) (xy 231.624403 -325.064992) (xy 231.639758 -325.117287)
			(xy 231.647514 -325.171235) (xy 231.648 -325.198486) (xy 231.648 -325.19874) (xy 231.647333 -325.230643)
			(xy 231.636692 -325.293556) (xy 231.615762 -325.353832) (xy 231.60101 -325.382128) (xy 231.597962 -325.387716)
			(xy 231.594406 -325.400924) (xy 231.594406 -325.401432) (xy 231.591866 -325.409814) (xy 231.594152 -325.430642)
			(xy 231.642158 -325.513954) (xy 231.646942 -325.52144) (xy 231.660549 -325.532839) (xy 231.677225 -325.53892)
			(xy 231.6861 -325.539354) (xy 236.58449 -325.539354) (xy 236.59456 -325.539777) (xy 236.613162 -325.547495)
			(xy 236.620558 -325.55434) (xy 236.813852 -325.747634) (xy 236.82125 -325.75448) (xy 236.839849 -325.762205)
			(xy 236.84992 -325.76262) (xy 246.702834 -325.76262) (xy 246.711216 -325.761858) (xy 246.718821 -325.760343)
			(xy 246.732657 -325.753359) (xy 246.738394 -325.748142) (xy 249.536204 -322.950332) (xy 249.543039 -322.94293)
			(xy 249.550748 -322.924332) (xy 249.55119 -322.914264) (xy 249.55119 -304.197766) (xy 249.550696 -304.187764)
			(xy 249.54303 -304.169285) (xy 249.528878 -304.155145) (xy 249.510393 -304.147495) (xy 249.50039 -304.146966)
			(xy 224.032318 -304.146966) (xy 224.013522 -304.154586) (xy 224.00641 -304.161952) (xy 221.424246 -306.744116)
			(xy 221.949516 -306.744116) (xy 221.953587 -306.688494) (xy 221.965713 -306.634057) (xy 221.985636 -306.581966)
			(xy 222.012932 -306.533331) (xy 222.047018 -306.489188) (xy 222.087167 -306.450479) (xy 222.132525 -306.418028)
			(xy 222.182125 -306.392527) (xy 222.234909 -306.37452) (xy 222.289752 -306.36439) (xy 222.345486 -306.362353)
			(xy 222.400923 -306.368453) (xy 222.45488 -306.382559) (xy 222.506209 -306.404371) (xy 222.553815 -306.433425)
			(xy 222.596683 -306.4691) (xy 222.6339 -306.510637) (xy 222.664673 -306.55715) (xy 222.688345 -306.607647)
			(xy 222.704413 -306.661054) (xy 222.712533 -306.71623) (xy 222.713042 -306.744116) (xy 222.712533 -306.772002)
			(xy 222.71032 -306.787042) (xy 229.223568 -306.787042) (xy 229.227639 -306.73142) (xy 229.239765 -306.676983)
			(xy 229.259688 -306.624892) (xy 229.286984 -306.576257) (xy 229.32107 -306.532114) (xy 229.361219 -306.493405)
			(xy 229.406577 -306.460954) (xy 229.456177 -306.435453) (xy 229.508961 -306.417446) (xy 229.563804 -306.407316)
			(xy 229.619538 -306.405279) (xy 229.674975 -306.411379) (xy 229.728932 -306.425485) (xy 229.780261 -306.447297)
			(xy 229.827867 -306.476351) (xy 229.870735 -306.512026) (xy 229.907952 -306.553563) (xy 229.938725 -306.600076)
			(xy 229.962397 -306.650573) (xy 229.978465 -306.70398) (xy 229.984372 -306.744116) (xy 238.199674 -306.744116)
			(xy 238.203745 -306.688494) (xy 238.215871 -306.634057) (xy 238.235794 -306.581966) (xy 238.26309 -306.533331)
			(xy 238.297176 -306.489188) (xy 238.337325 -306.450479) (xy 238.382683 -306.418028) (xy 238.432283 -306.392527)
			(xy 238.485067 -306.37452) (xy 238.53991 -306.36439) (xy 238.595644 -306.362353) (xy 238.651081 -306.368453)
			(xy 238.705038 -306.382559) (xy 238.756367 -306.404371) (xy 238.803973 -306.433425) (xy 238.846841 -306.4691)
			(xy 238.884058 -306.510637) (xy 238.914831 -306.55715) (xy 238.938503 -306.607647) (xy 238.954571 -306.661054)
			(xy 238.962691 -306.71623) (xy 238.9632 -306.744116) (xy 238.962691 -306.772002) (xy 238.960478 -306.787042)
			(xy 245.473726 -306.787042) (xy 245.477797 -306.73142) (xy 245.489923 -306.676983) (xy 245.509846 -306.624892)
			(xy 245.537142 -306.576257) (xy 245.571228 -306.532114) (xy 245.611377 -306.493405) (xy 245.656735 -306.460954)
			(xy 245.706335 -306.435453) (xy 245.759119 -306.417446) (xy 245.813962 -306.407316) (xy 245.869696 -306.405279)
			(xy 245.925133 -306.411379) (xy 245.97909 -306.425485) (xy 246.030419 -306.447297) (xy 246.078025 -306.476351)
			(xy 246.120893 -306.512026) (xy 246.15811 -306.553563) (xy 246.188883 -306.600076) (xy 246.212555 -306.650573)
			(xy 246.228623 -306.70398) (xy 246.236743 -306.759156) (xy 246.237252 -306.787042) (xy 246.236743 -306.814928)
			(xy 246.228623 -306.870104) (xy 246.212555 -306.923511) (xy 246.188883 -306.974008) (xy 246.15811 -307.020521)
			(xy 246.120893 -307.062058) (xy 246.078025 -307.097733) (xy 246.030419 -307.126787) (xy 245.97909 -307.148599)
			(xy 245.925133 -307.162705) (xy 245.869696 -307.168805) (xy 245.813962 -307.166768) (xy 245.759119 -307.156638)
			(xy 245.706335 -307.138631) (xy 245.656735 -307.11313) (xy 245.611377 -307.080679) (xy 245.571228 -307.04197)
			(xy 245.537142 -306.997827) (xy 245.509846 -306.949192) (xy 245.489923 -306.897101) (xy 245.477797 -306.842664)
			(xy 245.473726 -306.787042) (xy 238.960478 -306.787042) (xy 238.954571 -306.827178) (xy 238.938503 -306.880585)
			(xy 238.914831 -306.931082) (xy 238.884058 -306.977595) (xy 238.846841 -307.019132) (xy 238.803973 -307.054807)
			(xy 238.756367 -307.083861) (xy 238.705038 -307.105673) (xy 238.651081 -307.119779) (xy 238.595644 -307.125879)
			(xy 238.53991 -307.123842) (xy 238.485067 -307.113712) (xy 238.432283 -307.095705) (xy 238.382683 -307.070204)
			(xy 238.337325 -307.037753) (xy 238.297176 -306.999044) (xy 238.26309 -306.954901) (xy 238.235794 -306.906266)
			(xy 238.215871 -306.854175) (xy 238.203745 -306.799738) (xy 238.199674 -306.744116) (xy 229.984372 -306.744116)
			(xy 229.986585 -306.759156) (xy 229.987094 -306.787042) (xy 229.986585 -306.814928) (xy 229.978465 -306.870104)
			(xy 229.962397 -306.923511) (xy 229.938725 -306.974008) (xy 229.907952 -307.020521) (xy 229.870735 -307.062058)
			(xy 229.827867 -307.097733) (xy 229.780261 -307.126787) (xy 229.728932 -307.148599) (xy 229.674975 -307.162705)
			(xy 229.619538 -307.168805) (xy 229.563804 -307.166768) (xy 229.508961 -307.156638) (xy 229.456177 -307.138631)
			(xy 229.406577 -307.11313) (xy 229.361219 -307.080679) (xy 229.32107 -307.04197) (xy 229.286984 -306.997827)
			(xy 229.259688 -306.949192) (xy 229.239765 -306.897101) (xy 229.227639 -306.842664) (xy 229.223568 -306.787042)
			(xy 222.71032 -306.787042) (xy 222.704413 -306.827178) (xy 222.688345 -306.880585) (xy 222.664673 -306.931082)
			(xy 222.6339 -306.977595) (xy 222.596683 -307.019132) (xy 222.553815 -307.054807) (xy 222.506209 -307.083861)
			(xy 222.45488 -307.105673) (xy 222.400923 -307.119779) (xy 222.345486 -307.125879) (xy 222.289752 -307.123842)
			(xy 222.234909 -307.113712) (xy 222.182125 -307.095705) (xy 222.132525 -307.070204) (xy 222.087167 -307.037753)
			(xy 222.047018 -306.999044) (xy 222.012932 -306.954901) (xy 221.985636 -306.906266) (xy 221.965713 -306.854175)
			(xy 221.953587 -306.799738) (xy 221.949516 -306.744116) (xy 221.424246 -306.744116) (xy 220.721936 -307.446426)
			(xy 226.875084 -307.446426) (xy 226.879155 -307.390804) (xy 226.891281 -307.336367) (xy 226.911204 -307.284276)
			(xy 226.9385 -307.235641) (xy 226.972586 -307.191498) (xy 227.012735 -307.152789) (xy 227.058093 -307.120338)
			(xy 227.107693 -307.094837) (xy 227.160477 -307.07683) (xy 227.21532 -307.0667) (xy 227.271054 -307.064663)
			(xy 227.326491 -307.070763) (xy 227.380448 -307.084869) (xy 227.431777 -307.106681) (xy 227.479383 -307.135735)
			(xy 227.522251 -307.17141) (xy 227.559468 -307.212947) (xy 227.590241 -307.25946) (xy 227.613913 -307.309957)
			(xy 227.629981 -307.363364) (xy 227.638101 -307.41854) (xy 227.63861 -307.446426) (xy 227.638101 -307.474312)
			(xy 227.636635 -307.484272) (xy 231.935526 -307.484272) (xy 231.939599 -307.428613) (xy 231.951734 -307.37414)
			(xy 231.97167 -307.322014) (xy 231.998984 -307.273346) (xy 232.033092 -307.229174) (xy 232.073269 -307.190439)
			(xy 232.118657 -307.157967) (xy 232.168289 -307.132449) (xy 232.221109 -307.11443) (xy 232.275988 -307.104293)
			(xy 232.331759 -307.102255) (xy 232.387233 -307.108358) (xy 232.441226 -307.122474) (xy 232.492589 -307.144301)
			(xy 232.540227 -307.173374) (xy 232.583123 -307.209073) (xy 232.620365 -307.250637) (xy 232.651159 -307.297181)
			(xy 232.674847 -307.347712) (xy 232.690925 -307.401154) (xy 232.697588 -307.446426) (xy 243.125242 -307.446426)
			(xy 243.129313 -307.390804) (xy 243.141439 -307.336367) (xy 243.161362 -307.284276) (xy 243.188658 -307.235641)
			(xy 243.222744 -307.191498) (xy 243.262893 -307.152789) (xy 243.308251 -307.120338) (xy 243.357851 -307.094837)
			(xy 243.410635 -307.07683) (xy 243.465478 -307.0667) (xy 243.521212 -307.064663) (xy 243.576649 -307.070763)
			(xy 243.630606 -307.084869) (xy 243.681935 -307.106681) (xy 243.729541 -307.135735) (xy 243.772409 -307.17141)
			(xy 243.809626 -307.212947) (xy 243.840399 -307.25946) (xy 243.864071 -307.309957) (xy 243.880139 -307.363364)
			(xy 243.888259 -307.41854) (xy 243.888768 -307.446426) (xy 243.888259 -307.474312) (xy 243.886793 -307.484272)
			(xy 248.185684 -307.484272) (xy 248.189757 -307.428613) (xy 248.201892 -307.37414) (xy 248.221828 -307.322014)
			(xy 248.249142 -307.273346) (xy 248.28325 -307.229174) (xy 248.323427 -307.190439) (xy 248.368815 -307.157967)
			(xy 248.418447 -307.132449) (xy 248.471267 -307.11443) (xy 248.526146 -307.104293) (xy 248.581917 -307.102255)
			(xy 248.637391 -307.108358) (xy 248.691384 -307.122474) (xy 248.742747 -307.144301) (xy 248.790385 -307.173374)
			(xy 248.833281 -307.209073) (xy 248.870523 -307.250637) (xy 248.901317 -307.297181) (xy 248.925005 -307.347712)
			(xy 248.941083 -307.401154) (xy 248.949209 -307.456368) (xy 248.949718 -307.484272) (xy 248.949209 -307.512176)
			(xy 248.941083 -307.56739) (xy 248.925005 -307.620832) (xy 248.901317 -307.671363) (xy 248.870523 -307.717907)
			(xy 248.833281 -307.759471) (xy 248.790385 -307.79517) (xy 248.742747 -307.824243) (xy 248.691384 -307.84607)
			(xy 248.637391 -307.860186) (xy 248.581917 -307.866289) (xy 248.526146 -307.864251) (xy 248.471267 -307.854114)
			(xy 248.418447 -307.836095) (xy 248.368815 -307.810577) (xy 248.323427 -307.778105) (xy 248.28325 -307.73937)
			(xy 248.249142 -307.695198) (xy 248.221828 -307.64653) (xy 248.201892 -307.594404) (xy 248.189757 -307.539931)
			(xy 248.185684 -307.484272) (xy 243.886793 -307.484272) (xy 243.880139 -307.529488) (xy 243.864071 -307.582895)
			(xy 243.840399 -307.633392) (xy 243.809626 -307.679905) (xy 243.772409 -307.721442) (xy 243.729541 -307.757117)
			(xy 243.681935 -307.786171) (xy 243.630606 -307.807983) (xy 243.576649 -307.822089) (xy 243.521212 -307.828189)
			(xy 243.465478 -307.826152) (xy 243.410635 -307.816022) (xy 243.357851 -307.798015) (xy 243.308251 -307.772514)
			(xy 243.262893 -307.740063) (xy 243.222744 -307.701354) (xy 243.188658 -307.657211) (xy 243.161362 -307.608576)
			(xy 243.141439 -307.556485) (xy 243.129313 -307.502048) (xy 243.125242 -307.446426) (xy 232.697588 -307.446426)
			(xy 232.699051 -307.456368) (xy 232.69956 -307.484272) (xy 232.699051 -307.512176) (xy 232.690925 -307.56739)
			(xy 232.674847 -307.620832) (xy 232.651159 -307.671363) (xy 232.620365 -307.717907) (xy 232.583123 -307.759471)
			(xy 232.540227 -307.79517) (xy 232.492589 -307.824243) (xy 232.441226 -307.84607) (xy 232.387233 -307.860186)
			(xy 232.331759 -307.866289) (xy 232.275988 -307.864251) (xy 232.221109 -307.854114) (xy 232.168289 -307.836095)
			(xy 232.118657 -307.810577) (xy 232.073269 -307.778105) (xy 232.033092 -307.73937) (xy 231.998984 -307.695198)
			(xy 231.97167 -307.64653) (xy 231.951734 -307.594404) (xy 231.939599 -307.539931) (xy 231.935526 -307.484272)
			(xy 227.636635 -307.484272) (xy 227.629981 -307.529488) (xy 227.613913 -307.582895) (xy 227.590241 -307.633392)
			(xy 227.559468 -307.679905) (xy 227.522251 -307.721442) (xy 227.479383 -307.757117) (xy 227.431777 -307.786171)
			(xy 227.380448 -307.807983) (xy 227.326491 -307.822089) (xy 227.271054 -307.828189) (xy 227.21532 -307.826152)
			(xy 227.160477 -307.816022) (xy 227.107693 -307.798015) (xy 227.058093 -307.772514) (xy 227.012735 -307.740063)
			(xy 226.972586 -307.701354) (xy 226.9385 -307.657211) (xy 226.911204 -307.608576) (xy 226.891281 -307.556485)
			(xy 226.879155 -307.502048) (xy 226.875084 -307.446426) (xy 220.721936 -307.446426) (xy 220.595952 -307.57241)
			(xy 220.588586 -307.579522) (xy 220.580966 -307.598318) (xy 220.580966 -308.402228) (xy 227.932994 -308.402228)
			(xy 227.937065 -308.346606) (xy 227.949191 -308.292169) (xy 227.969114 -308.240078) (xy 227.99641 -308.191443)
			(xy 228.030496 -308.1473) (xy 228.070645 -308.108591) (xy 228.116003 -308.07614) (xy 228.165603 -308.050639)
			(xy 228.218387 -308.032632) (xy 228.27323 -308.022502) (xy 228.328964 -308.020465) (xy 228.384401 -308.026565)
			(xy 228.438358 -308.040671) (xy 228.489687 -308.062483) (xy 228.537293 -308.091537) (xy 228.580161 -308.127212)
			(xy 228.617378 -308.168749) (xy 228.648151 -308.215262) (xy 228.671823 -308.265759) (xy 228.687891 -308.319166)
			(xy 228.696011 -308.374342) (xy 228.69652 -308.402228) (xy 228.696011 -308.430114) (xy 228.687891 -308.48529)
			(xy 228.671823 -308.538697) (xy 228.657687 -308.568852) (xy 231.935526 -308.568852) (xy 231.939599 -308.513193)
			(xy 231.951734 -308.45872) (xy 231.97167 -308.406594) (xy 231.998984 -308.357926) (xy 232.033092 -308.313754)
			(xy 232.073269 -308.275019) (xy 232.118657 -308.242547) (xy 232.168289 -308.217029) (xy 232.221109 -308.19901)
			(xy 232.275988 -308.188873) (xy 232.331759 -308.186835) (xy 232.387233 -308.192938) (xy 232.441226 -308.207054)
			(xy 232.492589 -308.228881) (xy 232.540227 -308.257954) (xy 232.583123 -308.293653) (xy 232.620365 -308.335217)
			(xy 232.651159 -308.381761) (xy 232.660754 -308.402228) (xy 244.183152 -308.402228) (xy 244.187223 -308.346606)
			(xy 244.199349 -308.292169) (xy 244.219272 -308.240078) (xy 244.246568 -308.191443) (xy 244.280654 -308.1473)
			(xy 244.320803 -308.108591) (xy 244.366161 -308.07614) (xy 244.415761 -308.050639) (xy 244.468545 -308.032632)
			(xy 244.523388 -308.022502) (xy 244.579122 -308.020465) (xy 244.634559 -308.026565) (xy 244.688516 -308.040671)
			(xy 244.739845 -308.062483) (xy 244.787451 -308.091537) (xy 244.830319 -308.127212) (xy 244.867536 -308.168749)
			(xy 244.898309 -308.215262) (xy 244.921981 -308.265759) (xy 244.938049 -308.319166) (xy 244.946169 -308.374342)
			(xy 244.946678 -308.402228) (xy 244.946169 -308.430114) (xy 244.938049 -308.48529) (xy 244.921981 -308.538697)
			(xy 244.907845 -308.568852) (xy 248.185684 -308.568852) (xy 248.189757 -308.513193) (xy 248.201892 -308.45872)
			(xy 248.221828 -308.406594) (xy 248.249142 -308.357926) (xy 248.28325 -308.313754) (xy 248.323427 -308.275019)
			(xy 248.368815 -308.242547) (xy 248.418447 -308.217029) (xy 248.471267 -308.19901) (xy 248.526146 -308.188873)
			(xy 248.581917 -308.186835) (xy 248.637391 -308.192938) (xy 248.691384 -308.207054) (xy 248.742747 -308.228881)
			(xy 248.790385 -308.257954) (xy 248.833281 -308.293653) (xy 248.870523 -308.335217) (xy 248.901317 -308.381761)
			(xy 248.925005 -308.432292) (xy 248.941083 -308.485734) (xy 248.949209 -308.540948) (xy 248.949718 -308.568852)
			(xy 248.949209 -308.596756) (xy 248.941083 -308.65197) (xy 248.925005 -308.705412) (xy 248.901317 -308.755943)
			(xy 248.870523 -308.802487) (xy 248.833281 -308.844051) (xy 248.790385 -308.87975) (xy 248.742747 -308.908823)
			(xy 248.691384 -308.93065) (xy 248.637391 -308.944766) (xy 248.581917 -308.950869) (xy 248.526146 -308.948831)
			(xy 248.471267 -308.938694) (xy 248.418447 -308.920675) (xy 248.368815 -308.895157) (xy 248.323427 -308.862685)
			(xy 248.28325 -308.82395) (xy 248.249142 -308.779778) (xy 248.221828 -308.73111) (xy 248.201892 -308.678984)
			(xy 248.189757 -308.624511) (xy 248.185684 -308.568852) (xy 244.907845 -308.568852) (xy 244.898309 -308.589194)
			(xy 244.867536 -308.635707) (xy 244.830319 -308.677244) (xy 244.787451 -308.712919) (xy 244.739845 -308.741973)
			(xy 244.688516 -308.763785) (xy 244.634559 -308.777891) (xy 244.579122 -308.783991) (xy 244.523388 -308.781954)
			(xy 244.468545 -308.771824) (xy 244.415761 -308.753817) (xy 244.366161 -308.728316) (xy 244.320803 -308.695865)
			(xy 244.280654 -308.657156) (xy 244.246568 -308.613013) (xy 244.219272 -308.564378) (xy 244.199349 -308.512287)
			(xy 244.187223 -308.45785) (xy 244.183152 -308.402228) (xy 232.660754 -308.402228) (xy 232.674847 -308.432292)
			(xy 232.690925 -308.485734) (xy 232.699051 -308.540948) (xy 232.69956 -308.568852) (xy 232.699051 -308.596756)
			(xy 232.690925 -308.65197) (xy 232.674847 -308.705412) (xy 232.651159 -308.755943) (xy 232.620365 -308.802487)
			(xy 232.583123 -308.844051) (xy 232.540227 -308.87975) (xy 232.492589 -308.908823) (xy 232.441226 -308.93065)
			(xy 232.387233 -308.944766) (xy 232.331759 -308.950869) (xy 232.275988 -308.948831) (xy 232.221109 -308.938694)
			(xy 232.168289 -308.920675) (xy 232.118657 -308.895157) (xy 232.073269 -308.862685) (xy 232.033092 -308.82395)
			(xy 231.998984 -308.779778) (xy 231.97167 -308.73111) (xy 231.951734 -308.678984) (xy 231.939599 -308.624511)
			(xy 231.935526 -308.568852) (xy 228.657687 -308.568852) (xy 228.648151 -308.589194) (xy 228.617378 -308.635707)
			(xy 228.580161 -308.677244) (xy 228.537293 -308.712919) (xy 228.489687 -308.741973) (xy 228.438358 -308.763785)
			(xy 228.384401 -308.777891) (xy 228.328964 -308.783991) (xy 228.27323 -308.781954) (xy 228.218387 -308.771824)
			(xy 228.165603 -308.753817) (xy 228.116003 -308.728316) (xy 228.070645 -308.695865) (xy 228.030496 -308.657156)
			(xy 227.99641 -308.613013) (xy 227.969114 -308.564378) (xy 227.949191 -308.512287) (xy 227.937065 -308.45785)
			(xy 227.932994 -308.402228) (xy 220.580966 -308.402228) (xy 220.580966 -309.018178) (xy 229.941118 -309.018178)
			(xy 229.945189 -308.962556) (xy 229.957315 -308.908119) (xy 229.977238 -308.856028) (xy 230.004534 -308.807393)
			(xy 230.03862 -308.76325) (xy 230.078769 -308.724541) (xy 230.124127 -308.69209) (xy 230.173727 -308.666589)
			(xy 230.226511 -308.648582) (xy 230.281354 -308.638452) (xy 230.337088 -308.636415) (xy 230.392525 -308.642515)
			(xy 230.446482 -308.656621) (xy 230.497811 -308.678433) (xy 230.545417 -308.707487) (xy 230.588285 -308.743162)
			(xy 230.625502 -308.784699) (xy 230.656275 -308.831212) (xy 230.679947 -308.881709) (xy 230.696015 -308.935116)
			(xy 230.704135 -308.990292) (xy 230.704644 -309.018178) (xy 246.191276 -309.018178) (xy 246.195347 -308.962556)
			(xy 246.207473 -308.908119) (xy 246.227396 -308.856028) (xy 246.254692 -308.807393) (xy 246.288778 -308.76325)
			(xy 246.328927 -308.724541) (xy 246.374285 -308.69209) (xy 246.423885 -308.666589) (xy 246.476669 -308.648582)
			(xy 246.531512 -308.638452) (xy 246.587246 -308.636415) (xy 246.642683 -308.642515) (xy 246.69664 -308.656621)
			(xy 246.747969 -308.678433) (xy 246.795575 -308.707487) (xy 246.838443 -308.743162) (xy 246.87566 -308.784699)
			(xy 246.906433 -308.831212) (xy 246.930105 -308.881709) (xy 246.946173 -308.935116) (xy 246.954293 -308.990292)
			(xy 246.954802 -309.018178) (xy 246.954293 -309.046064) (xy 246.946173 -309.10124) (xy 246.930105 -309.154647)
			(xy 246.906433 -309.205144) (xy 246.87566 -309.251657) (xy 246.838443 -309.293194) (xy 246.795575 -309.328869)
			(xy 246.747969 -309.357923) (xy 246.69664 -309.379735) (xy 246.642683 -309.393841) (xy 246.587246 -309.399941)
			(xy 246.531512 -309.397904) (xy 246.476669 -309.387774) (xy 246.423885 -309.369767) (xy 246.374285 -309.344266)
			(xy 246.328927 -309.311815) (xy 246.288778 -309.273106) (xy 246.254692 -309.228963) (xy 246.227396 -309.180328)
			(xy 246.207473 -309.128237) (xy 246.195347 -309.0738) (xy 246.191276 -309.018178) (xy 230.704644 -309.018178)
			(xy 230.704135 -309.046064) (xy 230.696015 -309.10124) (xy 230.679947 -309.154647) (xy 230.656275 -309.205144)
			(xy 230.625502 -309.251657) (xy 230.588285 -309.293194) (xy 230.545417 -309.328869) (xy 230.497811 -309.357923)
			(xy 230.446482 -309.379735) (xy 230.392525 -309.393841) (xy 230.337088 -309.399941) (xy 230.281354 -309.397904)
			(xy 230.226511 -309.387774) (xy 230.173727 -309.369767) (xy 230.124127 -309.344266) (xy 230.078769 -309.311815)
			(xy 230.03862 -309.273106) (xy 230.004534 -309.228963) (xy 229.977238 -309.180328) (xy 229.957315 -309.128237)
			(xy 229.945189 -309.0738) (xy 229.941118 -309.018178) (xy 220.580966 -309.018178) (xy 220.580966 -309.908448)
			(xy 226.32111 -309.908448) (xy 226.325181 -309.852826) (xy 226.337307 -309.798389) (xy 226.35723 -309.746298)
			(xy 226.384526 -309.697663) (xy 226.418612 -309.65352) (xy 226.458761 -309.614811) (xy 226.504119 -309.58236)
			(xy 226.553719 -309.556859) (xy 226.606503 -309.538852) (xy 226.661346 -309.528722) (xy 226.71708 -309.526685)
			(xy 226.772517 -309.532785) (xy 226.826474 -309.546891) (xy 226.877803 -309.568703) (xy 226.925409 -309.597757)
			(xy 226.968277 -309.633432) (xy 227.005494 -309.674969) (xy 227.036267 -309.721482) (xy 227.047351 -309.745126)
			(xy 228.036626 -309.745126) (xy 228.040697 -309.689504) (xy 228.052823 -309.635067) (xy 228.072746 -309.582976)
			(xy 228.100042 -309.534341) (xy 228.134128 -309.490198) (xy 228.174277 -309.451489) (xy 228.219635 -309.419038)
			(xy 228.269235 -309.393537) (xy 228.322019 -309.37553) (xy 228.376862 -309.3654) (xy 228.432596 -309.363363)
			(xy 228.488033 -309.369463) (xy 228.54199 -309.383569) (xy 228.593319 -309.405381) (xy 228.640925 -309.434435)
			(xy 228.683793 -309.47011) (xy 228.72101 -309.511647) (xy 228.751783 -309.55816) (xy 228.775455 -309.608657)
			(xy 228.791523 -309.662064) (xy 228.799643 -309.71724) (xy 228.800152 -309.745126) (xy 228.799643 -309.773012)
			(xy 228.791523 -309.828188) (xy 228.775455 -309.881595) (xy 228.751783 -309.932092) (xy 228.72101 -309.978605)
			(xy 228.683793 -310.020142) (xy 228.640925 -310.055817) (xy 228.593319 -310.084871) (xy 228.54199 -310.106683)
			(xy 228.488033 -310.120789) (xy 228.432596 -310.126889) (xy 228.376862 -310.124852) (xy 228.322019 -310.114722)
			(xy 228.269235 -310.096715) (xy 228.219635 -310.071214) (xy 228.174277 -310.038763) (xy 228.134128 -310.000054)
			(xy 228.100042 -309.955911) (xy 228.072746 -309.907276) (xy 228.052823 -309.855185) (xy 228.040697 -309.800748)
			(xy 228.036626 -309.745126) (xy 227.047351 -309.745126) (xy 227.059939 -309.771979) (xy 227.076007 -309.825386)
			(xy 227.084127 -309.880562) (xy 227.084636 -309.908448) (xy 227.084127 -309.936334) (xy 227.076007 -309.99151)
			(xy 227.059939 -310.044917) (xy 227.036267 -310.095414) (xy 227.005494 -310.141927) (xy 226.999624 -310.148478)
			(xy 231.719118 -310.148478) (xy 231.723189 -310.092856) (xy 231.735315 -310.038419) (xy 231.755238 -309.986328)
			(xy 231.782534 -309.937693) (xy 231.81662 -309.89355) (xy 231.856769 -309.854841) (xy 231.902127 -309.82239)
			(xy 231.951727 -309.796889) (xy 232.004511 -309.778882) (xy 232.059354 -309.768752) (xy 232.115088 -309.766715)
			(xy 232.170525 -309.772815) (xy 232.224482 -309.786921) (xy 232.275811 -309.808733) (xy 232.323417 -309.837787)
			(xy 232.366285 -309.873462) (xy 232.397632 -309.908448) (xy 242.571268 -309.908448) (xy 242.575339 -309.852826)
			(xy 242.587465 -309.798389) (xy 242.607388 -309.746298) (xy 242.634684 -309.697663) (xy 242.66877 -309.65352)
			(xy 242.708919 -309.614811) (xy 242.754277 -309.58236) (xy 242.803877 -309.556859) (xy 242.856661 -309.538852)
			(xy 242.911504 -309.528722) (xy 242.967238 -309.526685) (xy 243.022675 -309.532785) (xy 243.076632 -309.546891)
			(xy 243.127961 -309.568703) (xy 243.175567 -309.597757) (xy 243.218435 -309.633432) (xy 243.255652 -309.674969)
			(xy 243.286425 -309.721482) (xy 243.297509 -309.745126) (xy 244.286784 -309.745126) (xy 244.290855 -309.689504)
			(xy 244.302981 -309.635067) (xy 244.322904 -309.582976) (xy 244.3502 -309.534341) (xy 244.384286 -309.490198)
			(xy 244.424435 -309.451489) (xy 244.469793 -309.419038) (xy 244.519393 -309.393537) (xy 244.572177 -309.37553)
			(xy 244.62702 -309.3654) (xy 244.682754 -309.363363) (xy 244.738191 -309.369463) (xy 244.792148 -309.383569)
			(xy 244.843477 -309.405381) (xy 244.891083 -309.434435) (xy 244.933951 -309.47011) (xy 244.971168 -309.511647)
			(xy 245.001941 -309.55816) (xy 245.025613 -309.608657) (xy 245.041681 -309.662064) (xy 245.049801 -309.71724)
			(xy 245.05031 -309.745126) (xy 245.049801 -309.773012) (xy 245.041681 -309.828188) (xy 245.025613 -309.881595)
			(xy 245.001941 -309.932092) (xy 244.971168 -309.978605) (xy 244.933951 -310.020142) (xy 244.891083 -310.055817)
			(xy 244.843477 -310.084871) (xy 244.792148 -310.106683) (xy 244.738191 -310.120789) (xy 244.682754 -310.126889)
			(xy 244.62702 -310.124852) (xy 244.572177 -310.114722) (xy 244.519393 -310.096715) (xy 244.469793 -310.071214)
			(xy 244.424435 -310.038763) (xy 244.384286 -310.000054) (xy 244.3502 -309.955911) (xy 244.322904 -309.907276)
			(xy 244.302981 -309.855185) (xy 244.290855 -309.800748) (xy 244.286784 -309.745126) (xy 243.297509 -309.745126)
			(xy 243.310097 -309.771979) (xy 243.326165 -309.825386) (xy 243.334285 -309.880562) (xy 243.334794 -309.908448)
			(xy 243.334285 -309.936334) (xy 243.326165 -309.99151) (xy 243.310097 -310.044917) (xy 243.286425 -310.095414)
			(xy 243.255652 -310.141927) (xy 243.218435 -310.183464) (xy 243.196075 -310.202072) (xy 248.072908 -310.202072)
			(xy 248.076979 -310.14645) (xy 248.089105 -310.092013) (xy 248.109028 -310.039922) (xy 248.136324 -309.991287)
			(xy 248.17041 -309.947144) (xy 248.210559 -309.908435) (xy 248.255917 -309.875984) (xy 248.305517 -309.850483)
			(xy 248.358301 -309.832476) (xy 248.413144 -309.822346) (xy 248.468878 -309.820309) (xy 248.524315 -309.826409)
			(xy 248.578272 -309.840515) (xy 248.629601 -309.862327) (xy 248.677207 -309.891381) (xy 248.720075 -309.927056)
			(xy 248.757292 -309.968593) (xy 248.788065 -310.015106) (xy 248.811737 -310.065603) (xy 248.827805 -310.11901)
			(xy 248.835925 -310.174186) (xy 248.836434 -310.202072) (xy 248.835925 -310.229958) (xy 248.827805 -310.285134)
			(xy 248.811737 -310.338541) (xy 248.788065 -310.389038) (xy 248.757292 -310.435551) (xy 248.720075 -310.477088)
			(xy 248.677207 -310.512763) (xy 248.629601 -310.541817) (xy 248.578272 -310.563629) (xy 248.524315 -310.577735)
			(xy 248.468878 -310.583835) (xy 248.413144 -310.581798) (xy 248.358301 -310.571668) (xy 248.305517 -310.553661)
			(xy 248.255917 -310.52816) (xy 248.210559 -310.495709) (xy 248.17041 -310.457) (xy 248.136324 -310.412857)
			(xy 248.109028 -310.364222) (xy 248.089105 -310.312131) (xy 248.076979 -310.257694) (xy 248.072908 -310.202072)
			(xy 243.196075 -310.202072) (xy 243.175567 -310.219139) (xy 243.127961 -310.248193) (xy 243.076632 -310.270005)
			(xy 243.022675 -310.284111) (xy 242.967238 -310.290211) (xy 242.911504 -310.288174) (xy 242.856661 -310.278044)
			(xy 242.803877 -310.260037) (xy 242.754277 -310.234536) (xy 242.708919 -310.202085) (xy 242.66877 -310.163376)
			(xy 242.634684 -310.119233) (xy 242.607388 -310.070598) (xy 242.587465 -310.018507) (xy 242.575339 -309.96407)
			(xy 242.571268 -309.908448) (xy 232.397632 -309.908448) (xy 232.403502 -309.914999) (xy 232.434275 -309.961512)
			(xy 232.457947 -310.012009) (xy 232.474015 -310.065416) (xy 232.482135 -310.120592) (xy 232.482644 -310.148478)
			(xy 232.482135 -310.176364) (xy 232.474015 -310.23154) (xy 232.457947 -310.284947) (xy 232.434275 -310.335444)
			(xy 232.403502 -310.381957) (xy 232.366285 -310.423494) (xy 232.323417 -310.459169) (xy 232.275811 -310.488223)
			(xy 232.224482 -310.510035) (xy 232.170525 -310.524141) (xy 232.115088 -310.530241) (xy 232.059354 -310.528204)
			(xy 232.004511 -310.518074) (xy 231.951727 -310.500067) (xy 231.902127 -310.474566) (xy 231.856769 -310.442115)
			(xy 231.81662 -310.403406) (xy 231.782534 -310.359263) (xy 231.755238 -310.310628) (xy 231.735315 -310.258537)
			(xy 231.723189 -310.2041) (xy 231.719118 -310.148478) (xy 226.999624 -310.148478) (xy 226.968277 -310.183464)
			(xy 226.925409 -310.219139) (xy 226.877803 -310.248193) (xy 226.826474 -310.270005) (xy 226.772517 -310.284111)
			(xy 226.71708 -310.290211) (xy 226.661346 -310.288174) (xy 226.606503 -310.278044) (xy 226.553719 -310.260037)
			(xy 226.504119 -310.234536) (xy 226.458761 -310.202085) (xy 226.418612 -310.163376) (xy 226.384526 -310.119233)
			(xy 226.35723 -310.070598) (xy 226.337307 -310.018507) (xy 226.325181 -309.96407) (xy 226.32111 -309.908448)
			(xy 220.580966 -309.908448) (xy 220.580966 -310.203596) (xy 220.582744 -310.2102) (xy 220.6036 -310.289213)
			(xy 220.639209 -310.448724) (xy 220.664462 -310.590946) (xy 230.918764 -310.590946) (xy 230.922835 -310.535324)
			(xy 230.934961 -310.480887) (xy 230.954884 -310.428796) (xy 230.98218 -310.380161) (xy 231.016266 -310.336018)
			(xy 231.056415 -310.297309) (xy 231.101773 -310.264858) (xy 231.151373 -310.239357) (xy 231.204157 -310.22135)
			(xy 231.259 -310.21122) (xy 231.314734 -310.209183) (xy 231.370171 -310.215283) (xy 231.424128 -310.229389)
			(xy 231.475457 -310.251201) (xy 231.523063 -310.280255) (xy 231.565931 -310.31593) (xy 231.603148 -310.357467)
			(xy 231.633921 -310.40398) (xy 231.657593 -310.454477) (xy 231.673661 -310.507884) (xy 231.681781 -310.56306)
			(xy 231.68229 -310.590946) (xy 231.681781 -310.618832) (xy 231.673661 -310.674008) (xy 231.657593 -310.727415)
			(xy 231.633921 -310.777912) (xy 231.603148 -310.824425) (xy 231.565931 -310.865962) (xy 231.523063 -310.901637)
			(xy 231.475457 -310.930691) (xy 231.424128 -310.952503) (xy 231.370171 -310.966609) (xy 231.314734 -310.972709)
			(xy 231.259 -310.970672) (xy 231.204157 -310.960542) (xy 231.151373 -310.942535) (xy 231.101773 -310.917034)
			(xy 231.056415 -310.884583) (xy 231.016266 -310.845874) (xy 230.98218 -310.801731) (xy 230.954884 -310.753096)
			(xy 230.934961 -310.701005) (xy 230.922835 -310.646568) (xy 230.918764 -310.590946) (xy 220.664462 -310.590946)
			(xy 220.667782 -310.609643) (xy 220.689263 -310.771662) (xy 220.703613 -310.934467) (xy 220.710802 -311.097746)
			(xy 220.711268 -311.179464) (xy 220.711268 -311.179972) (xy 220.711065 -311.215786) (xy 227.498908 -311.215786)
			(xy 227.502979 -311.160164) (xy 227.515105 -311.105727) (xy 227.535028 -311.053636) (xy 227.562324 -311.005001)
			(xy 227.59641 -310.960858) (xy 227.636559 -310.922149) (xy 227.681917 -310.889698) (xy 227.731517 -310.864197)
			(xy 227.784301 -310.84619) (xy 227.839144 -310.83606) (xy 227.894878 -310.834023) (xy 227.950315 -310.840123)
			(xy 228.004272 -310.854229) (xy 228.055601 -310.876041) (xy 228.103207 -310.905095) (xy 228.146075 -310.94077)
			(xy 228.183292 -310.982307) (xy 228.214065 -311.02882) (xy 228.237737 -311.079317) (xy 228.253805 -311.132724)
			(xy 228.261925 -311.1879) (xy 228.262434 -311.215786) (xy 228.261925 -311.243672) (xy 228.253805 -311.298848)
			(xy 228.237737 -311.352255) (xy 228.214065 -311.402752) (xy 228.183292 -311.449265) (xy 228.146075 -311.490802)
			(xy 228.103207 -311.526477) (xy 228.055601 -311.555531) (xy 228.025463 -311.568338) (xy 229.820468 -311.568338)
			(xy 229.824539 -311.512716) (xy 229.836665 -311.458279) (xy 229.856588 -311.406188) (xy 229.883884 -311.357553)
			(xy 229.91797 -311.31341) (xy 229.958119 -311.274701) (xy 230.003477 -311.24225) (xy 230.053077 -311.216749)
			(xy 230.105861 -311.198742) (xy 230.160704 -311.188612) (xy 230.216438 -311.186575) (xy 230.271875 -311.192675)
			(xy 230.325832 -311.206781) (xy 230.347023 -311.215786) (xy 243.749066 -311.215786) (xy 243.753137 -311.160164)
			(xy 243.765263 -311.105727) (xy 243.785186 -311.053636) (xy 243.812482 -311.005001) (xy 243.846568 -310.960858)
			(xy 243.886717 -310.922149) (xy 243.932075 -310.889698) (xy 243.981675 -310.864197) (xy 244.034459 -310.84619)
			(xy 244.089302 -310.83606) (xy 244.145036 -310.834023) (xy 244.200473 -310.840123) (xy 244.25443 -310.854229)
			(xy 244.305759 -310.876041) (xy 244.353365 -310.905095) (xy 244.396233 -310.94077) (xy 244.43345 -310.982307)
			(xy 244.464223 -311.02882) (xy 244.487895 -311.079317) (xy 244.503963 -311.132724) (xy 244.512083 -311.1879)
			(xy 244.512592 -311.215786) (xy 244.512083 -311.243672) (xy 244.503963 -311.298848) (xy 244.487895 -311.352255)
			(xy 244.464223 -311.402752) (xy 244.43345 -311.449265) (xy 244.396233 -311.490802) (xy 244.353365 -311.526477)
			(xy 244.305759 -311.555531) (xy 244.25443 -311.577343) (xy 244.200473 -311.591449) (xy 244.145036 -311.597549)
			(xy 244.089302 -311.595512) (xy 244.034459 -311.585382) (xy 243.981675 -311.567375) (xy 243.932075 -311.541874)
			(xy 243.886717 -311.509423) (xy 243.846568 -311.470714) (xy 243.812482 -311.426571) (xy 243.785186 -311.377936)
			(xy 243.765263 -311.325845) (xy 243.753137 -311.271408) (xy 243.749066 -311.215786) (xy 230.347023 -311.215786)
			(xy 230.377161 -311.228593) (xy 230.424767 -311.257647) (xy 230.467635 -311.293322) (xy 230.504852 -311.334859)
			(xy 230.535625 -311.381372) (xy 230.559297 -311.431869) (xy 230.575365 -311.485276) (xy 230.583485 -311.540452)
			(xy 230.583994 -311.568338) (xy 230.583485 -311.596224) (xy 230.575365 -311.6514) (xy 230.559297 -311.704807)
			(xy 230.535625 -311.755304) (xy 230.504852 -311.801817) (xy 230.467635 -311.843354) (xy 230.424767 -311.879029)
			(xy 230.377161 -311.908083) (xy 230.325832 -311.929895) (xy 230.271875 -311.944001) (xy 230.216438 -311.950101)
			(xy 230.160704 -311.948064) (xy 230.105861 -311.937934) (xy 230.053077 -311.919927) (xy 230.003477 -311.894426)
			(xy 229.958119 -311.861975) (xy 229.91797 -311.823266) (xy 229.883884 -311.779123) (xy 229.856588 -311.730488)
			(xy 229.836665 -311.678397) (xy 229.824539 -311.62396) (xy 229.820468 -311.568338) (xy 228.025463 -311.568338)
			(xy 228.004272 -311.577343) (xy 227.950315 -311.591449) (xy 227.894878 -311.597549) (xy 227.839144 -311.595512)
			(xy 227.784301 -311.585382) (xy 227.731517 -311.567375) (xy 227.681917 -311.541874) (xy 227.636559 -311.509423)
			(xy 227.59641 -311.470714) (xy 227.562324 -311.426571) (xy 227.535028 -311.377936) (xy 227.515105 -311.325845)
			(xy 227.502979 -311.271408) (xy 227.498908 -311.215786) (xy 220.711065 -311.215786) (xy 220.71078 -311.26594)
			(xy 220.70284 -311.437691) (xy 220.686977 -311.608893) (xy 220.663225 -311.77918) (xy 220.631633 -311.948188)
			(xy 220.592269 -312.115556) (xy 220.545218 -312.280928) (xy 220.49058 -312.443951) (xy 220.428471 -312.604276)
			(xy 220.359024 -312.761562) (xy 220.282386 -312.915472) (xy 220.198723 -313.065679) (xy 220.170107 -313.111896)
			(xy 230.52354 -313.111896) (xy 230.527611 -313.056274) (xy 230.539737 -313.001837) (xy 230.55966 -312.949746)
			(xy 230.586956 -312.901111) (xy 230.621042 -312.856968) (xy 230.661191 -312.818259) (xy 230.706549 -312.785808)
			(xy 230.756149 -312.760307) (xy 230.808933 -312.7423) (xy 230.863776 -312.73217) (xy 230.91951 -312.730133)
			(xy 230.974947 -312.736233) (xy 231.028904 -312.750339) (xy 231.080233 -312.772151) (xy 231.127839 -312.801205)
			(xy 231.170707 -312.83688) (xy 231.207924 -312.878417) (xy 231.238697 -312.92493) (xy 231.262369 -312.975427)
			(xy 231.278437 -313.028834) (xy 231.286557 -313.08401) (xy 231.287066 -313.111896) (xy 231.286557 -313.139782)
			(xy 231.278437 -313.194958) (xy 231.262369 -313.248365) (xy 231.238697 -313.298862) (xy 231.207924 -313.345375)
			(xy 231.170707 -313.386912) (xy 231.127839 -313.422587) (xy 231.080233 -313.451641) (xy 231.028904 -313.473453)
			(xy 230.974947 -313.487559) (xy 230.91951 -313.493659) (xy 230.863776 -313.491622) (xy 230.808933 -313.481492)
			(xy 230.756149 -313.463485) (xy 230.706549 -313.437984) (xy 230.661191 -313.405533) (xy 230.621042 -313.366824)
			(xy 230.586956 -313.322681) (xy 230.55966 -313.274046) (xy 230.539737 -313.221955) (xy 230.527611 -313.167518)
			(xy 230.52354 -313.111896) (xy 220.170107 -313.111896) (xy 220.108212 -313.211862) (xy 220.011046 -313.353709)
			(xy 219.907432 -313.490917) (xy 219.797593 -313.623193) (xy 219.681762 -313.750255) (xy 219.560186 -313.871833)
			(xy 219.433125 -313.987665) (xy 219.30085 -314.097506) (xy 219.163643 -314.201121) (xy 219.021797 -314.298289)
			(xy 218.875616 -314.388802) (xy 218.72541 -314.472467) (xy 218.5715 -314.549106) (xy 218.414215 -314.618555)
			(xy 218.25389 -314.680666) (xy 218.090868 -314.735306) (xy 217.925497 -314.782359) (xy 217.758129 -314.821724)
			(xy 217.589121 -314.853318) (xy 217.418835 -314.877073) (xy 217.247633 -314.892937) (xy 217.075882 -314.900879)
			(xy 216.989914 -314.901326) (xy 216.904249 -314.900835) (xy 216.7331 -314.892946) (xy 216.562496 -314.87719)
			(xy 216.392797 -314.853599) (xy 216.224364 -314.822224) (xy 216.057553 -314.783131) (xy 215.892718 -314.736403)
			(xy 215.730208 -314.682139) (xy 215.570368 -314.620453) (xy 215.413535 -314.551478) (xy 215.260043 -314.475358)
			(xy 215.110216 -314.392255) (xy 214.964373 -314.302345) (xy 214.822821 -314.205819) (xy 214.685862 -314.102881)
			(xy 214.553785 -313.993749) (xy 214.42687 -313.878655) (xy 214.305386 -313.757842) (xy 214.18959 -313.631566)
			(xy 214.079729 -313.500096) (xy 213.976033 -313.363709) (xy 213.878725 -313.222694) (xy 213.788008 -313.077351)
			(xy 213.704076 -312.927987) (xy 213.627107 -312.774919) (xy 213.557264 -312.618471) (xy 213.494694 -312.458974)
			(xy 213.43953 -312.296768) (xy 213.39189 -312.132194) (xy 213.351873 -311.965602) (xy 213.319566 -311.797346)
			(xy 213.295035 -311.62778) (xy 213.278334 -311.457266) (xy 213.273386 -311.371742) (xy 213.272878 -311.361582)
			(xy 213.263734 -311.342278) (xy 213.259283 -311.333814) (xy 213.245339 -311.320748) (xy 213.227568 -311.313721)
			(xy 213.218014 -311.313322) (xy 207.531208 -311.313322) (xy 207.521337 -311.313796) (xy 207.50306 -311.32126)
			(xy 207.495648 -311.3278) (xy 207.451452 -311.370726) (xy 207.44815 -311.373774) (xy 207.434942 -311.391554)
			(xy 207.432402 -311.399682) (xy 207.429608 -311.408064) (xy 207.429354 -311.416954) (xy 207.427322 -311.447942)
			(xy 207.427322 -311.448196) (xy 207.426814 -311.453276) (xy 207.423258 -311.475882) (xy 207.420972 -311.488328)
			(xy 207.428338 -311.51195) (xy 207.459326 -311.542938) (xy 207.466554 -311.549575) (xy 207.484586 -311.557271)
			(xy 207.494378 -311.557924) (xy 207.508856 -311.558178) (xy 207.514952 -311.556908) (xy 207.538127 -311.551926)
			(xy 207.58523 -311.546582) (xy 207.608932 -311.54624) (xy 207.60944 -311.54624) (xy 207.639665 -311.546782)
			(xy 207.699498 -311.55539) (xy 207.757498 -311.572425) (xy 207.812483 -311.597541) (xy 207.863335 -311.630225)
			(xy 207.909017 -311.669814) (xy 207.948601 -311.715501) (xy 207.98128 -311.766356) (xy 208.00639 -311.821343)
			(xy 208.02342 -311.879345) (xy 208.032021 -311.939179) (xy 208.032604 -311.969404) (xy 208.032604 -311.97042)
			(xy 208.03248 -311.985074) (xy 208.030445 -312.01431) (xy 208.02854 -312.02884) (xy 208.027524 -312.035698)
			(xy 208.027524 -312.039762) (xy 208.027977 -312.049916) (xy 208.035844 -312.068638) (xy 208.042764 -312.076084)
			(xy 208.06791 -312.100722) (xy 208.08823 -312.108088) (xy 208.099406 -312.107072) (xy 208.132426 -312.105802)
			(xy 208.159675 -312.10629) (xy 208.213619 -312.114049) (xy 208.265909 -312.129406) (xy 208.315482 -312.152048)
			(xy 208.361327 -312.181514) (xy 208.402513 -312.217205) (xy 208.438201 -312.258393) (xy 208.467664 -312.304241)
			(xy 208.490303 -312.353815) (xy 208.505656 -312.406107) (xy 208.513412 -312.460051) (xy 208.513412 -312.514549)
			(xy 208.505656 -312.568493) (xy 208.490303 -312.620785) (xy 208.467664 -312.670359) (xy 208.438201 -312.716207)
			(xy 208.402513 -312.757395) (xy 208.361327 -312.793086) (xy 208.315482 -312.822552) (xy 208.265909 -312.845194)
			(xy 208.213619 -312.860551) (xy 208.159675 -312.86831) (xy 208.132426 -312.868818) (xy 208.105219 -312.868337)
			(xy 208.051358 -312.86061) (xy 207.99914 -312.845309) (xy 207.949627 -312.822743) (xy 207.903822 -312.793372)
			(xy 207.862654 -312.757791) (xy 207.826959 -312.716722) (xy 207.797462 -312.670998) (xy 207.77476 -312.621546)
			(xy 207.759315 -312.569371) (xy 207.751439 -312.515531) (xy 207.750918 -312.488326) (xy 207.750918 -312.48731)
			(xy 207.751934 -312.45937) (xy 207.751934 -312.45429) (xy 207.749902 -312.443622) (xy 207.748237 -312.436201)
			(xy 207.741119 -312.422769) (xy 207.735932 -312.417206) (xy 207.735424 -312.416698) (xy 207.71104 -312.392568)
			(xy 207.68818 -312.385202) (xy 207.675988 -312.387234) (xy 207.659652 -312.389697) (xy 207.626721 -312.392371)
			(xy 207.610202 -312.392568) (xy 207.60944 -312.392568) (xy 207.579209 -312.392057) (xy 207.519363 -312.383458)
			(xy 207.46135 -312.366429) (xy 207.406351 -312.341316) (xy 207.355486 -312.308632) (xy 207.30979 -312.269041)
			(xy 207.270195 -312.223349) (xy 207.237505 -312.172488) (xy 207.212387 -312.117491) (xy 207.195352 -312.05948)
			(xy 207.186746 -311.999634) (xy 207.186276 -311.969404) (xy 207.186276 -311.960006) (xy 207.18658 -311.9367)
			(xy 207.191671 -311.890366) (xy 207.196436 -311.86755) (xy 207.197706 -311.862216) (xy 207.197706 -311.855358)
			(xy 207.197276 -311.845291) (xy 207.189551 -311.826697) (xy 207.18272 -311.81929) (xy 207.161892 -311.798462)
			(xy 207.15478 -311.791096) (xy 207.135984 -311.783476) (xy 207.115918 -311.783476) (xy 207.1116 -311.784238)
			(xy 207.09578 -311.786736) (xy 207.063861 -311.789406) (xy 207.047846 -311.789572) (xy 207.040226 -311.789572)
			(xy 207.013595 -311.788579) (xy 206.960981 -311.780117) (xy 206.910057 -311.764416) (xy 206.861813 -311.741781)
			(xy 206.817188 -311.712652) (xy 206.777051 -311.677598) (xy 206.742182 -311.637299) (xy 206.713261 -311.592539)
			(xy 206.69085 -311.544191) (xy 206.675385 -311.493194) (xy 206.667167 -311.440542) (xy 206.666338 -311.413906)
			(xy 206.666084 -311.401206) (xy 206.656432 -311.382918) (xy 206.65059 -311.37733) (xy 206.601314 -311.328816)
			(xy 206.600806 -311.328308) (xy 206.593694 -311.321196) (xy 206.575152 -311.313322) (xy 199.426576 -311.313322)
			(xy 199.414134 -311.314012) (xy 199.39217 -311.325725) (xy 199.384666 -311.335674) (xy 199.33793 -311.404762)
			(xy 199.335644 -311.41289) (xy 199.335136 -311.414414) (xy 199.332342 -311.422542) (xy 199.332342 -311.442862)
			(xy 199.33412 -311.454038) (xy 199.335898 -311.461658) (xy 199.336914 -311.464452) (xy 199.340838 -311.475985)
			(xy 199.347196 -311.499503) (xy 199.349614 -311.511442) (xy 199.349868 -311.51195) (xy 199.350376 -311.51449)
			(xy 199.350376 -311.515252) (xy 199.351392 -311.52084) (xy 199.353509 -311.534266) (xy 199.355798 -311.561351)
			(xy 199.355964 -311.574942) (xy 199.355451 -311.600947) (xy 199.347309 -311.652316) (xy 199.331232 -311.701779)
			(xy 199.307615 -311.748118) (xy 199.277042 -311.790193) (xy 199.240263 -311.826968) (xy 199.198184 -311.857536)
			(xy 199.151842 -311.881147) (xy 199.102377 -311.897218) (xy 199.051007 -311.905354) (xy 199.025002 -311.905904)
			(xy 198.96963 -311.905904) (xy 198.950072 -311.91454) (xy 198.942706 -311.922668) (xy 198.89216 -311.978548)
			(xy 198.888768 -311.982553) (xy 198.883524 -311.991643) (xy 198.881746 -311.996582) (xy 198.87819 -312.006996)
			(xy 198.879206 -312.017918) (xy 198.880984 -312.049668) (xy 198.880984 -312.049922) (xy 198.880459 -312.075884)
			(xy 198.872309 -312.127166) (xy 198.856243 -312.176544) (xy 198.832657 -312.222804) (xy 198.802131 -312.264808)
			(xy 198.765415 -312.301526) (xy 198.723411 -312.332053) (xy 198.677151 -312.35564) (xy 198.627774 -312.371707)
			(xy 198.576492 -312.379858) (xy 198.55053 -312.380376) (xy 197.600062 -312.380376) (xy 197.574079 -312.379864)
			(xy 197.522754 -312.371729) (xy 197.473334 -312.355666) (xy 197.427034 -312.332071) (xy 197.384995 -312.301523)
			(xy 197.348252 -312.264776) (xy 197.317709 -312.222734) (xy 197.294119 -312.176431) (xy 197.278062 -312.127009)
			(xy 197.269933 -312.075683) (xy 197.269933 -312.023717) (xy 197.278062 -311.972391) (xy 197.294119 -311.922969)
			(xy 197.317709 -311.876666) (xy 197.348252 -311.834624) (xy 197.384995 -311.797877) (xy 197.427034 -311.767329)
			(xy 197.473334 -311.743734) (xy 197.522754 -311.727671) (xy 197.574079 -311.719536) (xy 197.600062 -311.71896)
			(xy 197.655434 -311.71896) (xy 197.674738 -311.710324) (xy 197.682104 -311.702196) (xy 197.732396 -311.646824)
			(xy 197.738442 -311.639649) (xy 197.745209 -311.622164) (xy 197.745604 -311.612788) (xy 197.745604 -311.6072)
			(xy 197.74535 -311.604914) (xy 197.74408 -311.574942) (xy 197.74408 -311.569608) (xy 197.745858 -311.540398)
			(xy 197.747128 -311.528714) (xy 197.739508 -311.507124) (xy 197.731126 -311.498996) (xy 197.667118 -311.435242)
			(xy 197.645782 -311.427622) (xy 197.634352 -311.428892) (xy 197.599554 -311.43067) (xy 197.573852 -311.430147)
			(xy 197.523078 -311.422116) (xy 197.474161 -311.406318) (xy 197.428281 -311.383134) (xy 197.386546 -311.353124)
			(xy 197.367906 -311.33542) (xy 197.361048 -311.328816) (xy 197.334378 -311.317386) (xy 197.324726 -311.313322)
			(xy 196.935344 -311.313322) (xy 196.930246 -311.31343) (xy 196.920257 -311.315469) (xy 196.915532 -311.317386)
			(xy 196.888862 -311.328816) (xy 196.88175 -311.335674) (xy 196.863084 -311.353371) (xy 196.821288 -311.383348)
			(xy 196.775351 -311.406483) (xy 196.726381 -311.422216) (xy 196.675565 -311.430166) (xy 196.649848 -311.43067)
			(xy 196.623178 -311.429654) (xy 196.622924 -311.429654) (xy 196.617082 -311.429146) (xy 196.616828 -311.429146)
			(xy 196.606241 -311.428678) (xy 196.586167 -311.435386) (xy 196.577966 -311.4421) (xy 196.52234 -311.492392)
			(xy 196.51483 -311.499936) (xy 196.506167 -311.519356) (xy 196.505576 -311.529984) (xy 196.505576 -311.574688)
			(xy 196.505094 -311.600677) (xy 196.496964 -311.652015) (xy 196.480902 -311.701449) (xy 196.457305 -311.747762)
			(xy 196.426752 -311.789812) (xy 196.389997 -311.826565) (xy 196.347945 -311.857115) (xy 196.301631 -311.88071)
			(xy 196.252196 -311.896768) (xy 196.200857 -311.904895) (xy 196.174868 -311.905396) (xy 196.142356 -311.903872)
			(xy 196.142102 -311.903872) (xy 196.131538 -311.903344) (xy 196.11146 -311.909914) (xy 196.10324 -311.916572)
			(xy 196.04736 -311.967118) (xy 196.042485 -311.971786) (xy 196.035155 -311.983114) (xy 196.032882 -311.98947)
			(xy 196.030596 -311.99709) (xy 196.030596 -312.049922) (xy 196.030086 -312.075909) (xy 196.021956 -312.127244)
			(xy 196.005895 -312.176674) (xy 195.982299 -312.222984) (xy 195.951749 -312.265032) (xy 195.914998 -312.301783)
			(xy 195.87295 -312.332333) (xy 195.82664 -312.355929) (xy 195.77721 -312.37199) (xy 195.725875 -312.38012)
			(xy 195.673901 -312.38012) (xy 195.622566 -312.37199) (xy 195.573136 -312.355929) (xy 195.526826 -312.332333)
			(xy 195.484778 -312.301783) (xy 195.448027 -312.265032) (xy 195.417477 -312.222984) (xy 195.393881 -312.176674)
			(xy 195.37782 -312.127244) (xy 195.36969 -312.075909) (xy 195.36918 -312.049922) (xy 195.36918 -311.364122)
			(xy 195.368764 -311.354099) (xy 195.361097 -311.335578) (xy 195.346923 -311.321404) (xy 195.328403 -311.313737)
			(xy 195.31838 -311.313322) (xy 195.035424 -311.313322) (xy 195.030326 -311.313432) (xy 195.020339 -311.315475)
			(xy 195.015612 -311.317386) (xy 194.988942 -311.328816) (xy 194.98183 -311.335674) (xy 194.963166 -311.353376)
			(xy 194.921372 -311.383363) (xy 194.875435 -311.406509) (xy 194.826466 -311.422253) (xy 194.775647 -311.430216)
			(xy 194.749928 -311.43067) (xy 194.723258 -311.429654) (xy 194.723004 -311.429654) (xy 194.717162 -311.429146)
			(xy 194.716908 -311.429146) (xy 194.706315 -311.428662) (xy 194.686219 -311.435346) (xy 194.678046 -311.4421)
			(xy 194.62242 -311.492392) (xy 194.614912 -311.499937) (xy 194.606253 -311.519356) (xy 194.605656 -311.529984)
			(xy 194.605656 -311.574688) (xy 194.605147 -311.600677) (xy 194.597019 -311.652016) (xy 194.580959 -311.701451)
			(xy 194.557365 -311.747766) (xy 194.526816 -311.78982) (xy 194.490065 -311.826577) (xy 194.448017 -311.857133)
			(xy 194.401707 -311.880736) (xy 194.352274 -311.896805) (xy 194.300937 -311.904943) (xy 194.274948 -311.905396)
			(xy 194.242436 -311.903872) (xy 194.242182 -311.903872) (xy 194.23162 -311.903348) (xy 194.211547 -311.909924)
			(xy 194.20332 -311.916572) (xy 194.14744 -311.967118) (xy 194.142567 -311.971787) (xy 194.135239 -311.983116)
			(xy 194.132962 -311.98947) (xy 194.130676 -311.99709) (xy 194.130676 -312.049922) (xy 194.130166 -312.075909)
			(xy 194.122036 -312.127244) (xy 194.105975 -312.176674) (xy 194.082379 -312.222984) (xy 194.051829 -312.265032)
			(xy 194.015078 -312.301783) (xy 193.97303 -312.332333) (xy 193.92672 -312.355929) (xy 193.87729 -312.37199)
			(xy 193.825955 -312.38012) (xy 193.773981 -312.38012) (xy 193.722646 -312.37199) (xy 193.673216 -312.355929)
			(xy 193.626906 -312.332333) (xy 193.584858 -312.301783) (xy 193.548107 -312.265032) (xy 193.517557 -312.222984)
			(xy 193.493961 -312.176674) (xy 193.4779 -312.127244) (xy 193.46977 -312.075909) (xy 193.46926 -312.049922)
			(xy 193.46926 -311.364122) (xy 193.468844 -311.354101) (xy 193.461176 -311.335583) (xy 193.447002 -311.321414)
			(xy 193.428481 -311.313753) (xy 193.41846 -311.313322) (xy 193.135504 -311.313322) (xy 193.130407 -311.313434)
			(xy 193.120421 -311.31548) (xy 193.115692 -311.317386) (xy 193.089022 -311.328816) (xy 193.08191 -311.335674)
			(xy 193.063245 -311.353375) (xy 193.021451 -311.383359) (xy 192.975514 -311.406502) (xy 192.926545 -311.422244)
			(xy 192.875727 -311.430204) (xy 192.850008 -311.43067) (xy 192.823338 -311.429654) (xy 192.823084 -311.429654)
			(xy 192.817242 -311.429146) (xy 192.816988 -311.429146) (xy 192.806397 -311.428666) (xy 192.786306 -311.435356)
			(xy 192.778126 -311.4421) (xy 192.7225 -311.492392) (xy 192.714994 -311.499938) (xy 192.706339 -311.519357)
			(xy 192.705736 -311.529984) (xy 192.705736 -311.574688) (xy 192.705227 -311.600677) (xy 192.697098 -311.652014)
			(xy 192.681039 -311.701448) (xy 192.657444 -311.747761) (xy 192.626895 -311.789813) (xy 192.590144 -311.826569)
			(xy 192.548095 -311.857123) (xy 192.501785 -311.880724) (xy 192.452353 -311.896789) (xy 192.401017 -311.904924)
			(xy 192.375028 -311.905396) (xy 192.342516 -311.903872) (xy 192.342262 -311.903872) (xy 192.331694 -311.903332)
			(xy 192.311599 -311.909884) (xy 192.3034 -311.916572) (xy 192.24752 -311.967118) (xy 192.242649 -311.971788)
			(xy 192.235323 -311.983118) (xy 192.233042 -311.98947) (xy 192.230756 -311.99709) (xy 192.230756 -312.049922)
			(xy 192.230246 -312.075909) (xy 192.222116 -312.127244) (xy 192.206055 -312.176674) (xy 192.182459 -312.222984)
			(xy 192.151909 -312.265032) (xy 192.115158 -312.301783) (xy 192.07311 -312.332333) (xy 192.0268 -312.355929)
			(xy 191.97737 -312.37199) (xy 191.926035 -312.38012) (xy 191.874061 -312.38012) (xy 191.822726 -312.37199)
			(xy 191.773296 -312.355929) (xy 191.726986 -312.332333) (xy 191.684938 -312.301783) (xy 191.648187 -312.265032)
			(xy 191.617637 -312.222984) (xy 191.594041 -312.176674) (xy 191.57798 -312.127244) (xy 191.56985 -312.075909)
			(xy 191.56934 -312.049922) (xy 191.56934 -311.364122) (xy 191.568856 -311.354108) (xy 191.561202 -311.335602)
			(xy 191.54705 -311.321433) (xy 191.528553 -311.313756) (xy 191.51854 -311.313322) (xy 191.235584 -311.313322)
			(xy 191.230487 -311.313436) (xy 191.220503 -311.315486) (xy 191.215772 -311.317386) (xy 191.189102 -311.328816)
			(xy 191.18199 -311.335674) (xy 191.163325 -311.353374) (xy 191.12153 -311.383356) (xy 191.075593 -311.406496)
			(xy 191.026624 -311.422234) (xy 190.975806 -311.430191) (xy 190.950088 -311.43067) (xy 190.923418 -311.429654)
			(xy 190.923164 -311.429654) (xy 190.917322 -311.429146) (xy 190.917068 -311.429146) (xy 190.906478 -311.42867)
			(xy 190.886393 -311.435366) (xy 190.878206 -311.4421) (xy 190.82258 -311.492392) (xy 190.815077 -311.49994)
			(xy 190.806425 -311.519358) (xy 190.805816 -311.529984) (xy 190.805816 -311.574688) (xy 190.805334 -311.600678)
			(xy 190.797204 -311.652019) (xy 190.781143 -311.701455) (xy 190.757546 -311.747771) (xy 190.726994 -311.789824)
			(xy 190.69024 -311.826581) (xy 190.648188 -311.857136) (xy 190.601874 -311.880735) (xy 190.552438 -311.896799)
			(xy 190.501098 -311.904932) (xy 190.475108 -311.905396) (xy 190.474854 -311.905396) (xy 190.462744 -311.90529)
			(xy 190.438589 -311.903513) (xy 190.426594 -311.90184) (xy 190.42634 -311.90184) (xy 190.41872 -311.90057)
			(xy 190.407544 -311.898538) (xy 190.393574 -311.89549) (xy 190.387732 -311.893966) (xy 190.381636 -311.893966)
			(xy 190.371607 -311.894379) (xy 190.353072 -311.902041) (xy 190.33888 -311.916213) (xy 190.331192 -311.934738)
			(xy 190.330836 -311.944766) (xy 190.330836 -312.049922) (xy 190.330325 -312.075915) (xy 190.322193 -312.12726)
			(xy 190.306133 -312.176702) (xy 190.28254 -312.223025) (xy 190.251994 -312.265089) (xy 190.215246 -312.30186)
			(xy 190.173201 -312.332432) (xy 190.126893 -312.356054) (xy 190.07746 -312.372145) (xy 190.02612 -312.380309)
			(xy 190.000128 -312.380884) (xy 189.97689 -312.380493) (xy 189.930869 -312.373997) (xy 189.908434 -312.36793)
			(xy 189.904878 -312.366914) (xy 189.898782 -312.365898) (xy 189.886963 -312.364789) (xy 189.864442 -312.3722)
			(xy 189.855602 -312.380122) (xy 189.846966 -312.388504) (xy 189.839346 -312.410856) (xy 189.841378 -312.425842)
			(xy 189.844172 -312.437272) (xy 189.846458 -312.44286) (xy 189.850014 -312.44794) (xy 189.872357 -312.481072)
			(xy 189.912157 -312.550376) (xy 189.929516 -312.58637) (xy 189.933072 -312.59399) (xy 189.95644 -312.61812)
			(xy 189.963806 -312.62193) (xy 189.983021 -312.63198) (xy 190.020626 -312.653579) (xy 190.03899 -312.66511)
			(xy 190.042292 -312.667396) (xy 190.05804 -312.674254) (xy 190.063374 -312.67527) (xy 190.087333 -312.680406)
			(xy 190.133507 -312.696799) (xy 190.176758 -312.719825) (xy 190.216138 -312.748978) (xy 190.250788 -312.783622)
			(xy 190.279948 -312.822999) (xy 190.30298 -312.866246) (xy 190.31938 -312.912418) (xy 190.324486 -312.936382)
			(xy 190.325502 -312.941716) (xy 190.33236 -312.957464) (xy 190.334646 -312.960766) (xy 190.35531 -312.993968)
			(xy 190.391808 -313.06314) (xy 190.407544 -313.098942) (xy 190.410592 -313.1058) (xy 190.419482 -313.116722)
			(xy 190.44666 -313.135264) (xy 190.475362 -313.144154) (xy 190.50762 -313.145678) (xy 190.507874 -313.145678)
			(xy 190.51844 -313.146212) (xy 190.538529 -313.139654) (xy 190.546736 -313.132978) (xy 190.602616 -313.082432)
			(xy 190.607536 -313.077725) (xy 190.614882 -313.066266) (xy 190.617094 -313.059826) (xy 190.61938 -313.052206)
			(xy 190.61938 -312.999882) (xy 190.61989 -312.973895) (xy 190.62802 -312.92256) (xy 190.644081 -312.87313)
			(xy 190.667677 -312.82682) (xy 190.698227 -312.784772) (xy 190.734978 -312.748021) (xy 190.777026 -312.717471)
			(xy 190.823336 -312.693875) (xy 190.872766 -312.677814) (xy 190.924101 -312.669684) (xy 190.976075 -312.669684)
			(xy 191.02741 -312.677814) (xy 191.07684 -312.693875) (xy 191.12315 -312.717471) (xy 191.165198 -312.748021)
			(xy 191.201949 -312.784772) (xy 191.232499 -312.82682) (xy 191.256095 -312.87313) (xy 191.272156 -312.92256)
			(xy 191.280286 -312.973895) (xy 191.280796 -312.999882) (xy 191.280796 -313.02559) (xy 192.52336 -313.02559)
			(xy 192.52336 -312.974174) (xy 192.531403 -312.923392) (xy 192.547291 -312.874493) (xy 192.570634 -312.828681)
			(xy 192.600855 -312.787085) (xy 192.637211 -312.750729) (xy 192.678807 -312.720508) (xy 192.724619 -312.697165)
			(xy 192.773518 -312.681277) (xy 192.8243 -312.673234) (xy 192.875716 -312.673234) (xy 192.926498 -312.681277)
			(xy 192.975397 -312.697165) (xy 193.021209 -312.720508) (xy 193.062805 -312.750729) (xy 193.099161 -312.787085)
			(xy 193.129382 -312.828681) (xy 193.152725 -312.874493) (xy 193.168613 -312.923392) (xy 193.176656 -312.974174)
			(xy 193.17716 -312.999882) (xy 193.176656 -313.02559) (xy 194.42328 -313.02559) (xy 194.42328 -312.974174)
			(xy 194.431323 -312.923392) (xy 194.447211 -312.874493) (xy 194.470554 -312.828681) (xy 194.500775 -312.787085)
			(xy 194.537131 -312.750729) (xy 194.578727 -312.720508) (xy 194.624539 -312.697165) (xy 194.673438 -312.681277)
			(xy 194.72422 -312.673234) (xy 194.775636 -312.673234) (xy 194.826418 -312.681277) (xy 194.875317 -312.697165)
			(xy 194.921129 -312.720508) (xy 194.962725 -312.750729) (xy 194.999081 -312.787085) (xy 195.029302 -312.828681)
			(xy 195.052645 -312.874493) (xy 195.068533 -312.923392) (xy 195.076576 -312.974174) (xy 195.07708 -312.999882)
			(xy 195.076576 -313.02559) (xy 196.3232 -313.02559) (xy 196.3232 -312.974174) (xy 196.331243 -312.923392)
			(xy 196.347131 -312.874493) (xy 196.370474 -312.828681) (xy 196.400695 -312.787085) (xy 196.437051 -312.750729)
			(xy 196.478647 -312.720508) (xy 196.524459 -312.697165) (xy 196.573358 -312.681277) (xy 196.62414 -312.673234)
			(xy 196.675556 -312.673234) (xy 196.726338 -312.681277) (xy 196.775237 -312.697165) (xy 196.821049 -312.720508)
			(xy 196.862645 -312.750729) (xy 196.899001 -312.787085) (xy 196.929222 -312.828681) (xy 196.952565 -312.874493)
			(xy 196.968453 -312.923392) (xy 196.976496 -312.974174) (xy 196.977 -312.999882) (xy 196.976496 -313.02559)
			(xy 196.968453 -313.076372) (xy 196.952565 -313.125271) (xy 196.929222 -313.171083) (xy 196.899001 -313.212679)
			(xy 196.862645 -313.249035) (xy 196.821049 -313.279256) (xy 196.775237 -313.302599) (xy 196.726338 -313.318487)
			(xy 196.675556 -313.32653) (xy 196.62414 -313.32653) (xy 196.573358 -313.318487) (xy 196.524459 -313.302599)
			(xy 196.478647 -313.279256) (xy 196.437051 -313.249035) (xy 196.400695 -313.212679) (xy 196.370474 -313.171083)
			(xy 196.347131 -313.125271) (xy 196.331243 -313.076372) (xy 196.3232 -313.02559) (xy 195.076576 -313.02559)
			(xy 195.068533 -313.076372) (xy 195.052645 -313.125271) (xy 195.029302 -313.171083) (xy 194.999081 -313.212679)
			(xy 194.962725 -313.249035) (xy 194.921129 -313.279256) (xy 194.875317 -313.302599) (xy 194.826418 -313.318487)
			(xy 194.775636 -313.32653) (xy 194.72422 -313.32653) (xy 194.673438 -313.318487) (xy 194.624539 -313.302599)
			(xy 194.578727 -313.279256) (xy 194.537131 -313.249035) (xy 194.500775 -313.212679) (xy 194.470554 -313.171083)
			(xy 194.447211 -313.125271) (xy 194.431323 -313.076372) (xy 194.42328 -313.02559) (xy 193.176656 -313.02559)
			(xy 193.168613 -313.076372) (xy 193.152725 -313.125271) (xy 193.129382 -313.171083) (xy 193.099161 -313.212679)
			(xy 193.062805 -313.249035) (xy 193.021209 -313.279256) (xy 192.975397 -313.302599) (xy 192.926498 -313.318487)
			(xy 192.875716 -313.32653) (xy 192.8243 -313.32653) (xy 192.773518 -313.318487) (xy 192.724619 -313.302599)
			(xy 192.678807 -313.279256) (xy 192.637211 -313.249035) (xy 192.600855 -313.212679) (xy 192.570634 -313.171083)
			(xy 192.547291 -313.125271) (xy 192.531403 -313.076372) (xy 192.52336 -313.02559) (xy 191.280796 -313.02559)
			(xy 191.280796 -313.949842) (xy 191.28029 -313.97555) (xy 192.52336 -313.97555) (xy 192.52336 -313.924134)
			(xy 192.531403 -313.873352) (xy 192.547291 -313.824453) (xy 192.570634 -313.778641) (xy 192.600855 -313.737045)
			(xy 192.637211 -313.700689) (xy 192.678807 -313.670468) (xy 192.724619 -313.647125) (xy 192.773518 -313.631237)
			(xy 192.8243 -313.623194) (xy 192.875716 -313.623194) (xy 192.926498 -313.631237) (xy 192.975397 -313.647125)
			(xy 193.021209 -313.670468) (xy 193.062805 -313.700689) (xy 193.099161 -313.737045) (xy 193.129382 -313.778641)
			(xy 193.152725 -313.824453) (xy 193.168613 -313.873352) (xy 193.176656 -313.924134) (xy 193.17716 -313.949842)
			(xy 193.176656 -313.97555) (xy 194.42328 -313.97555) (xy 194.42328 -313.924134) (xy 194.431323 -313.873352)
			(xy 194.447211 -313.824453) (xy 194.470554 -313.778641) (xy 194.500775 -313.737045) (xy 194.537131 -313.700689)
			(xy 194.578727 -313.670468) (xy 194.624539 -313.647125) (xy 194.673438 -313.631237) (xy 194.72422 -313.623194)
			(xy 194.775636 -313.623194) (xy 194.826418 -313.631237) (xy 194.875317 -313.647125) (xy 194.921129 -313.670468)
			(xy 194.962725 -313.700689) (xy 194.999081 -313.737045) (xy 195.029302 -313.778641) (xy 195.052645 -313.824453)
			(xy 195.068533 -313.873352) (xy 195.076576 -313.924134) (xy 195.07708 -313.949842) (xy 195.076576 -313.97555)
			(xy 196.3232 -313.97555) (xy 196.3232 -313.924134) (xy 196.331243 -313.873352) (xy 196.347131 -313.824453)
			(xy 196.370474 -313.778641) (xy 196.400695 -313.737045) (xy 196.437051 -313.700689) (xy 196.478647 -313.670468)
			(xy 196.524459 -313.647125) (xy 196.573358 -313.631237) (xy 196.62414 -313.623194) (xy 196.675556 -313.623194)
			(xy 196.726338 -313.631237) (xy 196.775237 -313.647125) (xy 196.821049 -313.670468) (xy 196.862645 -313.700689)
			(xy 196.899001 -313.737045) (xy 196.929222 -313.778641) (xy 196.952565 -313.824453) (xy 196.968453 -313.873352)
			(xy 196.976496 -313.924134) (xy 196.977 -313.949842) (xy 196.976496 -313.97555) (xy 196.968453 -314.026332)
			(xy 196.952565 -314.075231) (xy 196.929222 -314.121043) (xy 196.899001 -314.162639) (xy 196.862645 -314.198995)
			(xy 196.821049 -314.229216) (xy 196.775237 -314.252559) (xy 196.726338 -314.268447) (xy 196.675556 -314.27649)
			(xy 196.62414 -314.27649) (xy 196.573358 -314.268447) (xy 196.524459 -314.252559) (xy 196.478647 -314.229216)
			(xy 196.437051 -314.198995) (xy 196.400695 -314.162639) (xy 196.370474 -314.121043) (xy 196.347131 -314.075231)
			(xy 196.331243 -314.026332) (xy 196.3232 -313.97555) (xy 195.076576 -313.97555) (xy 195.068533 -314.026332)
			(xy 195.052645 -314.075231) (xy 195.029302 -314.121043) (xy 194.999081 -314.162639) (xy 194.962725 -314.198995)
			(xy 194.921129 -314.229216) (xy 194.875317 -314.252559) (xy 194.826418 -314.268447) (xy 194.775636 -314.27649)
			(xy 194.72422 -314.27649) (xy 194.673438 -314.268447) (xy 194.624539 -314.252559) (xy 194.578727 -314.229216)
			(xy 194.537131 -314.198995) (xy 194.500775 -314.162639) (xy 194.470554 -314.121043) (xy 194.447211 -314.075231)
			(xy 194.431323 -314.026332) (xy 194.42328 -313.97555) (xy 193.176656 -313.97555) (xy 193.168613 -314.026332)
			(xy 193.152725 -314.075231) (xy 193.129382 -314.121043) (xy 193.099161 -314.162639) (xy 193.062805 -314.198995)
			(xy 193.021209 -314.229216) (xy 192.975397 -314.252559) (xy 192.926498 -314.268447) (xy 192.875716 -314.27649)
			(xy 192.8243 -314.27649) (xy 192.773518 -314.268447) (xy 192.724619 -314.252559) (xy 192.678807 -314.229216)
			(xy 192.637211 -314.198995) (xy 192.600855 -314.162639) (xy 192.570634 -314.121043) (xy 192.547291 -314.075231)
			(xy 192.531403 -314.026332) (xy 192.52336 -313.97555) (xy 191.28029 -313.97555) (xy 191.280285 -313.975823)
			(xy 191.272159 -314.027145) (xy 191.256113 -314.076566) (xy 191.232542 -314.122874) (xy 191.202024 -314.164929)
			(xy 191.16531 -314.201699) (xy 191.123301 -314.23228) (xy 191.077029 -314.255921) (xy 191.027631 -314.272042)
			(xy 190.976322 -314.280245) (xy 190.950342 -314.280804) (xy 190.949834 -314.280804) (xy 190.915544 -314.278772)
			(xy 190.904114 -314.277756) (xy 190.893192 -314.281566) (xy 190.887962 -314.283621) (xy 190.87848 -314.289645)
			(xy 190.874396 -314.293504) (xy 190.818516 -314.349384) (xy 190.814627 -314.353444) (xy 190.80861 -314.362937)
			(xy 190.806578 -314.36818) (xy 190.802514 -314.379102) (xy 190.803784 -314.390786) (xy 190.805988 -314.417244)
			(xy 190.802947 -314.470247) (xy 190.79149 -314.522086) (xy 190.771911 -314.571434) (xy 190.744712 -314.617027)
			(xy 190.710589 -314.657698) (xy 190.670415 -314.692406) (xy 190.648082 -314.706762) (xy 190.623102 -314.721344)
			(xy 190.569301 -314.742567) (xy 190.512635 -314.754134) (xy 190.483744 -314.75553) (xy 190.47968 -314.755784)
			(xy 190.468504 -314.757816) (xy 190.452756 -314.762896) (xy 190.449036 -314.764188) (xy 190.442019 -314.76776)
			(xy 190.438786 -314.770008) (xy 190.421006 -314.782708) (xy 190.41618 -314.78982) (xy 190.40856 -314.800234)
			(xy 190.406274 -314.805314) (xy 190.390651 -314.840514) (xy 190.354539 -314.908541) (xy 190.34394 -314.92551)
			(xy 197.273414 -314.92551) (xy 197.273414 -314.874094) (xy 197.281457 -314.823312) (xy 197.297345 -314.774413)
			(xy 197.320688 -314.728601) (xy 197.350909 -314.687005) (xy 197.387265 -314.650649) (xy 197.428861 -314.620428)
			(xy 197.474673 -314.597085) (xy 197.523572 -314.581197) (xy 197.574354 -314.573154) (xy 197.62577 -314.573154)
			(xy 197.676552 -314.581197) (xy 197.725451 -314.597085) (xy 197.771263 -314.620428) (xy 197.812859 -314.650649)
			(xy 197.849215 -314.687005) (xy 197.879436 -314.728601) (xy 197.902779 -314.774413) (xy 197.918667 -314.823312)
			(xy 197.92671 -314.874094) (xy 197.927214 -314.899802) (xy 197.92671 -314.92551) (xy 198.223374 -314.92551)
			(xy 198.223374 -314.874094) (xy 198.231417 -314.823312) (xy 198.247305 -314.774413) (xy 198.270648 -314.728601)
			(xy 198.300869 -314.687005) (xy 198.337225 -314.650649) (xy 198.378821 -314.620428) (xy 198.424633 -314.597085)
			(xy 198.473532 -314.581197) (xy 198.524314 -314.573154) (xy 198.57573 -314.573154) (xy 198.626512 -314.581197)
			(xy 198.675411 -314.597085) (xy 198.721223 -314.620428) (xy 198.762819 -314.650649) (xy 198.799175 -314.687005)
			(xy 198.829396 -314.728601) (xy 198.852739 -314.774413) (xy 198.868627 -314.823312) (xy 198.87667 -314.874094)
			(xy 198.877174 -314.899802) (xy 198.87667 -314.92551) (xy 198.868627 -314.976292) (xy 198.852739 -315.025191)
			(xy 198.829396 -315.071003) (xy 198.799175 -315.112599) (xy 198.762819 -315.148955) (xy 198.721223 -315.179176)
			(xy 198.675411 -315.202519) (xy 198.626512 -315.218407) (xy 198.57573 -315.22645) (xy 198.524314 -315.22645)
			(xy 198.473532 -315.218407) (xy 198.424633 -315.202519) (xy 198.378821 -315.179176) (xy 198.337225 -315.148955)
			(xy 198.300869 -315.112599) (xy 198.270648 -315.071003) (xy 198.247305 -315.025191) (xy 198.231417 -314.976292)
			(xy 198.223374 -314.92551) (xy 197.92671 -314.92551) (xy 197.918667 -314.976292) (xy 197.902779 -315.025191)
			(xy 197.879436 -315.071003) (xy 197.849215 -315.112599) (xy 197.812859 -315.148955) (xy 197.771263 -315.179176)
			(xy 197.725451 -315.202519) (xy 197.676552 -315.218407) (xy 197.62577 -315.22645) (xy 197.574354 -315.22645)
			(xy 197.523572 -315.218407) (xy 197.474673 -315.202519) (xy 197.428861 -315.179176) (xy 197.387265 -315.148955)
			(xy 197.350909 -315.112599) (xy 197.320688 -315.071003) (xy 197.297345 -315.025191) (xy 197.281457 -314.976292)
			(xy 197.273414 -314.92551) (xy 190.34394 -314.92551) (xy 190.334138 -314.941204) (xy 190.331598 -314.945268)
			(xy 190.32474 -314.96254) (xy 190.323724 -314.967112) (xy 190.32347 -314.967874) (xy 190.317639 -314.993251)
			(xy 190.299075 -315.041896) (xy 190.273115 -315.087029) (xy 190.240399 -315.127534) (xy 190.201737 -315.162409)
			(xy 190.158086 -315.190791) (xy 190.134494 -315.201808) (xy 190.13424 -315.202062) (xy 190.125554 -315.206472)
			(xy 190.112078 -315.220517) (xy 190.104779 -315.23856) (xy 190.104268 -315.24829) (xy 190.104268 -315.51626)
			(xy 190.120524 -315.541406) (xy 190.134494 -315.547502) (xy 190.159168 -315.559071) (xy 190.204666 -315.589061)
			(xy 190.244629 -315.626106) (xy 190.277975 -315.669204) (xy 190.303801 -315.717188) (xy 190.321408 -315.768757)
			(xy 190.330319 -315.822516) (xy 190.330836 -315.849762) (xy 190.330836 -315.87547) (xy 191.5734 -315.87547)
			(xy 191.5734 -315.824054) (xy 191.581443 -315.773272) (xy 191.597331 -315.724373) (xy 191.620674 -315.678561)
			(xy 191.650895 -315.636965) (xy 191.687251 -315.600609) (xy 191.728847 -315.570388) (xy 191.774659 -315.547045)
			(xy 191.823558 -315.531157) (xy 191.87434 -315.523114) (xy 191.925756 -315.523114) (xy 191.976538 -315.531157)
			(xy 192.025437 -315.547045) (xy 192.071249 -315.570388) (xy 192.112845 -315.600609) (xy 192.149201 -315.636965)
			(xy 192.179422 -315.678561) (xy 192.202765 -315.724373) (xy 192.218653 -315.773272) (xy 192.226696 -315.824054)
			(xy 192.2272 -315.849762) (xy 192.226696 -315.87547) (xy 193.47332 -315.87547) (xy 193.47332 -315.824054)
			(xy 193.481363 -315.773272) (xy 193.497251 -315.724373) (xy 193.520594 -315.678561) (xy 193.550815 -315.636965)
			(xy 193.587171 -315.600609) (xy 193.628767 -315.570388) (xy 193.674579 -315.547045) (xy 193.723478 -315.531157)
			(xy 193.77426 -315.523114) (xy 193.825676 -315.523114) (xy 193.876458 -315.531157) (xy 193.925357 -315.547045)
			(xy 193.971169 -315.570388) (xy 194.012765 -315.600609) (xy 194.049121 -315.636965) (xy 194.079342 -315.678561)
			(xy 194.102685 -315.724373) (xy 194.118573 -315.773272) (xy 194.126616 -315.824054) (xy 194.12712 -315.849762)
			(xy 194.126616 -315.87547) (xy 195.37324 -315.87547) (xy 195.37324 -315.824054) (xy 195.381283 -315.773272)
			(xy 195.397171 -315.724373) (xy 195.420514 -315.678561) (xy 195.450735 -315.636965) (xy 195.487091 -315.600609)
			(xy 195.528687 -315.570388) (xy 195.574499 -315.547045) (xy 195.623398 -315.531157) (xy 195.67418 -315.523114)
			(xy 195.725596 -315.523114) (xy 195.776378 -315.531157) (xy 195.825277 -315.547045) (xy 195.871089 -315.570388)
			(xy 195.912685 -315.600609) (xy 195.949041 -315.636965) (xy 195.979262 -315.678561) (xy 196.002605 -315.724373)
			(xy 196.018493 -315.773272) (xy 196.026536 -315.824054) (xy 196.02704 -315.849762) (xy 196.026536 -315.87547)
			(xy 196.018493 -315.926252) (xy 196.002605 -315.975151) (xy 195.979262 -316.020963) (xy 195.949041 -316.062559)
			(xy 195.912685 -316.098915) (xy 195.871089 -316.129136) (xy 195.825277 -316.152479) (xy 195.776378 -316.168367)
			(xy 195.725596 -316.17641) (xy 195.67418 -316.17641) (xy 195.623398 -316.168367) (xy 195.574499 -316.152479)
			(xy 195.528687 -316.129136) (xy 195.487091 -316.098915) (xy 195.450735 -316.062559) (xy 195.420514 -316.020963)
			(xy 195.397171 -315.975151) (xy 195.381283 -315.926252) (xy 195.37324 -315.87547) (xy 194.126616 -315.87547)
			(xy 194.118573 -315.926252) (xy 194.102685 -315.975151) (xy 194.079342 -316.020963) (xy 194.049121 -316.062559)
			(xy 194.012765 -316.098915) (xy 193.971169 -316.129136) (xy 193.925357 -316.152479) (xy 193.876458 -316.168367)
			(xy 193.825676 -316.17641) (xy 193.77426 -316.17641) (xy 193.723478 -316.168367) (xy 193.674579 -316.152479)
			(xy 193.628767 -316.129136) (xy 193.587171 -316.098915) (xy 193.550815 -316.062559) (xy 193.520594 -316.020963)
			(xy 193.497251 -315.975151) (xy 193.481363 -315.926252) (xy 193.47332 -315.87547) (xy 192.226696 -315.87547)
			(xy 192.218653 -315.926252) (xy 192.202765 -315.975151) (xy 192.179422 -316.020963) (xy 192.149201 -316.062559)
			(xy 192.112845 -316.098915) (xy 192.071249 -316.129136) (xy 192.025437 -316.152479) (xy 191.976538 -316.168367)
			(xy 191.925756 -316.17641) (xy 191.87434 -316.17641) (xy 191.823558 -316.168367) (xy 191.774659 -316.152479)
			(xy 191.728847 -316.129136) (xy 191.687251 -316.098915) (xy 191.650895 -316.062559) (xy 191.620674 -316.020963)
			(xy 191.597331 -315.975151) (xy 191.581443 -315.926252) (xy 191.5734 -315.87547) (xy 190.330836 -315.87547)
			(xy 190.330836 -315.89472) (xy 190.3313 -315.905376) (xy 190.339992 -315.924834) (xy 190.3476 -315.932312)
			(xy 190.403226 -315.982604) (xy 190.411459 -315.989232) (xy 190.431529 -315.995784) (xy 190.442088 -315.995304)
			(xy 190.442342 -315.995304) (xy 190.474092 -315.99378) (xy 190.475108 -315.99378) (xy 190.501122 -315.99429)
			(xy 190.55251 -316.002426) (xy 190.601994 -316.018497) (xy 190.648357 -316.042107) (xy 190.690458 -316.072676)
			(xy 190.727261 -316.109452) (xy 190.757862 -316.15153) (xy 190.781507 -316.197874) (xy 190.797615 -316.247346)
			(xy 190.80579 -316.298728) (xy 190.806324 -316.324742) (xy 190.806324 -316.82543) (xy 191.5734 -316.82543)
			(xy 191.5734 -316.774014) (xy 191.581443 -316.723232) (xy 191.597331 -316.674333) (xy 191.620674 -316.628521)
			(xy 191.650895 -316.586925) (xy 191.687251 -316.550569) (xy 191.728847 -316.520348) (xy 191.774659 -316.497005)
			(xy 191.823558 -316.481117) (xy 191.87434 -316.473074) (xy 191.925756 -316.473074) (xy 191.976538 -316.481117)
			(xy 192.025437 -316.497005) (xy 192.071249 -316.520348) (xy 192.112845 -316.550569) (xy 192.149201 -316.586925)
			(xy 192.179422 -316.628521) (xy 192.202765 -316.674333) (xy 192.218653 -316.723232) (xy 192.226696 -316.774014)
			(xy 192.2272 -316.799722) (xy 192.226696 -316.82543) (xy 193.47332 -316.82543) (xy 193.47332 -316.774014)
			(xy 193.481363 -316.723232) (xy 193.497251 -316.674333) (xy 193.520594 -316.628521) (xy 193.550815 -316.586925)
			(xy 193.587171 -316.550569) (xy 193.628767 -316.520348) (xy 193.674579 -316.497005) (xy 193.723478 -316.481117)
			(xy 193.77426 -316.473074) (xy 193.825676 -316.473074) (xy 193.876458 -316.481117) (xy 193.925357 -316.497005)
			(xy 193.971169 -316.520348) (xy 194.012765 -316.550569) (xy 194.049121 -316.586925) (xy 194.079342 -316.628521)
			(xy 194.102685 -316.674333) (xy 194.118573 -316.723232) (xy 194.126616 -316.774014) (xy 194.12712 -316.799722)
			(xy 194.126616 -316.82543) (xy 195.37324 -316.82543) (xy 195.37324 -316.774014) (xy 195.381283 -316.723232)
			(xy 195.397171 -316.674333) (xy 195.420514 -316.628521) (xy 195.450735 -316.586925) (xy 195.487091 -316.550569)
			(xy 195.528687 -316.520348) (xy 195.574499 -316.497005) (xy 195.623398 -316.481117) (xy 195.67418 -316.473074)
			(xy 195.725596 -316.473074) (xy 195.776378 -316.481117) (xy 195.825277 -316.497005) (xy 195.871089 -316.520348)
			(xy 195.912685 -316.550569) (xy 195.949041 -316.586925) (xy 195.979262 -316.628521) (xy 196.002605 -316.674333)
			(xy 196.018493 -316.723232) (xy 196.026536 -316.774014) (xy 196.02704 -316.799722) (xy 196.026536 -316.82543)
			(xy 197.273414 -316.82543) (xy 197.273414 -316.774014) (xy 197.281457 -316.723232) (xy 197.297345 -316.674333)
			(xy 197.320688 -316.628521) (xy 197.350909 -316.586925) (xy 197.387265 -316.550569) (xy 197.428861 -316.520348)
			(xy 197.474673 -316.497005) (xy 197.523572 -316.481117) (xy 197.574354 -316.473074) (xy 197.62577 -316.473074)
			(xy 197.676552 -316.481117) (xy 197.725451 -316.497005) (xy 197.771263 -316.520348) (xy 197.812859 -316.550569)
			(xy 197.849215 -316.586925) (xy 197.879436 -316.628521) (xy 197.902779 -316.674333) (xy 197.918667 -316.723232)
			(xy 197.92671 -316.774014) (xy 197.927214 -316.799722) (xy 197.92671 -316.82543) (xy 198.223374 -316.82543)
			(xy 198.223374 -316.774014) (xy 198.231417 -316.723232) (xy 198.247305 -316.674333) (xy 198.270648 -316.628521)
			(xy 198.300869 -316.586925) (xy 198.337225 -316.550569) (xy 198.378821 -316.520348) (xy 198.424633 -316.497005)
			(xy 198.473532 -316.481117) (xy 198.524314 -316.473074) (xy 198.57573 -316.473074) (xy 198.626512 -316.481117)
			(xy 198.675411 -316.497005) (xy 198.721223 -316.520348) (xy 198.762819 -316.550569) (xy 198.799175 -316.586925)
			(xy 198.829396 -316.628521) (xy 198.852739 -316.674333) (xy 198.868627 -316.723232) (xy 198.87667 -316.774014)
			(xy 198.877174 -316.799722) (xy 198.87667 -316.82543) (xy 198.868627 -316.876212) (xy 198.852739 -316.925111)
			(xy 198.829396 -316.970923) (xy 198.799175 -317.012519) (xy 198.762819 -317.048875) (xy 198.721223 -317.079096)
			(xy 198.675411 -317.102439) (xy 198.626512 -317.118327) (xy 198.57573 -317.12637) (xy 198.524314 -317.12637)
			(xy 198.473532 -317.118327) (xy 198.424633 -317.102439) (xy 198.378821 -317.079096) (xy 198.337225 -317.048875)
			(xy 198.300869 -317.012519) (xy 198.270648 -316.970923) (xy 198.247305 -316.925111) (xy 198.231417 -316.876212)
			(xy 198.223374 -316.82543) (xy 197.92671 -316.82543) (xy 197.918667 -316.876212) (xy 197.902779 -316.925111)
			(xy 197.879436 -316.970923) (xy 197.849215 -317.012519) (xy 197.812859 -317.048875) (xy 197.771263 -317.079096)
			(xy 197.725451 -317.102439) (xy 197.676552 -317.118327) (xy 197.62577 -317.12637) (xy 197.574354 -317.12637)
			(xy 197.523572 -317.118327) (xy 197.474673 -317.102439) (xy 197.428861 -317.079096) (xy 197.387265 -317.048875)
			(xy 197.350909 -317.012519) (xy 197.320688 -316.970923) (xy 197.297345 -316.925111) (xy 197.281457 -316.876212)
			(xy 197.273414 -316.82543) (xy 196.026536 -316.82543) (xy 196.018493 -316.876212) (xy 196.002605 -316.925111)
			(xy 195.979262 -316.970923) (xy 195.949041 -317.012519) (xy 195.912685 -317.048875) (xy 195.871089 -317.079096)
			(xy 195.825277 -317.102439) (xy 195.776378 -317.118327) (xy 195.725596 -317.12637) (xy 195.67418 -317.12637)
			(xy 195.623398 -317.118327) (xy 195.574499 -317.102439) (xy 195.528687 -317.079096) (xy 195.487091 -317.048875)
			(xy 195.450735 -317.012519) (xy 195.420514 -316.970923) (xy 195.397171 -316.925111) (xy 195.381283 -316.876212)
			(xy 195.37324 -316.82543) (xy 194.126616 -316.82543) (xy 194.118573 -316.876212) (xy 194.102685 -316.925111)
			(xy 194.079342 -316.970923) (xy 194.049121 -317.012519) (xy 194.012765 -317.048875) (xy 193.971169 -317.079096)
			(xy 193.925357 -317.102439) (xy 193.876458 -317.118327) (xy 193.825676 -317.12637) (xy 193.77426 -317.12637)
			(xy 193.723478 -317.118327) (xy 193.674579 -317.102439) (xy 193.628767 -317.079096) (xy 193.587171 -317.048875)
			(xy 193.550815 -317.012519) (xy 193.520594 -316.970923) (xy 193.497251 -316.925111) (xy 193.481363 -316.876212)
			(xy 193.47332 -316.82543) (xy 192.226696 -316.82543) (xy 192.218653 -316.876212) (xy 192.202765 -316.925111)
			(xy 192.179422 -316.970923) (xy 192.149201 -317.012519) (xy 192.112845 -317.048875) (xy 192.071249 -317.079096)
			(xy 192.025437 -317.102439) (xy 191.976538 -317.118327) (xy 191.925756 -317.12637) (xy 191.87434 -317.12637)
			(xy 191.823558 -317.118327) (xy 191.774659 -317.102439) (xy 191.728847 -317.079096) (xy 191.687251 -317.048875)
			(xy 191.650895 -317.012519) (xy 191.620674 -316.970923) (xy 191.597331 -316.925111) (xy 191.581443 -316.876212)
			(xy 191.5734 -316.82543) (xy 190.806324 -316.82543) (xy 190.806324 -317.27521) (xy 190.804546 -317.309246)
			(xy 190.803276 -317.320676) (xy 190.810896 -317.342266) (xy 190.883032 -317.414402) (xy 190.904622 -317.422022)
			(xy 190.916052 -317.420752) (xy 190.94958 -317.419228) (xy 190.950088 -317.419228) (xy 190.976068 -317.419759)
			(xy 191.027383 -317.427923) (xy 191.076792 -317.444007) (xy 191.123081 -317.467613) (xy 191.165112 -317.498164)
			(xy 191.201852 -317.534907) (xy 191.232399 -317.57694) (xy 191.256003 -317.62323) (xy 191.272082 -317.67264)
			(xy 191.280243 -317.723956) (xy 191.280796 -317.749936) (xy 191.280796 -317.775644) (xy 192.52336 -317.775644)
			(xy 192.52336 -317.724228) (xy 192.531403 -317.673446) (xy 192.547291 -317.624547) (xy 192.570634 -317.578735)
			(xy 192.600855 -317.537139) (xy 192.637211 -317.500783) (xy 192.678807 -317.470562) (xy 192.724619 -317.447219)
			(xy 192.773518 -317.431331) (xy 192.8243 -317.423288) (xy 192.875716 -317.423288) (xy 192.926498 -317.431331)
			(xy 192.975397 -317.447219) (xy 193.021209 -317.470562) (xy 193.062805 -317.500783) (xy 193.099161 -317.537139)
			(xy 193.129382 -317.578735) (xy 193.152725 -317.624547) (xy 193.168613 -317.673446) (xy 193.176656 -317.724228)
			(xy 193.17716 -317.749936) (xy 193.176656 -317.775644) (xy 194.42328 -317.775644) (xy 194.42328 -317.724228)
			(xy 194.431323 -317.673446) (xy 194.447211 -317.624547) (xy 194.470554 -317.578735) (xy 194.500775 -317.537139)
			(xy 194.537131 -317.500783) (xy 194.578727 -317.470562) (xy 194.624539 -317.447219) (xy 194.673438 -317.431331)
			(xy 194.72422 -317.423288) (xy 194.775636 -317.423288) (xy 194.826418 -317.431331) (xy 194.875317 -317.447219)
			(xy 194.921129 -317.470562) (xy 194.962725 -317.500783) (xy 194.999081 -317.537139) (xy 195.029302 -317.578735)
			(xy 195.052645 -317.624547) (xy 195.068533 -317.673446) (xy 195.076576 -317.724228) (xy 195.07708 -317.749936)
			(xy 195.076576 -317.775644) (xy 196.3232 -317.775644) (xy 196.3232 -317.724228) (xy 196.331243 -317.673446)
			(xy 196.347131 -317.624547) (xy 196.370474 -317.578735) (xy 196.400695 -317.537139) (xy 196.437051 -317.500783)
			(xy 196.478647 -317.470562) (xy 196.524459 -317.447219) (xy 196.573358 -317.431331) (xy 196.62414 -317.423288)
			(xy 196.675556 -317.423288) (xy 196.726338 -317.431331) (xy 196.775237 -317.447219) (xy 196.821049 -317.470562)
			(xy 196.862645 -317.500783) (xy 196.899001 -317.537139) (xy 196.929222 -317.578735) (xy 196.952565 -317.624547)
			(xy 196.968453 -317.673446) (xy 196.976496 -317.724228) (xy 196.977 -317.749936) (xy 196.976496 -317.775644)
			(xy 196.968453 -317.826426) (xy 196.952565 -317.875325) (xy 196.929222 -317.921137) (xy 196.899001 -317.962733)
			(xy 196.862645 -317.999089) (xy 196.821049 -318.02931) (xy 196.775237 -318.052653) (xy 196.726338 -318.068541)
			(xy 196.675556 -318.076584) (xy 196.62414 -318.076584) (xy 196.573358 -318.068541) (xy 196.524459 -318.052653)
			(xy 196.478647 -318.02931) (xy 196.437051 -317.999089) (xy 196.400695 -317.962733) (xy 196.370474 -317.921137)
			(xy 196.347131 -317.875325) (xy 196.331243 -317.826426) (xy 196.3232 -317.775644) (xy 195.076576 -317.775644)
			(xy 195.068533 -317.826426) (xy 195.052645 -317.875325) (xy 195.029302 -317.921137) (xy 194.999081 -317.962733)
			(xy 194.962725 -317.999089) (xy 194.921129 -318.02931) (xy 194.875317 -318.052653) (xy 194.826418 -318.068541)
			(xy 194.775636 -318.076584) (xy 194.72422 -318.076584) (xy 194.673438 -318.068541) (xy 194.624539 -318.052653)
			(xy 194.578727 -318.02931) (xy 194.537131 -317.999089) (xy 194.500775 -317.962733) (xy 194.470554 -317.921137)
			(xy 194.447211 -317.875325) (xy 194.431323 -317.826426) (xy 194.42328 -317.775644) (xy 193.176656 -317.775644)
			(xy 193.168613 -317.826426) (xy 193.152725 -317.875325) (xy 193.129382 -317.921137) (xy 193.099161 -317.962733)
			(xy 193.062805 -317.999089) (xy 193.021209 -318.02931) (xy 192.975397 -318.052653) (xy 192.926498 -318.068541)
			(xy 192.875716 -318.076584) (xy 192.8243 -318.076584) (xy 192.773518 -318.068541) (xy 192.724619 -318.052653)
			(xy 192.678807 -318.02931) (xy 192.637211 -317.999089) (xy 192.600855 -317.962733) (xy 192.570634 -317.921137)
			(xy 192.547291 -317.875325) (xy 192.531403 -317.826426) (xy 192.52336 -317.775644) (xy 191.280796 -317.775644)
			(xy 191.280796 -318.699896) (xy 191.280292 -318.725604) (xy 192.52336 -318.725604) (xy 192.52336 -318.674188)
			(xy 192.531403 -318.623406) (xy 192.547291 -318.574507) (xy 192.570634 -318.528695) (xy 192.600855 -318.487099)
			(xy 192.637211 -318.450743) (xy 192.678807 -318.420522) (xy 192.724619 -318.397179) (xy 192.773518 -318.381291)
			(xy 192.8243 -318.373248) (xy 192.875716 -318.373248) (xy 192.926498 -318.381291) (xy 192.975397 -318.397179)
			(xy 193.021209 -318.420522) (xy 193.062805 -318.450743) (xy 193.099161 -318.487099) (xy 193.129382 -318.528695)
			(xy 193.152725 -318.574507) (xy 193.168613 -318.623406) (xy 193.176656 -318.674188) (xy 193.17716 -318.699896)
			(xy 193.176656 -318.725604) (xy 194.42328 -318.725604) (xy 194.42328 -318.674188) (xy 194.431323 -318.623406)
			(xy 194.447211 -318.574507) (xy 194.470554 -318.528695) (xy 194.500775 -318.487099) (xy 194.537131 -318.450743)
			(xy 194.578727 -318.420522) (xy 194.624539 -318.397179) (xy 194.673438 -318.381291) (xy 194.72422 -318.373248)
			(xy 194.775636 -318.373248) (xy 194.826418 -318.381291) (xy 194.875317 -318.397179) (xy 194.921129 -318.420522)
			(xy 194.962725 -318.450743) (xy 194.999081 -318.487099) (xy 195.029302 -318.528695) (xy 195.052645 -318.574507)
			(xy 195.068533 -318.623406) (xy 195.076576 -318.674188) (xy 195.07708 -318.699896) (xy 195.076576 -318.725604)
			(xy 196.3232 -318.725604) (xy 196.3232 -318.674188) (xy 196.331243 -318.623406) (xy 196.347131 -318.574507)
			(xy 196.370474 -318.528695) (xy 196.400695 -318.487099) (xy 196.437051 -318.450743) (xy 196.478647 -318.420522)
			(xy 196.524459 -318.397179) (xy 196.573358 -318.381291) (xy 196.62414 -318.373248) (xy 196.675556 -318.373248)
			(xy 196.726338 -318.381291) (xy 196.775237 -318.397179) (xy 196.821049 -318.420522) (xy 196.862645 -318.450743)
			(xy 196.899001 -318.487099) (xy 196.929222 -318.528695) (xy 196.952565 -318.574507) (xy 196.968453 -318.623406)
			(xy 196.976496 -318.674188) (xy 196.977 -318.699896) (xy 196.976496 -318.725604) (xy 196.968453 -318.776386)
			(xy 196.952565 -318.825285) (xy 196.929222 -318.871097) (xy 196.899001 -318.912693) (xy 196.862645 -318.949049)
			(xy 196.821049 -318.97927) (xy 196.775237 -319.002613) (xy 196.726338 -319.018501) (xy 196.675556 -319.026544)
			(xy 196.62414 -319.026544) (xy 196.573358 -319.018501) (xy 196.524459 -319.002613) (xy 196.478647 -318.97927)
			(xy 196.437051 -318.949049) (xy 196.400695 -318.912693) (xy 196.370474 -318.871097) (xy 196.347131 -318.825285)
			(xy 196.331243 -318.776386) (xy 196.3232 -318.725604) (xy 195.076576 -318.725604) (xy 195.068533 -318.776386)
			(xy 195.052645 -318.825285) (xy 195.029302 -318.871097) (xy 194.999081 -318.912693) (xy 194.962725 -318.949049)
			(xy 194.921129 -318.97927) (xy 194.875317 -319.002613) (xy 194.826418 -319.018501) (xy 194.775636 -319.026544)
			(xy 194.72422 -319.026544) (xy 194.673438 -319.018501) (xy 194.624539 -319.002613) (xy 194.578727 -318.97927)
			(xy 194.537131 -318.949049) (xy 194.500775 -318.912693) (xy 194.470554 -318.871097) (xy 194.447211 -318.825285)
			(xy 194.431323 -318.776386) (xy 194.42328 -318.725604) (xy 193.176656 -318.725604) (xy 193.168613 -318.776386)
			(xy 193.152725 -318.825285) (xy 193.129382 -318.871097) (xy 193.099161 -318.912693) (xy 193.062805 -318.949049)
			(xy 193.021209 -318.97927) (xy 192.975397 -319.002613) (xy 192.926498 -319.018501) (xy 192.875716 -319.026544)
			(xy 192.8243 -319.026544) (xy 192.773518 -319.018501) (xy 192.724619 -319.002613) (xy 192.678807 -318.97927)
			(xy 192.637211 -318.949049) (xy 192.600855 -318.912693) (xy 192.570634 -318.871097) (xy 192.547291 -318.825285)
			(xy 192.531403 -318.776386) (xy 192.52336 -318.725604) (xy 191.280292 -318.725604) (xy 191.280286 -318.725903)
			(xy 191.272149 -318.777277) (xy 191.256076 -318.826745) (xy 191.232462 -318.87309) (xy 191.201888 -318.915171)
			(xy 191.165109 -318.95195) (xy 191.123028 -318.982524) (xy 191.076683 -319.006138) (xy 191.027215 -319.022211)
			(xy 190.975841 -319.030348) (xy 190.923827 -319.030348) (xy 190.872453 -319.022211) (xy 190.822985 -319.006138)
			(xy 190.77664 -318.982524) (xy 190.734559 -318.95195) (xy 190.69778 -318.915171) (xy 190.667206 -318.87309)
			(xy 190.643592 -318.826745) (xy 190.627519 -318.777277) (xy 190.619382 -318.725903) (xy 190.618872 -318.699896)
			(xy 190.618872 -317.749936) (xy 190.620904 -317.715646) (xy 190.62192 -317.704216) (xy 190.61811 -317.693294)
			(xy 190.616102 -317.687985) (xy 190.61007 -317.678371) (xy 190.606172 -317.674244) (xy 190.550546 -317.618618)
			(xy 190.542115 -317.611003) (xy 190.520749 -317.603369) (xy 190.509398 -317.603886) (xy 190.475616 -317.605664)
			(xy 190.4746 -317.605664) (xy 190.44031 -317.603886) (xy 190.42888 -317.602616) (xy 190.40729 -317.610236)
			(xy 190.343282 -317.674244) (xy 190.335711 -317.682766) (xy 190.328211 -317.70426) (xy 190.328804 -317.715646)
			(xy 190.328804 -317.716916) (xy 190.330582 -317.748666) (xy 190.330582 -317.75781) (xy 190.330328 -317.759334)
			(xy 190.330328 -317.760604) (xy 190.328953 -317.787019) (xy 190.318848 -317.838937) (xy 190.300609 -317.888585)
			(xy 190.274699 -317.934697) (xy 190.241781 -317.976096) (xy 190.202692 -318.011729) (xy 190.15843 -318.040685)
			(xy 190.134494 -318.051942) (xy 190.120524 -318.058292) (xy 190.104268 -318.083184) (xy 190.104268 -318.366648)
			(xy 190.120524 -318.39154) (xy 190.134494 -318.39789) (xy 190.157503 -318.408653) (xy 190.200192 -318.436183)
			(xy 190.238168 -318.469917) (xy 190.270538 -318.509063) (xy 190.29654 -318.552699) (xy 190.315563 -318.599798)
			(xy 190.327159 -318.649252) (xy 190.331055 -318.699898) (xy 190.32716 -318.750544) (xy 190.315564 -318.799999)
			(xy 190.296542 -318.847098) (xy 190.27054 -318.890734) (xy 190.23817 -318.929881) (xy 190.200195 -318.963615)
			(xy 190.157506 -318.991146) (xy 190.134494 -319.001902) (xy 190.120524 -319.008252) (xy 190.104268 -319.033144)
			(xy 190.104268 -319.6844) (xy 190.105284 -319.68948) (xy 190.107824 -319.703196) (xy 190.109348 -319.707768)
			(xy 190.125169 -319.750302) (xy 190.149874 -319.837632) (xy 190.166478 -319.926857) (xy 190.174843 -320.017228)
			(xy 190.175388 -320.062606) (xy 190.175388 -320.900044) (xy 202.982331 -320.900044) (xy 202.98632 -320.751504)
			(xy 202.998277 -320.603391) (xy 203.018167 -320.456134) (xy 203.045932 -320.310158) (xy 203.081493 -320.165881)
			(xy 203.124747 -320.023722) (xy 203.175569 -319.884089) (xy 203.233813 -319.747386) (xy 203.299311 -319.614006)
			(xy 203.371874 -319.484334) (xy 203.451292 -319.358744) (xy 203.537337 -319.237597) (xy 203.629761 -319.121244)
			(xy 203.728297 -319.01002) (xy 203.832661 -318.904245) (xy 203.942553 -318.804225) (xy 204.057654 -318.710247)
			(xy 204.177634 -318.622583) (xy 204.302147 -318.541486) (xy 204.430833 -318.467189) (xy 204.563322 -318.399907)
			(xy 204.699231 -318.339833) (xy 204.838169 -318.287141) (xy 204.979735 -318.241982) (xy 205.123521 -318.204487)
			(xy 205.269112 -318.174765) (xy 205.416088 -318.1529) (xy 205.564027 -318.138956) (xy 205.7125 -318.132972)
			(xy 205.861081 -318.134967) (xy 206.00934 -318.144935) (xy 206.156851 -318.162846) (xy 206.303187 -318.188649)
			(xy 206.447928 -318.222269) (xy 206.590655 -318.263611) (xy 206.730958 -318.312554) (xy 206.868431 -318.368957)
			(xy 207.002678 -318.432658) (xy 207.133313 -318.503474) (xy 207.259958 -318.581199) (xy 207.382248 -318.66561)
			(xy 207.499831 -318.756463) (xy 207.612368 -318.853497) (xy 207.719535 -318.956432) (xy 207.821022 -319.064971)
			(xy 207.916536 -319.1788) (xy 208.005803 -319.297593) (xy 208.088564 -319.421005) (xy 208.164582 -319.548683)
			(xy 208.233637 -319.680256) (xy 208.29553 -319.815347) (xy 208.350083 -319.953564) (xy 208.397138 -320.094511)
			(xy 208.43656 -320.237781) (xy 208.468234 -320.38296) (xy 208.49207 -320.529629) (xy 208.507999 -320.677367)
			(xy 208.51549 -320.816732) (xy 224.888044 -320.816732) (xy 224.888518 -320.789362) (xy 224.896332 -320.735183)
			(xy 224.911819 -320.682679) (xy 224.934659 -320.632932) (xy 224.964383 -320.586966) (xy 224.982024 -320.566034)
			(xy 224.98812 -320.558922) (xy 224.99447 -320.541904) (xy 224.99447 -320.45656) (xy 224.98812 -320.439542)
			(xy 224.982024 -320.43243) (xy 224.964389 -320.411494) (xy 224.934676 -320.365523) (xy 224.911839 -320.315776)
			(xy 224.896347 -320.263276) (xy 224.888518 -320.209101) (xy 224.888044 -320.181732) (xy 224.888608 -320.154484)
			(xy 224.896359 -320.100541) (xy 224.911707 -320.048251) (xy 224.934341 -319.998677) (xy 224.9638 -319.952829)
			(xy 224.999483 -319.91164) (xy 225.040665 -319.875948) (xy 225.086507 -319.84648) (xy 225.136076 -319.823835)
			(xy 225.188363 -319.808476) (xy 225.242304 -319.800714) (xy 225.269552 -319.800224) (xy 225.296921 -319.800712)
			(xy 225.3511 -319.808524) (xy 225.403603 -319.824007) (xy 225.45335 -319.846844) (xy 225.499318 -319.876565)
			(xy 225.52025 -319.894204) (xy 225.527362 -319.9003) (xy 225.54438 -319.90665) (xy 225.629724 -319.90665)
			(xy 225.646742 -319.9003) (xy 225.653854 -319.894204) (xy 225.674787 -319.876563) (xy 225.720755 -319.846839)
			(xy 225.770501 -319.823993) (xy 225.823003 -319.808497) (xy 225.877181 -319.800668) (xy 225.931923 -319.800668)
			(xy 225.986101 -319.808497) (xy 226.038603 -319.823993) (xy 226.088349 -319.846839) (xy 226.134317 -319.876563)
			(xy 226.15525 -319.894204) (xy 226.162362 -319.9003) (xy 226.17938 -319.90665) (xy 226.264724 -319.90665)
			(xy 226.281742 -319.9003) (xy 226.288854 -319.894204) (xy 226.309793 -319.876574) (xy 226.355764 -319.84686)
			(xy 226.40551 -319.824023) (xy 226.458009 -319.80853) (xy 226.512183 -319.800699) (xy 226.539552 -319.800224)
			(xy 226.566805 -319.8007) (xy 226.620757 -319.808451) (xy 226.673057 -319.823803) (xy 226.722639 -319.846442)
			(xy 226.768494 -319.875908) (xy 226.809688 -319.911601) (xy 226.845382 -319.952793) (xy 226.87485 -319.998647)
			(xy 226.897492 -320.048228) (xy 226.912845 -320.100527) (xy 226.920599 -320.154479) (xy 226.92106 -320.181732)
			(xy 226.920622 -320.209103) (xy 226.912799 -320.263284) (xy 226.897304 -320.315788) (xy 226.874456 -320.365534)
			(xy 226.844725 -320.4115) (xy 226.82708 -320.43243) (xy 226.820984 -320.439542) (xy 226.814634 -320.45656)
			(xy 226.814634 -320.541904) (xy 226.820984 -320.558922) (xy 226.82708 -320.566034) (xy 226.844699 -320.586983)
			(xy 226.874414 -320.632951) (xy 226.897254 -320.682694) (xy 226.91275 -320.735191) (xy 226.920583 -320.789364)
			(xy 226.92106 -320.816732) (xy 241.138202 -320.816732) (xy 241.138686 -320.789362) (xy 241.1465 -320.735184)
			(xy 241.161984 -320.682681) (xy 241.184822 -320.632934) (xy 241.214543 -320.586966) (xy 241.232182 -320.566034)
			(xy 241.238278 -320.558922) (xy 241.244628 -320.541904) (xy 241.244628 -320.45656) (xy 241.238278 -320.439542)
			(xy 241.232182 -320.43243) (xy 241.214541 -320.4115) (xy 241.18483 -320.365526) (xy 241.161995 -320.315778)
			(xy 241.146504 -320.263277) (xy 241.138676 -320.209101) (xy 241.138202 -320.181732) (xy 241.138685 -320.154479)
			(xy 241.146438 -320.100529) (xy 241.16179 -320.048231) (xy 241.18443 -319.99865) (xy 241.213896 -319.952796)
			(xy 241.249587 -319.911603) (xy 241.290779 -319.875909) (xy 241.336631 -319.846441) (xy 241.38621 -319.823798)
			(xy 241.438507 -319.808443) (xy 241.492458 -319.800687) (xy 241.51971 -319.800224) (xy 241.547081 -319.800678)
			(xy 241.601261 -319.808498) (xy 241.653764 -319.82399) (xy 241.703511 -319.846834) (xy 241.749477 -319.876561)
			(xy 241.770408 -319.894204) (xy 241.77752 -319.9003) (xy 241.794538 -319.90665) (xy 241.879882 -319.90665)
			(xy 241.8969 -319.9003) (xy 241.904012 -319.894204) (xy 241.924945 -319.876563) (xy 241.970913 -319.846839)
			(xy 242.020659 -319.823993) (xy 242.073161 -319.808497) (xy 242.127339 -319.800668) (xy 242.182081 -319.800668)
			(xy 242.236259 -319.808497) (xy 242.288761 -319.823993) (xy 242.338507 -319.846839) (xy 242.384475 -319.876563)
			(xy 242.405408 -319.894204) (xy 242.41252 -319.9003) (xy 242.429538 -319.90665) (xy 242.514882 -319.90665)
			(xy 242.5319 -319.9003) (xy 242.539012 -319.894204) (xy 242.559967 -319.876593) (xy 242.605933 -319.846877)
			(xy 242.655675 -319.824036) (xy 242.708171 -319.808538) (xy 242.762342 -319.800702) (xy 242.78971 -319.800224)
			(xy 242.816965 -319.800646) (xy 242.870919 -319.808405) (xy 242.923219 -319.823764) (xy 242.972802 -319.84641)
			(xy 243.018656 -319.875882) (xy 243.05985 -319.91158) (xy 243.095543 -319.952777) (xy 243.12501 -319.998635)
			(xy 243.147651 -320.04822) (xy 243.163004 -320.100522) (xy 243.170757 -320.154477) (xy 243.171218 -320.181732)
			(xy 243.170791 -320.209104) (xy 243.162967 -320.263285) (xy 243.14747 -320.31579) (xy 243.124619 -320.365536)
			(xy 243.094884 -320.4115) (xy 243.077238 -320.43243) (xy 243.071142 -320.439542) (xy 243.064792 -320.45656)
			(xy 243.064792 -320.541904) (xy 243.071142 -320.558922) (xy 243.077238 -320.566034) (xy 243.094866 -320.586975)
			(xy 243.124578 -320.632946) (xy 243.147416 -320.682691) (xy 243.16291 -320.73519) (xy 243.170742 -320.789364)
			(xy 243.171218 -320.816732) (xy 243.170752 -320.843984) (xy 243.162991 -320.897931) (xy 243.147633 -320.950226)
			(xy 243.124989 -320.999803) (xy 243.09552 -321.045652) (xy 243.059826 -321.086842) (xy 243.018635 -321.122533)
			(xy 242.972783 -321.151999) (xy 242.923205 -321.17464) (xy 242.87091 -321.189996) (xy 242.816962 -321.197754)
			(xy 242.78971 -321.19824) (xy 242.762339 -321.197783) (xy 242.708159 -321.189965) (xy 242.655655 -321.174475)
			(xy 242.605909 -321.151631) (xy 242.559943 -321.121903) (xy 242.539012 -321.10426) (xy 242.5319 -321.098164)
			(xy 242.514882 -321.091814) (xy 242.429538 -321.091814) (xy 242.41252 -321.098164) (xy 242.405408 -321.10426)
			(xy 242.384475 -321.121901) (xy 242.338507 -321.151625) (xy 242.288761 -321.174471) (xy 242.236259 -321.189967)
			(xy 242.182081 -321.197796) (xy 242.127339 -321.197796) (xy 242.073161 -321.189967) (xy 242.020659 -321.174471)
			(xy 241.970913 -321.151625) (xy 241.924945 -321.121901) (xy 241.904012 -321.10426) (xy 241.8969 -321.098164)
			(xy 241.879882 -321.091814) (xy 241.794538 -321.091814) (xy 241.77752 -321.098164) (xy 241.770408 -321.10426)
			(xy 241.749479 -321.121903) (xy 241.703506 -321.151615) (xy 241.653758 -321.174451) (xy 241.601256 -321.189941)
			(xy 241.547079 -321.197767) (xy 241.51971 -321.19824) (xy 241.49246 -321.197713) (xy 241.438516 -321.189958)
			(xy 241.386224 -321.174606) (xy 241.336649 -321.151968) (xy 241.2908 -321.122506) (xy 241.249611 -321.086819)
			(xy 241.213919 -321.045634) (xy 241.184452 -320.999788) (xy 241.161809 -320.950215) (xy 241.146451 -320.897925)
			(xy 241.13869 -320.843981) (xy 241.138202 -320.816732) (xy 226.92106 -320.816732) (xy 226.920675 -320.843988)
			(xy 226.912912 -320.897944) (xy 226.89755 -320.950246) (xy 226.8749 -320.99983) (xy 226.845424 -321.045685)
			(xy 226.809722 -321.086879) (xy 226.768521 -321.122572) (xy 226.72266 -321.152038) (xy 226.673071 -321.174678)
			(xy 226.620766 -321.190029) (xy 226.566808 -321.19778) (xy 226.539552 -321.19824) (xy 226.512182 -321.197758)
			(xy 226.458003 -321.189946) (xy 226.4055 -321.174462) (xy 226.355752 -321.151623) (xy 226.309786 -321.121901)
			(xy 226.288854 -321.10426) (xy 226.281742 -321.098164) (xy 226.264724 -321.091814) (xy 226.17938 -321.091814)
			(xy 226.162362 -321.098164) (xy 226.15525 -321.10426) (xy 226.134317 -321.121901) (xy 226.088349 -321.151625)
			(xy 226.038603 -321.174471) (xy 225.986101 -321.189967) (xy 225.931923 -321.197796) (xy 225.877181 -321.197796)
			(xy 225.823003 -321.189967) (xy 225.770501 -321.174471) (xy 225.720755 -321.151625) (xy 225.674787 -321.121901)
			(xy 225.653854 -321.10426) (xy 225.646742 -321.098164) (xy 225.629724 -321.091814) (xy 225.54438 -321.091814)
			(xy 225.527362 -321.098164) (xy 225.52025 -321.10426) (xy 225.499305 -321.121883) (xy 225.453336 -321.151599)
			(xy 225.403592 -321.174438) (xy 225.351094 -321.189933) (xy 225.29692 -321.197764) (xy 225.269552 -321.19824)
			(xy 225.242301 -321.197767) (xy 225.188355 -321.190005) (xy 225.136062 -321.174645) (xy 225.086486 -321.152001)
			(xy 225.040638 -321.122532) (xy 224.999449 -321.08684) (xy 224.963758 -321.04565) (xy 224.934292 -320.9998)
			(xy 224.911649 -320.950223) (xy 224.896292 -320.89793) (xy 224.888532 -320.843983) (xy 224.888044 -320.816732)
			(xy 208.51549 -320.816732) (xy 208.515975 -320.825747) (xy 208.516474 -320.900044) (xy 208.515975 -320.974341)
			(xy 208.507999 -321.122721) (xy 208.49207 -321.270459) (xy 208.468234 -321.417128) (xy 208.43656 -321.562307)
			(xy 208.397138 -321.705577) (xy 208.350083 -321.846524) (xy 208.29553 -321.984741) (xy 208.233637 -322.119832)
			(xy 208.164582 -322.251405) (xy 208.088564 -322.379083) (xy 208.005803 -322.502495) (xy 207.916536 -322.621288)
			(xy 207.821022 -322.735117) (xy 207.719535 -322.843656) (xy 207.612368 -322.946591) (xy 207.499831 -323.043625)
			(xy 207.382248 -323.134478) (xy 207.259958 -323.218889) (xy 207.133313 -323.296614) (xy 207.002678 -323.36743)
			(xy 206.868431 -323.431131) (xy 206.730958 -323.487534) (xy 206.590655 -323.536477) (xy 206.447928 -323.577819)
			(xy 206.303187 -323.611439) (xy 206.156851 -323.637242) (xy 206.00934 -323.655153) (xy 205.861081 -323.665121)
			(xy 205.7125 -323.667116) (xy 205.564027 -323.661132) (xy 205.416088 -323.647188) (xy 205.269112 -323.625323)
			(xy 205.123521 -323.595601) (xy 204.979735 -323.558106) (xy 204.838169 -323.512947) (xy 204.699231 -323.460255)
			(xy 204.563322 -323.400181) (xy 204.430833 -323.332899) (xy 204.302147 -323.258602) (xy 204.177634 -323.177505)
			(xy 204.057654 -323.089841) (xy 203.942553 -322.995863) (xy 203.832661 -322.895843) (xy 203.728297 -322.790068)
			(xy 203.629761 -322.678844) (xy 203.537337 -322.562491) (xy 203.451292 -322.441344) (xy 203.371874 -322.315754)
			(xy 203.299311 -322.186082) (xy 203.233813 -322.052702) (xy 203.175569 -321.915999) (xy 203.124747 -321.776366)
			(xy 203.081493 -321.634207) (xy 203.045932 -321.48993) (xy 203.018167 -321.343954) (xy 202.998277 -321.196697)
			(xy 202.98632 -321.048584) (xy 202.982331 -320.900044) (xy 190.175388 -320.900044) (xy 190.175388 -321.578986)
			(xy 190.175642 -321.580764) (xy 190.175896 -321.585844) (xy 190.175896 -321.586352) (xy 190.1753 -321.634873)
			(xy 190.165789 -321.731448) (xy 190.146864 -321.826626) (xy 190.118707 -321.919493) (xy 190.100712 -321.964558)
			(xy 189.11824 -324.337426) (xy 189.117986 -324.33768) (xy 189.114176 -324.347078) (xy 189.099285 -324.382746)
			(xy 189.064699 -324.451877) (xy 189.024829 -324.518101) (xy 189.00267 -324.54977) (xy 189.002416 -324.550024)
			(xy 189.001146 -324.551802) (xy 189.000384 -324.553072) (xy 188.980189 -324.584559) (xy 188.935744 -324.644734)
			(xy 188.886908 -324.701404) (xy 188.860684 -324.728078) (xy 187.073032 -326.51573) (xy 187.037988 -326.549974)
			(xy 186.962288 -326.612193) (xy 186.921902 -326.639936) (xy 183.298119 -329.061064) (xy 225.609148 -329.061064)
			(xy 225.613219 -329.005442) (xy 225.625345 -328.951005) (xy 225.645268 -328.898914) (xy 225.672564 -328.850279)
			(xy 225.70665 -328.806136) (xy 225.746799 -328.767427) (xy 225.792157 -328.734976) (xy 225.841757 -328.709475)
			(xy 225.894541 -328.691468) (xy 225.949384 -328.681338) (xy 226.005118 -328.679301) (xy 226.060555 -328.685401)
			(xy 226.114512 -328.699507) (xy 226.165841 -328.721319) (xy 226.213447 -328.750373) (xy 226.256315 -328.786048)
			(xy 226.293532 -328.827585) (xy 226.324305 -328.874098) (xy 226.347977 -328.924595) (xy 226.364045 -328.978002)
			(xy 226.372165 -329.033178) (xy 226.372674 -329.061064) (xy 226.372165 -329.08895) (xy 226.364045 -329.144126)
			(xy 226.347977 -329.197533) (xy 226.324305 -329.24803) (xy 226.293532 -329.294543) (xy 226.256315 -329.33608)
			(xy 226.213447 -329.371755) (xy 226.165841 -329.400809) (xy 226.114512 -329.422621) (xy 226.060555 -329.436727)
			(xy 226.005118 -329.442827) (xy 225.949384 -329.44079) (xy 225.894541 -329.43066) (xy 225.841757 -329.412653)
			(xy 225.792157 -329.387152) (xy 225.746799 -329.354701) (xy 225.70665 -329.315992) (xy 225.672564 -329.271849)
			(xy 225.645268 -329.223214) (xy 225.625345 -329.171123) (xy 225.613219 -329.116686) (xy 225.609148 -329.061064)
			(xy 183.298119 -329.061064) (xy 182.906924 -329.32243) (xy 182.892476 -329.332024) (xy 182.863005 -329.350316)
			(xy 182.847996 -329.359006) (xy 182.823104 -329.372722) (xy 182.816754 -329.376024) (xy 182.78094 -329.395074)
			(xy 182.780178 -329.395836) (xy 182.74411 -329.415902) (xy 180.883265 -330.411582) (xy 221.258892 -330.411582)
			(xy 221.259349 -330.384211) (xy 221.26717 -330.330032) (xy 221.282661 -330.277529) (xy 221.305504 -330.227782)
			(xy 221.33523 -330.181816) (xy 221.352872 -330.160884) (xy 221.358968 -330.153772) (xy 221.365318 -330.136754)
			(xy 221.365318 -330.05141) (xy 221.358968 -330.034392) (xy 221.352872 -330.02728) (xy 221.335253 -330.006332)
			(xy 221.305539 -329.960363) (xy 221.282699 -329.91062) (xy 221.267204 -329.858123) (xy 221.259369 -329.80395)
			(xy 221.258892 -329.776582) (xy 221.259378 -329.749331) (xy 221.267134 -329.695383) (xy 221.282489 -329.643088)
			(xy 221.305131 -329.593511) (xy 221.334597 -329.547661) (xy 221.370288 -329.50647) (xy 221.411479 -329.470779)
			(xy 221.457329 -329.441313) (xy 221.506906 -329.418671) (xy 221.559201 -329.403316) (xy 221.613149 -329.39556)
			(xy 221.667651 -329.39556) (xy 221.721599 -329.403316) (xy 221.773894 -329.418671) (xy 221.823471 -329.441313)
			(xy 221.869321 -329.470779) (xy 221.910512 -329.50647) (xy 221.946203 -329.547661) (xy 221.975669 -329.593511)
			(xy 221.998311 -329.643088) (xy 222.013666 -329.695383) (xy 222.021422 -329.749331) (xy 222.021908 -329.776582)
			(xy 222.021429 -329.803952) (xy 222.013614 -329.85813) (xy 222.009273 -329.872848) (xy 224.897186 -329.872848)
			(xy 224.901257 -329.817226) (xy 224.913383 -329.762789) (xy 224.933306 -329.710698) (xy 224.960602 -329.662063)
			(xy 224.994688 -329.61792) (xy 225.034837 -329.579211) (xy 225.080195 -329.54676) (xy 225.129795 -329.521259)
			(xy 225.182579 -329.503252) (xy 225.237422 -329.493122) (xy 225.293156 -329.491085) (xy 225.348593 -329.497185)
			(xy 225.40255 -329.511291) (xy 225.453879 -329.533103) (xy 225.501485 -329.562157) (xy 225.544353 -329.597832)
			(xy 225.58157 -329.639369) (xy 225.612343 -329.685882) (xy 225.636015 -329.736379) (xy 225.652083 -329.789786)
			(xy 225.660203 -329.844962) (xy 225.660712 -329.872848) (xy 225.660203 -329.900734) (xy 225.652083 -329.95591)
			(xy 225.636015 -330.009317) (xy 225.612343 -330.059814) (xy 225.58157 -330.106327) (xy 225.544353 -330.147864)
			(xy 225.501485 -330.183539) (xy 225.453879 -330.212593) (xy 225.40255 -330.234405) (xy 225.348593 -330.248511)
			(xy 225.293156 -330.254611) (xy 225.237422 -330.252574) (xy 225.182579 -330.242444) (xy 225.129795 -330.224437)
			(xy 225.080195 -330.198936) (xy 225.034837 -330.166485) (xy 224.994688 -330.127776) (xy 224.960602 -330.083633)
			(xy 224.933306 -330.034998) (xy 224.913383 -329.982907) (xy 224.901257 -329.92847) (xy 224.897186 -329.872848)
			(xy 222.009273 -329.872848) (xy 221.998128 -329.910633) (xy 221.975289 -329.96038) (xy 221.945568 -330.006348)
			(xy 221.927928 -330.02728) (xy 221.921832 -330.034392) (xy 221.915482 -330.05141) (xy 221.915482 -330.136754)
			(xy 221.921832 -330.153772) (xy 221.927928 -330.160884) (xy 221.945577 -330.181808) (xy 221.975287 -330.227783)
			(xy 221.99812 -330.277533) (xy 222.013609 -330.330035) (xy 222.021435 -330.384212) (xy 222.021908 -330.411582)
			(xy 222.021422 -330.438833) (xy 222.013666 -330.492781) (xy 221.998311 -330.545076) (xy 221.975669 -330.594653)
			(xy 221.946203 -330.640503) (xy 221.910512 -330.681694) (xy 221.869321 -330.717385) (xy 221.823471 -330.746851)
			(xy 221.773894 -330.769493) (xy 221.721599 -330.784848) (xy 221.667651 -330.792604) (xy 221.613149 -330.792604)
			(xy 221.559201 -330.784848) (xy 221.506906 -330.769493) (xy 221.457329 -330.746851) (xy 221.411479 -330.717385)
			(xy 221.370288 -330.681694) (xy 221.334597 -330.640503) (xy 221.305131 -330.594653) (xy 221.282489 -330.545076)
			(xy 221.267134 -330.492781) (xy 221.259378 -330.438833) (xy 221.258892 -330.411582) (xy 180.883265 -330.411582)
			(xy 179.32908 -331.243178) (xy 179.325778 -331.24521) (xy 174.991626 -334.00746) (xy 225.00285 -334.00746)
			(xy 225.006921 -333.951838) (xy 225.019047 -333.897401) (xy 225.03897 -333.84531) (xy 225.066266 -333.796675)
			(xy 225.100352 -333.752532) (xy 225.140501 -333.713823) (xy 225.185859 -333.681372) (xy 225.235459 -333.655871)
			(xy 225.288243 -333.637864) (xy 225.343086 -333.627734) (xy 225.39882 -333.625697) (xy 225.454257 -333.631797)
			(xy 225.508214 -333.645903) (xy 225.559543 -333.667715) (xy 225.607149 -333.696769) (xy 225.650017 -333.732444)
			(xy 225.687234 -333.773981) (xy 225.718007 -333.820494) (xy 225.72409 -333.83347) (xy 225.95916 -333.83347)
			(xy 225.963231 -333.777848) (xy 225.975357 -333.723411) (xy 225.99528 -333.67132) (xy 226.022576 -333.622685)
			(xy 226.056662 -333.578542) (xy 226.096811 -333.539833) (xy 226.142169 -333.507382) (xy 226.191769 -333.481881)
			(xy 226.244553 -333.463874) (xy 226.299396 -333.453744) (xy 226.35513 -333.451707) (xy 226.410567 -333.457807)
			(xy 226.464524 -333.471913) (xy 226.515853 -333.493725) (xy 226.563459 -333.522779) (xy 226.606327 -333.558454)
			(xy 226.643544 -333.599991) (xy 226.674317 -333.646504) (xy 226.697989 -333.697001) (xy 226.714057 -333.750408)
			(xy 226.722177 -333.805584) (xy 226.722686 -333.83347) (xy 226.722177 -333.861356) (xy 226.714057 -333.916532)
			(xy 226.697989 -333.969939) (xy 226.674317 -334.020436) (xy 226.643544 -334.066949) (xy 226.606327 -334.108486)
			(xy 226.563459 -334.144161) (xy 226.515853 -334.173215) (xy 226.464524 -334.195027) (xy 226.410567 -334.209133)
			(xy 226.35513 -334.215233) (xy 226.299396 -334.213196) (xy 226.244553 -334.203066) (xy 226.191769 -334.185059)
			(xy 226.142169 -334.159558) (xy 226.096811 -334.127107) (xy 226.056662 -334.088398) (xy 226.022576 -334.044255)
			(xy 225.99528 -333.99562) (xy 225.975357 -333.943529) (xy 225.963231 -333.889092) (xy 225.95916 -333.83347)
			(xy 225.72409 -333.83347) (xy 225.741679 -333.870991) (xy 225.757747 -333.924398) (xy 225.765867 -333.979574)
			(xy 225.766376 -334.00746) (xy 225.765867 -334.035346) (xy 225.757747 -334.090522) (xy 225.741679 -334.143929)
			(xy 225.718007 -334.194426) (xy 225.687234 -334.240939) (xy 225.650017 -334.282476) (xy 225.607149 -334.318151)
			(xy 225.559543 -334.347205) (xy 225.508214 -334.369017) (xy 225.454257 -334.383123) (xy 225.39882 -334.389223)
			(xy 225.343086 -334.387186) (xy 225.288243 -334.377056) (xy 225.235459 -334.359049) (xy 225.185859 -334.333548)
			(xy 225.140501 -334.301097) (xy 225.100352 -334.262388) (xy 225.066266 -334.218245) (xy 225.03897 -334.16961)
			(xy 225.019047 -334.117519) (xy 225.006921 -334.063082) (xy 225.00285 -334.00746) (xy 174.991626 -334.00746)
			(xy 167.403374 -338.84362) (xy 201.544174 -338.84362) (xy 201.544602 -338.817303) (xy 201.551829 -338.765168)
			(xy 201.566147 -338.71452) (xy 201.587286 -338.666319) (xy 201.614845 -338.621477) (xy 201.648302 -338.580846)
			(xy 201.667364 -338.562696) (xy 201.674764 -338.555173) (xy 201.683291 -338.535894) (xy 201.683874 -338.525358)
			(xy 201.683874 -338.450682) (xy 201.683322 -338.440135) (xy 201.674804 -338.420839) (xy 201.667364 -338.413344)
			(xy 201.648318 -338.395175) (xy 201.614835 -338.354564) (xy 201.587258 -338.309731) (xy 201.566113 -338.26153)
			(xy 201.551802 -338.210877) (xy 201.544598 -338.158738) (xy 201.544174 -338.13242) (xy 201.54466 -338.105169)
			(xy 201.552416 -338.051221) (xy 201.567771 -337.998926) (xy 201.590413 -337.949349) (xy 201.619879 -337.903499)
			(xy 201.65557 -337.862308) (xy 201.696761 -337.826617) (xy 201.742611 -337.797151) (xy 201.792188 -337.774509)
			(xy 201.844483 -337.759154) (xy 201.898431 -337.751398) (xy 201.952933 -337.751398) (xy 202.006881 -337.759154)
			(xy 202.059176 -337.774509) (xy 202.108753 -337.797151) (xy 202.154603 -337.826617) (xy 202.195794 -337.862308)
			(xy 202.231485 -337.903499) (xy 202.260951 -337.949349) (xy 202.283593 -337.998926) (xy 202.298948 -338.051221)
			(xy 202.306704 -338.105169) (xy 202.30719 -338.13242) (xy 202.306733 -338.158736) (xy 202.299514 -338.21087)
			(xy 202.285202 -338.261518) (xy 202.264068 -338.30972) (xy 202.236514 -338.354562) (xy 202.20306 -338.395194)
			(xy 202.184 -338.413344) (xy 202.176577 -338.420847) (xy 202.168065 -338.440141) (xy 202.16749 -338.450682)
			(xy 202.16749 -338.525358) (xy 202.168031 -338.535906) (xy 202.176558 -338.555202) (xy 202.184 -338.562696)
			(xy 202.203077 -338.580833) (xy 202.236556 -338.621453) (xy 202.264126 -338.666293) (xy 202.285265 -338.7145)
			(xy 202.29957 -338.765157) (xy 202.306769 -338.817301) (xy 202.30719 -338.84362) (xy 202.306704 -338.870871)
			(xy 202.298948 -338.924819) (xy 202.283593 -338.977114) (xy 202.260951 -339.026691) (xy 202.231485 -339.072541)
			(xy 202.195794 -339.113732) (xy 202.154603 -339.149423) (xy 202.108753 -339.178889) (xy 202.059176 -339.201531)
			(xy 202.006881 -339.216886) (xy 201.952933 -339.224642) (xy 201.898431 -339.224642) (xy 201.844483 -339.216886)
			(xy 201.792188 -339.201531) (xy 201.742611 -339.178889) (xy 201.696761 -339.149423) (xy 201.65557 -339.113732)
			(xy 201.619879 -339.072541) (xy 201.590413 -339.026691) (xy 201.567771 -338.977114) (xy 201.552416 -338.924819)
			(xy 201.54466 -338.870871) (xy 201.544174 -338.84362) (xy 167.403374 -338.84362) (xy 162.765486 -341.799448)
			(xy 231.047318 -341.799448) (xy 231.047318 -341.744952) (xy 231.055074 -341.691011) (xy 231.070427 -341.638723)
			(xy 231.093065 -341.589151) (xy 231.122527 -341.543306) (xy 231.158213 -341.502121) (xy 231.199398 -341.466433)
			(xy 231.245242 -341.436969) (xy 231.294813 -341.41433) (xy 231.347101 -341.398976) (xy 231.401042 -341.391219)
			(xy 231.42829 -341.390732) (xy 231.456426 -341.391179) (xy 231.51209 -341.399433) (xy 231.565936 -341.415778)
			(xy 231.616795 -341.439859) (xy 231.663563 -341.471153) (xy 231.705224 -341.508981) (xy 231.723438 -341.530432)
			(xy 231.73055 -341.539322) (xy 231.750616 -341.548974) (xy 231.850438 -341.550752) (xy 231.870758 -341.541862)
			(xy 231.878124 -341.53348) (xy 231.896316 -341.513539) (xy 231.937357 -341.478478) (xy 231.982928 -341.449551)
			(xy 232.032122 -341.427334) (xy 232.083955 -341.412271) (xy 232.137393 -341.404662) (xy 232.164382 -341.404194)
			(xy 232.191636 -341.404652) (xy 232.245589 -341.412407) (xy 232.297889 -341.427762) (xy 232.347472 -341.450403)
			(xy 232.393328 -341.479871) (xy 232.434523 -341.515565) (xy 232.470218 -341.556758) (xy 232.499688 -341.602612)
			(xy 232.522332 -341.652194) (xy 232.537689 -341.704493) (xy 232.545447 -341.758446) (xy 232.545447 -341.812954)
			(xy 232.537689 -341.866907) (xy 232.522332 -341.919206) (xy 232.499688 -341.968788) (xy 232.470218 -342.014642)
			(xy 232.434523 -342.055835) (xy 232.429691 -342.060022) (xy 255.91262 -342.060022) (xy 255.91262 -341.196422)
			(xy 255.91311 -341.166438) (xy 255.920938 -341.106982) (xy 255.936459 -341.049057) (xy 255.959408 -340.993653)
			(xy 255.989392 -340.941719) (xy 256.025898 -340.894143) (xy 256.068303 -340.851738) (xy 256.115879 -340.815232)
			(xy 256.167813 -340.785248) (xy 256.223217 -340.762299) (xy 256.281142 -340.746778) (xy 256.340598 -340.73895)
			(xy 256.400566 -340.73895) (xy 256.460022 -340.746778) (xy 256.517947 -340.762299) (xy 256.573351 -340.785248)
			(xy 256.625285 -340.815232) (xy 256.672861 -340.851738) (xy 256.715266 -340.894143) (xy 256.751772 -340.941719)
			(xy 256.781756 -340.993653) (xy 256.804705 -341.049057) (xy 256.820226 -341.106982) (xy 256.828054 -341.166438)
			(xy 256.828544 -341.196422) (xy 256.828544 -342.060022) (xy 256.828054 -342.090006) (xy 256.820226 -342.149462)
			(xy 256.804705 -342.207387) (xy 256.781756 -342.262791) (xy 256.751772 -342.314725) (xy 256.715266 -342.362301)
			(xy 256.672861 -342.404706) (xy 256.625285 -342.441212) (xy 256.573351 -342.471196) (xy 256.517947 -342.494145)
			(xy 256.460022 -342.509666) (xy 256.400566 -342.517494) (xy 256.340598 -342.517494) (xy 256.281142 -342.509666)
			(xy 256.223217 -342.494145) (xy 256.167813 -342.471196) (xy 256.115879 -342.441212) (xy 256.068303 -342.404706)
			(xy 256.025898 -342.362301) (xy 255.989392 -342.314725) (xy 255.959408 -342.262791) (xy 255.936459 -342.207387)
			(xy 255.920938 -342.149462) (xy 255.91311 -342.090006) (xy 255.91262 -342.060022) (xy 232.429691 -342.060022)
			(xy 232.393328 -342.091529) (xy 232.347472 -342.120997) (xy 232.297889 -342.143638) (xy 232.245589 -342.158993)
			(xy 232.191636 -342.166748) (xy 232.164382 -342.16721) (xy 232.136248 -342.166698) (xy 232.080588 -342.158455)
			(xy 232.026744 -342.142122) (xy 231.975885 -342.118053) (xy 231.929115 -342.086771) (xy 231.887451 -342.048955)
			(xy 231.869234 -342.02751) (xy 231.862122 -342.01862) (xy 231.842056 -342.008968) (xy 231.742234 -342.00719)
			(xy 231.721914 -342.01608) (xy 231.714548 -342.024462) (xy 231.696358 -342.044406) (xy 231.655318 -342.079468)
			(xy 231.609747 -342.108397) (xy 231.560553 -342.130614) (xy 231.508719 -342.145676) (xy 231.455279 -342.153282)
			(xy 231.42829 -342.153748) (xy 231.401042 -342.153181) (xy 231.347101 -342.145424) (xy 231.294813 -342.13007)
			(xy 231.245242 -342.107431) (xy 231.199398 -342.077967) (xy 231.158213 -342.042279) (xy 231.122527 -342.001094)
			(xy 231.093065 -341.955249) (xy 231.070427 -341.905677) (xy 231.055074 -341.853389) (xy 231.047318 -341.799448)
			(xy 162.765486 -341.799448) (xy 161.718417 -342.466768) (xy 164.913822 -342.466768) (xy 164.913822 -342.412232)
			(xy 164.921583 -342.35825) (xy 164.936947 -342.305923) (xy 164.959602 -342.256314) (xy 164.989085 -342.210434)
			(xy 165.024797 -342.169217) (xy 165.066012 -342.133502) (xy 165.11189 -342.104015) (xy 165.161496 -342.081357)
			(xy 165.213823 -342.065989) (xy 165.267804 -342.058224) (xy 165.295072 -342.057736) (xy 166.158672 -342.057736)
			(xy 166.185944 -342.058202) (xy 166.239934 -342.06596) (xy 166.29227 -342.081324) (xy 166.341886 -342.10398)
			(xy 166.387773 -342.133467) (xy 166.428996 -342.169184) (xy 166.464716 -342.210405) (xy 166.494207 -342.256289)
			(xy 166.516866 -342.305904) (xy 166.532234 -342.358239) (xy 166.539996 -342.412228) (xy 166.539996 -342.466772)
			(xy 166.539996 -342.466773) (xy 168.0227 -342.466773) (xy 168.0227 -342.412227) (xy 168.030463 -342.358237)
			(xy 168.045831 -342.305902) (xy 168.068491 -342.256286) (xy 168.097981 -342.210401) (xy 168.133702 -342.16918)
			(xy 168.174927 -342.133462) (xy 168.220815 -342.103975) (xy 168.270432 -342.081319) (xy 168.322769 -342.065956)
			(xy 168.376759 -342.058197) (xy 168.404032 -342.057736) (xy 169.267632 -342.057736) (xy 169.2949 -342.058229)
			(xy 169.34888 -342.065994) (xy 169.401205 -342.081362) (xy 169.450811 -342.10402) (xy 169.496688 -342.133506)
			(xy 169.537901 -342.169222) (xy 169.573613 -342.210438) (xy 169.603095 -342.256317) (xy 169.625749 -342.305925)
			(xy 169.641113 -342.358252) (xy 169.648874 -342.412232) (xy 169.648874 -342.466768) (xy 169.648874 -342.466769)
			(xy 171.131722 -342.466769) (xy 171.131722 -342.412231) (xy 171.139484 -342.358248) (xy 171.154849 -342.305918)
			(xy 171.177505 -342.256309) (xy 171.20699 -342.210428) (xy 171.242705 -342.16921) (xy 171.283921 -342.133495)
			(xy 171.329802 -342.104009) (xy 171.379411 -342.081352) (xy 171.43174 -342.065986) (xy 171.485723 -342.058223)
			(xy 171.512992 -342.057736) (xy 172.376592 -342.057736) (xy 172.403863 -342.058203) (xy 172.457851 -342.065964)
			(xy 172.510184 -342.08133) (xy 172.559798 -342.103987) (xy 172.605682 -342.133474) (xy 172.646903 -342.169191)
			(xy 172.682621 -342.210411) (xy 172.71211 -342.256295) (xy 172.734768 -342.305908) (xy 172.750134 -342.358241)
			(xy 172.757896 -342.412229) (xy 172.757896 -342.466767) (xy 174.240722 -342.466767) (xy 174.240722 -342.412233)
			(xy 174.248483 -342.358253) (xy 174.263846 -342.305927) (xy 174.286499 -342.25632) (xy 174.31598 -342.210441)
			(xy 174.35169 -342.169224) (xy 174.392902 -342.133509) (xy 174.438778 -342.104022) (xy 174.488382 -342.081363)
			(xy 174.540706 -342.065993) (xy 174.594685 -342.058226) (xy 174.621952 -342.057736) (xy 175.485552 -342.057736)
			(xy 175.512825 -342.0582) (xy 175.566817 -342.065957) (xy 175.619155 -342.081319) (xy 175.668774 -342.103974)
			(xy 175.714663 -342.13346) (xy 175.755889 -342.169177) (xy 175.791612 -342.210398) (xy 175.821103 -342.256284)
			(xy 175.843764 -342.3059) (xy 175.859133 -342.358236) (xy 175.866896 -342.412227) (xy 175.866896 -342.466772)
			(xy 177.3496 -342.466772) (xy 177.3496 -342.412228) (xy 177.357362 -342.35824) (xy 177.372729 -342.305906)
			(xy 177.395388 -342.256292) (xy 177.424876 -342.210407) (xy 177.460595 -342.169187) (xy 177.501817 -342.133469)
			(xy 177.547703 -342.103982) (xy 177.597317 -342.081325) (xy 177.649652 -342.065959) (xy 177.70364 -342.058199)
			(xy 177.730912 -342.057736) (xy 178.594512 -342.057736) (xy 178.621781 -342.058227) (xy 178.675763 -342.06599)
			(xy 178.728091 -342.081357) (xy 178.777699 -342.104013) (xy 178.823578 -342.133499) (xy 178.864794 -342.169214)
			(xy 178.900508 -342.210432) (xy 178.929992 -342.256312) (xy 178.952648 -342.305921) (xy 178.968012 -342.358249)
			(xy 178.975774 -342.412231) (xy 178.975774 -342.466768) (xy 180.458622 -342.466768) (xy 180.458622 -342.412232)
			(xy 180.466383 -342.35825) (xy 180.481747 -342.305923) (xy 180.504402 -342.256314) (xy 180.533885 -342.210434)
			(xy 180.569597 -342.169217) (xy 180.610812 -342.133502) (xy 180.65669 -342.104015) (xy 180.706296 -342.081357)
			(xy 180.758623 -342.065989) (xy 180.812604 -342.058224) (xy 180.839872 -342.057736) (xy 181.703472 -342.057736)
			(xy 181.730744 -342.058202) (xy 181.784734 -342.06596) (xy 181.83707 -342.081324) (xy 181.886686 -342.10398)
			(xy 181.932573 -342.133467) (xy 181.973796 -342.169184) (xy 182.009516 -342.210405) (xy 182.039007 -342.256289)
			(xy 182.061666 -342.305904) (xy 182.077034 -342.358239) (xy 182.084796 -342.412228) (xy 182.084796 -342.466772)
			(xy 182.084796 -342.466773) (xy 183.5675 -342.466773) (xy 183.5675 -342.412227) (xy 183.575263 -342.358237)
			(xy 183.590631 -342.305902) (xy 183.613291 -342.256286) (xy 183.642781 -342.210401) (xy 183.678502 -342.16918)
			(xy 183.719727 -342.133462) (xy 183.765615 -342.103975) (xy 183.815232 -342.081319) (xy 183.867569 -342.065956)
			(xy 183.921559 -342.058197) (xy 183.948832 -342.057736) (xy 184.812432 -342.057736) (xy 184.8397 -342.058229)
			(xy 184.89368 -342.065994) (xy 184.946005 -342.081362) (xy 184.995611 -342.10402) (xy 185.041488 -342.133506)
			(xy 185.082701 -342.169222) (xy 185.118413 -342.210438) (xy 185.147895 -342.256317) (xy 185.170549 -342.305925)
			(xy 185.185913 -342.358252) (xy 185.193674 -342.412232) (xy 185.193674 -342.466768) (xy 185.193674 -342.466769)
			(xy 186.676522 -342.466769) (xy 186.676522 -342.412231) (xy 186.684284 -342.358248) (xy 186.699649 -342.305918)
			(xy 186.722305 -342.256309) (xy 186.75179 -342.210428) (xy 186.787505 -342.16921) (xy 186.828721 -342.133495)
			(xy 186.874602 -342.104009) (xy 186.924211 -342.081352) (xy 186.97654 -342.065986) (xy 187.030523 -342.058223)
			(xy 187.057792 -342.057736) (xy 187.921392 -342.057736) (xy 187.948663 -342.058203) (xy 188.002651 -342.065964)
			(xy 188.054984 -342.08133) (xy 188.104598 -342.103987) (xy 188.150482 -342.133474) (xy 188.191703 -342.169191)
			(xy 188.227421 -342.210411) (xy 188.25691 -342.256295) (xy 188.279568 -342.305908) (xy 188.294934 -342.358241)
			(xy 188.302696 -342.412229) (xy 188.302696 -342.466767) (xy 189.785522 -342.466767) (xy 189.785522 -342.412233)
			(xy 189.793283 -342.358253) (xy 189.808646 -342.305927) (xy 189.831299 -342.25632) (xy 189.86078 -342.210441)
			(xy 189.89649 -342.169224) (xy 189.937702 -342.133509) (xy 189.983578 -342.104022) (xy 190.033182 -342.081363)
			(xy 190.085506 -342.065993) (xy 190.139485 -342.058226) (xy 190.166752 -342.057736) (xy 191.030352 -342.057736)
			(xy 191.057625 -342.0582) (xy 191.111617 -342.065957) (xy 191.163955 -342.081319) (xy 191.213574 -342.103974)
			(xy 191.259463 -342.13346) (xy 191.300689 -342.169177) (xy 191.336412 -342.210398) (xy 191.365903 -342.256284)
			(xy 191.388564 -342.3059) (xy 191.403933 -342.358236) (xy 191.411696 -342.412227) (xy 191.411696 -342.466772)
			(xy 192.8944 -342.466772) (xy 192.8944 -342.412228) (xy 192.902162 -342.35824) (xy 192.917529 -342.305906)
			(xy 192.940188 -342.256292) (xy 192.969676 -342.210407) (xy 193.005395 -342.169187) (xy 193.046617 -342.133469)
			(xy 193.092503 -342.103982) (xy 193.142117 -342.081325) (xy 193.194452 -342.065959) (xy 193.24844 -342.058199)
			(xy 193.275712 -342.057736) (xy 194.139312 -342.057736) (xy 194.166581 -342.058227) (xy 194.220563 -342.06599)
			(xy 194.272891 -342.081357) (xy 194.322499 -342.104013) (xy 194.368378 -342.133499) (xy 194.409594 -342.169214)
			(xy 194.445308 -342.210432) (xy 194.474792 -342.256312) (xy 194.497448 -342.305921) (xy 194.512812 -342.358249)
			(xy 194.520574 -342.412231) (xy 194.520574 -342.466768) (xy 196.003422 -342.466768) (xy 196.003422 -342.412232)
			(xy 196.011183 -342.35825) (xy 196.026547 -342.305923) (xy 196.049202 -342.256314) (xy 196.078685 -342.210434)
			(xy 196.114397 -342.169217) (xy 196.155612 -342.133502) (xy 196.20149 -342.104015) (xy 196.251096 -342.081357)
			(xy 196.303423 -342.065989) (xy 196.357404 -342.058224) (xy 196.384672 -342.057736) (xy 197.248272 -342.057736)
			(xy 197.275544 -342.058202) (xy 197.329534 -342.06596) (xy 197.38187 -342.081324) (xy 197.431486 -342.10398)
			(xy 197.477373 -342.133467) (xy 197.518596 -342.169184) (xy 197.554316 -342.210405) (xy 197.583807 -342.256289)
			(xy 197.606466 -342.305904) (xy 197.621834 -342.358239) (xy 197.629596 -342.412228) (xy 197.629596 -342.466772)
			(xy 197.621834 -342.520761) (xy 197.606466 -342.573096) (xy 197.583807 -342.622711) (xy 197.554316 -342.668595)
			(xy 197.518596 -342.709816) (xy 197.477373 -342.745533) (xy 197.431486 -342.77502) (xy 197.38187 -342.797676)
			(xy 197.329534 -342.81304) (xy 197.275544 -342.820798) (xy 197.248272 -342.82126) (xy 196.384672 -342.82126)
			(xy 196.357404 -342.820776) (xy 196.303423 -342.813011) (xy 196.251096 -342.797643) (xy 196.20149 -342.774985)
			(xy 196.155612 -342.745498) (xy 196.114397 -342.709783) (xy 196.078685 -342.668566) (xy 196.049202 -342.622686)
			(xy 196.026547 -342.573077) (xy 196.011183 -342.52075) (xy 196.003422 -342.466768) (xy 194.520574 -342.466768)
			(xy 194.520574 -342.466769) (xy 194.512812 -342.520751) (xy 194.497448 -342.573079) (xy 194.474792 -342.622688)
			(xy 194.445308 -342.668568) (xy 194.409594 -342.709786) (xy 194.368378 -342.745501) (xy 194.322499 -342.774987)
			(xy 194.272891 -342.797643) (xy 194.220563 -342.81301) (xy 194.166581 -342.820773) (xy 194.139312 -342.82126)
			(xy 193.275712 -342.82126) (xy 193.24844 -342.820801) (xy 193.194452 -342.813041) (xy 193.142117 -342.797675)
			(xy 193.092503 -342.775018) (xy 193.046617 -342.745531) (xy 193.005395 -342.709813) (xy 192.969676 -342.668593)
			(xy 192.940188 -342.622708) (xy 192.917529 -342.573094) (xy 192.902162 -342.52076) (xy 192.8944 -342.466772)
			(xy 191.411696 -342.466772) (xy 191.411696 -342.466773) (xy 191.403933 -342.520764) (xy 191.388564 -342.5731)
			(xy 191.365903 -342.622716) (xy 191.336412 -342.668602) (xy 191.300689 -342.709823) (xy 191.259463 -342.74554)
			(xy 191.213574 -342.775026) (xy 191.163955 -342.797681) (xy 191.111617 -342.813043) (xy 191.057625 -342.8208)
			(xy 191.030352 -342.82126) (xy 190.166752 -342.82126) (xy 190.139485 -342.820774) (xy 190.085506 -342.813007)
			(xy 190.033182 -342.797637) (xy 189.983578 -342.774978) (xy 189.937702 -342.745491) (xy 189.89649 -342.709776)
			(xy 189.86078 -342.668559) (xy 189.831299 -342.62268) (xy 189.808646 -342.573073) (xy 189.793283 -342.520747)
			(xy 189.785522 -342.466767) (xy 188.302696 -342.466767) (xy 188.302696 -342.466771) (xy 188.294934 -342.520759)
			(xy 188.279568 -342.573092) (xy 188.25691 -342.622705) (xy 188.227421 -342.668589) (xy 188.191703 -342.709809)
			(xy 188.150482 -342.745526) (xy 188.104598 -342.775013) (xy 188.054984 -342.79767) (xy 188.002651 -342.813036)
			(xy 187.948663 -342.820797) (xy 187.921392 -342.82126) (xy 187.057792 -342.82126) (xy 187.030523 -342.820777)
			(xy 186.97654 -342.813014) (xy 186.924211 -342.797648) (xy 186.874602 -342.774991) (xy 186.828721 -342.745505)
			(xy 186.787505 -342.70979) (xy 186.75179 -342.668572) (xy 186.722305 -342.622691) (xy 186.699649 -342.573082)
			(xy 186.684284 -342.520752) (xy 186.676522 -342.466769) (xy 185.193674 -342.466769) (xy 185.185913 -342.520748)
			(xy 185.170549 -342.573075) (xy 185.147895 -342.622683) (xy 185.118413 -342.668562) (xy 185.082701 -342.709778)
			(xy 185.041488 -342.745494) (xy 184.995611 -342.77498) (xy 184.946005 -342.797638) (xy 184.89368 -342.813006)
			(xy 184.8397 -342.820771) (xy 184.812432 -342.82126) (xy 183.948832 -342.82126) (xy 183.921559 -342.820803)
			(xy 183.867569 -342.813044) (xy 183.815232 -342.797681) (xy 183.765615 -342.775025) (xy 183.719727 -342.745538)
			(xy 183.678502 -342.70982) (xy 183.642781 -342.668599) (xy 183.613291 -342.622714) (xy 183.590631 -342.573098)
			(xy 183.575263 -342.520763) (xy 183.5675 -342.466773) (xy 182.084796 -342.466773) (xy 182.077034 -342.520761)
			(xy 182.061666 -342.573096) (xy 182.039007 -342.622711) (xy 182.009516 -342.668595) (xy 181.973796 -342.709816)
			(xy 181.932573 -342.745533) (xy 181.886686 -342.77502) (xy 181.83707 -342.797676) (xy 181.784734 -342.81304)
			(xy 181.730744 -342.820798) (xy 181.703472 -342.82126) (xy 180.839872 -342.82126) (xy 180.812604 -342.820776)
			(xy 180.758623 -342.813011) (xy 180.706296 -342.797643) (xy 180.65669 -342.774985) (xy 180.610812 -342.745498)
			(xy 180.569597 -342.709783) (xy 180.533885 -342.668566) (xy 180.504402 -342.622686) (xy 180.481747 -342.573077)
			(xy 180.466383 -342.52075) (xy 180.458622 -342.466768) (xy 178.975774 -342.466768) (xy 178.975774 -342.466769)
			(xy 178.968012 -342.520751) (xy 178.952648 -342.573079) (xy 178.929992 -342.622688) (xy 178.900508 -342.668568)
			(xy 178.864794 -342.709786) (xy 178.823578 -342.745501) (xy 178.777699 -342.774987) (xy 178.728091 -342.797643)
			(xy 178.675763 -342.81301) (xy 178.621781 -342.820773) (xy 178.594512 -342.82126) (xy 177.730912 -342.82126)
			(xy 177.70364 -342.820801) (xy 177.649652 -342.813041) (xy 177.597317 -342.797675) (xy 177.547703 -342.775018)
			(xy 177.501817 -342.745531) (xy 177.460595 -342.709813) (xy 177.424876 -342.668593) (xy 177.395388 -342.622708)
			(xy 177.372729 -342.573094) (xy 177.357362 -342.52076) (xy 177.3496 -342.466772) (xy 175.866896 -342.466772)
			(xy 175.866896 -342.466773) (xy 175.859133 -342.520764) (xy 175.843764 -342.5731) (xy 175.821103 -342.622716)
			(xy 175.791612 -342.668602) (xy 175.755889 -342.709823) (xy 175.714663 -342.74554) (xy 175.668774 -342.775026)
			(xy 175.619155 -342.797681) (xy 175.566817 -342.813043) (xy 175.512825 -342.8208) (xy 175.485552 -342.82126)
			(xy 174.621952 -342.82126) (xy 174.594685 -342.820774) (xy 174.540706 -342.813007) (xy 174.488382 -342.797637)
			(xy 174.438778 -342.774978) (xy 174.392902 -342.745491) (xy 174.35169 -342.709776) (xy 174.31598 -342.668559)
			(xy 174.286499 -342.62268) (xy 174.263846 -342.573073) (xy 174.248483 -342.520747) (xy 174.240722 -342.466767)
			(xy 172.757896 -342.466767) (xy 172.757896 -342.466771) (xy 172.750134 -342.520759) (xy 172.734768 -342.573092)
			(xy 172.71211 -342.622705) (xy 172.682621 -342.668589) (xy 172.646903 -342.709809) (xy 172.605682 -342.745526)
			(xy 172.559798 -342.775013) (xy 172.510184 -342.79767) (xy 172.457851 -342.813036) (xy 172.403863 -342.820797)
			(xy 172.376592 -342.82126) (xy 171.512992 -342.82126) (xy 171.485723 -342.820777) (xy 171.43174 -342.813014)
			(xy 171.379411 -342.797648) (xy 171.329802 -342.774991) (xy 171.283921 -342.745505) (xy 171.242705 -342.70979)
			(xy 171.20699 -342.668572) (xy 171.177505 -342.622691) (xy 171.154849 -342.573082) (xy 171.139484 -342.520752)
			(xy 171.131722 -342.466769) (xy 169.648874 -342.466769) (xy 169.641113 -342.520748) (xy 169.625749 -342.573075)
			(xy 169.603095 -342.622683) (xy 169.573613 -342.668562) (xy 169.537901 -342.709778) (xy 169.496688 -342.745494)
			(xy 169.450811 -342.77498) (xy 169.401205 -342.797638) (xy 169.34888 -342.813006) (xy 169.2949 -342.820771)
			(xy 169.267632 -342.82126) (xy 168.404032 -342.82126) (xy 168.376759 -342.820803) (xy 168.322769 -342.813044)
			(xy 168.270432 -342.797681) (xy 168.220815 -342.775025) (xy 168.174927 -342.745538) (xy 168.133702 -342.70982)
			(xy 168.097981 -342.668599) (xy 168.068491 -342.622714) (xy 168.045831 -342.573098) (xy 168.030463 -342.520763)
			(xy 168.0227 -342.466773) (xy 166.539996 -342.466773) (xy 166.532234 -342.520761) (xy 166.516866 -342.573096)
			(xy 166.494207 -342.622711) (xy 166.464716 -342.668595) (xy 166.428996 -342.709816) (xy 166.387773 -342.745533)
			(xy 166.341886 -342.77502) (xy 166.29227 -342.797676) (xy 166.239934 -342.81304) (xy 166.185944 -342.820798)
			(xy 166.158672 -342.82126) (xy 165.295072 -342.82126) (xy 165.267804 -342.820776) (xy 165.213823 -342.813011)
			(xy 165.161496 -342.797643) (xy 165.11189 -342.774985) (xy 165.066012 -342.745498) (xy 165.024797 -342.709783)
			(xy 164.989085 -342.668566) (xy 164.959602 -342.622686) (xy 164.936947 -342.573077) (xy 164.921583 -342.52075)
			(xy 164.913822 -342.466768) (xy 161.718417 -342.466768) (xy 160.779595 -343.0651) (xy 265.321032 -343.0651)
			(xy 265.325103 -343.009478) (xy 265.337229 -342.955041) (xy 265.357152 -342.90295) (xy 265.384448 -342.854315)
			(xy 265.418534 -342.810172) (xy 265.458683 -342.771463) (xy 265.504041 -342.739012) (xy 265.553641 -342.713511)
			(xy 265.606425 -342.695504) (xy 265.661268 -342.685374) (xy 265.717002 -342.683337) (xy 265.772439 -342.689437)
			(xy 265.826396 -342.703543) (xy 265.877725 -342.725355) (xy 265.925331 -342.754409) (xy 265.968199 -342.790084)
			(xy 266.005416 -342.831621) (xy 266.036189 -342.878134) (xy 266.059861 -342.928631) (xy 266.075929 -342.982038)
			(xy 266.084049 -343.037214) (xy 266.084558 -343.0651) (xy 266.084354 -343.076276) (xy 266.189714 -343.076276)
			(xy 266.190326 -343.047047) (xy 266.19926 -342.989274) (xy 266.2169 -342.93354) (xy 266.242834 -342.881148)
			(xy 266.276455 -342.833324) (xy 266.316975 -342.791186) (xy 266.363448 -342.755721) (xy 266.38885 -342.74125)
			(xy 266.401636 -342.733738) (xy 266.422542 -342.712728) (xy 266.43653 -342.686596) (xy 266.442421 -342.657548)
			(xy 266.439718 -342.628031) (xy 266.428649 -342.600536) (xy 266.410146 -342.57738) (xy 266.398248 -342.56853)
			(xy 266.376969 -342.553153) (xy 266.338401 -342.517536) (xy 266.305078 -342.476968) (xy 266.277631 -342.432216)
			(xy 266.256577 -342.384124) (xy 266.242315 -342.3336) (xy 266.235112 -342.281597) (xy 266.234672 -342.255348)
			(xy 266.235158 -342.228097) (xy 266.242914 -342.174149) (xy 266.258269 -342.121854) (xy 266.280911 -342.072277)
			(xy 266.310377 -342.026427) (xy 266.346068 -341.985236) (xy 266.387259 -341.949545) (xy 266.433109 -341.920079)
			(xy 266.482686 -341.897437) (xy 266.534981 -341.882082) (xy 266.588929 -341.874326) (xy 266.643431 -341.874326)
			(xy 266.697379 -341.882082) (xy 266.749674 -341.897437) (xy 266.799251 -341.920079) (xy 266.845101 -341.949545)
			(xy 266.886292 -341.985236) (xy 266.921983 -342.026427) (xy 266.951449 -342.072277) (xy 266.974091 -342.121854)
			(xy 266.989446 -342.174149) (xy 266.997202 -342.228097) (xy 266.997688 -342.255348) (xy 266.997094 -342.284578)
			(xy 266.988156 -342.342351) (xy 266.970513 -342.398086) (xy 266.944576 -342.450478) (xy 266.933121 -342.466771)
			(xy 267.515799 -342.466771) (xy 267.515799 -342.412229) (xy 267.523562 -342.358241) (xy 267.538928 -342.305908)
			(xy 267.561586 -342.256295) (xy 267.591074 -342.210411) (xy 267.626792 -342.16919) (xy 267.668012 -342.133473)
			(xy 267.713897 -342.103985) (xy 267.76351 -342.081327) (xy 267.815843 -342.065961) (xy 267.869831 -342.058199)
			(xy 267.897102 -342.057736) (xy 268.760702 -342.057736) (xy 268.787971 -342.058227) (xy 268.841954 -342.065988)
			(xy 268.894283 -342.081354) (xy 268.943893 -342.10401) (xy 268.989773 -342.133496) (xy 269.030991 -342.169211)
			(xy 269.066705 -342.210428) (xy 269.096191 -342.256309) (xy 269.118847 -342.305919) (xy 269.134212 -342.358248)
			(xy 269.141974 -342.412231) (xy 269.141974 -342.466768) (xy 270.624822 -342.466768) (xy 270.624822 -342.412232)
			(xy 270.632583 -342.358252) (xy 270.647947 -342.305925) (xy 270.6706 -342.256317) (xy 270.700083 -342.210438)
			(xy 270.735794 -342.169221) (xy 270.777007 -342.133505) (xy 270.822884 -342.104018) (xy 270.872489 -342.08136)
			(xy 270.924814 -342.065991) (xy 270.978794 -342.058225) (xy 271.006062 -342.057736) (xy 271.869662 -342.057736)
			(xy 271.896935 -342.058201) (xy 271.950925 -342.065959) (xy 272.003262 -342.081321) (xy 272.05288 -342.103977)
			(xy 272.098768 -342.133463) (xy 272.139993 -342.16918) (xy 272.175714 -342.210401) (xy 272.205205 -342.256287)
			(xy 272.227865 -342.305902) (xy 272.243233 -342.358237) (xy 272.250996 -342.412227) (xy 272.250996 -342.466772)
			(xy 273.7337 -342.466772) (xy 273.7337 -342.412228) (xy 273.741462 -342.358239) (xy 273.75683 -342.305904)
			(xy 273.779489 -342.256289) (xy 273.808979 -342.210404) (xy 273.844699 -342.169183) (xy 273.885922 -342.133466)
			(xy 273.931809 -342.103979) (xy 273.981425 -342.081322) (xy 274.03376 -342.065958) (xy 274.08775 -342.058198)
			(xy 274.115022 -342.057736) (xy 274.978622 -342.057736) (xy 275.00589 -342.058228) (xy 275.059871 -342.065992)
			(xy 275.112198 -342.081359) (xy 275.161805 -342.104017) (xy 275.207683 -342.133503) (xy 275.248898 -342.169218)
			(xy 275.28461 -342.210435) (xy 275.314094 -342.256314) (xy 275.336748 -342.305923) (xy 275.352113 -342.35825)
			(xy 275.359874 -342.412232) (xy 275.359874 -342.466768) (xy 275.359874 -342.466769) (xy 276.842722 -342.466769)
			(xy 276.842722 -342.412231) (xy 276.850484 -342.358249) (xy 276.865848 -342.305921) (xy 276.888503 -342.256311)
			(xy 276.917987 -342.210431) (xy 276.953701 -342.169214) (xy 276.994917 -342.133498) (xy 277.040796 -342.104012)
			(xy 277.090404 -342.081354) (xy 277.142731 -342.065987) (xy 277.196713 -342.058224) (xy 277.223982 -342.057736)
			(xy 278.087582 -342.057736) (xy 278.114854 -342.058202) (xy 278.168842 -342.065962) (xy 278.221177 -342.081327)
			(xy 278.270792 -342.103983) (xy 278.316678 -342.13347) (xy 278.3579 -342.169188) (xy 278.393619 -342.210408)
			(xy 278.423108 -342.256292) (xy 278.445767 -342.305906) (xy 278.461134 -342.35824) (xy 278.468896 -342.412228)
			(xy 278.468896 -342.466772) (xy 278.468896 -342.466773) (xy 279.9516 -342.466773) (xy 279.9516 -342.412227)
			(xy 279.959363 -342.358236) (xy 279.974731 -342.3059) (xy 279.997392 -342.256284) (xy 280.026884 -342.210398)
			(xy 280.062606 -342.169176) (xy 280.103831 -342.133459) (xy 280.14972 -342.103972) (xy 280.199339 -342.081317)
			(xy 280.251677 -342.065954) (xy 280.305669 -342.058197) (xy 280.332942 -342.057736) (xy 281.196542 -342.057736)
			(xy 281.223809 -342.058229) (xy 281.277788 -342.065996) (xy 281.330112 -342.081365) (xy 281.379717 -342.104023)
			(xy 281.425592 -342.13351) (xy 281.466805 -342.169225) (xy 281.502515 -342.210441) (xy 281.531997 -342.25632)
			(xy 281.55465 -342.305927) (xy 281.570013 -342.358253) (xy 281.577774 -342.412233) (xy 281.577774 -342.466767)
			(xy 281.577773 -342.466771) (xy 283.060599 -342.466771) (xy 283.060599 -342.412229) (xy 283.068362 -342.358241)
			(xy 283.083728 -342.305908) (xy 283.106386 -342.256295) (xy 283.135874 -342.210411) (xy 283.171592 -342.16919)
			(xy 283.212812 -342.133473) (xy 283.258697 -342.103985) (xy 283.30831 -342.081327) (xy 283.360643 -342.065961)
			(xy 283.414631 -342.058199) (xy 283.441902 -342.057736) (xy 284.305502 -342.057736) (xy 284.332771 -342.058227)
			(xy 284.386754 -342.065988) (xy 284.439083 -342.081354) (xy 284.488693 -342.10401) (xy 284.534573 -342.133496)
			(xy 284.575791 -342.169211) (xy 284.611505 -342.210428) (xy 284.640991 -342.256309) (xy 284.663647 -342.305919)
			(xy 284.679012 -342.358248) (xy 284.686774 -342.412231) (xy 284.686774 -342.466768) (xy 286.169622 -342.466768)
			(xy 286.169622 -342.412232) (xy 286.177383 -342.358252) (xy 286.192747 -342.305925) (xy 286.2154 -342.256317)
			(xy 286.244883 -342.210438) (xy 286.280594 -342.169221) (xy 286.321807 -342.133505) (xy 286.367684 -342.104018)
			(xy 286.417289 -342.08136) (xy 286.469614 -342.065991) (xy 286.523594 -342.058225) (xy 286.550862 -342.057736)
			(xy 287.414462 -342.057736) (xy 287.441735 -342.058201) (xy 287.495725 -342.065959) (xy 287.548062 -342.081321)
			(xy 287.59768 -342.103977) (xy 287.643568 -342.133463) (xy 287.684793 -342.16918) (xy 287.720514 -342.210401)
			(xy 287.750005 -342.256287) (xy 287.772665 -342.305902) (xy 287.788033 -342.358237) (xy 287.795796 -342.412227)
			(xy 287.795796 -342.466772) (xy 289.2785 -342.466772) (xy 289.2785 -342.412228) (xy 289.286262 -342.358239)
			(xy 289.30163 -342.305904) (xy 289.324289 -342.256289) (xy 289.353779 -342.210404) (xy 289.389499 -342.169183)
			(xy 289.430722 -342.133466) (xy 289.476609 -342.103979) (xy 289.526225 -342.081322) (xy 289.57856 -342.065958)
			(xy 289.63255 -342.058198) (xy 289.659822 -342.057736) (xy 290.523422 -342.057736) (xy 290.55069 -342.058228)
			(xy 290.604671 -342.065992) (xy 290.656998 -342.081359) (xy 290.706605 -342.104017) (xy 290.752483 -342.133503)
			(xy 290.793698 -342.169218) (xy 290.82941 -342.210435) (xy 290.858894 -342.256314) (xy 290.881548 -342.305923)
			(xy 290.896913 -342.35825) (xy 290.904674 -342.412232) (xy 290.904674 -342.466768) (xy 290.904674 -342.466769)
			(xy 292.387522 -342.466769) (xy 292.387522 -342.412231) (xy 292.395284 -342.358249) (xy 292.410648 -342.305921)
			(xy 292.433303 -342.256311) (xy 292.462787 -342.210431) (xy 292.498501 -342.169214) (xy 292.539717 -342.133498)
			(xy 292.585596 -342.104012) (xy 292.635204 -342.081354) (xy 292.687531 -342.065987) (xy 292.741513 -342.058224)
			(xy 292.768782 -342.057736) (xy 293.632382 -342.057736) (xy 293.659654 -342.058202) (xy 293.713642 -342.065962)
			(xy 293.765977 -342.081327) (xy 293.815592 -342.103983) (xy 293.861478 -342.13347) (xy 293.9027 -342.169188)
			(xy 293.938419 -342.210408) (xy 293.967908 -342.256292) (xy 293.990567 -342.305906) (xy 294.005934 -342.35824)
			(xy 294.013696 -342.412228) (xy 294.013696 -342.466772) (xy 294.013696 -342.466773) (xy 295.4964 -342.466773)
			(xy 295.4964 -342.412227) (xy 295.504163 -342.358236) (xy 295.519531 -342.3059) (xy 295.542192 -342.256284)
			(xy 295.571684 -342.210398) (xy 295.607406 -342.169176) (xy 295.648631 -342.133459) (xy 295.69452 -342.103972)
			(xy 295.744139 -342.081317) (xy 295.796477 -342.065954) (xy 295.850469 -342.058197) (xy 295.877742 -342.057736)
			(xy 296.741342 -342.057736) (xy 296.768609 -342.058229) (xy 296.822588 -342.065996) (xy 296.874912 -342.081365)
			(xy 296.924517 -342.104023) (xy 296.970392 -342.13351) (xy 297.011605 -342.169225) (xy 297.047315 -342.210441)
			(xy 297.076797 -342.25632) (xy 297.09945 -342.305927) (xy 297.114813 -342.358253) (xy 297.122574 -342.412233)
			(xy 297.122574 -342.466767) (xy 297.122573 -342.466771) (xy 298.605399 -342.466771) (xy 298.605399 -342.412229)
			(xy 298.613162 -342.358241) (xy 298.628528 -342.305908) (xy 298.651186 -342.256295) (xy 298.680674 -342.210411)
			(xy 298.716392 -342.16919) (xy 298.757612 -342.133473) (xy 298.803497 -342.103985) (xy 298.85311 -342.081327)
			(xy 298.905443 -342.065961) (xy 298.959431 -342.058199) (xy 298.986702 -342.057736) (xy 299.850302 -342.057736)
			(xy 299.877571 -342.058227) (xy 299.931554 -342.065988) (xy 299.983883 -342.081354) (xy 300.033493 -342.10401)
			(xy 300.079373 -342.133496) (xy 300.120591 -342.169211) (xy 300.156305 -342.210428) (xy 300.185791 -342.256309)
			(xy 300.208447 -342.305919) (xy 300.223812 -342.358248) (xy 300.231574 -342.412231) (xy 300.231574 -342.466769)
			(xy 300.223812 -342.520752) (xy 300.208447 -342.573081) (xy 300.185791 -342.622691) (xy 300.156305 -342.668572)
			(xy 300.120591 -342.709789) (xy 300.079373 -342.745504) (xy 300.033493 -342.77499) (xy 299.983883 -342.797646)
			(xy 299.931554 -342.813012) (xy 299.877571 -342.820773) (xy 299.850302 -342.82126) (xy 298.986702 -342.82126)
			(xy 298.959431 -342.820801) (xy 298.905443 -342.813039) (xy 298.85311 -342.797673) (xy 298.803497 -342.775015)
			(xy 298.757612 -342.745527) (xy 298.716392 -342.70981) (xy 298.680674 -342.668589) (xy 298.651186 -342.622705)
			(xy 298.628528 -342.573092) (xy 298.613162 -342.520759) (xy 298.605399 -342.466771) (xy 297.122573 -342.466771)
			(xy 297.114813 -342.520747) (xy 297.09945 -342.573073) (xy 297.076797 -342.62268) (xy 297.047315 -342.668559)
			(xy 297.011605 -342.709775) (xy 296.970392 -342.74549) (xy 296.924517 -342.774977) (xy 296.874912 -342.797635)
			(xy 296.822588 -342.813004) (xy 296.768609 -342.820771) (xy 296.741342 -342.82126) (xy 295.877742 -342.82126)
			(xy 295.850469 -342.820803) (xy 295.796477 -342.813046) (xy 295.744139 -342.797683) (xy 295.694521 -342.775028)
			(xy 295.648631 -342.745541) (xy 295.607406 -342.709824) (xy 295.571684 -342.668602) (xy 295.542192 -342.622716)
			(xy 295.519531 -342.5731) (xy 295.504163 -342.520764) (xy 295.4964 -342.466773) (xy 294.013696 -342.466773)
			(xy 294.005934 -342.52076) (xy 293.990567 -342.573094) (xy 293.967908 -342.622708) (xy 293.938419 -342.668592)
			(xy 293.9027 -342.709812) (xy 293.861478 -342.74553) (xy 293.815592 -342.775017) (xy 293.765977 -342.797673)
			(xy 293.713642 -342.813038) (xy 293.659654 -342.820798) (xy 293.632382 -342.82126) (xy 292.768782 -342.82126)
			(xy 292.741513 -342.820776) (xy 292.687531 -342.813013) (xy 292.635204 -342.797646) (xy 292.585596 -342.774988)
			(xy 292.539717 -342.745502) (xy 292.498501 -342.709786) (xy 292.462787 -342.668569) (xy 292.433303 -342.622689)
			(xy 292.410648 -342.573079) (xy 292.395284 -342.520751) (xy 292.387522 -342.466769) (xy 290.904674 -342.466769)
			(xy 290.896913 -342.52075) (xy 290.881548 -342.573077) (xy 290.858894 -342.622686) (xy 290.82941 -342.668565)
			(xy 290.793698 -342.709782) (xy 290.752483 -342.745497) (xy 290.706605 -342.774983) (xy 290.656998 -342.797641)
			(xy 290.604671 -342.813008) (xy 290.55069 -342.820772) (xy 290.523422 -342.82126) (xy 289.659822 -342.82126)
			(xy 289.63255 -342.820802) (xy 289.57856 -342.813042) (xy 289.526225 -342.797678) (xy 289.476609 -342.775021)
			(xy 289.430722 -342.745534) (xy 289.389499 -342.709817) (xy 289.353779 -342.668596) (xy 289.324289 -342.622711)
			(xy 289.30163 -342.573096) (xy 289.286262 -342.520761) (xy 289.2785 -342.466772) (xy 287.795796 -342.466772)
			(xy 287.795796 -342.466773) (xy 287.788033 -342.520763) (xy 287.772665 -342.573098) (xy 287.750005 -342.622713)
			(xy 287.720514 -342.668599) (xy 287.684793 -342.70982) (xy 287.643568 -342.745537) (xy 287.59768 -342.775023)
			(xy 287.548062 -342.797679) (xy 287.495725 -342.813041) (xy 287.441735 -342.820799) (xy 287.414462 -342.82126)
			(xy 286.550862 -342.82126) (xy 286.523594 -342.820775) (xy 286.469614 -342.813009) (xy 286.417289 -342.79764)
			(xy 286.367684 -342.774982) (xy 286.321807 -342.745495) (xy 286.280594 -342.709779) (xy 286.244883 -342.668562)
			(xy 286.2154 -342.622683) (xy 286.192747 -342.573075) (xy 286.177383 -342.520748) (xy 286.169622 -342.466768)
			(xy 284.686774 -342.466768) (xy 284.686774 -342.466769) (xy 284.679012 -342.520752) (xy 284.663647 -342.573081)
			(xy 284.640991 -342.622691) (xy 284.611505 -342.668572) (xy 284.575791 -342.709789) (xy 284.534573 -342.745504)
			(xy 284.488693 -342.77499) (xy 284.439083 -342.797646) (xy 284.386754 -342.813012) (xy 284.332771 -342.820773)
			(xy 284.305502 -342.82126) (xy 283.441902 -342.82126) (xy 283.414631 -342.820801) (xy 283.360643 -342.813039)
			(xy 283.30831 -342.797673) (xy 283.258697 -342.775015) (xy 283.212812 -342.745527) (xy 283.171592 -342.70981)
			(xy 283.135874 -342.668589) (xy 283.106386 -342.622705) (xy 283.083728 -342.573092) (xy 283.068362 -342.520759)
			(xy 283.060599 -342.466771) (xy 281.577773 -342.466771) (xy 281.570013 -342.520747) (xy 281.55465 -342.573073)
			(xy 281.531997 -342.62268) (xy 281.502515 -342.668559) (xy 281.466805 -342.709775) (xy 281.425592 -342.74549)
			(xy 281.379717 -342.774977) (xy 281.330112 -342.797635) (xy 281.277788 -342.813004) (xy 281.223809 -342.820771)
			(xy 281.196542 -342.82126) (xy 280.332942 -342.82126) (xy 280.305669 -342.820803) (xy 280.251677 -342.813046)
			(xy 280.199339 -342.797683) (xy 280.149721 -342.775028) (xy 280.103831 -342.745541) (xy 280.062606 -342.709824)
			(xy 280.026884 -342.668602) (xy 279.997392 -342.622716) (xy 279.974731 -342.5731) (xy 279.959363 -342.520764)
			(xy 279.9516 -342.466773) (xy 278.468896 -342.466773) (xy 278.461134 -342.52076) (xy 278.445767 -342.573094)
			(xy 278.423108 -342.622708) (xy 278.393619 -342.668592) (xy 278.3579 -342.709812) (xy 278.316678 -342.74553)
			(xy 278.270792 -342.775017) (xy 278.221177 -342.797673) (xy 278.168842 -342.813038) (xy 278.114854 -342.820798)
			(xy 278.087582 -342.82126) (xy 277.223982 -342.82126) (xy 277.196713 -342.820776) (xy 277.142731 -342.813013)
			(xy 277.090404 -342.797646) (xy 277.040796 -342.774988) (xy 276.994917 -342.745502) (xy 276.953701 -342.709786)
			(xy 276.917987 -342.668569) (xy 276.888503 -342.622689) (xy 276.865848 -342.573079) (xy 276.850484 -342.520751)
			(xy 276.842722 -342.466769) (xy 275.359874 -342.466769) (xy 275.352113 -342.52075) (xy 275.336748 -342.573077)
			(xy 275.314094 -342.622686) (xy 275.28461 -342.668565) (xy 275.248898 -342.709782) (xy 275.207683 -342.745497)
			(xy 275.161805 -342.774983) (xy 275.112198 -342.797641) (xy 275.059871 -342.813008) (xy 275.00589 -342.820772)
			(xy 274.978622 -342.82126) (xy 274.115022 -342.82126) (xy 274.08775 -342.820802) (xy 274.03376 -342.813042)
			(xy 273.981425 -342.797678) (xy 273.931809 -342.775021) (xy 273.885922 -342.745534) (xy 273.844699 -342.709817)
			(xy 273.808979 -342.668596) (xy 273.779489 -342.622711) (xy 273.75683 -342.573096) (xy 273.741462 -342.520761)
			(xy 273.7337 -342.466772) (xy 272.250996 -342.466772) (xy 272.250996 -342.466773) (xy 272.243233 -342.520763)
			(xy 272.227865 -342.573098) (xy 272.205205 -342.622713) (xy 272.175714 -342.668599) (xy 272.139993 -342.70982)
			(xy 272.098768 -342.745537) (xy 272.05288 -342.775023) (xy 272.003262 -342.797679) (xy 271.950925 -342.813041)
			(xy 271.896935 -342.820799) (xy 271.869662 -342.82126) (xy 271.006062 -342.82126) (xy 270.978794 -342.820775)
			(xy 270.924814 -342.813009) (xy 270.872489 -342.79764) (xy 270.822884 -342.774982) (xy 270.777007 -342.745495)
			(xy 270.735794 -342.709779) (xy 270.700083 -342.668562) (xy 270.6706 -342.622683) (xy 270.647947 -342.573075)
			(xy 270.632583 -342.520748) (xy 270.624822 -342.466768) (xy 269.141974 -342.466768) (xy 269.141974 -342.466769)
			(xy 269.134212 -342.520752) (xy 269.118847 -342.573081) (xy 269.096191 -342.622691) (xy 269.066705 -342.668572)
			(xy 269.030991 -342.709789) (xy 268.989773 -342.745504) (xy 268.943893 -342.77499) (xy 268.894283 -342.797646)
			(xy 268.841954 -342.813012) (xy 268.787971 -342.820773) (xy 268.760702 -342.82126) (xy 267.897102 -342.82126)
			(xy 267.869831 -342.820801) (xy 267.815843 -342.813039) (xy 267.76351 -342.797673) (xy 267.713897 -342.775015)
			(xy 267.668012 -342.745527) (xy 267.626792 -342.70981) (xy 267.591074 -342.668589) (xy 267.561586 -342.622705)
			(xy 267.538928 -342.573092) (xy 267.523562 -342.520759) (xy 267.515799 -342.466771) (xy 266.933121 -342.466771)
			(xy 266.910953 -342.498302) (xy 266.87043 -342.540439) (xy 266.823955 -342.575903) (xy 266.798552 -342.590374)
			(xy 266.785745 -342.597852) (xy 266.764836 -342.61887) (xy 266.750848 -342.645008) (xy 266.744959 -342.674064)
			(xy 266.747667 -342.703586) (xy 266.758742 -342.731086) (xy 266.777252 -342.754244) (xy 266.789154 -342.763094)
			(xy 266.810445 -342.778455) (xy 266.849013 -342.814075) (xy 266.882334 -342.854646) (xy 266.90978 -342.899401)
			(xy 266.930831 -342.947495) (xy 266.945092 -342.998022) (xy 266.952292 -343.050026) (xy 266.95273 -343.076276)
			(xy 266.952244 -343.103527) (xy 266.944488 -343.157475) (xy 266.929133 -343.20977) (xy 266.906491 -343.259347)
			(xy 266.877025 -343.305197) (xy 266.841334 -343.346388) (xy 266.800143 -343.382079) (xy 266.754293 -343.411545)
			(xy 266.704716 -343.434187) (xy 266.652421 -343.449542) (xy 266.598473 -343.457298) (xy 266.543971 -343.457298)
			(xy 266.490023 -343.449542) (xy 266.437728 -343.434187) (xy 266.388151 -343.411545) (xy 266.342301 -343.382079)
			(xy 266.30111 -343.346388) (xy 266.265419 -343.305197) (xy 266.235953 -343.259347) (xy 266.213311 -343.20977)
			(xy 266.197956 -343.157475) (xy 266.1902 -343.103527) (xy 266.189714 -343.076276) (xy 266.084354 -343.076276)
			(xy 266.084049 -343.092986) (xy 266.075929 -343.148162) (xy 266.059861 -343.201569) (xy 266.036189 -343.252066)
			(xy 266.005416 -343.298579) (xy 265.968199 -343.340116) (xy 265.925331 -343.375791) (xy 265.877725 -343.404845)
			(xy 265.826396 -343.426657) (xy 265.772439 -343.440763) (xy 265.717002 -343.446863) (xy 265.661268 -343.444826)
			(xy 265.606425 -343.434696) (xy 265.553641 -343.416689) (xy 265.504041 -343.391188) (xy 265.458683 -343.358737)
			(xy 265.418534 -343.320028) (xy 265.384448 -343.275885) (xy 265.357152 -343.22725) (xy 265.337229 -343.175159)
			(xy 265.325103 -343.120722) (xy 265.321032 -343.0651) (xy 160.779595 -343.0651) (xy 156.971057 -345.492365)
			(xy 164.91387 -345.492365) (xy 164.91387 -345.437835) (xy 164.92163 -345.383861) (xy 164.936992 -345.33154)
			(xy 164.959644 -345.281937) (xy 164.989123 -345.236063) (xy 165.024831 -345.194851) (xy 165.066041 -345.15914)
			(xy 165.111913 -345.129657) (xy 165.161513 -345.107002) (xy 165.213833 -345.091636) (xy 165.267807 -345.083872)
			(xy 165.295072 -345.083384) (xy 166.158672 -345.083384) (xy 166.185948 -345.083754) (xy 166.239944 -345.091514)
			(xy 166.292286 -345.106879) (xy 166.341909 -345.129538) (xy 166.387802 -345.159028) (xy 166.42903 -345.19475)
			(xy 166.464755 -345.235976) (xy 166.494249 -345.281866) (xy 166.516911 -345.331487) (xy 166.532281 -345.383829)
			(xy 166.540044 -345.437824) (xy 166.540044 -345.492369) (xy 168.022747 -345.492369) (xy 168.022747 -345.437831)
			(xy 168.03051 -345.383848) (xy 168.045876 -345.331519) (xy 168.068533 -345.281909) (xy 168.09802 -345.23603)
			(xy 168.133736 -345.194814) (xy 168.174955 -345.159101) (xy 168.220838 -345.129617) (xy 168.270449 -345.106964)
			(xy 168.322779 -345.091603) (xy 168.376763 -345.083845) (xy 168.404032 -345.083384) (xy 169.267632 -345.083384)
			(xy 169.294903 -345.083781) (xy 169.34889 -345.091547) (xy 169.401222 -345.106917) (xy 169.450834 -345.129578)
			(xy 169.496716 -345.159068) (xy 169.537935 -345.194788) (xy 169.573651 -345.236009) (xy 169.603138 -345.281894)
			(xy 169.625794 -345.331508) (xy 169.64116 -345.383842) (xy 169.648922 -345.437829) (xy 169.648922 -345.492366)
			(xy 171.13177 -345.492366) (xy 171.13177 -345.437834) (xy 171.139531 -345.383858) (xy 171.154894 -345.331535)
			(xy 171.177547 -345.281932) (xy 171.207028 -345.236057) (xy 171.242738 -345.194844) (xy 171.28395 -345.159133)
			(xy 171.329825 -345.129651) (xy 171.379428 -345.106997) (xy 171.43175 -345.091633) (xy 171.485726 -345.083871)
			(xy 171.512992 -345.083384) (xy 172.376592 -345.083384) (xy 172.403867 -345.083755) (xy 172.457861 -345.091517)
			(xy 172.510201 -345.106885) (xy 172.559821 -345.129544) (xy 172.605711 -345.159035) (xy 172.646937 -345.194757)
			(xy 172.68266 -345.235982) (xy 172.712152 -345.281872) (xy 172.734813 -345.331492) (xy 172.750181 -345.383831)
			(xy 172.757944 -345.437825) (xy 172.757944 -345.492364) (xy 174.24077 -345.492364) (xy 174.24077 -345.437836)
			(xy 174.24853 -345.383863) (xy 174.263891 -345.331544) (xy 174.286541 -345.281943) (xy 174.316019 -345.23607)
			(xy 174.351724 -345.194858) (xy 174.392931 -345.159147) (xy 174.438801 -345.129664) (xy 174.488399 -345.107008)
			(xy 174.540716 -345.09164) (xy 174.594688 -345.083874) (xy 174.621952 -345.083384) (xy 175.485552 -345.083384)
			(xy 175.512829 -345.083752) (xy 175.566827 -345.09151) (xy 175.619172 -345.106874) (xy 175.668797 -345.129531)
			(xy 175.714692 -345.159021) (xy 175.755923 -345.194743) (xy 175.79165 -345.235969) (xy 175.821146 -345.281861)
			(xy 175.843809 -345.331483) (xy 175.85918 -345.383826) (xy 175.866944 -345.437824) (xy 175.866944 -345.492368)
			(xy 177.349647 -345.492368) (xy 177.349647 -345.437832) (xy 177.357409 -345.38385) (xy 177.372774 -345.331523)
			(xy 177.39543 -345.281915) (xy 177.424915 -345.236036) (xy 177.460629 -345.194821) (xy 177.501846 -345.159108)
			(xy 177.547726 -345.129624) (xy 177.597334 -345.10697) (xy 177.649662 -345.091606) (xy 177.703644 -345.083847)
			(xy 177.730912 -345.083384) (xy 178.594512 -345.083384) (xy 178.621784 -345.083779) (xy 178.675773 -345.091543)
			(xy 178.728107 -345.106912) (xy 178.777722 -345.129571) (xy 178.823607 -345.159061) (xy 178.864828 -345.194781)
			(xy 178.900546 -345.236003) (xy 178.930035 -345.281889) (xy 178.952693 -345.331504) (xy 178.968059 -345.383839)
			(xy 178.975821 -345.437828) (xy 178.975821 -345.492365) (xy 180.45867 -345.492365) (xy 180.45867 -345.437835)
			(xy 180.46643 -345.383861) (xy 180.481792 -345.33154) (xy 180.504444 -345.281937) (xy 180.533923 -345.236063)
			(xy 180.569631 -345.194851) (xy 180.610841 -345.15914) (xy 180.656713 -345.129657) (xy 180.706313 -345.107002)
			(xy 180.758633 -345.091636) (xy 180.812607 -345.083872) (xy 180.839872 -345.083384) (xy 181.703472 -345.083384)
			(xy 181.730748 -345.083754) (xy 181.784744 -345.091514) (xy 181.837086 -345.106879) (xy 181.886709 -345.129538)
			(xy 181.932602 -345.159028) (xy 181.97383 -345.19475) (xy 182.009555 -345.235976) (xy 182.039049 -345.281866)
			(xy 182.061711 -345.331487) (xy 182.077081 -345.383829) (xy 182.084844 -345.437824) (xy 182.084844 -345.492369)
			(xy 183.567547 -345.492369) (xy 183.567547 -345.437831) (xy 183.57531 -345.383848) (xy 183.590676 -345.331519)
			(xy 183.613333 -345.281909) (xy 183.64282 -345.23603) (xy 183.678536 -345.194814) (xy 183.719755 -345.159101)
			(xy 183.765638 -345.129617) (xy 183.815249 -345.106964) (xy 183.867579 -345.091603) (xy 183.921563 -345.083845)
			(xy 183.948832 -345.083384) (xy 184.812432 -345.083384) (xy 184.839703 -345.083781) (xy 184.89369 -345.091547)
			(xy 184.946022 -345.106917) (xy 184.995634 -345.129578) (xy 185.041516 -345.159068) (xy 185.082735 -345.194788)
			(xy 185.118451 -345.236009) (xy 185.147938 -345.281894) (xy 185.170594 -345.331508) (xy 185.18596 -345.383842)
			(xy 185.193722 -345.437829) (xy 185.193722 -345.492366) (xy 186.67657 -345.492366) (xy 186.67657 -345.437834)
			(xy 186.684331 -345.383858) (xy 186.699694 -345.331535) (xy 186.722347 -345.281932) (xy 186.751828 -345.236057)
			(xy 186.787538 -345.194844) (xy 186.82875 -345.159133) (xy 186.874625 -345.129651) (xy 186.924228 -345.106997)
			(xy 186.97655 -345.091633) (xy 187.030526 -345.083871) (xy 187.057792 -345.083384) (xy 187.921392 -345.083384)
			(xy 187.948667 -345.083755) (xy 188.002661 -345.091517) (xy 188.055001 -345.106885) (xy 188.104621 -345.129544)
			(xy 188.150511 -345.159035) (xy 188.191737 -345.194757) (xy 188.22746 -345.235982) (xy 188.256952 -345.281872)
			(xy 188.279613 -345.331492) (xy 188.294981 -345.383831) (xy 188.302744 -345.437825) (xy 188.302744 -345.492364)
			(xy 189.78557 -345.492364) (xy 189.78557 -345.437836) (xy 189.79333 -345.383863) (xy 189.808691 -345.331544)
			(xy 189.831341 -345.281943) (xy 189.860819 -345.23607) (xy 189.896524 -345.194858) (xy 189.937731 -345.159147)
			(xy 189.983601 -345.129664) (xy 190.033199 -345.107008) (xy 190.085516 -345.09164) (xy 190.139488 -345.083874)
			(xy 190.166752 -345.083384) (xy 191.030352 -345.083384) (xy 191.057629 -345.083752) (xy 191.111627 -345.09151)
			(xy 191.163972 -345.106874) (xy 191.213597 -345.129531) (xy 191.259492 -345.159021) (xy 191.300723 -345.194743)
			(xy 191.33645 -345.235969) (xy 191.365946 -345.281861) (xy 191.388609 -345.331483) (xy 191.40398 -345.383826)
			(xy 191.411744 -345.437824) (xy 191.411744 -345.492368) (xy 192.894447 -345.492368) (xy 192.894447 -345.437832)
			(xy 192.902209 -345.38385) (xy 192.917574 -345.331523) (xy 192.94023 -345.281915) (xy 192.969715 -345.236036)
			(xy 193.005429 -345.194821) (xy 193.046646 -345.159108) (xy 193.092526 -345.129624) (xy 193.142134 -345.10697)
			(xy 193.194462 -345.091606) (xy 193.248444 -345.083847) (xy 193.275712 -345.083384) (xy 194.139312 -345.083384)
			(xy 194.166584 -345.083779) (xy 194.220573 -345.091543) (xy 194.272907 -345.106912) (xy 194.322522 -345.129571)
			(xy 194.368407 -345.159061) (xy 194.409628 -345.194781) (xy 194.445346 -345.236003) (xy 194.474835 -345.281889)
			(xy 194.497493 -345.331504) (xy 194.512859 -345.383839) (xy 194.520621 -345.437828) (xy 194.520621 -345.492365)
			(xy 196.00347 -345.492365) (xy 196.00347 -345.437835) (xy 196.01123 -345.383861) (xy 196.026592 -345.33154)
			(xy 196.049244 -345.281937) (xy 196.078723 -345.236063) (xy 196.114431 -345.194851) (xy 196.155641 -345.15914)
			(xy 196.201513 -345.129657) (xy 196.251113 -345.107002) (xy 196.303433 -345.091636) (xy 196.357407 -345.083872)
			(xy 196.384672 -345.083384) (xy 197.248272 -345.083384) (xy 197.275548 -345.083754) (xy 197.329544 -345.091514)
			(xy 197.381886 -345.106879) (xy 197.431509 -345.129538) (xy 197.477402 -345.159028) (xy 197.51863 -345.19475)
			(xy 197.554355 -345.235976) (xy 197.583849 -345.281866) (xy 197.606511 -345.331487) (xy 197.621881 -345.383829)
			(xy 197.628314 -345.42857) (xy 229.27894 -345.42857) (xy 229.283011 -345.372948) (xy 229.295137 -345.318511)
			(xy 229.31506 -345.26642) (xy 229.342356 -345.217785) (xy 229.376442 -345.173642) (xy 229.416591 -345.134933)
			(xy 229.461949 -345.102482) (xy 229.511549 -345.076981) (xy 229.564333 -345.058974) (xy 229.619176 -345.048844)
			(xy 229.67491 -345.046807) (xy 229.730347 -345.052907) (xy 229.784304 -345.067013) (xy 229.835633 -345.088825)
			(xy 229.883239 -345.117879) (xy 229.926107 -345.153554) (xy 229.963324 -345.195091) (xy 229.994097 -345.241604)
			(xy 230.017769 -345.292101) (xy 230.033837 -345.345508) (xy 230.041957 -345.400684) (xy 230.042466 -345.42857)
			(xy 230.041957 -345.456456) (xy 230.033837 -345.511632) (xy 230.017769 -345.565039) (xy 229.994097 -345.615536)
			(xy 229.963324 -345.662049) (xy 229.926107 -345.703586) (xy 229.883239 -345.739261) (xy 229.835633 -345.768315)
			(xy 229.784304 -345.790127) (xy 229.730347 -345.804233) (xy 229.67491 -345.810333) (xy 229.619176 -345.808296)
			(xy 229.564333 -345.798166) (xy 229.511549 -345.780159) (xy 229.461949 -345.754658) (xy 229.416591 -345.722207)
			(xy 229.376442 -345.683498) (xy 229.342356 -345.639355) (xy 229.31506 -345.59072) (xy 229.295137 -345.538629)
			(xy 229.283011 -345.484192) (xy 229.27894 -345.42857) (xy 197.628314 -345.42857) (xy 197.629644 -345.437824)
			(xy 197.629644 -345.492376) (xy 197.621881 -345.546371) (xy 197.606511 -345.598713) (xy 197.583849 -345.648334)
			(xy 197.554355 -345.694224) (xy 197.51863 -345.73545) (xy 197.477402 -345.771172) (xy 197.431509 -345.800662)
			(xy 197.381886 -345.823321) (xy 197.349125 -345.832938) (xy 235.125004 -345.832938) (xy 235.129075 -345.777316)
			(xy 235.141201 -345.722879) (xy 235.161124 -345.670788) (xy 235.18842 -345.622153) (xy 235.222506 -345.57801)
			(xy 235.262655 -345.539301) (xy 235.308013 -345.50685) (xy 235.357613 -345.481349) (xy 235.410397 -345.463342)
			(xy 235.46524 -345.453212) (xy 235.520974 -345.451175) (xy 235.576411 -345.457275) (xy 235.630368 -345.471381)
			(xy 235.681697 -345.493193) (xy 235.729303 -345.522247) (xy 235.772171 -345.557922) (xy 235.809388 -345.599459)
			(xy 235.840161 -345.645972) (xy 235.863833 -345.696469) (xy 235.879901 -345.749876) (xy 235.888021 -345.805052)
			(xy 235.88853 -345.832938) (xy 235.888021 -345.860824) (xy 235.879901 -345.916) (xy 235.87226 -345.941396)
			(xy 250.769118 -345.941396) (xy 250.773189 -345.885774) (xy 250.785315 -345.831337) (xy 250.805238 -345.779246)
			(xy 250.832534 -345.730611) (xy 250.86662 -345.686468) (xy 250.906769 -345.647759) (xy 250.952127 -345.615308)
			(xy 251.001727 -345.589807) (xy 251.054511 -345.5718) (xy 251.109354 -345.56167) (xy 251.165088 -345.559633)
			(xy 251.220525 -345.565733) (xy 251.274482 -345.579839) (xy 251.325811 -345.601651) (xy 251.373417 -345.630705)
			(xy 251.40125 -345.653868) (xy 257.171696 -345.653868) (xy 257.175767 -345.598246) (xy 257.187893 -345.543809)
			(xy 257.207816 -345.491718) (xy 257.235112 -345.443083) (xy 257.269198 -345.39894) (xy 257.309347 -345.360231)
			(xy 257.354705 -345.32778) (xy 257.404305 -345.302279) (xy 257.457089 -345.284272) (xy 257.511932 -345.274142)
			(xy 257.567666 -345.272105) (xy 257.623103 -345.278205) (xy 257.67706 -345.292311) (xy 257.728389 -345.314123)
			(xy 257.775995 -345.343177) (xy 257.818863 -345.378852) (xy 257.85608 -345.420389) (xy 257.886853 -345.466902)
			(xy 257.898791 -345.492368) (xy 267.515847 -345.492368) (xy 267.515847 -345.437832) (xy 267.523609 -345.383852)
			(xy 267.538973 -345.331525) (xy 267.561628 -345.281918) (xy 267.591112 -345.23604) (xy 267.626826 -345.194824)
			(xy 267.668041 -345.159111) (xy 267.71392 -345.129627) (xy 267.763527 -345.106972) (xy 267.815854 -345.091608)
			(xy 267.869834 -345.083847) (xy 267.897102 -345.083384) (xy 268.760702 -345.083384) (xy 268.787975 -345.083779)
			(xy 268.841964 -345.091542) (xy 268.8943 -345.106909) (xy 268.943916 -345.129568) (xy 268.989802 -345.159057)
			(xy 269.031024 -345.194777) (xy 269.066744 -345.236) (xy 269.096233 -345.281886) (xy 269.118892 -345.331502)
			(xy 269.134259 -345.383838) (xy 269.142021 -345.437827) (xy 269.142021 -345.492364) (xy 270.62487 -345.492364)
			(xy 270.62487 -345.437836) (xy 270.63263 -345.383862) (xy 270.647992 -345.331542) (xy 270.670642 -345.28194)
			(xy 270.700121 -345.236066) (xy 270.735828 -345.194855) (xy 270.777036 -345.159144) (xy 270.822907 -345.12966)
			(xy 270.872506 -345.107005) (xy 270.924825 -345.091638) (xy 270.978798 -345.083873) (xy 271.006062 -345.083384)
			(xy 271.869662 -345.083384) (xy 271.896938 -345.083753) (xy 271.950936 -345.091512) (xy 272.003279 -345.106877)
			(xy 272.052903 -345.129535) (xy 272.098797 -345.159025) (xy 272.140027 -345.194747) (xy 272.175752 -345.235973)
			(xy 272.205247 -345.281864) (xy 272.22791 -345.331485) (xy 272.24328 -345.383827) (xy 272.251044 -345.437824)
			(xy 272.251044 -345.492369) (xy 273.733747 -345.492369) (xy 273.733747 -345.437831) (xy 273.741509 -345.383849)
			(xy 273.756875 -345.331521) (xy 273.779531 -345.281912) (xy 273.809017 -345.236033) (xy 273.844733 -345.194817)
			(xy 273.885951 -345.159104) (xy 273.931832 -345.129621) (xy 273.981441 -345.106967) (xy 274.033771 -345.091605)
			(xy 274.087753 -345.083846) (xy 274.115022 -345.083384) (xy 274.978622 -345.083384) (xy 275.005894 -345.08378)
			(xy 275.059881 -345.091545) (xy 275.112215 -345.106914) (xy 275.161828 -345.129574) (xy 275.207712 -345.159064)
			(xy 275.248932 -345.194784) (xy 275.284649 -345.236006) (xy 275.314136 -345.281891) (xy 275.336793 -345.331506)
			(xy 275.352159 -345.38384) (xy 275.359922 -345.437828) (xy 275.359922 -345.492365) (xy 276.84277 -345.492365)
			(xy 276.84277 -345.437835) (xy 276.850531 -345.383859) (xy 276.865893 -345.331537) (xy 276.888545 -345.281934)
			(xy 276.918026 -345.23606) (xy 276.953735 -345.194848) (xy 276.994945 -345.159137) (xy 277.040819 -345.129654)
			(xy 277.090421 -345.106999) (xy 277.142742 -345.091634) (xy 277.196717 -345.083872) (xy 277.223982 -345.083384)
			(xy 278.087582 -345.083384) (xy 278.114857 -345.083754) (xy 278.168852 -345.091515) (xy 278.221194 -345.106882)
			(xy 278.270815 -345.129541) (xy 278.316706 -345.159032) (xy 278.357934 -345.194754) (xy 278.393657 -345.235979)
			(xy 278.42315 -345.281869) (xy 278.445812 -345.33149) (xy 278.461181 -345.38383) (xy 278.468944 -345.437825)
			(xy 278.468944 -345.49237) (xy 279.951648 -345.49237) (xy 279.951648 -345.43783) (xy 279.95941 -345.383846)
			(xy 279.974776 -345.331517) (xy 279.997434 -345.281907) (xy 280.026922 -345.236026) (xy 280.06264 -345.19481)
			(xy 280.10386 -345.159097) (xy 280.149744 -345.129614) (xy 280.199356 -345.106962) (xy 280.251687 -345.091601)
			(xy 280.305672 -345.083845) (xy 280.332942 -345.083384) (xy 281.196542 -345.083384) (xy 281.223813 -345.083781)
			(xy 281.277798 -345.091549) (xy 281.330129 -345.10692) (xy 281.37974 -345.129581) (xy 281.425621 -345.159072)
			(xy 281.466839 -345.194791) (xy 281.502554 -345.236013) (xy 281.532039 -345.281897) (xy 281.554695 -345.33151)
			(xy 281.57006 -345.383843) (xy 281.577822 -345.437829) (xy 281.577822 -345.492368) (xy 283.060647 -345.492368)
			(xy 283.060647 -345.437832) (xy 283.068409 -345.383852) (xy 283.083773 -345.331525) (xy 283.106428 -345.281918)
			(xy 283.135912 -345.23604) (xy 283.171626 -345.194824) (xy 283.212841 -345.159111) (xy 283.25872 -345.129627)
			(xy 283.308327 -345.106972) (xy 283.360654 -345.091608) (xy 283.414634 -345.083847) (xy 283.441902 -345.083384)
			(xy 284.305502 -345.083384) (xy 284.332775 -345.083779) (xy 284.386764 -345.091542) (xy 284.4391 -345.106909)
			(xy 284.488716 -345.129568) (xy 284.534602 -345.159057) (xy 284.575824 -345.194777) (xy 284.611544 -345.236)
			(xy 284.641033 -345.281886) (xy 284.663692 -345.331502) (xy 284.679059 -345.383838) (xy 284.686821 -345.437827)
			(xy 284.686821 -345.492364) (xy 286.16967 -345.492364) (xy 286.16967 -345.437836) (xy 286.17743 -345.383862)
			(xy 286.192792 -345.331542) (xy 286.215442 -345.28194) (xy 286.244921 -345.236066) (xy 286.280628 -345.194855)
			(xy 286.321836 -345.159144) (xy 286.367707 -345.12966) (xy 286.417306 -345.107005) (xy 286.469625 -345.091638)
			(xy 286.523598 -345.083873) (xy 286.550862 -345.083384) (xy 287.414462 -345.083384) (xy 287.441738 -345.083753)
			(xy 287.495736 -345.091512) (xy 287.548079 -345.106877) (xy 287.597703 -345.129535) (xy 287.643597 -345.159025)
			(xy 287.684827 -345.194747) (xy 287.720552 -345.235973) (xy 287.750047 -345.281864) (xy 287.77271 -345.331485)
			(xy 287.78808 -345.383827) (xy 287.795844 -345.437824) (xy 287.795844 -345.492369) (xy 289.278547 -345.492369)
			(xy 289.278547 -345.437831) (xy 289.286309 -345.383849) (xy 289.301675 -345.331521) (xy 289.324331 -345.281912)
			(xy 289.353817 -345.236033) (xy 289.389533 -345.194817) (xy 289.430751 -345.159104) (xy 289.476632 -345.129621)
			(xy 289.526241 -345.106967) (xy 289.578571 -345.091605) (xy 289.632553 -345.083846) (xy 289.659822 -345.083384)
			(xy 290.523422 -345.083384) (xy 290.550694 -345.08378) (xy 290.604681 -345.091545) (xy 290.657015 -345.106914)
			(xy 290.706628 -345.129574) (xy 290.752512 -345.159064) (xy 290.793732 -345.194784) (xy 290.829449 -345.236006)
			(xy 290.858936 -345.281891) (xy 290.881593 -345.331506) (xy 290.896959 -345.38384) (xy 290.904722 -345.437828)
			(xy 290.904722 -345.492365) (xy 292.38757 -345.492365) (xy 292.38757 -345.437835) (xy 292.395331 -345.383859)
			(xy 292.410693 -345.331537) (xy 292.433345 -345.281934) (xy 292.462826 -345.23606) (xy 292.498535 -345.194848)
			(xy 292.539745 -345.159137) (xy 292.585619 -345.129654) (xy 292.635221 -345.106999) (xy 292.687542 -345.091634)
			(xy 292.741517 -345.083872) (xy 292.768782 -345.083384) (xy 293.632382 -345.083384) (xy 293.659657 -345.083754)
			(xy 293.713652 -345.091515) (xy 293.765994 -345.106882) (xy 293.815615 -345.129541) (xy 293.861506 -345.159032)
			(xy 293.902734 -345.194754) (xy 293.938457 -345.235979) (xy 293.96795 -345.281869) (xy 293.990612 -345.33149)
			(xy 294.005981 -345.38383) (xy 294.013744 -345.437825) (xy 294.013744 -345.49237) (xy 295.496448 -345.49237)
			(xy 295.496448 -345.43783) (xy 295.50421 -345.383846) (xy 295.519576 -345.331517) (xy 295.542234 -345.281907)
			(xy 295.571722 -345.236026) (xy 295.60744 -345.19481) (xy 295.64866 -345.159097) (xy 295.694544 -345.129614)
			(xy 295.744156 -345.106962) (xy 295.796487 -345.091601) (xy 295.850472 -345.083845) (xy 295.877742 -345.083384)
			(xy 296.741342 -345.083384) (xy 296.768613 -345.083781) (xy 296.822598 -345.091549) (xy 296.874929 -345.10692)
			(xy 296.92454 -345.129581) (xy 296.970421 -345.159072) (xy 297.011639 -345.194791) (xy 297.047354 -345.236013)
			(xy 297.076839 -345.281897) (xy 297.099495 -345.33151) (xy 297.11486 -345.383843) (xy 297.122622 -345.437829)
			(xy 297.122622 -345.492368) (xy 298.605447 -345.492368) (xy 298.605447 -345.437832) (xy 298.613209 -345.383852)
			(xy 298.628573 -345.331525) (xy 298.651228 -345.281918) (xy 298.680712 -345.23604) (xy 298.716426 -345.194824)
			(xy 298.757641 -345.159111) (xy 298.80352 -345.129627) (xy 298.853127 -345.106972) (xy 298.905454 -345.091608)
			(xy 298.959434 -345.083847) (xy 298.986702 -345.083384) (xy 299.850302 -345.083384) (xy 299.877575 -345.083779)
			(xy 299.931564 -345.091542) (xy 299.9839 -345.106909) (xy 300.033516 -345.129568) (xy 300.079402 -345.159057)
			(xy 300.120624 -345.194777) (xy 300.156344 -345.236) (xy 300.185833 -345.281886) (xy 300.208492 -345.331502)
			(xy 300.223859 -345.383838) (xy 300.231621 -345.437827) (xy 300.231621 -345.492373) (xy 300.223859 -345.546362)
			(xy 300.208492 -345.598698) (xy 300.185833 -345.648314) (xy 300.156344 -345.6942) (xy 300.120624 -345.735423)
			(xy 300.079402 -345.771143) (xy 300.033516 -345.800632) (xy 299.9839 -345.823291) (xy 299.931564 -345.838658)
			(xy 299.877575 -345.846421) (xy 299.850302 -345.846908) (xy 298.986702 -345.846908) (xy 298.959434 -345.846353)
			(xy 298.905454 -345.838592) (xy 298.853127 -345.823228) (xy 298.80352 -345.800573) (xy 298.757641 -345.771089)
			(xy 298.716426 -345.735376) (xy 298.680712 -345.69416) (xy 298.651228 -345.648282) (xy 298.628573 -345.598675)
			(xy 298.613209 -345.546348) (xy 298.605447 -345.492368) (xy 297.122622 -345.492368) (xy 297.122622 -345.492371)
			(xy 297.11486 -345.546357) (xy 297.099495 -345.59869) (xy 297.076839 -345.648303) (xy 297.047354 -345.694187)
			(xy 297.011639 -345.735409) (xy 296.970421 -345.771128) (xy 296.92454 -345.800619) (xy 296.874929 -345.82328)
			(xy 296.822598 -345.838651) (xy 296.768613 -345.846419) (xy 296.741342 -345.846908) (xy 295.877742 -345.846908)
			(xy 295.850472 -345.846355) (xy 295.796487 -345.838599) (xy 295.744156 -345.823238) (xy 295.694543 -345.800586)
			(xy 295.64866 -345.771103) (xy 295.60744 -345.73539) (xy 295.571722 -345.694174) (xy 295.542234 -345.648293)
			(xy 295.519576 -345.598683) (xy 295.50421 -345.546354) (xy 295.496448 -345.49237) (xy 294.013744 -345.49237)
			(xy 294.013744 -345.492375) (xy 294.005981 -345.54637) (xy 293.990612 -345.59871) (xy 293.96795 -345.648331)
			(xy 293.938457 -345.694221) (xy 293.902734 -345.735446) (xy 293.861506 -345.771168) (xy 293.815615 -345.800659)
			(xy 293.765994 -345.823318) (xy 293.713652 -345.838685) (xy 293.659657 -345.846446) (xy 293.632382 -345.846908)
			(xy 292.768782 -345.846908) (xy 292.741517 -345.846328) (xy 292.687542 -345.838566) (xy 292.635221 -345.823201)
			(xy 292.585619 -345.800546) (xy 292.539745 -345.771063) (xy 292.498535 -345.735352) (xy 292.462826 -345.69414)
			(xy 292.433345 -345.648266) (xy 292.410693 -345.598663) (xy 292.395331 -345.546341) (xy 292.38757 -345.492365)
			(xy 290.904722 -345.492365) (xy 290.904722 -345.492372) (xy 290.896959 -345.54636) (xy 290.881593 -345.598694)
			(xy 290.858936 -345.648309) (xy 290.829449 -345.694194) (xy 290.793732 -345.735416) (xy 290.752512 -345.771136)
			(xy 290.706628 -345.800626) (xy 290.657015 -345.823286) (xy 290.604681 -345.838655) (xy 290.550694 -345.84642)
			(xy 290.523422 -345.846908) (xy 289.659822 -345.846908) (xy 289.632553 -345.846354) (xy 289.57857 -345.838595)
			(xy 289.526241 -345.823233) (xy 289.476632 -345.800579) (xy 289.430751 -345.771096) (xy 289.389533 -345.735383)
			(xy 289.353817 -345.694167) (xy 289.324331 -345.648288) (xy 289.301675 -345.598679) (xy 289.286309 -345.546351)
			(xy 289.278547 -345.492369) (xy 287.795844 -345.492369) (xy 287.795844 -345.492376) (xy 287.78808 -345.546373)
			(xy 287.77271 -345.598715) (xy 287.750047 -345.648336) (xy 287.720552 -345.694227) (xy 287.684827 -345.735453)
			(xy 287.643597 -345.771175) (xy 287.597703 -345.800665) (xy 287.548079 -345.823323) (xy 287.495736 -345.838688)
			(xy 287.441738 -345.846447) (xy 287.414462 -345.846908) (xy 286.550862 -345.846908) (xy 286.523598 -345.846327)
			(xy 286.469625 -345.838562) (xy 286.417306 -345.823195) (xy 286.367707 -345.80054) (xy 286.321836 -345.771056)
			(xy 286.280628 -345.735345) (xy 286.244921 -345.694134) (xy 286.215442 -345.64826) (xy 286.192792 -345.598658)
			(xy 286.17743 -345.546338) (xy 286.16967 -345.492364) (xy 284.686821 -345.492364) (xy 284.686821 -345.492373)
			(xy 284.679059 -345.546362) (xy 284.663692 -345.598698) (xy 284.641033 -345.648314) (xy 284.611544 -345.6942)
			(xy 284.575824 -345.735423) (xy 284.534602 -345.771143) (xy 284.488716 -345.800632) (xy 284.4391 -345.823291)
			(xy 284.386764 -345.838658) (xy 284.332775 -345.846421) (xy 284.305502 -345.846908) (xy 283.441902 -345.846908)
			(xy 283.414634 -345.846353) (xy 283.360654 -345.838592) (xy 283.308327 -345.823228) (xy 283.25872 -345.800573)
			(xy 283.212841 -345.771089) (xy 283.171626 -345.735376) (xy 283.135912 -345.69416) (xy 283.106428 -345.648282)
			(xy 283.083773 -345.598675) (xy 283.068409 -345.546348) (xy 283.060647 -345.492368) (xy 281.577822 -345.492368)
			(xy 281.577822 -345.492371) (xy 281.57006 -345.546357) (xy 281.554695 -345.59869) (xy 281.532039 -345.648303)
			(xy 281.502554 -345.694187) (xy 281.466839 -345.735409) (xy 281.425621 -345.771128) (xy 281.37974 -345.800619)
			(xy 281.330129 -345.82328) (xy 281.277798 -345.838651) (xy 281.223813 -345.846419) (xy 281.196542 -345.846908)
			(xy 280.332942 -345.846908) (xy 280.305672 -345.846355) (xy 280.251687 -345.838599) (xy 280.199356 -345.823238)
			(xy 280.149743 -345.800586) (xy 280.10386 -345.771103) (xy 280.06264 -345.73539) (xy 280.026922 -345.694174)
			(xy 279.997434 -345.648293) (xy 279.974776 -345.598683) (xy 279.95941 -345.546354) (xy 279.951648 -345.49237)
			(xy 278.468944 -345.49237) (xy 278.468944 -345.492375) (xy 278.461181 -345.54637) (xy 278.445812 -345.59871)
			(xy 278.42315 -345.648331) (xy 278.393657 -345.694221) (xy 278.357934 -345.735446) (xy 278.316706 -345.771168)
			(xy 278.270815 -345.800659) (xy 278.221194 -345.823318) (xy 278.168852 -345.838685) (xy 278.114857 -345.846446)
			(xy 278.087582 -345.846908) (xy 277.223982 -345.846908) (xy 277.196717 -345.846328) (xy 277.142742 -345.838566)
			(xy 277.090421 -345.823201) (xy 277.040819 -345.800546) (xy 276.994945 -345.771063) (xy 276.953735 -345.735352)
			(xy 276.918026 -345.69414) (xy 276.888545 -345.648266) (xy 276.865893 -345.598663) (xy 276.850531 -345.546341)
			(xy 276.84277 -345.492365) (xy 275.359922 -345.492365) (xy 275.359922 -345.492372) (xy 275.352159 -345.54636)
			(xy 275.336793 -345.598694) (xy 275.314136 -345.648309) (xy 275.284649 -345.694194) (xy 275.248932 -345.735416)
			(xy 275.207712 -345.771136) (xy 275.161828 -345.800626) (xy 275.112215 -345.823286) (xy 275.059881 -345.838655)
			(xy 275.005894 -345.84642) (xy 274.978622 -345.846908) (xy 274.115022 -345.846908) (xy 274.087753 -345.846354)
			(xy 274.03377 -345.838595) (xy 273.981441 -345.823233) (xy 273.931832 -345.800579) (xy 273.885951 -345.771096)
			(xy 273.844733 -345.735383) (xy 273.809017 -345.694167) (xy 273.779531 -345.648288) (xy 273.756875 -345.598679)
			(xy 273.741509 -345.546351) (xy 273.733747 -345.492369) (xy 272.251044 -345.492369) (xy 272.251044 -345.492376)
			(xy 272.24328 -345.546373) (xy 272.22791 -345.598715) (xy 272.205247 -345.648336) (xy 272.175752 -345.694227)
			(xy 272.140027 -345.735453) (xy 272.098797 -345.771175) (xy 272.052903 -345.800665) (xy 272.003279 -345.823323)
			(xy 271.950936 -345.838688) (xy 271.896938 -345.846447) (xy 271.869662 -345.846908) (xy 271.006062 -345.846908)
			(xy 270.978798 -345.846327) (xy 270.924825 -345.838562) (xy 270.872506 -345.823195) (xy 270.822907 -345.80054)
			(xy 270.777036 -345.771056) (xy 270.735828 -345.735345) (xy 270.700121 -345.694134) (xy 270.670642 -345.64826)
			(xy 270.647992 -345.598658) (xy 270.63263 -345.546338) (xy 270.62487 -345.492364) (xy 269.142021 -345.492364)
			(xy 269.142021 -345.492373) (xy 269.134259 -345.546362) (xy 269.118892 -345.598698) (xy 269.096233 -345.648314)
			(xy 269.066744 -345.6942) (xy 269.031024 -345.735423) (xy 268.989802 -345.771143) (xy 268.943916 -345.800632)
			(xy 268.8943 -345.823291) (xy 268.841964 -345.838658) (xy 268.787975 -345.846421) (xy 268.760702 -345.846908)
			(xy 267.897102 -345.846908) (xy 267.869834 -345.846353) (xy 267.815854 -345.838592) (xy 267.763527 -345.823228)
			(xy 267.71392 -345.800573) (xy 267.668041 -345.771089) (xy 267.626826 -345.735376) (xy 267.591112 -345.69416)
			(xy 267.561628 -345.648282) (xy 267.538973 -345.598675) (xy 267.523609 -345.546348) (xy 267.515847 -345.492368)
			(xy 257.898791 -345.492368) (xy 257.910525 -345.517399) (xy 257.926593 -345.570806) (xy 257.934713 -345.625982)
			(xy 257.935222 -345.653868) (xy 257.934713 -345.681754) (xy 257.926593 -345.73693) (xy 257.910525 -345.790337)
			(xy 257.886853 -345.840834) (xy 257.85608 -345.887347) (xy 257.818863 -345.928884) (xy 257.775995 -345.964559)
			(xy 257.728389 -345.993613) (xy 257.67706 -346.015425) (xy 257.623103 -346.029531) (xy 257.567666 -346.035631)
			(xy 257.511932 -346.033594) (xy 257.457089 -346.023464) (xy 257.404305 -346.005457) (xy 257.354705 -345.979956)
			(xy 257.309347 -345.947505) (xy 257.269198 -345.908796) (xy 257.235112 -345.864653) (xy 257.207816 -345.816018)
			(xy 257.187893 -345.763927) (xy 257.175767 -345.70949) (xy 257.171696 -345.653868) (xy 251.40125 -345.653868)
			(xy 251.416285 -345.66638) (xy 251.453502 -345.707917) (xy 251.484275 -345.75443) (xy 251.507947 -345.804927)
			(xy 251.524015 -345.858334) (xy 251.532135 -345.91351) (xy 251.532644 -345.941396) (xy 251.532135 -345.969282)
			(xy 251.524015 -346.024458) (xy 251.507947 -346.077865) (xy 251.484275 -346.128362) (xy 251.453502 -346.174875)
			(xy 251.416285 -346.216412) (xy 251.373417 -346.252087) (xy 251.325811 -346.281141) (xy 251.274482 -346.302953)
			(xy 251.220525 -346.317059) (xy 251.165088 -346.323159) (xy 251.109354 -346.321122) (xy 251.054511 -346.310992)
			(xy 251.001727 -346.292985) (xy 250.952127 -346.267484) (xy 250.906769 -346.235033) (xy 250.86662 -346.196324)
			(xy 250.832534 -346.152181) (xy 250.805238 -346.103546) (xy 250.785315 -346.051455) (xy 250.773189 -345.997018)
			(xy 250.769118 -345.941396) (xy 235.87226 -345.941396) (xy 235.863833 -345.969407) (xy 235.840161 -346.019904)
			(xy 235.809388 -346.066417) (xy 235.772171 -346.107954) (xy 235.729303 -346.143629) (xy 235.681697 -346.172683)
			(xy 235.630368 -346.194495) (xy 235.576411 -346.208601) (xy 235.520974 -346.214701) (xy 235.46524 -346.212664)
			(xy 235.410397 -346.202534) (xy 235.357613 -346.184527) (xy 235.308013 -346.159026) (xy 235.262655 -346.126575)
			(xy 235.222506 -346.087866) (xy 235.18842 -346.043723) (xy 235.161124 -345.995088) (xy 235.141201 -345.942997)
			(xy 235.129075 -345.88856) (xy 235.125004 -345.832938) (xy 197.349125 -345.832938) (xy 197.329544 -345.838686)
			(xy 197.275548 -345.846446) (xy 197.248272 -345.846908) (xy 196.384672 -345.846908) (xy 196.357407 -345.846328)
			(xy 196.303433 -345.838564) (xy 196.251113 -345.823198) (xy 196.201513 -345.800543) (xy 196.155641 -345.77106)
			(xy 196.114431 -345.735349) (xy 196.078723 -345.694137) (xy 196.049244 -345.648263) (xy 196.026592 -345.59866)
			(xy 196.01123 -345.546339) (xy 196.00347 -345.492365) (xy 194.520621 -345.492365) (xy 194.520621 -345.492372)
			(xy 194.512859 -345.546361) (xy 194.497493 -345.598696) (xy 194.474835 -345.648311) (xy 194.445346 -345.694197)
			(xy 194.409628 -345.735419) (xy 194.368407 -345.771139) (xy 194.322522 -345.800629) (xy 194.272907 -345.823288)
			(xy 194.220573 -345.838657) (xy 194.166584 -345.846421) (xy 194.139312 -345.846908) (xy 193.275712 -345.846908)
			(xy 193.248444 -345.846353) (xy 193.194462 -345.838594) (xy 193.142134 -345.82323) (xy 193.092526 -345.800576)
			(xy 193.046646 -345.771092) (xy 193.005429 -345.735379) (xy 192.969715 -345.694164) (xy 192.94023 -345.648285)
			(xy 192.917574 -345.598677) (xy 192.902209 -345.54635) (xy 192.894447 -345.492368) (xy 191.411744 -345.492368)
			(xy 191.411744 -345.492376) (xy 191.40398 -345.546374) (xy 191.388609 -345.598717) (xy 191.365946 -345.648339)
			(xy 191.33645 -345.694231) (xy 191.300723 -345.735457) (xy 191.259492 -345.771179) (xy 191.213597 -345.800669)
			(xy 191.163972 -345.823326) (xy 191.111627 -345.83869) (xy 191.057629 -345.846448) (xy 191.030352 -345.846908)
			(xy 190.166752 -345.846908) (xy 190.139488 -345.846326) (xy 190.085516 -345.83856) (xy 190.033199 -345.823192)
			(xy 189.983601 -345.800536) (xy 189.937731 -345.771053) (xy 189.896524 -345.735342) (xy 189.860819 -345.69413)
			(xy 189.831341 -345.648257) (xy 189.808691 -345.598656) (xy 189.79333 -345.546337) (xy 189.78557 -345.492364)
			(xy 188.302744 -345.492364) (xy 188.302744 -345.492375) (xy 188.294981 -345.546369) (xy 188.279613 -345.598708)
			(xy 188.256952 -345.648328) (xy 188.22746 -345.694218) (xy 188.191737 -345.735443) (xy 188.150511 -345.771165)
			(xy 188.104621 -345.800656) (xy 188.055001 -345.823315) (xy 188.002661 -345.838683) (xy 187.948667 -345.846445)
			(xy 187.921392 -345.846908) (xy 187.057792 -345.846908) (xy 187.030526 -345.846329) (xy 186.97655 -345.838567)
			(xy 186.924228 -345.823203) (xy 186.874625 -345.800549) (xy 186.82875 -345.771067) (xy 186.787538 -345.735356)
			(xy 186.751828 -345.694143) (xy 186.722347 -345.648268) (xy 186.699694 -345.598665) (xy 186.684331 -345.546342)
			(xy 186.67657 -345.492366) (xy 185.193722 -345.492366) (xy 185.193722 -345.492371) (xy 185.18596 -345.546358)
			(xy 185.170594 -345.598692) (xy 185.147938 -345.648306) (xy 185.118451 -345.694191) (xy 185.082735 -345.735412)
			(xy 185.041516 -345.771132) (xy 184.995634 -345.800622) (xy 184.946022 -345.823283) (xy 184.89369 -345.838653)
			(xy 184.839703 -345.846419) (xy 184.812432 -345.846908) (xy 183.948832 -345.846908) (xy 183.921563 -345.846355)
			(xy 183.867579 -345.838597) (xy 183.815249 -345.823236) (xy 183.765638 -345.800583) (xy 183.719755 -345.771099)
			(xy 183.678536 -345.735386) (xy 183.64282 -345.69417) (xy 183.613333 -345.648291) (xy 183.590676 -345.598681)
			(xy 183.57531 -345.546352) (xy 183.567547 -345.492369) (xy 182.084844 -345.492369) (xy 182.084844 -345.492376)
			(xy 182.077081 -345.546371) (xy 182.061711 -345.598713) (xy 182.039049 -345.648334) (xy 182.009555 -345.694224)
			(xy 181.97383 -345.73545) (xy 181.932602 -345.771172) (xy 181.886709 -345.800662) (xy 181.837086 -345.823321)
			(xy 181.784744 -345.838686) (xy 181.730748 -345.846446) (xy 181.703472 -345.846908) (xy 180.839872 -345.846908)
			(xy 180.812607 -345.846328) (xy 180.758633 -345.838564) (xy 180.706313 -345.823198) (xy 180.656713 -345.800543)
			(xy 180.610841 -345.77106) (xy 180.569631 -345.735349) (xy 180.533923 -345.694137) (xy 180.504444 -345.648263)
			(xy 180.481792 -345.59866) (xy 180.46643 -345.546339) (xy 180.45867 -345.492365) (xy 178.975821 -345.492365)
			(xy 178.975821 -345.492372) (xy 178.968059 -345.546361) (xy 178.952693 -345.598696) (xy 178.930035 -345.648311)
			(xy 178.900546 -345.694197) (xy 178.864828 -345.735419) (xy 178.823607 -345.771139) (xy 178.777722 -345.800629)
			(xy 178.728107 -345.823288) (xy 178.675773 -345.838657) (xy 178.621784 -345.846421) (xy 178.594512 -345.846908)
			(xy 177.730912 -345.846908) (xy 177.703644 -345.846353) (xy 177.649662 -345.838594) (xy 177.597334 -345.82323)
			(xy 177.547726 -345.800576) (xy 177.501846 -345.771092) (xy 177.460629 -345.735379) (xy 177.424915 -345.694164)
			(xy 177.39543 -345.648285) (xy 177.372774 -345.598677) (xy 177.357409 -345.54635) (xy 177.349647 -345.492368)
			(xy 175.866944 -345.492368) (xy 175.866944 -345.492376) (xy 175.85918 -345.546374) (xy 175.843809 -345.598717)
			(xy 175.821146 -345.648339) (xy 175.79165 -345.694231) (xy 175.755923 -345.735457) (xy 175.714692 -345.771179)
			(xy 175.668797 -345.800669) (xy 175.619172 -345.823326) (xy 175.566827 -345.83869) (xy 175.512829 -345.846448)
			(xy 175.485552 -345.846908) (xy 174.621952 -345.846908) (xy 174.594688 -345.846326) (xy 174.540716 -345.83856)
			(xy 174.488399 -345.823192) (xy 174.438801 -345.800536) (xy 174.392931 -345.771053) (xy 174.351724 -345.735342)
			(xy 174.316019 -345.69413) (xy 174.286541 -345.648257) (xy 174.263891 -345.598656) (xy 174.24853 -345.546337)
			(xy 174.24077 -345.492364) (xy 172.757944 -345.492364) (xy 172.757944 -345.492375) (xy 172.750181 -345.546369)
			(xy 172.734813 -345.598708) (xy 172.712152 -345.648328) (xy 172.68266 -345.694218) (xy 172.646937 -345.735443)
			(xy 172.605711 -345.771165) (xy 172.559821 -345.800656) (xy 172.510201 -345.823315) (xy 172.457861 -345.838683)
			(xy 172.403867 -345.846445) (xy 172.376592 -345.846908) (xy 171.512992 -345.846908) (xy 171.485726 -345.846329)
			(xy 171.43175 -345.838567) (xy 171.379428 -345.823203) (xy 171.329825 -345.800549) (xy 171.28395 -345.771067)
			(xy 171.242738 -345.735356) (xy 171.207028 -345.694143) (xy 171.177547 -345.648268) (xy 171.154894 -345.598665)
			(xy 171.139531 -345.546342) (xy 171.13177 -345.492366) (xy 169.648922 -345.492366) (xy 169.648922 -345.492371)
			(xy 169.64116 -345.546358) (xy 169.625794 -345.598692) (xy 169.603138 -345.648306) (xy 169.573651 -345.694191)
			(xy 169.537935 -345.735412) (xy 169.496716 -345.771132) (xy 169.450834 -345.800622) (xy 169.401222 -345.823283)
			(xy 169.34889 -345.838653) (xy 169.294903 -345.846419) (xy 169.267632 -345.846908) (xy 168.404032 -345.846908)
			(xy 168.376763 -345.846355) (xy 168.322779 -345.838597) (xy 168.270449 -345.823236) (xy 168.220838 -345.800583)
			(xy 168.174955 -345.771099) (xy 168.133736 -345.735386) (xy 168.09802 -345.69417) (xy 168.068533 -345.648291)
			(xy 168.045876 -345.598681) (xy 168.03051 -345.546352) (xy 168.022747 -345.492369) (xy 166.540044 -345.492369)
			(xy 166.540044 -345.492376) (xy 166.532281 -345.546371) (xy 166.516911 -345.598713) (xy 166.494249 -345.648334)
			(xy 166.464755 -345.694224) (xy 166.42903 -345.73545) (xy 166.387802 -345.771172) (xy 166.341909 -345.800662)
			(xy 166.292286 -345.823321) (xy 166.239944 -345.838686) (xy 166.185948 -345.846446) (xy 166.158672 -345.846908)
			(xy 165.295072 -345.846908) (xy 165.267807 -345.846328) (xy 165.213833 -345.838564) (xy 165.161513 -345.823198)
			(xy 165.111913 -345.800543) (xy 165.066041 -345.77106) (xy 165.024831 -345.735349) (xy 164.989123 -345.694137)
			(xy 164.959644 -345.648263) (xy 164.936992 -345.59866) (xy 164.92163 -345.546339) (xy 164.91387 -345.492365)
			(xy 156.971057 -345.492365) (xy 154.734211 -346.917956) (xy 245.50903 -346.917956) (xy 245.50903 -346.83326)
			(xy 245.517081 -346.748946) (xy 245.53311 -346.66578) (xy 245.556971 -346.584513) (xy 245.58845 -346.505883)
			(xy 245.627261 -346.430602) (xy 245.673051 -346.35935) (xy 245.725407 -346.292774) (xy 245.783855 -346.231476)
			(xy 245.847865 -346.176011) (xy 245.916857 -346.126882) (xy 245.990207 -346.084533) (xy 246.06725 -346.049349)
			(xy 246.147289 -346.021647) (xy 246.229598 -346.001679) (xy 246.313433 -345.989626) (xy 246.398034 -345.985596)
			(xy 246.482635 -345.989626) (xy 246.56647 -346.001679) (xy 246.648779 -346.021647) (xy 246.728818 -346.049349)
			(xy 246.805861 -346.084533) (xy 246.879211 -346.126882) (xy 246.948203 -346.176011) (xy 247.012213 -346.231476)
			(xy 247.070661 -346.292774) (xy 247.123017 -346.35935) (xy 247.168807 -346.430602) (xy 247.171556 -346.435934)
			(xy 259.550914 -346.435934) (xy 259.554985 -346.380312) (xy 259.567111 -346.325875) (xy 259.587034 -346.273784)
			(xy 259.61433 -346.225149) (xy 259.648416 -346.181006) (xy 259.688565 -346.142297) (xy 259.733923 -346.109846)
			(xy 259.783523 -346.084345) (xy 259.836307 -346.066338) (xy 259.89115 -346.056208) (xy 259.946884 -346.054171)
			(xy 260.002321 -346.060271) (xy 260.056278 -346.074377) (xy 260.107607 -346.096189) (xy 260.155213 -346.125243)
			(xy 260.198081 -346.160918) (xy 260.235298 -346.202455) (xy 260.266071 -346.248968) (xy 260.289743 -346.299465)
			(xy 260.305811 -346.352872) (xy 260.313931 -346.408048) (xy 260.31444 -346.435934) (xy 260.313931 -346.46382)
			(xy 260.305811 -346.518996) (xy 260.289743 -346.572403) (xy 260.266071 -346.6229) (xy 260.235298 -346.669413)
			(xy 260.198081 -346.71095) (xy 260.155213 -346.746625) (xy 260.107607 -346.775679) (xy 260.056278 -346.797491)
			(xy 260.002321 -346.811597) (xy 259.946884 -346.817697) (xy 259.89115 -346.81566) (xy 259.836307 -346.80553)
			(xy 259.783523 -346.787523) (xy 259.733923 -346.762022) (xy 259.688565 -346.729571) (xy 259.648416 -346.690862)
			(xy 259.61433 -346.646719) (xy 259.587034 -346.598084) (xy 259.567111 -346.545993) (xy 259.554985 -346.491556)
			(xy 259.550914 -346.435934) (xy 247.171556 -346.435934) (xy 247.207618 -346.505883) (xy 247.239097 -346.584513)
			(xy 247.262958 -346.66578) (xy 247.278987 -346.748946) (xy 247.287038 -346.83326) (xy 247.287542 -346.875608)
			(xy 247.287038 -346.917956) (xy 247.278987 -347.00227) (xy 247.262958 -347.085436) (xy 247.239097 -347.166703)
			(xy 247.207618 -347.245333) (xy 247.168807 -347.320614) (xy 247.123017 -347.391866) (xy 247.070661 -347.458442)
			(xy 247.012213 -347.51974) (xy 246.948203 -347.575205) (xy 246.879211 -347.624334) (xy 246.805861 -347.666683)
			(xy 246.728818 -347.701867) (xy 246.648779 -347.729569) (xy 246.56647 -347.749537) (xy 246.482635 -347.76159)
			(xy 246.398034 -347.765621) (xy 246.313433 -347.76159) (xy 246.229598 -347.749537) (xy 246.147289 -347.729569)
			(xy 246.06725 -347.701867) (xy 245.990207 -347.666683) (xy 245.916857 -347.624334) (xy 245.847865 -347.575205)
			(xy 245.783855 -347.51974) (xy 245.725407 -347.458442) (xy 245.673051 -347.391866) (xy 245.627261 -347.320614)
			(xy 245.58845 -347.245333) (xy 245.556971 -347.166703) (xy 245.53311 -347.085436) (xy 245.517081 -347.00227)
			(xy 245.50903 -346.917956) (xy 154.734211 -346.917956) (xy 153.386629 -347.7768) (xy 253.262382 -347.7768)
			(xy 253.266453 -347.721178) (xy 253.278579 -347.666741) (xy 253.298502 -347.61465) (xy 253.325798 -347.566015)
			(xy 253.359884 -347.521872) (xy 253.400033 -347.483163) (xy 253.445391 -347.450712) (xy 253.494991 -347.425211)
			(xy 253.547775 -347.407204) (xy 253.602618 -347.397074) (xy 253.658352 -347.395037) (xy 253.713789 -347.401137)
			(xy 253.767746 -347.415243) (xy 253.819075 -347.437055) (xy 253.866681 -347.466109) (xy 253.909549 -347.501784)
			(xy 253.946766 -347.543321) (xy 253.977539 -347.589834) (xy 254.001211 -347.640331) (xy 254.014376 -347.68409)
			(xy 255.611882 -347.68409) (xy 255.615953 -347.628468) (xy 255.628079 -347.574031) (xy 255.648002 -347.52194)
			(xy 255.675298 -347.473305) (xy 255.709384 -347.429162) (xy 255.749533 -347.390453) (xy 255.794891 -347.358002)
			(xy 255.844491 -347.332501) (xy 255.897275 -347.314494) (xy 255.952118 -347.304364) (xy 256.007852 -347.302327)
			(xy 256.063289 -347.308427) (xy 256.117246 -347.322533) (xy 256.168575 -347.344345) (xy 256.216181 -347.373399)
			(xy 256.259049 -347.409074) (xy 256.296266 -347.450611) (xy 256.327039 -347.497124) (xy 256.350711 -347.547621)
			(xy 256.366779 -347.601028) (xy 256.374899 -347.656204) (xy 256.375408 -347.68409) (xy 256.374899 -347.711976)
			(xy 256.366779 -347.767152) (xy 256.350711 -347.820559) (xy 256.327039 -347.871056) (xy 256.296266 -347.917569)
			(xy 256.259049 -347.959106) (xy 256.216181 -347.994781) (xy 256.168575 -348.023835) (xy 256.117246 -348.045647)
			(xy 256.063289 -348.059753) (xy 256.007852 -348.065853) (xy 255.952118 -348.063816) (xy 255.897275 -348.053686)
			(xy 255.844491 -348.035679) (xy 255.794891 -348.010178) (xy 255.749533 -347.977727) (xy 255.709384 -347.939018)
			(xy 255.675298 -347.894875) (xy 255.648002 -347.84624) (xy 255.628079 -347.794149) (xy 255.615953 -347.739712)
			(xy 255.611882 -347.68409) (xy 254.014376 -347.68409) (xy 254.017279 -347.693738) (xy 254.025399 -347.748914)
			(xy 254.025908 -347.7768) (xy 254.025399 -347.804686) (xy 254.017279 -347.859862) (xy 254.001211 -347.913269)
			(xy 253.977539 -347.963766) (xy 253.946766 -348.010279) (xy 253.909549 -348.051816) (xy 253.866681 -348.087491)
			(xy 253.819075 -348.116545) (xy 253.767746 -348.138357) (xy 253.713789 -348.152463) (xy 253.658352 -348.158563)
			(xy 253.602618 -348.156526) (xy 253.547775 -348.146396) (xy 253.494991 -348.128389) (xy 253.445391 -348.102888)
			(xy 253.400033 -348.070437) (xy 253.359884 -348.031728) (xy 253.325798 -347.987585) (xy 253.298502 -347.93895)
			(xy 253.278579 -347.886859) (xy 253.266453 -347.832422) (xy 253.262382 -347.7768) (xy 153.386629 -347.7768)
			(xy 152.074463 -348.613072) (xy 161.804792 -348.613072) (xy 161.804792 -348.558528) (xy 161.812554 -348.504538)
			(xy 161.827921 -348.452203) (xy 161.850581 -348.402588) (xy 161.88007 -348.356703) (xy 161.91579 -348.315481)
			(xy 161.957012 -348.279763) (xy 162.002899 -348.250275) (xy 162.052515 -348.227617) (xy 162.10485 -348.212252)
			(xy 162.15884 -348.204491) (xy 162.186112 -348.204028) (xy 163.049712 -348.204028) (xy 163.07698 -348.204535)
			(xy 163.130961 -348.212298) (xy 163.183288 -348.227664) (xy 163.232895 -348.25032) (xy 163.278773 -348.279806)
			(xy 163.319988 -348.31552) (xy 163.355701 -348.356736) (xy 163.385185 -348.402615) (xy 163.40784 -348.452224)
			(xy 163.423204 -348.504551) (xy 163.430966 -348.558532) (xy 163.430966 -348.613068) (xy 163.430966 -348.613069)
			(xy 164.913814 -348.613069) (xy 164.913814 -348.558531) (xy 164.921576 -348.504549) (xy 164.93694 -348.45222)
			(xy 164.959595 -348.40261) (xy 164.989079 -348.35673) (xy 165.024792 -348.315512) (xy 165.066007 -348.279795)
			(xy 165.111886 -348.250308) (xy 165.161494 -348.22765) (xy 165.213821 -348.212281) (xy 165.267803 -348.204516)
			(xy 165.295072 -348.204028) (xy 166.158672 -348.204028) (xy 166.185944 -348.20451) (xy 166.239932 -348.212268)
			(xy 166.292267 -348.227632) (xy 166.341882 -348.250287) (xy 166.387768 -348.279773) (xy 166.42899 -348.31549)
			(xy 166.46471 -348.356709) (xy 166.494199 -348.402593) (xy 166.516859 -348.452207) (xy 166.532226 -348.504541)
			(xy 166.539988 -348.558528) (xy 166.539988 -348.613072) (xy 166.539988 -348.613073) (xy 168.022692 -348.613073)
			(xy 168.022692 -348.558527) (xy 168.030455 -348.504536) (xy 168.045823 -348.452199) (xy 168.068484 -348.402583)
			(xy 168.097975 -348.356696) (xy 168.133697 -348.315474) (xy 168.174922 -348.279756) (xy 168.220811 -348.250268)
			(xy 168.270429 -348.227612) (xy 168.322767 -348.212248) (xy 168.376759 -348.204489) (xy 168.404032 -348.204028)
			(xy 169.267632 -348.204028) (xy 169.294899 -348.204537) (xy 169.348878 -348.212302) (xy 169.401202 -348.227669)
			(xy 169.450807 -348.250327) (xy 169.496683 -348.279813) (xy 169.537895 -348.315527) (xy 169.573606 -348.356743)
			(xy 169.603088 -348.402621) (xy 169.625742 -348.452228) (xy 169.641105 -348.504553) (xy 169.648866 -348.558533)
			(xy 169.648866 -348.613067) (xy 169.648866 -348.61307) (xy 171.131714 -348.61307) (xy 171.131714 -348.55853)
			(xy 171.139476 -348.504546) (xy 171.154841 -348.452216) (xy 171.177498 -348.402605) (xy 171.206984 -348.356723)
			(xy 171.242699 -348.315505) (xy 171.283917 -348.279788) (xy 171.329798 -348.250301) (xy 171.379408 -348.227644)
			(xy 171.431738 -348.212278) (xy 171.485722 -348.204515) (xy 171.512992 -348.204028) (xy 172.376592 -348.204028)
			(xy 172.403863 -348.204511) (xy 172.457849 -348.212272) (xy 172.510181 -348.227637) (xy 172.559794 -348.250294)
			(xy 172.605678 -348.27978) (xy 172.646898 -348.315497) (xy 172.682615 -348.356716) (xy 172.712103 -348.402599)
			(xy 172.73476 -348.452211) (xy 172.750126 -348.504543) (xy 172.757889 -348.558529) (xy 172.757889 -348.613068)
			(xy 174.240714 -348.613068) (xy 174.240714 -348.558532) (xy 174.248475 -348.504551) (xy 174.263838 -348.452224)
			(xy 174.286492 -348.402616) (xy 174.315974 -348.356736) (xy 174.351685 -348.315519) (xy 174.392898 -348.279803)
			(xy 174.438774 -348.250315) (xy 174.488379 -348.227655) (xy 174.540704 -348.212285) (xy 174.594684 -348.204518)
			(xy 174.621952 -348.204028) (xy 175.485552 -348.204028) (xy 175.512825 -348.204508) (xy 175.566815 -348.212265)
			(xy 175.619152 -348.227626) (xy 175.66877 -348.250281) (xy 175.714659 -348.279766) (xy 175.755883 -348.315483)
			(xy 175.791605 -348.356703) (xy 175.821096 -348.402588) (xy 175.843757 -348.452203) (xy 175.859125 -348.504538)
			(xy 175.866888 -348.558528) (xy 175.866888 -348.613072) (xy 177.349592 -348.613072) (xy 177.349592 -348.558528)
			(xy 177.357354 -348.504538) (xy 177.372721 -348.452203) (xy 177.395381 -348.402588) (xy 177.42487 -348.356703)
			(xy 177.46059 -348.315481) (xy 177.501812 -348.279763) (xy 177.547699 -348.250275) (xy 177.597315 -348.227617)
			(xy 177.64965 -348.212252) (xy 177.70364 -348.204491) (xy 177.730912 -348.204028) (xy 178.594512 -348.204028)
			(xy 178.62178 -348.204535) (xy 178.675761 -348.212298) (xy 178.728088 -348.227664) (xy 178.777695 -348.25032)
			(xy 178.823573 -348.279806) (xy 178.864788 -348.31552) (xy 178.900501 -348.356736) (xy 178.929985 -348.402615)
			(xy 178.95264 -348.452224) (xy 178.968004 -348.504551) (xy 178.975766 -348.558532) (xy 178.975766 -348.613068)
			(xy 178.975766 -348.613069) (xy 180.458614 -348.613069) (xy 180.458614 -348.558531) (xy 180.466376 -348.504549)
			(xy 180.48174 -348.45222) (xy 180.504395 -348.40261) (xy 180.533879 -348.35673) (xy 180.569592 -348.315512)
			(xy 180.610807 -348.279795) (xy 180.656686 -348.250308) (xy 180.706294 -348.22765) (xy 180.758621 -348.212281)
			(xy 180.812603 -348.204516) (xy 180.839872 -348.204028) (xy 181.703472 -348.204028) (xy 181.730744 -348.20451)
			(xy 181.784732 -348.212268) (xy 181.837067 -348.227632) (xy 181.886682 -348.250287) (xy 181.932568 -348.279773)
			(xy 181.97379 -348.31549) (xy 182.00951 -348.356709) (xy 182.038999 -348.402593) (xy 182.061659 -348.452207)
			(xy 182.077026 -348.504541) (xy 182.084788 -348.558528) (xy 182.084788 -348.613072) (xy 182.084788 -348.613073)
			(xy 183.567492 -348.613073) (xy 183.567492 -348.558527) (xy 183.575255 -348.504536) (xy 183.590623 -348.452199)
			(xy 183.613284 -348.402583) (xy 183.642775 -348.356696) (xy 183.678497 -348.315474) (xy 183.719722 -348.279756)
			(xy 183.765611 -348.250268) (xy 183.815229 -348.227612) (xy 183.867567 -348.212248) (xy 183.921559 -348.204489)
			(xy 183.948832 -348.204028) (xy 184.812432 -348.204028) (xy 184.839699 -348.204537) (xy 184.893678 -348.212302)
			(xy 184.946002 -348.227669) (xy 184.995607 -348.250327) (xy 185.041483 -348.279813) (xy 185.082695 -348.315527)
			(xy 185.118406 -348.356743) (xy 185.147888 -348.402621) (xy 185.170542 -348.452228) (xy 185.185905 -348.504553)
			(xy 185.193666 -348.558533) (xy 185.193666 -348.613067) (xy 185.193666 -348.61307) (xy 186.676514 -348.61307)
			(xy 186.676514 -348.55853) (xy 186.684276 -348.504546) (xy 186.699641 -348.452216) (xy 186.722298 -348.402605)
			(xy 186.751784 -348.356723) (xy 186.787499 -348.315505) (xy 186.828717 -348.279788) (xy 186.874598 -348.250301)
			(xy 186.924208 -348.227644) (xy 186.976538 -348.212278) (xy 187.030522 -348.204515) (xy 187.057792 -348.204028)
			(xy 187.921392 -348.204028) (xy 187.948663 -348.204511) (xy 188.002649 -348.212272) (xy 188.054981 -348.227637)
			(xy 188.104594 -348.250294) (xy 188.150478 -348.27978) (xy 188.191698 -348.315497) (xy 188.227415 -348.356716)
			(xy 188.256903 -348.402599) (xy 188.27956 -348.452211) (xy 188.294926 -348.504543) (xy 188.302689 -348.558529)
			(xy 188.302689 -348.613068) (xy 189.785514 -348.613068) (xy 189.785514 -348.558532) (xy 189.793275 -348.504551)
			(xy 189.808638 -348.452224) (xy 189.831292 -348.402616) (xy 189.860774 -348.356736) (xy 189.896485 -348.315519)
			(xy 189.937698 -348.279803) (xy 189.983574 -348.250315) (xy 190.033179 -348.227655) (xy 190.085504 -348.212285)
			(xy 190.139484 -348.204518) (xy 190.166752 -348.204028) (xy 191.030352 -348.204028) (xy 191.057625 -348.204508)
			(xy 191.111615 -348.212265) (xy 191.163952 -348.227626) (xy 191.21357 -348.250281) (xy 191.259459 -348.279766)
			(xy 191.300683 -348.315483) (xy 191.336405 -348.356703) (xy 191.365896 -348.402588) (xy 191.388557 -348.452203)
			(xy 191.403925 -348.504538) (xy 191.411688 -348.558528) (xy 191.411688 -348.613072) (xy 192.894392 -348.613072)
			(xy 192.894392 -348.558528) (xy 192.902154 -348.504538) (xy 192.917521 -348.452203) (xy 192.940181 -348.402588)
			(xy 192.96967 -348.356703) (xy 193.00539 -348.315481) (xy 193.046612 -348.279763) (xy 193.092499 -348.250275)
			(xy 193.142115 -348.227617) (xy 193.19445 -348.212252) (xy 193.24844 -348.204491) (xy 193.275712 -348.204028)
			(xy 194.139312 -348.204028) (xy 194.16658 -348.204535) (xy 194.220561 -348.212298) (xy 194.272888 -348.227664)
			(xy 194.322495 -348.25032) (xy 194.368373 -348.279806) (xy 194.409588 -348.31552) (xy 194.445301 -348.356736)
			(xy 194.474785 -348.402615) (xy 194.49744 -348.452224) (xy 194.50429 -348.475554) (xy 236.142528 -348.475554)
			(xy 236.146599 -348.419932) (xy 236.158725 -348.365495) (xy 236.178648 -348.313404) (xy 236.205944 -348.264769)
			(xy 236.24003 -348.220626) (xy 236.280179 -348.181917) (xy 236.325537 -348.149466) (xy 236.375137 -348.123965)
			(xy 236.427921 -348.105958) (xy 236.482764 -348.095828) (xy 236.538498 -348.093791) (xy 236.593935 -348.099891)
			(xy 236.647892 -348.113997) (xy 236.699221 -348.135809) (xy 236.746827 -348.164863) (xy 236.789695 -348.200538)
			(xy 236.826912 -348.242075) (xy 236.857685 -348.288588) (xy 236.881357 -348.339085) (xy 236.897425 -348.392492)
			(xy 236.902555 -348.427353) (xy 240.622271 -348.427353) (xy 240.622271 -348.372847) (xy 240.630029 -348.318896)
			(xy 240.645386 -348.266598) (xy 240.668029 -348.217018) (xy 240.697499 -348.171166) (xy 240.733194 -348.129974)
			(xy 240.774388 -348.094282) (xy 240.820243 -348.064816) (xy 240.869824 -348.042176) (xy 240.922123 -348.026823)
			(xy 240.976075 -348.019069) (xy 241.003328 -348.018608) (xy 241.032243 -348.019175) (xy 241.089412 -348.027893)
			(xy 241.14461 -348.045141) (xy 241.196572 -348.070524) (xy 241.244107 -348.103459) (xy 241.286126 -348.143192)
			(xy 241.304318 -348.165674) (xy 241.311864 -348.174452) (xy 241.332635 -348.184623) (xy 241.344196 -348.185232)
			(xy 241.42446 -348.185232) (xy 241.436029 -348.184662) (xy 241.456801 -348.17447) (xy 241.464338 -348.165674)
			(xy 241.482501 -348.143167) (xy 241.524527 -348.103434) (xy 241.572068 -348.070499) (xy 241.624035 -348.045115)
			(xy 241.679237 -348.027863) (xy 241.73641 -348.01914) (xy 241.765328 -348.018608) (xy 241.792579 -348.019064)
			(xy 241.846526 -348.026824) (xy 241.89882 -348.042182) (xy 241.948395 -348.064826) (xy 241.994244 -348.094294)
			(xy 242.035433 -348.129987) (xy 242.071123 -348.171178) (xy 242.100588 -348.217029) (xy 242.123228 -348.266607)
			(xy 242.138582 -348.318901) (xy 242.146338 -348.372849) (xy 242.146338 -348.427351) (xy 242.138582 -348.481299)
			(xy 242.123228 -348.533593) (xy 242.100588 -348.583171) (xy 242.071123 -348.629022) (xy 242.035433 -348.670213)
			(xy 241.994244 -348.705906) (xy 241.948395 -348.735374) (xy 241.89882 -348.758018) (xy 241.846526 -348.773376)
			(xy 241.792579 -348.781136) (xy 241.765328 -348.781624) (xy 241.73641 -348.781115) (xy 241.679237 -348.772388)
			(xy 241.624037 -348.75513) (xy 241.572075 -348.729737) (xy 241.524541 -348.69679) (xy 241.482527 -348.657046)
			(xy 241.464338 -348.634558) (xy 241.456762 -348.625811) (xy 241.436014 -348.615621) (xy 241.42446 -348.615)
			(xy 241.344196 -348.615) (xy 241.332628 -348.615568) (xy 241.311857 -348.625764) (xy 241.304318 -348.634558)
			(xy 241.286106 -348.657024) (xy 241.244092 -348.696762) (xy 241.196562 -348.729705) (xy 241.144604 -348.755096)
			(xy 241.08941 -348.772356) (xy 241.032243 -348.781088) (xy 241.003328 -348.781624) (xy 240.976075 -348.781131)
			(xy 240.922123 -348.773377) (xy 240.869824 -348.758024) (xy 240.820243 -348.735384) (xy 240.774388 -348.705918)
			(xy 240.733194 -348.670226) (xy 240.697499 -348.629034) (xy 240.668029 -348.583182) (xy 240.645386 -348.533602)
			(xy 240.630029 -348.481304) (xy 240.622271 -348.427353) (xy 236.902555 -348.427353) (xy 236.905545 -348.447668)
			(xy 236.906054 -348.475554) (xy 236.905545 -348.50344) (xy 236.897425 -348.558616) (xy 236.881357 -348.612023)
			(xy 236.857685 -348.66252) (xy 236.826912 -348.709033) (xy 236.789695 -348.75057) (xy 236.746827 -348.786245)
			(xy 236.699221 -348.815299) (xy 236.647892 -348.837111) (xy 236.593935 -348.851217) (xy 236.538498 -348.857317)
			(xy 236.482764 -348.85528) (xy 236.427921 -348.84515) (xy 236.375137 -348.827143) (xy 236.325537 -348.801642)
			(xy 236.280179 -348.769191) (xy 236.24003 -348.730482) (xy 236.205944 -348.686339) (xy 236.178648 -348.637704)
			(xy 236.158725 -348.585613) (xy 236.146599 -348.531176) (xy 236.142528 -348.475554) (xy 194.50429 -348.475554)
			(xy 194.512804 -348.504551) (xy 194.520566 -348.558532) (xy 194.520566 -348.613068) (xy 194.512804 -348.667049)
			(xy 194.49744 -348.719376) (xy 194.474785 -348.768985) (xy 194.445301 -348.814864) (xy 194.409588 -348.85608)
			(xy 194.368373 -348.891794) (xy 194.322495 -348.92128) (xy 194.272888 -348.943936) (xy 194.220561 -348.959302)
			(xy 194.16658 -348.967065) (xy 194.139312 -348.967552) (xy 193.275712 -348.967552) (xy 193.24844 -348.967109)
			(xy 193.19445 -348.959348) (xy 193.142115 -348.943983) (xy 193.092499 -348.921325) (xy 193.046612 -348.891837)
			(xy 193.00539 -348.856119) (xy 192.96967 -348.814897) (xy 192.940181 -348.769012) (xy 192.917521 -348.719397)
			(xy 192.902154 -348.667062) (xy 192.894392 -348.613072) (xy 191.411688 -348.613072) (xy 191.403925 -348.667062)
			(xy 191.388557 -348.719397) (xy 191.365896 -348.769012) (xy 191.336405 -348.814897) (xy 191.300683 -348.856117)
			(xy 191.259459 -348.891834) (xy 191.21357 -348.921319) (xy 191.163952 -348.943974) (xy 191.111615 -348.959335)
			(xy 191.057625 -348.967092) (xy 191.030352 -348.967552) (xy 190.166752 -348.967552) (xy 190.139484 -348.967082)
			(xy 190.085504 -348.959315) (xy 190.033179 -348.943945) (xy 189.983574 -348.921285) (xy 189.937698 -348.891797)
			(xy 189.896485 -348.856081) (xy 189.860774 -348.814864) (xy 189.831292 -348.768984) (xy 189.808638 -348.719376)
			(xy 189.793275 -348.667049) (xy 189.785514 -348.613068) (xy 188.302689 -348.613068) (xy 188.302689 -348.613071)
			(xy 188.294926 -348.667057) (xy 188.27956 -348.719389) (xy 188.256903 -348.769001) (xy 188.227415 -348.814884)
			(xy 188.191698 -348.856103) (xy 188.150478 -348.89182) (xy 188.104594 -348.921306) (xy 188.054981 -348.943963)
			(xy 188.002649 -348.959328) (xy 187.948663 -348.967089) (xy 187.921392 -348.967552) (xy 187.057792 -348.967552)
			(xy 187.030522 -348.967085) (xy 186.976538 -348.959322) (xy 186.924208 -348.943956) (xy 186.874598 -348.921299)
			(xy 186.828717 -348.891812) (xy 186.787499 -348.856095) (xy 186.751784 -348.814877) (xy 186.722298 -348.768995)
			(xy 186.699641 -348.719384) (xy 186.684276 -348.667054) (xy 186.676514 -348.61307) (xy 185.193666 -348.61307)
			(xy 185.185905 -348.667047) (xy 185.170542 -348.719372) (xy 185.147888 -348.768979) (xy 185.118406 -348.814857)
			(xy 185.082695 -348.856073) (xy 185.041483 -348.891787) (xy 184.995607 -348.921273) (xy 184.946002 -348.943931)
			(xy 184.893678 -348.959298) (xy 184.839699 -348.967063) (xy 184.812432 -348.967552) (xy 183.948832 -348.967552)
			(xy 183.921559 -348.967111) (xy 183.867567 -348.959352) (xy 183.815229 -348.943988) (xy 183.765611 -348.921332)
			(xy 183.719722 -348.891844) (xy 183.678497 -348.856126) (xy 183.642775 -348.814904) (xy 183.613284 -348.769017)
			(xy 183.590623 -348.719401) (xy 183.575255 -348.667064) (xy 183.567492 -348.613073) (xy 182.084788 -348.613073)
			(xy 182.077026 -348.667059) (xy 182.061659 -348.719393) (xy 182.038999 -348.769007) (xy 182.00951 -348.814891)
			(xy 181.97379 -348.85611) (xy 181.932568 -348.891827) (xy 181.886682 -348.921313) (xy 181.837067 -348.943968)
			(xy 181.784732 -348.959332) (xy 181.730744 -348.96709) (xy 181.703472 -348.967552) (xy 180.839872 -348.967552)
			(xy 180.812603 -348.967084) (xy 180.758621 -348.959319) (xy 180.706294 -348.94395) (xy 180.656686 -348.921292)
			(xy 180.610807 -348.891805) (xy 180.569592 -348.856088) (xy 180.533879 -348.81487) (xy 180.504395 -348.76899)
			(xy 180.48174 -348.71938) (xy 180.466376 -348.667051) (xy 180.458614 -348.613069) (xy 178.975766 -348.613069)
			(xy 178.968004 -348.667049) (xy 178.95264 -348.719376) (xy 178.929985 -348.768985) (xy 178.900501 -348.814864)
			(xy 178.864788 -348.85608) (xy 178.823573 -348.891794) (xy 178.777695 -348.92128) (xy 178.728088 -348.943936)
			(xy 178.675761 -348.959302) (xy 178.62178 -348.967065) (xy 178.594512 -348.967552) (xy 177.730912 -348.967552)
			(xy 177.70364 -348.967109) (xy 177.64965 -348.959348) (xy 177.597315 -348.943983) (xy 177.547699 -348.921325)
			(xy 177.501812 -348.891837) (xy 177.46059 -348.856119) (xy 177.42487 -348.814897) (xy 177.395381 -348.769012)
			(xy 177.372721 -348.719397) (xy 177.357354 -348.667062) (xy 177.349592 -348.613072) (xy 175.866888 -348.613072)
			(xy 175.859125 -348.667062) (xy 175.843757 -348.719397) (xy 175.821096 -348.769012) (xy 175.791605 -348.814897)
			(xy 175.755883 -348.856117) (xy 175.714659 -348.891834) (xy 175.66877 -348.921319) (xy 175.619152 -348.943974)
			(xy 175.566815 -348.959335) (xy 175.512825 -348.967092) (xy 175.485552 -348.967552) (xy 174.621952 -348.967552)
			(xy 174.594684 -348.967082) (xy 174.540704 -348.959315) (xy 174.488379 -348.943945) (xy 174.438774 -348.921285)
			(xy 174.392898 -348.891797) (xy 174.351685 -348.856081) (xy 174.315974 -348.814864) (xy 174.286492 -348.768984)
			(xy 174.263838 -348.719376) (xy 174.248475 -348.667049) (xy 174.240714 -348.613068) (xy 172.757889 -348.613068)
			(xy 172.757889 -348.613071) (xy 172.750126 -348.667057) (xy 172.73476 -348.719389) (xy 172.712103 -348.769001)
			(xy 172.682615 -348.814884) (xy 172.646898 -348.856103) (xy 172.605678 -348.89182) (xy 172.559794 -348.921306)
			(xy 172.510181 -348.943963) (xy 172.457849 -348.959328) (xy 172.403863 -348.967089) (xy 172.376592 -348.967552)
			(xy 171.512992 -348.967552) (xy 171.485722 -348.967085) (xy 171.431738 -348.959322) (xy 171.379408 -348.943956)
			(xy 171.329798 -348.921299) (xy 171.283917 -348.891812) (xy 171.242699 -348.856095) (xy 171.206984 -348.814877)
			(xy 171.177498 -348.768995) (xy 171.154841 -348.719384) (xy 171.139476 -348.667054) (xy 171.131714 -348.61307)
			(xy 169.648866 -348.61307) (xy 169.641105 -348.667047) (xy 169.625742 -348.719372) (xy 169.603088 -348.768979)
			(xy 169.573606 -348.814857) (xy 169.537895 -348.856073) (xy 169.496683 -348.891787) (xy 169.450807 -348.921273)
			(xy 169.401202 -348.943931) (xy 169.348878 -348.959298) (xy 169.294899 -348.967063) (xy 169.267632 -348.967552)
			(xy 168.404032 -348.967552) (xy 168.376759 -348.967111) (xy 168.322767 -348.959352) (xy 168.270429 -348.943988)
			(xy 168.220811 -348.921332) (xy 168.174922 -348.891844) (xy 168.133697 -348.856126) (xy 168.097975 -348.814904)
			(xy 168.068484 -348.769017) (xy 168.045823 -348.719401) (xy 168.030455 -348.667064) (xy 168.022692 -348.613073)
			(xy 166.539988 -348.613073) (xy 166.532226 -348.667059) (xy 166.516859 -348.719393) (xy 166.494199 -348.769007)
			(xy 166.46471 -348.814891) (xy 166.42899 -348.85611) (xy 166.387768 -348.891827) (xy 166.341882 -348.921313)
			(xy 166.292267 -348.943968) (xy 166.239932 -348.959332) (xy 166.185944 -348.96709) (xy 166.158672 -348.967552)
			(xy 165.295072 -348.967552) (xy 165.267803 -348.967084) (xy 165.213821 -348.959319) (xy 165.161494 -348.94395)
			(xy 165.111886 -348.921292) (xy 165.066007 -348.891805) (xy 165.024792 -348.856088) (xy 164.989079 -348.81487)
			(xy 164.959595 -348.76899) (xy 164.93694 -348.71938) (xy 164.921576 -348.667051) (xy 164.913814 -348.613069)
			(xy 163.430966 -348.613069) (xy 163.423204 -348.667049) (xy 163.40784 -348.719376) (xy 163.385185 -348.768985)
			(xy 163.355701 -348.814864) (xy 163.319988 -348.85608) (xy 163.278773 -348.891794) (xy 163.232895 -348.92128)
			(xy 163.183288 -348.943936) (xy 163.130961 -348.959302) (xy 163.07698 -348.967065) (xy 163.049712 -348.967552)
			(xy 162.186112 -348.967552) (xy 162.15884 -348.967109) (xy 162.10485 -348.959348) (xy 162.052515 -348.943983)
			(xy 162.002899 -348.921325) (xy 161.957012 -348.891837) (xy 161.91579 -348.856119) (xy 161.88007 -348.814897)
			(xy 161.850581 -348.769012) (xy 161.827921 -348.719397) (xy 161.812554 -348.667062) (xy 161.804792 -348.613072)
			(xy 152.074463 -348.613072) (xy 150.992184 -349.302832) (xy 204.379574 -349.302832) (xy 204.383645 -349.24721)
			(xy 204.395771 -349.192773) (xy 204.415694 -349.140682) (xy 204.44299 -349.092047) (xy 204.477076 -349.047904)
			(xy 204.517225 -349.009195) (xy 204.562583 -348.976744) (xy 204.612183 -348.951243) (xy 204.664967 -348.933236)
			(xy 204.71981 -348.923106) (xy 204.775544 -348.921069) (xy 204.830981 -348.927169) (xy 204.884938 -348.941275)
			(xy 204.936267 -348.963087) (xy 204.983873 -348.992141) (xy 205.026741 -349.027816) (xy 205.063958 -349.069353)
			(xy 205.094731 -349.115866) (xy 205.118403 -349.166363) (xy 205.134471 -349.21977) (xy 205.134584 -349.220536)
			(xy 205.395574 -349.220536) (xy 205.399645 -349.164914) (xy 205.411771 -349.110477) (xy 205.431694 -349.058386)
			(xy 205.45899 -349.009751) (xy 205.493076 -348.965608) (xy 205.533225 -348.926899) (xy 205.578583 -348.894448)
			(xy 205.628183 -348.868947) (xy 205.680967 -348.85094) (xy 205.73581 -348.84081) (xy 205.791544 -348.838773)
			(xy 205.846981 -348.844873) (xy 205.900938 -348.858979) (xy 205.952267 -348.880791) (xy 205.983722 -348.899988)
			(xy 248.580146 -348.899988) (xy 248.584217 -348.844366) (xy 248.596343 -348.789929) (xy 248.616266 -348.737838)
			(xy 248.643562 -348.689203) (xy 248.677648 -348.64506) (xy 248.717797 -348.606351) (xy 248.763155 -348.5739)
			(xy 248.812755 -348.548399) (xy 248.865539 -348.530392) (xy 248.920382 -348.520262) (xy 248.976116 -348.518225)
			(xy 249.031553 -348.524325) (xy 249.08551 -348.538431) (xy 249.136839 -348.560243) (xy 249.184445 -348.589297)
			(xy 249.227313 -348.624972) (xy 249.26453 -348.666509) (xy 249.295303 -348.713022) (xy 249.318975 -348.763519)
			(xy 249.335043 -348.816926) (xy 249.338968 -348.8436) (xy 253.262382 -348.8436) (xy 253.266453 -348.787978)
			(xy 253.278579 -348.733541) (xy 253.298502 -348.68145) (xy 253.325798 -348.632815) (xy 253.359884 -348.588672)
			(xy 253.400033 -348.549963) (xy 253.445391 -348.517512) (xy 253.494991 -348.492011) (xy 253.547775 -348.474004)
			(xy 253.602618 -348.463874) (xy 253.658352 -348.461837) (xy 253.713789 -348.467937) (xy 253.767746 -348.482043)
			(xy 253.819075 -348.503855) (xy 253.866681 -348.532909) (xy 253.909549 -348.568584) (xy 253.946766 -348.610121)
			(xy 253.948718 -348.613072) (xy 267.515792 -348.613072) (xy 267.515792 -348.558528) (xy 267.523554 -348.50454)
			(xy 267.538921 -348.452206) (xy 267.561579 -348.402591) (xy 267.591068 -348.356706) (xy 267.626786 -348.315485)
			(xy 267.668008 -348.279766) (xy 267.713893 -348.250278) (xy 267.763507 -348.22762) (xy 267.815842 -348.212253)
			(xy 267.86983 -348.204491) (xy 267.897102 -348.204028) (xy 268.760702 -348.204028) (xy 268.787971 -348.204535)
			(xy 268.841953 -348.212296) (xy 268.89428 -348.227661) (xy 268.943889 -348.250317) (xy 268.989769 -348.279802)
			(xy 269.030985 -348.315517) (xy 269.066699 -348.356733) (xy 269.096184 -348.402613) (xy 269.118839 -348.452221)
			(xy 269.134204 -348.504549) (xy 269.141966 -348.558531) (xy 269.141966 -348.613068) (xy 270.624814 -348.613068)
			(xy 270.624814 -348.558532) (xy 270.632575 -348.50455) (xy 270.647939 -348.452222) (xy 270.670593 -348.402613)
			(xy 270.700076 -348.356733) (xy 270.735788 -348.315515) (xy 270.777002 -348.279799) (xy 270.82288 -348.250311)
			(xy 270.872486 -348.227652) (xy 270.924813 -348.212283) (xy 270.978794 -348.204517) (xy 271.006062 -348.204028)
			(xy 271.869662 -348.204028) (xy 271.896934 -348.204509) (xy 271.950924 -348.212266) (xy 272.00326 -348.227629)
			(xy 272.052876 -348.250284) (xy 272.098763 -348.27977) (xy 272.139987 -348.315486) (xy 272.175708 -348.356706)
			(xy 272.205198 -348.40259) (xy 272.227858 -348.452205) (xy 272.243226 -348.504539) (xy 272.250988 -348.558528)
			(xy 272.250988 -348.613072) (xy 272.250988 -348.613073) (xy 273.733692 -348.613073) (xy 273.733692 -348.558527)
			(xy 273.741454 -348.504537) (xy 273.756822 -348.452201) (xy 273.779482 -348.402585) (xy 273.808972 -348.356699)
			(xy 273.844693 -348.315478) (xy 273.885917 -348.279759) (xy 273.931805 -348.250271) (xy 273.981422 -348.227615)
			(xy 274.033759 -348.21225) (xy 274.087749 -348.20449) (xy 274.115022 -348.204028) (xy 274.978622 -348.204028)
			(xy 275.00589 -348.204536) (xy 275.059869 -348.2123) (xy 275.112195 -348.227667) (xy 275.161801 -348.250324)
			(xy 275.207678 -348.279809) (xy 275.248892 -348.315524) (xy 275.284604 -348.35674) (xy 275.314087 -348.402618)
			(xy 275.336741 -348.452226) (xy 275.352105 -348.504552) (xy 275.359866 -348.558532) (xy 275.359866 -348.613068)
			(xy 275.359866 -348.613069) (xy 276.842714 -348.613069) (xy 276.842714 -348.558531) (xy 276.850476 -348.504547)
			(xy 276.865841 -348.452218) (xy 276.888496 -348.402608) (xy 276.917981 -348.356726) (xy 276.953695 -348.315508)
			(xy 276.994912 -348.279792) (xy 277.040792 -348.250305) (xy 277.090401 -348.227647) (xy 277.14273 -348.21228)
			(xy 277.196713 -348.204516) (xy 277.223982 -348.204028) (xy 278.087582 -348.204028) (xy 278.114853 -348.20451)
			(xy 278.168841 -348.21227) (xy 278.221174 -348.227634) (xy 278.270788 -348.25029) (xy 278.316673 -348.279777)
			(xy 278.357894 -348.315493) (xy 278.393612 -348.356713) (xy 278.423101 -348.402596) (xy 278.445759 -348.452209)
			(xy 278.461126 -348.504542) (xy 278.468888 -348.558529) (xy 278.468888 -348.613071) (xy 278.468888 -348.613074)
			(xy 279.951592 -348.613074) (xy 279.951592 -348.558526) (xy 279.959355 -348.504534) (xy 279.974724 -348.452197)
			(xy 279.997385 -348.40258) (xy 280.026877 -348.356693) (xy 280.0626 -348.315471) (xy 280.103827 -348.279752)
			(xy 280.149717 -348.250265) (xy 280.199336 -348.227609) (xy 280.251676 -348.212246) (xy 280.305668 -348.204489)
			(xy 280.332942 -348.204028) (xy 281.196542 -348.204028) (xy 281.223809 -348.204537) (xy 281.277786 -348.212304)
			(xy 281.330109 -348.227672) (xy 281.379713 -348.25033) (xy 281.425587 -348.279816) (xy 281.466799 -348.315531)
			(xy 281.502509 -348.356746) (xy 281.53199 -348.402624) (xy 281.554643 -348.45223) (xy 281.570005 -348.504555)
			(xy 281.577766 -348.558533) (xy 281.577766 -348.613067) (xy 281.577765 -348.613072) (xy 283.060592 -348.613072)
			(xy 283.060592 -348.558528) (xy 283.068354 -348.50454) (xy 283.083721 -348.452206) (xy 283.106379 -348.402591)
			(xy 283.135868 -348.356706) (xy 283.171586 -348.315485) (xy 283.212808 -348.279766) (xy 283.258693 -348.250278)
			(xy 283.308307 -348.22762) (xy 283.360642 -348.212253) (xy 283.41463 -348.204491) (xy 283.441902 -348.204028)
			(xy 284.305502 -348.204028) (xy 284.332771 -348.204535) (xy 284.386753 -348.212296) (xy 284.43908 -348.227661)
			(xy 284.488689 -348.250317) (xy 284.534569 -348.279802) (xy 284.575785 -348.315517) (xy 284.611499 -348.356733)
			(xy 284.640984 -348.402613) (xy 284.663639 -348.452221) (xy 284.679004 -348.504549) (xy 284.686766 -348.558531)
			(xy 284.686766 -348.613068) (xy 286.169614 -348.613068) (xy 286.169614 -348.558532) (xy 286.177375 -348.50455)
			(xy 286.192739 -348.452222) (xy 286.215393 -348.402613) (xy 286.244876 -348.356733) (xy 286.280588 -348.315515)
			(xy 286.321802 -348.279799) (xy 286.36768 -348.250311) (xy 286.417286 -348.227652) (xy 286.469613 -348.212283)
			(xy 286.523594 -348.204517) (xy 286.550862 -348.204028) (xy 287.414462 -348.204028) (xy 287.441734 -348.204509)
			(xy 287.495724 -348.212266) (xy 287.54806 -348.227629) (xy 287.597676 -348.250284) (xy 287.643563 -348.27977)
			(xy 287.684787 -348.315486) (xy 287.720508 -348.356706) (xy 287.749998 -348.40259) (xy 287.772658 -348.452205)
			(xy 287.788026 -348.504539) (xy 287.795788 -348.558528) (xy 287.795788 -348.613072) (xy 287.795788 -348.613073)
			(xy 289.278492 -348.613073) (xy 289.278492 -348.558527) (xy 289.286254 -348.504537) (xy 289.301622 -348.452201)
			(xy 289.324282 -348.402585) (xy 289.353772 -348.356699) (xy 289.389493 -348.315478) (xy 289.430717 -348.279759)
			(xy 289.476605 -348.250271) (xy 289.526222 -348.227615) (xy 289.578559 -348.21225) (xy 289.632549 -348.20449)
			(xy 289.659822 -348.204028) (xy 290.523422 -348.204028) (xy 290.55069 -348.204536) (xy 290.604669 -348.2123)
			(xy 290.656995 -348.227667) (xy 290.706601 -348.250324) (xy 290.752478 -348.279809) (xy 290.793692 -348.315524)
			(xy 290.829404 -348.35674) (xy 290.858887 -348.402618) (xy 290.881541 -348.452226) (xy 290.896905 -348.504552)
			(xy 290.904666 -348.558532) (xy 290.904666 -348.613068) (xy 290.904666 -348.613069) (xy 292.387514 -348.613069)
			(xy 292.387514 -348.558531) (xy 292.395276 -348.504547) (xy 292.410641 -348.452218) (xy 292.433296 -348.402608)
			(xy 292.462781 -348.356726) (xy 292.498495 -348.315508) (xy 292.539712 -348.279792) (xy 292.585592 -348.250305)
			(xy 292.635201 -348.227647) (xy 292.68753 -348.21228) (xy 292.741513 -348.204516) (xy 292.768782 -348.204028)
			(xy 293.632382 -348.204028) (xy 293.659653 -348.20451) (xy 293.713641 -348.21227) (xy 293.765974 -348.227634)
			(xy 293.815588 -348.25029) (xy 293.861473 -348.279777) (xy 293.902694 -348.315493) (xy 293.938412 -348.356713)
			(xy 293.967901 -348.402596) (xy 293.990559 -348.452209) (xy 294.005926 -348.504542) (xy 294.013688 -348.558529)
			(xy 294.013688 -348.613071) (xy 294.013688 -348.613074) (xy 295.496392 -348.613074) (xy 295.496392 -348.558526)
			(xy 295.504155 -348.504534) (xy 295.519524 -348.452197) (xy 295.542185 -348.40258) (xy 295.571677 -348.356693)
			(xy 295.6074 -348.315471) (xy 295.648627 -348.279752) (xy 295.694517 -348.250265) (xy 295.744136 -348.227609)
			(xy 295.796476 -348.212246) (xy 295.850468 -348.204489) (xy 295.877742 -348.204028) (xy 296.741342 -348.204028)
			(xy 296.768609 -348.204537) (xy 296.822586 -348.212304) (xy 296.874909 -348.227672) (xy 296.924513 -348.25033)
			(xy 296.970387 -348.279816) (xy 297.011599 -348.315531) (xy 297.047309 -348.356746) (xy 297.07679 -348.402624)
			(xy 297.099443 -348.45223) (xy 297.114805 -348.504555) (xy 297.122566 -348.558533) (xy 297.122566 -348.613067)
			(xy 297.122565 -348.613072) (xy 298.605392 -348.613072) (xy 298.605392 -348.558528) (xy 298.613154 -348.50454)
			(xy 298.628521 -348.452206) (xy 298.651179 -348.402591) (xy 298.680668 -348.356706) (xy 298.716386 -348.315485)
			(xy 298.757608 -348.279766) (xy 298.803493 -348.250278) (xy 298.853107 -348.22762) (xy 298.905442 -348.212253)
			(xy 298.95943 -348.204491) (xy 298.986702 -348.204028) (xy 299.850302 -348.204028) (xy 299.877571 -348.204535)
			(xy 299.931553 -348.212296) (xy 299.98388 -348.227661) (xy 300.033489 -348.250317) (xy 300.079369 -348.279802)
			(xy 300.120585 -348.315517) (xy 300.156299 -348.356733) (xy 300.185784 -348.402613) (xy 300.208439 -348.452221)
			(xy 300.223804 -348.504549) (xy 300.231566 -348.558531) (xy 300.231566 -348.613069) (xy 300.223804 -348.667051)
			(xy 300.208439 -348.719379) (xy 300.185784 -348.768987) (xy 300.156299 -348.814867) (xy 300.120585 -348.856083)
			(xy 300.079369 -348.891798) (xy 300.033489 -348.921283) (xy 299.98388 -348.943939) (xy 299.931553 -348.959304)
			(xy 299.877571 -348.967065) (xy 299.850302 -348.967552) (xy 298.986702 -348.967552) (xy 298.95943 -348.967109)
			(xy 298.905442 -348.959347) (xy 298.853107 -348.94398) (xy 298.803493 -348.921322) (xy 298.757608 -348.891834)
			(xy 298.716386 -348.856115) (xy 298.680668 -348.814894) (xy 298.651179 -348.769009) (xy 298.628521 -348.719394)
			(xy 298.613154 -348.66706) (xy 298.605392 -348.613072) (xy 297.122565 -348.613072) (xy 297.114805 -348.667045)
			(xy 297.099443 -348.71937) (xy 297.07679 -348.768976) (xy 297.047309 -348.814854) (xy 297.011599 -348.856069)
			(xy 296.970387 -348.891784) (xy 296.924513 -348.92127) (xy 296.874909 -348.943928) (xy 296.822586 -348.959296)
			(xy 296.768609 -348.967063) (xy 296.741342 -348.967552) (xy 295.877742 -348.967552) (xy 295.850468 -348.967111)
			(xy 295.796476 -348.959354) (xy 295.744136 -348.943991) (xy 295.694517 -348.921335) (xy 295.648627 -348.891848)
			(xy 295.6074 -348.856129) (xy 295.571677 -348.814907) (xy 295.542185 -348.76902) (xy 295.519524 -348.719403)
			(xy 295.504155 -348.667066) (xy 295.496392 -348.613074) (xy 294.013688 -348.613074) (xy 294.005926 -348.667058)
			(xy 293.990559 -348.719391) (xy 293.967901 -348.769004) (xy 293.938412 -348.814887) (xy 293.902694 -348.856107)
			(xy 293.861473 -348.891823) (xy 293.815588 -348.92131) (xy 293.765974 -348.943966) (xy 293.713641 -348.95933)
			(xy 293.659653 -348.96709) (xy 293.632382 -348.967552) (xy 292.768782 -348.967552) (xy 292.741513 -348.967084)
			(xy 292.68753 -348.95932) (xy 292.635201 -348.943953) (xy 292.585592 -348.921295) (xy 292.539712 -348.891808)
			(xy 292.498495 -348.856092) (xy 292.462781 -348.814874) (xy 292.433296 -348.768992) (xy 292.410641 -348.719382)
			(xy 292.395276 -348.667053) (xy 292.387514 -348.613069) (xy 290.904666 -348.613069) (xy 290.896905 -348.667048)
			(xy 290.881541 -348.719374) (xy 290.858887 -348.768982) (xy 290.829404 -348.81486) (xy 290.793692 -348.856076)
			(xy 290.752478 -348.891791) (xy 290.706601 -348.921276) (xy 290.656995 -348.943933) (xy 290.604669 -348.9593)
			(xy 290.55069 -348.967064) (xy 290.523422 -348.967552) (xy 289.659822 -348.967552) (xy 289.632549 -348.96711)
			(xy 289.578559 -348.95935) (xy 289.526222 -348.943985) (xy 289.476605 -348.921329) (xy 289.430717 -348.891841)
			(xy 289.389493 -348.856122) (xy 289.353772 -348.814901) (xy 289.324282 -348.769015) (xy 289.301622 -348.719399)
			(xy 289.286254 -348.667063) (xy 289.278492 -348.613073) (xy 287.795788 -348.613073) (xy 287.788026 -348.667061)
			(xy 287.772658 -348.719395) (xy 287.749998 -348.76901) (xy 287.720508 -348.814894) (xy 287.684787 -348.856114)
			(xy 287.643563 -348.89183) (xy 287.597676 -348.921316) (xy 287.54806 -348.943971) (xy 287.495724 -348.959334)
			(xy 287.441734 -348.967091) (xy 287.414462 -348.967552) (xy 286.550862 -348.967552) (xy 286.523594 -348.967083)
			(xy 286.469613 -348.959317) (xy 286.417286 -348.943948) (xy 286.36768 -348.921289) (xy 286.321802 -348.891801)
			(xy 286.280588 -348.856085) (xy 286.244876 -348.814867) (xy 286.215393 -348.768987) (xy 286.192739 -348.719378)
			(xy 286.177375 -348.66705) (xy 286.169614 -348.613068) (xy 284.686766 -348.613068) (xy 284.686766 -348.613069)
			(xy 284.679004 -348.667051) (xy 284.663639 -348.719379) (xy 284.640984 -348.768987) (xy 284.611499 -348.814867)
			(xy 284.575785 -348.856083) (xy 284.534569 -348.891798) (xy 284.488689 -348.921283) (xy 284.43908 -348.943939)
			(xy 284.386753 -348.959304) (xy 284.332771 -348.967065) (xy 284.305502 -348.967552) (xy 283.441902 -348.967552)
			(xy 283.41463 -348.967109) (xy 283.360642 -348.959347) (xy 283.308307 -348.94398) (xy 283.258693 -348.921322)
			(xy 283.212808 -348.891834) (xy 283.171586 -348.856115) (xy 283.135868 -348.814894) (xy 283.106379 -348.769009)
			(xy 283.083721 -348.719394) (xy 283.068354 -348.66706) (xy 283.060592 -348.613072) (xy 281.577765 -348.613072)
			(xy 281.570005 -348.667045) (xy 281.554643 -348.71937) (xy 281.53199 -348.768976) (xy 281.502509 -348.814854)
			(xy 281.466799 -348.856069) (xy 281.425587 -348.891784) (xy 281.379713 -348.92127) (xy 281.330109 -348.943928)
			(xy 281.277786 -348.959296) (xy 281.223809 -348.967063) (xy 281.196542 -348.967552) (xy 280.332942 -348.967552)
			(xy 280.305668 -348.967111) (xy 280.251676 -348.959354) (xy 280.199336 -348.943991) (xy 280.149717 -348.921335)
			(xy 280.103827 -348.891848) (xy 280.0626 -348.856129) (xy 280.026877 -348.814907) (xy 279.997385 -348.76902)
			(xy 279.974724 -348.719403) (xy 279.959355 -348.667066) (xy 279.951592 -348.613074) (xy 278.468888 -348.613074)
			(xy 278.461126 -348.667058) (xy 278.445759 -348.719391) (xy 278.423101 -348.769004) (xy 278.393612 -348.814887)
			(xy 278.357894 -348.856107) (xy 278.316673 -348.891823) (xy 278.270788 -348.92131) (xy 278.221174 -348.943966)
			(xy 278.168841 -348.95933) (xy 278.114853 -348.96709) (xy 278.087582 -348.967552) (xy 277.223982 -348.967552)
			(xy 277.196713 -348.967084) (xy 277.14273 -348.95932) (xy 277.090401 -348.943953) (xy 277.040792 -348.921295)
			(xy 276.994912 -348.891808) (xy 276.953695 -348.856092) (xy 276.917981 -348.814874) (xy 276.888496 -348.768992)
			(xy 276.865841 -348.719382) (xy 276.850476 -348.667053) (xy 276.842714 -348.613069) (xy 275.359866 -348.613069)
			(xy 275.352105 -348.667048) (xy 275.336741 -348.719374) (xy 275.314087 -348.768982) (xy 275.284604 -348.81486)
			(xy 275.248892 -348.856076) (xy 275.207678 -348.891791) (xy 275.161801 -348.921276) (xy 275.112195 -348.943933)
			(xy 275.059869 -348.9593) (xy 275.00589 -348.967064) (xy 274.978622 -348.967552) (xy 274.115022 -348.967552)
			(xy 274.087749 -348.96711) (xy 274.033759 -348.95935) (xy 273.981422 -348.943985) (xy 273.931805 -348.921329)
			(xy 273.885917 -348.891841) (xy 273.844693 -348.856122) (xy 273.808972 -348.814901) (xy 273.779482 -348.769015)
			(xy 273.756822 -348.719399) (xy 273.741454 -348.667063) (xy 273.733692 -348.613073) (xy 272.250988 -348.613073)
			(xy 272.243226 -348.667061) (xy 272.227858 -348.719395) (xy 272.205198 -348.76901) (xy 272.175708 -348.814894)
			(xy 272.139987 -348.856114) (xy 272.098763 -348.89183) (xy 272.052876 -348.921316) (xy 272.00326 -348.943971)
			(xy 271.950924 -348.959334) (xy 271.896934 -348.967091) (xy 271.869662 -348.967552) (xy 271.006062 -348.967552)
			(xy 270.978794 -348.967083) (xy 270.924813 -348.959317) (xy 270.872486 -348.943948) (xy 270.82288 -348.921289)
			(xy 270.777002 -348.891801) (xy 270.735788 -348.856085) (xy 270.700076 -348.814867) (xy 270.670593 -348.768987)
			(xy 270.647939 -348.719378) (xy 270.632575 -348.66705) (xy 270.624814 -348.613068) (xy 269.141966 -348.613068)
			(xy 269.141966 -348.613069) (xy 269.134204 -348.667051) (xy 269.118839 -348.719379) (xy 269.096184 -348.768987)
			(xy 269.066699 -348.814867) (xy 269.030985 -348.856083) (xy 268.989769 -348.891798) (xy 268.943889 -348.921283)
			(xy 268.89428 -348.943939) (xy 268.841953 -348.959304) (xy 268.787971 -348.967065) (xy 268.760702 -348.967552)
			(xy 267.897102 -348.967552) (xy 267.86983 -348.967109) (xy 267.815842 -348.959347) (xy 267.763507 -348.94398)
			(xy 267.713893 -348.921322) (xy 267.668008 -348.891834) (xy 267.626786 -348.856115) (xy 267.591068 -348.814894)
			(xy 267.561579 -348.769009) (xy 267.538921 -348.719394) (xy 267.523554 -348.66706) (xy 267.515792 -348.613072)
			(xy 253.948718 -348.613072) (xy 253.977539 -348.656634) (xy 254.001211 -348.707131) (xy 254.017279 -348.760538)
			(xy 254.025399 -348.815714) (xy 254.025908 -348.8436) (xy 254.025399 -348.871486) (xy 254.017279 -348.926662)
			(xy 254.001211 -348.980069) (xy 253.977539 -349.030566) (xy 253.946766 -349.077079) (xy 253.909549 -349.118616)
			(xy 253.866681 -349.154291) (xy 253.819075 -349.183345) (xy 253.767746 -349.205157) (xy 253.713789 -349.219263)
			(xy 253.658352 -349.225363) (xy 253.602618 -349.223326) (xy 253.547775 -349.213196) (xy 253.494991 -349.195189)
			(xy 253.445391 -349.169688) (xy 253.400033 -349.137237) (xy 253.359884 -349.098528) (xy 253.325798 -349.054385)
			(xy 253.298502 -349.00575) (xy 253.278579 -348.953659) (xy 253.266453 -348.899222) (xy 253.262382 -348.8436)
			(xy 249.338968 -348.8436) (xy 249.343163 -348.872102) (xy 249.343672 -348.899988) (xy 249.343163 -348.927874)
			(xy 249.335043 -348.98305) (xy 249.318975 -349.036457) (xy 249.295303 -349.086954) (xy 249.26453 -349.133467)
			(xy 249.227313 -349.175004) (xy 249.184445 -349.210679) (xy 249.136839 -349.239733) (xy 249.08551 -349.261545)
			(xy 249.031553 -349.275651) (xy 248.976116 -349.281751) (xy 248.920382 -349.279714) (xy 248.865539 -349.269584)
			(xy 248.812755 -349.251577) (xy 248.763155 -349.226076) (xy 248.717797 -349.193625) (xy 248.677648 -349.154916)
			(xy 248.643562 -349.110773) (xy 248.616266 -349.062138) (xy 248.596343 -349.010047) (xy 248.584217 -348.95561)
			(xy 248.580146 -348.899988) (xy 205.983722 -348.899988) (xy 205.999873 -348.909845) (xy 206.042741 -348.94552)
			(xy 206.079958 -348.987057) (xy 206.110731 -349.03357) (xy 206.134403 -349.084067) (xy 206.150471 -349.137474)
			(xy 206.158591 -349.19265) (xy 206.1591 -349.220536) (xy 206.158591 -349.248422) (xy 206.150471 -349.303598)
			(xy 206.134403 -349.357005) (xy 206.110731 -349.407502) (xy 206.079958 -349.454015) (xy 206.062937 -349.473012)
			(xy 236.12678 -349.473012) (xy 236.130851 -349.41739) (xy 236.142977 -349.362953) (xy 236.1629 -349.310862)
			(xy 236.190196 -349.262227) (xy 236.224282 -349.218084) (xy 236.264431 -349.179375) (xy 236.309789 -349.146924)
			(xy 236.359389 -349.121423) (xy 236.412173 -349.103416) (xy 236.467016 -349.093286) (xy 236.52275 -349.091249)
			(xy 236.578187 -349.097349) (xy 236.632144 -349.111455) (xy 236.683473 -349.133267) (xy 236.731079 -349.162321)
			(xy 236.773947 -349.197996) (xy 236.811164 -349.239533) (xy 236.841937 -349.286046) (xy 236.865609 -349.336543)
			(xy 236.881677 -349.38995) (xy 236.887181 -349.42735) (xy 240.762792 -349.42735) (xy 240.762792 -349.37285)
			(xy 240.770548 -349.318905) (xy 240.785902 -349.266613) (xy 240.808542 -349.217039) (xy 240.838006 -349.171191)
			(xy 240.873695 -349.130002) (xy 240.914883 -349.094312) (xy 240.96073 -349.064847) (xy 241.010304 -349.042206)
			(xy 241.062596 -349.02685) (xy 241.11654 -349.019093) (xy 241.14379 -349.018606) (xy 241.172707 -349.019129)
			(xy 241.229878 -349.027857) (xy 241.285077 -349.045114) (xy 241.337038 -349.070505) (xy 241.384572 -349.103447)
			(xy 241.42659 -349.143187) (xy 241.44478 -349.165672) (xy 241.452343 -349.174432) (xy 241.473101 -349.184614)
			(xy 241.484658 -349.18523) (xy 241.564922 -349.18523) (xy 241.576488 -349.184639) (xy 241.597261 -349.174462)
			(xy 241.6048 -349.165672) (xy 241.622984 -349.143183) (xy 241.665006 -349.103449) (xy 241.712543 -349.070512)
			(xy 241.764505 -349.045125) (xy 241.819704 -349.027869) (xy 241.876874 -349.019141) (xy 241.90579 -349.018606)
			(xy 241.933044 -349.01904) (xy 241.986998 -349.026796) (xy 242.039299 -349.042152) (xy 242.088883 -349.064795)
			(xy 242.134739 -349.094264) (xy 242.175934 -349.129959) (xy 242.21163 -349.171153) (xy 242.2411 -349.217009)
			(xy 242.263744 -349.266591) (xy 242.279102 -349.318892) (xy 242.286859 -349.372846) (xy 242.286859 -349.427354)
			(xy 242.279102 -349.481308) (xy 242.263744 -349.533609) (xy 242.2411 -349.583191) (xy 242.21163 -349.629047)
			(xy 242.175934 -349.670241) (xy 242.134739 -349.705936) (xy 242.088883 -349.735405) (xy 242.039299 -349.758048)
			(xy 241.986998 -349.773404) (xy 241.933044 -349.78116) (xy 241.90579 -349.781622) (xy 241.876874 -349.781069)
			(xy 241.819703 -349.772351) (xy 241.764504 -349.755102) (xy 241.712541 -349.729717) (xy 241.665007 -349.696778)
			(xy 241.62299 -349.65704) (xy 241.6048 -349.634556) (xy 241.597241 -349.625791) (xy 241.57648 -349.615611)
			(xy 241.564922 -349.614998) (xy 241.484658 -349.614998) (xy 241.473095 -349.615603) (xy 241.452323 -349.625773)
			(xy 241.44478 -349.634556) (xy 241.426589 -349.65704) (xy 241.384571 -349.696777) (xy 241.337036 -349.729717)
			(xy 241.285075 -349.755106) (xy 241.229876 -349.772362) (xy 241.172706 -349.781088) (xy 241.14379 -349.781622)
			(xy 241.11654 -349.781107) (xy 241.062596 -349.77335) (xy 241.010304 -349.757994) (xy 240.96073 -349.735353)
			(xy 240.914883 -349.705888) (xy 240.873695 -349.670198) (xy 240.838006 -349.629009) (xy 240.808542 -349.583161)
			(xy 240.785902 -349.533587) (xy 240.770548 -349.481295) (xy 240.762792 -349.42735) (xy 236.887181 -349.42735)
			(xy 236.889797 -349.445126) (xy 236.890306 -349.473012) (xy 236.889797 -349.500898) (xy 236.881677 -349.556074)
			(xy 236.865609 -349.609481) (xy 236.841937 -349.659978) (xy 236.811164 -349.706491) (xy 236.773947 -349.748028)
			(xy 236.731079 -349.783703) (xy 236.683473 -349.812757) (xy 236.632144 -349.834569) (xy 236.578187 -349.848675)
			(xy 236.52275 -349.854775) (xy 236.467016 -349.852738) (xy 236.412173 -349.842608) (xy 236.359389 -349.824601)
			(xy 236.309789 -349.7991) (xy 236.264431 -349.766649) (xy 236.224282 -349.72794) (xy 236.190196 -349.683797)
			(xy 236.1629 -349.635162) (xy 236.142977 -349.583071) (xy 236.130851 -349.528634) (xy 236.12678 -349.473012)
			(xy 206.062937 -349.473012) (xy 206.042741 -349.495552) (xy 205.999873 -349.531227) (xy 205.952267 -349.560281)
			(xy 205.900938 -349.582093) (xy 205.846981 -349.596199) (xy 205.791544 -349.602299) (xy 205.73581 -349.600262)
			(xy 205.680967 -349.590132) (xy 205.628183 -349.572125) (xy 205.578583 -349.546624) (xy 205.533225 -349.514173)
			(xy 205.493076 -349.475464) (xy 205.45899 -349.431321) (xy 205.431694 -349.382686) (xy 205.411771 -349.330595)
			(xy 205.399645 -349.276158) (xy 205.395574 -349.220536) (xy 205.134584 -349.220536) (xy 205.142591 -349.274946)
			(xy 205.1431 -349.302832) (xy 205.142591 -349.330718) (xy 205.134471 -349.385894) (xy 205.118403 -349.439301)
			(xy 205.094731 -349.489798) (xy 205.063958 -349.536311) (xy 205.026741 -349.577848) (xy 204.983873 -349.613523)
			(xy 204.936267 -349.642577) (xy 204.884938 -349.664389) (xy 204.830981 -349.678495) (xy 204.775544 -349.684595)
			(xy 204.71981 -349.682558) (xy 204.664967 -349.672428) (xy 204.612183 -349.654421) (xy 204.562583 -349.62892)
			(xy 204.517225 -349.596469) (xy 204.477076 -349.55776) (xy 204.44299 -349.513617) (xy 204.415694 -349.464982)
			(xy 204.395771 -349.412891) (xy 204.383645 -349.358454) (xy 204.379574 -349.302832) (xy 150.992184 -349.302832)
			(xy 150.05521 -349.899986) (xy 248.589544 -349.899986) (xy 248.593615 -349.844364) (xy 248.605741 -349.789927)
			(xy 248.625664 -349.737836) (xy 248.65296 -349.689201) (xy 248.687046 -349.645058) (xy 248.727195 -349.606349)
			(xy 248.772553 -349.573898) (xy 248.822153 -349.548397) (xy 248.874937 -349.53039) (xy 248.92978 -349.52026)
			(xy 248.985514 -349.518223) (xy 249.040951 -349.524323) (xy 249.094908 -349.538429) (xy 249.146237 -349.560241)
			(xy 249.193843 -349.589295) (xy 249.236711 -349.62497) (xy 249.273928 -349.666507) (xy 249.304701 -349.71302)
			(xy 249.328373 -349.763517) (xy 249.344441 -349.816924) (xy 249.350721 -349.8596) (xy 253.435864 -349.8596)
			(xy 253.439935 -349.803978) (xy 253.452061 -349.749541) (xy 253.471984 -349.69745) (xy 253.49928 -349.648815)
			(xy 253.533366 -349.604672) (xy 253.573515 -349.565963) (xy 253.618873 -349.533512) (xy 253.668473 -349.508011)
			(xy 253.721257 -349.490004) (xy 253.7761 -349.479874) (xy 253.831834 -349.477837) (xy 253.887271 -349.483937)
			(xy 253.941228 -349.498043) (xy 253.992557 -349.519855) (xy 254.040163 -349.548909) (xy 254.083031 -349.584584)
			(xy 254.120248 -349.626121) (xy 254.151021 -349.672634) (xy 254.174693 -349.723131) (xy 254.189845 -349.773494)
			(xy 258.543296 -349.773494) (xy 258.547367 -349.717872) (xy 258.559493 -349.663435) (xy 258.579416 -349.611344)
			(xy 258.606712 -349.562709) (xy 258.640798 -349.518566) (xy 258.680947 -349.479857) (xy 258.726305 -349.447406)
			(xy 258.775905 -349.421905) (xy 258.828689 -349.403898) (xy 258.883532 -349.393768) (xy 258.939266 -349.391731)
			(xy 258.994703 -349.397831) (xy 259.04866 -349.411937) (xy 259.099989 -349.433749) (xy 259.147595 -349.462803)
			(xy 259.190463 -349.498478) (xy 259.22768 -349.540015) (xy 259.258453 -349.586528) (xy 259.282125 -349.637025)
			(xy 259.298193 -349.690432) (xy 259.306313 -349.745608) (xy 259.306822 -349.773494) (xy 259.306313 -349.80138)
			(xy 259.298193 -349.856556) (xy 259.282125 -349.909963) (xy 259.258453 -349.96046) (xy 259.22768 -350.006973)
			(xy 259.190463 -350.04851) (xy 259.147595 -350.084185) (xy 259.099989 -350.113239) (xy 259.04866 -350.135051)
			(xy 258.994703 -350.149157) (xy 258.939266 -350.155257) (xy 258.883532 -350.15322) (xy 258.828689 -350.14309)
			(xy 258.775905 -350.125083) (xy 258.726305 -350.099582) (xy 258.680947 -350.067131) (xy 258.640798 -350.028422)
			(xy 258.606712 -349.984279) (xy 258.579416 -349.935644) (xy 258.559493 -349.883553) (xy 258.547367 -349.829116)
			(xy 258.543296 -349.773494) (xy 254.189845 -349.773494) (xy 254.190761 -349.776538) (xy 254.198881 -349.831714)
			(xy 254.19939 -349.8596) (xy 254.198881 -349.887486) (xy 254.190761 -349.942662) (xy 254.174693 -349.996069)
			(xy 254.151021 -350.046566) (xy 254.120248 -350.093079) (xy 254.083031 -350.134616) (xy 254.040163 -350.170291)
			(xy 253.992557 -350.199345) (xy 253.941228 -350.221157) (xy 253.887271 -350.235263) (xy 253.831834 -350.241363)
			(xy 253.7761 -350.239326) (xy 253.721257 -350.229196) (xy 253.668473 -350.211189) (xy 253.618873 -350.185688)
			(xy 253.573515 -350.153237) (xy 253.533366 -350.114528) (xy 253.49928 -350.070385) (xy 253.471984 -350.02175)
			(xy 253.452061 -349.969659) (xy 253.439935 -349.915222) (xy 253.435864 -349.8596) (xy 249.350721 -349.8596)
			(xy 249.352561 -349.8721) (xy 249.35307 -349.899986) (xy 249.352561 -349.927872) (xy 249.344441 -349.983048)
			(xy 249.328373 -350.036455) (xy 249.304701 -350.086952) (xy 249.273928 -350.133465) (xy 249.236711 -350.175002)
			(xy 249.193843 -350.210677) (xy 249.146237 -350.239731) (xy 249.094908 -350.261543) (xy 249.040951 -350.275649)
			(xy 248.985514 -350.281749) (xy 248.92978 -350.279712) (xy 248.874937 -350.269582) (xy 248.822153 -350.251575)
			(xy 248.772553 -350.226074) (xy 248.727195 -350.193623) (xy 248.687046 -350.154914) (xy 248.65296 -350.110771)
			(xy 248.625664 -350.062136) (xy 248.605741 -350.010045) (xy 248.593615 -349.955608) (xy 248.589544 -349.899986)
			(xy 150.05521 -349.899986) (xy 149.32787 -350.363536) (xy 149.315424 -350.386142) (xy 149.315424 -350.712532)
			(xy 207.046574 -350.712532) (xy 207.050645 -350.65691) (xy 207.062771 -350.602473) (xy 207.082694 -350.550382)
			(xy 207.10999 -350.501747) (xy 207.144076 -350.457604) (xy 207.184225 -350.418895) (xy 207.229583 -350.386444)
			(xy 207.279183 -350.360943) (xy 207.331967 -350.342936) (xy 207.38681 -350.332806) (xy 207.442544 -350.330769)
			(xy 207.497981 -350.336869) (xy 207.551938 -350.350975) (xy 207.603267 -350.372787) (xy 207.606005 -350.374458)
			(xy 236.132368 -350.374458) (xy 236.136439 -350.318836) (xy 236.148565 -350.264399) (xy 236.168488 -350.212308)
			(xy 236.195784 -350.163673) (xy 236.22987 -350.11953) (xy 236.270019 -350.080821) (xy 236.315377 -350.04837)
			(xy 236.364977 -350.022869) (xy 236.417761 -350.004862) (xy 236.472604 -349.994732) (xy 236.528338 -349.992695)
			(xy 236.583775 -349.998795) (xy 236.637732 -350.012901) (xy 236.689061 -350.034713) (xy 236.736667 -350.063767)
			(xy 236.779535 -350.099442) (xy 236.816752 -350.140979) (xy 236.847525 -350.187492) (xy 236.871197 -350.237989)
			(xy 236.887265 -350.291396) (xy 236.895385 -350.346572) (xy 236.895894 -350.374458) (xy 236.895385 -350.402344)
			(xy 236.891705 -350.427353) (xy 240.784067 -350.427353) (xy 240.784067 -350.372847) (xy 240.791825 -350.318895)
			(xy 240.807182 -350.266597) (xy 240.829825 -350.217017) (xy 240.859295 -350.171164) (xy 240.89499 -350.129972)
			(xy 240.936185 -350.094279) (xy 240.98204 -350.064813) (xy 241.031621 -350.042173) (xy 241.083921 -350.026819)
			(xy 241.137873 -350.019066) (xy 241.165126 -350.018604) (xy 241.19333 -350.019135) (xy 241.249121 -350.027455)
			(xy 241.30308 -350.043897) (xy 241.354032 -350.0681) (xy 241.400866 -350.09954) (xy 241.442563 -350.13753)
			(xy 241.460782 -350.159066) (xy 241.468402 -350.167434) (xy 241.488848 -350.177065) (xy 241.500152 -350.177608)
			(xy 241.578892 -350.177608) (xy 241.590183 -350.177023) (xy 241.610611 -350.167391) (xy 241.618262 -350.159066)
			(xy 241.636487 -350.137533) (xy 241.678171 -350.099523) (xy 241.725 -350.06807) (xy 241.775952 -350.043859)
			(xy 241.829916 -350.02742) (xy 241.885712 -350.019111) (xy 241.913918 -350.018604) (xy 241.941169 -350.019067)
			(xy 241.995117 -350.026826) (xy 242.047411 -350.042183) (xy 242.096987 -350.064826) (xy 242.142837 -350.094294)
			(xy 242.184026 -350.129986) (xy 242.219717 -350.171177) (xy 242.249183 -350.217028) (xy 242.271823 -350.266606)
			(xy 242.287178 -350.318901) (xy 242.294934 -350.372849) (xy 242.294934 -350.427351) (xy 242.287178 -350.481299)
			(xy 242.271823 -350.533594) (xy 242.249183 -350.583172) (xy 242.219717 -350.629023) (xy 242.184026 -350.670214)
			(xy 242.142837 -350.705906) (xy 242.096987 -350.735374) (xy 242.047411 -350.758017) (xy 241.995117 -350.773374)
			(xy 241.941169 -350.781133) (xy 241.913918 -350.78162) (xy 241.885713 -350.78112) (xy 241.829921 -350.772792)
			(xy 241.775962 -350.756344) (xy 241.72501 -350.732134) (xy 241.678177 -350.70069) (xy 241.63648 -350.662696)
			(xy 241.618262 -350.641158) (xy 241.610662 -350.632769) (xy 241.590201 -350.623148) (xy 241.578892 -350.622616)
			(xy 241.500152 -350.622616) (xy 241.488863 -350.623218) (xy 241.468434 -350.632837) (xy 241.460782 -350.641158)
			(xy 241.442593 -350.662723) (xy 241.400901 -350.70073) (xy 241.354064 -350.732178) (xy 241.303105 -350.756383)
			(xy 241.249135 -350.772815) (xy 241.193334 -350.781117) (xy 241.165126 -350.78162) (xy 241.137873 -350.781134)
			(xy 241.083921 -350.773381) (xy 241.031621 -350.758027) (xy 240.98204 -350.735387) (xy 240.936185 -350.705921)
			(xy 240.89499 -350.670228) (xy 240.859295 -350.629036) (xy 240.829825 -350.583183) (xy 240.807182 -350.533603)
			(xy 240.791825 -350.481305) (xy 240.784067 -350.427353) (xy 236.891705 -350.427353) (xy 236.887265 -350.45752)
			(xy 236.871197 -350.510927) (xy 236.847525 -350.561424) (xy 236.816752 -350.607937) (xy 236.779535 -350.649474)
			(xy 236.736667 -350.685149) (xy 236.689061 -350.714203) (xy 236.637732 -350.736015) (xy 236.583775 -350.750121)
			(xy 236.528338 -350.756221) (xy 236.472604 -350.754184) (xy 236.417761 -350.744054) (xy 236.364977 -350.726047)
			(xy 236.315377 -350.700546) (xy 236.270019 -350.668095) (xy 236.22987 -350.629386) (xy 236.195784 -350.585243)
			(xy 236.168488 -350.536608) (xy 236.148565 -350.484517) (xy 236.136439 -350.43008) (xy 236.132368 -350.374458)
			(xy 207.606005 -350.374458) (xy 207.650873 -350.401841) (xy 207.693741 -350.437516) (xy 207.730958 -350.479053)
			(xy 207.761731 -350.525566) (xy 207.785403 -350.576063) (xy 207.801471 -350.62947) (xy 207.809591 -350.684646)
			(xy 207.8101 -350.712532) (xy 207.809591 -350.740418) (xy 207.801471 -350.795594) (xy 207.785403 -350.849001)
			(xy 207.761731 -350.899498) (xy 207.761409 -350.899984) (xy 248.573288 -350.899984) (xy 248.577359 -350.844362)
			(xy 248.589485 -350.789925) (xy 248.609408 -350.737834) (xy 248.636704 -350.689199) (xy 248.67079 -350.645056)
			(xy 248.710939 -350.606347) (xy 248.756297 -350.573896) (xy 248.805897 -350.548395) (xy 248.858681 -350.530388)
			(xy 248.913524 -350.520258) (xy 248.969258 -350.518221) (xy 249.024695 -350.524321) (xy 249.078652 -350.538427)
			(xy 249.129981 -350.560239) (xy 249.177587 -350.589293) (xy 249.220455 -350.624968) (xy 249.257672 -350.666505)
			(xy 249.288445 -350.713018) (xy 249.312117 -350.763515) (xy 249.328185 -350.816922) (xy 249.329344 -350.8248)
			(xy 252.957836 -350.8248) (xy 252.961907 -350.769178) (xy 252.974033 -350.714741) (xy 252.993956 -350.66265)
			(xy 253.021252 -350.614015) (xy 253.055338 -350.569872) (xy 253.095487 -350.531163) (xy 253.140845 -350.498712)
			(xy 253.190445 -350.473211) (xy 253.243229 -350.455204) (xy 253.298072 -350.445074) (xy 253.353806 -350.443037)
			(xy 253.409243 -350.449137) (xy 253.4632 -350.463243) (xy 253.514529 -350.485055) (xy 253.562135 -350.514109)
			(xy 253.605003 -350.549784) (xy 253.64222 -350.591321) (xy 253.672993 -350.637834) (xy 253.696665 -350.688331)
			(xy 253.706926 -350.722438) (xy 255.74828 -350.722438) (xy 255.752351 -350.666816) (xy 255.764477 -350.612379)
			(xy 255.7844 -350.560288) (xy 255.811696 -350.511653) (xy 255.845782 -350.46751) (xy 255.885931 -350.428801)
			(xy 255.931289 -350.39635) (xy 255.980889 -350.370849) (xy 256.033673 -350.352842) (xy 256.088516 -350.342712)
			(xy 256.14425 -350.340675) (xy 256.199687 -350.346775) (xy 256.253644 -350.360881) (xy 256.304973 -350.382693)
			(xy 256.352579 -350.411747) (xy 256.395447 -350.447422) (xy 256.432664 -350.488959) (xy 256.463437 -350.535472)
			(xy 256.487109 -350.585969) (xy 256.503177 -350.639376) (xy 256.511297 -350.694552) (xy 256.511806 -350.722438)
			(xy 256.511297 -350.750324) (xy 256.503177 -350.8055) (xy 256.487109 -350.858907) (xy 256.463437 -350.909404)
			(xy 256.432664 -350.955917) (xy 256.395447 -350.997454) (xy 256.352579 -351.033129) (xy 256.304973 -351.062183)
			(xy 256.253644 -351.083995) (xy 256.199687 -351.098101) (xy 256.14425 -351.104201) (xy 256.088516 -351.102164)
			(xy 256.033673 -351.092034) (xy 255.980889 -351.074027) (xy 255.931289 -351.048526) (xy 255.885931 -351.016075)
			(xy 255.845782 -350.977366) (xy 255.811696 -350.933223) (xy 255.7844 -350.884588) (xy 255.764477 -350.832497)
			(xy 255.752351 -350.77806) (xy 255.74828 -350.722438) (xy 253.706926 -350.722438) (xy 253.712733 -350.741738)
			(xy 253.720853 -350.796914) (xy 253.721362 -350.8248) (xy 253.720853 -350.852686) (xy 253.712733 -350.907862)
			(xy 253.696665 -350.961269) (xy 253.672993 -351.011766) (xy 253.64222 -351.058279) (xy 253.605003 -351.099816)
			(xy 253.562135 -351.135491) (xy 253.514529 -351.164545) (xy 253.4632 -351.186357) (xy 253.409243 -351.200463)
			(xy 253.353806 -351.206563) (xy 253.298072 -351.204526) (xy 253.243229 -351.194396) (xy 253.190445 -351.176389)
			(xy 253.140845 -351.150888) (xy 253.095487 -351.118437) (xy 253.055338 -351.079728) (xy 253.021252 -351.035585)
			(xy 252.993956 -350.98695) (xy 252.974033 -350.934859) (xy 252.961907 -350.880422) (xy 252.957836 -350.8248)
			(xy 249.329344 -350.8248) (xy 249.336305 -350.872098) (xy 249.336814 -350.899984) (xy 249.336305 -350.92787)
			(xy 249.328185 -350.983046) (xy 249.312117 -351.036453) (xy 249.288445 -351.08695) (xy 249.257672 -351.133463)
			(xy 249.220455 -351.175) (xy 249.177587 -351.210675) (xy 249.129981 -351.239729) (xy 249.078652 -351.261541)
			(xy 249.024695 -351.275647) (xy 248.969258 -351.281747) (xy 248.913524 -351.27971) (xy 248.858681 -351.26958)
			(xy 248.805897 -351.251573) (xy 248.756297 -351.226072) (xy 248.710939 -351.193621) (xy 248.67079 -351.154912)
			(xy 248.636704 -351.110769) (xy 248.609408 -351.062134) (xy 248.589485 -351.010043) (xy 248.577359 -350.955606)
			(xy 248.573288 -350.899984) (xy 207.761409 -350.899984) (xy 207.730958 -350.946011) (xy 207.693741 -350.987548)
			(xy 207.650873 -351.023223) (xy 207.603267 -351.052277) (xy 207.551938 -351.074089) (xy 207.497981 -351.088195)
			(xy 207.442544 -351.094295) (xy 207.38681 -351.092258) (xy 207.331967 -351.082128) (xy 207.279183 -351.064121)
			(xy 207.229583 -351.03862) (xy 207.184225 -351.006169) (xy 207.144076 -350.96746) (xy 207.10999 -350.923317)
			(xy 207.082694 -350.874682) (xy 207.062771 -350.822591) (xy 207.050645 -350.768154) (xy 207.046574 -350.712532)
			(xy 149.315424 -350.712532) (xy 149.315424 -351.638669) (xy 161.804839 -351.638669) (xy 161.804839 -351.584131)
			(xy 161.812601 -351.530149) (xy 161.827966 -351.47782) (xy 161.850623 -351.428211) (xy 161.880108 -351.382331)
			(xy 161.915824 -351.341115) (xy 161.957041 -351.305401) (xy 162.002922 -351.275917) (xy 162.052531 -351.253262)
			(xy 162.10486 -351.237899) (xy 162.158843 -351.230139) (xy 162.186112 -351.229676) (xy 163.049712 -351.229676)
			(xy 163.076984 -351.230087) (xy 163.130971 -351.237851) (xy 163.183304 -351.253219) (xy 163.232918 -351.275878)
			(xy 163.278802 -351.305367) (xy 163.320022 -351.341086) (xy 163.35574 -351.382308) (xy 163.385228 -351.428192)
			(xy 163.407885 -351.477807) (xy 163.423251 -351.530141) (xy 163.431014 -351.584128) (xy 163.431014 -351.638665)
			(xy 164.913862 -351.638665) (xy 164.913862 -351.584135) (xy 164.921622 -351.530159) (xy 164.936985 -351.477837)
			(xy 164.959637 -351.428233) (xy 164.989117 -351.382358) (xy 165.024826 -351.341146) (xy 165.066036 -351.305434)
			(xy 165.111909 -351.27595) (xy 165.16151 -351.253295) (xy 165.213831 -351.237928) (xy 165.267807 -351.230164)
			(xy 165.295072 -351.229676) (xy 166.158672 -351.229676) (xy 166.185947 -351.230062) (xy 166.239942 -351.237821)
			(xy 166.292284 -351.253187) (xy 166.341905 -351.275845) (xy 166.387797 -351.305335) (xy 166.429024 -351.341056)
			(xy 166.464748 -351.382281) (xy 166.494242 -351.42817) (xy 166.516903 -351.47779) (xy 166.532273 -351.53013)
			(xy 166.540036 -351.584125) (xy 166.540036 -351.63867) (xy 168.022739 -351.63867) (xy 168.022739 -351.58413)
			(xy 168.030502 -351.530146) (xy 168.045868 -351.477816) (xy 168.068526 -351.428206) (xy 168.098013 -351.382325)
			(xy 168.133731 -351.341108) (xy 168.174951 -351.305394) (xy 168.220834 -351.27591) (xy 168.270446 -351.253257)
			(xy 168.322777 -351.237895) (xy 168.376762 -351.230137) (xy 168.404032 -351.229676) (xy 169.267632 -351.229676)
			(xy 169.294903 -351.230089) (xy 169.348888 -351.237855) (xy 169.401219 -351.253224) (xy 169.45083 -351.275885)
			(xy 169.496712 -351.305374) (xy 169.537929 -351.341093) (xy 169.573645 -351.382314) (xy 169.603131 -351.428198)
			(xy 169.625787 -351.477811) (xy 169.641152 -351.530143) (xy 169.648914 -351.584129) (xy 169.648914 -351.638666)
			(xy 171.131762 -351.638666) (xy 171.131762 -351.584134) (xy 171.139523 -351.530156) (xy 171.154886 -351.477832)
			(xy 171.17754 -351.428228) (xy 171.207022 -351.382352) (xy 171.242733 -351.341138) (xy 171.283945 -351.305427)
			(xy 171.329821 -351.275944) (xy 171.379425 -351.253289) (xy 171.431748 -351.237925) (xy 171.485726 -351.230163)
			(xy 171.512992 -351.229676) (xy 172.376592 -351.229676) (xy 172.403866 -351.230063) (xy 172.457859 -351.237825)
			(xy 172.510198 -351.253192) (xy 172.559817 -351.275851) (xy 172.605706 -351.305342) (xy 172.646932 -351.341063)
			(xy 172.682653 -351.382287) (xy 172.712145 -351.428176) (xy 172.734805 -351.477794) (xy 172.750173 -351.530133)
			(xy 172.757936 -351.584126) (xy 172.757936 -351.638664) (xy 174.240762 -351.638664) (xy 174.240762 -351.584136)
			(xy 174.248522 -351.530162) (xy 174.263883 -351.477841) (xy 174.286534 -351.428239) (xy 174.316012 -351.382365)
			(xy 174.351719 -351.341153) (xy 174.392926 -351.305441) (xy 174.438797 -351.275957) (xy 174.488396 -351.2533)
			(xy 174.540715 -351.237932) (xy 174.594688 -351.230166) (xy 174.621952 -351.229676) (xy 175.485552 -351.229676)
			(xy 175.512828 -351.23006) (xy 175.566825 -351.237818) (xy 175.619169 -351.253181) (xy 175.668793 -351.275838)
			(xy 175.714687 -351.305328) (xy 175.755917 -351.341049) (xy 175.791644 -351.382274) (xy 175.821139 -351.428165)
			(xy 175.843802 -351.477786) (xy 175.859172 -351.530128) (xy 175.866936 -351.584124) (xy 175.866936 -351.638669)
			(xy 177.349639 -351.638669) (xy 177.349639 -351.584131) (xy 177.357401 -351.530149) (xy 177.372766 -351.47782)
			(xy 177.395423 -351.428211) (xy 177.424908 -351.382331) (xy 177.460624 -351.341115) (xy 177.501841 -351.305401)
			(xy 177.547722 -351.275917) (xy 177.597331 -351.253262) (xy 177.64966 -351.237899) (xy 177.703643 -351.230139)
			(xy 177.730912 -351.229676) (xy 178.594512 -351.229676) (xy 178.621784 -351.230087) (xy 178.675771 -351.237851)
			(xy 178.728104 -351.253219) (xy 178.777718 -351.275878) (xy 178.823602 -351.305367) (xy 178.864822 -351.341086)
			(xy 178.90054 -351.382308) (xy 178.930028 -351.428192) (xy 178.952685 -351.477807) (xy 178.968051 -351.530141)
			(xy 178.975814 -351.584128) (xy 178.975814 -351.638665) (xy 180.458662 -351.638665) (xy 180.458662 -351.584135)
			(xy 180.466422 -351.530159) (xy 180.481785 -351.477837) (xy 180.504437 -351.428233) (xy 180.533917 -351.382358)
			(xy 180.569626 -351.341146) (xy 180.610836 -351.305434) (xy 180.656709 -351.27595) (xy 180.70631 -351.253295)
			(xy 180.758631 -351.237928) (xy 180.812607 -351.230164) (xy 180.839872 -351.229676) (xy 181.703472 -351.229676)
			(xy 181.730747 -351.230062) (xy 181.784742 -351.237821) (xy 181.837084 -351.253187) (xy 181.886705 -351.275845)
			(xy 181.932597 -351.305335) (xy 181.973824 -351.341056) (xy 182.009548 -351.382281) (xy 182.039042 -351.42817)
			(xy 182.061703 -351.47779) (xy 182.077073 -351.53013) (xy 182.084836 -351.584125) (xy 182.084836 -351.63867)
			(xy 183.567539 -351.63867) (xy 183.567539 -351.58413) (xy 183.575302 -351.530146) (xy 183.590668 -351.477816)
			(xy 183.613326 -351.428206) (xy 183.642813 -351.382325) (xy 183.678531 -351.341108) (xy 183.719751 -351.305394)
			(xy 183.765634 -351.27591) (xy 183.815246 -351.253257) (xy 183.867577 -351.237895) (xy 183.921562 -351.230137)
			(xy 183.948832 -351.229676) (xy 184.812432 -351.229676) (xy 184.839703 -351.230089) (xy 184.893688 -351.237855)
			(xy 184.946019 -351.253224) (xy 184.99563 -351.275885) (xy 185.041512 -351.305374) (xy 185.082729 -351.341093)
			(xy 185.118445 -351.382314) (xy 185.147931 -351.428198) (xy 185.170587 -351.477811) (xy 185.185952 -351.530143)
			(xy 185.193714 -351.584129) (xy 185.193714 -351.638666) (xy 186.676562 -351.638666) (xy 186.676562 -351.584134)
			(xy 186.684323 -351.530156) (xy 186.699686 -351.477832) (xy 186.72234 -351.428228) (xy 186.751822 -351.382352)
			(xy 186.787533 -351.341138) (xy 186.828745 -351.305427) (xy 186.874621 -351.275944) (xy 186.924225 -351.253289)
			(xy 186.976548 -351.237925) (xy 187.030526 -351.230163) (xy 187.057792 -351.229676) (xy 187.921392 -351.229676)
			(xy 187.948666 -351.230063) (xy 188.002659 -351.237825) (xy 188.054998 -351.253192) (xy 188.104617 -351.275851)
			(xy 188.150506 -351.305342) (xy 188.191732 -351.341063) (xy 188.227453 -351.382287) (xy 188.256945 -351.428176)
			(xy 188.279605 -351.477794) (xy 188.294973 -351.530133) (xy 188.302736 -351.584126) (xy 188.302736 -351.638664)
			(xy 189.785562 -351.638664) (xy 189.785562 -351.584136) (xy 189.793322 -351.530162) (xy 189.808683 -351.477841)
			(xy 189.831334 -351.428239) (xy 189.860812 -351.382365) (xy 189.896519 -351.341153) (xy 189.937726 -351.305441)
			(xy 189.983597 -351.275957) (xy 190.033196 -351.2533) (xy 190.085515 -351.237932) (xy 190.139488 -351.230166)
			(xy 190.166752 -351.229676) (xy 191.030352 -351.229676) (xy 191.057628 -351.23006) (xy 191.111625 -351.237818)
			(xy 191.163969 -351.253181) (xy 191.213593 -351.275838) (xy 191.259487 -351.305328) (xy 191.300717 -351.341049)
			(xy 191.336444 -351.382274) (xy 191.365939 -351.428165) (xy 191.388602 -351.477786) (xy 191.403972 -351.530128)
			(xy 191.411736 -351.584124) (xy 191.411736 -351.638669) (xy 192.894439 -351.638669) (xy 192.894439 -351.584131)
			(xy 192.902201 -351.530149) (xy 192.917566 -351.47782) (xy 192.940223 -351.428211) (xy 192.969708 -351.382331)
			(xy 193.005424 -351.341115) (xy 193.046641 -351.305401) (xy 193.092522 -351.275917) (xy 193.142131 -351.253262)
			(xy 193.19446 -351.237899) (xy 193.248443 -351.230139) (xy 193.275712 -351.229676) (xy 194.139312 -351.229676)
			(xy 194.166584 -351.230087) (xy 194.220571 -351.237851) (xy 194.272904 -351.253219) (xy 194.322518 -351.275878)
			(xy 194.368402 -351.305367) (xy 194.409622 -351.341086) (xy 194.44534 -351.382308) (xy 194.474828 -351.428192)
			(xy 194.491002 -351.46361) (xy 204.379574 -351.46361) (xy 204.383645 -351.407988) (xy 204.395771 -351.353551)
			(xy 204.415694 -351.30146) (xy 204.44299 -351.252825) (xy 204.477076 -351.208682) (xy 204.517225 -351.169973)
			(xy 204.562583 -351.137522) (xy 204.612183 -351.112021) (xy 204.664967 -351.094014) (xy 204.71981 -351.083884)
			(xy 204.775544 -351.081847) (xy 204.830981 -351.087947) (xy 204.884938 -351.102053) (xy 204.936267 -351.123865)
			(xy 204.983873 -351.152919) (xy 205.026741 -351.188594) (xy 205.063958 -351.230131) (xy 205.094731 -351.276644)
			(xy 205.118403 -351.327141) (xy 205.124996 -351.349056) (xy 233.362752 -351.349056) (xy 233.366823 -351.293434)
			(xy 233.378949 -351.238997) (xy 233.398872 -351.186906) (xy 233.426168 -351.138271) (xy 233.460254 -351.094128)
			(xy 233.500403 -351.055419) (xy 233.545761 -351.022968) (xy 233.595361 -350.997467) (xy 233.648145 -350.97946)
			(xy 233.702988 -350.96933) (xy 233.758722 -350.967293) (xy 233.814159 -350.973393) (xy 233.868116 -350.987499)
			(xy 233.919445 -351.009311) (xy 233.967051 -351.038365) (xy 234.009919 -351.07404) (xy 234.047136 -351.115577)
			(xy 234.077909 -351.16209) (xy 234.101581 -351.212587) (xy 234.117649 -351.265994) (xy 234.125769 -351.32117)
			(xy 234.126106 -351.339658) (xy 236.132368 -351.339658) (xy 236.136439 -351.284036) (xy 236.148565 -351.229599)
			(xy 236.168488 -351.177508) (xy 236.195784 -351.128873) (xy 236.22987 -351.08473) (xy 236.270019 -351.046021)
			(xy 236.315377 -351.01357) (xy 236.364977 -350.988069) (xy 236.417761 -350.970062) (xy 236.472604 -350.959932)
			(xy 236.528338 -350.957895) (xy 236.583775 -350.963995) (xy 236.637732 -350.978101) (xy 236.689061 -350.999913)
			(xy 236.736667 -351.028967) (xy 236.779535 -351.064642) (xy 236.816752 -351.106179) (xy 236.847525 -351.152692)
			(xy 236.871197 -351.203189) (xy 236.887265 -351.256596) (xy 236.895385 -351.311772) (xy 236.895894 -351.339658)
			(xy 236.895385 -351.367544) (xy 236.890592 -351.40011) (xy 241.568476 -351.40011) (xy 241.572547 -351.344488)
			(xy 241.584673 -351.290051) (xy 241.604596 -351.23796) (xy 241.631892 -351.189325) (xy 241.665978 -351.145182)
			(xy 241.706127 -351.106473) (xy 241.751485 -351.074022) (xy 241.801085 -351.048521) (xy 241.853869 -351.030514)
			(xy 241.908712 -351.020384) (xy 241.964446 -351.018347) (xy 242.019883 -351.024447) (xy 242.07384 -351.038553)
			(xy 242.125169 -351.060365) (xy 242.172775 -351.089419) (xy 242.215643 -351.125094) (xy 242.25286 -351.166631)
			(xy 242.283633 -351.213144) (xy 242.307305 -351.263641) (xy 242.323373 -351.317048) (xy 242.331493 -351.372224)
			(xy 242.332002 -351.40011) (xy 242.331493 -351.427996) (xy 242.323373 -351.483172) (xy 242.307305 -351.536579)
			(xy 242.283633 -351.587076) (xy 242.25286 -351.633589) (xy 242.248309 -351.638668) (xy 267.515839 -351.638668)
			(xy 267.515839 -351.584132) (xy 267.523601 -351.53015) (xy 267.538966 -351.477822) (xy 267.561621 -351.428214)
			(xy 267.591106 -351.382335) (xy 267.62682 -351.341119) (xy 267.668036 -351.305405) (xy 267.713916 -351.27592)
			(xy 267.763524 -351.253265) (xy 267.815852 -351.2379) (xy 267.869834 -351.230139) (xy 267.897102 -351.229676)
			(xy 268.760702 -351.229676) (xy 268.787974 -351.230087) (xy 268.841963 -351.237849) (xy 268.894297 -351.253216)
			(xy 268.943912 -351.275875) (xy 268.989797 -351.305364) (xy 269.031019 -351.341083) (xy 269.066737 -351.382304)
			(xy 269.096226 -351.42819) (xy 269.118884 -351.477805) (xy 269.134251 -351.530139) (xy 269.142013 -351.584128)
			(xy 269.142013 -351.638665) (xy 270.624862 -351.638665) (xy 270.624862 -351.584135) (xy 270.632622 -351.53016)
			(xy 270.647984 -351.477839) (xy 270.670635 -351.428236) (xy 270.700115 -351.382362) (xy 270.735822 -351.341149)
			(xy 270.777031 -351.305437) (xy 270.822903 -351.275953) (xy 270.872503 -351.253297) (xy 270.924823 -351.23793)
			(xy 270.978797 -351.230165) (xy 271.006062 -351.229676) (xy 271.869662 -351.229676) (xy 271.896937 -351.230061)
			(xy 271.950934 -351.23782) (xy 272.003276 -351.253184) (xy 272.052899 -351.275842) (xy 272.098792 -351.305331)
			(xy 272.140021 -351.341052) (xy 272.175746 -351.382277) (xy 272.20524 -351.428167) (xy 272.227903 -351.477788)
			(xy 272.243272 -351.530129) (xy 272.251036 -351.584125) (xy 272.251036 -351.638669) (xy 273.733739 -351.638669)
			(xy 273.733739 -351.584131) (xy 273.741501 -351.530147) (xy 273.756867 -351.477818) (xy 273.779524 -351.428208)
			(xy 273.809011 -351.382328) (xy 273.844727 -351.341112) (xy 273.885946 -351.305398) (xy 273.931828 -351.275914)
			(xy 273.981439 -351.25326) (xy 274.033769 -351.237897) (xy 274.087753 -351.230138) (xy 274.115022 -351.229676)
			(xy 274.978622 -351.229676) (xy 275.005893 -351.230088) (xy 275.05988 -351.237853) (xy 275.112212 -351.253222)
			(xy 275.161824 -351.275881) (xy 275.207707 -351.305371) (xy 275.248926 -351.34109) (xy 275.284642 -351.382311)
			(xy 275.314129 -351.428195) (xy 275.336786 -351.477809) (xy 275.352152 -351.530142) (xy 275.359914 -351.584129)
			(xy 275.359914 -351.638666) (xy 276.842762 -351.638666) (xy 276.842762 -351.584134) (xy 276.850523 -351.530158)
			(xy 276.865886 -351.477835) (xy 276.888538 -351.428231) (xy 276.91802 -351.382355) (xy 276.953729 -351.341142)
			(xy 276.994941 -351.30543) (xy 277.040815 -351.275947) (xy 277.090418 -351.253292) (xy 277.14274 -351.237927)
			(xy 277.196716 -351.230164) (xy 277.223982 -351.229676) (xy 278.087582 -351.229676) (xy 278.114857 -351.230062)
			(xy 278.168851 -351.237823) (xy 278.221191 -351.253189) (xy 278.270811 -351.275848) (xy 278.316702 -351.305338)
			(xy 278.357928 -351.341059) (xy 278.393651 -351.382284) (xy 278.423143 -351.428173) (xy 278.445804 -351.477792)
			(xy 278.461173 -351.530132) (xy 278.468936 -351.584125) (xy 278.468936 -351.63867) (xy 279.95164 -351.63867)
			(xy 279.95164 -351.58413) (xy 279.959402 -351.530145) (xy 279.974769 -351.477814) (xy 279.997427 -351.428203)
			(xy 280.026916 -351.382322) (xy 280.062634 -351.341105) (xy 280.103855 -351.305391) (xy 280.14974 -351.275907)
			(xy 280.199353 -351.253254) (xy 280.251686 -351.237893) (xy 280.305672 -351.230137) (xy 280.332942 -351.229676)
			(xy 281.196542 -351.229676) (xy 281.223812 -351.230089) (xy 281.277797 -351.237857) (xy 281.330126 -351.253227)
			(xy 281.379736 -351.275888) (xy 281.425616 -351.305378) (xy 281.466833 -351.341097) (xy 281.502547 -351.382317)
			(xy 281.532032 -351.428201) (xy 281.554688 -351.477813) (xy 281.570052 -351.530145) (xy 281.577814 -351.58413)
			(xy 281.577814 -351.638668) (xy 283.060639 -351.638668) (xy 283.060639 -351.584132) (xy 283.068401 -351.53015)
			(xy 283.083766 -351.477822) (xy 283.106421 -351.428214) (xy 283.135906 -351.382335) (xy 283.17162 -351.341119)
			(xy 283.212836 -351.305405) (xy 283.258716 -351.27592) (xy 283.308324 -351.253265) (xy 283.360652 -351.2379)
			(xy 283.414634 -351.230139) (xy 283.441902 -351.229676) (xy 284.305502 -351.229676) (xy 284.332774 -351.230087)
			(xy 284.386763 -351.237849) (xy 284.439097 -351.253216) (xy 284.488712 -351.275875) (xy 284.534597 -351.305364)
			(xy 284.575819 -351.341083) (xy 284.611537 -351.382304) (xy 284.641026 -351.42819) (xy 284.663684 -351.477805)
			(xy 284.679051 -351.530139) (xy 284.686813 -351.584128) (xy 284.686813 -351.638665) (xy 286.169662 -351.638665)
			(xy 286.169662 -351.584135) (xy 286.177422 -351.53016) (xy 286.192784 -351.477839) (xy 286.215435 -351.428236)
			(xy 286.244915 -351.382362) (xy 286.280622 -351.341149) (xy 286.321831 -351.305437) (xy 286.367703 -351.275953)
			(xy 286.417303 -351.253297) (xy 286.469623 -351.23793) (xy 286.523597 -351.230165) (xy 286.550862 -351.229676)
			(xy 287.414462 -351.229676) (xy 287.441737 -351.230061) (xy 287.495734 -351.23782) (xy 287.548076 -351.253184)
			(xy 287.597699 -351.275842) (xy 287.643592 -351.305331) (xy 287.684821 -351.341052) (xy 287.720546 -351.382277)
			(xy 287.75004 -351.428167) (xy 287.772703 -351.477788) (xy 287.788072 -351.530129) (xy 287.795836 -351.584125)
			(xy 287.795836 -351.638669) (xy 289.278539 -351.638669) (xy 289.278539 -351.584131) (xy 289.286301 -351.530147)
			(xy 289.301667 -351.477818) (xy 289.324324 -351.428208) (xy 289.353811 -351.382328) (xy 289.389527 -351.341112)
			(xy 289.430746 -351.305398) (xy 289.476628 -351.275914) (xy 289.526239 -351.25326) (xy 289.578569 -351.237897)
			(xy 289.632553 -351.230138) (xy 289.659822 -351.229676) (xy 290.523422 -351.229676) (xy 290.550693 -351.230088)
			(xy 290.60468 -351.237853) (xy 290.657012 -351.253222) (xy 290.706624 -351.275881) (xy 290.752507 -351.305371)
			(xy 290.793726 -351.34109) (xy 290.829442 -351.382311) (xy 290.858929 -351.428195) (xy 290.881586 -351.477809)
			(xy 290.896952 -351.530142) (xy 290.904714 -351.584129) (xy 290.904714 -351.638666) (xy 292.387562 -351.638666)
			(xy 292.387562 -351.584134) (xy 292.395323 -351.530158) (xy 292.410686 -351.477835) (xy 292.433338 -351.428231)
			(xy 292.46282 -351.382355) (xy 292.498529 -351.341142) (xy 292.539741 -351.30543) (xy 292.585615 -351.275947)
			(xy 292.635218 -351.253292) (xy 292.68754 -351.237927) (xy 292.741516 -351.230164) (xy 292.768782 -351.229676)
			(xy 293.632382 -351.229676) (xy 293.659657 -351.230062) (xy 293.713651 -351.237823) (xy 293.765991 -351.253189)
			(xy 293.815611 -351.275848) (xy 293.861502 -351.305338) (xy 293.902728 -351.341059) (xy 293.938451 -351.382284)
			(xy 293.967943 -351.428173) (xy 293.990604 -351.477792) (xy 294.005973 -351.530132) (xy 294.013736 -351.584125)
			(xy 294.013736 -351.63867) (xy 295.49644 -351.63867) (xy 295.49644 -351.58413) (xy 295.504202 -351.530145)
			(xy 295.519569 -351.477814) (xy 295.542227 -351.428203) (xy 295.571716 -351.382322) (xy 295.607434 -351.341105)
			(xy 295.648655 -351.305391) (xy 295.69454 -351.275907) (xy 295.744153 -351.253254) (xy 295.796486 -351.237893)
			(xy 295.850472 -351.230137) (xy 295.877742 -351.229676) (xy 296.741342 -351.229676) (xy 296.768612 -351.230089)
			(xy 296.822597 -351.237857) (xy 296.874926 -351.253227) (xy 296.924536 -351.275888) (xy 296.970416 -351.305378)
			(xy 297.011633 -351.341097) (xy 297.047347 -351.382317) (xy 297.076832 -351.428201) (xy 297.099488 -351.477813)
			(xy 297.114852 -351.530145) (xy 297.122614 -351.58413) (xy 297.122614 -351.638668) (xy 298.605439 -351.638668)
			(xy 298.605439 -351.584132) (xy 298.613201 -351.53015) (xy 298.628566 -351.477822) (xy 298.651221 -351.428214)
			(xy 298.680706 -351.382335) (xy 298.71642 -351.341119) (xy 298.757636 -351.305405) (xy 298.803516 -351.27592)
			(xy 298.853124 -351.253265) (xy 298.905452 -351.2379) (xy 298.959434 -351.230139) (xy 298.986702 -351.229676)
			(xy 299.850302 -351.229676) (xy 299.877574 -351.230087) (xy 299.931563 -351.237849) (xy 299.983897 -351.253216)
			(xy 300.033512 -351.275875) (xy 300.079397 -351.305364) (xy 300.120619 -351.341083) (xy 300.156337 -351.382304)
			(xy 300.185826 -351.42819) (xy 300.208484 -351.477805) (xy 300.223851 -351.530139) (xy 300.231613 -351.584128)
			(xy 300.231613 -351.638672) (xy 300.223851 -351.692661) (xy 300.208484 -351.744995) (xy 300.185826 -351.79461)
			(xy 300.156337 -351.840496) (xy 300.120619 -351.881717) (xy 300.079397 -351.917436) (xy 300.033512 -351.946925)
			(xy 299.983897 -351.969584) (xy 299.931563 -351.984951) (xy 299.877574 -351.992713) (xy 299.850302 -351.9932)
			(xy 298.986702 -351.9932) (xy 298.959434 -351.992661) (xy 298.905452 -351.9849) (xy 298.853124 -351.969535)
			(xy 298.803516 -351.94688) (xy 298.757636 -351.917395) (xy 298.71642 -351.881681) (xy 298.680706 -351.840465)
			(xy 298.651221 -351.794586) (xy 298.628566 -351.744978) (xy 298.613201 -351.69265) (xy 298.605439 -351.638668)
			(xy 297.122614 -351.638668) (xy 297.122614 -351.63867) (xy 297.114852 -351.692655) (xy 297.099488 -351.744987)
			(xy 297.076832 -351.794599) (xy 297.047347 -351.840483) (xy 297.011633 -351.881703) (xy 296.970416 -351.917422)
			(xy 296.924536 -351.946912) (xy 296.874926 -351.969573) (xy 296.822597 -351.984943) (xy 296.768612 -351.992711)
			(xy 296.741342 -351.9932) (xy 295.877742 -351.9932) (xy 295.850472 -351.992663) (xy 295.796486 -351.984907)
			(xy 295.744153 -351.969546) (xy 295.69454 -351.946893) (xy 295.648655 -351.917409) (xy 295.607434 -351.881695)
			(xy 295.571716 -351.840478) (xy 295.542227 -351.794597) (xy 295.519569 -351.744986) (xy 295.504202 -351.692655)
			(xy 295.49644 -351.63867) (xy 294.013736 -351.63867) (xy 294.013736 -351.638675) (xy 294.005973 -351.692668)
			(xy 293.990604 -351.745008) (xy 293.967943 -351.794627) (xy 293.938451 -351.840516) (xy 293.902728 -351.881741)
			(xy 293.861502 -351.917462) (xy 293.815611 -351.946952) (xy 293.765991 -351.969611) (xy 293.713651 -351.984977)
			(xy 293.659657 -351.992738) (xy 293.632382 -351.9932) (xy 292.768782 -351.9932) (xy 292.741516 -351.992636)
			(xy 292.68754 -351.984873) (xy 292.635218 -351.969508) (xy 292.585615 -351.946853) (xy 292.539741 -351.91737)
			(xy 292.498529 -351.881658) (xy 292.46282 -351.840445) (xy 292.433338 -351.794569) (xy 292.410686 -351.744965)
			(xy 292.395323 -351.692642) (xy 292.387562 -351.638666) (xy 290.904714 -351.638666) (xy 290.904714 -351.638671)
			(xy 290.896952 -351.692658) (xy 290.881586 -351.744991) (xy 290.858929 -351.794605) (xy 290.829442 -351.840489)
			(xy 290.793726 -351.88171) (xy 290.752507 -351.917429) (xy 290.706624 -351.946919) (xy 290.657012 -351.969578)
			(xy 290.60468 -351.984947) (xy 290.550693 -351.992712) (xy 290.523422 -351.9932) (xy 289.659822 -351.9932)
			(xy 289.632553 -351.992662) (xy 289.578569 -351.984903) (xy 289.526239 -351.96954) (xy 289.476628 -351.946886)
			(xy 289.430746 -351.917402) (xy 289.389527 -351.881688) (xy 289.353811 -351.840472) (xy 289.324324 -351.794592)
			(xy 289.301667 -351.744982) (xy 289.286301 -351.692653) (xy 289.278539 -351.638669) (xy 287.795836 -351.638669)
			(xy 287.795836 -351.638675) (xy 287.788072 -351.692671) (xy 287.772703 -351.745012) (xy 287.75004 -351.794633)
			(xy 287.720546 -351.840523) (xy 287.684821 -351.881748) (xy 287.643592 -351.917469) (xy 287.597699 -351.946958)
			(xy 287.548076 -351.969616) (xy 287.495734 -351.98498) (xy 287.441737 -351.992739) (xy 287.414462 -351.9932)
			(xy 286.550862 -351.9932) (xy 286.523597 -351.992635) (xy 286.469623 -351.98487) (xy 286.417303 -351.969503)
			(xy 286.367703 -351.946847) (xy 286.321831 -351.917363) (xy 286.280622 -351.881651) (xy 286.244915 -351.840438)
			(xy 286.215435 -351.794564) (xy 286.192784 -351.744961) (xy 286.177422 -351.69264) (xy 286.169662 -351.638665)
			(xy 284.686813 -351.638665) (xy 284.686813 -351.638672) (xy 284.679051 -351.692661) (xy 284.663684 -351.744995)
			(xy 284.641026 -351.79461) (xy 284.611537 -351.840496) (xy 284.575819 -351.881717) (xy 284.534597 -351.917436)
			(xy 284.488712 -351.946925) (xy 284.439097 -351.969584) (xy 284.386763 -351.984951) (xy 284.332774 -351.992713)
			(xy 284.305502 -351.9932) (xy 283.441902 -351.9932) (xy 283.414634 -351.992661) (xy 283.360652 -351.9849)
			(xy 283.308324 -351.969535) (xy 283.258716 -351.94688) (xy 283.212836 -351.917395) (xy 283.17162 -351.881681)
			(xy 283.135906 -351.840465) (xy 283.106421 -351.794586) (xy 283.083766 -351.744978) (xy 283.068401 -351.69265)
			(xy 283.060639 -351.638668) (xy 281.577814 -351.638668) (xy 281.577814 -351.63867) (xy 281.570052 -351.692655)
			(xy 281.554688 -351.744987) (xy 281.532032 -351.794599) (xy 281.502547 -351.840483) (xy 281.466833 -351.881703)
			(xy 281.425616 -351.917422) (xy 281.379736 -351.946912) (xy 281.330126 -351.969573) (xy 281.277797 -351.984943)
			(xy 281.223812 -351.992711) (xy 281.196542 -351.9932) (xy 280.332942 -351.9932) (xy 280.305672 -351.992663)
			(xy 280.251686 -351.984907) (xy 280.199353 -351.969546) (xy 280.14974 -351.946893) (xy 280.103855 -351.917409)
			(xy 280.062634 -351.881695) (xy 280.026916 -351.840478) (xy 279.997427 -351.794597) (xy 279.974769 -351.744986)
			(xy 279.959402 -351.692655) (xy 279.95164 -351.63867) (xy 278.468936 -351.63867) (xy 278.468936 -351.638675)
			(xy 278.461173 -351.692668) (xy 278.445804 -351.745008) (xy 278.423143 -351.794627) (xy 278.393651 -351.840516)
			(xy 278.357928 -351.881741) (xy 278.316702 -351.917462) (xy 278.270811 -351.946952) (xy 278.221191 -351.969611)
			(xy 278.168851 -351.984977) (xy 278.114857 -351.992738) (xy 278.087582 -351.9932) (xy 277.223982 -351.9932)
			(xy 277.196716 -351.992636) (xy 277.14274 -351.984873) (xy 277.090418 -351.969508) (xy 277.040815 -351.946853)
			(xy 276.994941 -351.91737) (xy 276.953729 -351.881658) (xy 276.91802 -351.840445) (xy 276.888538 -351.794569)
			(xy 276.865886 -351.744965) (xy 276.850523 -351.692642) (xy 276.842762 -351.638666) (xy 275.359914 -351.638666)
			(xy 275.359914 -351.638671) (xy 275.352152 -351.692658) (xy 275.336786 -351.744991) (xy 275.314129 -351.794605)
			(xy 275.284642 -351.840489) (xy 275.248926 -351.88171) (xy 275.207707 -351.917429) (xy 275.161824 -351.946919)
			(xy 275.112212 -351.969578) (xy 275.05988 -351.984947) (xy 275.005893 -351.992712) (xy 274.978622 -351.9932)
			(xy 274.115022 -351.9932) (xy 274.087753 -351.992662) (xy 274.033769 -351.984903) (xy 273.981439 -351.96954)
			(xy 273.931828 -351.946886) (xy 273.885946 -351.917402) (xy 273.844727 -351.881688) (xy 273.809011 -351.840472)
			(xy 273.779524 -351.794592) (xy 273.756867 -351.744982) (xy 273.741501 -351.692653) (xy 273.733739 -351.638669)
			(xy 272.251036 -351.638669) (xy 272.251036 -351.638675) (xy 272.243272 -351.692671) (xy 272.227903 -351.745012)
			(xy 272.20524 -351.794633) (xy 272.175746 -351.840523) (xy 272.140021 -351.881748) (xy 272.098792 -351.917469)
			(xy 272.052899 -351.946958) (xy 272.003276 -351.969616) (xy 271.950934 -351.98498) (xy 271.896937 -351.992739)
			(xy 271.869662 -351.9932) (xy 271.006062 -351.9932) (xy 270.978797 -351.992635) (xy 270.924823 -351.98487)
			(xy 270.872503 -351.969503) (xy 270.822903 -351.946847) (xy 270.777031 -351.917363) (xy 270.735822 -351.881651)
			(xy 270.700115 -351.840438) (xy 270.670635 -351.794564) (xy 270.647984 -351.744961) (xy 270.632622 -351.69264)
			(xy 270.624862 -351.638665) (xy 269.142013 -351.638665) (xy 269.142013 -351.638672) (xy 269.134251 -351.692661)
			(xy 269.118884 -351.744995) (xy 269.096226 -351.79461) (xy 269.066737 -351.840496) (xy 269.031019 -351.881717)
			(xy 268.989797 -351.917436) (xy 268.943912 -351.946925) (xy 268.894297 -351.969584) (xy 268.841963 -351.984951)
			(xy 268.787974 -351.992713) (xy 268.760702 -351.9932) (xy 267.897102 -351.9932) (xy 267.869834 -351.992661)
			(xy 267.815852 -351.9849) (xy 267.763524 -351.969535) (xy 267.713916 -351.94688) (xy 267.668036 -351.917395)
			(xy 267.62682 -351.881681) (xy 267.591106 -351.840465) (xy 267.561621 -351.794586) (xy 267.538966 -351.744978)
			(xy 267.523601 -351.69265) (xy 267.515839 -351.638668) (xy 242.248309 -351.638668) (xy 242.215643 -351.675126)
			(xy 242.172775 -351.710801) (xy 242.125169 -351.739855) (xy 242.07384 -351.761667) (xy 242.019883 -351.775773)
			(xy 241.964446 -351.781873) (xy 241.908712 -351.779836) (xy 241.853869 -351.769706) (xy 241.801085 -351.751699)
			(xy 241.751485 -351.726198) (xy 241.706127 -351.693747) (xy 241.665978 -351.655038) (xy 241.631892 -351.610895)
			(xy 241.604596 -351.56226) (xy 241.584673 -351.510169) (xy 241.572547 -351.455732) (xy 241.568476 -351.40011)
			(xy 236.890592 -351.40011) (xy 236.887265 -351.42272) (xy 236.871197 -351.476127) (xy 236.847525 -351.526624)
			(xy 236.816752 -351.573137) (xy 236.779535 -351.614674) (xy 236.736667 -351.650349) (xy 236.689061 -351.679403)
			(xy 236.637732 -351.701215) (xy 236.583775 -351.715321) (xy 236.528338 -351.721421) (xy 236.472604 -351.719384)
			(xy 236.417761 -351.709254) (xy 236.364977 -351.691247) (xy 236.315377 -351.665746) (xy 236.270019 -351.633295)
			(xy 236.22987 -351.594586) (xy 236.195784 -351.550443) (xy 236.168488 -351.501808) (xy 236.148565 -351.449717)
			(xy 236.136439 -351.39528) (xy 236.132368 -351.339658) (xy 234.126106 -351.339658) (xy 234.126278 -351.349056)
			(xy 234.125769 -351.376942) (xy 234.117649 -351.432118) (xy 234.101581 -351.485525) (xy 234.077909 -351.536022)
			(xy 234.047136 -351.582535) (xy 234.009919 -351.624072) (xy 233.967051 -351.659747) (xy 233.919445 -351.688801)
			(xy 233.868116 -351.710613) (xy 233.814159 -351.724719) (xy 233.758722 -351.730819) (xy 233.702988 -351.728782)
			(xy 233.648145 -351.718652) (xy 233.595361 -351.700645) (xy 233.545761 -351.675144) (xy 233.500403 -351.642693)
			(xy 233.460254 -351.603984) (xy 233.426168 -351.559841) (xy 233.398872 -351.511206) (xy 233.378949 -351.459115)
			(xy 233.366823 -351.404678) (xy 233.362752 -351.349056) (xy 205.124996 -351.349056) (xy 205.134471 -351.380548)
			(xy 205.142591 -351.435724) (xy 205.1431 -351.46361) (xy 205.142591 -351.491496) (xy 205.134471 -351.546672)
			(xy 205.118403 -351.600079) (xy 205.094731 -351.650576) (xy 205.063958 -351.697089) (xy 205.026741 -351.738626)
			(xy 204.983873 -351.774301) (xy 204.936267 -351.803355) (xy 204.884938 -351.825167) (xy 204.830981 -351.839273)
			(xy 204.775544 -351.845373) (xy 204.71981 -351.843336) (xy 204.664967 -351.833206) (xy 204.612183 -351.815199)
			(xy 204.562583 -351.789698) (xy 204.517225 -351.757247) (xy 204.477076 -351.718538) (xy 204.44299 -351.674395)
			(xy 204.415694 -351.62576) (xy 204.395771 -351.573669) (xy 204.383645 -351.519232) (xy 204.379574 -351.46361)
			(xy 194.491002 -351.46361) (xy 194.497485 -351.477807) (xy 194.512851 -351.530141) (xy 194.520614 -351.584128)
			(xy 194.520614 -351.638672) (xy 194.512851 -351.692659) (xy 194.497485 -351.744993) (xy 194.474828 -351.794608)
			(xy 194.44534 -351.840492) (xy 194.409622 -351.881714) (xy 194.368402 -351.917433) (xy 194.322518 -351.946922)
			(xy 194.272904 -351.969581) (xy 194.220571 -351.984949) (xy 194.166584 -351.992713) (xy 194.139312 -351.9932)
			(xy 193.275712 -351.9932) (xy 193.248443 -351.992661) (xy 193.19446 -351.984901) (xy 193.142131 -351.969538)
			(xy 193.092522 -351.946883) (xy 193.046641 -351.917399) (xy 193.005424 -351.881685) (xy 192.969708 -351.840469)
			(xy 192.940223 -351.794589) (xy 192.917566 -351.74498) (xy 192.902201 -351.692651) (xy 192.894439 -351.638669)
			(xy 191.411736 -351.638669) (xy 191.411736 -351.638676) (xy 191.403972 -351.692672) (xy 191.388602 -351.745014)
			(xy 191.365939 -351.794635) (xy 191.336444 -351.840526) (xy 191.300717 -351.881751) (xy 191.259487 -351.917472)
			(xy 191.213593 -351.946962) (xy 191.163969 -351.969619) (xy 191.111625 -351.984982) (xy 191.057628 -351.99274)
			(xy 191.030352 -351.9932) (xy 190.166752 -351.9932) (xy 190.139488 -351.992634) (xy 190.085515 -351.984868)
			(xy 190.033196 -351.9695) (xy 189.983597 -351.946843) (xy 189.937726 -351.917359) (xy 189.896519 -351.881647)
			(xy 189.860812 -351.840435) (xy 189.831334 -351.794561) (xy 189.808683 -351.744959) (xy 189.793322 -351.692639)
			(xy 189.785562 -351.638664) (xy 188.302736 -351.638664) (xy 188.302736 -351.638674) (xy 188.294973 -351.692667)
			(xy 188.279605 -351.745006) (xy 188.256945 -351.794624) (xy 188.227453 -351.840513) (xy 188.191732 -351.881737)
			(xy 188.150506 -351.917458) (xy 188.104617 -351.946949) (xy 188.054998 -351.969608) (xy 188.002659 -351.984975)
			(xy 187.948666 -351.992737) (xy 187.921392 -351.9932) (xy 187.057792 -351.9932) (xy 187.030526 -351.992637)
			(xy 186.976548 -351.984875) (xy 186.924225 -351.969511) (xy 186.874621 -351.946856) (xy 186.828745 -351.917373)
			(xy 186.787533 -351.881662) (xy 186.751822 -351.840448) (xy 186.72234 -351.794572) (xy 186.699686 -351.744968)
			(xy 186.684323 -351.692644) (xy 186.676562 -351.638666) (xy 185.193714 -351.638666) (xy 185.193714 -351.638671)
			(xy 185.185952 -351.692657) (xy 185.170587 -351.744989) (xy 185.147931 -351.794602) (xy 185.118445 -351.840486)
			(xy 185.082729 -351.881707) (xy 185.041512 -351.917426) (xy 184.99563 -351.946915) (xy 184.946019 -351.969576)
			(xy 184.893688 -351.984945) (xy 184.839703 -351.992711) (xy 184.812432 -351.9932) (xy 183.948832 -351.9932)
			(xy 183.921562 -351.992663) (xy 183.867577 -351.984905) (xy 183.815246 -351.969543) (xy 183.765634 -351.94689)
			(xy 183.719751 -351.917406) (xy 183.678531 -351.881692) (xy 183.642813 -351.840475) (xy 183.613326 -351.794594)
			(xy 183.590668 -351.744984) (xy 183.575302 -351.692654) (xy 183.567539 -351.63867) (xy 182.084836 -351.63867)
			(xy 182.084836 -351.638675) (xy 182.077073 -351.69267) (xy 182.061703 -351.74501) (xy 182.039042 -351.79463)
			(xy 182.009548 -351.840519) (xy 181.973824 -351.881744) (xy 181.932597 -351.917465) (xy 181.886705 -351.946955)
			(xy 181.837084 -351.969613) (xy 181.784742 -351.984979) (xy 181.730747 -351.992738) (xy 181.703472 -351.9932)
			(xy 180.839872 -351.9932) (xy 180.812607 -351.992636) (xy 180.758631 -351.984872) (xy 180.70631 -351.969505)
			(xy 180.656709 -351.94685) (xy 180.610836 -351.917366) (xy 180.569626 -351.881654) (xy 180.533917 -351.840442)
			(xy 180.504437 -351.794567) (xy 180.481785 -351.744963) (xy 180.466422 -351.692641) (xy 180.458662 -351.638665)
			(xy 178.975814 -351.638665) (xy 178.975814 -351.638672) (xy 178.968051 -351.692659) (xy 178.952685 -351.744993)
			(xy 178.930028 -351.794608) (xy 178.90054 -351.840492) (xy 178.864822 -351.881714) (xy 178.823602 -351.917433)
			(xy 178.777718 -351.946922) (xy 178.728104 -351.969581) (xy 178.675771 -351.984949) (xy 178.621784 -351.992713)
			(xy 178.594512 -351.9932) (xy 177.730912 -351.9932) (xy 177.703643 -351.992661) (xy 177.64966 -351.984901)
			(xy 177.597331 -351.969538) (xy 177.547722 -351.946883) (xy 177.501841 -351.917399) (xy 177.460624 -351.881685)
			(xy 177.424908 -351.840469) (xy 177.395423 -351.794589) (xy 177.372766 -351.74498) (xy 177.357401 -351.692651)
			(xy 177.349639 -351.638669) (xy 175.866936 -351.638669) (xy 175.866936 -351.638676) (xy 175.859172 -351.692672)
			(xy 175.843802 -351.745014) (xy 175.821139 -351.794635) (xy 175.791644 -351.840526) (xy 175.755917 -351.881751)
			(xy 175.714687 -351.917472) (xy 175.668793 -351.946962) (xy 175.619169 -351.969619) (xy 175.566825 -351.984982)
			(xy 175.512828 -351.99274) (xy 175.485552 -351.9932) (xy 174.621952 -351.9932) (xy 174.594688 -351.992634)
			(xy 174.540715 -351.984868) (xy 174.488396 -351.9695) (xy 174.438797 -351.946843) (xy 174.392926 -351.917359)
			(xy 174.351719 -351.881647) (xy 174.316012 -351.840435) (xy 174.286534 -351.794561) (xy 174.263883 -351.744959)
			(xy 174.248522 -351.692639) (xy 174.240762 -351.638664) (xy 172.757936 -351.638664) (xy 172.757936 -351.638674)
			(xy 172.750173 -351.692667) (xy 172.734805 -351.745006) (xy 172.712145 -351.794624) (xy 172.682653 -351.840513)
			(xy 172.646932 -351.881737) (xy 172.605706 -351.917458) (xy 172.559817 -351.946949) (xy 172.510198 -351.969608)
			(xy 172.457859 -351.984975) (xy 172.403866 -351.992737) (xy 172.376592 -351.9932) (xy 171.512992 -351.9932)
			(xy 171.485726 -351.992637) (xy 171.431748 -351.984875) (xy 171.379425 -351.969511) (xy 171.329821 -351.946856)
			(xy 171.283945 -351.917373) (xy 171.242733 -351.881662) (xy 171.207022 -351.840448) (xy 171.17754 -351.794572)
			(xy 171.154886 -351.744968) (xy 171.139523 -351.692644) (xy 171.131762 -351.638666) (xy 169.648914 -351.638666)
			(xy 169.648914 -351.638671) (xy 169.641152 -351.692657) (xy 169.625787 -351.744989) (xy 169.603131 -351.794602)
			(xy 169.573645 -351.840486) (xy 169.537929 -351.881707) (xy 169.496712 -351.917426) (xy 169.45083 -351.946915)
			(xy 169.401219 -351.969576) (xy 169.348888 -351.984945) (xy 169.294903 -351.992711) (xy 169.267632 -351.9932)
			(xy 168.404032 -351.9932) (xy 168.376762 -351.992663) (xy 168.322777 -351.984905) (xy 168.270446 -351.969543)
			(xy 168.220834 -351.94689) (xy 168.174951 -351.917406) (xy 168.133731 -351.881692) (xy 168.098013 -351.840475)
			(xy 168.068526 -351.794594) (xy 168.045868 -351.744984) (xy 168.030502 -351.692654) (xy 168.022739 -351.63867)
			(xy 166.540036 -351.63867) (xy 166.540036 -351.638675) (xy 166.532273 -351.69267) (xy 166.516903 -351.74501)
			(xy 166.494242 -351.79463) (xy 166.464748 -351.840519) (xy 166.429024 -351.881744) (xy 166.387797 -351.917465)
			(xy 166.341905 -351.946955) (xy 166.292284 -351.969613) (xy 166.239942 -351.984979) (xy 166.185947 -351.992738)
			(xy 166.158672 -351.9932) (xy 165.295072 -351.9932) (xy 165.267807 -351.992636) (xy 165.213831 -351.984872)
			(xy 165.16151 -351.969505) (xy 165.111909 -351.94685) (xy 165.066036 -351.917366) (xy 165.024826 -351.881654)
			(xy 164.989117 -351.840442) (xy 164.959637 -351.794567) (xy 164.936985 -351.744963) (xy 164.921622 -351.692641)
			(xy 164.913862 -351.638665) (xy 163.431014 -351.638665) (xy 163.431014 -351.638672) (xy 163.423251 -351.692659)
			(xy 163.407885 -351.744993) (xy 163.385228 -351.794608) (xy 163.35574 -351.840492) (xy 163.320022 -351.881714)
			(xy 163.278802 -351.917433) (xy 163.232918 -351.946922) (xy 163.183304 -351.969581) (xy 163.130971 -351.984949)
			(xy 163.076984 -351.992713) (xy 163.049712 -351.9932) (xy 162.186112 -351.9932) (xy 162.158843 -351.992661)
			(xy 162.10486 -351.984901) (xy 162.052531 -351.969538) (xy 162.002922 -351.946883) (xy 161.957041 -351.917399)
			(xy 161.915824 -351.881685) (xy 161.880108 -351.840469) (xy 161.850623 -351.794589) (xy 161.827966 -351.74498)
			(xy 161.812601 -351.692651) (xy 161.804839 -351.638669) (xy 149.315424 -351.638669) (xy 149.315424 -352.307906)
			(xy 233.389422 -352.307906) (xy 233.393493 -352.252284) (xy 233.405619 -352.197847) (xy 233.425542 -352.145756)
			(xy 233.452838 -352.097121) (xy 233.486924 -352.052978) (xy 233.527073 -352.014269) (xy 233.572431 -351.981818)
			(xy 233.622031 -351.956317) (xy 233.674815 -351.93831) (xy 233.729658 -351.92818) (xy 233.785392 -351.926143)
			(xy 233.840829 -351.932243) (xy 233.894786 -351.946349) (xy 233.946115 -351.968161) (xy 233.993721 -351.997215)
			(xy 234.036589 -352.03289) (xy 234.073806 -352.074427) (xy 234.104579 -352.12094) (xy 234.128251 -352.171437)
			(xy 234.144319 -352.224844) (xy 234.152439 -352.28002) (xy 234.152892 -352.304858) (xy 236.132368 -352.304858)
			(xy 236.136439 -352.249236) (xy 236.148565 -352.194799) (xy 236.168488 -352.142708) (xy 236.195784 -352.094073)
			(xy 236.22987 -352.04993) (xy 236.270019 -352.011221) (xy 236.315377 -351.97877) (xy 236.364977 -351.953269)
			(xy 236.417761 -351.935262) (xy 236.472604 -351.925132) (xy 236.528338 -351.923095) (xy 236.583775 -351.929195)
			(xy 236.637732 -351.943301) (xy 236.689061 -351.965113) (xy 236.736667 -351.994167) (xy 236.779535 -352.029842)
			(xy 236.816752 -352.071379) (xy 236.847525 -352.117892) (xy 236.871197 -352.168389) (xy 236.887265 -352.221796)
			(xy 236.895385 -352.276972) (xy 236.895894 -352.304858) (xy 236.895385 -352.332744) (xy 236.887265 -352.38792)
			(xy 236.883598 -352.400108) (xy 241.607846 -352.400108) (xy 241.611917 -352.344486) (xy 241.624043 -352.290049)
			(xy 241.643966 -352.237958) (xy 241.671262 -352.189323) (xy 241.705348 -352.14518) (xy 241.745497 -352.106471)
			(xy 241.790855 -352.07402) (xy 241.840455 -352.048519) (xy 241.893239 -352.030512) (xy 241.948082 -352.020382)
			(xy 242.003816 -352.018345) (xy 242.059253 -352.024445) (xy 242.11321 -352.038551) (xy 242.164539 -352.060363)
			(xy 242.179346 -352.0694) (xy 248.537476 -352.0694) (xy 248.537962 -352.042149) (xy 248.545718 -351.988201)
			(xy 248.561073 -351.935906) (xy 248.583715 -351.886329) (xy 248.613181 -351.840479) (xy 248.648872 -351.799288)
			(xy 248.690063 -351.763597) (xy 248.735913 -351.734131) (xy 248.78549 -351.711489) (xy 248.837785 -351.696134)
			(xy 248.891733 -351.688378) (xy 248.946235 -351.688378) (xy 249.000183 -351.696134) (xy 249.052478 -351.711489)
			(xy 249.102055 -351.734131) (xy 249.147905 -351.763597) (xy 249.189096 -351.799288) (xy 249.224787 -351.840479)
			(xy 249.254253 -351.886329) (xy 249.276895 -351.935906) (xy 249.29225 -351.988201) (xy 249.300006 -352.042149)
			(xy 249.300492 -352.0694) (xy 249.30006 -352.09683) (xy 249.292182 -352.151123) (xy 249.276617 -352.20373)
			(xy 249.253686 -352.253569) (xy 249.223861 -352.299614) (xy 249.187754 -352.340918) (xy 249.146109 -352.376632)
			(xy 249.1232 -352.391726) (xy 249.11084 -352.400294) (xy 249.091263 -352.423097) (xy 249.079171 -352.45061)
			(xy 249.07561 -352.480453) (xy 249.080889 -352.510039) (xy 249.094552 -352.536808) (xy 249.115414 -352.558442)
			(xy 249.12828 -352.566224) (xy 249.153419 -352.580761) (xy 249.199351 -352.616288) (xy 249.239371 -352.658364)
			(xy 249.272556 -352.706016) (xy 249.29814 -352.758145) (xy 249.315532 -352.813548) (xy 249.324332 -352.870946)
			(xy 249.324876 -352.89998) (xy 249.32439 -352.927231) (xy 249.316634 -352.981179) (xy 249.301279 -353.033474)
			(xy 249.278637 -353.083051) (xy 249.249171 -353.128901) (xy 249.21348 -353.170092) (xy 249.172289 -353.205783)
			(xy 249.126439 -353.235249) (xy 249.076862 -353.257891) (xy 249.024567 -353.273246) (xy 248.970619 -353.281002)
			(xy 248.916117 -353.281002) (xy 248.862169 -353.273246) (xy 248.809874 -353.257891) (xy 248.760297 -353.235249)
			(xy 248.714447 -353.205783) (xy 248.673256 -353.170092) (xy 248.637565 -353.128901) (xy 248.608099 -353.083051)
			(xy 248.585457 -353.033474) (xy 248.570102 -352.981179) (xy 248.562346 -352.927231) (xy 248.56186 -352.89998)
			(xy 248.562376 -352.872553) (xy 248.570242 -352.818265) (xy 248.585793 -352.765661) (xy 248.608711 -352.715823)
			(xy 248.638523 -352.669777) (xy 248.674617 -352.62847) (xy 248.716249 -352.592751) (xy 248.739152 -352.577654)
			(xy 248.751525 -352.569107) (xy 248.771093 -352.546296) (xy 248.783177 -352.518779) (xy 248.786733 -352.488937)
			(xy 248.781453 -352.45935) (xy 248.767793 -352.43258) (xy 248.746936 -352.410942) (xy 248.734072 -352.403156)
			(xy 248.708914 -352.388652) (xy 248.662984 -352.353117) (xy 248.622966 -352.311035) (xy 248.589784 -352.263378)
			(xy 248.564204 -352.211244) (xy 248.546815 -352.155837) (xy 248.538019 -352.098436) (xy 248.537476 -352.0694)
			(xy 242.179346 -352.0694) (xy 242.212145 -352.089417) (xy 242.255013 -352.125092) (xy 242.29223 -352.166629)
			(xy 242.323003 -352.213142) (xy 242.346675 -352.263639) (xy 242.362743 -352.317046) (xy 242.370863 -352.372222)
			(xy 242.371372 -352.400108) (xy 242.370863 -352.427994) (xy 242.362743 -352.48317) (xy 242.346675 -352.536577)
			(xy 242.323003 -352.587074) (xy 242.29223 -352.633587) (xy 242.255013 -352.675124) (xy 242.212145 -352.710799)
			(xy 242.164539 -352.739853) (xy 242.11321 -352.761665) (xy 242.059253 -352.775771) (xy 242.003816 -352.781871)
			(xy 241.948082 -352.779834) (xy 241.893239 -352.769704) (xy 241.840455 -352.751697) (xy 241.790855 -352.726196)
			(xy 241.745497 -352.693745) (xy 241.705348 -352.655036) (xy 241.671262 -352.610893) (xy 241.643966 -352.562258)
			(xy 241.624043 -352.510167) (xy 241.611917 -352.45573) (xy 241.607846 -352.400108) (xy 236.883598 -352.400108)
			(xy 236.871197 -352.441327) (xy 236.847525 -352.491824) (xy 236.816752 -352.538337) (xy 236.779535 -352.579874)
			(xy 236.736667 -352.615549) (xy 236.689061 -352.644603) (xy 236.637732 -352.666415) (xy 236.583775 -352.680521)
			(xy 236.528338 -352.686621) (xy 236.472604 -352.684584) (xy 236.417761 -352.674454) (xy 236.364977 -352.656447)
			(xy 236.315377 -352.630946) (xy 236.270019 -352.598495) (xy 236.22987 -352.559786) (xy 236.195784 -352.515643)
			(xy 236.168488 -352.467008) (xy 236.148565 -352.414917) (xy 236.136439 -352.36048) (xy 236.132368 -352.304858)
			(xy 234.152892 -352.304858) (xy 234.152948 -352.307906) (xy 234.152439 -352.335792) (xy 234.144319 -352.390968)
			(xy 234.128251 -352.444375) (xy 234.104579 -352.494872) (xy 234.073806 -352.541385) (xy 234.036589 -352.582922)
			(xy 233.993721 -352.618597) (xy 233.946115 -352.647651) (xy 233.894786 -352.669463) (xy 233.840829 -352.683569)
			(xy 233.785392 -352.689669) (xy 233.729658 -352.687632) (xy 233.674815 -352.677502) (xy 233.622031 -352.659495)
			(xy 233.572431 -352.633994) (xy 233.527073 -352.601543) (xy 233.486924 -352.562834) (xy 233.452838 -352.518691)
			(xy 233.425542 -352.470056) (xy 233.405619 -352.417965) (xy 233.393493 -352.363528) (xy 233.389422 -352.307906)
			(xy 149.315424 -352.307906) (xy 149.315424 -353.270058) (xy 236.132368 -353.270058) (xy 236.136439 -353.214436)
			(xy 236.148565 -353.159999) (xy 236.168488 -353.107908) (xy 236.195784 -353.059273) (xy 236.22987 -353.01513)
			(xy 236.270019 -352.976421) (xy 236.315377 -352.94397) (xy 236.364977 -352.918469) (xy 236.417761 -352.900462)
			(xy 236.472604 -352.890332) (xy 236.528338 -352.888295) (xy 236.583775 -352.894395) (xy 236.637732 -352.908501)
			(xy 236.689061 -352.930313) (xy 236.736667 -352.959367) (xy 236.779535 -352.995042) (xy 236.816752 -353.036579)
			(xy 236.847525 -353.083092) (xy 236.871197 -353.133589) (xy 236.887265 -353.186996) (xy 236.895385 -353.242172)
			(xy 236.895894 -353.270058) (xy 236.895385 -353.297944) (xy 236.887265 -353.35312) (xy 236.873129 -353.400106)
			(xy 241.556538 -353.400106) (xy 241.560609 -353.344484) (xy 241.572735 -353.290047) (xy 241.592658 -353.237956)
			(xy 241.619954 -353.189321) (xy 241.65404 -353.145178) (xy 241.694189 -353.106469) (xy 241.739547 -353.074018)
			(xy 241.789147 -353.048517) (xy 241.841931 -353.03051) (xy 241.896774 -353.02038) (xy 241.952508 -353.018343)
			(xy 242.007945 -353.024443) (xy 242.061902 -353.038549) (xy 242.113231 -353.060361) (xy 242.160837 -353.089415)
			(xy 242.203705 -353.12509) (xy 242.240922 -353.166627) (xy 242.271695 -353.21314) (xy 242.295367 -353.263637)
			(xy 242.311435 -353.317044) (xy 242.319555 -353.37222) (xy 242.320064 -353.400106) (xy 242.319555 -353.427992)
			(xy 242.311435 -353.483168) (xy 242.295367 -353.536575) (xy 242.271695 -353.587072) (xy 242.240922 -353.633585)
			(xy 242.203705 -353.675122) (xy 242.160837 -353.710797) (xy 242.113231 -353.739851) (xy 242.061902 -353.761663)
			(xy 242.007945 -353.775769) (xy 241.952508 -353.781869) (xy 241.896774 -353.779832) (xy 241.841931 -353.769702)
			(xy 241.789147 -353.751695) (xy 241.739547 -353.726194) (xy 241.694189 -353.693743) (xy 241.65404 -353.655034)
			(xy 241.619954 -353.610891) (xy 241.592658 -353.562256) (xy 241.572735 -353.510165) (xy 241.560609 -353.455728)
			(xy 241.556538 -353.400106) (xy 236.873129 -353.400106) (xy 236.871197 -353.406527) (xy 236.847525 -353.457024)
			(xy 236.816752 -353.503537) (xy 236.779535 -353.545074) (xy 236.736667 -353.580749) (xy 236.689061 -353.609803)
			(xy 236.637732 -353.631615) (xy 236.583775 -353.645721) (xy 236.528338 -353.651821) (xy 236.472604 -353.649784)
			(xy 236.417761 -353.639654) (xy 236.364977 -353.621647) (xy 236.315377 -353.596146) (xy 236.270019 -353.563695)
			(xy 236.22987 -353.524986) (xy 236.195784 -353.480843) (xy 236.168488 -353.432208) (xy 236.148565 -353.380117)
			(xy 236.136439 -353.32568) (xy 236.132368 -353.270058) (xy 149.315424 -353.270058) (xy 149.315424 -354.235258)
			(xy 236.132368 -354.235258) (xy 236.136439 -354.179636) (xy 236.148565 -354.125199) (xy 236.168488 -354.073108)
			(xy 236.195784 -354.024473) (xy 236.22987 -353.98033) (xy 236.270019 -353.941621) (xy 236.315377 -353.90917)
			(xy 236.364977 -353.883669) (xy 236.417761 -353.865662) (xy 236.472604 -353.855532) (xy 236.528338 -353.853495)
			(xy 236.583775 -353.859595) (xy 236.637732 -353.873701) (xy 236.689061 -353.895513) (xy 236.696793 -353.900232)
			(xy 248.573288 -353.900232) (xy 248.577359 -353.84461) (xy 248.589485 -353.790173) (xy 248.609408 -353.738082)
			(xy 248.636704 -353.689447) (xy 248.67079 -353.645304) (xy 248.710939 -353.606595) (xy 248.756297 -353.574144)
			(xy 248.805897 -353.548643) (xy 248.858681 -353.530636) (xy 248.913524 -353.520506) (xy 248.969258 -353.518469)
			(xy 249.024695 -353.524569) (xy 249.078652 -353.538675) (xy 249.129981 -353.560487) (xy 249.177587 -353.589541)
			(xy 249.220455 -353.625216) (xy 249.257672 -353.666753) (xy 249.288445 -353.713266) (xy 249.312117 -353.763763)
			(xy 249.328185 -353.81717) (xy 249.336305 -353.872346) (xy 249.336814 -353.900232) (xy 249.336305 -353.928118)
			(xy 249.328185 -353.983294) (xy 249.312117 -354.036701) (xy 249.288445 -354.087198) (xy 249.257672 -354.133711)
			(xy 249.220455 -354.175248) (xy 249.177587 -354.210923) (xy 249.129981 -354.239977) (xy 249.078652 -354.261789)
			(xy 249.024695 -354.275895) (xy 248.969258 -354.281995) (xy 248.913524 -354.279958) (xy 248.858681 -354.269828)
			(xy 248.805897 -354.251821) (xy 248.756297 -354.22632) (xy 248.710939 -354.193869) (xy 248.67079 -354.15516)
			(xy 248.636704 -354.111017) (xy 248.609408 -354.062382) (xy 248.589485 -354.010291) (xy 248.577359 -353.955854)
			(xy 248.573288 -353.900232) (xy 236.696793 -353.900232) (xy 236.736667 -353.924567) (xy 236.779535 -353.960242)
			(xy 236.816752 -354.001779) (xy 236.847525 -354.048292) (xy 236.871197 -354.098789) (xy 236.887265 -354.152196)
			(xy 236.895385 -354.207372) (xy 236.895894 -354.235258) (xy 236.895385 -354.263144) (xy 236.887265 -354.31832)
			(xy 236.871197 -354.371727) (xy 236.857894 -354.400104) (xy 241.526312 -354.400104) (xy 241.530383 -354.344482)
			(xy 241.542509 -354.290045) (xy 241.562432 -354.237954) (xy 241.589728 -354.189319) (xy 241.623814 -354.145176)
			(xy 241.663963 -354.106467) (xy 241.709321 -354.074016) (xy 241.758921 -354.048515) (xy 241.811705 -354.030508)
			(xy 241.866548 -354.020378) (xy 241.922282 -354.018341) (xy 241.977719 -354.024441) (xy 242.031676 -354.038547)
			(xy 242.083005 -354.060359) (xy 242.130611 -354.089413) (xy 242.173479 -354.125088) (xy 242.210696 -354.166625)
			(xy 242.241469 -354.213138) (xy 242.265141 -354.263635) (xy 242.281209 -354.317042) (xy 242.289329 -354.372218)
			(xy 242.289838 -354.400104) (xy 242.289329 -354.42799) (xy 242.281209 -354.483166) (xy 242.265141 -354.536573)
			(xy 242.241469 -354.58707) (xy 242.210696 -354.633583) (xy 242.173479 -354.67512) (xy 242.130611 -354.710795)
			(xy 242.083005 -354.739849) (xy 242.031676 -354.761661) (xy 241.977719 -354.775767) (xy 241.922282 -354.781867)
			(xy 241.866548 -354.77983) (xy 241.811705 -354.7697) (xy 241.758921 -354.751693) (xy 241.709321 -354.726192)
			(xy 241.663963 -354.693741) (xy 241.623814 -354.655032) (xy 241.589728 -354.610889) (xy 241.562432 -354.562254)
			(xy 241.542509 -354.510163) (xy 241.530383 -354.455726) (xy 241.526312 -354.400104) (xy 236.857894 -354.400104)
			(xy 236.847525 -354.422224) (xy 236.816752 -354.468737) (xy 236.779535 -354.510274) (xy 236.736667 -354.545949)
			(xy 236.689061 -354.575003) (xy 236.637732 -354.596815) (xy 236.583775 -354.610921) (xy 236.528338 -354.617021)
			(xy 236.472604 -354.614984) (xy 236.417761 -354.604854) (xy 236.364977 -354.586847) (xy 236.315377 -354.561346)
			(xy 236.270019 -354.528895) (xy 236.22987 -354.490186) (xy 236.195784 -354.446043) (xy 236.168488 -354.397408)
			(xy 236.148565 -354.345317) (xy 236.136439 -354.29088) (xy 236.132368 -354.235258) (xy 149.315424 -354.235258)
			(xy 149.315424 -354.759368) (xy 158.695906 -354.759368) (xy 158.695906 -354.704832) (xy 158.703667 -354.65085)
			(xy 158.719031 -354.598521) (xy 158.741685 -354.548912) (xy 158.771167 -354.503031) (xy 158.806879 -354.461813)
			(xy 158.848093 -354.426096) (xy 158.89397 -354.396608) (xy 158.943576 -354.373948) (xy 158.995903 -354.358577)
			(xy 159.049884 -354.35081) (xy 159.077152 -354.35032) (xy 159.940752 -354.35032) (xy 159.968024 -354.350816)
			(xy 160.022013 -354.358572) (xy 160.074349 -354.373934) (xy 160.123966 -354.396588) (xy 160.169854 -354.426072)
			(xy 160.211078 -354.461788) (xy 160.246799 -354.503008) (xy 160.276289 -354.548891) (xy 160.298949 -354.598506)
			(xy 160.314317 -354.65084) (xy 160.32208 -354.704828) (xy 160.32208 -354.759372) (xy 160.32208 -354.759373)
			(xy 161.804784 -354.759373) (xy 161.804784 -354.704827) (xy 161.812546 -354.650837) (xy 161.827914 -354.598501)
			(xy 161.850573 -354.548884) (xy 161.880064 -354.502998) (xy 161.915784 -354.461776) (xy 161.957008 -354.426056)
			(xy 162.002895 -354.396568) (xy 162.052512 -354.37391) (xy 162.104848 -354.358544) (xy 162.158839 -354.350783)
			(xy 162.186112 -354.35032) (xy 163.049712 -354.35032) (xy 163.07698 -354.350843) (xy 163.130959 -354.358606)
			(xy 163.183285 -354.373972) (xy 163.232891 -354.396627) (xy 163.278768 -354.426112) (xy 163.319983 -354.461826)
			(xy 163.355695 -354.503041) (xy 163.385178 -354.548919) (xy 163.407833 -354.598526) (xy 163.423197 -354.650852)
			(xy 163.430958 -354.704832) (xy 163.430958 -354.759368) (xy 163.430958 -354.759369) (xy 164.913806 -354.759369)
			(xy 164.913806 -354.704831) (xy 164.921568 -354.650847) (xy 164.936932 -354.598517) (xy 164.959588 -354.548907)
			(xy 164.989072 -354.503025) (xy 165.024786 -354.461806) (xy 165.066002 -354.426089) (xy 165.111882 -354.396601)
			(xy 165.161491 -354.373942) (xy 165.21382 -354.358574) (xy 165.267803 -354.350808) (xy 165.295072 -354.35032)
			(xy 166.158672 -354.35032) (xy 166.185943 -354.350818) (xy 166.23993 -354.358576) (xy 166.292264 -354.373939)
			(xy 166.341878 -354.396594) (xy 166.387763 -354.42608) (xy 166.428985 -354.461795) (xy 166.464704 -354.503014)
			(xy 166.494192 -354.548897) (xy 166.516851 -354.59851) (xy 166.532218 -354.650842) (xy 166.53998 -354.704829)
			(xy 166.53998 -354.759371) (xy 166.53998 -354.759374) (xy 168.022684 -354.759374) (xy 168.022684 -354.704826)
			(xy 168.030447 -354.650834) (xy 168.045816 -354.598496) (xy 168.068477 -354.548879) (xy 168.097969 -354.502991)
			(xy 168.133691 -354.461768) (xy 168.174917 -354.426049) (xy 168.220807 -354.396561) (xy 168.270426 -354.373904)
			(xy 168.322765 -354.35854) (xy 168.376758 -354.350781) (xy 168.404032 -354.35032) (xy 169.267632 -354.35032)
			(xy 169.294899 -354.350845) (xy 169.348876 -354.35861) (xy 169.401199 -354.373977) (xy 169.450803 -354.396634)
			(xy 169.496678 -354.426119) (xy 169.53789 -354.461833) (xy 169.5736 -354.503048) (xy 169.603081 -354.548925)
			(xy 169.625734 -354.598531) (xy 169.641097 -354.650855) (xy 169.648858 -354.704833) (xy 169.648858 -354.759367)
			(xy 169.648858 -354.75937) (xy 171.131706 -354.75937) (xy 171.131706 -354.70483) (xy 171.139468 -354.650844)
			(xy 171.154834 -354.598513) (xy 171.177491 -354.548901) (xy 171.206977 -354.503018) (xy 171.242693 -354.461799)
			(xy 171.283912 -354.426082) (xy 171.329794 -354.396594) (xy 171.379405 -354.373937) (xy 171.431736 -354.35857)
			(xy 171.485722 -354.350807) (xy 171.512992 -354.35032) (xy 172.376592 -354.35032) (xy 172.403862 -354.350819)
			(xy 172.457847 -354.35858) (xy 172.510178 -354.373945) (xy 172.55979 -354.396601) (xy 172.605673 -354.426087)
			(xy 172.646892 -354.461802) (xy 172.682609 -354.503021) (xy 172.712096 -354.548903) (xy 172.734753 -354.598514)
			(xy 172.750119 -354.650845) (xy 172.757881 -354.70483) (xy 172.757881 -354.759368) (xy 174.240706 -354.759368)
			(xy 174.240706 -354.704832) (xy 174.248467 -354.65085) (xy 174.263831 -354.598521) (xy 174.286485 -354.548912)
			(xy 174.315967 -354.503031) (xy 174.351679 -354.461813) (xy 174.392893 -354.426096) (xy 174.43877 -354.396608)
			(xy 174.488376 -354.373948) (xy 174.540703 -354.358577) (xy 174.594684 -354.35081) (xy 174.621952 -354.35032)
			(xy 175.485552 -354.35032) (xy 175.512824 -354.350816) (xy 175.566813 -354.358572) (xy 175.619149 -354.373934)
			(xy 175.668766 -354.396588) (xy 175.714654 -354.426072) (xy 175.755878 -354.461788) (xy 175.791599 -354.503008)
			(xy 175.821089 -354.548891) (xy 175.843749 -354.598506) (xy 175.859117 -354.65084) (xy 175.86688 -354.704828)
			(xy 175.86688 -354.759372) (xy 175.86688 -354.759373) (xy 177.349584 -354.759373) (xy 177.349584 -354.704827)
			(xy 177.357346 -354.650837) (xy 177.372714 -354.598501) (xy 177.395373 -354.548884) (xy 177.424864 -354.502998)
			(xy 177.460584 -354.461776) (xy 177.501808 -354.426056) (xy 177.547695 -354.396568) (xy 177.597312 -354.37391)
			(xy 177.649648 -354.358544) (xy 177.703639 -354.350783) (xy 177.730912 -354.35032) (xy 178.594512 -354.35032)
			(xy 178.62178 -354.350843) (xy 178.675759 -354.358606) (xy 178.728085 -354.373972) (xy 178.777691 -354.396627)
			(xy 178.823568 -354.426112) (xy 178.864783 -354.461826) (xy 178.900495 -354.503041) (xy 178.929978 -354.548919)
			(xy 178.952633 -354.598526) (xy 178.967997 -354.650852) (xy 178.975758 -354.704832) (xy 178.975758 -354.759368)
			(xy 178.975758 -354.759369) (xy 180.458606 -354.759369) (xy 180.458606 -354.704831) (xy 180.466368 -354.650847)
			(xy 180.481732 -354.598517) (xy 180.504388 -354.548907) (xy 180.533872 -354.503025) (xy 180.569586 -354.461806)
			(xy 180.610802 -354.426089) (xy 180.656682 -354.396601) (xy 180.706291 -354.373942) (xy 180.75862 -354.358574)
			(xy 180.812603 -354.350808) (xy 180.839872 -354.35032) (xy 181.703472 -354.35032) (xy 181.730743 -354.350818)
			(xy 181.78473 -354.358576) (xy 181.837064 -354.373939) (xy 181.886678 -354.396594) (xy 181.932563 -354.42608)
			(xy 181.973785 -354.461795) (xy 182.009504 -354.503014) (xy 182.038992 -354.548897) (xy 182.061651 -354.59851)
			(xy 182.077018 -354.650842) (xy 182.08478 -354.704829) (xy 182.08478 -354.735472) (xy 183.567508 -354.735472)
			(xy 183.567508 -354.680928) (xy 183.57527 -354.626939) (xy 183.590638 -354.574605) (xy 183.613298 -354.52499)
			(xy 183.642788 -354.479106) (xy 183.678508 -354.437885) (xy 183.719731 -354.402169) (xy 183.765618 -354.372682)
			(xy 183.815235 -354.350027) (xy 183.86757 -354.334664) (xy 183.92156 -354.326905) (xy 183.948832 -354.326444)
			(xy 184.812432 -354.326444) (xy 184.8397 -354.326921) (xy 184.893681 -354.334686) (xy 184.946008 -354.350054)
			(xy 184.995615 -354.372713) (xy 185.041492 -354.4022) (xy 185.082707 -354.437916) (xy 185.118419 -354.479133)
			(xy 185.147903 -354.525013) (xy 185.170557 -354.574622) (xy 185.185921 -354.62695) (xy 185.193682 -354.680932)
			(xy 185.193682 -354.735468) (xy 185.193682 -354.735469) (xy 186.67653 -354.735469) (xy 186.67653 -354.680931)
			(xy 186.684292 -354.626949) (xy 186.699656 -354.574621) (xy 186.722312 -354.525012) (xy 186.751796 -354.479133)
			(xy 186.78751 -354.437916) (xy 186.828726 -354.402201) (xy 186.874605 -354.372716) (xy 186.924214 -354.350059)
			(xy 186.976542 -354.334693) (xy 187.030523 -354.326931) (xy 187.057792 -354.326444) (xy 187.921392 -354.326444)
			(xy 187.948664 -354.326895) (xy 188.002652 -354.334656) (xy 188.054987 -354.350022) (xy 188.104602 -354.37268)
			(xy 188.150487 -354.402167) (xy 188.191709 -354.437885) (xy 188.227428 -354.479106) (xy 188.256917 -354.524991)
			(xy 188.279575 -354.574606) (xy 188.294942 -354.62694) (xy 188.302704 -354.680928) (xy 188.302704 -354.735472)
			(xy 188.294942 -354.78946) (xy 188.279575 -354.841794) (xy 188.256917 -354.891409) (xy 188.227428 -354.937294)
			(xy 188.191709 -354.978515) (xy 188.15161 -355.01326) (xy 201.179174 -355.01326) (xy 201.183245 -354.957638)
			(xy 201.195371 -354.903201) (xy 201.215294 -354.85111) (xy 201.24259 -354.802475) (xy 201.276676 -354.758332)
			(xy 201.316825 -354.719623) (xy 201.362183 -354.687172) (xy 201.411783 -354.661671) (xy 201.464567 -354.643664)
			(xy 201.51941 -354.633534) (xy 201.575144 -354.631497) (xy 201.630581 -354.637597) (xy 201.684538 -354.651703)
			(xy 201.735867 -354.673515) (xy 201.783473 -354.702569) (xy 201.826341 -354.738244) (xy 201.863558 -354.779781)
			(xy 201.894331 -354.826294) (xy 201.918003 -354.876791) (xy 201.934071 -354.930198) (xy 201.942191 -354.985374)
			(xy 201.9427 -355.01326) (xy 201.942191 -355.041146) (xy 201.934071 -355.096322) (xy 201.918003 -355.149729)
			(xy 201.894331 -355.200226) (xy 201.894178 -355.200458) (xy 236.132368 -355.200458) (xy 236.136439 -355.144836)
			(xy 236.148565 -355.090399) (xy 236.168488 -355.038308) (xy 236.195784 -354.989673) (xy 236.22987 -354.94553)
			(xy 236.270019 -354.906821) (xy 236.315377 -354.87437) (xy 236.364977 -354.848869) (xy 236.417761 -354.830862)
			(xy 236.472604 -354.820732) (xy 236.528338 -354.818695) (xy 236.583775 -354.824795) (xy 236.637732 -354.838901)
			(xy 236.689061 -354.860713) (xy 236.736667 -354.889767) (xy 236.779535 -354.925442) (xy 236.816752 -354.966979)
			(xy 236.847525 -355.013492) (xy 236.871197 -355.063989) (xy 236.887265 -355.117396) (xy 236.895385 -355.172572)
			(xy 236.895894 -355.200458) (xy 238.265968 -355.200458) (xy 238.270039 -355.144836) (xy 238.282165 -355.090399)
			(xy 238.302088 -355.038308) (xy 238.329384 -354.989673) (xy 238.36347 -354.94553) (xy 238.403619 -354.906821)
			(xy 238.448977 -354.87437) (xy 238.498577 -354.848869) (xy 238.551361 -354.830862) (xy 238.606204 -354.820732)
			(xy 238.661938 -354.818695) (xy 238.717375 -354.824795) (xy 238.771332 -354.838901) (xy 238.822661 -354.860713)
			(xy 238.870267 -354.889767) (xy 238.88284 -354.90023) (xy 248.54992 -354.90023) (xy 248.553991 -354.844608)
			(xy 248.566117 -354.790171) (xy 248.58604 -354.73808) (xy 248.613336 -354.689445) (xy 248.647422 -354.645302)
			(xy 248.687571 -354.606593) (xy 248.732929 -354.574142) (xy 248.782529 -354.548641) (xy 248.835313 -354.530634)
			(xy 248.890156 -354.520504) (xy 248.94589 -354.518467) (xy 249.001327 -354.524567) (xy 249.055284 -354.538673)
			(xy 249.106613 -354.560485) (xy 249.154219 -354.589539) (xy 249.197087 -354.625214) (xy 249.234304 -354.666751)
			(xy 249.265077 -354.713264) (xy 249.28669 -354.759369) (xy 270.624806 -354.759369) (xy 270.624806 -354.704831)
			(xy 270.632567 -354.650848) (xy 270.647932 -354.598519) (xy 270.670586 -354.548909) (xy 270.70007 -354.503028)
			(xy 270.735783 -354.46181) (xy 270.776998 -354.426093) (xy 270.822876 -354.396604) (xy 270.872484 -354.373945)
			(xy 270.924811 -354.358575) (xy 270.978793 -354.350809) (xy 271.006062 -354.35032) (xy 271.869662 -354.35032)
			(xy 271.896933 -354.350817) (xy 271.950922 -354.358574) (xy 272.003257 -354.373936) (xy 272.052872 -354.396591)
			(xy 272.098759 -354.426076) (xy 272.139981 -354.461792) (xy 272.175701 -354.503011) (xy 272.205191 -354.548894)
			(xy 272.22785 -354.598508) (xy 272.243218 -354.650841) (xy 272.25098 -354.704829) (xy 272.25098 -354.759371)
			(xy 272.25098 -354.759373) (xy 273.733684 -354.759373) (xy 273.733684 -354.704827) (xy 273.741447 -354.650835)
			(xy 273.756815 -354.598498) (xy 273.779475 -354.548882) (xy 273.808966 -354.502995) (xy 273.844688 -354.461772)
			(xy 273.885912 -354.426053) (xy 273.931801 -354.396564) (xy 273.981419 -354.373907) (xy 274.033757 -354.358542)
			(xy 274.087749 -354.350782) (xy 274.115022 -354.35032) (xy 274.978622 -354.35032) (xy 275.005889 -354.350844)
			(xy 275.059868 -354.358608) (xy 275.112192 -354.373974) (xy 275.161797 -354.396631) (xy 275.207673 -354.426116)
			(xy 275.248886 -354.461829) (xy 275.284597 -354.503044) (xy 275.31408 -354.548922) (xy 275.336733 -354.598528)
			(xy 275.352097 -354.650854) (xy 275.359858 -354.704833) (xy 275.359858 -354.759367) (xy 275.359858 -354.75937)
			(xy 276.842706 -354.75937) (xy 276.842706 -354.70483) (xy 276.850468 -354.650846) (xy 276.865833 -354.598515)
			(xy 276.888489 -354.548904) (xy 276.917975 -354.503022) (xy 276.95369 -354.461802) (xy 276.994907 -354.426085)
			(xy 277.040788 -354.396598) (xy 277.090398 -354.373939) (xy 277.142728 -354.358572) (xy 277.196712 -354.350808)
			(xy 277.223982 -354.35032) (xy 278.087582 -354.35032) (xy 278.114853 -354.350818) (xy 278.168839 -354.358578)
			(xy 278.221171 -354.373942) (xy 278.270784 -354.396597) (xy 278.316668 -354.426083) (xy 278.357888 -354.461799)
			(xy 278.393606 -354.503018) (xy 278.423094 -354.5489) (xy 278.445752 -354.598512) (xy 278.461118 -354.650844)
			(xy 278.468881 -354.704829) (xy 278.468881 -354.759371) (xy 278.468881 -354.759374) (xy 279.951584 -354.759374)
			(xy 279.951584 -354.704826) (xy 279.959347 -354.650833) (xy 279.974716 -354.598494) (xy 279.997378 -354.548876)
			(xy 280.026871 -354.502988) (xy 280.062595 -354.461765) (xy 280.103822 -354.426046) (xy 280.149713 -354.396558)
			(xy 280.199334 -354.373902) (xy 280.251674 -354.358538) (xy 280.305668 -354.350781) (xy 280.332942 -354.35032)
			(xy 281.196542 -354.35032) (xy 281.223808 -354.350845) (xy 281.277785 -354.358611) (xy 281.330107 -354.37398)
			(xy 281.379709 -354.396637) (xy 281.425583 -354.426123) (xy 281.466793 -354.461836) (xy 281.502502 -354.503051)
			(xy 281.531983 -354.548928) (xy 281.554635 -354.598533) (xy 281.569998 -354.650856) (xy 281.577758 -354.704834)
			(xy 281.577758 -354.759366) (xy 281.577757 -354.759372) (xy 283.060584 -354.759372) (xy 283.060584 -354.704828)
			(xy 283.068346 -354.650838) (xy 283.083713 -354.598503) (xy 283.106372 -354.548887) (xy 283.135861 -354.503001)
			(xy 283.171581 -354.461779) (xy 283.212803 -354.42606) (xy 283.258689 -354.396571) (xy 283.308305 -354.373912)
			(xy 283.36064 -354.358546) (xy 283.41463 -354.350783) (xy 283.441902 -354.35032) (xy 284.305502 -354.35032)
			(xy 284.33277 -354.350843) (xy 284.386751 -354.358604) (xy 284.439078 -354.373969) (xy 284.488685 -354.396624)
			(xy 284.534564 -354.426109) (xy 284.575779 -354.461822) (xy 284.611493 -354.503038) (xy 284.640977 -354.548917)
			(xy 284.663632 -354.598524) (xy 284.678996 -354.650851) (xy 284.686758 -354.704832) (xy 284.686758 -354.759368)
			(xy 284.686758 -354.759369) (xy 286.169606 -354.759369) (xy 286.169606 -354.704831) (xy 286.177367 -354.650848)
			(xy 286.192732 -354.598519) (xy 286.215386 -354.548909) (xy 286.24487 -354.503028) (xy 286.280583 -354.46181)
			(xy 286.321798 -354.426093) (xy 286.367676 -354.396604) (xy 286.417284 -354.373945) (xy 286.469611 -354.358575)
			(xy 286.523593 -354.350809) (xy 286.550862 -354.35032) (xy 287.414462 -354.35032) (xy 287.441733 -354.350817)
			(xy 287.495722 -354.358574) (xy 287.548057 -354.373936) (xy 287.597672 -354.396591) (xy 287.643559 -354.426076)
			(xy 287.684781 -354.461792) (xy 287.720501 -354.503011) (xy 287.749991 -354.548894) (xy 287.77265 -354.598508)
			(xy 287.788018 -354.650841) (xy 287.79578 -354.704829) (xy 287.79578 -354.759371) (xy 287.79578 -354.759373)
			(xy 289.278484 -354.759373) (xy 289.278484 -354.704827) (xy 289.286247 -354.650835) (xy 289.301615 -354.598498)
			(xy 289.324275 -354.548882) (xy 289.353766 -354.502995) (xy 289.389488 -354.461772) (xy 289.430712 -354.426053)
			(xy 289.476601 -354.396564) (xy 289.526219 -354.373907) (xy 289.578557 -354.358542) (xy 289.632549 -354.350782)
			(xy 289.659822 -354.35032) (xy 290.523422 -354.35032) (xy 290.550689 -354.350844) (xy 290.604668 -354.358608)
			(xy 290.656992 -354.373974) (xy 290.706597 -354.396631) (xy 290.752473 -354.426116) (xy 290.793686 -354.461829)
			(xy 290.829397 -354.503044) (xy 290.85888 -354.548922) (xy 290.881533 -354.598528) (xy 290.896897 -354.650854)
			(xy 290.904658 -354.704833) (xy 290.904658 -354.759367) (xy 290.904658 -354.75937) (xy 292.387506 -354.75937)
			(xy 292.387506 -354.70483) (xy 292.395268 -354.650846) (xy 292.410633 -354.598515) (xy 292.433289 -354.548904)
			(xy 292.462775 -354.503022) (xy 292.49849 -354.461802) (xy 292.539707 -354.426085) (xy 292.585588 -354.396598)
			(xy 292.635198 -354.373939) (xy 292.687528 -354.358572) (xy 292.741512 -354.350808) (xy 292.768782 -354.35032)
			(xy 293.632382 -354.35032) (xy 293.659653 -354.350818) (xy 293.713639 -354.358578) (xy 293.765971 -354.373942)
			(xy 293.815584 -354.396597) (xy 293.861468 -354.426083) (xy 293.902688 -354.461799) (xy 293.938406 -354.503018)
			(xy 293.967894 -354.5489) (xy 293.990552 -354.598512) (xy 294.005918 -354.650844) (xy 294.013681 -354.704829)
			(xy 294.013681 -354.759371) (xy 294.013681 -354.759374) (xy 295.496384 -354.759374) (xy 295.496384 -354.704826)
			(xy 295.504147 -354.650833) (xy 295.519516 -354.598494) (xy 295.542178 -354.548876) (xy 295.571671 -354.502988)
			(xy 295.607395 -354.461765) (xy 295.648622 -354.426046) (xy 295.694513 -354.396558) (xy 295.744134 -354.373902)
			(xy 295.796474 -354.358538) (xy 295.850468 -354.350781) (xy 295.877742 -354.35032) (xy 296.741342 -354.35032)
			(xy 296.768608 -354.350845) (xy 296.822585 -354.358611) (xy 296.874907 -354.37398) (xy 296.924509 -354.396637)
			(xy 296.970383 -354.426123) (xy 297.011593 -354.461836) (xy 297.047302 -354.503051) (xy 297.076783 -354.548928)
			(xy 297.099435 -354.598533) (xy 297.114798 -354.650856) (xy 297.122558 -354.704834) (xy 297.122558 -354.759366)
			(xy 297.122557 -354.759372) (xy 298.605384 -354.759372) (xy 298.605384 -354.704828) (xy 298.613146 -354.650838)
			(xy 298.628513 -354.598503) (xy 298.651172 -354.548887) (xy 298.680661 -354.503001) (xy 298.716381 -354.461779)
			(xy 298.757603 -354.42606) (xy 298.803489 -354.396571) (xy 298.853105 -354.373912) (xy 298.90544 -354.358546)
			(xy 298.95943 -354.350783) (xy 298.986702 -354.35032) (xy 299.850302 -354.35032) (xy 299.87757 -354.350843)
			(xy 299.931551 -354.358604) (xy 299.983878 -354.373969) (xy 300.033485 -354.396624) (xy 300.079364 -354.426109)
			(xy 300.120579 -354.461822) (xy 300.156293 -354.503038) (xy 300.185777 -354.548917) (xy 300.208432 -354.598524)
			(xy 300.223796 -354.650851) (xy 300.231558 -354.704832) (xy 300.231558 -354.759368) (xy 300.223796 -354.813349)
			(xy 300.208432 -354.865676) (xy 300.185777 -354.915283) (xy 300.156293 -354.961162) (xy 300.120579 -355.002378)
			(xy 300.079364 -355.038091) (xy 300.033485 -355.067576) (xy 299.983878 -355.090231) (xy 299.931551 -355.105596)
			(xy 299.87757 -355.113357) (xy 299.850302 -355.113844) (xy 298.986702 -355.113844) (xy 298.95943 -355.113417)
			(xy 298.90544 -355.105654) (xy 298.853105 -355.090288) (xy 298.803489 -355.067629) (xy 298.757603 -355.03814)
			(xy 298.716381 -355.002421) (xy 298.680661 -354.961199) (xy 298.651172 -354.915313) (xy 298.628513 -354.865697)
			(xy 298.613146 -354.813362) (xy 298.605384 -354.759372) (xy 297.122557 -354.759372) (xy 297.114798 -354.813344)
			(xy 297.099435 -354.865667) (xy 297.076783 -354.915272) (xy 297.047302 -354.961149) (xy 297.011593 -355.002364)
			(xy 296.970383 -355.038077) (xy 296.924509 -355.067563) (xy 296.874907 -355.09022) (xy 296.822585 -355.105589)
			(xy 296.768608 -355.113355) (xy 296.741342 -355.113844) (xy 295.877742 -355.113844) (xy 295.850468 -355.113419)
			(xy 295.796474 -355.105662) (xy 295.744134 -355.090298) (xy 295.694513 -355.067642) (xy 295.648622 -355.038154)
			(xy 295.607395 -355.002435) (xy 295.571671 -354.961212) (xy 295.542178 -354.915324) (xy 295.519516 -354.865706)
			(xy 295.504147 -354.813367) (xy 295.496384 -354.759374) (xy 294.013681 -354.759374) (xy 294.005918 -354.813356)
			(xy 293.990552 -354.865688) (xy 293.967894 -354.9153) (xy 293.938406 -354.961182) (xy 293.902688 -355.002401)
			(xy 293.861468 -355.038117) (xy 293.815584 -355.067603) (xy 293.765971 -355.090258) (xy 293.713639 -355.105622)
			(xy 293.659653 -355.113382) (xy 293.632382 -355.113844) (xy 292.768782 -355.113844) (xy 292.741512 -355.113392)
			(xy 292.687528 -355.105628) (xy 292.635198 -355.090261) (xy 292.585588 -355.067602) (xy 292.539707 -355.038115)
			(xy 292.49849 -355.002398) (xy 292.462775 -354.961178) (xy 292.433289 -354.915296) (xy 292.410633 -354.865685)
			(xy 292.395268 -354.813354) (xy 292.387506 -354.75937) (xy 290.904658 -354.75937) (xy 290.896897 -354.813346)
			(xy 290.881533 -354.865672) (xy 290.85888 -354.915278) (xy 290.829397 -354.961156) (xy 290.793686 -355.002371)
			(xy 290.752473 -355.038084) (xy 290.706597 -355.067569) (xy 290.656992 -355.090226) (xy 290.604668 -355.105592)
			(xy 290.550689 -355.113356) (xy 290.523422 -355.113844) (xy 289.659822 -355.113844) (xy 289.632549 -355.113418)
			(xy 289.578557 -355.105658) (xy 289.526219 -355.090293) (xy 289.476601 -355.067636) (xy 289.430712 -355.038147)
			(xy 289.389488 -355.002428) (xy 289.353766 -354.961205) (xy 289.324275 -354.915318) (xy 289.301615 -354.865702)
			(xy 289.286247 -354.813365) (xy 289.278484 -354.759373) (xy 287.79578 -354.759373) (xy 287.788018 -354.813359)
			(xy 287.77265 -354.865692) (xy 287.749991 -354.915306) (xy 287.720501 -354.961189) (xy 287.684781 -355.002408)
			(xy 287.643559 -355.038124) (xy 287.597672 -355.067609) (xy 287.548057 -355.090264) (xy 287.495722 -355.105626)
			(xy 287.441733 -355.113383) (xy 287.414462 -355.113844) (xy 286.550862 -355.113844) (xy 286.523593 -355.113391)
			(xy 286.469611 -355.105625) (xy 286.417284 -355.090255) (xy 286.367676 -355.067596) (xy 286.321798 -355.038107)
			(xy 286.280583 -355.00239) (xy 286.24487 -354.961172) (xy 286.215386 -354.915291) (xy 286.192732 -354.865681)
			(xy 286.177367 -354.813352) (xy 286.169606 -354.759369) (xy 284.686758 -354.759369) (xy 284.678996 -354.813349)
			(xy 284.663632 -354.865676) (xy 284.640977 -354.915283) (xy 284.611493 -354.961162) (xy 284.575779 -355.002378)
			(xy 284.534564 -355.038091) (xy 284.488685 -355.067576) (xy 284.439078 -355.090231) (xy 284.386751 -355.105596)
			(xy 284.33277 -355.113357) (xy 284.305502 -355.113844) (xy 283.441902 -355.113844) (xy 283.41463 -355.113417)
			(xy 283.36064 -355.105654) (xy 283.308305 -355.090288) (xy 283.258689 -355.067629) (xy 283.212803 -355.03814)
			(xy 283.171581 -355.002421) (xy 283.135861 -354.961199) (xy 283.106372 -354.915313) (xy 283.083713 -354.865697)
			(xy 283.068346 -354.813362) (xy 283.060584 -354.759372) (xy 281.577757 -354.759372) (xy 281.569998 -354.813344)
			(xy 281.554635 -354.865667) (xy 281.531983 -354.915272) (xy 281.502502 -354.961149) (xy 281.466793 -355.002364)
			(xy 281.425583 -355.038077) (xy 281.379709 -355.067563) (xy 281.330107 -355.09022) (xy 281.277785 -355.105589)
			(xy 281.223808 -355.113355) (xy 281.196542 -355.113844) (xy 280.332942 -355.113844) (xy 280.305668 -355.113419)
			(xy 280.251674 -355.105662) (xy 280.199334 -355.090298) (xy 280.149713 -355.067642) (xy 280.103822 -355.038154)
			(xy 280.062595 -355.002435) (xy 280.026871 -354.961212) (xy 279.997378 -354.915324) (xy 279.974716 -354.865706)
			(xy 279.959347 -354.813367) (xy 279.951584 -354.759374) (xy 278.468881 -354.759374) (xy 278.461118 -354.813356)
			(xy 278.445752 -354.865688) (xy 278.423094 -354.9153) (xy 278.393606 -354.961182) (xy 278.357888 -355.002401)
			(xy 278.316668 -355.038117) (xy 278.270784 -355.067603) (xy 278.221171 -355.090258) (xy 278.168839 -355.105622)
			(xy 278.114853 -355.113382) (xy 278.087582 -355.113844) (xy 277.223982 -355.113844) (xy 277.196712 -355.113392)
			(xy 277.142728 -355.105628) (xy 277.090398 -355.090261) (xy 277.040788 -355.067602) (xy 276.994907 -355.038115)
			(xy 276.95369 -355.002398) (xy 276.917975 -354.961178) (xy 276.888489 -354.915296) (xy 276.865833 -354.865685)
			(xy 276.850468 -354.813354) (xy 276.842706 -354.75937) (xy 275.359858 -354.75937) (xy 275.352097 -354.813346)
			(xy 275.336733 -354.865672) (xy 275.31408 -354.915278) (xy 275.284597 -354.961156) (xy 275.248886 -355.002371)
			(xy 275.207673 -355.038084) (xy 275.161797 -355.067569) (xy 275.112192 -355.090226) (xy 275.059868 -355.105592)
			(xy 275.005889 -355.113356) (xy 274.978622 -355.113844) (xy 274.115022 -355.113844) (xy 274.087749 -355.113418)
			(xy 274.033757 -355.105658) (xy 273.981419 -355.090293) (xy 273.931801 -355.067636) (xy 273.885912 -355.038147)
			(xy 273.844688 -355.002428) (xy 273.808966 -354.961205) (xy 273.779475 -354.915318) (xy 273.756815 -354.865702)
			(xy 273.741447 -354.813365) (xy 273.733684 -354.759373) (xy 272.25098 -354.759373) (xy 272.243218 -354.813359)
			(xy 272.22785 -354.865692) (xy 272.205191 -354.915306) (xy 272.175701 -354.961189) (xy 272.139981 -355.002408)
			(xy 272.098759 -355.038124) (xy 272.052872 -355.067609) (xy 272.003257 -355.090264) (xy 271.950922 -355.105626)
			(xy 271.896933 -355.113383) (xy 271.869662 -355.113844) (xy 271.006062 -355.113844) (xy 270.978793 -355.113391)
			(xy 270.924811 -355.105625) (xy 270.872484 -355.090255) (xy 270.822876 -355.067596) (xy 270.776998 -355.038107)
			(xy 270.735783 -355.00239) (xy 270.70007 -354.961172) (xy 270.670586 -354.915291) (xy 270.647932 -354.865681)
			(xy 270.632567 -354.813352) (xy 270.624806 -354.759369) (xy 249.28669 -354.759369) (xy 249.288749 -354.763761)
			(xy 249.304817 -354.817168) (xy 249.312937 -354.872344) (xy 249.313446 -354.90023) (xy 249.312937 -354.928116)
			(xy 249.304817 -354.983292) (xy 249.288749 -355.036699) (xy 249.265077 -355.087196) (xy 249.234304 -355.133709)
			(xy 249.21 -355.160834) (xy 249.921774 -355.160834) (xy 249.925845 -355.105212) (xy 249.937971 -355.050775)
			(xy 249.957894 -354.998684) (xy 249.98519 -354.950049) (xy 250.019276 -354.905906) (xy 250.059425 -354.867197)
			(xy 250.104783 -354.834746) (xy 250.154383 -354.809245) (xy 250.207167 -354.791238) (xy 250.26201 -354.781108)
			(xy 250.317744 -354.779071) (xy 250.373181 -354.785171) (xy 250.427138 -354.799277) (xy 250.478467 -354.821089)
			(xy 250.526073 -354.850143) (xy 250.568941 -354.885818) (xy 250.606158 -354.927355) (xy 250.636931 -354.973868)
			(xy 250.660603 -355.024365) (xy 250.676671 -355.077772) (xy 250.684791 -355.132948) (xy 250.6853 -355.160834)
			(xy 253.273304 -355.160834) (xy 253.277375 -355.105212) (xy 253.289501 -355.050775) (xy 253.309424 -354.998684)
			(xy 253.33672 -354.950049) (xy 253.370806 -354.905906) (xy 253.410955 -354.867197) (xy 253.456313 -354.834746)
			(xy 253.505913 -354.809245) (xy 253.558697 -354.791238) (xy 253.61354 -354.781108) (xy 253.669274 -354.779071)
			(xy 253.724711 -354.785171) (xy 253.778668 -354.799277) (xy 253.829997 -354.821089) (xy 253.877603 -354.850143)
			(xy 253.920471 -354.885818) (xy 253.957688 -354.927355) (xy 253.988461 -354.973868) (xy 254.012133 -355.024365)
			(xy 254.028201 -355.077772) (xy 254.036321 -355.132948) (xy 254.03683 -355.160834) (xy 254.036321 -355.18872)
			(xy 254.028201 -355.243896) (xy 254.012133 -355.297303) (xy 253.988461 -355.3478) (xy 253.957688 -355.394313)
			(xy 253.920471 -355.43585) (xy 253.877603 -355.471525) (xy 253.829997 -355.500579) (xy 253.778668 -355.522391)
			(xy 253.724711 -355.536497) (xy 253.669274 -355.542597) (xy 253.61354 -355.54056) (xy 253.558697 -355.53043)
			(xy 253.505913 -355.512423) (xy 253.456313 -355.486922) (xy 253.410955 -355.454471) (xy 253.370806 -355.415762)
			(xy 253.33672 -355.371619) (xy 253.309424 -355.322984) (xy 253.289501 -355.270893) (xy 253.277375 -355.216456)
			(xy 253.273304 -355.160834) (xy 250.6853 -355.160834) (xy 250.684791 -355.18872) (xy 250.676671 -355.243896)
			(xy 250.660603 -355.297303) (xy 250.636931 -355.3478) (xy 250.606158 -355.394313) (xy 250.568941 -355.43585)
			(xy 250.526073 -355.471525) (xy 250.478467 -355.500579) (xy 250.427138 -355.522391) (xy 250.373181 -355.536497)
			(xy 250.317744 -355.542597) (xy 250.26201 -355.54056) (xy 250.207167 -355.53043) (xy 250.154383 -355.512423)
			(xy 250.104783 -355.486922) (xy 250.059425 -355.454471) (xy 250.019276 -355.415762) (xy 249.98519 -355.371619)
			(xy 249.957894 -355.322984) (xy 249.937971 -355.270893) (xy 249.925845 -355.216456) (xy 249.921774 -355.160834)
			(xy 249.21 -355.160834) (xy 249.197087 -355.175246) (xy 249.154219 -355.210921) (xy 249.106613 -355.239975)
			(xy 249.055284 -355.261787) (xy 249.001327 -355.275893) (xy 248.94589 -355.281993) (xy 248.890156 -355.279956)
			(xy 248.835313 -355.269826) (xy 248.782529 -355.251819) (xy 248.732929 -355.226318) (xy 248.687571 -355.193867)
			(xy 248.647422 -355.155158) (xy 248.613336 -355.111015) (xy 248.58604 -355.06238) (xy 248.566117 -355.010289)
			(xy 248.553991 -354.955852) (xy 248.54992 -354.90023) (xy 238.88284 -354.90023) (xy 238.913135 -354.925442)
			(xy 238.950352 -354.966979) (xy 238.981125 -355.013492) (xy 239.004797 -355.063989) (xy 239.020865 -355.117396)
			(xy 239.028985 -355.172572) (xy 239.029494 -355.200458) (xy 239.028985 -355.228344) (xy 239.020865 -355.28352)
			(xy 239.004797 -355.336927) (xy 238.981125 -355.387424) (xy 238.950352 -355.433937) (xy 238.913135 -355.475474)
			(xy 238.870267 -355.511149) (xy 238.822661 -355.540203) (xy 238.771332 -355.562015) (xy 238.717375 -355.576121)
			(xy 238.661938 -355.582221) (xy 238.606204 -355.580184) (xy 238.551361 -355.570054) (xy 238.498577 -355.552047)
			(xy 238.448977 -355.526546) (xy 238.403619 -355.494095) (xy 238.36347 -355.455386) (xy 238.329384 -355.411243)
			(xy 238.302088 -355.362608) (xy 238.282165 -355.310517) (xy 238.270039 -355.25608) (xy 238.265968 -355.200458)
			(xy 236.895894 -355.200458) (xy 236.895385 -355.228344) (xy 236.887265 -355.28352) (xy 236.871197 -355.336927)
			(xy 236.847525 -355.387424) (xy 236.816752 -355.433937) (xy 236.779535 -355.475474) (xy 236.736667 -355.511149)
			(xy 236.689061 -355.540203) (xy 236.637732 -355.562015) (xy 236.583775 -355.576121) (xy 236.528338 -355.582221)
			(xy 236.472604 -355.580184) (xy 236.417761 -355.570054) (xy 236.364977 -355.552047) (xy 236.315377 -355.526546)
			(xy 236.270019 -355.494095) (xy 236.22987 -355.455386) (xy 236.195784 -355.411243) (xy 236.168488 -355.362608)
			(xy 236.148565 -355.310517) (xy 236.136439 -355.25608) (xy 236.132368 -355.200458) (xy 201.894178 -355.200458)
			(xy 201.863558 -355.246739) (xy 201.826341 -355.288276) (xy 201.783473 -355.323951) (xy 201.735867 -355.353005)
			(xy 201.684538 -355.374817) (xy 201.630581 -355.388923) (xy 201.575144 -355.395023) (xy 201.51941 -355.392986)
			(xy 201.464567 -355.382856) (xy 201.411783 -355.364849) (xy 201.362183 -355.339348) (xy 201.316825 -355.306897)
			(xy 201.276676 -355.268188) (xy 201.24259 -355.224045) (xy 201.215294 -355.17541) (xy 201.195371 -355.123319)
			(xy 201.183245 -355.068882) (xy 201.179174 -355.01326) (xy 188.15161 -355.01326) (xy 188.150487 -355.014233)
			(xy 188.104602 -355.04372) (xy 188.054987 -355.066378) (xy 188.002652 -355.081744) (xy 187.948664 -355.089505)
			(xy 187.921392 -355.089968) (xy 187.057792 -355.089968) (xy 187.030523 -355.089469) (xy 186.976542 -355.081707)
			(xy 186.924214 -355.066341) (xy 186.874605 -355.043684) (xy 186.828726 -355.014199) (xy 186.78751 -354.978484)
			(xy 186.751796 -354.937267) (xy 186.722312 -354.891388) (xy 186.699656 -354.841779) (xy 186.684292 -354.789451)
			(xy 186.67653 -354.735469) (xy 185.193682 -354.735469) (xy 185.185921 -354.78945) (xy 185.170557 -354.841778)
			(xy 185.147903 -354.891387) (xy 185.118419 -354.937267) (xy 185.082707 -354.978484) (xy 185.041492 -355.0142)
			(xy 184.995615 -355.043687) (xy 184.946008 -355.066346) (xy 184.893681 -355.081714) (xy 184.8397 -355.089479)
			(xy 184.812432 -355.089968) (xy 183.948832 -355.089968) (xy 183.92156 -355.089495) (xy 183.86757 -355.081736)
			(xy 183.815235 -355.066373) (xy 183.765618 -355.043718) (xy 183.719731 -355.014231) (xy 183.678508 -354.978515)
			(xy 183.642788 -354.937294) (xy 183.613298 -354.89141) (xy 183.590638 -354.841795) (xy 183.57527 -354.789461)
			(xy 183.567508 -354.735472) (xy 182.08478 -354.735472) (xy 182.08478 -354.759371) (xy 182.077018 -354.813358)
			(xy 182.061651 -354.86569) (xy 182.038992 -354.915303) (xy 182.009504 -354.961186) (xy 181.973785 -355.002405)
			(xy 181.932563 -355.03812) (xy 181.886678 -355.067606) (xy 181.837064 -355.090261) (xy 181.78473 -355.105624)
			(xy 181.730743 -355.113382) (xy 181.703472 -355.113844) (xy 180.839872 -355.113844) (xy 180.812603 -355.113392)
			(xy 180.75862 -355.105626) (xy 180.706291 -355.090258) (xy 180.656682 -355.067599) (xy 180.610802 -355.038111)
			(xy 180.569586 -355.002394) (xy 180.533872 -354.961175) (xy 180.504388 -354.915293) (xy 180.481732 -354.865683)
			(xy 180.466368 -354.813353) (xy 180.458606 -354.759369) (xy 178.975758 -354.759369) (xy 178.967997 -354.813348)
			(xy 178.952633 -354.865674) (xy 178.929978 -354.915281) (xy 178.900495 -354.961159) (xy 178.864783 -355.002374)
			(xy 178.823568 -355.038088) (xy 178.777691 -355.067573) (xy 178.728085 -355.090228) (xy 178.675759 -355.105594)
			(xy 178.62178 -355.113357) (xy 178.594512 -355.113844) (xy 177.730912 -355.113844) (xy 177.703639 -355.113417)
			(xy 177.649648 -355.105656) (xy 177.597312 -355.09029) (xy 177.547695 -355.067632) (xy 177.501808 -355.038144)
			(xy 177.460584 -355.002424) (xy 177.424864 -354.961202) (xy 177.395373 -354.915316) (xy 177.372714 -354.865699)
			(xy 177.357346 -354.813363) (xy 177.349584 -354.759373) (xy 175.86688 -354.759373) (xy 175.859117 -354.81336)
			(xy 175.843749 -354.865694) (xy 175.821089 -354.915309) (xy 175.791599 -354.961192) (xy 175.755878 -355.002412)
			(xy 175.714654 -355.038128) (xy 175.668766 -355.067612) (xy 175.619149 -355.090266) (xy 175.566813 -355.105628)
			(xy 175.512824 -355.113384) (xy 175.485552 -355.113844) (xy 174.621952 -355.113844) (xy 174.594684 -355.11339)
			(xy 174.540703 -355.105623) (xy 174.488376 -355.090252) (xy 174.43877 -355.067592) (xy 174.392893 -355.038104)
			(xy 174.351679 -355.002387) (xy 174.315967 -354.961169) (xy 174.286485 -354.915288) (xy 174.263831 -354.865679)
			(xy 174.248467 -354.81335) (xy 174.240706 -354.759368) (xy 172.757881 -354.759368) (xy 172.757881 -354.75937)
			(xy 172.750119 -354.813355) (xy 172.734753 -354.865686) (xy 172.712096 -354.915297) (xy 172.682609 -354.961179)
			(xy 172.646892 -355.002398) (xy 172.605673 -355.038113) (xy 172.55979 -355.067599) (xy 172.510178 -355.090255)
			(xy 172.457847 -355.10562) (xy 172.403862 -355.113381) (xy 172.376592 -355.113844) (xy 171.512992 -355.113844)
			(xy 171.485722 -355.113393) (xy 171.431736 -355.10563) (xy 171.379405 -355.090263) (xy 171.329794 -355.067606)
			(xy 171.283912 -355.038118) (xy 171.242693 -355.002401) (xy 171.206977 -354.961182) (xy 171.177491 -354.915299)
			(xy 171.154834 -354.865687) (xy 171.139468 -354.813356) (xy 171.131706 -354.75937) (xy 169.648858 -354.75937)
			(xy 169.641097 -354.813345) (xy 169.625734 -354.865669) (xy 169.603081 -354.915275) (xy 169.5736 -354.961152)
			(xy 169.53789 -355.002367) (xy 169.496678 -355.038081) (xy 169.450803 -355.067566) (xy 169.401199 -355.090223)
			(xy 169.348876 -355.10559) (xy 169.294899 -355.113355) (xy 169.267632 -355.113844) (xy 168.404032 -355.113844)
			(xy 168.376758 -355.113419) (xy 168.322765 -355.10566) (xy 168.270426 -355.090296) (xy 168.220807 -355.067639)
			(xy 168.174917 -355.038151) (xy 168.133691 -355.002432) (xy 168.097969 -354.961209) (xy 168.068477 -354.915321)
			(xy 168.045816 -354.865704) (xy 168.030447 -354.813366) (xy 168.022684 -354.759374) (xy 166.53998 -354.759374)
			(xy 166.532218 -354.813358) (xy 166.516851 -354.86569) (xy 166.494192 -354.915303) (xy 166.464704 -354.961186)
			(xy 166.428985 -355.002405) (xy 166.387763 -355.03812) (xy 166.341878 -355.067606) (xy 166.292264 -355.090261)
			(xy 166.23993 -355.105624) (xy 166.185943 -355.113382) (xy 166.158672 -355.113844) (xy 165.295072 -355.113844)
			(xy 165.267803 -355.113392) (xy 165.21382 -355.105626) (xy 165.161491 -355.090258) (xy 165.111882 -355.067599)
			(xy 165.066002 -355.038111) (xy 165.024786 -355.002394) (xy 164.989072 -354.961175) (xy 164.959588 -354.915293)
			(xy 164.936932 -354.865683) (xy 164.921568 -354.813353) (xy 164.913806 -354.759369) (xy 163.430958 -354.759369)
			(xy 163.423197 -354.813348) (xy 163.407833 -354.865674) (xy 163.385178 -354.915281) (xy 163.355695 -354.961159)
			(xy 163.319983 -355.002374) (xy 163.278768 -355.038088) (xy 163.232891 -355.067573) (xy 163.183285 -355.090228)
			(xy 163.130959 -355.105594) (xy 163.07698 -355.113357) (xy 163.049712 -355.113844) (xy 162.186112 -355.113844)
			(xy 162.158839 -355.113417) (xy 162.104848 -355.105656) (xy 162.052512 -355.09029) (xy 162.002895 -355.067632)
			(xy 161.957008 -355.038144) (xy 161.915784 -355.002424) (xy 161.880064 -354.961202) (xy 161.850573 -354.915316)
			(xy 161.827914 -354.865699) (xy 161.812546 -354.813363) (xy 161.804784 -354.759373) (xy 160.32208 -354.759373)
			(xy 160.314317 -354.81336) (xy 160.298949 -354.865694) (xy 160.276289 -354.915309) (xy 160.246799 -354.961192)
			(xy 160.211078 -355.002412) (xy 160.169854 -355.038128) (xy 160.123966 -355.067612) (xy 160.074349 -355.090266)
			(xy 160.022013 -355.105628) (xy 159.968024 -355.113384) (xy 159.940752 -355.113844) (xy 159.077152 -355.113844)
			(xy 159.049884 -355.11339) (xy 158.995903 -355.105623) (xy 158.943576 -355.090252) (xy 158.89397 -355.067592)
			(xy 158.848093 -355.038104) (xy 158.806879 -355.002387) (xy 158.771167 -354.961169) (xy 158.741685 -354.915288)
			(xy 158.719031 -354.865679) (xy 158.703667 -354.81335) (xy 158.695906 -354.759368) (xy 149.315424 -354.759368)
			(xy 149.315424 -356.021894) (xy 205.409798 -356.021894) (xy 205.413869 -355.966272) (xy 205.425995 -355.911835)
			(xy 205.445918 -355.859744) (xy 205.473214 -355.811109) (xy 205.5073 -355.766966) (xy 205.547449 -355.728257)
			(xy 205.592807 -355.695806) (xy 205.642407 -355.670305) (xy 205.695191 -355.652298) (xy 205.750034 -355.642168)
			(xy 205.805768 -355.640131) (xy 205.861205 -355.646231) (xy 205.915162 -355.660337) (xy 205.966491 -355.682149)
			(xy 206.014097 -355.711203) (xy 206.056965 -355.746878) (xy 206.094182 -355.788415) (xy 206.124955 -355.834928)
			(xy 206.148627 -355.885425) (xy 206.164695 -355.938832) (xy 206.172815 -355.994008) (xy 206.173324 -356.021894)
			(xy 206.172815 -356.04978) (xy 206.164695 -356.104956) (xy 206.148627 -356.158363) (xy 206.145207 -356.165658)
			(xy 236.132368 -356.165658) (xy 236.136439 -356.110036) (xy 236.148565 -356.055599) (xy 236.168488 -356.003508)
			(xy 236.195784 -355.954873) (xy 236.22987 -355.91073) (xy 236.270019 -355.872021) (xy 236.315377 -355.83957)
			(xy 236.364977 -355.814069) (xy 236.417761 -355.796062) (xy 236.472604 -355.785932) (xy 236.528338 -355.783895)
			(xy 236.583775 -355.789995) (xy 236.637732 -355.804101) (xy 236.689061 -355.825913) (xy 236.736667 -355.854967)
			(xy 236.779535 -355.890642) (xy 236.816752 -355.932179) (xy 236.847525 -355.978692) (xy 236.871197 -356.029189)
			(xy 236.887265 -356.082596) (xy 236.895385 -356.137772) (xy 236.895894 -356.165658) (xy 238.265968 -356.165658)
			(xy 238.270039 -356.110036) (xy 238.282165 -356.055599) (xy 238.302088 -356.003508) (xy 238.329384 -355.954873)
			(xy 238.36347 -355.91073) (xy 238.403619 -355.872021) (xy 238.448977 -355.83957) (xy 238.498577 -355.814069)
			(xy 238.551361 -355.796062) (xy 238.606204 -355.785932) (xy 238.661938 -355.783895) (xy 238.717375 -355.789995)
			(xy 238.771332 -355.804101) (xy 238.822661 -355.825913) (xy 238.870267 -355.854967) (xy 238.913135 -355.890642)
			(xy 238.950352 -355.932179) (xy 238.981125 -355.978692) (xy 239.004797 -356.029189) (xy 239.008878 -356.042752)
			(xy 249.589499 -356.042752) (xy 249.589499 -355.988248) (xy 249.597257 -355.9343) (xy 249.612613 -355.882004)
			(xy 249.635256 -355.832427) (xy 249.664725 -355.786577) (xy 249.700419 -355.745388) (xy 249.741612 -355.709698)
			(xy 249.787466 -355.680235) (xy 249.837046 -355.657598) (xy 249.889343 -355.642247) (xy 249.943292 -355.634496)
			(xy 249.970544 -355.634036) (xy 249.99946 -355.634581) (xy 250.056631 -355.643302) (xy 250.11183 -355.660554)
			(xy 250.163792 -355.685941) (xy 250.211326 -355.71888) (xy 250.253344 -355.758618) (xy 250.271534 -355.781102)
			(xy 250.279085 -355.789875) (xy 250.299852 -355.800052) (xy 250.311412 -355.80066) (xy 250.391676 -355.80066)
			(xy 250.403244 -355.800089) (xy 250.424016 -355.789896) (xy 250.431554 -355.781102) (xy 250.449771 -355.758641)
			(xy 250.491786 -355.718904) (xy 250.539315 -355.685963) (xy 250.591271 -355.66057) (xy 250.646464 -355.643309)
			(xy 250.70363 -355.634574) (xy 250.732544 -355.634036) (xy 250.759796 -355.634437) (xy 250.813746 -355.642199)
			(xy 250.866041 -355.65756) (xy 250.915618 -355.680206) (xy 250.961469 -355.709677) (xy 251.002658 -355.745373)
			(xy 251.038349 -355.786567) (xy 251.067815 -355.83242) (xy 251.090455 -355.882) (xy 251.10581 -355.934298)
			(xy 251.113566 -355.988248) (xy 251.113566 -356.042752) (xy 251.10581 -356.096702) (xy 251.090455 -356.149)
			(xy 251.067815 -356.19858) (xy 251.038349 -356.244433) (xy 251.002658 -356.285627) (xy 250.961469 -356.321323)
			(xy 250.915618 -356.350794) (xy 250.866041 -356.37344) (xy 250.813746 -356.388801) (xy 250.759796 -356.396563)
			(xy 250.732544 -356.397052) (xy 250.703627 -356.39652) (xy 250.646456 -356.387797) (xy 250.591257 -356.370543)
			(xy 250.539294 -356.345154) (xy 250.49176 -356.312211) (xy 250.449744 -356.272471) (xy 250.431554 -356.249986)
			(xy 250.42401 -356.241206) (xy 250.403238 -356.231033) (xy 250.391676 -356.230428) (xy 250.311412 -356.230428)
			(xy 250.299844 -356.230996) (xy 250.279072 -356.241191) (xy 250.271534 -356.249986) (xy 250.25332 -356.27245)
			(xy 250.211306 -356.312187) (xy 250.163776 -356.345129) (xy 250.111819 -356.370521) (xy 250.056625 -356.387781)
			(xy 249.999459 -356.396515) (xy 249.970544 -356.397052) (xy 249.943292 -356.396504) (xy 249.889343 -356.388753)
			(xy 249.837046 -356.373402) (xy 249.787466 -356.350765) (xy 249.741612 -356.321302) (xy 249.700419 -356.285612)
			(xy 249.664725 -356.244423) (xy 249.635256 -356.198573) (xy 249.612613 -356.148996) (xy 249.597257 -356.0967)
			(xy 249.589499 -356.042752) (xy 239.008878 -356.042752) (xy 239.020865 -356.082596) (xy 239.028985 -356.137772)
			(xy 239.029494 -356.165658) (xy 239.028985 -356.193544) (xy 239.020865 -356.24872) (xy 239.004797 -356.302127)
			(xy 238.981125 -356.352624) (xy 238.950352 -356.399137) (xy 238.913135 -356.440674) (xy 238.870267 -356.476349)
			(xy 238.822661 -356.505403) (xy 238.771332 -356.527215) (xy 238.717375 -356.541321) (xy 238.661938 -356.547421)
			(xy 238.606204 -356.545384) (xy 238.551361 -356.535254) (xy 238.498577 -356.517247) (xy 238.448977 -356.491746)
			(xy 238.403619 -356.459295) (xy 238.36347 -356.420586) (xy 238.329384 -356.376443) (xy 238.302088 -356.327808)
			(xy 238.282165 -356.275717) (xy 238.270039 -356.22128) (xy 238.265968 -356.165658) (xy 236.895894 -356.165658)
			(xy 236.895385 -356.193544) (xy 236.887265 -356.24872) (xy 236.871197 -356.302127) (xy 236.847525 -356.352624)
			(xy 236.816752 -356.399137) (xy 236.779535 -356.440674) (xy 236.736667 -356.476349) (xy 236.689061 -356.505403)
			(xy 236.637732 -356.527215) (xy 236.583775 -356.541321) (xy 236.528338 -356.547421) (xy 236.472604 -356.545384)
			(xy 236.417761 -356.535254) (xy 236.364977 -356.517247) (xy 236.315377 -356.491746) (xy 236.270019 -356.459295)
			(xy 236.22987 -356.420586) (xy 236.195784 -356.376443) (xy 236.168488 -356.327808) (xy 236.148565 -356.275717)
			(xy 236.136439 -356.22128) (xy 236.132368 -356.165658) (xy 206.145207 -356.165658) (xy 206.124955 -356.20886)
			(xy 206.094182 -356.255373) (xy 206.056965 -356.29691) (xy 206.014097 -356.332585) (xy 205.966491 -356.361639)
			(xy 205.915162 -356.383451) (xy 205.861205 -356.397557) (xy 205.805768 -356.403657) (xy 205.750034 -356.40162)
			(xy 205.695191 -356.39149) (xy 205.642407 -356.373483) (xy 205.592807 -356.347982) (xy 205.547449 -356.315531)
			(xy 205.5073 -356.276822) (xy 205.473214 -356.232679) (xy 205.445918 -356.184044) (xy 205.425995 -356.131953)
			(xy 205.413869 -356.077516) (xy 205.409798 -356.021894) (xy 149.315424 -356.021894) (xy 149.315424 -356.811326)
			(xy 204.000098 -356.811326) (xy 204.004169 -356.755704) (xy 204.016295 -356.701267) (xy 204.036218 -356.649176)
			(xy 204.063514 -356.600541) (xy 204.0976 -356.556398) (xy 204.137749 -356.517689) (xy 204.183107 -356.485238)
			(xy 204.232707 -356.459737) (xy 204.285491 -356.44173) (xy 204.340334 -356.4316) (xy 204.396068 -356.429563)
			(xy 204.451505 -356.435663) (xy 204.505462 -356.449769) (xy 204.556791 -356.471581) (xy 204.604397 -356.500635)
			(xy 204.647265 -356.53631) (xy 204.684482 -356.577847) (xy 204.715255 -356.62436) (xy 204.738927 -356.674857)
			(xy 204.754995 -356.728264) (xy 204.763115 -356.78344) (xy 204.763624 -356.811326) (xy 204.763115 -356.839212)
			(xy 204.754995 -356.894388) (xy 204.738927 -356.947795) (xy 204.715255 -356.998292) (xy 204.684482 -357.044805)
			(xy 204.647265 -357.086342) (xy 204.604397 -357.122017) (xy 204.589911 -357.130858) (xy 236.132368 -357.130858)
			(xy 236.136439 -357.075236) (xy 236.148565 -357.020799) (xy 236.168488 -356.968708) (xy 236.195784 -356.920073)
			(xy 236.22987 -356.87593) (xy 236.270019 -356.837221) (xy 236.315377 -356.80477) (xy 236.364977 -356.779269)
			(xy 236.417761 -356.761262) (xy 236.472604 -356.751132) (xy 236.528338 -356.749095) (xy 236.583775 -356.755195)
			(xy 236.637732 -356.769301) (xy 236.689061 -356.791113) (xy 236.736667 -356.820167) (xy 236.779535 -356.855842)
			(xy 236.816752 -356.897379) (xy 236.847525 -356.943892) (xy 236.871197 -356.994389) (xy 236.887265 -357.047796)
			(xy 236.895385 -357.102972) (xy 236.895894 -357.130858) (xy 236.895385 -357.158744) (xy 236.890705 -357.190548)
			(xy 239.453672 -357.190548) (xy 239.457743 -357.134926) (xy 239.469869 -357.080489) (xy 239.489792 -357.028398)
			(xy 239.517088 -356.979763) (xy 239.551174 -356.93562) (xy 239.591323 -356.896911) (xy 239.636681 -356.86446)
			(xy 239.686281 -356.838959) (xy 239.739065 -356.820952) (xy 239.793908 -356.810822) (xy 239.849642 -356.808785)
			(xy 239.905079 -356.814885) (xy 239.959036 -356.828991) (xy 240.010365 -356.850803) (xy 240.057971 -356.879857)
			(xy 240.100839 -356.915532) (xy 240.138056 -356.957069) (xy 240.168829 -357.003582) (xy 240.192501 -357.054079)
			(xy 240.208569 -357.107486) (xy 240.216689 -357.162662) (xy 240.217198 -357.190548) (xy 240.469672 -357.190548)
			(xy 240.473743 -357.134926) (xy 240.485869 -357.080489) (xy 240.505792 -357.028398) (xy 240.533088 -356.979763)
			(xy 240.567174 -356.93562) (xy 240.607323 -356.896911) (xy 240.652681 -356.86446) (xy 240.702281 -356.838959)
			(xy 240.755065 -356.820952) (xy 240.809908 -356.810822) (xy 240.865642 -356.808785) (xy 240.921079 -356.814885)
			(xy 240.975036 -356.828991) (xy 241.026365 -356.850803) (xy 241.073971 -356.879857) (xy 241.116839 -356.915532)
			(xy 241.154056 -356.957069) (xy 241.184829 -357.003582) (xy 241.208501 -357.054079) (xy 241.224569 -357.107486)
			(xy 241.232689 -357.162662) (xy 241.233198 -357.190548) (xy 241.232689 -357.218434) (xy 241.224569 -357.27361)
			(xy 241.208501 -357.327017) (xy 241.184829 -357.377514) (xy 241.154056 -357.424027) (xy 241.116839 -357.465564)
			(xy 241.073971 -357.501239) (xy 241.026365 -357.530293) (xy 240.975036 -357.552105) (xy 240.921079 -357.566211)
			(xy 240.865642 -357.572311) (xy 240.809908 -357.570274) (xy 240.755065 -357.560144) (xy 240.702281 -357.542137)
			(xy 240.652681 -357.516636) (xy 240.607323 -357.484185) (xy 240.567174 -357.445476) (xy 240.533088 -357.401333)
			(xy 240.505792 -357.352698) (xy 240.485869 -357.300607) (xy 240.473743 -357.24617) (xy 240.469672 -357.190548)
			(xy 240.217198 -357.190548) (xy 240.216689 -357.218434) (xy 240.208569 -357.27361) (xy 240.192501 -357.327017)
			(xy 240.168829 -357.377514) (xy 240.138056 -357.424027) (xy 240.100839 -357.465564) (xy 240.057971 -357.501239)
			(xy 240.010365 -357.530293) (xy 239.959036 -357.552105) (xy 239.905079 -357.566211) (xy 239.849642 -357.572311)
			(xy 239.793908 -357.570274) (xy 239.739065 -357.560144) (xy 239.686281 -357.542137) (xy 239.636681 -357.516636)
			(xy 239.591323 -357.484185) (xy 239.551174 -357.445476) (xy 239.517088 -357.401333) (xy 239.489792 -357.352698)
			(xy 239.469869 -357.300607) (xy 239.457743 -357.24617) (xy 239.453672 -357.190548) (xy 236.890705 -357.190548)
			(xy 236.887265 -357.21392) (xy 236.871197 -357.267327) (xy 236.847525 -357.317824) (xy 236.816752 -357.364337)
			(xy 236.779535 -357.405874) (xy 236.736667 -357.441549) (xy 236.689061 -357.470603) (xy 236.637732 -357.492415)
			(xy 236.583775 -357.506521) (xy 236.528338 -357.512621) (xy 236.472604 -357.510584) (xy 236.417761 -357.500454)
			(xy 236.364977 -357.482447) (xy 236.315377 -357.456946) (xy 236.270019 -357.424495) (xy 236.22987 -357.385786)
			(xy 236.195784 -357.341643) (xy 236.168488 -357.293008) (xy 236.148565 -357.240917) (xy 236.136439 -357.18648)
			(xy 236.132368 -357.130858) (xy 204.589911 -357.130858) (xy 204.556791 -357.151071) (xy 204.505462 -357.172883)
			(xy 204.451505 -357.186989) (xy 204.396068 -357.193089) (xy 204.340334 -357.191052) (xy 204.285491 -357.180922)
			(xy 204.232707 -357.162915) (xy 204.183107 -357.137414) (xy 204.137749 -357.104963) (xy 204.0976 -357.066254)
			(xy 204.063514 -357.022111) (xy 204.036218 -356.973476) (xy 204.016295 -356.921385) (xy 204.004169 -356.866948)
			(xy 204.000098 -356.811326) (xy 149.315424 -356.811326) (xy 149.315424 -357.784965) (xy 158.695954 -357.784965)
			(xy 158.695954 -357.730435) (xy 158.703714 -357.67646) (xy 158.719076 -357.624138) (xy 158.741727 -357.574535)
			(xy 158.771206 -357.52866) (xy 158.806913 -357.487447) (xy 158.848122 -357.451735) (xy 158.893993 -357.42225)
			(xy 158.943593 -357.399593) (xy 158.995913 -357.384224) (xy 159.049887 -357.376458) (xy 159.077152 -357.375968)
			(xy 159.940752 -357.375968) (xy 159.968027 -357.376368) (xy 160.022024 -357.384125) (xy 160.074366 -357.399489)
			(xy 160.123989 -357.422145) (xy 160.169883 -357.451634) (xy 160.211112 -357.487354) (xy 160.246837 -357.528579)
			(xy 160.276332 -357.574468) (xy 160.298994 -357.624089) (xy 160.314364 -357.676429) (xy 160.322128 -357.730425)
			(xy 160.322128 -357.784969) (xy 161.804831 -357.784969) (xy 161.804831 -357.730431) (xy 161.812593 -357.676447)
			(xy 161.827959 -357.624117) (xy 161.850616 -357.574507) (xy 161.880102 -357.528627) (xy 161.915818 -357.487409)
			(xy 161.957036 -357.451695) (xy 162.002918 -357.42221) (xy 162.052529 -357.399555) (xy 162.104859 -357.384191)
			(xy 162.158843 -357.376431) (xy 162.186112 -357.375968) (xy 163.049712 -357.375968) (xy 163.076983 -357.376395)
			(xy 163.130969 -357.384159) (xy 163.183302 -357.399527) (xy 163.232914 -357.422185) (xy 163.278797 -357.451674)
			(xy 163.320017 -357.487392) (xy 163.355733 -357.528612) (xy 163.385221 -357.574496) (xy 163.407878 -357.62411)
			(xy 163.423244 -357.676442) (xy 163.431006 -357.730429) (xy 163.431006 -357.784966) (xy 164.913854 -357.784966)
			(xy 164.913854 -357.730434) (xy 164.921615 -357.676457) (xy 164.936977 -357.624134) (xy 164.95963 -357.57453)
			(xy 164.989111 -357.528654) (xy 165.02482 -357.48744) (xy 165.066031 -357.451727) (xy 165.111905 -357.422243)
			(xy 165.161508 -357.399587) (xy 165.21383 -357.384221) (xy 165.267806 -357.376456) (xy 165.295072 -357.375968)
			(xy 166.158672 -357.375968) (xy 166.185946 -357.37637) (xy 166.239941 -357.384129) (xy 166.292281 -357.399494)
			(xy 166.341901 -357.422152) (xy 166.387792 -357.451641) (xy 166.429019 -357.487361) (xy 166.464742 -357.528585)
			(xy 166.494235 -357.574474) (xy 166.516896 -357.624093) (xy 166.532265 -357.676432) (xy 166.540028 -357.730426)
			(xy 166.540028 -357.78497) (xy 168.022732 -357.78497) (xy 168.022732 -357.73043) (xy 168.030494 -357.676444)
			(xy 168.045861 -357.624113) (xy 168.068519 -357.574502) (xy 168.098007 -357.52862) (xy 168.133725 -357.487402)
			(xy 168.174946 -357.451688) (xy 168.22083 -357.422203) (xy 168.270443 -357.399549) (xy 168.322776 -357.384187)
			(xy 168.376762 -357.376429) (xy 168.404032 -357.375968) (xy 169.267632 -357.375968) (xy 169.294902 -357.376397)
			(xy 169.348886 -357.384163) (xy 169.401216 -357.399532) (xy 169.450826 -357.422192) (xy 169.496707 -357.451681)
			(xy 169.537924 -357.487399) (xy 169.573638 -357.528619) (xy 169.603124 -357.574502) (xy 169.625779 -357.624114)
			(xy 169.641144 -357.676445) (xy 169.648906 -357.73043) (xy 169.648906 -357.784967) (xy 171.131754 -357.784967)
			(xy 171.131754 -357.730433) (xy 171.139515 -357.676454) (xy 171.154879 -357.62413) (xy 171.177533 -357.574524)
			(xy 171.207016 -357.528647) (xy 171.242727 -357.487433) (xy 171.283941 -357.45172) (xy 171.329817 -357.422237)
			(xy 171.379422 -357.399582) (xy 171.431747 -357.384217) (xy 171.485725 -357.376455) (xy 171.512992 -357.375968)
			(xy 172.376592 -357.375968) (xy 172.403866 -357.376371) (xy 172.457857 -357.384133) (xy 172.510195 -357.3995)
			(xy 172.559813 -357.422159) (xy 172.605702 -357.451648) (xy 172.646926 -357.487368) (xy 172.682647 -357.528592)
			(xy 172.712138 -357.57448) (xy 172.734798 -357.624097) (xy 172.750165 -357.676435) (xy 172.757928 -357.730426)
			(xy 172.757928 -357.784965) (xy 174.240754 -357.784965) (xy 174.240754 -357.730435) (xy 174.248514 -357.67646)
			(xy 174.263876 -357.624138) (xy 174.286527 -357.574535) (xy 174.316006 -357.52866) (xy 174.351713 -357.487447)
			(xy 174.392922 -357.451735) (xy 174.438793 -357.42225) (xy 174.488393 -357.399593) (xy 174.540713 -357.384224)
			(xy 174.594687 -357.376458) (xy 174.621952 -357.375968) (xy 175.485552 -357.375968) (xy 175.512827 -357.376368)
			(xy 175.566824 -357.384125) (xy 175.619166 -357.399489) (xy 175.668789 -357.422145) (xy 175.714683 -357.451634)
			(xy 175.755912 -357.487354) (xy 175.791637 -357.528579) (xy 175.821132 -357.574468) (xy 175.843794 -357.624089)
			(xy 175.859164 -357.676429) (xy 175.866928 -357.730425) (xy 175.866928 -357.784969) (xy 177.349631 -357.784969)
			(xy 177.349631 -357.730431) (xy 177.357393 -357.676447) (xy 177.372759 -357.624117) (xy 177.395416 -357.574507)
			(xy 177.424902 -357.528627) (xy 177.460618 -357.487409) (xy 177.501836 -357.451695) (xy 177.547718 -357.42221)
			(xy 177.597329 -357.399555) (xy 177.649659 -357.384191) (xy 177.703643 -357.376431) (xy 177.730912 -357.375968)
			(xy 178.594512 -357.375968) (xy 178.621783 -357.376395) (xy 178.675769 -357.384159) (xy 178.728102 -357.399527)
			(xy 178.777714 -357.422185) (xy 178.823597 -357.451674) (xy 178.864817 -357.487392) (xy 178.900533 -357.528612)
			(xy 178.930021 -357.574496) (xy 178.952678 -357.62411) (xy 178.968044 -357.676442) (xy 178.975806 -357.730429)
			(xy 178.975806 -357.784966) (xy 180.458654 -357.784966) (xy 180.458654 -357.730434) (xy 180.466415 -357.676457)
			(xy 180.481777 -357.624134) (xy 180.50443 -357.57453) (xy 180.533911 -357.528654) (xy 180.56962 -357.48744)
			(xy 180.610831 -357.451727) (xy 180.656705 -357.422243) (xy 180.706308 -357.399587) (xy 180.75863 -357.384221)
			(xy 180.812606 -357.376456) (xy 180.839872 -357.375968) (xy 181.703472 -357.375968) (xy 181.730746 -357.37637)
			(xy 181.784741 -357.384129) (xy 181.837081 -357.399494) (xy 181.886701 -357.422152) (xy 181.932592 -357.451641)
			(xy 181.973819 -357.487361) (xy 182.009542 -357.528585) (xy 182.039035 -357.574474) (xy 182.061696 -357.624093)
			(xy 182.077065 -357.676432) (xy 182.084828 -357.730426) (xy 182.084828 -357.761176) (xy 183.567456 -357.761176)
			(xy 183.567456 -357.706624) (xy 183.57522 -357.652628) (xy 183.590589 -357.600287) (xy 183.613252 -357.550665)
			(xy 183.642746 -357.504775) (xy 183.678471 -357.463549) (xy 183.7197 -357.427827) (xy 183.765593 -357.398337)
			(xy 183.815217 -357.375678) (xy 183.867559 -357.360313) (xy 183.921556 -357.352553) (xy 183.948832 -357.352092)
			(xy 184.812432 -357.352092) (xy 184.839697 -357.352672) (xy 184.89367 -357.360437) (xy 184.94599 -357.375803)
			(xy 184.99559 -357.398458) (xy 185.041461 -357.427942) (xy 185.08267 -357.463653) (xy 185.118378 -357.504864)
			(xy 185.147857 -357.550738) (xy 185.170508 -357.60034) (xy 185.18587 -357.652661) (xy 185.19363 -357.706635)
			(xy 185.19363 -357.761165) (xy 185.193629 -357.761172) (xy 186.676479 -357.761172) (xy 186.676479 -357.706628)
			(xy 186.684241 -357.652638) (xy 186.699608 -357.600303) (xy 186.722266 -357.550688) (xy 186.751755 -357.504801)
			(xy 186.787473 -357.463579) (xy 186.828695 -357.42786) (xy 186.87458 -357.39837) (xy 186.924196 -357.37571)
			(xy 186.97653 -357.360343) (xy 187.03052 -357.352579) (xy 187.057792 -357.352092) (xy 187.921392 -357.352092)
			(xy 187.94866 -357.352647) (xy 188.002641 -357.360407) (xy 188.054969 -357.375771) (xy 188.104577 -357.398425)
			(xy 188.150456 -357.427909) (xy 188.191672 -357.463622) (xy 188.227386 -357.504838) (xy 188.256871 -357.550716)
			(xy 188.279526 -357.600324) (xy 188.294891 -357.652651) (xy 188.302653 -357.706632) (xy 188.302653 -357.761168)
			(xy 188.294891 -357.815149) (xy 188.279526 -357.867476) (xy 188.256871 -357.917084) (xy 188.227386 -357.962962)
			(xy 188.191672 -358.004178) (xy 188.150456 -358.039891) (xy 188.104577 -358.069375) (xy 188.054969 -358.092029)
			(xy 188.002641 -358.107393) (xy 187.94866 -358.115153) (xy 187.921392 -358.115616) (xy 187.057792 -358.115616)
			(xy 187.03052 -358.115221) (xy 186.97653 -358.107457) (xy 186.924196 -358.092089) (xy 186.87458 -358.06943)
			(xy 186.828695 -358.03994) (xy 186.787473 -358.004221) (xy 186.751755 -357.962999) (xy 186.722266 -357.917112)
			(xy 186.699608 -357.867497) (xy 186.684241 -357.815162) (xy 186.676479 -357.761172) (xy 185.193629 -357.761172)
			(xy 185.18587 -357.815139) (xy 185.170508 -357.86746) (xy 185.147857 -357.917062) (xy 185.118378 -357.962936)
			(xy 185.08267 -358.004147) (xy 185.041461 -358.039858) (xy 184.99559 -358.069342) (xy 184.94599 -358.091997)
			(xy 184.89367 -358.107363) (xy 184.839697 -358.115128) (xy 184.812432 -358.115616) (xy 183.948832 -358.115616)
			(xy 183.921556 -358.115247) (xy 183.867559 -358.107487) (xy 183.815217 -358.092122) (xy 183.765593 -358.069463)
			(xy 183.7197 -358.039973) (xy 183.678471 -358.004251) (xy 183.642746 -357.963025) (xy 183.613252 -357.917135)
			(xy 183.590589 -357.867513) (xy 183.57522 -357.815172) (xy 183.567456 -357.761176) (xy 182.084828 -357.761176)
			(xy 182.084828 -357.784974) (xy 182.077065 -357.838968) (xy 182.061696 -357.891307) (xy 182.039035 -357.940926)
			(xy 182.009542 -357.986815) (xy 181.973819 -358.028039) (xy 181.932592 -358.063759) (xy 181.886701 -358.093248)
			(xy 181.837081 -358.115906) (xy 181.784741 -358.131271) (xy 181.730746 -358.13903) (xy 181.703472 -358.139492)
			(xy 180.839872 -358.139492) (xy 180.812606 -358.138944) (xy 180.75863 -358.131179) (xy 180.706308 -358.115813)
			(xy 180.656705 -358.093157) (xy 180.610831 -358.063673) (xy 180.56962 -358.02796) (xy 180.533911 -357.986746)
			(xy 180.50443 -357.94087) (xy 180.481777 -357.891266) (xy 180.466415 -357.838943) (xy 180.458654 -357.784966)
			(xy 178.975806 -357.784966) (xy 178.975806 -357.784971) (xy 178.968044 -357.838958) (xy 178.952678 -357.89129)
			(xy 178.930021 -357.940904) (xy 178.900533 -357.986788) (xy 178.864817 -358.028008) (xy 178.823597 -358.063726)
			(xy 178.777714 -358.093215) (xy 178.728102 -358.115873) (xy 178.675769 -358.131241) (xy 178.621783 -358.139005)
			(xy 178.594512 -358.139492) (xy 177.730912 -358.139492) (xy 177.703643 -358.138969) (xy 177.649659 -358.131209)
			(xy 177.597329 -358.115845) (xy 177.547718 -358.09319) (xy 177.501836 -358.063705) (xy 177.460618 -358.027991)
			(xy 177.424902 -357.986773) (xy 177.395416 -357.940893) (xy 177.372759 -357.891283) (xy 177.357393 -357.838953)
			(xy 177.349631 -357.784969) (xy 175.866928 -357.784969) (xy 175.866928 -357.784975) (xy 175.859164 -357.838971)
			(xy 175.843794 -357.891311) (xy 175.821132 -357.940932) (xy 175.791637 -357.986821) (xy 175.755912 -358.028046)
			(xy 175.714683 -358.063766) (xy 175.668789 -358.093255) (xy 175.619166 -358.115911) (xy 175.566824 -358.131275)
			(xy 175.512827 -358.139032) (xy 175.485552 -358.139492) (xy 174.621952 -358.139492) (xy 174.594687 -358.138942)
			(xy 174.540713 -358.131176) (xy 174.488393 -358.115807) (xy 174.438793 -358.09315) (xy 174.392922 -358.063665)
			(xy 174.351713 -358.027953) (xy 174.316006 -357.98674) (xy 174.286527 -357.940865) (xy 174.263876 -357.891262)
			(xy 174.248514 -357.83894) (xy 174.240754 -357.784965) (xy 172.757928 -357.784965) (xy 172.757928 -357.784974)
			(xy 172.750165 -357.838965) (xy 172.734798 -357.891303) (xy 172.712138 -357.94092) (xy 172.682647 -357.986808)
			(xy 172.646926 -358.028032) (xy 172.605702 -358.063752) (xy 172.559813 -358.093241) (xy 172.510195 -358.1159)
			(xy 172.457857 -358.131267) (xy 172.403866 -358.139029) (xy 172.376592 -358.139492) (xy 171.512992 -358.139492)
			(xy 171.485725 -358.138945) (xy 171.431747 -358.131183) (xy 171.379422 -358.115818) (xy 171.329817 -358.093163)
			(xy 171.283941 -358.06368) (xy 171.242727 -358.027967) (xy 171.207016 -357.986753) (xy 171.177533 -357.940876)
			(xy 171.154879 -357.89127) (xy 171.139515 -357.838946) (xy 171.131754 -357.784967) (xy 169.648906 -357.784967)
			(xy 169.648906 -357.78497) (xy 169.641144 -357.838955) (xy 169.625779 -357.891286) (xy 169.603124 -357.940898)
			(xy 169.573638 -357.986781) (xy 169.537924 -358.028001) (xy 169.496707 -358.063719) (xy 169.450826 -358.093208)
			(xy 169.401216 -358.115868) (xy 169.348886 -358.131237) (xy 169.294902 -358.139003) (xy 169.267632 -358.139492)
			(xy 168.404032 -358.139492) (xy 168.376762 -358.138971) (xy 168.322776 -358.131213) (xy 168.270443 -358.115851)
			(xy 168.22083 -358.093197) (xy 168.174946 -358.063712) (xy 168.133725 -358.027998) (xy 168.098007 -357.98678)
			(xy 168.068519 -357.940898) (xy 168.045861 -357.891287) (xy 168.030494 -357.838956) (xy 168.022732 -357.78497)
			(xy 166.540028 -357.78497) (xy 166.540028 -357.784974) (xy 166.532265 -357.838968) (xy 166.516896 -357.891307)
			(xy 166.494235 -357.940926) (xy 166.464742 -357.986815) (xy 166.429019 -358.028039) (xy 166.387792 -358.063759)
			(xy 166.341901 -358.093248) (xy 166.292281 -358.115906) (xy 166.239941 -358.131271) (xy 166.185946 -358.13903)
			(xy 166.158672 -358.139492) (xy 165.295072 -358.139492) (xy 165.267806 -358.138944) (xy 165.21383 -358.131179)
			(xy 165.161508 -358.115813) (xy 165.111905 -358.093157) (xy 165.066031 -358.063673) (xy 165.02482 -358.02796)
			(xy 164.989111 -357.986746) (xy 164.95963 -357.94087) (xy 164.936977 -357.891266) (xy 164.921615 -357.838943)
			(xy 164.913854 -357.784966) (xy 163.431006 -357.784966) (xy 163.431006 -357.784971) (xy 163.423244 -357.838958)
			(xy 163.407878 -357.89129) (xy 163.385221 -357.940904) (xy 163.355733 -357.986788) (xy 163.320017 -358.028008)
			(xy 163.278797 -358.063726) (xy 163.232914 -358.093215) (xy 163.183302 -358.115873) (xy 163.130969 -358.131241)
			(xy 163.076983 -358.139005) (xy 163.049712 -358.139492) (xy 162.186112 -358.139492) (xy 162.158843 -358.138969)
			(xy 162.104859 -358.131209) (xy 162.052529 -358.115845) (xy 162.002918 -358.09319) (xy 161.957036 -358.063705)
			(xy 161.915818 -358.027991) (xy 161.880102 -357.986773) (xy 161.850616 -357.940893) (xy 161.827959 -357.891283)
			(xy 161.812593 -357.838953) (xy 161.804831 -357.784969) (xy 160.322128 -357.784969) (xy 160.322128 -357.784975)
			(xy 160.314364 -357.838971) (xy 160.298994 -357.891311) (xy 160.276332 -357.940932) (xy 160.246837 -357.986821)
			(xy 160.211112 -358.028046) (xy 160.169883 -358.063766) (xy 160.123989 -358.093255) (xy 160.074366 -358.115911)
			(xy 160.022024 -358.131275) (xy 159.968027 -358.139032) (xy 159.940752 -358.139492) (xy 159.077152 -358.139492)
			(xy 159.049887 -358.138942) (xy 158.995913 -358.131176) (xy 158.943593 -358.115807) (xy 158.893993 -358.09315)
			(xy 158.848122 -358.063665) (xy 158.806913 -358.027953) (xy 158.771206 -357.98674) (xy 158.741727 -357.940865)
			(xy 158.719076 -357.891262) (xy 158.703714 -357.83894) (xy 158.695954 -357.784965) (xy 149.315424 -357.784965)
			(xy 149.315424 -361.624372) (xy 149.314988 -361.634437) (xy 149.307258 -361.653025) (xy 149.300438 -361.66044)
			(xy 148.11756 -362.843318) (xy 148.110163 -362.850167) (xy 148.091564 -362.8579) (xy 148.081492 -362.858304)
			(xy 143.570706 -362.858304) (xy 143.560635 -362.858726) (xy 143.54203 -362.86644) (xy 143.534638 -362.87329)
			(xy 141.289976 -365.117952) (xy 194.110065 -365.117952) (xy 194.110065 -365.063448) (xy 194.117822 -365.009498)
			(xy 194.133178 -364.957201) (xy 194.15582 -364.907622) (xy 194.185287 -364.86177) (xy 194.22098 -364.820579)
			(xy 194.262172 -364.784886) (xy 194.308024 -364.755419) (xy 194.357603 -364.732777) (xy 194.4099 -364.717422)
			(xy 194.46385 -364.709665) (xy 194.491102 -364.709202) (xy 194.517968 -364.709649) (xy 194.571169 -364.717189)
			(xy 194.622786 -364.732119) (xy 194.671797 -364.754143) (xy 194.717233 -364.782827) (xy 194.758194 -364.817602)
			(xy 194.793871 -364.857781) (xy 194.823558 -364.902568) (xy 194.835526 -364.926626) (xy 194.842292 -364.939646)
			(xy 194.861922 -364.961438) (xy 194.886936 -364.976752) (xy 194.915271 -364.984326) (xy 194.94459 -364.983533)
			(xy 194.972474 -364.974441) (xy 194.996625 -364.957798) (xy 195.006214 -364.946692) (xy 195.024426 -364.92493)
			(xy 195.066198 -364.886523) (xy 195.113199 -364.854729) (xy 195.164393 -364.830249) (xy 195.218648 -364.813626)
			(xy 195.274767 -364.805224) (xy 195.30314 -364.804706) (xy 195.33039 -364.805167) (xy 195.384336 -364.812928)
			(xy 195.436628 -364.828287) (xy 195.486202 -364.850931) (xy 195.532049 -364.8804) (xy 195.573236 -364.916093)
			(xy 195.608924 -364.957283) (xy 195.638388 -365.003134) (xy 195.661027 -365.05271) (xy 195.676381 -365.105003)
			(xy 195.684136 -365.15895) (xy 195.684136 -365.21345) (xy 195.676381 -365.267397) (xy 195.661027 -365.31969)
			(xy 195.638388 -365.369266) (xy 195.608924 -365.415117) (xy 195.573236 -365.456307) (xy 195.532049 -365.492)
			(xy 195.486202 -365.521469) (xy 195.436628 -365.544113) (xy 195.384336 -365.559472) (xy 195.33039 -365.567233)
			(xy 195.30314 -365.567722) (xy 195.276276 -365.567226) (xy 195.223077 -365.559693) (xy 195.171463 -365.544769)
			(xy 195.122453 -365.522751) (xy 195.077017 -365.494074) (xy 195.036054 -365.459306) (xy 195.000375 -365.419134)
			(xy 194.970686 -365.374353) (xy 194.958716 -365.350298) (xy 194.951897 -365.337311) (xy 194.932271 -365.315537)
			(xy 194.907268 -365.300233) (xy 194.878948 -365.292662) (xy 194.849644 -365.293446) (xy 194.82177 -365.302521)
			(xy 194.797621 -365.319139) (xy 194.788028 -365.330232) (xy 194.769799 -365.351979) (xy 194.72803 -365.390387)
			(xy 194.681032 -365.422182) (xy 194.629842 -365.446663) (xy 194.57559 -365.463291) (xy 194.519473 -365.471698)
			(xy 194.491102 -365.472218) (xy 194.46385 -365.471735) (xy 194.4099 -365.463978) (xy 194.357603 -365.448623)
			(xy 194.308024 -365.425981) (xy 194.262172 -365.396514) (xy 194.22098 -365.360821) (xy 194.185287 -365.31963)
			(xy 194.15582 -365.273778) (xy 194.133178 -365.224199) (xy 194.117822 -365.171902) (xy 194.110065 -365.117952)
			(xy 141.289976 -365.117952) (xy 140.577824 -365.830104) (xy 192.759074 -365.830104) (xy 192.763145 -365.774482)
			(xy 192.775271 -365.720045) (xy 192.795194 -365.667954) (xy 192.82249 -365.619319) (xy 192.856576 -365.575176)
			(xy 192.896725 -365.536467) (xy 192.942083 -365.504016) (xy 192.991683 -365.478515) (xy 193.044467 -365.460508)
			(xy 193.09931 -365.450378) (xy 193.155044 -365.448341) (xy 193.210481 -365.454441) (xy 193.264438 -365.468547)
			(xy 193.315767 -365.490359) (xy 193.363373 -365.519413) (xy 193.406241 -365.555088) (xy 193.443458 -365.596625)
			(xy 193.474231 -365.643138) (xy 193.497903 -365.693635) (xy 193.513971 -365.747042) (xy 193.522091 -365.802218)
			(xy 193.5226 -365.830104) (xy 193.522091 -365.85799) (xy 193.513971 -365.913166) (xy 193.497903 -365.966573)
			(xy 193.474231 -366.01707) (xy 193.443458 -366.063583) (xy 193.406241 -366.10512) (xy 193.363373 -366.140795)
			(xy 193.315767 -366.169849) (xy 193.264438 -366.191661) (xy 193.210481 -366.205767) (xy 193.155044 -366.211867)
			(xy 193.09931 -366.20983) (xy 193.044467 -366.1997) (xy 192.991683 -366.181693) (xy 192.942083 -366.156192)
			(xy 192.896725 -366.123741) (xy 192.856576 -366.085032) (xy 192.82249 -366.040889) (xy 192.795194 -365.992254)
			(xy 192.775271 -365.940163) (xy 192.763145 -365.885726) (xy 192.759074 -365.830104) (xy 140.577824 -365.830104)
			(xy 139.752832 -366.655096) (xy 191.396872 -366.655096) (xy 191.400943 -366.599474) (xy 191.413069 -366.545037)
			(xy 191.432992 -366.492946) (xy 191.460288 -366.444311) (xy 191.494374 -366.400168) (xy 191.534523 -366.361459)
			(xy 191.579881 -366.329008) (xy 191.629481 -366.303507) (xy 191.682265 -366.2855) (xy 191.737108 -366.27537)
			(xy 191.792842 -366.273333) (xy 191.848279 -366.279433) (xy 191.902236 -366.293539) (xy 191.953565 -366.315351)
			(xy 192.001171 -366.344405) (xy 192.044039 -366.38008) (xy 192.081256 -366.421617) (xy 192.112029 -366.46813)
			(xy 192.135701 -366.518627) (xy 192.151769 -366.572034) (xy 192.159889 -366.62721) (xy 192.160398 -366.655096)
			(xy 192.159889 -366.682982) (xy 192.151769 -366.738158) (xy 192.135701 -366.791565) (xy 192.112029 -366.842062)
			(xy 192.081256 -366.888575) (xy 192.044039 -366.930112) (xy 192.001171 -366.965787) (xy 191.953565 -366.994841)
			(xy 191.902236 -367.016653) (xy 191.848279 -367.030759) (xy 191.792842 -367.036859) (xy 191.737108 -367.034822)
			(xy 191.682265 -367.024692) (xy 191.629481 -367.006685) (xy 191.579881 -366.981184) (xy 191.534523 -366.948733)
			(xy 191.494374 -366.910024) (xy 191.460288 -366.865881) (xy 191.432992 -366.817246) (xy 191.413069 -366.765155)
			(xy 191.400943 -366.710718) (xy 191.396872 -366.655096) (xy 139.752832 -366.655096) (xy 139.318492 -367.089436)
			(xy 139.314174 -367.094262) (xy 139.308586 -367.103406) (xy 139.106444 -367.519052) (xy 195.59445 -367.519052)
			(xy 195.59445 -367.464548) (xy 195.602206 -367.410598) (xy 195.617561 -367.358301) (xy 195.640203 -367.308722)
			(xy 195.669669 -367.262869) (xy 195.705361 -367.221676) (xy 195.746551 -367.185982) (xy 195.792402 -367.156513)
			(xy 195.841981 -367.133869) (xy 195.894276 -367.118511) (xy 195.948226 -367.110751) (xy 195.975478 -367.110264)
			(xy 196.002202 -367.110721) (xy 196.055129 -367.11817) (xy 196.1065 -367.132925) (xy 196.155312 -367.154699)
			(xy 196.200611 -367.183065) (xy 196.22135 -367.199926) (xy 196.23278 -367.209578) (xy 196.26199 -367.213388)
			(xy 196.359018 -367.16843) (xy 196.367592 -367.163956) (xy 196.380809 -367.149858) (xy 196.387862 -367.131867)
			(xy 196.388228 -367.122202) (xy 196.388228 -363.514386) (xy 196.388607 -363.492224) (xy 196.394983 -363.448363)
			(xy 196.400928 -363.42701) (xy 196.40296 -363.419898) (xy 196.40296 -358.614218) (xy 196.403725 -358.585231)
			(xy 196.414852 -358.52833) (xy 196.425058 -358.501188) (xy 196.425058 -358.500934) (xy 196.444616 -358.451404)
			(xy 196.446766 -358.446393) (xy 196.452773 -358.437298) (xy 196.456554 -358.43337) (xy 196.493892 -358.397556)
			(xy 196.4944 -358.396794) (xy 196.977 -357.914194) (xy 197.000622 -357.893366) (xy 197.000876 -357.893366)
			(xy 197.021273 -357.87763) (xy 197.066285 -357.85258) (xy 197.114859 -357.835428) (xy 197.165621 -357.826658)
			(xy 197.191376 -357.826056) (xy 198.621396 -357.826056) (xy 198.647952 -357.826604) (xy 198.700459 -357.834603)
			(xy 198.751193 -357.850321) (xy 198.799026 -357.873407) (xy 198.842896 -357.903347) (xy 198.862696 -357.921052)
			(xy 198.863204 -357.921306) (xy 198.865236 -357.923338) (xy 198.865744 -357.923846) (xy 198.880696 -357.938429)
			(xy 198.907433 -357.970519) (xy 198.919084 -357.987854) (xy 198.919338 -357.988362) (xy 198.931276 -358.007666)
			(xy 198.94042 -358.025192) (xy 198.96911 -358.016527) (xy 199.028311 -358.007217) (xy 199.058276 -358.00665)
			(xy 199.088245 -358.007154) (xy 199.147453 -358.016478) (xy 199.176132 -358.025192) (xy 199.185276 -358.007666)
			(xy 199.197214 -357.988362) (xy 199.197468 -357.987854) (xy 199.209119 -357.970519) (xy 199.235858 -357.938431)
			(xy 199.250808 -357.923846) (xy 199.251316 -357.923338) (xy 199.253348 -357.921306) (xy 199.253856 -357.921052)
			(xy 199.273644 -357.903334) (xy 199.31752 -357.873402) (xy 199.365357 -357.850321) (xy 199.416093 -357.834605)
			(xy 199.4686 -357.826603) (xy 199.495156 -357.826056) (xy 201.417682 -357.826056) (xy 201.443309 -357.826535)
			(xy 201.494031 -357.833893) (xy 201.543175 -357.848443) (xy 201.589727 -357.869887) (xy 201.632725 -357.897782)
			(xy 201.671281 -357.93155) (xy 201.704599 -357.970496) (xy 201.718672 -357.991918) (xy 201.7235 -357.999001)
			(xy 201.736882 -358.009702) (xy 201.753033 -358.01542) (xy 201.761598 -358.015794) (xy 201.84745 -358.015794)
			(xy 201.856023 -358.01546) (xy 201.872196 -358.00976) (xy 201.885564 -357.999022) (xy 201.890376 -357.991918)
			(xy 201.90443 -357.97048) (xy 201.937738 -357.931517) (xy 201.976292 -357.897735) (xy 202.019293 -357.869832)
			(xy 202.065851 -357.848387) (xy 202.115004 -357.833842) (xy 202.165736 -357.826498) (xy 202.191366 -357.826056)
			(xy 235.942632 -357.826056) (xy 235.971618 -357.826835) (xy 236.028519 -357.837953) (xy 236.055662 -357.848154)
			(xy 236.055916 -357.848154) (xy 236.105446 -357.867712) (xy 236.110462 -357.869851) (xy 236.119554 -357.875866)
			(xy 236.12348 -357.87965) (xy 236.159294 -357.916988) (xy 236.160056 -357.917496) (xy 236.29674 -358.054262)
			(xy 240.979625 -358.054262) (xy 240.979625 -357.99975) (xy 240.987382 -357.945794) (xy 241.002739 -357.893491)
			(xy 241.025383 -357.843906) (xy 241.054854 -357.798048) (xy 241.090551 -357.756851) (xy 241.131748 -357.721154)
			(xy 241.177606 -357.691683) (xy 241.227191 -357.669039) (xy 241.279494 -357.653682) (xy 241.33345 -357.645925)
			(xy 241.360706 -357.645462) (xy 241.386106 -357.646224) (xy 241.400221 -357.646776) (xy 241.427834 -357.64085)
			(xy 241.452769 -357.627589) (xy 241.47312 -357.608007) (xy 241.487331 -357.583601) (xy 241.494315 -357.556237)
			(xy 241.493539 -357.528005) (xy 241.489738 -357.514398) (xy 241.481556 -357.486534) (xy 241.472755 -357.429134)
			(xy 241.472212 -357.400098) (xy 241.47268 -357.372847) (xy 241.480436 -357.3189) (xy 241.495791 -357.266607)
			(xy 241.518432 -357.21703) (xy 241.547898 -357.171181) (xy 241.583589 -357.129991) (xy 241.624778 -357.0943)
			(xy 241.670627 -357.064834) (xy 241.720204 -357.042193) (xy 241.772497 -357.026837) (xy 241.826444 -357.01908)
			(xy 241.880945 -357.019079) (xy 241.934892 -357.026835) (xy 241.987186 -357.042189) (xy 242.036763 -357.064829)
			(xy 242.082613 -357.094293) (xy 242.123804 -357.129983) (xy 242.159496 -357.171172) (xy 242.188963 -357.217021)
			(xy 242.211605 -357.266597) (xy 242.226961 -357.31889) (xy 242.234719 -357.372837) (xy 242.234721 -357.427338)
			(xy 242.226967 -357.481285) (xy 242.211614 -357.53358) (xy 242.188975 -357.583157) (xy 242.159511 -357.629008)
			(xy 242.123822 -357.670199) (xy 242.082634 -357.705891) (xy 242.036786 -357.735359) (xy 241.98721 -357.758002)
			(xy 241.934917 -357.77336) (xy 241.880971 -357.781119) (xy 241.85372 -357.781606) (xy 241.82832 -357.780844)
			(xy 241.814205 -357.780356) (xy 241.7866 -357.786274) (xy 241.76167 -357.799525) (xy 241.741322 -357.819096)
			(xy 241.72711 -357.84349) (xy 241.720122 -357.870844) (xy 241.720891 -357.899066) (xy 241.724688 -357.91267)
			(xy 241.732863 -357.940536) (xy 241.736916 -357.966956) (xy 245.50903 -357.966956) (xy 245.50903 -357.88226)
			(xy 245.517081 -357.797946) (xy 245.53311 -357.71478) (xy 245.556971 -357.633513) (xy 245.58845 -357.554883)
			(xy 245.627261 -357.479602) (xy 245.673051 -357.40835) (xy 245.725407 -357.341774) (xy 245.783855 -357.280476)
			(xy 245.847865 -357.225011) (xy 245.916857 -357.175882) (xy 245.990207 -357.133533) (xy 246.06725 -357.098349)
			(xy 246.147289 -357.070647) (xy 246.229598 -357.050679) (xy 246.313433 -357.038626) (xy 246.398034 -357.034596)
			(xy 246.482635 -357.038626) (xy 246.56647 -357.050679) (xy 246.648779 -357.070647) (xy 246.728818 -357.098349)
			(xy 246.805861 -357.133533) (xy 246.879211 -357.175882) (xy 246.948203 -357.225011) (xy 247.012213 -357.280476)
			(xy 247.070661 -357.341774) (xy 247.123017 -357.40835) (xy 247.168807 -357.479602) (xy 247.207618 -357.554883)
			(xy 247.239097 -357.633513) (xy 247.262958 -357.71478) (xy 247.278987 -357.797946) (xy 247.287038 -357.88226)
			(xy 247.287542 -357.924608) (xy 247.287038 -357.966956) (xy 247.278987 -358.05127) (xy 247.262958 -358.134436)
			(xy 247.239097 -358.215703) (xy 247.207618 -358.294333) (xy 247.168807 -358.369614) (xy 247.123017 -358.440866)
			(xy 247.070661 -358.507442) (xy 247.012213 -358.56874) (xy 246.948203 -358.624205) (xy 246.879211 -358.673334)
			(xy 246.805861 -358.715683) (xy 246.728818 -358.750867) (xy 246.648779 -358.778569) (xy 246.56647 -358.798537)
			(xy 246.482635 -358.81059) (xy 246.398034 -358.814621) (xy 246.313433 -358.81059) (xy 246.229598 -358.798537)
			(xy 246.147289 -358.778569) (xy 246.06725 -358.750867) (xy 245.990207 -358.715683) (xy 245.916857 -358.673334)
			(xy 245.847865 -358.624205) (xy 245.783855 -358.56874) (xy 245.725407 -358.507442) (xy 245.673051 -358.440866)
			(xy 245.627261 -358.369614) (xy 245.58845 -358.294333) (xy 245.556971 -358.215703) (xy 245.53311 -358.134436)
			(xy 245.517081 -358.05127) (xy 245.50903 -357.966956) (xy 241.736916 -357.966956) (xy 241.741668 -357.997935)
			(xy 241.742214 -358.02697) (xy 241.741777 -358.054226) (xy 241.734024 -358.108182) (xy 241.71867 -358.160487)
			(xy 241.696029 -358.210073) (xy 241.666561 -358.255933) (xy 241.630866 -358.297132) (xy 241.589671 -358.332832)
			(xy 241.543816 -358.362305) (xy 241.494232 -358.384953) (xy 241.441929 -358.400313) (xy 241.387974 -358.408074)
			(xy 241.333462 -358.408076) (xy 241.279506 -358.400321) (xy 241.227202 -358.384966) (xy 241.177616 -358.362323)
			(xy 241.131757 -358.332853) (xy 241.090559 -358.297158) (xy 241.054861 -358.255962) (xy 241.025389 -358.210105)
			(xy 241.002743 -358.16052) (xy 240.987384 -358.108218) (xy 240.979625 -358.054262) (xy 236.29674 -358.054262)
			(xy 236.58576 -358.343454) (xy 236.768386 -358.52608) (xy 236.76864 -358.526334) (xy 236.801914 -358.559354)
			(xy 236.822742 -358.582976) (xy 236.822742 -358.58323) (xy 236.838444 -358.603652) (xy 236.863505 -358.648654)
			(xy 236.880667 -358.697221) (xy 236.889446 -358.747977) (xy 236.890052 -358.77373) (xy 236.890052 -360.631232)
			(xy 236.906816 -360.656632) (xy 236.921294 -360.662474) (xy 236.930735 -360.665802) (xy 236.950727 -360.66583)
			(xy 236.969222 -360.658241) (xy 236.976666 -360.651552) (xy 237.323376 -360.304588) (xy 237.331758 -360.304588)
			(xy 237.334044 -360.302556) (xy 245.510304 -360.302556) (xy 245.520375 -360.302144) (xy 245.538973 -360.294415)
			(xy 245.546372 -360.28757) (xy 246.551196 -359.282492) (xy 246.558657 -359.275773) (xy 246.577232 -359.268196)
			(xy 246.587264 -359.26776) (xy 251.495814 -359.26776) (xy 251.505885 -359.267352) (xy 251.524484 -359.25962)
			(xy 251.531882 -359.252774) (xy 252.421644 -358.363012) (xy 252.428365 -358.355552) (xy 252.435939 -358.336977)
			(xy 252.436376 -358.326944) (xy 252.436376 -357.009446) (xy 252.436806 -356.999377) (xy 252.444521 -356.980778)
			(xy 252.451362 -356.973378) (xy 253.023624 -356.401116) (xy 253.031102 -356.394418) (xy 253.049664 -356.386832)
			(xy 253.059692 -356.386384) (xy 261.450074 -356.386384) (xy 261.460123 -356.386719) (xy 261.47872 -356.39433)
			(xy 261.486142 -356.401116) (xy 261.992872 -356.907846) (xy 261.999578 -356.915317) (xy 262.00716 -356.933884)
			(xy 262.007604 -356.943914) (xy 262.007604 -357.784966) (xy 270.624854 -357.784966) (xy 270.624854 -357.730435)
			(xy 270.632614 -357.676458) (xy 270.647977 -357.624136) (xy 270.670628 -357.574532) (xy 270.700108 -357.528657)
			(xy 270.735817 -357.487443) (xy 270.777026 -357.451731) (xy 270.822899 -357.422246) (xy 270.8725 -357.39959)
			(xy 270.924821 -357.384222) (xy 270.978797 -357.376457) (xy 271.006062 -357.375968) (xy 271.869662 -357.375968)
			(xy 271.896937 -357.376369) (xy 271.950932 -357.384127) (xy 272.003273 -357.399491) (xy 272.052895 -357.422149)
			(xy 272.098787 -357.451638) (xy 272.140015 -357.487358) (xy 272.17574 -357.528582) (xy 272.205233 -357.574471)
			(xy 272.227895 -357.624091) (xy 272.243265 -357.676431) (xy 272.251028 -357.730425) (xy 272.251028 -357.78497)
			(xy 273.733731 -357.78497) (xy 273.733731 -357.73043) (xy 273.741494 -357.676446) (xy 273.75686 -357.624115)
			(xy 273.779517 -357.574505) (xy 273.809005 -357.528623) (xy 273.844722 -357.487406) (xy 273.885941 -357.451691)
			(xy 273.931824 -357.422207) (xy 273.981436 -357.399552) (xy 274.033767 -357.384189) (xy 274.087752 -357.37643)
			(xy 274.115022 -357.375968) (xy 274.978622 -357.375968) (xy 275.005892 -357.376396) (xy 275.059878 -357.384161)
			(xy 275.112209 -357.399529) (xy 275.16182 -357.422189) (xy 275.207702 -357.451677) (xy 275.24892 -357.487395)
			(xy 275.284636 -357.528616) (xy 275.314122 -357.574499) (xy 275.336778 -357.624112) (xy 275.352144 -357.676444)
			(xy 275.359906 -357.730429) (xy 275.359906 -357.784966) (xy 276.842754 -357.784966) (xy 276.842754 -357.730434)
			(xy 276.850515 -357.676456) (xy 276.865878 -357.624132) (xy 276.888531 -357.574527) (xy 276.918013 -357.52865)
			(xy 276.953724 -357.487436) (xy 276.994936 -357.451724) (xy 277.040811 -357.42224) (xy 277.090415 -357.399584)
			(xy 277.142738 -357.384219) (xy 277.196716 -357.376456) (xy 277.223982 -357.375968) (xy 278.087582 -357.375968)
			(xy 278.114856 -357.37637) (xy 278.168849 -357.384131) (xy 278.221188 -357.399497) (xy 278.270807 -357.422155)
			(xy 278.316697 -357.451645) (xy 278.357922 -357.487365) (xy 278.393644 -357.528589) (xy 278.423136 -357.574477)
			(xy 278.445797 -357.624095) (xy 278.461165 -357.676433) (xy 278.468928 -357.730426) (xy 278.468928 -357.784971)
			(xy 279.951632 -357.784971) (xy 279.951632 -357.730429) (xy 279.959394 -357.676443) (xy 279.974761 -357.624111)
			(xy 279.99742 -357.574499) (xy 280.026909 -357.528617) (xy 280.062629 -357.487399) (xy 280.103851 -357.451684)
			(xy 280.149736 -357.4222) (xy 280.19935 -357.399547) (xy 280.251684 -357.384185) (xy 280.305671 -357.376429)
			(xy 280.332942 -357.375968) (xy 281.196542 -357.375968) (xy 281.223812 -357.376397) (xy 281.277795 -357.384165)
			(xy 281.330123 -357.399535) (xy 281.379732 -357.422195) (xy 281.425611 -357.451684) (xy 281.466827 -357.487402)
			(xy 281.502541 -357.528622) (xy 281.532025 -357.574505) (xy 281.55468 -357.624116) (xy 281.570044 -357.676446)
			(xy 281.577806 -357.73043) (xy 281.577806 -357.784969) (xy 283.060631 -357.784969) (xy 283.060631 -357.730431)
			(xy 283.068393 -357.676448) (xy 283.083758 -357.62412) (xy 283.106414 -357.57451) (xy 283.1359 -357.52863)
			(xy 283.171614 -357.487413) (xy 283.212832 -357.451698) (xy 283.258712 -357.422213) (xy 283.308321 -357.399557)
			(xy 283.36065 -357.384193) (xy 283.414633 -357.376431) (xy 283.441902 -357.375968) (xy 284.305502 -357.375968)
			(xy 284.332773 -357.376395) (xy 284.386761 -357.384157) (xy 284.439094 -357.399524) (xy 284.488708 -357.422182)
			(xy 284.534593 -357.45167) (xy 284.575813 -357.487388) (xy 284.611531 -357.528609) (xy 284.641019 -357.574493)
			(xy 284.663677 -357.624107) (xy 284.679043 -357.676441) (xy 284.686806 -357.730429) (xy 284.686806 -357.784966)
			(xy 286.169654 -357.784966) (xy 286.169654 -357.730435) (xy 286.177414 -357.676458) (xy 286.192777 -357.624136)
			(xy 286.215428 -357.574532) (xy 286.244908 -357.528657) (xy 286.280617 -357.487443) (xy 286.321826 -357.451731)
			(xy 286.367699 -357.422246) (xy 286.4173 -357.39959) (xy 286.469621 -357.384222) (xy 286.523597 -357.376457)
			(xy 286.550862 -357.375968) (xy 287.414462 -357.375968) (xy 287.441737 -357.376369) (xy 287.495732 -357.384127)
			(xy 287.548073 -357.399491) (xy 287.597695 -357.422149) (xy 287.643587 -357.451638) (xy 287.684815 -357.487358)
			(xy 287.72054 -357.528582) (xy 287.750033 -357.574471) (xy 287.772695 -357.624091) (xy 287.788065 -357.676431)
			(xy 287.795828 -357.730425) (xy 287.795828 -357.78497) (xy 289.278531 -357.78497) (xy 289.278531 -357.73043)
			(xy 289.286294 -357.676446) (xy 289.30166 -357.624115) (xy 289.324317 -357.574505) (xy 289.353805 -357.528623)
			(xy 289.389522 -357.487406) (xy 289.430741 -357.451691) (xy 289.476624 -357.422207) (xy 289.526236 -357.399552)
			(xy 289.578567 -357.384189) (xy 289.632552 -357.37643) (xy 289.659822 -357.375968) (xy 290.523422 -357.375968)
			(xy 290.550692 -357.376396) (xy 290.604678 -357.384161) (xy 290.657009 -357.399529) (xy 290.70662 -357.422189)
			(xy 290.752502 -357.451677) (xy 290.79372 -357.487395) (xy 290.829436 -357.528616) (xy 290.858922 -357.574499)
			(xy 290.881578 -357.624112) (xy 290.896944 -357.676444) (xy 290.904706 -357.730429) (xy 290.904706 -357.784966)
			(xy 292.387554 -357.784966) (xy 292.387554 -357.730434) (xy 292.395315 -357.676456) (xy 292.410678 -357.624132)
			(xy 292.433331 -357.574527) (xy 292.462813 -357.52865) (xy 292.498524 -357.487436) (xy 292.539736 -357.451724)
			(xy 292.585611 -357.42224) (xy 292.635215 -357.399584) (xy 292.687538 -357.384219) (xy 292.741516 -357.376456)
			(xy 292.768782 -357.375968) (xy 293.632382 -357.375968) (xy 293.659656 -357.37637) (xy 293.713649 -357.384131)
			(xy 293.765988 -357.399497) (xy 293.815607 -357.422155) (xy 293.861497 -357.451645) (xy 293.902722 -357.487365)
			(xy 293.938444 -357.528589) (xy 293.967936 -357.574477) (xy 293.990597 -357.624095) (xy 294.005965 -357.676433)
			(xy 294.013728 -357.730426) (xy 294.013728 -357.784971) (xy 295.496432 -357.784971) (xy 295.496432 -357.730429)
			(xy 295.504194 -357.676443) (xy 295.519561 -357.624111) (xy 295.54222 -357.574499) (xy 295.571709 -357.528617)
			(xy 295.607429 -357.487399) (xy 295.648651 -357.451684) (xy 295.694536 -357.4222) (xy 295.74415 -357.399547)
			(xy 295.796484 -357.384185) (xy 295.850471 -357.376429) (xy 295.877742 -357.375968) (xy 296.741342 -357.375968)
			(xy 296.768612 -357.376397) (xy 296.822595 -357.384165) (xy 296.874923 -357.399535) (xy 296.924532 -357.422195)
			(xy 296.970411 -357.451684) (xy 297.011627 -357.487402) (xy 297.047341 -357.528622) (xy 297.076825 -357.574505)
			(xy 297.09948 -357.624116) (xy 297.114844 -357.676446) (xy 297.122606 -357.73043) (xy 297.122606 -357.784969)
			(xy 298.605431 -357.784969) (xy 298.605431 -357.730431) (xy 298.613193 -357.676448) (xy 298.628558 -357.62412)
			(xy 298.651214 -357.57451) (xy 298.6807 -357.52863) (xy 298.716414 -357.487413) (xy 298.757632 -357.451698)
			(xy 298.803512 -357.422213) (xy 298.853121 -357.399557) (xy 298.90545 -357.384193) (xy 298.959433 -357.376431)
			(xy 298.986702 -357.375968) (xy 299.850302 -357.375968) (xy 299.877573 -357.376395) (xy 299.931561 -357.384157)
			(xy 299.983894 -357.399524) (xy 300.033508 -357.422182) (xy 300.079393 -357.45167) (xy 300.120613 -357.487388)
			(xy 300.156331 -357.528609) (xy 300.185819 -357.574493) (xy 300.208477 -357.624107) (xy 300.223843 -357.676441)
			(xy 300.231606 -357.730429) (xy 300.231606 -357.784971) (xy 300.223843 -357.838959) (xy 300.208477 -357.891293)
			(xy 300.185819 -357.940907) (xy 300.156331 -357.986791) (xy 300.120613 -358.028012) (xy 300.079393 -358.06373)
			(xy 300.033508 -358.093218) (xy 299.983894 -358.115876) (xy 299.931561 -358.131243) (xy 299.877573 -358.139005)
			(xy 299.850302 -358.139492) (xy 298.986702 -358.139492) (xy 298.959433 -358.138969) (xy 298.90545 -358.131207)
			(xy 298.853121 -358.115843) (xy 298.803512 -358.093187) (xy 298.757632 -358.063702) (xy 298.716414 -358.027987)
			(xy 298.6807 -357.98677) (xy 298.651214 -357.94089) (xy 298.628558 -357.89128) (xy 298.613193 -357.838952)
			(xy 298.605431 -357.784969) (xy 297.122606 -357.784969) (xy 297.122606 -357.78497) (xy 297.114844 -357.838954)
			(xy 297.09948 -357.891284) (xy 297.076825 -357.940895) (xy 297.047341 -357.986778) (xy 297.011627 -358.027998)
			(xy 296.970411 -358.063716) (xy 296.924532 -358.093205) (xy 296.874923 -358.115865) (xy 296.822595 -358.131235)
			(xy 296.768612 -358.139003) (xy 296.741342 -358.139492) (xy 295.877742 -358.139492) (xy 295.850471 -358.138971)
			(xy 295.796484 -358.131215) (xy 295.74415 -358.115853) (xy 295.694536 -358.0932) (xy 295.64865 -358.063716)
			(xy 295.607429 -358.028001) (xy 295.571709 -357.986783) (xy 295.54222 -357.940901) (xy 295.519561 -357.891289)
			(xy 295.504194 -357.838957) (xy 295.496432 -357.784971) (xy 294.013728 -357.784971) (xy 294.013728 -357.784974)
			(xy 294.005965 -357.838967) (xy 293.990597 -357.891305) (xy 293.967936 -357.940923) (xy 293.938444 -357.986811)
			(xy 293.902722 -358.028035) (xy 293.861497 -358.063755) (xy 293.815607 -358.093245) (xy 293.765988 -358.115903)
			(xy 293.713649 -358.131269) (xy 293.659656 -358.13903) (xy 293.632382 -358.139492) (xy 292.768782 -358.139492)
			(xy 292.741516 -358.138944) (xy 292.687538 -358.131181) (xy 292.635215 -358.115816) (xy 292.585611 -358.09316)
			(xy 292.539736 -358.063676) (xy 292.498524 -358.027964) (xy 292.462813 -357.98675) (xy 292.433331 -357.940873)
			(xy 292.410678 -357.891268) (xy 292.395315 -357.838944) (xy 292.387554 -357.784966) (xy 290.904706 -357.784966)
			(xy 290.904706 -357.784971) (xy 290.896944 -357.838956) (xy 290.881578 -357.891288) (xy 290.858922 -357.940901)
			(xy 290.829436 -357.986784) (xy 290.79372 -358.028005) (xy 290.752502 -358.063723) (xy 290.70662 -358.093211)
			(xy 290.657009 -358.115871) (xy 290.604678 -358.131239) (xy 290.550692 -358.139004) (xy 290.523422 -358.139492)
			(xy 289.659822 -358.139492) (xy 289.632552 -358.13897) (xy 289.578567 -358.131211) (xy 289.526236 -358.115848)
			(xy 289.476624 -358.093193) (xy 289.430741 -358.063709) (xy 289.389522 -358.027994) (xy 289.353805 -357.986777)
			(xy 289.324317 -357.940895) (xy 289.30166 -357.891285) (xy 289.286294 -357.838954) (xy 289.278531 -357.78497)
			(xy 287.795828 -357.78497) (xy 287.795828 -357.784975) (xy 287.788065 -357.838969) (xy 287.772695 -357.891309)
			(xy 287.750033 -357.940929) (xy 287.72054 -357.986818) (xy 287.684815 -358.028042) (xy 287.643587 -358.063762)
			(xy 287.597695 -358.093251) (xy 287.548073 -358.115908) (xy 287.495732 -358.131273) (xy 287.441737 -358.139031)
			(xy 287.414462 -358.139492) (xy 286.550862 -358.139492) (xy 286.523597 -358.138943) (xy 286.469621 -358.131178)
			(xy 286.4173 -358.11581) (xy 286.367699 -358.093154) (xy 286.321826 -358.063669) (xy 286.280617 -358.027957)
			(xy 286.244908 -357.986743) (xy 286.215428 -357.940868) (xy 286.192777 -357.891264) (xy 286.177414 -357.838942)
			(xy 286.169654 -357.784966) (xy 284.686806 -357.784966) (xy 284.686806 -357.784971) (xy 284.679043 -357.838959)
			(xy 284.663677 -357.891293) (xy 284.641019 -357.940907) (xy 284.611531 -357.986791) (xy 284.575813 -358.028012)
			(xy 284.534593 -358.06373) (xy 284.488708 -358.093218) (xy 284.439094 -358.115876) (xy 284.386761 -358.131243)
			(xy 284.332773 -358.139005) (xy 284.305502 -358.139492) (xy 283.441902 -358.139492) (xy 283.414633 -358.138969)
			(xy 283.36065 -358.131207) (xy 283.308321 -358.115843) (xy 283.258712 -358.093187) (xy 283.212832 -358.063702)
			(xy 283.171614 -358.027987) (xy 283.1359 -357.98677) (xy 283.106414 -357.94089) (xy 283.083758 -357.89128)
			(xy 283.068393 -357.838952) (xy 283.060631 -357.784969) (xy 281.577806 -357.784969) (xy 281.577806 -357.78497)
			(xy 281.570044 -357.838954) (xy 281.55468 -357.891284) (xy 281.532025 -357.940895) (xy 281.502541 -357.986778)
			(xy 281.466827 -358.027998) (xy 281.425611 -358.063716) (xy 281.379732 -358.093205) (xy 281.330123 -358.115865)
			(xy 281.277795 -358.131235) (xy 281.223812 -358.139003) (xy 281.196542 -358.139492) (xy 280.332942 -358.139492)
			(xy 280.305671 -358.138971) (xy 280.251684 -358.131215) (xy 280.19935 -358.115853) (xy 280.149736 -358.0932)
			(xy 280.10385 -358.063716) (xy 280.062629 -358.028001) (xy 280.026909 -357.986783) (xy 279.99742 -357.940901)
			(xy 279.974761 -357.891289) (xy 279.959394 -357.838957) (xy 279.951632 -357.784971) (xy 278.468928 -357.784971)
			(xy 278.468928 -357.784974) (xy 278.461165 -357.838967) (xy 278.445797 -357.891305) (xy 278.423136 -357.940923)
			(xy 278.393644 -357.986811) (xy 278.357922 -358.028035) (xy 278.316697 -358.063755) (xy 278.270807 -358.093245)
			(xy 278.221188 -358.115903) (xy 278.168849 -358.131269) (xy 278.114856 -358.13903) (xy 278.087582 -358.139492)
			(xy 277.223982 -358.139492) (xy 277.196716 -358.138944) (xy 277.142738 -358.131181) (xy 277.090415 -358.115816)
			(xy 277.040811 -358.09316) (xy 276.994936 -358.063676) (xy 276.953724 -358.027964) (xy 276.918013 -357.98675)
			(xy 276.888531 -357.940873) (xy 276.865878 -357.891268) (xy 276.850515 -357.838944) (xy 276.842754 -357.784966)
			(xy 275.359906 -357.784966) (xy 275.359906 -357.784971) (xy 275.352144 -357.838956) (xy 275.336778 -357.891288)
			(xy 275.314122 -357.940901) (xy 275.284636 -357.986784) (xy 275.24892 -358.028005) (xy 275.207702 -358.063723)
			(xy 275.16182 -358.093211) (xy 275.112209 -358.115871) (xy 275.059878 -358.131239) (xy 275.005892 -358.139004)
			(xy 274.978622 -358.139492) (xy 274.115022 -358.139492) (xy 274.087752 -358.13897) (xy 274.033767 -358.131211)
			(xy 273.981436 -358.115848) (xy 273.931824 -358.093193) (xy 273.885941 -358.063709) (xy 273.844722 -358.027994)
			(xy 273.809005 -357.986777) (xy 273.779517 -357.940895) (xy 273.75686 -357.891285) (xy 273.741494 -357.838954)
			(xy 273.733731 -357.78497) (xy 272.251028 -357.78497) (xy 272.251028 -357.784975) (xy 272.243265 -357.838969)
			(xy 272.227895 -357.891309) (xy 272.205233 -357.940929) (xy 272.17574 -357.986818) (xy 272.140015 -358.028042)
			(xy 272.098787 -358.063762) (xy 272.052895 -358.093251) (xy 272.003273 -358.115908) (xy 271.950932 -358.131273)
			(xy 271.896937 -358.139031) (xy 271.869662 -358.139492) (xy 271.006062 -358.139492) (xy 270.978797 -358.138943)
			(xy 270.924821 -358.131178) (xy 270.8725 -358.11581) (xy 270.822899 -358.093154) (xy 270.777026 -358.063669)
			(xy 270.735817 -358.027957) (xy 270.700108 -357.986743) (xy 270.670628 -357.940868) (xy 270.647977 -357.891264)
			(xy 270.632614 -357.838942) (xy 270.624854 -357.784966) (xy 262.007604 -357.784966) (xy 262.007604 -360.644948)
			(xy 262.008029 -360.655018) (xy 262.015747 -360.673617) (xy 262.02259 -360.681016) (xy 262.192516 -360.850942)
			(xy 262.199912 -360.857787) (xy 262.218514 -360.865503) (xy 262.228584 -360.865928) (xy 265.778234 -360.865928)
			(xy 265.788279 -360.866298) (xy 265.806876 -360.873886) (xy 265.814302 -360.88066) (xy 266.857734 -361.924092)
			(xy 266.864568 -361.931497) (xy 266.87229 -361.950093) (xy 266.87272 -361.96016) (xy 266.87272 -366.02797)
			(xy 266.8723 -366.03804) (xy 266.864578 -366.056639) (xy 266.857734 -366.064038) (xy 266.5476 -366.373918)
			(xy 266.540955 -366.381398) (xy 266.533356 -366.39988) (xy 266.533344 -366.419863) (xy 266.540922 -366.438353)
			(xy 266.5476 -366.4458) (xy 266.723622 -366.621822) (xy 266.730467 -366.629218) (xy 266.738184 -366.64782)
			(xy 266.738608 -366.65789) (xy 266.738608 -367.167414) (xy 271.30705 -367.167414) (xy 271.311121 -367.111792)
			(xy 271.323247 -367.057355) (xy 271.34317 -367.005264) (xy 271.370466 -366.956629) (xy 271.404552 -366.912486)
			(xy 271.444701 -366.873777) (xy 271.490059 -366.841326) (xy 271.539659 -366.815825) (xy 271.592443 -366.797818)
			(xy 271.647286 -366.787688) (xy 271.70302 -366.785651) (xy 271.758457 -366.791751) (xy 271.812414 -366.805857)
			(xy 271.863743 -366.827669) (xy 271.911349 -366.856723) (xy 271.954217 -366.892398) (xy 271.991434 -366.933935)
			(xy 272.022207 -366.980448) (xy 272.045879 -367.030945) (xy 272.061947 -367.084352) (xy 272.070067 -367.139528)
			(xy 272.070576 -367.167414) (xy 272.070067 -367.1953) (xy 272.061947 -367.250476) (xy 272.045879 -367.303883)
			(xy 272.022207 -367.35438) (xy 271.991434 -367.400893) (xy 271.954217 -367.44243) (xy 271.911349 -367.478105)
			(xy 271.863743 -367.507159) (xy 271.812414 -367.528971) (xy 271.758457 -367.543077) (xy 271.70302 -367.549177)
			(xy 271.647286 -367.54714) (xy 271.592443 -367.53701) (xy 271.539659 -367.519003) (xy 271.490059 -367.493502)
			(xy 271.444701 -367.461051) (xy 271.404552 -367.422342) (xy 271.370466 -367.378199) (xy 271.34317 -367.329564)
			(xy 271.323247 -367.277473) (xy 271.311121 -367.223036) (xy 271.30705 -367.167414) (xy 266.738608 -367.167414)
			(xy 266.738608 -368.632994) (xy 271.108676 -368.632994) (xy 271.112747 -368.577372) (xy 271.124873 -368.522935)
			(xy 271.144796 -368.470844) (xy 271.172092 -368.422209) (xy 271.206178 -368.378066) (xy 271.246327 -368.339357)
			(xy 271.291685 -368.306906) (xy 271.341285 -368.281405) (xy 271.394069 -368.263398) (xy 271.448912 -368.253268)
			(xy 271.504646 -368.251231) (xy 271.560083 -368.257331) (xy 271.61404 -368.271437) (xy 271.665369 -368.293249)
			(xy 271.712975 -368.322303) (xy 271.755843 -368.357978) (xy 271.79306 -368.399515) (xy 271.823833 -368.446028)
			(xy 271.847505 -368.496525) (xy 271.863573 -368.549932) (xy 271.871693 -368.605108) (xy 271.872202 -368.632994)
			(xy 271.871693 -368.66088) (xy 271.863573 -368.716056) (xy 271.847505 -368.769463) (xy 271.823833 -368.81996)
			(xy 271.79306 -368.866473) (xy 271.755843 -368.90801) (xy 271.712975 -368.943685) (xy 271.665369 -368.972739)
			(xy 271.624472 -368.990118) (xy 289.203646 -368.990118) (xy 289.207637 -368.927951) (xy 289.219546 -368.866804)
			(xy 289.239175 -368.807683) (xy 289.266204 -368.751557) (xy 289.300188 -368.699348) (xy 289.34057 -368.651913)
			(xy 289.386686 -368.610032) (xy 289.437778 -368.574392) (xy 289.493009 -368.545578) (xy 289.551471 -368.524064)
			(xy 289.612205 -368.510202) (xy 289.674212 -368.50422) (xy 289.736475 -368.506216) (xy 289.797972 -368.516159)
			(xy 289.857693 -368.533883) (xy 289.914656 -368.5591) (xy 289.967927 -368.591393) (xy 290.016632 -368.630233)
			(xy 290.059969 -368.674983) (xy 290.097229 -368.724907) (xy 290.127798 -368.779186) (xy 290.151176 -368.836929)
			(xy 290.166977 -368.897187) (xy 290.174943 -368.95897) (xy 290.175442 -368.990118) (xy 293.603688 -368.990118)
			(xy 293.607679 -368.927951) (xy 293.619588 -368.866804) (xy 293.639217 -368.807683) (xy 293.666246 -368.751557)
			(xy 293.70023 -368.699348) (xy 293.740612 -368.651913) (xy 293.786728 -368.610032) (xy 293.83782 -368.574392)
			(xy 293.893051 -368.545578) (xy 293.951513 -368.524064) (xy 294.012247 -368.510202) (xy 294.074254 -368.50422)
			(xy 294.136517 -368.506216) (xy 294.198014 -368.516159) (xy 294.257735 -368.533883) (xy 294.314698 -368.5591)
			(xy 294.367969 -368.591393) (xy 294.416674 -368.630233) (xy 294.460011 -368.674983) (xy 294.497271 -368.724907)
			(xy 294.52784 -368.779186) (xy 294.551218 -368.836929) (xy 294.567019 -368.897187) (xy 294.574985 -368.95897)
			(xy 294.575484 -368.990118) (xy 298.00373 -368.990118) (xy 298.007721 -368.927951) (xy 298.01963 -368.866804)
			(xy 298.039259 -368.807683) (xy 298.066288 -368.751557) (xy 298.100272 -368.699348) (xy 298.140654 -368.651913)
			(xy 298.18677 -368.610032) (xy 298.237862 -368.574392) (xy 298.293093 -368.545578) (xy 298.351555 -368.524064)
			(xy 298.412289 -368.510202) (xy 298.474296 -368.50422) (xy 298.536559 -368.506216) (xy 298.598056 -368.516159)
			(xy 298.657777 -368.533883) (xy 298.71474 -368.5591) (xy 298.768011 -368.591393) (xy 298.816716 -368.630233)
			(xy 298.860053 -368.674983) (xy 298.897313 -368.724907) (xy 298.927882 -368.779186) (xy 298.95126 -368.836929)
			(xy 298.967061 -368.897187) (xy 298.975027 -368.95897) (xy 298.975526 -368.990118) (xy 302.403772 -368.990118)
			(xy 302.407763 -368.927951) (xy 302.419672 -368.866804) (xy 302.439301 -368.807683) (xy 302.46633 -368.751557)
			(xy 302.500314 -368.699348) (xy 302.540696 -368.651913) (xy 302.586812 -368.610032) (xy 302.637904 -368.574392)
			(xy 302.693135 -368.545578) (xy 302.751597 -368.524064) (xy 302.812331 -368.510202) (xy 302.874338 -368.50422)
			(xy 302.936601 -368.506216) (xy 302.998098 -368.516159) (xy 303.057819 -368.533883) (xy 303.114782 -368.5591)
			(xy 303.168053 -368.591393) (xy 303.216758 -368.630233) (xy 303.260095 -368.674983) (xy 303.297355 -368.724907)
			(xy 303.327924 -368.779186) (xy 303.351302 -368.836929) (xy 303.367103 -368.897187) (xy 303.375069 -368.95897)
			(xy 303.375568 -368.990118) (xy 306.803814 -368.990118) (xy 306.807805 -368.927951) (xy 306.819714 -368.866804)
			(xy 306.839343 -368.807683) (xy 306.866372 -368.751557) (xy 306.900356 -368.699348) (xy 306.940738 -368.651913)
			(xy 306.986854 -368.610032) (xy 307.037946 -368.574392) (xy 307.093177 -368.545578) (xy 307.151639 -368.524064)
			(xy 307.212373 -368.510202) (xy 307.27438 -368.50422) (xy 307.336643 -368.506216) (xy 307.39814 -368.516159)
			(xy 307.457861 -368.533883) (xy 307.514824 -368.5591) (xy 307.568095 -368.591393) (xy 307.6168 -368.630233)
			(xy 307.660137 -368.674983) (xy 307.697397 -368.724907) (xy 307.727966 -368.779186) (xy 307.751344 -368.836929)
			(xy 307.767145 -368.897187) (xy 307.775111 -368.95897) (xy 307.77561 -368.990118) (xy 307.775111 -369.021266)
			(xy 307.767145 -369.083049) (xy 307.751344 -369.143307) (xy 307.727966 -369.20105) (xy 307.697397 -369.255329)
			(xy 307.660137 -369.305253) (xy 307.6168 -369.350003) (xy 307.568095 -369.388843) (xy 307.514824 -369.421136)
			(xy 307.457861 -369.446353) (xy 307.39814 -369.464077) (xy 307.336643 -369.47402) (xy 307.27438 -369.476016)
			(xy 307.212373 -369.470034) (xy 307.151639 -369.456172) (xy 307.093177 -369.434658) (xy 307.037946 -369.405844)
			(xy 306.986854 -369.370204) (xy 306.940738 -369.328323) (xy 306.900356 -369.280888) (xy 306.866372 -369.228679)
			(xy 306.839343 -369.172553) (xy 306.819714 -369.113432) (xy 306.807805 -369.052285) (xy 306.803814 -368.990118)
			(xy 303.375568 -368.990118) (xy 303.375069 -369.021266) (xy 303.367103 -369.083049) (xy 303.351302 -369.143307)
			(xy 303.327924 -369.20105) (xy 303.297355 -369.255329) (xy 303.260095 -369.305253) (xy 303.216758 -369.350003)
			(xy 303.168053 -369.388843) (xy 303.114782 -369.421136) (xy 303.057819 -369.446353) (xy 302.998098 -369.464077)
			(xy 302.936601 -369.47402) (xy 302.874338 -369.476016) (xy 302.812331 -369.470034) (xy 302.751597 -369.456172)
			(xy 302.693135 -369.434658) (xy 302.637904 -369.405844) (xy 302.586812 -369.370204) (xy 302.540696 -369.328323)
			(xy 302.500314 -369.280888) (xy 302.46633 -369.228679) (xy 302.439301 -369.172553) (xy 302.419672 -369.113432)
			(xy 302.407763 -369.052285) (xy 302.403772 -368.990118) (xy 298.975526 -368.990118) (xy 298.975027 -369.021266)
			(xy 298.967061 -369.083049) (xy 298.95126 -369.143307) (xy 298.927882 -369.20105) (xy 298.897313 -369.255329)
			(xy 298.860053 -369.305253) (xy 298.816716 -369.350003) (xy 298.768011 -369.388843) (xy 298.71474 -369.421136)
			(xy 298.657777 -369.446353) (xy 298.598056 -369.464077) (xy 298.536559 -369.47402) (xy 298.474296 -369.476016)
			(xy 298.412289 -369.470034) (xy 298.351555 -369.456172) (xy 298.293093 -369.434658) (xy 298.237862 -369.405844)
			(xy 298.18677 -369.370204) (xy 298.140654 -369.328323) (xy 298.100272 -369.280888) (xy 298.066288 -369.228679)
			(xy 298.039259 -369.172553) (xy 298.01963 -369.113432) (xy 298.007721 -369.052285) (xy 298.00373 -368.990118)
			(xy 294.575484 -368.990118) (xy 294.574985 -369.021266) (xy 294.567019 -369.083049) (xy 294.551218 -369.143307)
			(xy 294.52784 -369.20105) (xy 294.497271 -369.255329) (xy 294.460011 -369.305253) (xy 294.416674 -369.350003)
			(xy 294.367969 -369.388843) (xy 294.314698 -369.421136) (xy 294.257735 -369.446353) (xy 294.198014 -369.464077)
			(xy 294.136517 -369.47402) (xy 294.074254 -369.476016) (xy 294.012247 -369.470034) (xy 293.951513 -369.456172)
			(xy 293.893051 -369.434658) (xy 293.83782 -369.405844) (xy 293.786728 -369.370204) (xy 293.740612 -369.328323)
			(xy 293.70023 -369.280888) (xy 293.666246 -369.228679) (xy 293.639217 -369.172553) (xy 293.619588 -369.113432)
			(xy 293.607679 -369.052285) (xy 293.603688 -368.990118) (xy 290.175442 -368.990118) (xy 290.174943 -369.021266)
			(xy 290.166977 -369.083049) (xy 290.151176 -369.143307) (xy 290.127798 -369.20105) (xy 290.097229 -369.255329)
			(xy 290.059969 -369.305253) (xy 290.016632 -369.350003) (xy 289.967927 -369.388843) (xy 289.914656 -369.421136)
			(xy 289.857693 -369.446353) (xy 289.797972 -369.464077) (xy 289.736475 -369.47402) (xy 289.674212 -369.476016)
			(xy 289.612205 -369.470034) (xy 289.551471 -369.456172) (xy 289.493009 -369.434658) (xy 289.437778 -369.405844)
			(xy 289.386686 -369.370204) (xy 289.34057 -369.328323) (xy 289.300188 -369.280888) (xy 289.266204 -369.228679)
			(xy 289.239175 -369.172553) (xy 289.219546 -369.113432) (xy 289.207637 -369.052285) (xy 289.203646 -368.990118)
			(xy 271.624472 -368.990118) (xy 271.61404 -368.994551) (xy 271.560083 -369.008657) (xy 271.504646 -369.014757)
			(xy 271.448912 -369.01272) (xy 271.394069 -369.00259) (xy 271.341285 -368.984583) (xy 271.291685 -368.959082)
			(xy 271.246327 -368.926631) (xy 271.206178 -368.887922) (xy 271.172092 -368.843779) (xy 271.144796 -368.795144)
			(xy 271.124873 -368.743053) (xy 271.112747 -368.688616) (xy 271.108676 -368.632994) (xy 266.738608 -368.632994)
			(xy 266.738608 -370.522712) (xy 287.004772 -370.522712) (xy 287.004773 -370.457268) (xy 287.013569 -370.392417)
			(xy 287.030998 -370.329336) (xy 287.056746 -370.26917) (xy 287.073086 -370.240814) (xy 287.07644 -370.234794)
			(xy 287.080183 -370.221538) (xy 287.080452 -370.214652) (xy 287.080452 -369.928902) (xy 287.080929 -369.918774)
			(xy 287.088658 -369.900051) (xy 287.102947 -369.885694) (xy 287.121634 -369.877877) (xy 287.13176 -369.87734)
			(xy 287.84804 -369.87734) (xy 287.858202 -369.87769) (xy 287.876963 -369.885506) (xy 287.891286 -369.899925)
			(xy 287.898977 -369.918738) (xy 287.899348 -369.928902) (xy 287.899348 -370.214652) (xy 287.899571 -370.221546)
			(xy 287.903306 -370.234818) (xy 287.906714 -370.240814) (xy 287.923043 -370.269175) (xy 287.94879 -370.32934)
			(xy 287.966219 -370.392419) (xy 287.975014 -370.457268) (xy 287.975016 -370.522711) (xy 287.975016 -370.522712)
			(xy 291.404822 -370.522712) (xy 291.404823 -370.457268) (xy 291.413618 -370.392418) (xy 291.431045 -370.329337)
			(xy 291.45679 -370.26917) (xy 291.473128 -370.240814) (xy 291.47644 -370.234788) (xy 291.480047 -370.221525)
			(xy 291.48024 -370.214652) (xy 291.48024 -369.928902) (xy 291.480665 -369.91873) (xy 291.48845 -369.899935)
			(xy 291.502835 -369.88555) (xy 291.52163 -369.877765) (xy 291.531802 -369.87734) (xy 292.248082 -369.87734)
			(xy 292.258253 -369.877778) (xy 292.277047 -369.885558) (xy 292.291433 -369.899939) (xy 292.299218 -369.918731)
			(xy 292.299644 -369.928902) (xy 292.299644 -370.214652) (xy 292.299849 -370.221524) (xy 292.303448 -370.234787)
			(xy 292.306756 -370.240814) (xy 292.323083 -370.269176) (xy 292.348828 -370.329341) (xy 292.366256 -370.39242)
			(xy 292.375051 -370.457269) (xy 292.375052 -370.522711) (xy 292.375052 -370.522712) (xy 295.804858 -370.522712)
			(xy 295.80486 -370.457268) (xy 295.813655 -370.392417) (xy 295.831084 -370.329337) (xy 295.856831 -370.26917)
			(xy 295.87317 -370.240814) (xy 295.876531 -370.234797) (xy 295.880268 -370.221538) (xy 295.880536 -370.214652)
			(xy 295.880536 -369.928902) (xy 295.881028 -369.918776) (xy 295.888755 -369.900056) (xy 295.903039 -369.885699)
			(xy 295.92172 -369.877879) (xy 295.931844 -369.87734) (xy 296.648124 -369.87734) (xy 296.658285 -369.877703)
			(xy 296.677045 -369.885514) (xy 296.691369 -369.899929) (xy 296.699061 -369.918739) (xy 296.699432 -369.928902)
			(xy 296.699432 -370.214652) (xy 296.699658 -370.221545) (xy 296.703391 -370.234817) (xy 296.706798 -370.240814)
			(xy 296.723124 -370.269176) (xy 296.748867 -370.329342) (xy 296.766293 -370.392421) (xy 296.775087 -370.457269)
			(xy 296.775088 -370.522711) (xy 296.775088 -370.522712) (xy 300.204648 -370.522712) (xy 300.204649 -370.457268)
			(xy 300.213444 -370.392417) (xy 300.230873 -370.329337) (xy 300.256619 -370.26917) (xy 300.272958 -370.240814)
			(xy 300.276318 -370.234797) (xy 300.280056 -370.221538) (xy 300.280324 -370.214652) (xy 300.280324 -369.928902)
			(xy 300.280828 -369.918777) (xy 300.288552 -369.900059) (xy 300.302833 -369.885704) (xy 300.32151 -369.877882)
			(xy 300.331632 -369.87734) (xy 301.047912 -369.87734) (xy 301.058072 -369.877712) (xy 301.076832 -369.885519)
			(xy 301.091157 -369.899932) (xy 301.098849 -369.91874) (xy 301.09922 -369.928902) (xy 301.09922 -370.214652)
			(xy 301.099469 -370.221542) (xy 301.1032 -370.234808) (xy 301.106586 -370.240814) (xy 301.122912 -370.269176)
			(xy 301.148656 -370.329342) (xy 301.166083 -370.392421) (xy 301.174876 -370.457269) (xy 301.174877 -370.489988)
			(xy 304.603666 -370.489988) (xy 304.607657 -370.427821) (xy 304.619566 -370.366674) (xy 304.639195 -370.307553)
			(xy 304.666224 -370.251427) (xy 304.700208 -370.199218) (xy 304.74059 -370.151783) (xy 304.786706 -370.109902)
			(xy 304.837798 -370.074262) (xy 304.893029 -370.045448) (xy 304.951491 -370.023934) (xy 305.012225 -370.010072)
			(xy 305.074232 -370.00409) (xy 305.136495 -370.006086) (xy 305.197992 -370.016029) (xy 305.257713 -370.033753)
			(xy 305.314676 -370.05897) (xy 305.367947 -370.091263) (xy 305.416652 -370.130103) (xy 305.459989 -370.174853)
			(xy 305.497249 -370.224777) (xy 305.527818 -370.279056) (xy 305.551196 -370.336799) (xy 305.566997 -370.397057)
			(xy 305.574963 -370.45884) (xy 305.575462 -370.489988) (xy 305.574963 -370.521136) (xy 305.566997 -370.582919)
			(xy 305.551196 -370.643177) (xy 305.527818 -370.70092) (xy 305.497249 -370.755199) (xy 305.459989 -370.805123)
			(xy 305.416652 -370.849873) (xy 305.367947 -370.888713) (xy 305.314676 -370.921006) (xy 305.257713 -370.946223)
			(xy 305.197992 -370.963947) (xy 305.136495 -370.97389) (xy 305.074232 -370.975886) (xy 305.012225 -370.969904)
			(xy 304.951491 -370.956042) (xy 304.893029 -370.934528) (xy 304.837798 -370.905714) (xy 304.786706 -370.870074)
			(xy 304.74059 -370.828193) (xy 304.700208 -370.780758) (xy 304.666224 -370.728549) (xy 304.639195 -370.672423)
			(xy 304.619566 -370.613302) (xy 304.607657 -370.552155) (xy 304.603666 -370.489988) (xy 301.174877 -370.489988)
			(xy 301.174878 -370.522711) (xy 301.166087 -370.587559) (xy 301.148663 -370.650639) (xy 301.122922 -370.710806)
			(xy 301.106586 -370.739162) (xy 301.103203 -370.745168) (xy 301.099479 -370.758435) (xy 301.09922 -370.765324)
			(xy 301.09922 -371.514878) (xy 301.099459 -371.521769) (xy 301.103197 -371.535035) (xy 301.106586 -371.54104)
			(xy 301.122934 -371.56939) (xy 301.14578 -371.62279) (xy 302.404788 -371.62279) (xy 302.404793 -371.557345)
			(xy 302.41359 -371.492494) (xy 302.43102 -371.429412) (xy 302.456767 -371.369245) (xy 302.473106 -371.340888)
			(xy 302.476471 -371.334873) (xy 302.480207 -371.321613) (xy 302.480472 -371.314726) (xy 302.480472 -371.028722)
			(xy 302.480945 -371.018593) (xy 302.488672 -370.999866) (xy 302.502963 -370.985508) (xy 302.521653 -370.977693)
			(xy 302.53178 -370.97716) (xy 303.24806 -370.97716) (xy 303.258207 -370.977654) (xy 303.27695 -370.985429)
			(xy 303.291274 -370.999803) (xy 303.298982 -371.018574) (xy 303.299368 -371.028722) (xy 303.299368 -371.314726)
			(xy 303.299599 -371.321619) (xy 303.303329 -371.334891) (xy 303.306734 -371.340888) (xy 303.32304 -371.369262)
			(xy 303.348788 -371.429424) (xy 303.366219 -371.4925) (xy 303.375017 -371.557347) (xy 303.375021 -371.622788)
			(xy 303.366232 -371.687636) (xy 303.34881 -371.750714) (xy 303.331911 -371.790214) (xy 304.603666 -371.790214)
			(xy 304.607657 -371.728047) (xy 304.619566 -371.6669) (xy 304.639195 -371.607779) (xy 304.666224 -371.551653)
			(xy 304.700208 -371.499444) (xy 304.74059 -371.452009) (xy 304.786706 -371.410128) (xy 304.837798 -371.374488)
			(xy 304.893029 -371.345674) (xy 304.951491 -371.32416) (xy 305.012225 -371.310298) (xy 305.074232 -371.304316)
			(xy 305.136495 -371.306312) (xy 305.197992 -371.316255) (xy 305.257713 -371.333979) (xy 305.314676 -371.359196)
			(xy 305.367947 -371.391489) (xy 305.416652 -371.430329) (xy 305.459989 -371.475079) (xy 305.497249 -371.525003)
			(xy 305.527818 -371.579282) (xy 305.532182 -371.590062) (xy 306.803814 -371.590062) (xy 306.807805 -371.527895)
			(xy 306.819714 -371.466748) (xy 306.839343 -371.407627) (xy 306.866372 -371.351501) (xy 306.900356 -371.299292)
			(xy 306.940738 -371.251857) (xy 306.986854 -371.209976) (xy 307.037946 -371.174336) (xy 307.093177 -371.145522)
			(xy 307.151639 -371.124008) (xy 307.212373 -371.110146) (xy 307.27438 -371.104164) (xy 307.336643 -371.10616)
			(xy 307.39814 -371.116103) (xy 307.457861 -371.133827) (xy 307.514824 -371.159044) (xy 307.568095 -371.191337)
			(xy 307.6168 -371.230177) (xy 307.660137 -371.274927) (xy 307.697397 -371.324851) (xy 307.727966 -371.37913)
			(xy 307.751344 -371.436873) (xy 307.767145 -371.497131) (xy 307.775111 -371.558914) (xy 307.77561 -371.590062)
			(xy 307.775111 -371.62121) (xy 307.767145 -371.682993) (xy 307.751344 -371.743251) (xy 307.727966 -371.800994)
			(xy 307.697397 -371.855273) (xy 307.660137 -371.905197) (xy 307.6168 -371.949947) (xy 307.568095 -371.988787)
			(xy 307.514824 -372.02108) (xy 307.457861 -372.046297) (xy 307.39814 -372.064021) (xy 307.336643 -372.073964)
			(xy 307.27438 -372.07596) (xy 307.212373 -372.069978) (xy 307.151639 -372.056116) (xy 307.093177 -372.034602)
			(xy 307.037946 -372.005788) (xy 306.986854 -371.970148) (xy 306.940738 -371.928267) (xy 306.900356 -371.880832)
			(xy 306.866372 -371.828623) (xy 306.839343 -371.772497) (xy 306.819714 -371.713376) (xy 306.807805 -371.652229)
			(xy 306.803814 -371.590062) (xy 305.532182 -371.590062) (xy 305.551196 -371.637025) (xy 305.566997 -371.697283)
			(xy 305.574963 -371.759066) (xy 305.575462 -371.790214) (xy 305.574963 -371.821362) (xy 305.566997 -371.883145)
			(xy 305.551196 -371.943403) (xy 305.527818 -372.001146) (xy 305.497249 -372.055425) (xy 305.459989 -372.105349)
			(xy 305.416652 -372.150099) (xy 305.367947 -372.188939) (xy 305.314676 -372.221232) (xy 305.257713 -372.246449)
			(xy 305.197992 -372.264173) (xy 305.136495 -372.274116) (xy 305.074232 -372.276112) (xy 305.012225 -372.27013)
			(xy 304.951491 -372.256268) (xy 304.893029 -372.234754) (xy 304.837798 -372.20594) (xy 304.786706 -372.1703)
			(xy 304.74059 -372.128419) (xy 304.700208 -372.080984) (xy 304.666224 -372.028775) (xy 304.639195 -371.972649)
			(xy 304.619566 -371.913528) (xy 304.607657 -371.852381) (xy 304.603666 -371.790214) (xy 303.331911 -371.790214)
			(xy 303.32307 -371.81088) (xy 303.306734 -371.839236) (xy 303.303356 -371.845244) (xy 303.299629 -371.85851)
			(xy 303.299368 -371.865398) (xy 303.299368 -372.614698) (xy 303.299571 -372.621593) (xy 303.30332 -372.634865)
			(xy 303.306734 -372.64086) (xy 303.323101 -372.6692) (xy 303.348844 -372.72937) (xy 303.366268 -372.792454)
			(xy 303.375058 -372.857306) (xy 303.375056 -372.890034) (xy 306.803814 -372.890034) (xy 306.807805 -372.827867)
			(xy 306.819714 -372.76672) (xy 306.839343 -372.707599) (xy 306.866372 -372.651473) (xy 306.900356 -372.599264)
			(xy 306.940738 -372.551829) (xy 306.986854 -372.509948) (xy 307.037946 -372.474308) (xy 307.093177 -372.445494)
			(xy 307.151639 -372.42398) (xy 307.212373 -372.410118) (xy 307.27438 -372.404136) (xy 307.336643 -372.406132)
			(xy 307.39814 -372.416075) (xy 307.457861 -372.433799) (xy 307.514824 -372.459016) (xy 307.568095 -372.491309)
			(xy 307.6168 -372.530149) (xy 307.660137 -372.574899) (xy 307.697397 -372.624823) (xy 307.727966 -372.679102)
			(xy 307.751344 -372.736845) (xy 307.767145 -372.797103) (xy 307.775111 -372.858886) (xy 307.77561 -372.890034)
			(xy 307.775111 -372.921182) (xy 307.767145 -372.982965) (xy 307.751344 -373.043223) (xy 307.727966 -373.100966)
			(xy 307.697397 -373.155245) (xy 307.660137 -373.205169) (xy 307.6168 -373.249919) (xy 307.568095 -373.288759)
			(xy 307.514824 -373.321052) (xy 307.457861 -373.346269) (xy 307.39814 -373.363993) (xy 307.336643 -373.373936)
			(xy 307.27438 -373.375932) (xy 307.212373 -373.36995) (xy 307.151639 -373.356088) (xy 307.093177 -373.334574)
			(xy 307.037946 -373.30576) (xy 306.986854 -373.27012) (xy 306.940738 -373.228239) (xy 306.900356 -373.180804)
			(xy 306.866372 -373.128595) (xy 306.839343 -373.072469) (xy 306.819714 -373.013348) (xy 306.807805 -372.952201)
			(xy 306.803814 -372.890034) (xy 303.375056 -372.890034) (xy 303.375054 -372.922752) (xy 303.366256 -372.987604)
			(xy 303.348824 -373.050685) (xy 303.323074 -373.110852) (xy 303.306734 -373.139208) (xy 303.303366 -373.145221)
			(xy 303.299633 -373.158483) (xy 303.299368 -373.16537) (xy 303.299368 -373.451374) (xy 303.298853 -373.461498)
			(xy 303.291135 -373.480217) (xy 303.276857 -373.494574) (xy 303.258181 -373.502396) (xy 303.24806 -373.502936)
			(xy 302.53178 -373.502936) (xy 302.521629 -373.502496) (xy 302.502883 -373.4947) (xy 302.488562 -373.48031)
			(xy 302.480856 -373.461527) (xy 302.480472 -373.451374) (xy 302.480472 -373.16537) (xy 302.480237 -373.158477)
			(xy 302.47651 -373.145205) (xy 302.473106 -373.139208) (xy 302.456798 -373.110836) (xy 302.431054 -373.050672)
			(xy 302.413625 -372.987596) (xy 302.404829 -372.922749) (xy 302.404825 -372.857309) (xy 302.413614 -372.792462)
			(xy 302.431034 -372.729383) (xy 302.456772 -372.669216) (xy 302.473106 -372.64086) (xy 302.476481 -372.63485)
			(xy 302.48021 -372.621586) (xy 302.480472 -372.614698) (xy 302.480472 -371.865398) (xy 302.480243 -371.858506)
			(xy 302.476498 -371.84524) (xy 302.473106 -371.839236) (xy 302.456737 -371.810897) (xy 302.430998 -371.750726)
			(xy 302.413577 -371.687642) (xy 302.404788 -371.62279) (xy 301.14578 -371.62279) (xy 301.148676 -371.629558)
			(xy 301.1661 -371.69264) (xy 301.174891 -371.75749) (xy 301.17489 -371.822934) (xy 301.166095 -371.887784)
			(xy 301.148668 -371.950864) (xy 301.122924 -372.011032) (xy 301.106586 -372.039388) (xy 301.103229 -372.045407)
			(xy 301.099488 -372.058664) (xy 301.09922 -372.06555) (xy 301.09922 -372.351554) (xy 301.098734 -372.361683)
			(xy 301.091014 -372.38041) (xy 301.076727 -372.39477) (xy 301.058038 -372.402583) (xy 301.047912 -372.403116)
			(xy 300.331632 -372.403116) (xy 300.321482 -372.402653) (xy 300.302733 -372.394871) (xy 300.288409 -372.380487)
			(xy 300.280705 -372.361706) (xy 300.280324 -372.351554) (xy 300.280324 -372.06555) (xy 300.280103 -372.058656)
			(xy 300.276367 -372.045384) (xy 300.272958 -372.039388) (xy 300.256632 -372.011025) (xy 300.230886 -371.95086)
			(xy 300.213457 -371.887782) (xy 300.204663 -371.822933) (xy 300.204661 -371.757491) (xy 300.213453 -371.692642)
			(xy 300.230878 -371.629562) (xy 300.256621 -371.569396) (xy 300.272958 -371.54104) (xy 300.276344 -371.535036)
			(xy 300.280066 -371.521767) (xy 300.280324 -371.514878) (xy 300.280324 -370.765324) (xy 300.280114 -370.758429)
			(xy 300.27637 -370.745157) (xy 300.272958 -370.739162) (xy 300.25661 -370.710812) (xy 300.230866 -370.650644)
			(xy 300.21344 -370.587562) (xy 300.204648 -370.522712) (xy 296.775088 -370.522712) (xy 296.766297 -370.587559)
			(xy 296.748874 -370.650639) (xy 296.723133 -370.710805) (xy 296.706798 -370.739162) (xy 296.703416 -370.745168)
			(xy 296.699691 -370.758435) (xy 296.699432 -370.765324) (xy 296.699432 -371.514878) (xy 296.699669 -371.521769)
			(xy 296.703408 -371.535035) (xy 296.706798 -371.54104) (xy 296.723146 -371.56939) (xy 296.745991 -371.62279)
			(xy 298.004738 -371.62279) (xy 298.004743 -371.557344) (xy 298.013541 -371.492493) (xy 298.030973 -371.429411)
			(xy 298.056723 -371.369244) (xy 298.073064 -371.340888) (xy 298.07638 -371.334864) (xy 298.079985 -371.3216)
			(xy 298.080176 -371.314726) (xy 298.080176 -371.028722) (xy 298.080583 -371.018547) (xy 298.088368 -370.999746)
			(xy 298.102759 -370.985359) (xy 298.121563 -370.97758) (xy 298.131738 -370.97716) (xy 298.848018 -370.97716)
			(xy 298.858193 -370.97755) (xy 298.876993 -370.985345) (xy 298.891378 -370.999741) (xy 298.899158 -371.018546)
			(xy 298.89958 -371.028722) (xy 298.89958 -371.314726) (xy 298.899765 -371.3216) (xy 298.903378 -371.334862)
			(xy 298.906692 -371.340888) (xy 298.922996 -371.369262) (xy 298.948741 -371.429425) (xy 298.96617 -371.492501)
			(xy 298.974967 -371.557347) (xy 298.974971 -371.622787) (xy 298.966183 -371.687635) (xy 298.948763 -371.750713)
			(xy 298.923026 -371.81088) (xy 298.906692 -371.839236) (xy 298.903364 -371.845254) (xy 298.899767 -371.858523)
			(xy 298.89958 -371.865398) (xy 298.89958 -372.614698) (xy 298.899775 -372.621571) (xy 298.903381 -372.634834)
			(xy 298.906692 -372.64086) (xy 298.923057 -372.669201) (xy 298.948797 -372.729371) (xy 298.966219 -372.792455)
			(xy 298.975008 -372.857307) (xy 298.975004 -372.922752) (xy 298.966207 -372.987603) (xy 298.948777 -373.050684)
			(xy 298.923031 -373.110851) (xy 298.906692 -373.139208) (xy 298.903374 -373.145231) (xy 298.899771 -373.158496)
			(xy 298.89958 -373.16537) (xy 298.89958 -373.451374) (xy 298.899115 -373.461542) (xy 298.891342 -373.480332)
			(xy 298.876969 -373.494717) (xy 298.858185 -373.502506) (xy 298.848018 -373.502936) (xy 298.131738 -373.502936)
			(xy 298.121566 -373.502504) (xy 298.102767 -373.494727) (xy 298.08838 -373.480343) (xy 298.080598 -373.461546)
			(xy 298.080176 -373.451374) (xy 298.080176 -373.16537) (xy 298.079999 -373.158496) (xy 298.076381 -373.145233)
			(xy 298.073064 -373.139208) (xy 298.056755 -373.110836) (xy 298.031007 -373.050673) (xy 298.013576 -372.987597)
			(xy 298.004779 -372.92275) (xy 298.004775 -372.857309) (xy 298.013565 -372.792461) (xy 298.030987 -372.729382)
			(xy 298.056728 -372.669216) (xy 298.073064 -372.64086) (xy 298.07639 -372.634841) (xy 298.079989 -372.621573)
			(xy 298.080176 -372.614698) (xy 298.080176 -371.865398) (xy 298.079988 -371.858524) (xy 298.076377 -371.845262)
			(xy 298.073064 -371.839236) (xy 298.056694 -371.810898) (xy 298.030951 -371.750727) (xy 298.013528 -371.687643)
			(xy 298.004738 -371.62279) (xy 296.745991 -371.62279) (xy 296.748887 -371.629559) (xy 296.766311 -371.69264)
			(xy 296.775101 -371.75749) (xy 296.7751 -371.822934) (xy 296.766306 -371.887784) (xy 296.748879 -371.950864)
			(xy 296.723135 -372.011031) (xy 296.706798 -372.039388) (xy 296.703442 -372.045407) (xy 296.699701 -372.058664)
			(xy 296.699432 -372.06555) (xy 296.699432 -372.351554) (xy 296.698935 -372.361681) (xy 296.691217 -372.380407)
			(xy 296.676933 -372.394765) (xy 296.658249 -372.402581) (xy 296.648124 -372.403116) (xy 295.931844 -372.403116)
			(xy 295.921695 -372.402643) (xy 295.902946 -372.394865) (xy 295.888622 -372.380484) (xy 295.880918 -372.361705)
			(xy 295.880536 -372.351554) (xy 295.880536 -372.06555) (xy 295.880314 -372.058656) (xy 295.876578 -372.045384)
			(xy 295.87317 -372.039388) (xy 295.856844 -372.011026) (xy 295.831097 -371.950861) (xy 295.813668 -371.887782)
			(xy 295.804873 -371.822933) (xy 295.804871 -371.757491) (xy 295.813663 -371.692642) (xy 295.831089 -371.629562)
			(xy 295.856833 -371.569396) (xy 295.87317 -371.54104) (xy 295.876557 -371.535036) (xy 295.880278 -371.521767)
			(xy 295.880536 -371.514878) (xy 295.880536 -370.765324) (xy 295.880324 -370.75843) (xy 295.876581 -370.745157)
			(xy 295.87317 -370.739162) (xy 295.856821 -370.710812) (xy 295.831077 -370.650644) (xy 295.81365 -370.587563)
			(xy 295.804858 -370.522712) (xy 292.375052 -370.522712) (xy 292.36626 -370.58756) (xy 292.348835 -370.650639)
			(xy 292.323093 -370.710806) (xy 292.306756 -370.739162) (xy 292.303459 -370.745196) (xy 292.299842 -370.758452)
			(xy 292.299644 -370.765324) (xy 292.299644 -371.514878) (xy 292.299839 -371.521751) (xy 292.303445 -371.535014)
			(xy 292.306756 -371.54104) (xy 292.323105 -371.56939) (xy 292.345952 -371.62279) (xy 293.604702 -371.62279)
			(xy 293.604706 -371.557345) (xy 293.613504 -371.492493) (xy 293.630935 -371.429412) (xy 293.656683 -371.369244)
			(xy 293.673022 -371.340888) (xy 293.676388 -371.334874) (xy 293.680123 -371.321613) (xy 293.680388 -371.314726)
			(xy 293.680388 -371.028722) (xy 293.680943 -371.018603) (xy 293.688654 -370.999892) (xy 293.702919 -370.985537)
			(xy 293.72158 -370.977708) (xy 293.731696 -370.97716) (xy 294.447976 -370.97716) (xy 294.458124 -370.97764)
			(xy 294.476868 -370.98542) (xy 294.491191 -370.999799) (xy 294.498898 -371.018573) (xy 294.499284 -371.028722)
			(xy 294.499284 -371.314726) (xy 294.499513 -371.321619) (xy 294.503244 -371.334891) (xy 294.50665 -371.340888)
			(xy 294.522956 -371.369262) (xy 294.548703 -371.429424) (xy 294.566133 -371.492501) (xy 294.574931 -371.557347)
			(xy 294.574935 -371.622788) (xy 294.566146 -371.687635) (xy 294.548725 -371.750714) (xy 294.522985 -371.81088)
			(xy 294.50665 -371.839236) (xy 294.503273 -371.845245) (xy 294.499546 -371.85851) (xy 294.499284 -371.865398)
			(xy 294.499284 -372.614698) (xy 294.499485 -372.621593) (xy 294.503235 -372.634866) (xy 294.50665 -372.64086)
			(xy 294.523017 -372.6692) (xy 294.548758 -372.72937) (xy 294.566182 -372.792454) (xy 294.574972 -372.857306)
			(xy 294.574968 -372.922752) (xy 294.56617 -372.987603) (xy 294.548739 -373.050685) (xy 294.52299 -373.110852)
			(xy 294.50665 -373.139208) (xy 294.503283 -373.145222) (xy 294.49955 -373.158483) (xy 294.499284 -373.16537)
			(xy 294.499284 -373.451374) (xy 294.498753 -373.461496) (xy 294.491038 -373.480212) (xy 294.476766 -373.494569)
			(xy 294.458095 -373.502393) (xy 294.447976 -373.502936) (xy 293.731696 -373.502936) (xy 293.721546 -373.502482)
			(xy 293.702801 -373.494692) (xy 293.688479 -373.480306) (xy 293.680773 -373.461526) (xy 293.680388 -373.451374)
			(xy 293.680388 -373.16537) (xy 293.680129 -373.158481) (xy 293.676405 -373.145215) (xy 293.673022 -373.139208)
			(xy 293.656714 -373.110836) (xy 293.630968 -373.050673) (xy 293.613539 -372.987596) (xy 293.604743 -372.922749)
			(xy 293.604739 -372.857309) (xy 293.613528 -372.792461) (xy 293.630949 -372.729383) (xy 293.656687 -372.669216)
			(xy 293.673022 -372.64086) (xy 293.676398 -372.634851) (xy 293.680126 -372.621586) (xy 293.680388 -372.614698)
			(xy 293.680388 -371.865398) (xy 293.680157 -371.858506) (xy 293.676413 -371.845241) (xy 293.673022 -371.839236)
			(xy 293.656653 -371.810897) (xy 293.630913 -371.750726) (xy 293.613491 -371.687643) (xy 293.604702 -371.62279)
			(xy 292.345952 -371.62279) (xy 292.348848 -371.629558) (xy 292.366274 -371.692639) (xy 292.375065 -371.75749)
			(xy 292.375064 -371.822934) (xy 292.366269 -371.887784) (xy 292.34884 -371.950865) (xy 292.323094 -372.011032)
			(xy 292.306756 -372.039388) (xy 292.30345 -372.045417) (xy 292.299838 -372.058677) (xy 292.299644 -372.06555)
			(xy 292.299644 -372.351554) (xy 292.299198 -372.361725) (xy 292.291425 -372.380522) (xy 292.277046 -372.394909)
			(xy 292.258253 -372.402693) (xy 292.248082 -372.403116) (xy 291.531802 -372.403116) (xy 291.521625 -372.402733)
			(xy 291.502821 -372.394941) (xy 291.488435 -372.380542) (xy 291.480658 -372.361732) (xy 291.48024 -372.351554)
			(xy 291.48024 -372.06555) (xy 291.480024 -372.058679) (xy 291.476432 -372.045416) (xy 291.473128 -372.039388)
			(xy 291.456803 -372.011025) (xy 291.431058 -371.95086) (xy 291.413631 -371.887781) (xy 291.404837 -371.822933)
			(xy 291.404835 -371.757491) (xy 291.413626 -371.692642) (xy 291.43105 -371.629563) (xy 291.456792 -371.569396)
			(xy 291.473128 -371.54104) (xy 291.47643 -371.535009) (xy 291.480043 -371.52175) (xy 291.48024 -371.514878)
			(xy 291.48024 -370.765324) (xy 291.480034 -370.758452) (xy 291.476435 -370.745189) (xy 291.473128 -370.739162)
			(xy 291.456781 -370.710811) (xy 291.431038 -370.650643) (xy 291.413614 -370.587562) (xy 291.404822 -370.522712)
			(xy 287.975016 -370.522712) (xy 287.966223 -370.58756) (xy 287.948797 -370.65064) (xy 287.923052 -370.710806)
			(xy 287.906714 -370.739162) (xy 287.903333 -370.745169) (xy 287.899607 -370.758435) (xy 287.899348 -370.765324)
			(xy 287.899348 -371.514878) (xy 287.899561 -371.521772) (xy 287.903303 -371.535044) (xy 287.906714 -371.54104)
			(xy 287.923065 -371.569389) (xy 287.945915 -371.62279) (xy 289.204652 -371.62279) (xy 289.204656 -371.557344)
			(xy 289.213455 -371.492492) (xy 289.230888 -371.429411) (xy 289.256639 -371.369244) (xy 289.27298 -371.340888)
			(xy 289.276298 -371.334865) (xy 289.279902 -371.3216) (xy 289.280092 -371.314726) (xy 289.280092 -371.028722)
			(xy 289.28065 -371.018571) (xy 289.288409 -370.999811) (xy 289.302754 -370.985447) (xy 289.321504 -370.977663)
			(xy 289.331654 -370.97716) (xy 290.047934 -370.97716) (xy 290.058097 -370.977606) (xy 290.076871 -370.985396)
			(xy 290.091236 -370.999776) (xy 290.099005 -371.018559) (xy 290.099496 -371.028722) (xy 290.099496 -371.314726)
			(xy 290.099678 -371.3216) (xy 290.103293 -371.334863) (xy 290.106608 -371.340888) (xy 290.122915 -371.369261)
			(xy 290.148665 -371.429423) (xy 290.166096 -371.4925) (xy 290.174894 -371.557347) (xy 290.174899 -371.622788)
			(xy 290.16611 -371.687636) (xy 290.148686 -371.750715) (xy 290.122944 -371.81088) (xy 290.106608 -371.839236)
			(xy 290.103281 -371.845255) (xy 290.099683 -371.858523) (xy 290.099496 -371.865398) (xy 290.099496 -372.614698)
			(xy 290.099689 -372.621571) (xy 290.103296 -372.634834) (xy 290.106608 -372.64086) (xy 290.122976 -372.6692)
			(xy 290.14872 -372.72937) (xy 290.166145 -372.792453) (xy 290.174935 -372.857306) (xy 290.174931 -372.922752)
			(xy 290.166133 -372.987604) (xy 290.148701 -373.050685) (xy 290.122949 -373.110852) (xy 290.106608 -373.139208)
			(xy 290.103291 -373.145232) (xy 290.099687 -373.158496) (xy 290.099496 -373.16537) (xy 290.099496 -373.451374)
			(xy 290.098946 -373.461526) (xy 290.091187 -373.480288) (xy 290.076838 -373.494653) (xy 290.058085 -373.502435)
			(xy 290.047934 -373.502936) (xy 289.331654 -373.502936) (xy 289.32149 -373.502504) (xy 289.302715 -373.494709)
			(xy 289.28835 -373.480325) (xy 289.280582 -373.461539) (xy 289.280092 -373.451374) (xy 289.280092 -373.16537)
			(xy 289.279913 -373.158496) (xy 289.276296 -373.145233) (xy 289.27298 -373.139208) (xy 289.25667 -373.110836)
			(xy 289.230921 -373.050674) (xy 289.21349 -372.987597) (xy 289.204693 -372.92275) (xy 289.204689 -372.857309)
			(xy 289.213479 -372.79246) (xy 289.230902 -372.729381) (xy 289.256644 -372.669216) (xy 289.27298 -372.64086)
			(xy 289.276308 -372.634842) (xy 289.279905 -372.621573) (xy 289.280092 -372.614698) (xy 289.280092 -371.865398)
			(xy 289.279902 -371.858525) (xy 289.276293 -371.845262) (xy 289.27298 -371.839236) (xy 289.256609 -371.810898)
			(xy 289.230866 -371.750728) (xy 289.213442 -371.687644) (xy 289.204652 -371.62279) (xy 287.945915 -371.62279)
			(xy 287.94881 -371.629557) (xy 287.966237 -371.692639) (xy 287.975029 -371.75749) (xy 287.975028 -371.822934)
			(xy 287.966232 -371.887785) (xy 287.948802 -371.950866) (xy 287.923054 -372.011032) (xy 287.906714 -372.039388)
			(xy 287.903359 -372.045408) (xy 287.899617 -372.058664) (xy 287.899348 -372.06555) (xy 287.899348 -372.351554)
			(xy 287.898835 -372.361679) (xy 287.89112 -372.380402) (xy 287.876842 -372.39476) (xy 287.858162 -372.402579)
			(xy 287.84804 -372.403116) (xy 287.13176 -372.403116) (xy 287.121605 -372.402711) (xy 287.102855 -372.394906)
			(xy 287.088534 -372.380504) (xy 287.080833 -372.361711) (xy 287.080452 -372.351554) (xy 287.080452 -372.06555)
			(xy 287.080228 -372.058657) (xy 287.076493 -372.045385) (xy 287.073086 -372.039388) (xy 287.056759 -372.011026)
			(xy 287.031012 -371.950861) (xy 287.013582 -371.887782) (xy 287.004787 -371.822933) (xy 287.004785 -371.757491)
			(xy 287.013577 -371.692641) (xy 287.031004 -371.629562) (xy 287.056748 -371.569396) (xy 287.073086 -371.54104)
			(xy 287.076466 -371.535033) (xy 287.080193 -371.521767) (xy 287.080452 -371.514878) (xy 287.080452 -370.765324)
			(xy 287.080238 -370.75843) (xy 287.076496 -370.745158) (xy 287.073086 -370.739162) (xy 287.056737 -370.710812)
			(xy 287.030992 -370.650644) (xy 287.013565 -370.587563) (xy 287.004772 -370.522712) (xy 266.738608 -370.522712)
			(xy 266.738608 -372.924324) (xy 266.644069 -373.009338) (xy 266.460017 -373.184791) (xy 266.281833 -373.366201)
			(xy 266.109709 -373.55337) (xy 265.943832 -373.746098) (xy 265.784382 -373.944175) (xy 265.63153 -374.147388)
			(xy 265.485442 -374.355516) (xy 265.441386 -374.422887) (xy 287.004755 -374.422887) (xy 287.00476 -374.357441)
			(xy 287.013559 -374.292589) (xy 287.030992 -374.229507) (xy 287.056744 -374.16934) (xy 287.073086 -374.140984)
			(xy 287.076451 -374.134969) (xy 287.080187 -374.121709) (xy 287.080452 -374.114822) (xy 287.080452 -373.828818)
			(xy 287.080942 -373.818691) (xy 287.088666 -373.799968) (xy 287.102951 -373.785611) (xy 287.121636 -373.777793)
			(xy 287.13176 -373.777256) (xy 287.84804 -373.777256) (xy 287.858191 -373.777688) (xy 287.876936 -373.785489)
			(xy 287.891256 -373.799881) (xy 287.898963 -373.818665) (xy 287.899348 -373.828818) (xy 287.899348 -374.114822)
			(xy 287.899583 -374.121715) (xy 287.90331 -374.134987) (xy 287.906714 -374.140984) (xy 287.923017 -374.169359)
			(xy 287.948767 -374.229521) (xy 287.966199 -374.292597) (xy 287.974997 -374.357444) (xy 287.975002 -374.422884)
			(xy 287.975002 -374.422887) (xy 291.404805 -374.422887) (xy 291.40481 -374.357441) (xy 291.413608 -374.292589)
			(xy 291.431039 -374.229508) (xy 291.456788 -374.16934) (xy 291.473128 -374.140984) (xy 291.47645 -374.134963)
			(xy 291.480051 -374.121696) (xy 291.48024 -374.114822) (xy 291.48024 -373.828818) (xy 291.480678 -373.818647)
			(xy 291.488458 -373.799853) (xy 291.502839 -373.785467) (xy 291.521631 -373.777682) (xy 291.531802 -373.777256)
			(xy 292.248082 -373.777256) (xy 292.258255 -373.777679) (xy 292.277053 -373.785461) (xy 292.291439 -373.799847)
			(xy 292.299221 -373.818645) (xy 292.299644 -373.828818) (xy 292.299644 -374.114822) (xy 292.299822 -374.121696)
			(xy 292.303439 -374.134959) (xy 292.306756 -374.140984) (xy 292.323058 -374.16936) (xy 292.348805 -374.229522)
			(xy 292.366236 -374.292598) (xy 292.375033 -374.357444) (xy 292.375038 -374.422884) (xy 292.375038 -374.422887)
			(xy 295.804841 -374.422887) (xy 295.804846 -374.357441) (xy 295.813645 -374.292589) (xy 295.831078 -374.229507)
			(xy 295.856829 -374.16934) (xy 295.87317 -374.140984) (xy 295.876541 -374.134973) (xy 295.880272 -374.121709)
			(xy 295.880536 -374.114822) (xy 295.880536 -373.828818) (xy 295.881041 -373.818693) (xy 295.888762 -373.799973)
			(xy 295.903043 -373.785616) (xy 295.921722 -373.777796) (xy 295.931844 -373.777256) (xy 296.648124 -373.777256)
			(xy 296.658274 -373.777701) (xy 296.677019 -373.785496) (xy 296.69134 -373.799885) (xy 296.699046 -373.818666)
			(xy 296.699432 -373.828818) (xy 296.699432 -374.114822) (xy 296.699669 -374.121714) (xy 296.703395 -374.134986)
			(xy 296.706798 -374.140984) (xy 296.723099 -374.16936) (xy 296.748844 -374.229523) (xy 296.766273 -374.292599)
			(xy 296.77507 -374.357444) (xy 296.775074 -374.422884) (xy 296.775074 -374.422887) (xy 300.204631 -374.422887)
			(xy 300.204636 -374.357441) (xy 300.213434 -374.292589) (xy 300.230867 -374.229507) (xy 300.256617 -374.16934)
			(xy 300.272958 -374.140984) (xy 300.276329 -374.134972) (xy 300.28006 -374.121709) (xy 300.280324 -374.114822)
			(xy 300.280324 -373.828818) (xy 300.280841 -373.818694) (xy 300.28856 -373.799977) (xy 300.302837 -373.78562)
			(xy 300.321511 -373.777798) (xy 300.331632 -373.777256) (xy 301.047912 -373.777256) (xy 301.058061 -373.777711)
			(xy 301.076806 -373.785502) (xy 301.091127 -373.799888) (xy 301.098834 -373.818667) (xy 301.09922 -373.828818)
			(xy 301.09922 -374.114822) (xy 301.099459 -374.121714) (xy 301.103184 -374.134986) (xy 301.106586 -374.140984)
			(xy 301.122887 -374.16936) (xy 301.148633 -374.229522) (xy 301.166062 -374.292598) (xy 301.174859 -374.357444)
			(xy 301.174861 -374.390158) (xy 304.603666 -374.390158) (xy 304.607657 -374.327991) (xy 304.619566 -374.266844)
			(xy 304.639195 -374.207723) (xy 304.666224 -374.151597) (xy 304.700208 -374.099388) (xy 304.74059 -374.051953)
			(xy 304.786706 -374.010072) (xy 304.837798 -373.974432) (xy 304.893029 -373.945618) (xy 304.951491 -373.924104)
			(xy 305.012225 -373.910242) (xy 305.074232 -373.90426) (xy 305.136495 -373.906256) (xy 305.197992 -373.916199)
			(xy 305.257713 -373.933923) (xy 305.314676 -373.95914) (xy 305.367947 -373.991433) (xy 305.416652 -374.030273)
			(xy 305.459989 -374.075023) (xy 305.497249 -374.124947) (xy 305.527818 -374.179226) (xy 305.551196 -374.236969)
			(xy 305.566997 -374.297227) (xy 305.574963 -374.35901) (xy 305.575462 -374.390158) (xy 305.574963 -374.421306)
			(xy 305.566997 -374.483089) (xy 305.551196 -374.543347) (xy 305.527818 -374.60109) (xy 305.497249 -374.655369)
			(xy 305.459989 -374.705293) (xy 305.416652 -374.750043) (xy 305.367947 -374.788883) (xy 305.314676 -374.821176)
			(xy 305.257713 -374.846393) (xy 305.197992 -374.864117) (xy 305.136495 -374.87406) (xy 305.074232 -374.876056)
			(xy 305.012225 -374.870074) (xy 304.951491 -374.856212) (xy 304.893029 -374.834698) (xy 304.837798 -374.805884)
			(xy 304.786706 -374.770244) (xy 304.74059 -374.728363) (xy 304.700208 -374.680928) (xy 304.666224 -374.628719)
			(xy 304.639195 -374.572593) (xy 304.619566 -374.513472) (xy 304.607657 -374.452325) (xy 304.603666 -374.390158)
			(xy 301.174861 -374.390158) (xy 301.174864 -374.422884) (xy 301.166077 -374.487731) (xy 301.148657 -374.550809)
			(xy 301.12292 -374.610976) (xy 301.106586 -374.639332) (xy 301.103213 -374.645343) (xy 301.099483 -374.658606)
			(xy 301.09922 -374.665494) (xy 301.09922 -375.414794) (xy 301.099453 -375.421685) (xy 301.103195 -375.434951)
			(xy 301.106586 -375.440956) (xy 301.122948 -375.469298) (xy 301.148688 -375.529469) (xy 301.166111 -375.592552)
			(xy 301.1749 -375.657403) (xy 301.174897 -375.722848) (xy 301.166101 -375.787699) (xy 301.148671 -375.85078)
			(xy 301.122925 -375.910948) (xy 301.106586 -375.939304) (xy 301.103223 -375.94532) (xy 301.099486 -375.958579)
			(xy 301.09922 -375.965466) (xy 301.09922 -376.25147) (xy 301.098748 -376.2616) (xy 301.091023 -376.280328)
			(xy 301.076731 -376.294687) (xy 301.058039 -376.3025) (xy 301.047912 -376.303032) (xy 300.331632 -376.303032)
			(xy 300.321484 -376.302553) (xy 300.302738 -376.294774) (xy 300.288415 -376.280395) (xy 300.280708 -376.26162)
			(xy 300.280324 -376.25147) (xy 300.280324 -375.965466) (xy 300.280097 -375.958573) (xy 300.276365 -375.945301)
			(xy 300.272958 -375.939304) (xy 300.256645 -375.910934) (xy 300.230898 -375.850771) (xy 300.213468 -375.787693)
			(xy 300.204672 -375.722846) (xy 300.204668 -375.657405) (xy 300.213458 -375.592557) (xy 300.230881 -375.529478)
			(xy 300.256622 -375.469312) (xy 300.272958 -375.440956) (xy 300.276338 -375.434949) (xy 300.280064 -375.421682)
			(xy 300.280324 -375.414794) (xy 300.280324 -374.665494) (xy 300.280125 -374.658598) (xy 300.276374 -374.645326)
			(xy 300.272958 -374.639332) (xy 300.256584 -374.610996) (xy 300.230843 -374.550825) (xy 300.21342 -374.48774)
			(xy 300.204631 -374.422887) (xy 296.775074 -374.422887) (xy 296.766287 -374.487731) (xy 296.748868 -374.550809)
			(xy 296.723131 -374.610975) (xy 296.706798 -374.639332) (xy 296.703426 -374.645343) (xy 296.699695 -374.658606)
			(xy 296.699432 -374.665494) (xy 296.699432 -375.414794) (xy 296.699663 -375.421686) (xy 296.703406 -375.434952)
			(xy 296.706798 -375.440956) (xy 296.72316 -375.469299) (xy 296.748899 -375.529469) (xy 296.766321 -375.592552)
			(xy 296.775111 -375.657403) (xy 296.775107 -375.722848) (xy 296.766311 -375.787699) (xy 296.748882 -375.85078)
			(xy 296.723136 -375.910947) (xy 296.706798 -375.939304) (xy 296.703436 -375.94532) (xy 296.699698 -375.95858)
			(xy 296.699432 -375.965466) (xy 296.699432 -376.25147) (xy 296.698948 -376.261598) (xy 296.691225 -376.280324)
			(xy 296.676937 -376.294683) (xy 296.65825 -376.302498) (xy 296.648124 -376.303032) (xy 295.931844 -376.303032)
			(xy 295.921697 -376.302543) (xy 295.902951 -376.294768) (xy 295.888628 -376.280392) (xy 295.880921 -376.261619)
			(xy 295.880536 -376.25147) (xy 295.880536 -375.965466) (xy 295.880308 -375.958573) (xy 295.876576 -375.945301)
			(xy 295.87317 -375.939304) (xy 295.856857 -375.910934) (xy 295.831109 -375.850771) (xy 295.813679 -375.787694)
			(xy 295.804882 -375.722846) (xy 295.804879 -375.657405) (xy 295.813668 -375.592557) (xy 295.831092 -375.529478)
			(xy 295.856834 -375.469312) (xy 295.87317 -375.440956) (xy 295.876551 -375.43495) (xy 295.880276 -375.421683)
			(xy 295.880536 -375.414794) (xy 295.880536 -374.665494) (xy 295.880335 -374.658599) (xy 295.876585 -374.645327)
			(xy 295.87317 -374.639332) (xy 295.856796 -374.610996) (xy 295.831054 -374.550825) (xy 295.81363 -374.487741)
			(xy 295.804841 -374.422887) (xy 292.375038 -374.422887) (xy 292.36625 -374.487731) (xy 292.348829 -374.55081)
			(xy 292.323091 -374.610976) (xy 292.306756 -374.639332) (xy 292.303434 -374.645353) (xy 292.299832 -374.65862)
			(xy 292.299644 -374.665494) (xy 292.299644 -375.414794) (xy 292.299833 -375.421668) (xy 292.303443 -375.434931)
			(xy 292.306756 -375.440956) (xy 292.323119 -375.469298) (xy 292.348861 -375.529468) (xy 292.366285 -375.592551)
			(xy 292.375074 -375.657403) (xy 292.375071 -375.722848) (xy 292.366274 -375.787699) (xy 292.348844 -375.850781)
			(xy 292.323096 -375.910948) (xy 292.306756 -375.939304) (xy 292.303444 -375.94533) (xy 292.299836 -375.958593)
			(xy 292.299644 -375.965466) (xy 292.299644 -376.25147) (xy 292.299211 -376.261642) (xy 292.291433 -376.280439)
			(xy 292.277049 -376.294826) (xy 292.258254 -376.302609) (xy 292.248082 -376.303032) (xy 291.531802 -376.303032)
			(xy 291.521627 -376.302634) (xy 291.502826 -376.294844) (xy 291.48844 -376.28045) (xy 291.480661 -376.261645)
			(xy 291.48024 -376.25147) (xy 291.48024 -375.965466) (xy 291.480056 -375.958592) (xy 291.476442 -375.94533)
			(xy 291.473128 -375.939304) (xy 291.456816 -375.910934) (xy 291.431071 -375.85077) (xy 291.413642 -375.787693)
			(xy 291.404846 -375.722846) (xy 291.404843 -375.657405) (xy 291.413632 -375.592557) (xy 291.431054 -375.529479)
			(xy 291.456793 -375.469312) (xy 291.473128 -375.440956) (xy 291.47646 -375.43494) (xy 291.480054 -375.42167)
			(xy 291.48024 -375.414794) (xy 291.48024 -374.665494) (xy 291.480045 -374.658621) (xy 291.476438 -374.645358)
			(xy 291.473128 -374.639332) (xy 291.456755 -374.610995) (xy 291.431015 -374.550824) (xy 291.413593 -374.48774)
			(xy 291.404805 -374.422887) (xy 287.975002 -374.422887) (xy 287.966213 -374.487732) (xy 287.948791 -374.550811)
			(xy 287.92305 -374.610976) (xy 287.906714 -374.639332) (xy 287.903344 -374.645344) (xy 287.899611 -374.658607)
			(xy 287.899348 -374.665494) (xy 287.899348 -375.414794) (xy 287.899555 -375.421689) (xy 287.903301 -375.434961)
			(xy 287.906714 -375.440956) (xy 287.923078 -375.469298) (xy 287.948822 -375.529467) (xy 287.966248 -375.59255)
			(xy 287.975038 -375.657403) (xy 287.975035 -375.722849) (xy 287.966237 -375.7877) (xy 287.948805 -375.850781)
			(xy 287.923055 -375.910948) (xy 287.906714 -375.939304) (xy 287.903353 -375.945321) (xy 287.899615 -375.95858)
			(xy 287.899348 -375.965466) (xy 287.899348 -376.25147) (xy 287.898849 -376.261596) (xy 287.891129 -376.280319)
			(xy 287.876846 -376.294677) (xy 287.858164 -376.302495) (xy 287.84804 -376.303032) (xy 287.13176 -376.303032)
			(xy 287.121607 -376.302612) (xy 287.10286 -376.294809) (xy 287.088539 -376.280413) (xy 287.080835 -376.261625)
			(xy 287.080452 -376.25147) (xy 287.080452 -375.965466) (xy 287.080222 -375.958573) (xy 287.076491 -375.945301)
			(xy 287.073086 -375.939304) (xy 287.056773 -375.910934) (xy 287.031024 -375.850771) (xy 287.013593 -375.787694)
			(xy 287.004796 -375.722846) (xy 287.004792 -375.657405) (xy 287.013583 -375.592557) (xy 287.031007 -375.529477)
			(xy 287.056749 -375.469312) (xy 287.073086 -375.440956) (xy 287.076461 -375.434946) (xy 287.080191 -375.421682)
			(xy 287.080452 -375.414794) (xy 287.080452 -374.665494) (xy 287.080249 -374.658599) (xy 287.0765 -374.645327)
			(xy 287.073086 -374.639332) (xy 287.056712 -374.610996) (xy 287.030969 -374.550825) (xy 287.013544 -374.487741)
			(xy 287.004755 -374.422887) (xy 265.441386 -374.422887) (xy 265.346275 -374.568334) (xy 265.214181 -374.785613)
			(xy 265.089302 -375.007118) (xy 264.971773 -375.232608) (xy 264.861722 -375.461841) (xy 264.759266 -375.694568)
			(xy 264.664518 -375.930538) (xy 264.577579 -376.169495) (xy 264.498543 -376.411182) (xy 264.427496 -376.655336)
			(xy 264.364515 -376.901694) (xy 264.309668 -377.14999) (xy 264.263014 -377.399955) (xy 264.224603 -377.651319)
			(xy 264.209022 -377.777502) (xy 264.187686 -377.956826) (xy 264.186239 -377.965967) (xy 264.177695 -377.982371)
			(xy 264.163901 -377.994691) (xy 264.146639 -378.001334) (xy 264.137394 -378.001784) (xy 263.558782 -378.001784)
			(xy 263.548811 -378.002229) (xy 263.530375 -378.009825) (xy 263.522968 -378.016516) (xy 262.772673 -378.766811)
			(xy 269.68983 -378.766811) (xy 269.68983 -378.633249) (xy 269.697894 -378.499931) (xy 269.713994 -378.367343)
			(xy 269.738069 -378.235969) (xy 269.770032 -378.106288) (xy 269.809767 -377.978774) (xy 269.857129 -377.853891)
			(xy 269.911944 -377.732096) (xy 269.974014 -377.613833) (xy 270.04311 -377.499534) (xy 270.118982 -377.389614)
			(xy 270.201352 -377.284477) (xy 270.28992 -377.184504) (xy 270.384362 -377.090062) (xy 270.484335 -377.001494)
			(xy 270.589472 -376.919124) (xy 270.699392 -376.843252) (xy 270.813691 -376.774156) (xy 270.931954 -376.712086)
			(xy 271.053749 -376.657271) (xy 271.178632 -376.609909) (xy 271.306146 -376.570174) (xy 271.435827 -376.538211)
			(xy 271.567201 -376.514136) (xy 271.699789 -376.498036) (xy 271.833107 -376.489972) (xy 271.966669 -376.489972)
			(xy 272.099987 -376.498036) (xy 272.232575 -376.514136) (xy 272.363949 -376.538211) (xy 272.49363 -376.570174)
			(xy 272.621144 -376.609909) (xy 272.746027 -376.657271) (xy 272.867822 -376.712086) (xy 272.954316 -376.757482)
			(xy 289.204675 -376.757482) (xy 289.213469 -376.692632) (xy 289.230896 -376.629552) (xy 289.256642 -376.569386)
			(xy 289.27298 -376.54103) (xy 289.276283 -376.534999) (xy 289.279896 -376.52174) (xy 289.280092 -376.514868)
			(xy 289.280092 -375.765568) (xy 289.279913 -375.758694) (xy 289.276296 -375.745431) (xy 289.27298 -375.739406)
			(xy 289.256668 -375.711035) (xy 289.23092 -375.650872) (xy 289.213489 -375.587795) (xy 289.204692 -375.522948)
			(xy 289.204688 -375.457507) (xy 289.213478 -375.392659) (xy 289.230902 -375.329579) (xy 289.256643 -375.269414)
			(xy 289.27298 -375.241058) (xy 289.276308 -375.23504) (xy 289.279906 -375.221771) (xy 289.280092 -375.214896)
			(xy 289.280092 -374.928638) (xy 289.280664 -374.918488) (xy 289.288417 -374.899729) (xy 289.302758 -374.885364)
			(xy 289.321505 -374.87758) (xy 289.331654 -374.877076) (xy 290.047934 -374.877076) (xy 290.058113 -374.877437)
			(xy 290.076915 -374.88524) (xy 290.0913 -374.899645) (xy 290.099077 -374.918459) (xy 290.099496 -374.928638)
			(xy 290.099496 -375.214896) (xy 290.09969 -375.221769) (xy 290.103297 -375.235032) (xy 290.106608 -375.241058)
			(xy 290.122974 -375.269399) (xy 290.148718 -375.329568) (xy 290.166144 -375.392652) (xy 290.174934 -375.457505)
			(xy 290.174931 -375.52295) (xy 290.166133 -375.587802) (xy 290.1487 -375.650884) (xy 290.122949 -375.71105)
			(xy 290.106608 -375.739406) (xy 290.103292 -375.74543) (xy 290.099687 -375.758694) (xy 290.099496 -375.765568)
			(xy 290.099496 -376.514868) (xy 290.099701 -376.52174) (xy 290.103301 -376.535003) (xy 290.106608 -376.54103)
			(xy 290.12295 -376.569384) (xy 290.148697 -376.62955) (xy 290.166125 -376.692631) (xy 290.174918 -376.757481)
			(xy 290.174918 -376.822925) (xy 293.604726 -376.822925) (xy 293.604726 -376.757482) (xy 293.613518 -376.692633)
			(xy 293.630943 -376.629553) (xy 293.656685 -376.569386) (xy 293.673022 -376.54103) (xy 293.676373 -376.535009)
			(xy 293.680117 -376.521753) (xy 293.680388 -376.514868) (xy 293.680388 -375.765568) (xy 293.68013 -375.758679)
			(xy 293.676405 -375.745412) (xy 293.673022 -375.739406) (xy 293.656712 -375.711035) (xy 293.630967 -375.650871)
			(xy 293.613538 -375.587794) (xy 293.604742 -375.522948) (xy 293.604738 -375.457507) (xy 293.613527 -375.392659)
			(xy 293.630949 -375.329581) (xy 293.656687 -375.269414) (xy 293.673022 -375.241058) (xy 293.676399 -375.235049)
			(xy 293.680127 -375.221784) (xy 293.680388 -375.214896) (xy 293.680388 -374.928638) (xy 293.680956 -374.91852)
			(xy 293.688662 -374.89981) (xy 293.702923 -374.885454) (xy 293.721582 -374.877624) (xy 293.731696 -374.877076)
			(xy 294.447976 -374.877076) (xy 294.458126 -374.877541) (xy 294.476873 -374.885324) (xy 294.491196 -374.899707)
			(xy 294.498901 -374.918487) (xy 294.499284 -374.928638) (xy 294.499284 -375.214896) (xy 294.499486 -375.221791)
			(xy 294.503235 -375.235063) (xy 294.50665 -375.241058) (xy 294.523015 -375.269399) (xy 294.548757 -375.329569)
			(xy 294.566181 -375.392652) (xy 294.57497 -375.457505) (xy 294.574967 -375.52295) (xy 294.56617 -375.587801)
			(xy 294.548739 -375.650883) (xy 294.52299 -375.71105) (xy 294.50665 -375.739406) (xy 294.503284 -375.74542)
			(xy 294.49955 -375.758681) (xy 294.499284 -375.765568) (xy 294.499284 -376.514868) (xy 294.499496 -376.521763)
			(xy 294.503238 -376.535035) (xy 294.50665 -376.54103) (xy 294.522991 -376.569384) (xy 294.548735 -376.629551)
			(xy 294.566162 -376.692632) (xy 294.574954 -376.757482) (xy 294.574954 -376.822925) (xy 298.004762 -376.822925)
			(xy 298.004762 -376.757482) (xy 298.013555 -376.692632) (xy 298.030981 -376.629552) (xy 298.056726 -376.569386)
			(xy 298.073064 -376.54103) (xy 298.076365 -376.534999) (xy 298.07998 -376.52174) (xy 298.080176 -376.514868)
			(xy 298.080176 -375.765568) (xy 298.079999 -375.758694) (xy 298.076381 -375.745431) (xy 298.073064 -375.739406)
			(xy 298.056753 -375.711035) (xy 298.031005 -375.650872) (xy 298.013575 -375.587795) (xy 298.004778 -375.522948)
			(xy 298.004774 -375.457507) (xy 298.013564 -375.392659) (xy 298.030987 -375.32958) (xy 298.056728 -375.269414)
			(xy 298.073064 -375.241058) (xy 298.076391 -375.235039) (xy 298.079989 -375.221771) (xy 298.080176 -375.214896)
			(xy 298.080176 -374.928638) (xy 298.080596 -374.918464) (xy 298.088376 -374.899663) (xy 298.102763 -374.885276)
			(xy 298.121564 -374.877496) (xy 298.131738 -374.877076) (xy 298.848018 -374.877076) (xy 298.858195 -374.87745)
			(xy 298.876998 -374.885248) (xy 298.891383 -374.899649) (xy 298.899161 -374.91846) (xy 298.89958 -374.928638)
			(xy 298.89958 -375.214896) (xy 298.899776 -375.221769) (xy 298.903382 -375.235032) (xy 298.906692 -375.241058)
			(xy 298.923056 -375.2694) (xy 298.948795 -375.32957) (xy 298.966218 -375.392653) (xy 298.975007 -375.457505)
			(xy 298.975003 -375.52295) (xy 298.966207 -375.587801) (xy 298.948777 -375.650882) (xy 298.923031 -375.711049)
			(xy 298.906692 -375.739406) (xy 298.903375 -375.745429) (xy 298.899771 -375.758694) (xy 298.89958 -375.765568)
			(xy 298.89958 -376.514868) (xy 298.899787 -376.52174) (xy 298.903385 -376.535003) (xy 298.906692 -376.54103)
			(xy 298.923032 -376.569385) (xy 298.948774 -376.629552) (xy 298.966199 -376.692632) (xy 298.974991 -376.757482)
			(xy 298.97499 -376.822925) (xy 302.404812 -376.822925) (xy 302.404812 -376.757482) (xy 302.413604 -376.692633)
			(xy 302.431028 -376.629553) (xy 302.45677 -376.569387) (xy 302.473106 -376.54103) (xy 302.476456 -376.535008)
			(xy 302.480201 -376.521753) (xy 302.480472 -376.514868) (xy 302.480472 -375.765568) (xy 302.480238 -375.758675)
			(xy 302.47651 -375.745403) (xy 302.473106 -375.739406) (xy 302.456797 -375.711035) (xy 302.431052 -375.650871)
			(xy 302.413624 -375.587794) (xy 302.404828 -375.522948) (xy 302.404824 -375.457507) (xy 302.413613 -375.39266)
			(xy 302.431034 -375.329581) (xy 302.456772 -375.269414) (xy 302.473106 -375.241058) (xy 302.476481 -375.235049)
			(xy 302.48021 -375.221784) (xy 302.480472 -375.214896) (xy 302.480472 -374.928638) (xy 302.480959 -374.91851)
			(xy 302.48868 -374.899784) (xy 302.502967 -374.885425) (xy 302.521654 -374.87761) (xy 302.53178 -374.877076)
			(xy 303.24806 -374.877076) (xy 303.258209 -374.877554) (xy 303.276955 -374.885332) (xy 303.291279 -374.899711)
			(xy 303.298985 -374.918488) (xy 303.299368 -374.928638) (xy 303.299368 -375.214896) (xy 303.299572 -375.221791)
			(xy 303.30332 -375.235063) (xy 303.306734 -375.241058) (xy 303.323099 -375.269399) (xy 303.348842 -375.329569)
			(xy 303.366267 -375.392652) (xy 303.375057 -375.457505) (xy 303.375053 -375.52295) (xy 303.366256 -375.587802)
			(xy 303.348824 -375.650883) (xy 303.332027 -375.69013) (xy 304.603666 -375.69013) (xy 304.607657 -375.627963)
			(xy 304.619566 -375.566816) (xy 304.639195 -375.507695) (xy 304.666224 -375.451569) (xy 304.700208 -375.39936)
			(xy 304.74059 -375.351925) (xy 304.786706 -375.310044) (xy 304.837798 -375.274404) (xy 304.893029 -375.24559)
			(xy 304.951491 -375.224076) (xy 305.012225 -375.210214) (xy 305.074232 -375.204232) (xy 305.136495 -375.206228)
			(xy 305.197992 -375.216171) (xy 305.257713 -375.233895) (xy 305.314676 -375.259112) (xy 305.367947 -375.291405)
			(xy 305.416652 -375.330245) (xy 305.459989 -375.374995) (xy 305.497249 -375.424919) (xy 305.527818 -375.479198)
			(xy 305.532285 -375.490232) (xy 306.803814 -375.490232) (xy 306.807805 -375.428065) (xy 306.819714 -375.366918)
			(xy 306.839343 -375.307797) (xy 306.866372 -375.251671) (xy 306.900356 -375.199462) (xy 306.940738 -375.152027)
			(xy 306.986854 -375.110146) (xy 307.037946 -375.074506) (xy 307.093177 -375.045692) (xy 307.151639 -375.024178)
			(xy 307.212373 -375.010316) (xy 307.27438 -375.004334) (xy 307.336643 -375.00633) (xy 307.39814 -375.016273)
			(xy 307.457861 -375.033997) (xy 307.514824 -375.059214) (xy 307.568095 -375.091507) (xy 307.6168 -375.130347)
			(xy 307.660137 -375.175097) (xy 307.697397 -375.225021) (xy 307.727966 -375.2793) (xy 307.751344 -375.337043)
			(xy 307.767145 -375.397301) (xy 307.775111 -375.459084) (xy 307.77561 -375.490232) (xy 307.775111 -375.52138)
			(xy 307.767145 -375.583163) (xy 307.751344 -375.643421) (xy 307.727966 -375.701164) (xy 307.697397 -375.755443)
			(xy 307.660137 -375.805367) (xy 307.6168 -375.850117) (xy 307.568095 -375.888957) (xy 307.514824 -375.92125)
			(xy 307.457861 -375.946467) (xy 307.39814 -375.964191) (xy 307.336643 -375.974134) (xy 307.27438 -375.97613)
			(xy 307.212373 -375.970148) (xy 307.151639 -375.956286) (xy 307.093177 -375.934772) (xy 307.037946 -375.905958)
			(xy 306.986854 -375.870318) (xy 306.940738 -375.828437) (xy 306.900356 -375.781002) (xy 306.866372 -375.728793)
			(xy 306.839343 -375.672667) (xy 306.819714 -375.613546) (xy 306.807805 -375.552399) (xy 306.803814 -375.490232)
			(xy 305.532285 -375.490232) (xy 305.551196 -375.536941) (xy 305.566997 -375.597199) (xy 305.574963 -375.658982)
			(xy 305.575462 -375.69013) (xy 305.574963 -375.721278) (xy 305.566997 -375.783061) (xy 305.551196 -375.843319)
			(xy 305.527818 -375.901062) (xy 305.497249 -375.955341) (xy 305.459989 -376.005265) (xy 305.416652 -376.050015)
			(xy 305.367947 -376.088855) (xy 305.314676 -376.121148) (xy 305.257713 -376.146365) (xy 305.197992 -376.164089)
			(xy 305.136495 -376.174032) (xy 305.074232 -376.176028) (xy 305.012225 -376.170046) (xy 304.951491 -376.156184)
			(xy 304.893029 -376.13467) (xy 304.837798 -376.105856) (xy 304.786706 -376.070216) (xy 304.74059 -376.028335)
			(xy 304.700208 -375.9809) (xy 304.666224 -375.928691) (xy 304.639195 -375.872565) (xy 304.619566 -375.813444)
			(xy 304.607657 -375.752297) (xy 304.603666 -375.69013) (xy 303.332027 -375.69013) (xy 303.323074 -375.71105)
			(xy 303.306734 -375.739406) (xy 303.303366 -375.745419) (xy 303.299633 -375.758681) (xy 303.299368 -375.765568)
			(xy 303.299368 -376.514868) (xy 303.299583 -376.521762) (xy 303.303323 -376.535034) (xy 303.306734 -376.54103)
			(xy 303.323076 -376.569384) (xy 303.348821 -376.629551) (xy 303.366248 -376.692631) (xy 303.375041 -376.757482)
			(xy 303.37504 -376.790204) (xy 306.803814 -376.790204) (xy 306.807805 -376.728037) (xy 306.819714 -376.66689)
			(xy 306.839343 -376.607769) (xy 306.866372 -376.551643) (xy 306.900356 -376.499434) (xy 306.940738 -376.451999)
			(xy 306.986854 -376.410118) (xy 307.037946 -376.374478) (xy 307.093177 -376.345664) (xy 307.151639 -376.32415)
			(xy 307.212373 -376.310288) (xy 307.27438 -376.304306) (xy 307.336643 -376.306302) (xy 307.39814 -376.316245)
			(xy 307.457861 -376.333969) (xy 307.514824 -376.359186) (xy 307.568095 -376.391479) (xy 307.6168 -376.430319)
			(xy 307.660137 -376.475069) (xy 307.697397 -376.524993) (xy 307.727966 -376.579272) (xy 307.751344 -376.637015)
			(xy 307.767145 -376.697273) (xy 307.775111 -376.759056) (xy 307.77561 -376.790204) (xy 307.775111 -376.821352)
			(xy 307.767145 -376.883135) (xy 307.751344 -376.943393) (xy 307.727966 -377.001136) (xy 307.697397 -377.055415)
			(xy 307.660137 -377.105339) (xy 307.6168 -377.150089) (xy 307.568095 -377.188929) (xy 307.514824 -377.221222)
			(xy 307.457861 -377.246439) (xy 307.39814 -377.264163) (xy 307.336643 -377.274106) (xy 307.27438 -377.276102)
			(xy 307.212373 -377.27012) (xy 307.151639 -377.256258) (xy 307.093177 -377.234744) (xy 307.037946 -377.20593)
			(xy 306.986854 -377.17029) (xy 306.940738 -377.128409) (xy 306.900356 -377.080974) (xy 306.866372 -377.028765)
			(xy 306.839343 -376.972639) (xy 306.819714 -376.913518) (xy 306.807805 -376.852371) (xy 306.803814 -376.790204)
			(xy 303.37504 -376.790204) (xy 303.37504 -376.822925) (xy 303.366246 -376.887775) (xy 303.348818 -376.950856)
			(xy 303.323072 -377.011022) (xy 303.306734 -377.039378) (xy 303.303376 -377.045396) (xy 303.299637 -377.058654)
			(xy 303.299368 -377.06554) (xy 303.299368 -377.35129) (xy 303.298865 -377.361415) (xy 303.291142 -377.380135)
			(xy 303.276861 -377.394491) (xy 303.258182 -377.402312) (xy 303.24806 -377.402852) (xy 302.53178 -377.402852)
			(xy 302.521631 -377.402396) (xy 302.502888 -377.394604) (xy 302.488567 -377.380218) (xy 302.480859 -377.361441)
			(xy 302.480472 -377.35129) (xy 302.480472 -377.06554) (xy 302.480227 -377.058649) (xy 302.476493 -377.045383)
			(xy 302.473106 -377.039378) (xy 302.456773 -377.01102) (xy 302.431031 -376.950853) (xy 302.413605 -376.887773)
			(xy 302.404812 -376.822925) (xy 298.97499 -376.822925) (xy 298.966197 -376.887774) (xy 298.948771 -376.950854)
			(xy 298.923029 -377.011021) (xy 298.906692 -377.039378) (xy 298.903385 -377.045406) (xy 298.899774 -377.058667)
			(xy 298.89958 -377.06554) (xy 298.89958 -377.35129) (xy 298.899059 -377.361445) (xy 298.891291 -377.38021)
			(xy 298.876934 -377.394575) (xy 298.858173 -377.402353) (xy 298.848018 -377.402852) (xy 298.131738 -377.402852)
			(xy 298.121568 -377.402405) (xy 298.102772 -377.39463) (xy 298.088385 -377.380252) (xy 298.080601 -377.36146)
			(xy 298.080176 -377.35129) (xy 298.080176 -377.06554) (xy 298.079972 -377.058668) (xy 298.076372 -377.045405)
			(xy 298.073064 -377.039378) (xy 298.056729 -377.01102) (xy 298.030984 -376.950854) (xy 298.013556 -376.887774)
			(xy 298.004762 -376.822925) (xy 294.574954 -376.822925) (xy 294.56616 -376.887775) (xy 294.548733 -376.950855)
			(xy 294.522988 -377.011022) (xy 294.50665 -377.039378) (xy 294.503294 -377.045397) (xy 294.499553 -377.058654)
			(xy 294.499284 -377.06554) (xy 294.499284 -377.35129) (xy 294.498766 -377.361413) (xy 294.491046 -377.38013)
			(xy 294.47677 -377.394485) (xy 294.458096 -377.402309) (xy 294.447976 -377.402852) (xy 293.731696 -377.402852)
			(xy 293.721548 -377.402383) (xy 293.702806 -377.394595) (xy 293.688484 -377.380214) (xy 293.680776 -377.36144)
			(xy 293.680388 -377.35129) (xy 293.680388 -377.06554) (xy 293.680141 -377.05865) (xy 293.676408 -377.045384)
			(xy 293.673022 -377.039378) (xy 293.656689 -377.01102) (xy 293.630945 -376.950853) (xy 293.613519 -376.887774)
			(xy 293.604726 -376.822925) (xy 290.174918 -376.822925) (xy 290.166123 -376.887776) (xy 290.148695 -376.950856)
			(xy 290.122947 -377.011022) (xy 290.106608 -377.039378) (xy 290.103302 -377.045407) (xy 290.099691 -377.058667)
			(xy 290.099496 -377.06554) (xy 290.099496 -377.35129) (xy 290.098959 -377.361443) (xy 290.091194 -377.380205)
			(xy 290.076842 -377.39457) (xy 290.058087 -377.402351) (xy 290.047934 -377.402852) (xy 289.331654 -377.402852)
			(xy 289.321492 -377.402404) (xy 289.30272 -377.394613) (xy 289.288356 -377.380233) (xy 289.280585 -377.361452)
			(xy 289.280092 -377.35129) (xy 289.280092 -377.06554) (xy 289.279886 -377.058668) (xy 289.276287 -377.045405)
			(xy 289.27298 -377.039378) (xy 289.256645 -377.01102) (xy 289.230898 -376.950854) (xy 289.21347 -376.887775)
			(xy 289.204676 -376.822925) (xy 289.204675 -376.757482) (xy 272.954316 -376.757482) (xy 272.986085 -376.774156)
			(xy 273.100384 -376.843252) (xy 273.210304 -376.919124) (xy 273.315441 -377.001494) (xy 273.415414 -377.090062)
			(xy 273.509856 -377.184504) (xy 273.598424 -377.284477) (xy 273.680794 -377.389614) (xy 273.756666 -377.499534)
			(xy 273.825762 -377.613833) (xy 273.887832 -377.732096) (xy 273.942647 -377.853891) (xy 273.990009 -377.978774)
			(xy 274.029744 -378.106288) (xy 274.061707 -378.235969) (xy 274.077619 -378.3228) (xy 287.004764 -378.3228)
			(xy 287.004767 -378.257355) (xy 287.013564 -378.192504) (xy 287.030996 -378.129422) (xy 287.056745 -378.069256)
			(xy 287.073086 -378.0409) (xy 287.076445 -378.034882) (xy 287.080185 -378.021624) (xy 287.080452 -378.014738)
			(xy 287.080452 -377.728734) (xy 287.080955 -377.718608) (xy 287.088674 -377.699885) (xy 287.102955 -377.685528)
			(xy 287.121637 -377.677709) (xy 287.13176 -377.677172) (xy 287.84804 -377.677172) (xy 287.858193 -377.677588)
			(xy 287.876941 -377.685392) (xy 287.891262 -377.699789) (xy 287.898965 -377.718579) (xy 287.899348 -377.728734)
			(xy 287.899348 -378.014738) (xy 287.899577 -378.021631) (xy 287.903308 -378.034903) (xy 287.906714 -378.0409)
			(xy 287.923031 -378.069268) (xy 287.948779 -378.129431) (xy 287.96621 -378.192509) (xy 287.975006 -378.257357)
			(xy 287.975009 -378.322799) (xy 287.975009 -378.3228) (xy 291.404814 -378.3228) (xy 291.404817 -378.257355)
			(xy 291.413613 -378.192505) (xy 291.431042 -378.129424) (xy 291.456789 -378.069256) (xy 291.473128 -378.0409)
			(xy 291.476445 -378.034876) (xy 291.480049 -378.021612) (xy 291.48024 -378.014738) (xy 291.48024 -377.728734)
			(xy 291.480692 -377.718564) (xy 291.488466 -377.69977) (xy 291.502843 -377.685384) (xy 291.521633 -377.677598)
			(xy 291.531802 -377.677172) (xy 292.248082 -377.677172) (xy 292.258257 -377.677579) (xy 292.277058 -377.685365)
			(xy 292.291444 -377.699756) (xy 292.299224 -377.718559) (xy 292.299644 -377.728734) (xy 292.299644 -378.014738)
			(xy 292.299854 -378.02161) (xy 292.303449 -378.034873) (xy 292.306756 -378.0409) (xy 292.323071 -378.069268)
			(xy 292.348818 -378.129432) (xy 292.366247 -378.19251) (xy 292.375043 -378.257357) (xy 292.375046 -378.322798)
			(xy 292.375046 -378.3228) (xy 295.80485 -378.3228) (xy 295.804853 -378.257355) (xy 295.81365 -378.192504)
			(xy 295.831081 -378.129423) (xy 295.85683 -378.069256) (xy 295.87317 -378.0409) (xy 295.876536 -378.034886)
			(xy 295.88027 -378.021625) (xy 295.880536 -378.014738) (xy 295.880536 -377.728734) (xy 295.881055 -377.71861)
			(xy 295.88877 -377.69989) (xy 295.903047 -377.685533) (xy 295.921723 -377.677712) (xy 295.931844 -377.677172)
			(xy 296.648124 -377.677172) (xy 296.658276 -377.677601) (xy 296.677024 -377.6854) (xy 296.691345 -377.699793)
			(xy 296.699049 -377.71858) (xy 296.699432 -377.728734) (xy 296.699432 -378.014738) (xy 296.699663 -378.021631)
			(xy 296.703393 -378.034903) (xy 296.706798 -378.0409) (xy 296.723112 -378.069269) (xy 296.748856 -378.129433)
			(xy 296.766284 -378.19251) (xy 296.775079 -378.257357) (xy 296.775082 -378.322798) (xy 296.775082 -378.3228)
			(xy 300.20464 -378.3228) (xy 300.204643 -378.257355) (xy 300.213439 -378.192504) (xy 300.23087 -378.129423)
			(xy 300.256618 -378.069256) (xy 300.272958 -378.0409) (xy 300.276323 -378.034885) (xy 300.280058 -378.021625)
			(xy 300.280324 -378.014738) (xy 300.280324 -377.728734) (xy 300.280854 -377.718611) (xy 300.288568 -377.699894)
			(xy 300.302841 -377.685537) (xy 300.321512 -377.677714) (xy 300.331632 -377.677172) (xy 301.047912 -377.677172)
			(xy 301.058063 -377.677611) (xy 301.076811 -377.685405) (xy 301.091133 -377.699796) (xy 301.098837 -377.718581)
			(xy 301.09922 -377.728734) (xy 301.09922 -378.014738) (xy 301.099474 -378.021628) (xy 301.103202 -378.034894)
			(xy 301.106586 -378.0409) (xy 301.122901 -378.069269) (xy 301.148645 -378.129433) (xy 301.166073 -378.19251)
			(xy 301.174868 -378.257357) (xy 301.174869 -378.290074) (xy 304.603666 -378.290074) (xy 304.607657 -378.227907)
			(xy 304.619566 -378.16676) (xy 304.639195 -378.107639) (xy 304.666224 -378.051513) (xy 304.700208 -377.999304)
			(xy 304.74059 -377.951869) (xy 304.786706 -377.909988) (xy 304.837798 -377.874348) (xy 304.893029 -377.845534)
			(xy 304.951491 -377.82402) (xy 305.012225 -377.810158) (xy 305.074232 -377.804176) (xy 305.136495 -377.806172)
			(xy 305.197992 -377.816115) (xy 305.257713 -377.833839) (xy 305.314676 -377.859056) (xy 305.367947 -377.891349)
			(xy 305.416652 -377.930189) (xy 305.459989 -377.974939) (xy 305.497249 -378.024863) (xy 305.527818 -378.079142)
			(xy 305.551196 -378.136885) (xy 305.566997 -378.197143) (xy 305.574963 -378.258926) (xy 305.575462 -378.290074)
			(xy 305.574963 -378.321222) (xy 305.566997 -378.383005) (xy 305.551196 -378.443263) (xy 305.527818 -378.501006)
			(xy 305.497249 -378.555285) (xy 305.459989 -378.605209) (xy 305.416652 -378.649959) (xy 305.367947 -378.688799)
			(xy 305.314676 -378.721092) (xy 305.257713 -378.746309) (xy 305.197992 -378.764033) (xy 305.136495 -378.773976)
			(xy 305.074232 -378.775972) (xy 305.012225 -378.76999) (xy 304.951491 -378.756128) (xy 304.893029 -378.734614)
			(xy 304.837798 -378.7058) (xy 304.786706 -378.67016) (xy 304.74059 -378.628279) (xy 304.700208 -378.580844)
			(xy 304.666224 -378.528635) (xy 304.639195 -378.472509) (xy 304.619566 -378.413388) (xy 304.607657 -378.352241)
			(xy 304.603666 -378.290074) (xy 301.174869 -378.290074) (xy 301.174871 -378.322798) (xy 301.166082 -378.387646)
			(xy 301.14866 -378.450725) (xy 301.122921 -378.510892) (xy 301.106586 -378.539248) (xy 301.103208 -378.545256)
			(xy 301.099481 -378.558522) (xy 301.09922 -378.56541) (xy 301.09922 -379.31471) (xy 301.099447 -379.321602)
			(xy 301.103193 -379.334868) (xy 301.106586 -379.340872) (xy 301.122962 -379.369207) (xy 301.148701 -379.429379)
			(xy 301.166122 -379.492463) (xy 301.174909 -379.557317) (xy 301.174904 -379.622762) (xy 301.166106 -379.687614)
			(xy 301.148674 -379.750696) (xy 301.122926 -379.810863) (xy 301.106586 -379.83922) (xy 301.103218 -379.845233)
			(xy 301.099484 -379.858495) (xy 301.09922 -379.865382) (xy 301.09922 -380.151386) (xy 301.098761 -380.161517)
			(xy 301.09103 -380.180245) (xy 301.076735 -380.194603) (xy 301.058041 -380.202416) (xy 301.047912 -380.202948)
			(xy 300.331632 -380.202948) (xy 300.321486 -380.202453) (xy 300.302743 -380.194677) (xy 300.28842 -380.180304)
			(xy 300.280711 -380.161534) (xy 300.280324 -380.151386) (xy 300.280324 -379.865382) (xy 300.280091 -379.858489)
			(xy 300.276363 -379.845217) (xy 300.272958 -379.83922) (xy 300.256659 -379.810843) (xy 300.23091 -379.750681)
			(xy 300.213479 -379.687605) (xy 300.204681 -379.622759) (xy 300.204676 -379.557319) (xy 300.213463 -379.492472)
			(xy 300.230884 -379.429394) (xy 300.256623 -379.369228) (xy 300.272958 -379.340872) (xy 300.276333 -379.334862)
			(xy 300.280062 -379.321598) (xy 300.280324 -379.31471) (xy 300.280324 -378.56541) (xy 300.280119 -378.558515)
			(xy 300.276372 -378.545243) (xy 300.272958 -378.539248) (xy 300.256598 -378.510904) (xy 300.230855 -378.450735)
			(xy 300.21343 -378.387652) (xy 300.20464 -378.3228) (xy 296.775082 -378.3228) (xy 296.766293 -378.387646)
			(xy 296.748871 -378.450725) (xy 296.723132 -378.510891) (xy 296.706798 -378.539248) (xy 296.703421 -378.545257)
			(xy 296.699693 -378.558522) (xy 296.699432 -378.56541) (xy 296.699432 -379.31471) (xy 296.699657 -379.321602)
			(xy 296.703405 -379.334868) (xy 296.706798 -379.340872) (xy 296.723173 -379.369207) (xy 296.748912 -379.429379)
			(xy 296.766332 -379.492464) (xy 296.77512 -379.557317) (xy 296.775114 -379.622762) (xy 296.766316 -379.687614)
			(xy 296.748885 -379.750696) (xy 296.723137 -379.810863) (xy 296.706798 -379.83922) (xy 296.703431 -379.845233)
			(xy 296.699696 -379.858495) (xy 296.699432 -379.865382) (xy 296.699432 -380.151386) (xy 296.698961 -380.161515)
			(xy 296.691233 -380.180241) (xy 296.676941 -380.194599) (xy 296.658251 -380.202414) (xy 296.648124 -380.202948)
			(xy 295.931844 -380.202948) (xy 295.921699 -380.202443) (xy 295.902957 -380.194671) (xy 295.888633 -380.1803)
			(xy 295.880924 -380.161533) (xy 295.880536 -380.151386) (xy 295.880536 -379.865382) (xy 295.880301 -379.858489)
			(xy 295.876574 -379.845217) (xy 295.87317 -379.83922) (xy 295.856871 -379.810843) (xy 295.831121 -379.750681)
			(xy 295.81369 -379.687606) (xy 295.804891 -379.62276) (xy 295.804886 -379.557319) (xy 295.813674 -379.492472)
			(xy 295.831095 -379.429393) (xy 295.856835 -379.369228) (xy 295.87317 -379.340872) (xy 295.876546 -379.334863)
			(xy 295.880274 -379.321598) (xy 295.880536 -379.31471) (xy 295.880536 -378.56541) (xy 295.880329 -378.558515)
			(xy 295.876583 -378.545243) (xy 295.87317 -378.539248) (xy 295.85681 -378.510904) (xy 295.831066 -378.450735)
			(xy 295.813641 -378.387652) (xy 295.80485 -378.3228) (xy 292.375046 -378.3228) (xy 292.366256 -378.387647)
			(xy 292.348832 -378.450726) (xy 292.323092 -378.510892) (xy 292.306756 -378.539248) (xy 292.303429 -378.545267)
			(xy 292.29983 -378.558535) (xy 292.299644 -378.56541) (xy 292.299644 -379.31471) (xy 292.299827 -379.321584)
			(xy 292.303441 -379.334847) (xy 292.306756 -379.340872) (xy 292.323133 -379.369207) (xy 292.348873 -379.429378)
			(xy 292.366295 -379.492463) (xy 292.375084 -379.557316) (xy 292.375078 -379.622763) (xy 292.366279 -379.687615)
			(xy 292.348847 -379.750696) (xy 292.323097 -379.810864) (xy 292.306756 -379.83922) (xy 292.303439 -379.845243)
			(xy 292.299834 -379.858508) (xy 292.299644 -379.865382) (xy 292.299644 -380.151386) (xy 292.299224 -380.161559)
			(xy 292.291441 -380.180357) (xy 292.277054 -380.194743) (xy 292.258255 -380.202525) (xy 292.248082 -380.202948)
			(xy 291.531802 -380.202948) (xy 291.521629 -380.202534) (xy 291.502831 -380.194747) (xy 291.488446 -380.180358)
			(xy 291.480663 -380.161559) (xy 291.48024 -380.151386) (xy 291.48024 -379.865382) (xy 291.48005 -379.858509)
			(xy 291.47644 -379.845246) (xy 291.473128 -379.83922) (xy 291.45683 -379.810842) (xy 291.431083 -379.75068)
			(xy 291.413653 -379.687605) (xy 291.404855 -379.622759) (xy 291.40485 -379.55732) (xy 291.413637 -379.492473)
			(xy 291.431057 -379.429394) (xy 291.456794 -379.369228) (xy 291.473128 -379.340872) (xy 291.476455 -379.334853)
			(xy 291.480052 -379.321585) (xy 291.48024 -379.31471) (xy 291.48024 -378.56541) (xy 291.480039 -378.558537)
			(xy 291.476436 -378.545275) (xy 291.473128 -378.539248) (xy 291.456769 -378.510904) (xy 291.431028 -378.450734)
			(xy 291.413604 -378.387652) (xy 291.404814 -378.3228) (xy 287.975009 -378.3228) (xy 287.966219 -378.387647)
			(xy 287.948794 -378.450727) (xy 287.923051 -378.510892) (xy 287.906714 -378.539248) (xy 287.903338 -378.545257)
			(xy 287.899609 -378.558522) (xy 287.899348 -378.56541) (xy 287.899348 -379.31471) (xy 287.899549 -379.321605)
			(xy 287.903299 -379.334877) (xy 287.906714 -379.340872) (xy 287.923092 -379.369206) (xy 287.948835 -379.429377)
			(xy 287.966258 -379.492462) (xy 287.975047 -379.557316) (xy 287.975042 -379.622763) (xy 287.966243 -379.687615)
			(xy 287.948808 -379.750697) (xy 287.923056 -379.810864) (xy 287.906714 -379.83922) (xy 287.903348 -379.845234)
			(xy 287.899613 -379.858495) (xy 287.899348 -379.865382) (xy 287.899348 -380.151386) (xy 287.898862 -380.161513)
			(xy 287.891136 -380.180236) (xy 287.87685 -380.194594) (xy 287.858165 -380.202411) (xy 287.84804 -380.202948)
			(xy 287.13176 -380.202948) (xy 287.121609 -380.202512) (xy 287.102865 -380.194712) (xy 287.088545 -380.180321)
			(xy 287.080838 -380.161539) (xy 287.080452 -380.151386) (xy 287.080452 -379.865382) (xy 287.080216 -379.858489)
			(xy 287.07649 -379.845217) (xy 287.073086 -379.83922) (xy 287.056786 -379.810843) (xy 287.031036 -379.750682)
			(xy 287.013604 -379.687606) (xy 287.004805 -379.62276) (xy 287.0048 -379.557319) (xy 287.013588 -379.492472)
			(xy 287.03101 -379.429393) (xy 287.05675 -379.369228) (xy 287.073086 -379.340872) (xy 287.076455 -379.334859)
			(xy 287.080188 -379.321597) (xy 287.080452 -379.31471) (xy 287.080452 -378.56541) (xy 287.080243 -378.558515)
			(xy 287.076498 -378.545243) (xy 287.073086 -378.539248) (xy 287.056725 -378.510904) (xy 287.030981 -378.450735)
			(xy 287.013555 -378.387653) (xy 287.004764 -378.3228) (xy 274.077619 -378.3228) (xy 274.085782 -378.367343)
			(xy 274.101882 -378.499931) (xy 274.109946 -378.633249) (xy 274.11045 -378.70003) (xy 274.109946 -378.766811)
			(xy 274.101882 -378.900129) (xy 274.085782 -379.032717) (xy 274.061707 -379.164091) (xy 274.029744 -379.293772)
			(xy 273.990009 -379.421286) (xy 273.942647 -379.546169) (xy 273.887832 -379.667964) (xy 273.825762 -379.786227)
			(xy 273.756666 -379.900526) (xy 273.680794 -380.010446) (xy 273.598424 -380.115583) (xy 273.509856 -380.215556)
			(xy 273.415414 -380.309998) (xy 273.315441 -380.398566) (xy 273.210304 -380.480936) (xy 273.100384 -380.556808)
			(xy 272.986085 -380.625904) (xy 272.926083 -380.657396) (xy 289.204683 -380.657396) (xy 289.213474 -380.592547)
			(xy 289.230899 -380.529468) (xy 289.256643 -380.469302) (xy 289.27298 -380.440946) (xy 289.276277 -380.434913)
			(xy 289.279894 -380.421656) (xy 289.280092 -380.414784) (xy 289.280092 -379.665484) (xy 289.279907 -379.65861)
			(xy 289.276294 -379.645347) (xy 289.27298 -379.639322) (xy 289.256682 -379.610944) (xy 289.230932 -379.550783)
			(xy 289.2135 -379.487707) (xy 289.204701 -379.422861) (xy 289.204695 -379.357421) (xy 289.213483 -379.292574)
			(xy 289.230905 -379.229495) (xy 289.256645 -379.16933) (xy 289.27298 -379.140974) (xy 289.276303 -379.134953)
			(xy 289.279904 -379.121687) (xy 289.280092 -379.114812) (xy 289.280092 -378.828554) (xy 289.280595 -378.818399)
			(xy 289.288376 -378.799638) (xy 289.302738 -378.785276) (xy 289.321499 -378.777495) (xy 289.331654 -378.776992)
			(xy 290.047934 -378.776992) (xy 290.058088 -378.777504) (xy 290.076849 -378.785281) (xy 290.091212 -378.799641)
			(xy 290.098993 -378.8184) (xy 290.099496 -378.828554) (xy 290.099496 -379.114812) (xy 290.099684 -379.121686)
			(xy 290.103295 -379.134948) (xy 290.106608 -379.140974) (xy 290.122988 -379.169307) (xy 290.148731 -379.229479)
			(xy 290.166155 -379.292564) (xy 290.174943 -379.357418) (xy 290.174938 -379.422865) (xy 290.166138 -379.487717)
			(xy 290.148703 -379.550799) (xy 290.12295 -379.610966) (xy 290.106608 -379.639322) (xy 290.103286 -379.645343)
			(xy 290.099685 -379.65861) (xy 290.099496 -379.665484) (xy 290.099496 -380.414784) (xy 290.099694 -380.421657)
			(xy 290.103298 -380.43492) (xy 290.106608 -380.440946) (xy 290.122964 -380.469292) (xy 290.148709 -380.529461)
			(xy 290.166136 -380.592543) (xy 290.174927 -380.657395) (xy 290.174927 -380.657396) (xy 293.604733 -380.657396)
			(xy 293.613523 -380.592548) (xy 293.630946 -380.529469) (xy 293.656686 -380.469302) (xy 293.673022 -380.440946)
			(xy 293.676403 -380.434939) (xy 293.680128 -380.421673) (xy 293.680388 -380.414784) (xy 293.680388 -379.665484)
			(xy 293.680124 -379.658595) (xy 293.676403 -379.645329) (xy 293.673022 -379.639322) (xy 293.656726 -379.610943)
			(xy 293.630979 -379.550782) (xy 293.613549 -379.487706) (xy 293.604751 -379.422861) (xy 293.604746 -379.357421)
			(xy 293.613532 -379.292575) (xy 293.630952 -379.229496) (xy 293.656688 -379.16933) (xy 293.673022 -379.140974)
			(xy 293.676393 -379.134962) (xy 293.680125 -379.121699) (xy 293.680388 -379.114812) (xy 293.680388 -378.828554)
			(xy 293.680887 -378.818431) (xy 293.688621 -378.799718) (xy 293.702902 -378.785366) (xy 293.721575 -378.777539)
			(xy 293.731696 -378.776992) (xy 294.447976 -378.776992) (xy 294.458128 -378.777441) (xy 294.476878 -378.785227)
			(xy 294.491202 -378.799615) (xy 294.498904 -378.818401) (xy 294.499284 -378.828554) (xy 294.499284 -379.114812)
			(xy 294.499518 -379.121705) (xy 294.503245 -379.134977) (xy 294.50665 -379.140974) (xy 294.523028 -379.169308)
			(xy 294.548769 -379.229479) (xy 294.566191 -379.292564) (xy 294.57498 -379.357418) (xy 294.574974 -379.422864)
			(xy 294.566175 -379.487717) (xy 294.548742 -379.550798) (xy 294.522991 -379.610966) (xy 294.50665 -379.639322)
			(xy 294.503278 -379.645333) (xy 294.499548 -379.658597) (xy 294.499284 -379.665484) (xy 294.499284 -380.414784)
			(xy 294.49949 -380.421679) (xy 294.503236 -380.434951) (xy 294.50665 -380.440946) (xy 294.523005 -380.469293)
			(xy 294.548748 -380.529461) (xy 294.566173 -380.592544) (xy 294.574964 -380.657395) (xy 294.574964 -380.657396)
			(xy 298.004769 -380.657396) (xy 298.01356 -380.592547) (xy 298.030985 -380.529468) (xy 298.056727 -380.469302)
			(xy 298.073064 -380.440946) (xy 298.076359 -380.434912) (xy 298.079978 -380.421656) (xy 298.080176 -380.414784)
			(xy 298.080176 -379.665484) (xy 298.079993 -379.65861) (xy 298.076379 -379.645347) (xy 298.073064 -379.639322)
			(xy 298.056767 -379.610944) (xy 298.031018 -379.550782) (xy 298.013586 -379.487707) (xy 298.004787 -379.422861)
			(xy 298.004782 -379.357421) (xy 298.013569 -379.292574) (xy 298.03099 -379.229495) (xy 298.056729 -379.16933)
			(xy 298.073064 -379.140974) (xy 298.076385 -379.134952) (xy 298.079987 -379.121686) (xy 298.080176 -379.114812)
			(xy 298.080176 -378.828554) (xy 298.080597 -378.818389) (xy 298.088393 -378.799611) (xy 298.102782 -378.785246)
			(xy 298.121572 -378.77748) (xy 298.131738 -378.776992) (xy 298.848018 -378.776992) (xy 298.858171 -378.777517)
			(xy 298.876932 -378.785289) (xy 298.891295 -378.799644) (xy 298.899077 -378.818401) (xy 298.89958 -378.828554)
			(xy 298.89958 -379.114812) (xy 298.89977 -379.121685) (xy 298.90338 -379.134948) (xy 298.906692 -379.140974)
			(xy 298.923069 -379.169308) (xy 298.948808 -379.22948) (xy 298.966228 -379.292565) (xy 298.975016 -379.357418)
			(xy 298.97501 -379.422864) (xy 298.966212 -379.487716) (xy 298.94878 -379.550798) (xy 298.923032 -379.610965)
			(xy 298.906692 -379.639322) (xy 298.903369 -379.645342) (xy 298.899769 -379.658609) (xy 298.89958 -379.665484)
			(xy 298.89958 -380.414784) (xy 298.89978 -380.421657) (xy 298.903383 -380.434919) (xy 298.906692 -380.440946)
			(xy 298.923045 -380.469293) (xy 298.948786 -380.529462) (xy 298.966209 -380.592544) (xy 298.975 -380.657395)
			(xy 298.975 -380.657397) (xy 302.404819 -380.657397) (xy 302.413609 -380.592548) (xy 302.431032 -380.529469)
			(xy 302.456771 -380.469302) (xy 302.473106 -380.440946) (xy 302.476486 -380.434939) (xy 302.480212 -380.421672)
			(xy 302.480472 -380.414784) (xy 302.480472 -379.665484) (xy 302.480232 -379.658592) (xy 302.476508 -379.64532)
			(xy 302.473106 -379.639322) (xy 302.45681 -379.610943) (xy 302.431064 -379.550781) (xy 302.413635 -379.487706)
			(xy 302.404837 -379.422861) (xy 302.404832 -379.357422) (xy 302.413618 -379.292575) (xy 302.431037 -379.229497)
			(xy 302.456773 -379.16933) (xy 302.473106 -379.140974) (xy 302.476476 -379.134962) (xy 302.480208 -379.121699)
			(xy 302.480472 -379.114812) (xy 302.480472 -378.828554) (xy 302.48089 -378.81842) (xy 302.488639 -378.799692)
			(xy 302.502946 -378.785336) (xy 302.521648 -378.777525) (xy 302.53178 -378.776992) (xy 303.24806 -378.776992)
			(xy 303.258211 -378.777454) (xy 303.27696 -378.785235) (xy 303.291285 -378.79962) (xy 303.298987 -378.818402)
			(xy 303.299368 -378.828554) (xy 303.299368 -379.114812) (xy 303.299604 -379.121705) (xy 303.30333 -379.134977)
			(xy 303.306734 -379.140974) (xy 303.323113 -379.169307) (xy 303.348854 -379.229479) (xy 303.366277 -379.292564)
			(xy 303.375066 -379.357418) (xy 303.37506 -379.422864) (xy 303.366261 -379.487717) (xy 303.348827 -379.550799)
			(xy 303.332029 -379.590046) (xy 304.603666 -379.590046) (xy 304.607657 -379.527879) (xy 304.619566 -379.466732)
			(xy 304.639195 -379.407611) (xy 304.666224 -379.351485) (xy 304.700208 -379.299276) (xy 304.74059 -379.251841)
			(xy 304.786706 -379.20996) (xy 304.837798 -379.17432) (xy 304.893029 -379.145506) (xy 304.951491 -379.123992)
			(xy 305.012225 -379.11013) (xy 305.074232 -379.104148) (xy 305.136495 -379.106144) (xy 305.197992 -379.116087)
			(xy 305.257713 -379.133811) (xy 305.314676 -379.159028) (xy 305.367947 -379.191321) (xy 305.416652 -379.230161)
			(xy 305.459989 -379.274911) (xy 305.497249 -379.324835) (xy 305.527818 -379.379114) (xy 305.532285 -379.390148)
			(xy 306.803814 -379.390148) (xy 306.807805 -379.327981) (xy 306.819714 -379.266834) (xy 306.839343 -379.207713)
			(xy 306.866372 -379.151587) (xy 306.900356 -379.099378) (xy 306.940738 -379.051943) (xy 306.986854 -379.010062)
			(xy 307.037946 -378.974422) (xy 307.093177 -378.945608) (xy 307.151639 -378.924094) (xy 307.212373 -378.910232)
			(xy 307.27438 -378.90425) (xy 307.336643 -378.906246) (xy 307.39814 -378.916189) (xy 307.457861 -378.933913)
			(xy 307.514824 -378.95913) (xy 307.568095 -378.991423) (xy 307.6168 -379.030263) (xy 307.660137 -379.075013)
			(xy 307.697397 -379.124937) (xy 307.727966 -379.179216) (xy 307.751344 -379.236959) (xy 307.767145 -379.297217)
			(xy 307.775111 -379.359) (xy 307.77561 -379.390148) (xy 307.775111 -379.421296) (xy 307.767145 -379.483079)
			(xy 307.751344 -379.543337) (xy 307.727966 -379.60108) (xy 307.697397 -379.655359) (xy 307.660137 -379.705283)
			(xy 307.6168 -379.750033) (xy 307.568095 -379.788873) (xy 307.514824 -379.821166) (xy 307.457861 -379.846383)
			(xy 307.39814 -379.864107) (xy 307.336643 -379.87405) (xy 307.27438 -379.876046) (xy 307.212373 -379.870064)
			(xy 307.151639 -379.856202) (xy 307.093177 -379.834688) (xy 307.037946 -379.805874) (xy 306.986854 -379.770234)
			(xy 306.940738 -379.728353) (xy 306.900356 -379.680918) (xy 306.866372 -379.628709) (xy 306.839343 -379.572583)
			(xy 306.819714 -379.513462) (xy 306.807805 -379.452315) (xy 306.803814 -379.390148) (xy 305.532285 -379.390148)
			(xy 305.551196 -379.436857) (xy 305.566997 -379.497115) (xy 305.574963 -379.558898) (xy 305.575462 -379.590046)
			(xy 305.574963 -379.621194) (xy 305.566997 -379.682977) (xy 305.551196 -379.743235) (xy 305.527818 -379.800978)
			(xy 305.497249 -379.855257) (xy 305.459989 -379.905181) (xy 305.416652 -379.949931) (xy 305.367947 -379.988771)
			(xy 305.314676 -380.021064) (xy 305.257713 -380.046281) (xy 305.197992 -380.064005) (xy 305.136495 -380.073948)
			(xy 305.074232 -380.075944) (xy 305.012225 -380.069962) (xy 304.951491 -380.0561) (xy 304.893029 -380.034586)
			(xy 304.837798 -380.005772) (xy 304.786706 -379.970132) (xy 304.74059 -379.928251) (xy 304.700208 -379.880816)
			(xy 304.666224 -379.828607) (xy 304.639195 -379.772481) (xy 304.619566 -379.71336) (xy 304.607657 -379.652213)
			(xy 304.603666 -379.590046) (xy 303.332029 -379.590046) (xy 303.323075 -379.610966) (xy 303.306734 -379.639322)
			(xy 303.303361 -379.645332) (xy 303.299631 -379.658596) (xy 303.299368 -379.665484) (xy 303.299368 -380.414784)
			(xy 303.299576 -380.421679) (xy 303.303321 -380.434951) (xy 303.306734 -380.440946) (xy 303.323089 -380.469293)
			(xy 303.348833 -380.529461) (xy 303.366258 -380.592543) (xy 303.37505 -380.657395) (xy 303.375048 -380.69012)
			(xy 306.803814 -380.69012) (xy 306.807805 -380.627953) (xy 306.819714 -380.566806) (xy 306.839343 -380.507685)
			(xy 306.866372 -380.451559) (xy 306.900356 -380.39935) (xy 306.940738 -380.351915) (xy 306.986854 -380.310034)
			(xy 307.037946 -380.274394) (xy 307.093177 -380.24558) (xy 307.151639 -380.224066) (xy 307.212373 -380.210204)
			(xy 307.27438 -380.204222) (xy 307.336643 -380.206218) (xy 307.39814 -380.216161) (xy 307.457861 -380.233885)
			(xy 307.514824 -380.259102) (xy 307.568095 -380.291395) (xy 307.6168 -380.330235) (xy 307.660137 -380.374985)
			(xy 307.697397 -380.424909) (xy 307.727966 -380.479188) (xy 307.751344 -380.536931) (xy 307.767145 -380.597189)
			(xy 307.775111 -380.658972) (xy 307.77561 -380.69012) (xy 307.775111 -380.721268) (xy 307.767145 -380.783051)
			(xy 307.751344 -380.843309) (xy 307.727966 -380.901052) (xy 307.697397 -380.955331) (xy 307.660137 -381.005255)
			(xy 307.6168 -381.050005) (xy 307.568095 -381.088845) (xy 307.514824 -381.121138) (xy 307.457861 -381.146355)
			(xy 307.39814 -381.164079) (xy 307.336643 -381.174022) (xy 307.27438 -381.176018) (xy 307.212373 -381.170036)
			(xy 307.151639 -381.156174) (xy 307.093177 -381.13466) (xy 307.037946 -381.105846) (xy 306.986854 -381.070206)
			(xy 306.940738 -381.028325) (xy 306.900356 -380.98089) (xy 306.866372 -380.928681) (xy 306.839343 -380.872555)
			(xy 306.819714 -380.813434) (xy 306.807805 -380.752287) (xy 306.803814 -380.69012) (xy 303.375048 -380.69012)
			(xy 303.375047 -380.722839) (xy 303.366252 -380.78769) (xy 303.348822 -380.850771) (xy 303.323074 -380.910938)
			(xy 303.306734 -380.939294) (xy 303.303371 -380.945309) (xy 303.299635 -380.958569) (xy 303.299368 -380.965456)
			(xy 303.299368 -381.251206) (xy 303.298878 -381.261332) (xy 303.29115 -381.280052) (xy 303.276865 -381.294408)
			(xy 303.258184 -381.302228) (xy 303.24806 -381.302768) (xy 302.53178 -381.302768) (xy 302.521621 -381.302394)
			(xy 302.502861 -381.294586) (xy 302.488538 -381.280174) (xy 302.480844 -381.261368) (xy 302.480472 -381.251206)
			(xy 302.480472 -380.965456) (xy 302.480243 -380.958563) (xy 302.476511 -380.945291) (xy 302.473106 -380.939294)
			(xy 302.456787 -380.910928) (xy 302.431043 -380.850763) (xy 302.413616 -380.787685) (xy 302.404821 -380.722838)
			(xy 302.404819 -380.657397) (xy 298.975 -380.657397) (xy 298.974997 -380.722839) (xy 298.966203 -380.787689)
			(xy 298.948775 -380.85077) (xy 298.92303 -380.910937) (xy 298.906692 -380.939294) (xy 298.903379 -380.945319)
			(xy 298.899772 -380.958583) (xy 298.89958 -380.965456) (xy 298.89958 -381.251206) (xy 298.899072 -381.261362)
			(xy 298.891299 -381.280128) (xy 298.876938 -381.294492) (xy 298.858174 -381.302269) (xy 298.848018 -381.302768)
			(xy 298.131738 -381.302768) (xy 298.12157 -381.302305) (xy 298.102777 -381.294534) (xy 298.088391 -381.28016)
			(xy 298.080604 -381.261374) (xy 298.080176 -381.251206) (xy 298.080176 -380.965456) (xy 298.079966 -380.958584)
			(xy 298.07637 -380.945321) (xy 298.073064 -380.939294) (xy 298.056743 -380.910929) (xy 298.030996 -380.850764)
			(xy 298.013567 -380.787686) (xy 298.004771 -380.722838) (xy 298.004769 -380.657396) (xy 294.574964 -380.657396)
			(xy 294.574961 -380.722839) (xy 294.566166 -380.78769) (xy 294.548736 -380.850771) (xy 294.522989 -380.910938)
			(xy 294.50665 -380.939294) (xy 294.503288 -380.94531) (xy 294.499551 -380.95857) (xy 294.499284 -380.965456)
			(xy 294.499284 -381.251206) (xy 294.498779 -381.26133) (xy 294.491054 -381.280047) (xy 294.476773 -381.294402)
			(xy 294.458097 -381.302225) (xy 294.447976 -381.302768) (xy 293.731696 -381.302768) (xy 293.721538 -381.302381)
			(xy 293.702779 -381.294578) (xy 293.688455 -381.28017) (xy 293.680761 -381.261367) (xy 293.680388 -381.251206)
			(xy 293.680388 -380.965456) (xy 293.680135 -380.958566) (xy 293.676406 -380.9453) (xy 293.673022 -380.939294)
			(xy 293.656702 -380.910928) (xy 293.630958 -380.850764) (xy 293.61353 -380.787686) (xy 293.604735 -380.722838)
			(xy 293.604733 -380.657396) (xy 290.174927 -380.657396) (xy 290.174925 -380.72284) (xy 290.166129 -380.787691)
			(xy 290.148698 -380.850772) (xy 290.122948 -380.910938) (xy 290.106608 -380.939294) (xy 290.103296 -380.94532)
			(xy 290.099688 -380.958583) (xy 290.099496 -380.965456) (xy 290.099496 -381.251206) (xy 290.098972 -381.26136)
			(xy 290.091202 -381.280123) (xy 290.076846 -381.294486) (xy 290.058088 -381.302267) (xy 290.047934 -381.302768)
			(xy 289.331654 -381.302768) (xy 289.321494 -381.302304) (xy 289.302725 -381.294516) (xy 289.288362 -381.280141)
			(xy 289.280588 -381.261366) (xy 289.280092 -381.251206) (xy 289.280092 -380.965456) (xy 289.27988 -380.958584)
			(xy 289.276285 -380.945321) (xy 289.27298 -380.939294) (xy 289.256658 -380.910929) (xy 289.230911 -380.850765)
			(xy 289.213481 -380.787686) (xy 289.204685 -380.722838) (xy 289.204683 -380.657396) (xy 272.926083 -380.657396)
			(xy 272.867822 -380.687974) (xy 272.746027 -380.742789) (xy 272.621144 -380.790151) (xy 272.49363 -380.829886)
			(xy 272.363949 -380.861849) (xy 272.232575 -380.885924) (xy 272.099987 -380.902024) (xy 271.966669 -380.910088)
			(xy 271.833107 -380.910088) (xy 271.699789 -380.902024) (xy 271.567201 -380.885924) (xy 271.435827 -380.861849)
			(xy 271.306146 -380.829886) (xy 271.178632 -380.790151) (xy 271.053749 -380.742789) (xy 270.931954 -380.687974)
			(xy 270.813691 -380.625904) (xy 270.699392 -380.556808) (xy 270.589472 -380.480936) (xy 270.484335 -380.398566)
			(xy 270.384362 -380.309998) (xy 270.28992 -380.215556) (xy 270.201352 -380.115583) (xy 270.118982 -380.010446)
			(xy 270.04311 -379.900526) (xy 269.974014 -379.786227) (xy 269.911944 -379.667964) (xy 269.857129 -379.546169)
			(xy 269.809767 -379.421286) (xy 269.770032 -379.293772) (xy 269.738069 -379.164091) (xy 269.713994 -379.032717)
			(xy 269.697894 -378.900129) (xy 269.68983 -378.766811) (xy 262.772673 -378.766811) (xy 262.59917 -378.940314)
			(xy 262.592421 -378.947697) (xy 262.584716 -378.966138) (xy 262.584184 -378.976128) (xy 262.584184 -382.222714)
			(xy 287.004773 -382.222714) (xy 287.004774 -382.157269) (xy 287.013569 -382.092419) (xy 287.030999 -382.029338)
			(xy 287.056746 -381.969172) (xy 287.073086 -381.940816) (xy 287.07644 -381.934796) (xy 287.080183 -381.92154)
			(xy 287.080452 -381.914654) (xy 287.080452 -381.628904) (xy 287.080987 -381.618801) (xy 287.088715 -381.600133)
			(xy 287.102996 -381.585839) (xy 287.121658 -381.578096) (xy 287.13176 -381.577596) (xy 287.84804 -381.577596)
			(xy 287.858151 -381.578052) (xy 287.876829 -381.585802) (xy 287.891122 -381.600108) (xy 287.898856 -381.618793)
			(xy 287.899348 -381.628904) (xy 287.899348 -381.914654) (xy 287.899571 -381.921548) (xy 287.903306 -381.93482)
			(xy 287.906714 -381.940816) (xy 287.923044 -381.969176) (xy 287.948792 -382.029342) (xy 287.966221 -382.092421)
			(xy 287.975015 -382.15727) (xy 287.975017 -382.222713) (xy 291.404823 -382.222713) (xy 291.404824 -382.15727)
			(xy 291.413618 -382.09242) (xy 291.431046 -382.029339) (xy 291.45679 -381.969172) (xy 291.473128 -381.940816)
			(xy 291.476439 -381.93479) (xy 291.480047 -381.921527) (xy 291.48024 -381.914654) (xy 291.48024 -381.628904)
			(xy 291.480626 -381.618745) (xy 291.488427 -381.599985) (xy 291.502836 -381.58566) (xy 291.521641 -381.577968)
			(xy 291.531802 -381.577596) (xy 292.248082 -381.577596) (xy 292.258202 -381.57814) (xy 292.276915 -381.585854)
			(xy 292.29127 -381.600122) (xy 292.299098 -381.618787) (xy 292.299644 -381.628904) (xy 292.299644 -381.914654)
			(xy 292.299848 -381.921526) (xy 292.303447 -381.934789) (xy 292.306756 -381.940816) (xy 292.323085 -381.969177)
			(xy 292.34883 -382.029342) (xy 292.366258 -382.092422) (xy 292.375052 -382.15727) (xy 292.375053 -382.222713)
			(xy 295.804859 -382.222713) (xy 295.80486 -382.157269) (xy 295.813655 -382.092419) (xy 295.831084 -382.029338)
			(xy 295.856831 -381.969172) (xy 295.87317 -381.940816) (xy 295.87653 -381.934799) (xy 295.880268 -381.92154)
			(xy 295.880536 -381.914654) (xy 295.880536 -381.628904) (xy 295.88092 -381.618777) (xy 295.888674 -381.600067)
			(xy 295.903001 -381.585751) (xy 295.921717 -381.578012) (xy 295.931844 -381.577596) (xy 296.648124 -381.577596)
			(xy 296.658234 -381.578065) (xy 296.676912 -381.58581) (xy 296.691206 -381.600112) (xy 296.69894 -381.618794)
			(xy 296.699432 -381.628904) (xy 296.699432 -381.914654) (xy 296.699657 -381.921547) (xy 296.703391 -381.934819)
			(xy 296.706798 -381.940816) (xy 296.723126 -381.969177) (xy 296.748868 -382.029343) (xy 296.766294 -382.092422)
			(xy 296.775088 -382.157271) (xy 296.775089 -382.222712) (xy 296.775089 -382.222713) (xy 300.204649 -382.222713)
			(xy 300.20465 -382.157269) (xy 300.213445 -382.092419) (xy 300.230873 -382.029339) (xy 300.256619 -381.969172)
			(xy 300.272958 -381.940816) (xy 300.276317 -381.934799) (xy 300.280056 -381.92154) (xy 300.280324 -381.914654)
			(xy 300.280324 -381.628904) (xy 300.28072 -381.618779) (xy 300.288471 -381.600071) (xy 300.302794 -381.585755)
			(xy 300.321507 -381.578014) (xy 300.331632 -381.577596) (xy 301.047912 -381.577596) (xy 301.058021 -381.578075)
			(xy 301.076699 -381.585816) (xy 301.090993 -381.600115) (xy 301.098728 -381.618795) (xy 301.09922 -381.628904)
			(xy 301.09922 -381.914654) (xy 301.099468 -381.921544) (xy 301.1032 -381.93481) (xy 301.106586 -381.940816)
			(xy 301.122914 -381.969177) (xy 301.148657 -382.029343) (xy 301.166084 -382.092422) (xy 301.174877 -382.15727)
			(xy 301.174878 -382.18999) (xy 304.603666 -382.18999) (xy 304.607657 -382.127823) (xy 304.619566 -382.066676)
			(xy 304.639195 -382.007555) (xy 304.666224 -381.951429) (xy 304.700208 -381.89922) (xy 304.74059 -381.851785)
			(xy 304.786706 -381.809904) (xy 304.837798 -381.774264) (xy 304.893029 -381.74545) (xy 304.951491 -381.723936)
			(xy 305.012225 -381.710074) (xy 305.074232 -381.704092) (xy 305.136495 -381.706088) (xy 305.197992 -381.716031)
			(xy 305.257713 -381.733755) (xy 305.314676 -381.758972) (xy 305.367947 -381.791265) (xy 305.416652 -381.830105)
			(xy 305.459989 -381.874855) (xy 305.497249 -381.924779) (xy 305.527818 -381.979058) (xy 305.551196 -382.036801)
			(xy 305.566997 -382.097059) (xy 305.574963 -382.158842) (xy 305.575462 -382.18999) (xy 305.574963 -382.221138)
			(xy 305.566997 -382.282921) (xy 305.551196 -382.343179) (xy 305.527818 -382.400922) (xy 305.497249 -382.455201)
			(xy 305.459989 -382.505125) (xy 305.416652 -382.549875) (xy 305.367947 -382.588715) (xy 305.314676 -382.621008)
			(xy 305.257713 -382.646225) (xy 305.197992 -382.663949) (xy 305.136495 -382.673892) (xy 305.074232 -382.675888)
			(xy 305.012225 -382.669906) (xy 304.951491 -382.656044) (xy 304.893029 -382.63453) (xy 304.837798 -382.605716)
			(xy 304.786706 -382.570076) (xy 304.74059 -382.528195) (xy 304.700208 -382.48076) (xy 304.666224 -382.428551)
			(xy 304.639195 -382.372425) (xy 304.619566 -382.313304) (xy 304.607657 -382.252157) (xy 304.603666 -382.18999)
			(xy 301.174878 -382.18999) (xy 301.174879 -382.222712) (xy 301.166087 -382.287561) (xy 301.148663 -382.350641)
			(xy 301.122922 -382.410808) (xy 301.106586 -382.439164) (xy 301.103237 -382.445187) (xy 301.099492 -382.458441)
			(xy 301.09922 -382.465326) (xy 301.09922 -383.21488) (xy 301.099458 -383.221771) (xy 301.103197 -383.235037)
			(xy 301.106586 -383.241042) (xy 301.122936 -383.269391) (xy 301.145782 -383.322792) (xy 302.404789 -383.322792)
			(xy 302.404794 -383.257347) (xy 302.41359 -383.192496) (xy 302.43102 -383.129414) (xy 302.456767 -383.069247)
			(xy 302.473106 -383.04089) (xy 302.47647 -383.034875) (xy 302.480206 -383.021615) (xy 302.480472 -383.014728)
			(xy 302.480472 -382.728724) (xy 302.480935 -382.718606) (xy 302.48867 -382.699909) (xy 302.502972 -382.685595)
			(xy 302.521663 -382.677843) (xy 302.53178 -382.677416) (xy 303.24806 -382.677416) (xy 303.258182 -382.677849)
			(xy 303.276888 -382.685587) (xy 303.291204 -382.699899) (xy 303.298948 -382.718602) (xy 303.299368 -382.728724)
			(xy 303.299368 -383.014728) (xy 303.299598 -383.021621) (xy 303.303329 -383.034893) (xy 303.306734 -383.04089)
			(xy 303.323042 -383.069263) (xy 303.34879 -383.129425) (xy 303.366221 -383.192502) (xy 303.375018 -383.257349)
			(xy 303.375022 -383.32279) (xy 303.366233 -383.387637) (xy 303.34881 -383.450716) (xy 303.331911 -383.490216)
			(xy 304.603666 -383.490216) (xy 304.607657 -383.428049) (xy 304.619566 -383.366902) (xy 304.639195 -383.307781)
			(xy 304.666224 -383.251655) (xy 304.700208 -383.199446) (xy 304.74059 -383.152011) (xy 304.786706 -383.11013)
			(xy 304.837798 -383.07449) (xy 304.893029 -383.045676) (xy 304.951491 -383.024162) (xy 305.012225 -383.0103)
			(xy 305.074232 -383.004318) (xy 305.136495 -383.006314) (xy 305.197992 -383.016257) (xy 305.257713 -383.033981)
			(xy 305.314676 -383.059198) (xy 305.367947 -383.091491) (xy 305.416652 -383.130331) (xy 305.459989 -383.175081)
			(xy 305.497249 -383.225005) (xy 305.527818 -383.279284) (xy 305.532182 -383.290064) (xy 306.803814 -383.290064)
			(xy 306.807805 -383.227897) (xy 306.819714 -383.16675) (xy 306.839343 -383.107629) (xy 306.866372 -383.051503)
			(xy 306.900356 -382.999294) (xy 306.940738 -382.951859) (xy 306.986854 -382.909978) (xy 307.037946 -382.874338)
			(xy 307.093177 -382.845524) (xy 307.151639 -382.82401) (xy 307.212373 -382.810148) (xy 307.27438 -382.804166)
			(xy 307.336643 -382.806162) (xy 307.39814 -382.816105) (xy 307.457861 -382.833829) (xy 307.514824 -382.859046)
			(xy 307.568095 -382.891339) (xy 307.6168 -382.930179) (xy 307.660137 -382.974929) (xy 307.697397 -383.024853)
			(xy 307.727966 -383.079132) (xy 307.751344 -383.136875) (xy 307.767145 -383.197133) (xy 307.775111 -383.258916)
			(xy 307.77561 -383.290064) (xy 307.775111 -383.321212) (xy 307.767145 -383.382995) (xy 307.751344 -383.443253)
			(xy 307.727966 -383.500996) (xy 307.697397 -383.555275) (xy 307.660137 -383.605199) (xy 307.6168 -383.649949)
			(xy 307.568095 -383.688789) (xy 307.514824 -383.721082) (xy 307.457861 -383.746299) (xy 307.39814 -383.764023)
			(xy 307.336643 -383.773966) (xy 307.27438 -383.775962) (xy 307.212373 -383.76998) (xy 307.151639 -383.756118)
			(xy 307.093177 -383.734604) (xy 307.037946 -383.70579) (xy 306.986854 -383.67015) (xy 306.940738 -383.628269)
			(xy 306.900356 -383.580834) (xy 306.866372 -383.528625) (xy 306.839343 -383.472499) (xy 306.819714 -383.413378)
			(xy 306.807805 -383.352231) (xy 306.803814 -383.290064) (xy 305.532182 -383.290064) (xy 305.551196 -383.337027)
			(xy 305.566997 -383.397285) (xy 305.574963 -383.459068) (xy 305.575462 -383.490216) (xy 305.574963 -383.521364)
			(xy 305.566997 -383.583147) (xy 305.551196 -383.643405) (xy 305.527818 -383.701148) (xy 305.497249 -383.755427)
			(xy 305.459989 -383.805351) (xy 305.416652 -383.850101) (xy 305.367947 -383.888941) (xy 305.314676 -383.921234)
			(xy 305.257713 -383.946451) (xy 305.197992 -383.964175) (xy 305.136495 -383.974118) (xy 305.074232 -383.976114)
			(xy 305.012225 -383.970132) (xy 304.951491 -383.95627) (xy 304.893029 -383.934756) (xy 304.837798 -383.905942)
			(xy 304.786706 -383.870302) (xy 304.74059 -383.828421) (xy 304.700208 -383.780986) (xy 304.666224 -383.728777)
			(xy 304.639195 -383.672651) (xy 304.619566 -383.61353) (xy 304.607657 -383.552383) (xy 304.603666 -383.490216)
			(xy 303.331911 -383.490216) (xy 303.32307 -383.510882) (xy 303.306734 -383.539238) (xy 303.303355 -383.545246)
			(xy 303.299629 -383.558512) (xy 303.299368 -383.5654) (xy 303.299368 -384.3147) (xy 303.29957 -384.321595)
			(xy 303.303319 -384.334867) (xy 303.306734 -384.340862) (xy 303.323103 -384.369201) (xy 303.348845 -384.429371)
			(xy 303.366269 -384.492455) (xy 303.375059 -384.557308) (xy 303.375057 -384.590036) (xy 306.803814 -384.590036)
			(xy 306.807805 -384.527869) (xy 306.819714 -384.466722) (xy 306.839343 -384.407601) (xy 306.866372 -384.351475)
			(xy 306.900356 -384.299266) (xy 306.940738 -384.251831) (xy 306.986854 -384.20995) (xy 307.037946 -384.17431)
			(xy 307.093177 -384.145496) (xy 307.151639 -384.123982) (xy 307.212373 -384.11012) (xy 307.27438 -384.104138)
			(xy 307.336643 -384.106134) (xy 307.39814 -384.116077) (xy 307.457861 -384.133801) (xy 307.514824 -384.159018)
			(xy 307.568095 -384.191311) (xy 307.6168 -384.230151) (xy 307.660137 -384.274901) (xy 307.697397 -384.324825)
			(xy 307.727966 -384.379104) (xy 307.751344 -384.436847) (xy 307.767145 -384.497105) (xy 307.775111 -384.558888)
			(xy 307.77561 -384.590036) (xy 307.775111 -384.621184) (xy 307.767145 -384.682967) (xy 307.751344 -384.743225)
			(xy 307.727966 -384.800968) (xy 307.697397 -384.855247) (xy 307.660137 -384.905171) (xy 307.6168 -384.949921)
			(xy 307.568095 -384.988761) (xy 307.514824 -385.021054) (xy 307.457861 -385.046271) (xy 307.39814 -385.063995)
			(xy 307.336643 -385.073938) (xy 307.27438 -385.075934) (xy 307.212373 -385.069952) (xy 307.151639 -385.05609)
			(xy 307.093177 -385.034576) (xy 307.037946 -385.005762) (xy 306.986854 -384.970122) (xy 306.940738 -384.928241)
			(xy 306.900356 -384.880806) (xy 306.866372 -384.828597) (xy 306.839343 -384.772471) (xy 306.819714 -384.71335)
			(xy 306.807805 -384.652203) (xy 306.803814 -384.590036) (xy 303.375057 -384.590036) (xy 303.375055 -384.622754)
			(xy 303.366257 -384.687605) (xy 303.348825 -384.750687) (xy 303.323075 -384.810854) (xy 303.306734 -384.83921)
			(xy 303.303365 -384.845223) (xy 303.299633 -384.858485) (xy 303.299368 -384.865372) (xy 303.299368 -385.151376)
			(xy 303.298964 -385.161501) (xy 303.291218 -385.18021) (xy 303.276897 -385.194527) (xy 303.258185 -385.202267)
			(xy 303.24806 -385.202684) (xy 302.53178 -385.202684) (xy 302.521654 -385.2023) (xy 302.502947 -385.194542)
			(xy 302.488633 -385.180216) (xy 302.480891 -385.161502) (xy 302.480472 -385.151376) (xy 302.480472 -384.865372)
			(xy 302.480237 -384.858479) (xy 302.47651 -384.845208) (xy 302.473106 -384.83921) (xy 302.4568 -384.810837)
			(xy 302.431055 -384.750674) (xy 302.413627 -384.687597) (xy 302.40483 -384.622751) (xy 302.404826 -384.557311)
			(xy 302.413614 -384.492464) (xy 302.431035 -384.429385) (xy 302.456772 -384.369218) (xy 302.473106 -384.340862)
			(xy 302.47648 -384.334852) (xy 302.48021 -384.321588) (xy 302.480472 -384.3147) (xy 302.480472 -383.5654)
			(xy 302.480242 -383.558508) (xy 302.476498 -383.545242) (xy 302.473106 -383.539238) (xy 302.456739 -383.510898)
			(xy 302.431 -383.450727) (xy 302.413578 -383.387644) (xy 302.404789 -383.322792) (xy 301.145782 -383.322792)
			(xy 301.148677 -383.32956) (xy 301.166101 -383.392641) (xy 301.174892 -383.457492) (xy 301.17489 -383.522936)
			(xy 301.166096 -383.587786) (xy 301.148668 -383.650866) (xy 301.122924 -383.711034) (xy 301.106586 -383.73939)
			(xy 301.103228 -383.745408) (xy 301.099488 -383.758666) (xy 301.09922 -383.765552) (xy 301.09922 -384.051556)
			(xy 301.098748 -384.061673) (xy 301.091018 -384.080372) (xy 301.076719 -384.094687) (xy 301.058029 -384.102437)
			(xy 301.047912 -384.102864) (xy 300.331632 -384.102864) (xy 300.321507 -384.102457) (xy 300.302797 -384.094713)
			(xy 300.28848 -384.080393) (xy 300.28074 -384.061681) (xy 300.280324 -384.051556) (xy 300.280324 -383.765552)
			(xy 300.280102 -383.758658) (xy 300.276366 -383.745386) (xy 300.272958 -383.73939) (xy 300.256634 -383.711027)
			(xy 300.230887 -383.650862) (xy 300.213459 -383.587783) (xy 300.204664 -383.522935) (xy 300.204662 -383.457493)
			(xy 300.213453 -383.392644) (xy 300.230878 -383.329564) (xy 300.256621 -383.269398) (xy 300.272958 -383.241042)
			(xy 300.276343 -383.235037) (xy 300.280065 -383.221769) (xy 300.280324 -383.21488) (xy 300.280324 -382.465326)
			(xy 300.280113 -382.458431) (xy 300.27637 -382.445159) (xy 300.272958 -382.439164) (xy 300.256612 -382.410813)
			(xy 300.230867 -382.350645) (xy 300.213441 -382.287564) (xy 300.204649 -382.222713) (xy 296.775089 -382.222713)
			(xy 296.766298 -382.287561) (xy 296.748874 -382.350641) (xy 296.723134 -382.410807) (xy 296.706798 -382.439164)
			(xy 296.70345 -382.445187) (xy 296.699704 -382.458441) (xy 296.699432 -382.465326) (xy 296.699432 -383.21488)
			(xy 296.699669 -383.221771) (xy 296.703408 -383.235037) (xy 296.706798 -383.241042) (xy 296.723148 -383.269391)
			(xy 296.745993 -383.322792) (xy 298.004739 -383.322792) (xy 298.004744 -383.257346) (xy 298.013541 -383.192495)
			(xy 298.030973 -383.129413) (xy 298.056723 -383.069246) (xy 298.073064 -383.04089) (xy 298.076379 -383.034866)
			(xy 298.079985 -383.021602) (xy 298.080176 -383.014728) (xy 298.080176 -382.728724) (xy 298.080641 -382.718574)
			(xy 298.088424 -382.699827) (xy 298.102807 -382.685504) (xy 298.121587 -382.677799) (xy 298.131738 -382.677416)
			(xy 298.848018 -382.677416) (xy 298.858143 -382.677911) (xy 298.87686 -382.68564) (xy 298.891215 -382.699923)
			(xy 298.899038 -382.718602) (xy 298.89958 -382.728724) (xy 298.89958 -383.014728) (xy 298.899764 -383.021602)
			(xy 298.903378 -383.034864) (xy 298.906692 -383.04089) (xy 298.922998 -383.069263) (xy 298.948743 -383.129426)
			(xy 298.966172 -383.192503) (xy 298.974968 -383.257349) (xy 298.974972 -383.322789) (xy 298.966184 -383.387637)
			(xy 298.948763 -383.450715) (xy 298.923026 -383.510882) (xy 298.906692 -383.539238) (xy 298.903363 -383.545256)
			(xy 298.899767 -383.558525) (xy 298.89958 -383.5654) (xy 298.89958 -384.3147) (xy 298.899774 -384.321573)
			(xy 298.903381 -384.334836) (xy 298.906692 -384.340862) (xy 298.923059 -384.369202) (xy 298.948798 -384.429373)
			(xy 298.96622 -384.492456) (xy 298.975009 -384.557308) (xy 298.975005 -384.622753) (xy 298.966208 -384.687605)
			(xy 298.948778 -384.750686) (xy 298.923031 -384.810853) (xy 298.906692 -384.83921) (xy 298.903373 -384.845233)
			(xy 298.89977 -384.858498) (xy 298.89958 -384.865372) (xy 298.89958 -385.151376) (xy 298.899159 -385.161531)
			(xy 298.891367 -385.180287) (xy 298.87697 -385.194612) (xy 298.858175 -385.202309) (xy 298.848018 -385.202684)
			(xy 298.131738 -385.202684) (xy 298.121617 -385.202143) (xy 298.102901 -385.194432) (xy 298.088544 -385.180162)
			(xy 298.08072 -385.161494) (xy 298.080176 -385.151376) (xy 298.080176 -384.865372) (xy 298.079998 -384.858498)
			(xy 298.076381 -384.845235) (xy 298.073064 -384.83921) (xy 298.056756 -384.810837) (xy 298.031008 -384.750675)
			(xy 298.013578 -384.687598) (xy 298.00478 -384.622751) (xy 298.004776 -384.55731) (xy 298.013565 -384.492463)
			(xy 298.030988 -384.429384) (xy 298.056728 -384.369218) (xy 298.073064 -384.340862) (xy 298.076389 -384.334842)
			(xy 298.079989 -384.321575) (xy 298.080176 -384.3147) (xy 298.080176 -383.5654) (xy 298.079987 -383.558527)
			(xy 298.076377 -383.545264) (xy 298.073064 -383.539238) (xy 298.056695 -383.510899) (xy 298.030953 -383.450729)
			(xy 298.013529 -383.387645) (xy 298.004739 -383.322792) (xy 296.745993 -383.322792) (xy 296.748888 -383.32956)
			(xy 296.766312 -383.392641) (xy 296.775103 -383.457492) (xy 296.775101 -383.522936) (xy 296.766307 -383.587786)
			(xy 296.748879 -383.650866) (xy 296.723135 -383.711033) (xy 296.706798 -383.73939) (xy 296.703441 -383.745409)
			(xy 296.6997 -383.758666) (xy 296.699432 -383.765552) (xy 296.699432 -384.051556) (xy 296.698949 -384.061672)
			(xy 296.691221 -384.080368) (xy 296.676925 -384.094683) (xy 296.658239 -384.102435) (xy 296.648124 -384.102864)
			(xy 295.931844 -384.102864) (xy 295.92172 -384.102447) (xy 295.90301 -384.094707) (xy 295.888693 -384.08039)
			(xy 295.880953 -384.06168) (xy 295.880536 -384.051556) (xy 295.880536 -383.765552) (xy 295.880313 -383.758658)
			(xy 295.876578 -383.745386) (xy 295.87317 -383.73939) (xy 295.856845 -383.711027) (xy 295.831098 -383.650862)
			(xy 295.813669 -383.587783) (xy 295.804874 -383.522935) (xy 295.804872 -383.457493) (xy 295.813664 -383.392644)
			(xy 295.831089 -383.329564) (xy 295.856833 -383.269398) (xy 295.87317 -383.241042) (xy 295.876556 -383.235038)
			(xy 295.880278 -383.221769) (xy 295.880536 -383.21488) (xy 295.880536 -382.465326) (xy 295.880323 -382.458432)
			(xy 295.876581 -382.44516) (xy 295.87317 -382.439164) (xy 295.856823 -382.410813) (xy 295.831078 -382.350645)
			(xy 295.813652 -382.287564) (xy 295.804859 -382.222713) (xy 292.375053 -382.222713) (xy 292.366261 -382.287562)
			(xy 292.348836 -382.350641) (xy 292.323093 -382.410808) (xy 292.306756 -382.439164) (xy 292.303458 -382.445197)
			(xy 292.299841 -382.458454) (xy 292.299644 -382.465326) (xy 292.299644 -383.21488) (xy 292.299838 -383.221753)
			(xy 292.303444 -383.235016) (xy 292.306756 -383.241042) (xy 292.323107 -383.269391) (xy 292.345955 -383.322792)
			(xy 293.604703 -383.322792) (xy 293.604707 -383.257347) (xy 293.613504 -383.192495) (xy 293.630935 -383.129414)
			(xy 293.656683 -383.069246) (xy 293.673022 -383.04089) (xy 293.676387 -383.034876) (xy 293.680122 -383.021615)
			(xy 293.680388 -383.014728) (xy 293.680388 -382.728724) (xy 293.680835 -382.718605) (xy 293.688573 -382.699904)
			(xy 293.70288 -382.685589) (xy 293.721577 -382.677841) (xy 293.731696 -382.677416) (xy 294.447976 -382.677416)
			(xy 294.458099 -382.677836) (xy 294.476805 -382.685579) (xy 294.491121 -382.699895) (xy 294.498864 -382.718601)
			(xy 294.499284 -382.728724) (xy 294.499284 -383.014728) (xy 294.499512 -383.021621) (xy 294.503244 -383.034893)
			(xy 294.50665 -383.04089) (xy 294.522957 -383.069263) (xy 294.548705 -383.129426) (xy 294.566135 -383.192502)
			(xy 294.574932 -383.257349) (xy 294.574936 -383.322789) (xy 294.566147 -383.387637) (xy 294.548725 -383.450716)
			(xy 294.522985 -383.510882) (xy 294.50665 -383.539238) (xy 294.503273 -383.545246) (xy 294.499546 -383.558512)
			(xy 294.499284 -383.5654) (xy 294.499284 -384.3147) (xy 294.499484 -384.321596) (xy 294.503234 -384.334868)
			(xy 294.50665 -384.340862) (xy 294.523018 -384.369201) (xy 294.54876 -384.429372) (xy 294.566183 -384.492455)
			(xy 294.574973 -384.557308) (xy 294.574969 -384.622754) (xy 294.566171 -384.687605) (xy 294.548739 -384.750687)
			(xy 294.52299 -384.810854) (xy 294.50665 -384.83921) (xy 294.503283 -384.845223) (xy 294.499549 -384.858485)
			(xy 294.499284 -384.865372) (xy 294.499284 -385.151376) (xy 294.498864 -385.161499) (xy 294.491121 -385.180205)
			(xy 294.476805 -385.194521) (xy 294.458099 -385.202264) (xy 294.447976 -385.202684) (xy 293.731696 -385.202684)
			(xy 293.721571 -385.202287) (xy 293.702865 -385.194534) (xy 293.68855 -385.180212) (xy 293.680808 -385.161501)
			(xy 293.680388 -385.151376) (xy 293.680388 -384.865372) (xy 293.680129 -384.858483) (xy 293.676404 -384.845217)
			(xy 293.673022 -384.83921) (xy 293.656716 -384.810837) (xy 293.63097 -384.750674) (xy 293.613541 -384.687597)
			(xy 293.604744 -384.622751) (xy 293.60474 -384.557311) (xy 293.613528 -384.492463) (xy 293.630949 -384.429385)
			(xy 293.656688 -384.369218) (xy 293.673022 -384.340862) (xy 293.676397 -384.334852) (xy 293.680126 -384.321588)
			(xy 293.680388 -384.3147) (xy 293.680388 -383.5654) (xy 293.680156 -383.558508) (xy 293.676413 -383.545243)
			(xy 293.673022 -383.539238) (xy 293.656655 -383.510898) (xy 293.630914 -383.450728) (xy 293.613492 -383.387644)
			(xy 293.604703 -383.322792) (xy 292.345955 -383.322792) (xy 292.34885 -383.329559) (xy 292.366275 -383.392641)
			(xy 292.375066 -383.457492) (xy 292.375065 -383.522936) (xy 292.36627 -383.587786) (xy 292.348841 -383.650867)
			(xy 292.323095 -383.711034) (xy 292.306756 -383.73939) (xy 292.303449 -383.745419) (xy 292.299838 -383.758679)
			(xy 292.299644 -383.765552) (xy 292.299644 -384.051556) (xy 292.299143 -384.061702) (xy 292.29137 -384.080445)
			(xy 292.276998 -384.094768) (xy 292.258229 -384.102477) (xy 292.248082 -384.102864) (xy 291.531802 -384.102864)
			(xy 291.521676 -384.102372) (xy 291.502956 -384.094645) (xy 291.488599 -384.080361) (xy 291.480779 -384.06168)
			(xy 291.48024 -384.051556) (xy 291.48024 -383.765552) (xy 291.480023 -383.758681) (xy 291.476431 -383.745418)
			(xy 291.473128 -383.73939) (xy 291.456805 -383.711026) (xy 291.43106 -383.650861) (xy 291.413632 -383.587783)
			(xy 291.404838 -383.522935) (xy 291.404836 -383.457493) (xy 291.413627 -383.392644) (xy 291.431051 -383.329565)
			(xy 291.456792 -383.269398) (xy 291.473128 -383.241042) (xy 291.47643 -383.235011) (xy 291.480043 -383.221752)
			(xy 291.48024 -383.21488) (xy 291.48024 -382.465326) (xy 291.480033 -382.458454) (xy 291.476435 -382.445191)
			(xy 291.473128 -382.439164) (xy 291.456782 -382.410812) (xy 291.43104 -382.350645) (xy 291.413615 -382.287563)
			(xy 291.404823 -382.222713) (xy 287.975017 -382.222713) (xy 287.966224 -382.287562) (xy 287.948797 -382.350642)
			(xy 287.923052 -382.410808) (xy 287.906714 -382.439164) (xy 287.903367 -382.445188) (xy 287.89962 -382.458441)
			(xy 287.899348 -382.465326) (xy 287.899348 -383.21488) (xy 287.899561 -383.221774) (xy 287.903303 -383.235046)
			(xy 287.906714 -383.241042) (xy 287.923066 -383.26939) (xy 287.945917 -383.322792) (xy 289.204653 -383.322792)
			(xy 289.204657 -383.257346) (xy 289.213455 -383.192494) (xy 289.230888 -383.129413) (xy 289.256639 -383.069246)
			(xy 289.27298 -383.04089) (xy 289.276297 -383.034866) (xy 289.279902 -383.021602) (xy 289.280092 -383.014728)
			(xy 289.280092 -382.728724) (xy 289.280541 -382.718572) (xy 289.288327 -382.699822) (xy 289.302715 -382.685498)
			(xy 289.321501 -382.677796) (xy 289.331654 -382.677416) (xy 290.047934 -382.677416) (xy 290.05806 -382.677898)
			(xy 290.076777 -382.685632) (xy 290.091132 -382.69992) (xy 290.098954 -382.7186) (xy 290.099496 -382.728724)
			(xy 290.099496 -383.014728) (xy 290.099678 -383.021602) (xy 290.103293 -383.034865) (xy 290.106608 -383.04089)
			(xy 290.122917 -383.069262) (xy 290.148666 -383.129425) (xy 290.166098 -383.192502) (xy 290.174896 -383.257349)
			(xy 290.1749 -383.32279) (xy 290.16611 -383.387638) (xy 290.148686 -383.450717) (xy 290.122945 -383.510882)
			(xy 290.106608 -383.539238) (xy 290.10328 -383.545256) (xy 290.099683 -383.558525) (xy 290.099496 -383.5654)
			(xy 290.099496 -384.3147) (xy 290.099688 -384.321573) (xy 290.103296 -384.334836) (xy 290.106608 -384.340862)
			(xy 290.122978 -384.369201) (xy 290.148721 -384.429371) (xy 290.166146 -384.492455) (xy 290.174937 -384.557308)
			(xy 290.174932 -384.622754) (xy 290.166134 -384.687606) (xy 290.148701 -384.750687) (xy 290.122949 -384.810854)
			(xy 290.106608 -384.83921) (xy 290.10329 -384.845233) (xy 290.099686 -384.858498) (xy 290.099496 -384.865372)
			(xy 290.099496 -385.151376) (xy 290.099059 -385.161529) (xy 290.09127 -385.180282) (xy 290.076878 -385.194606)
			(xy 290.058089 -385.202306) (xy 290.047934 -385.202684) (xy 289.331654 -385.202684) (xy 289.321527 -385.202212)
			(xy 289.30281 -385.194473) (xy 289.288456 -385.180183) (xy 289.280634 -385.1615) (xy 289.280092 -385.151376)
			(xy 289.280092 -384.865372) (xy 289.279912 -384.858498) (xy 289.276296 -384.845235) (xy 289.27298 -384.83921)
			(xy 289.256672 -384.810837) (xy 289.230923 -384.750675) (xy 289.213492 -384.687598) (xy 289.204694 -384.622751)
			(xy 289.20469 -384.55731) (xy 289.213479 -384.492462) (xy 289.230903 -384.429383) (xy 289.256644 -384.369218)
			(xy 289.27298 -384.340862) (xy 289.276307 -384.334843) (xy 289.279905 -384.321575) (xy 289.280092 -384.3147)
			(xy 289.280092 -383.5654) (xy 289.279901 -383.558527) (xy 289.276292 -383.545264) (xy 289.27298 -383.539238)
			(xy 289.256611 -383.510899) (xy 289.230868 -383.450729) (xy 289.213443 -383.387645) (xy 289.204653 -383.322792)
			(xy 287.945917 -383.322792) (xy 287.948812 -383.329558) (xy 287.966238 -383.39264) (xy 287.97503 -383.457491)
			(xy 287.975028 -383.522936) (xy 287.966233 -383.587787) (xy 287.948802 -383.650868) (xy 287.923054 -383.711034)
			(xy 287.906714 -383.73939) (xy 287.903358 -383.745409) (xy 287.899616 -383.758666) (xy 287.899348 -383.765552)
			(xy 287.899348 -384.051556) (xy 287.898849 -384.06167) (xy 287.891124 -384.080363) (xy 287.876834 -384.094677)
			(xy 287.858153 -384.102432) (xy 287.84804 -384.102864) (xy 287.13176 -384.102864) (xy 287.12163 -384.102516)
			(xy 287.102919 -384.094748) (xy 287.088605 -384.08041) (xy 287.080868 -384.061686) (xy 287.080452 -384.051556)
			(xy 287.080452 -383.765552) (xy 287.080227 -383.758659) (xy 287.076493 -383.745387) (xy 287.073086 -383.73939)
			(xy 287.056761 -383.711027) (xy 287.031013 -383.650862) (xy 287.013583 -383.587784) (xy 287.004788 -383.522935)
			(xy 287.004786 -383.457492) (xy 287.013578 -383.392643) (xy 287.031004 -383.329564) (xy 287.056748 -383.269398)
			(xy 287.073086 -383.241042) (xy 287.076466 -383.235035) (xy 287.080192 -383.221768) (xy 287.080452 -383.21488)
			(xy 287.080452 -382.465326) (xy 287.080237 -382.458432) (xy 287.076496 -382.44516) (xy 287.073086 -382.439164)
			(xy 287.056739 -382.410813) (xy 287.030993 -382.350646) (xy 287.013566 -382.287564) (xy 287.004773 -382.222714)
			(xy 262.584184 -382.222714) (xy 262.584184 -388.02818) (xy 262.583835 -388.038228) (xy 262.576232 -388.056824)
			(xy 262.569452 -388.064248) (xy 259.339588 -391.294112) (xy 259.332098 -391.300795) (xy 259.313546 -391.308392)
			(xy 259.30352 -391.308844) (xy 245.276624 -391.308844) (xy 245.266555 -391.309271) (xy 245.247956 -391.316989)
			(xy 245.240556 -391.32383) (xy 244.419628 -392.144758) (xy 244.412917 -392.152225) (xy 244.405338 -392.170795)
			(xy 244.404896 -392.180826) (xy 244.404896 -392.657838) (xy 244.401086 -392.661394) (xy 244.394254 -392.668801)
			(xy 244.38653 -392.687395) (xy 244.3861 -392.697462) (xy 244.3861 -392.739372) (xy 244.403118 -392.764772)
			(xy 244.417596 -392.770614) (xy 244.427038 -392.773934) (xy 244.447028 -392.77396) (xy 244.465523 -392.766377)
			(xy 244.472968 -392.759692) (xy 245.043198 -392.189462) (xy 245.050585 -392.182718) (xy 245.069023 -392.175011)
			(xy 245.079012 -392.174476) (xy 252.520704 -392.174476) (xy 252.530708 -392.174945) (xy 252.549171 -392.182658)
			(xy 252.556518 -392.189462) (xy 253.186946 -392.81989) (xy 253.193687 -392.827279) (xy 253.201396 -392.845715)
			(xy 253.201932 -392.855704) (xy 253.201932 -397.552164) (xy 253.201492 -397.562171) (xy 253.193759 -397.580634)
			(xy 253.186946 -397.587978) (xy 252.572266 -398.202658) (xy 252.564881 -398.209406) (xy 252.546442 -398.217114)
			(xy 252.536452 -398.217644) (xy 244.994938 -398.217644) (xy 244.984931 -398.2172) (xy 244.966468 -398.20947)
			(xy 244.959124 -398.202658) (xy 244.461792 -397.70558) (xy 244.432074 -397.699484) (xy 244.417596 -397.70558)
			(xy 244.408551 -397.709846) (xy 244.394372 -397.723914) (xy 244.38664 -397.742332) (xy 244.3861 -397.752316)
			(xy 244.3861 -399.931128) (xy 244.385746 -399.941176) (xy 244.378149 -399.959773) (xy 244.371368 -399.967196)
			(xy 243.163598 -401.174966) (xy 243.156189 -401.181795) (xy 243.137597 -401.189522) (xy 243.12753 -401.189952)
			(xy 239.132872 -401.189952) (xy 239.122826 -401.190319) (xy 239.10423 -401.197909) (xy 239.096804 -401.204684)
			(xy 237.350554 -402.950934) (xy 237.3437 -402.958323) (xy 237.33599 -402.976931) (xy 237.335568 -402.987002)
			(xy 237.335568 -412.15183) (xy 237.335197 -412.161875) (xy 237.32761 -412.180472) (xy 237.320836 -412.187898)
			(xy 235.883196 -413.625538) (xy 235.875796 -413.632378) (xy 235.857196 -413.640096) (xy 235.847128 -413.640524)
			(xy 208.71815 -413.640524) (xy 208.708081 -413.640092) (xy 208.689482 -413.632378) (xy 208.682082 -413.625538)
			(xy 207.013302 -411.956758) (xy 207.006451 -411.949366) (xy 206.998738 -411.930761) (xy 206.998316 -411.92069)
			(xy 206.998316 -389.900414) (xy 206.997988 -389.890364) (xy 206.990372 -389.871767) (xy 206.983584 -389.864346)
			(xy 204.426566 -387.307582) (xy 204.419721 -387.300186) (xy 204.412005 -387.281584) (xy 204.41158 -387.271514)
			(xy 204.41158 -378.673614) (xy 204.388974 -378.645928) (xy 204.371194 -378.642118) (xy 204.344485 -378.635964)
			(xy 204.293002 -378.617167) (xy 204.24474 -378.591196) (xy 204.200691 -378.558585) (xy 204.161763 -378.520006)
			(xy 204.128757 -378.476252) (xy 204.102353 -378.428225) (xy 204.083095 -378.376913) (xy 204.071378 -378.323373)
			(xy 204.067445 -378.268708) (xy 204.071376 -378.214042) (xy 204.08309 -378.160502) (xy 204.102346 -378.10919)
			(xy 204.128748 -378.061161) (xy 204.161752 -378.017406) (xy 204.200679 -377.978825) (xy 204.244726 -377.946212)
			(xy 204.292988 -377.920239) (xy 204.34447 -377.901441) (xy 204.371194 -377.895358) (xy 204.388974 -377.891548)
			(xy 204.41158 -377.863862) (xy 204.41158 -375.798334) (xy 204.394816 -375.772934) (xy 204.380338 -375.767092)
			(xy 204.370913 -375.763714) (xy 204.35091 -375.763709) (xy 204.33241 -375.771317) (xy 204.324966 -375.778014)
			(xy 204.101446 -376.001788) (xy 204.087009 -376.015584) (xy 204.055157 -376.039669) (xy 204.037946 -376.049794)
			(xy 204.01487 -376.062285) (xy 203.965492 -376.080027) (xy 203.913811 -376.089081) (xy 203.887578 -376.089672)
			(xy 202.043538 -376.089672) (xy 202.022359 -376.088674) (xy 201.980559 -376.081573) (xy 201.940142 -376.068763)
			(xy 201.920856 -376.059954) (xy 201.900152 -376.049536) (xy 201.861886 -376.023386) (xy 201.844656 -376.007884)
			(xy 197.560692 -371.724428) (xy 197.553834 -371.720872) (xy 197.549516 -371.718586) (xy 197.549008 -371.718332)
			(xy 197.540009 -371.713573) (xy 197.522593 -371.703026) (xy 197.51421 -371.69725) (xy 197.513702 -371.696996)
			(xy 197.502074 -371.688384) (xy 197.480318 -371.669305) (xy 197.470268 -371.658896) (xy 197.46976 -371.658642)
			(xy 196.810884 -370.999766) (xy 196.47662 -370.665502) (xy 196.46052 -370.648584) (xy 196.433131 -370.610759)
			(xy 196.411834 -370.569199) (xy 196.397126 -370.524876) (xy 196.3928 -370.501926) (xy 196.390734 -370.48939)
			(xy 196.388441 -370.464084) (xy 196.388228 -370.45138) (xy 196.388228 -367.861342) (xy 196.38784 -367.851682)
			(xy 196.380784 -367.833701) (xy 196.36758 -367.819603) (xy 196.359018 -367.815114) (xy 196.26199 -367.770156)
			(xy 196.23278 -367.773966) (xy 196.22135 -367.783618) (xy 196.200611 -367.800483) (xy 196.155326 -367.828882)
			(xy 196.106516 -367.850671) (xy 196.055139 -367.865425) (xy 196.002205 -367.872852) (xy 195.975478 -367.87328)
			(xy 195.948226 -367.872849) (xy 195.894276 -367.865089) (xy 195.841981 -367.849731) (xy 195.792402 -367.827087)
			(xy 195.746551 -367.797618) (xy 195.705361 -367.761924) (xy 195.669669 -367.720731) (xy 195.640203 -367.674878)
			(xy 195.617561 -367.625299) (xy 195.602206 -367.573002) (xy 195.59445 -367.519052) (xy 139.106444 -367.519052)
			(xy 138.391018 -368.990118) (xy 161.623764 -368.990118) (xy 161.627755 -368.927951) (xy 161.639664 -368.866804)
			(xy 161.659293 -368.807683) (xy 161.686322 -368.751557) (xy 161.720306 -368.699348) (xy 161.760688 -368.651913)
			(xy 161.806804 -368.610032) (xy 161.857896 -368.574392) (xy 161.913127 -368.545578) (xy 161.971589 -368.524064)
			(xy 162.032323 -368.510202) (xy 162.09433 -368.50422) (xy 162.156593 -368.506216) (xy 162.21809 -368.516159)
			(xy 162.277811 -368.533883) (xy 162.334774 -368.5591) (xy 162.388045 -368.591393) (xy 162.43675 -368.630233)
			(xy 162.480087 -368.674983) (xy 162.517347 -368.724907) (xy 162.547916 -368.779186) (xy 162.571294 -368.836929)
			(xy 162.587095 -368.897187) (xy 162.595061 -368.95897) (xy 162.59556 -368.990118) (xy 166.023806 -368.990118)
			(xy 166.027797 -368.927951) (xy 166.039706 -368.866804) (xy 166.059335 -368.807683) (xy 166.086364 -368.751557)
			(xy 166.120348 -368.699348) (xy 166.16073 -368.651913) (xy 166.206846 -368.610032) (xy 166.257938 -368.574392)
			(xy 166.313169 -368.545578) (xy 166.371631 -368.524064) (xy 166.432365 -368.510202) (xy 166.494372 -368.50422)
			(xy 166.556635 -368.506216) (xy 166.618132 -368.516159) (xy 166.677853 -368.533883) (xy 166.734816 -368.5591)
			(xy 166.788087 -368.591393) (xy 166.836792 -368.630233) (xy 166.880129 -368.674983) (xy 166.917389 -368.724907)
			(xy 166.947958 -368.779186) (xy 166.971336 -368.836929) (xy 166.987137 -368.897187) (xy 166.995103 -368.95897)
			(xy 166.995602 -368.990118) (xy 170.423848 -368.990118) (xy 170.427839 -368.927951) (xy 170.439748 -368.866804)
			(xy 170.459377 -368.807683) (xy 170.486406 -368.751557) (xy 170.52039 -368.699348) (xy 170.560772 -368.651913)
			(xy 170.606888 -368.610032) (xy 170.65798 -368.574392) (xy 170.713211 -368.545578) (xy 170.771673 -368.524064)
			(xy 170.832407 -368.510202) (xy 170.894414 -368.50422) (xy 170.956677 -368.506216) (xy 171.018174 -368.516159)
			(xy 171.077895 -368.533883) (xy 171.134858 -368.5591) (xy 171.188129 -368.591393) (xy 171.236834 -368.630233)
			(xy 171.280171 -368.674983) (xy 171.317431 -368.724907) (xy 171.348 -368.779186) (xy 171.371378 -368.836929)
			(xy 171.387179 -368.897187) (xy 171.395145 -368.95897) (xy 171.395644 -368.990118) (xy 174.82389 -368.990118)
			(xy 174.827881 -368.927951) (xy 174.83979 -368.866804) (xy 174.859419 -368.807683) (xy 174.886448 -368.751557)
			(xy 174.920432 -368.699348) (xy 174.960814 -368.651913) (xy 175.00693 -368.610032) (xy 175.058022 -368.574392)
			(xy 175.113253 -368.545578) (xy 175.171715 -368.524064) (xy 175.232449 -368.510202) (xy 175.294456 -368.50422)
			(xy 175.356719 -368.506216) (xy 175.418216 -368.516159) (xy 175.477937 -368.533883) (xy 175.5349 -368.5591)
			(xy 175.588171 -368.591393) (xy 175.636876 -368.630233) (xy 175.680213 -368.674983) (xy 175.717473 -368.724907)
			(xy 175.748042 -368.779186) (xy 175.77142 -368.836929) (xy 175.787221 -368.897187) (xy 175.795187 -368.95897)
			(xy 175.795686 -368.990118) (xy 179.223932 -368.990118) (xy 179.227923 -368.927951) (xy 179.239832 -368.866804)
			(xy 179.259461 -368.807683) (xy 179.28649 -368.751557) (xy 179.320474 -368.699348) (xy 179.360856 -368.651913)
			(xy 179.406972 -368.610032) (xy 179.458064 -368.574392) (xy 179.513295 -368.545578) (xy 179.571757 -368.524064)
			(xy 179.632491 -368.510202) (xy 179.694498 -368.50422) (xy 179.756761 -368.506216) (xy 179.818258 -368.516159)
			(xy 179.877979 -368.533883) (xy 179.934942 -368.5591) (xy 179.988213 -368.591393) (xy 180.036918 -368.630233)
			(xy 180.080255 -368.674983) (xy 180.117515 -368.724907) (xy 180.148084 -368.779186) (xy 180.171462 -368.836929)
			(xy 180.187263 -368.897187) (xy 180.195229 -368.95897) (xy 180.195728 -368.990118) (xy 180.195229 -369.021266)
			(xy 180.187263 -369.083049) (xy 180.172402 -369.139724) (xy 194.89623 -369.139724) (xy 194.900301 -369.084102)
			(xy 194.912427 -369.029665) (xy 194.93235 -368.977574) (xy 194.959646 -368.928939) (xy 194.993732 -368.884796)
			(xy 195.033881 -368.846087) (xy 195.079239 -368.813636) (xy 195.128839 -368.788135) (xy 195.181623 -368.770128)
			(xy 195.236466 -368.759998) (xy 195.2922 -368.757961) (xy 195.347637 -368.764061) (xy 195.401594 -368.778167)
			(xy 195.452923 -368.799979) (xy 195.500529 -368.829033) (xy 195.543397 -368.864708) (xy 195.580614 -368.906245)
			(xy 195.611387 -368.952758) (xy 195.635059 -369.003255) (xy 195.651127 -369.056662) (xy 195.659247 -369.111838)
			(xy 195.659756 -369.139724) (xy 195.659247 -369.16761) (xy 195.651127 -369.222786) (xy 195.635059 -369.276193)
			(xy 195.611387 -369.32669) (xy 195.580614 -369.373203) (xy 195.543397 -369.41474) (xy 195.500529 -369.450415)
			(xy 195.452923 -369.479469) (xy 195.401594 -369.501281) (xy 195.347637 -369.515387) (xy 195.2922 -369.521487)
			(xy 195.236466 -369.51945) (xy 195.181623 -369.50932) (xy 195.128839 -369.491313) (xy 195.079239 -369.465812)
			(xy 195.033881 -369.433361) (xy 194.993732 -369.394652) (xy 194.959646 -369.350509) (xy 194.93235 -369.301874)
			(xy 194.912427 -369.249783) (xy 194.900301 -369.195346) (xy 194.89623 -369.139724) (xy 180.172402 -369.139724)
			(xy 180.171462 -369.143307) (xy 180.148084 -369.20105) (xy 180.117515 -369.255329) (xy 180.080255 -369.305253)
			(xy 180.036918 -369.350003) (xy 179.988213 -369.388843) (xy 179.934942 -369.421136) (xy 179.877979 -369.446353)
			(xy 179.818258 -369.464077) (xy 179.756761 -369.47402) (xy 179.694498 -369.476016) (xy 179.632491 -369.470034)
			(xy 179.571757 -369.456172) (xy 179.513295 -369.434658) (xy 179.458064 -369.405844) (xy 179.406972 -369.370204)
			(xy 179.360856 -369.328323) (xy 179.320474 -369.280888) (xy 179.28649 -369.228679) (xy 179.259461 -369.172553)
			(xy 179.239832 -369.113432) (xy 179.227923 -369.052285) (xy 179.223932 -368.990118) (xy 175.795686 -368.990118)
			(xy 175.795187 -369.021266) (xy 175.787221 -369.083049) (xy 175.77142 -369.143307) (xy 175.748042 -369.20105)
			(xy 175.717473 -369.255329) (xy 175.680213 -369.305253) (xy 175.636876 -369.350003) (xy 175.588171 -369.388843)
			(xy 175.5349 -369.421136) (xy 175.477937 -369.446353) (xy 175.418216 -369.464077) (xy 175.356719 -369.47402)
			(xy 175.294456 -369.476016) (xy 175.232449 -369.470034) (xy 175.171715 -369.456172) (xy 175.113253 -369.434658)
			(xy 175.058022 -369.405844) (xy 175.00693 -369.370204) (xy 174.960814 -369.328323) (xy 174.920432 -369.280888)
			(xy 174.886448 -369.228679) (xy 174.859419 -369.172553) (xy 174.83979 -369.113432) (xy 174.827881 -369.052285)
			(xy 174.82389 -368.990118) (xy 171.395644 -368.990118) (xy 171.395145 -369.021266) (xy 171.387179 -369.083049)
			(xy 171.371378 -369.143307) (xy 171.348 -369.20105) (xy 171.317431 -369.255329) (xy 171.280171 -369.305253)
			(xy 171.236834 -369.350003) (xy 171.188129 -369.388843) (xy 171.134858 -369.421136) (xy 171.077895 -369.446353)
			(xy 171.018174 -369.464077) (xy 170.956677 -369.47402) (xy 170.894414 -369.476016) (xy 170.832407 -369.470034)
			(xy 170.771673 -369.456172) (xy 170.713211 -369.434658) (xy 170.65798 -369.405844) (xy 170.606888 -369.370204)
			(xy 170.560772 -369.328323) (xy 170.52039 -369.280888) (xy 170.486406 -369.228679) (xy 170.459377 -369.172553)
			(xy 170.439748 -369.113432) (xy 170.427839 -369.052285) (xy 170.423848 -368.990118) (xy 166.995602 -368.990118)
			(xy 166.995103 -369.021266) (xy 166.987137 -369.083049) (xy 166.971336 -369.143307) (xy 166.947958 -369.20105)
			(xy 166.917389 -369.255329) (xy 166.880129 -369.305253) (xy 166.836792 -369.350003) (xy 166.788087 -369.388843)
			(xy 166.734816 -369.421136) (xy 166.677853 -369.446353) (xy 166.618132 -369.464077) (xy 166.556635 -369.47402)
			(xy 166.494372 -369.476016) (xy 166.432365 -369.470034) (xy 166.371631 -369.456172) (xy 166.313169 -369.434658)
			(xy 166.257938 -369.405844) (xy 166.206846 -369.370204) (xy 166.16073 -369.328323) (xy 166.120348 -369.280888)
			(xy 166.086364 -369.228679) (xy 166.059335 -369.172553) (xy 166.039706 -369.113432) (xy 166.027797 -369.052285)
			(xy 166.023806 -368.990118) (xy 162.59556 -368.990118) (xy 162.595061 -369.021266) (xy 162.587095 -369.083049)
			(xy 162.571294 -369.143307) (xy 162.547916 -369.20105) (xy 162.517347 -369.255329) (xy 162.480087 -369.305253)
			(xy 162.43675 -369.350003) (xy 162.388045 -369.388843) (xy 162.334774 -369.421136) (xy 162.277811 -369.446353)
			(xy 162.21809 -369.464077) (xy 162.156593 -369.47402) (xy 162.09433 -369.476016) (xy 162.032323 -369.470034)
			(xy 161.971589 -369.456172) (xy 161.913127 -369.434658) (xy 161.857896 -369.405844) (xy 161.806804 -369.370204)
			(xy 161.760688 -369.328323) (xy 161.720306 -369.280888) (xy 161.686322 -369.228679) (xy 161.659293 -369.172553)
			(xy 161.639664 -369.113432) (xy 161.627755 -369.052285) (xy 161.623764 -368.990118) (xy 138.391018 -368.990118)
			(xy 137.64567 -370.522711) (xy 159.424901 -370.522711) (xy 159.424903 -370.457268) (xy 159.433697 -370.392418)
			(xy 159.451123 -370.329338) (xy 159.476867 -370.269171) (xy 159.493204 -370.240814) (xy 159.496514 -370.234787)
			(xy 159.500123 -370.221525) (xy 159.500316 -370.214652) (xy 159.500316 -369.928902) (xy 159.500835 -369.918747)
			(xy 159.508604 -369.899982) (xy 159.522962 -369.885618) (xy 159.541723 -369.877839) (xy 159.551878 -369.87734)
			(xy 160.268158 -369.87734) (xy 160.278327 -369.877798) (xy 160.297121 -369.88557) (xy 160.311508 -369.899945)
			(xy 160.319294 -369.918733) (xy 160.31972 -369.928902) (xy 160.31972 -370.214652) (xy 160.319928 -370.221524)
			(xy 160.323525 -370.234787) (xy 160.326832 -370.240814) (xy 160.34316 -370.269175) (xy 160.368906 -370.329341)
			(xy 160.386335 -370.39242) (xy 160.39513 -370.457268) (xy 160.395131 -370.522711) (xy 160.395131 -370.522712)
			(xy 163.824938 -370.522712) (xy 163.824939 -370.457268) (xy 163.833733 -370.392418) (xy 163.851162 -370.329337)
			(xy 163.876908 -370.26917) (xy 163.893246 -370.240814) (xy 163.896605 -370.234796) (xy 163.900344 -370.221538)
			(xy 163.900612 -370.214652) (xy 163.900612 -369.928902) (xy 163.901127 -369.918779) (xy 163.908849 -369.900063)
			(xy 163.923126 -369.885708) (xy 163.9418 -369.877884) (xy 163.95192 -369.87734) (xy 164.6682 -369.87734)
			(xy 164.678359 -369.877722) (xy 164.697119 -369.885526) (xy 164.711444 -369.899935) (xy 164.719136 -369.918741)
			(xy 164.719508 -369.928902) (xy 164.719508 -370.214652) (xy 164.719759 -370.221542) (xy 164.723489 -370.234808)
			(xy 164.726874 -370.240814) (xy 164.743201 -370.269176) (xy 164.768945 -370.329341) (xy 164.786372 -370.39242)
			(xy 164.795166 -370.457269) (xy 164.795167 -370.522711) (xy 164.795167 -370.522712) (xy 168.224974 -370.522712)
			(xy 168.224975 -370.457268) (xy 168.23377 -370.392417) (xy 168.2512 -370.329336) (xy 168.276948 -370.26917)
			(xy 168.293288 -370.240814) (xy 168.296597 -370.234786) (xy 168.300206 -370.221525) (xy 168.3004 -370.214652)
			(xy 168.3004 -369.928902) (xy 168.300934 -369.918749) (xy 168.308701 -369.899987) (xy 168.323054 -369.885623)
			(xy 168.341809 -369.877842) (xy 168.351962 -369.87734) (xy 169.068242 -369.87734) (xy 169.078403 -369.877799)
			(xy 169.097173 -369.885588) (xy 169.111537 -369.899964) (xy 169.11931 -369.918741) (xy 169.119804 -369.928902)
			(xy 169.119804 -370.214652) (xy 169.120014 -370.221524) (xy 169.12361 -370.234787) (xy 169.126916 -370.240814)
			(xy 169.143245 -370.269175) (xy 169.168992 -370.32934) (xy 169.186421 -370.392419) (xy 169.195216 -370.457268)
			(xy 169.195217 -370.522711) (xy 169.195217 -370.522712) (xy 172.624763 -370.522712) (xy 172.624765 -370.457268)
			(xy 172.63356 -370.392417) (xy 172.650989 -370.329336) (xy 172.676737 -370.26917) (xy 172.693076 -370.240814)
			(xy 172.696384 -370.234786) (xy 172.699994 -370.221525) (xy 172.700188 -370.214652) (xy 172.700188 -369.928902)
			(xy 172.700567 -369.918724) (xy 172.70836 -369.89992) (xy 172.72276 -369.885533) (xy 172.741572 -369.877757)
			(xy 172.75175 -369.87734) (xy 173.46803 -369.87734) (xy 173.47819 -369.877809) (xy 173.49696 -369.885593)
			(xy 173.511325 -369.899967) (xy 173.519098 -369.918742) (xy 173.519592 -369.928902) (xy 173.519592 -370.214652)
			(xy 173.519804 -370.221524) (xy 173.523399 -370.234786) (xy 173.526704 -370.240814) (xy 173.54303 -370.269176)
			(xy 173.568772 -370.329342) (xy 173.586198 -370.392421) (xy 173.594992 -370.457269) (xy 173.594992 -370.489988)
			(xy 177.023784 -370.489988) (xy 177.027775 -370.427821) (xy 177.039684 -370.366674) (xy 177.059313 -370.307553)
			(xy 177.086342 -370.251427) (xy 177.120326 -370.199218) (xy 177.160708 -370.151783) (xy 177.206824 -370.109902)
			(xy 177.257916 -370.074262) (xy 177.313147 -370.045448) (xy 177.371609 -370.023934) (xy 177.432343 -370.010072)
			(xy 177.49435 -370.00409) (xy 177.556613 -370.006086) (xy 177.61811 -370.016029) (xy 177.677831 -370.033753)
			(xy 177.734794 -370.05897) (xy 177.788065 -370.091263) (xy 177.83677 -370.130103) (xy 177.880107 -370.174853)
			(xy 177.917367 -370.224777) (xy 177.947936 -370.279056) (xy 177.971314 -370.336799) (xy 177.987115 -370.397057)
			(xy 177.995081 -370.45884) (xy 177.99558 -370.489988) (xy 177.995081 -370.521136) (xy 177.994021 -370.529358)
			(xy 189.975488 -370.529358) (xy 189.979559 -370.473736) (xy 189.991685 -370.419299) (xy 190.011608 -370.367208)
			(xy 190.038904 -370.318573) (xy 190.07299 -370.27443) (xy 190.113139 -370.235721) (xy 190.158497 -370.20327)
			(xy 190.208097 -370.177769) (xy 190.260881 -370.159762) (xy 190.315724 -370.149632) (xy 190.371458 -370.147595)
			(xy 190.426895 -370.153695) (xy 190.480852 -370.167801) (xy 190.532181 -370.189613) (xy 190.579787 -370.218667)
			(xy 190.622655 -370.254342) (xy 190.659872 -370.295879) (xy 190.690645 -370.342392) (xy 190.714317 -370.392889)
			(xy 190.730385 -370.446296) (xy 190.738505 -370.501472) (xy 190.739014 -370.529358) (xy 190.738505 -370.557244)
			(xy 190.730385 -370.61242) (xy 190.714317 -370.665827) (xy 190.690645 -370.716324) (xy 190.659872 -370.762837)
			(xy 190.622655 -370.804374) (xy 190.579787 -370.840049) (xy 190.532181 -370.869103) (xy 190.480852 -370.890915)
			(xy 190.426895 -370.905021) (xy 190.371458 -370.911121) (xy 190.315724 -370.909084) (xy 190.260881 -370.898954)
			(xy 190.208097 -370.880947) (xy 190.158497 -370.855446) (xy 190.113139 -370.822995) (xy 190.07299 -370.784286)
			(xy 190.038904 -370.740143) (xy 190.011608 -370.691508) (xy 189.991685 -370.639417) (xy 189.979559 -370.58498)
			(xy 189.975488 -370.529358) (xy 177.994021 -370.529358) (xy 177.987115 -370.582919) (xy 177.971314 -370.643177)
			(xy 177.947936 -370.70092) (xy 177.917367 -370.755199) (xy 177.880107 -370.805123) (xy 177.83677 -370.849873)
			(xy 177.788065 -370.888713) (xy 177.734794 -370.921006) (xy 177.677831 -370.946223) (xy 177.61811 -370.963947)
			(xy 177.556613 -370.97389) (xy 177.49435 -370.975886) (xy 177.432343 -370.969904) (xy 177.371609 -370.956042)
			(xy 177.313147 -370.934528) (xy 177.257916 -370.905714) (xy 177.206824 -370.870074) (xy 177.160708 -370.828193)
			(xy 177.120326 -370.780758) (xy 177.086342 -370.728549) (xy 177.059313 -370.672423) (xy 177.039684 -370.613302)
			(xy 177.027775 -370.552155) (xy 177.023784 -370.489988) (xy 173.594992 -370.489988) (xy 173.594993 -370.522711)
			(xy 173.586203 -370.587559) (xy 173.568779 -370.650639) (xy 173.543039 -370.710805) (xy 173.526704 -370.739162)
			(xy 173.523403 -370.745193) (xy 173.519789 -370.758452) (xy 173.519592 -370.765324) (xy 173.519592 -371.514878)
			(xy 173.519793 -371.521751) (xy 173.523395 -371.535013) (xy 173.526704 -371.54104) (xy 173.543052 -371.56939)
			(xy 173.565896 -371.62279) (xy 174.824904 -371.62279) (xy 174.824908 -371.557345) (xy 174.833706 -371.492493)
			(xy 174.851136 -371.429412) (xy 174.876885 -371.369244) (xy 174.893224 -371.340888) (xy 174.896545 -371.334866)
			(xy 174.900146 -371.3216) (xy 174.900336 -371.314726) (xy 174.900336 -371.028722) (xy 174.900782 -371.018552)
			(xy 174.908559 -370.999758) (xy 174.922938 -370.985373) (xy 174.941728 -370.977587) (xy 174.951898 -370.97716)
			(xy 175.668178 -370.97716) (xy 175.678351 -370.977583) (xy 175.697149 -370.985364) (xy 175.711536 -370.999751)
			(xy 175.719317 -371.018549) (xy 175.71974 -371.028722) (xy 175.71974 -371.314726) (xy 175.719917 -371.3216)
			(xy 175.723535 -371.334863) (xy 175.726852 -371.340888) (xy 175.743157 -371.369262) (xy 175.768905 -371.429424)
			(xy 175.786335 -371.492501) (xy 175.795132 -371.557347) (xy 175.795137 -371.622788) (xy 175.786348 -371.687635)
			(xy 175.768926 -371.750714) (xy 175.752028 -371.790214) (xy 177.023784 -371.790214) (xy 177.027775 -371.728047)
			(xy 177.039684 -371.6669) (xy 177.059313 -371.607779) (xy 177.086342 -371.551653) (xy 177.120326 -371.499444)
			(xy 177.160708 -371.452009) (xy 177.206824 -371.410128) (xy 177.257916 -371.374488) (xy 177.313147 -371.345674)
			(xy 177.371609 -371.32416) (xy 177.432343 -371.310298) (xy 177.49435 -371.304316) (xy 177.556613 -371.306312)
			(xy 177.61811 -371.316255) (xy 177.677831 -371.333979) (xy 177.734794 -371.359196) (xy 177.788065 -371.391489)
			(xy 177.83677 -371.430329) (xy 177.880107 -371.475079) (xy 177.917367 -371.525003) (xy 177.947936 -371.579282)
			(xy 177.9523 -371.590062) (xy 179.223932 -371.590062) (xy 179.227923 -371.527895) (xy 179.239832 -371.466748)
			(xy 179.259461 -371.407627) (xy 179.28649 -371.351501) (xy 179.320474 -371.299292) (xy 179.360856 -371.251857)
			(xy 179.406972 -371.209976) (xy 179.458064 -371.174336) (xy 179.513295 -371.145522) (xy 179.571757 -371.124008)
			(xy 179.632491 -371.110146) (xy 179.694498 -371.104164) (xy 179.756761 -371.10616) (xy 179.818258 -371.116103)
			(xy 179.877979 -371.133827) (xy 179.934942 -371.159044) (xy 179.988213 -371.191337) (xy 180.036918 -371.230177)
			(xy 180.080255 -371.274927) (xy 180.117515 -371.324851) (xy 180.148084 -371.37913) (xy 180.171462 -371.436873)
			(xy 180.187263 -371.497131) (xy 180.195229 -371.558914) (xy 180.195728 -371.590062) (xy 180.195229 -371.62121)
			(xy 180.187263 -371.682993) (xy 180.171462 -371.743251) (xy 180.148084 -371.800994) (xy 180.117515 -371.855273)
			(xy 180.080255 -371.905197) (xy 180.036918 -371.949947) (xy 179.988213 -371.988787) (xy 179.934942 -372.02108)
			(xy 179.877979 -372.046297) (xy 179.818258 -372.064021) (xy 179.756761 -372.073964) (xy 179.694498 -372.07596)
			(xy 179.632491 -372.069978) (xy 179.571757 -372.056116) (xy 179.513295 -372.034602) (xy 179.458064 -372.005788)
			(xy 179.406972 -371.970148) (xy 179.360856 -371.928267) (xy 179.320474 -371.880832) (xy 179.28649 -371.828623)
			(xy 179.259461 -371.772497) (xy 179.239832 -371.713376) (xy 179.227923 -371.652229) (xy 179.223932 -371.590062)
			(xy 177.9523 -371.590062) (xy 177.971314 -371.637025) (xy 177.987115 -371.697283) (xy 177.995081 -371.759066)
			(xy 177.99558 -371.790214) (xy 177.995081 -371.821362) (xy 177.987115 -371.883145) (xy 177.971314 -371.943403)
			(xy 177.947936 -372.001146) (xy 177.917367 -372.055425) (xy 177.880107 -372.105349) (xy 177.83677 -372.150099)
			(xy 177.788065 -372.188939) (xy 177.734794 -372.221232) (xy 177.677831 -372.246449) (xy 177.61811 -372.264173)
			(xy 177.556613 -372.274116) (xy 177.49435 -372.276112) (xy 177.432343 -372.27013) (xy 177.371609 -372.256268)
			(xy 177.313147 -372.234754) (xy 177.257916 -372.20594) (xy 177.206824 -372.1703) (xy 177.160708 -372.128419)
			(xy 177.120326 -372.080984) (xy 177.086342 -372.028775) (xy 177.059313 -371.972649) (xy 177.039684 -371.913528)
			(xy 177.027775 -371.852381) (xy 177.023784 -371.790214) (xy 175.752028 -371.790214) (xy 175.743187 -371.81088)
			(xy 175.726852 -371.839236) (xy 175.723529 -371.845256) (xy 175.719928 -371.858523) (xy 175.71974 -371.865398)
			(xy 175.71974 -372.614698) (xy 175.719928 -372.621572) (xy 175.723538 -372.634835) (xy 175.726852 -372.64086)
			(xy 175.743218 -372.6692) (xy 175.76896 -372.72937) (xy 175.786384 -372.792454) (xy 175.795173 -372.857306)
			(xy 175.795171 -372.890034) (xy 179.223932 -372.890034) (xy 179.227923 -372.827867) (xy 179.239832 -372.76672)
			(xy 179.259461 -372.707599) (xy 179.28649 -372.651473) (xy 179.320474 -372.599264) (xy 179.360856 -372.551829)
			(xy 179.406972 -372.509948) (xy 179.458064 -372.474308) (xy 179.513295 -372.445494) (xy 179.571757 -372.42398)
			(xy 179.632491 -372.410118) (xy 179.694498 -372.404136) (xy 179.756761 -372.406132) (xy 179.818258 -372.416075)
			(xy 179.877979 -372.433799) (xy 179.934942 -372.459016) (xy 179.988213 -372.491309) (xy 180.036918 -372.530149)
			(xy 180.080255 -372.574899) (xy 180.117515 -372.624823) (xy 180.148084 -372.679102) (xy 180.171462 -372.736845)
			(xy 180.187263 -372.797103) (xy 180.195229 -372.858886) (xy 180.195728 -372.890034) (xy 180.195229 -372.921182)
			(xy 180.187263 -372.982965) (xy 180.171462 -373.043223) (xy 180.148084 -373.100966) (xy 180.117515 -373.155245)
			(xy 180.080255 -373.205169) (xy 180.036918 -373.249919) (xy 179.988213 -373.288759) (xy 179.934942 -373.321052)
			(xy 179.877979 -373.346269) (xy 179.818258 -373.363993) (xy 179.756761 -373.373936) (xy 179.694498 -373.375932)
			(xy 179.632491 -373.36995) (xy 179.571757 -373.356088) (xy 179.513295 -373.334574) (xy 179.458064 -373.30576)
			(xy 179.406972 -373.27012) (xy 179.360856 -373.228239) (xy 179.320474 -373.180804) (xy 179.28649 -373.128595)
			(xy 179.259461 -373.072469) (xy 179.239832 -373.013348) (xy 179.227923 -372.952201) (xy 179.223932 -372.890034)
			(xy 175.795171 -372.890034) (xy 175.795169 -372.922752) (xy 175.786372 -372.987603) (xy 175.768941 -373.050685)
			(xy 175.743192 -373.110852) (xy 175.726852 -373.139208) (xy 175.723539 -373.145233) (xy 175.719931 -373.158496)
			(xy 175.71974 -373.16537) (xy 175.71974 -373.451374) (xy 175.719314 -373.461547) (xy 175.711534 -373.480345)
			(xy 175.697148 -373.494731) (xy 175.678351 -373.502513) (xy 175.668178 -373.502936) (xy 174.951898 -373.502936)
			(xy 174.941723 -373.502537) (xy 174.922923 -373.494747) (xy 174.908538 -373.480353) (xy 174.900757 -373.461549)
			(xy 174.900336 -373.451374) (xy 174.900336 -373.16537) (xy 174.900151 -373.158496) (xy 174.896537 -373.145234)
			(xy 174.893224 -373.139208) (xy 174.876916 -373.110836) (xy 174.85117 -373.050673) (xy 174.833741 -372.987596)
			(xy 174.824945 -372.922749) (xy 174.824941 -372.857309) (xy 174.833729 -372.792461) (xy 174.851151 -372.729383)
			(xy 174.876889 -372.669216) (xy 174.893224 -372.64086) (xy 174.896555 -372.634843) (xy 174.90015 -372.621573)
			(xy 174.900336 -372.614698) (xy 174.900336 -371.865398) (xy 174.90014 -371.858525) (xy 174.896534 -371.845262)
			(xy 174.893224 -371.839236) (xy 174.876855 -371.810897) (xy 174.851115 -371.750726) (xy 174.833692 -371.687643)
			(xy 174.824904 -371.62279) (xy 173.565896 -371.62279) (xy 173.568792 -371.629559) (xy 173.586216 -371.69264)
			(xy 173.595007 -371.75749) (xy 173.595005 -371.822934) (xy 173.586211 -371.887784) (xy 173.568784 -371.950864)
			(xy 173.543041 -372.011031) (xy 173.526704 -372.039388) (xy 173.523394 -372.045415) (xy 173.519785 -372.058677)
			(xy 173.519592 -372.06555) (xy 173.519592 -372.351554) (xy 173.519099 -372.361719) (xy 173.511335 -372.380507)
			(xy 173.496971 -372.394892) (xy 173.478194 -372.402684) (xy 173.46803 -372.403116) (xy 172.75175 -372.403116)
			(xy 172.741576 -372.402694) (xy 172.722773 -372.394917) (xy 172.708385 -372.38053) (xy 172.700607 -372.361728)
			(xy 172.700188 -372.351554) (xy 172.700188 -372.06555) (xy 172.699978 -372.058678) (xy 172.696382 -372.045415)
			(xy 172.693076 -372.039388) (xy 172.676749 -372.011026) (xy 172.651002 -371.950861) (xy 172.633573 -371.887782)
			(xy 172.624778 -371.822933) (xy 172.624777 -371.757491) (xy 172.633568 -371.692642) (xy 172.650994 -371.629562)
			(xy 172.676738 -371.569396) (xy 172.693076 -371.54104) (xy 172.696375 -371.535008) (xy 172.699991 -371.52175)
			(xy 172.700188 -371.514878) (xy 172.700188 -370.765324) (xy 172.699988 -370.758451) (xy 172.696385 -370.745189)
			(xy 172.693076 -370.739162) (xy 172.676727 -370.710812) (xy 172.650982 -370.650644) (xy 172.633556 -370.587563)
			(xy 172.624763 -370.522712) (xy 169.195217 -370.522712) (xy 169.186425 -370.58756) (xy 169.168999 -370.65064)
			(xy 169.143254 -370.710806) (xy 169.126916 -370.739162) (xy 169.123616 -370.745194) (xy 169.120001 -370.758452)
			(xy 169.119804 -370.765324) (xy 169.119804 -371.514878) (xy 169.120004 -371.521751) (xy 169.123607 -371.535013)
			(xy 169.126916 -371.54104) (xy 169.143267 -371.569389) (xy 169.166117 -371.62279) (xy 170.424854 -371.62279)
			(xy 170.424858 -371.557344) (xy 170.433657 -371.492492) (xy 170.45109 -371.429411) (xy 170.476841 -371.369244)
			(xy 170.493182 -371.340888) (xy 170.496545 -371.334872) (xy 170.500282 -371.321613) (xy 170.500548 -371.314726)
			(xy 170.500548 -371.028722) (xy 170.501045 -371.018596) (xy 170.508767 -370.999873) (xy 170.52305 -370.985516)
			(xy 170.541732 -370.977698) (xy 170.551856 -370.97716) (xy 171.268136 -370.97716) (xy 171.278287 -370.977591)
			(xy 171.297033 -370.985391) (xy 171.311354 -370.999784) (xy 171.319059 -371.018568) (xy 171.319444 -371.028722)
			(xy 171.319444 -371.314726) (xy 171.319678 -371.321619) (xy 171.323406 -371.334891) (xy 171.32681 -371.340888)
			(xy 171.343117 -371.369261) (xy 171.368866 -371.429424) (xy 171.386298 -371.4925) (xy 171.395096 -371.557347)
			(xy 171.3951 -371.622788) (xy 171.386311 -371.687636) (xy 171.368888 -371.750715) (xy 171.343146 -371.81088)
			(xy 171.32681 -371.839236) (xy 171.323438 -371.845247) (xy 171.319706 -371.85851) (xy 171.319444 -371.865398)
			(xy 171.319444 -372.614698) (xy 171.31965 -372.621593) (xy 171.323397 -372.634865) (xy 171.32681 -372.64086)
			(xy 171.343178 -372.6692) (xy 171.368922 -372.72937) (xy 171.386347 -372.792453) (xy 171.395137 -372.857306)
			(xy 171.395133 -372.922752) (xy 171.386335 -372.987604) (xy 171.368902 -373.050685) (xy 171.343151 -373.110852)
			(xy 171.32681 -373.139208) (xy 171.323448 -373.145224) (xy 171.31971 -373.158484) (xy 171.319444 -373.16537)
			(xy 171.319444 -373.451374) (xy 171.318952 -373.461501) (xy 171.31123 -373.480225) (xy 171.296945 -373.494583)
			(xy 171.27826 -373.5024) (xy 171.268136 -373.502936) (xy 170.551856 -373.502936) (xy 170.541704 -373.502515)
			(xy 170.522957 -373.494712) (xy 170.508637 -373.480316) (xy 170.500932 -373.461529) (xy 170.500548 -373.451374)
			(xy 170.500548 -373.16537) (xy 170.500317 -373.158477) (xy 170.496587 -373.145205) (xy 170.493182 -373.139208)
			(xy 170.476872 -373.110836) (xy 170.451123 -373.050674) (xy 170.433692 -372.987597) (xy 170.424895 -372.92275)
			(xy 170.424891 -372.857309) (xy 170.43368 -372.79246) (xy 170.451104 -372.729381) (xy 170.476846 -372.669216)
			(xy 170.493182 -372.64086) (xy 170.496555 -372.634849) (xy 170.500286 -372.621586) (xy 170.500548 -372.614698)
			(xy 170.500548 -371.865398) (xy 170.500344 -371.858503) (xy 170.496596 -371.845231) (xy 170.493182 -371.839236)
			(xy 170.476811 -371.810898) (xy 170.451068 -371.750728) (xy 170.433643 -371.687644) (xy 170.424854 -371.62279)
			(xy 169.166117 -371.62279) (xy 169.169012 -371.629557) (xy 169.186439 -371.692639) (xy 169.195231 -371.75749)
			(xy 169.195229 -371.822934) (xy 169.186434 -371.887785) (xy 169.169004 -371.950866) (xy 169.143256 -372.011032)
			(xy 169.126916 -372.039388) (xy 169.123607 -372.045415) (xy 169.119997 -372.058677) (xy 169.119804 -372.06555)
			(xy 169.119804 -372.351554) (xy 169.1193 -372.361717) (xy 169.111537 -372.380503) (xy 169.097177 -372.394888)
			(xy 169.078405 -372.402682) (xy 169.068242 -372.403116) (xy 168.351962 -372.403116) (xy 168.341782 -372.402766)
			(xy 168.322978 -372.39496) (xy 168.308593 -372.380552) (xy 168.300817 -372.361734) (xy 168.3004 -372.351554)
			(xy 168.3004 -372.06555) (xy 168.300189 -372.058678) (xy 168.296594 -372.045415) (xy 168.293288 -372.039388)
			(xy 168.276961 -372.011026) (xy 168.251213 -371.950861) (xy 168.233784 -371.887782) (xy 168.224989 -371.822933)
			(xy 168.224987 -371.757491) (xy 168.233779 -371.692641) (xy 168.251205 -371.629562) (xy 168.27695 -371.569396)
			(xy 168.293288 -371.54104) (xy 168.296588 -371.535008) (xy 168.300203 -371.52175) (xy 168.3004 -371.514878)
			(xy 168.3004 -370.765324) (xy 168.300199 -370.758451) (xy 168.296597 -370.745189) (xy 168.293288 -370.739162)
			(xy 168.276939 -370.710812) (xy 168.251193 -370.650644) (xy 168.233766 -370.587563) (xy 168.224974 -370.522712)
			(xy 164.795167 -370.522712) (xy 164.786376 -370.587559) (xy 164.768952 -370.650639) (xy 164.74321 -370.710806)
			(xy 164.726874 -370.739162) (xy 164.72349 -370.745167) (xy 164.719767 -370.758435) (xy 164.719508 -370.765324)
			(xy 164.719508 -371.514878) (xy 164.719749 -371.521769) (xy 164.723486 -371.535035) (xy 164.726874 -371.54104)
			(xy 164.743223 -371.56939) (xy 164.766069 -371.62279) (xy 166.024818 -371.62279) (xy 166.024822 -371.557345)
			(xy 166.03362 -371.492493) (xy 166.051051 -371.429412) (xy 166.0768 -371.369244) (xy 166.09314 -371.340888)
			(xy 166.096454 -371.334863) (xy 166.100061 -371.3216) (xy 166.100252 -371.314726) (xy 166.100252 -371.028722)
			(xy 166.100682 -371.01855) (xy 166.108463 -370.999753) (xy 166.122847 -370.985367) (xy 166.141642 -370.977584)
			(xy 166.151814 -370.97716) (xy 166.868094 -370.97716) (xy 166.878268 -370.977569) (xy 166.897067 -370.985356)
			(xy 166.911453 -370.999747) (xy 166.919234 -371.018548) (xy 166.919656 -371.028722) (xy 166.919656 -371.314726)
			(xy 166.919831 -371.321601) (xy 166.92345 -371.334864) (xy 166.926768 -371.340888) (xy 166.943073 -371.369262)
			(xy 166.968819 -371.429425) (xy 166.986249 -371.492501) (xy 166.995046 -371.557347) (xy 166.99505 -371.622788)
			(xy 166.986262 -371.687635) (xy 166.968841 -371.750714) (xy 166.943103 -371.81088) (xy 166.926768 -371.839236)
			(xy 166.923438 -371.845253) (xy 166.919843 -371.858523) (xy 166.919656 -371.865398) (xy 166.919656 -372.614698)
			(xy 166.919842 -372.621572) (xy 166.923453 -372.634835) (xy 166.926768 -372.64086) (xy 166.943134 -372.6692)
			(xy 166.968875 -372.729371) (xy 166.986298 -372.792454) (xy 166.995087 -372.857307) (xy 166.995083 -372.922752)
			(xy 166.986286 -372.987603) (xy 166.968855 -373.050684) (xy 166.943107 -373.110852) (xy 166.926768 -373.139208)
			(xy 166.923448 -373.14523) (xy 166.919846 -373.158496) (xy 166.919656 -373.16537) (xy 166.919656 -373.451374)
			(xy 166.919215 -373.461545) (xy 166.911437 -373.48034) (xy 166.897057 -373.494726) (xy 166.878264 -373.502511)
			(xy 166.868094 -373.502936) (xy 166.151814 -373.502936) (xy 166.14164 -373.502524) (xy 166.122841 -373.494739)
			(xy 166.108454 -373.480349) (xy 166.100673 -373.461548) (xy 166.100252 -373.451374) (xy 166.100252 -373.16537)
			(xy 166.100077 -373.158495) (xy 166.096458 -373.145232) (xy 166.09314 -373.139208) (xy 166.076831 -373.110836)
			(xy 166.051085 -373.050673) (xy 166.033655 -372.987596) (xy 166.024859 -372.922749) (xy 166.024855 -372.857309)
			(xy 166.033643 -372.792461) (xy 166.051065 -372.729382) (xy 166.076805 -372.669216) (xy 166.09314 -372.64086)
			(xy 166.096464 -372.63484) (xy 166.100065 -372.621573) (xy 166.100252 -372.614698) (xy 166.100252 -371.865398)
			(xy 166.100067 -371.858524) (xy 166.096455 -371.845261) (xy 166.09314 -371.839236) (xy 166.07677 -371.810898)
			(xy 166.051029 -371.750727) (xy 166.033607 -371.687643) (xy 166.024818 -371.62279) (xy 164.766069 -371.62279)
			(xy 164.768965 -371.629558) (xy 164.78639 -371.69264) (xy 164.795181 -371.75749) (xy 164.795179 -371.822934)
			(xy 164.786385 -371.887784) (xy 164.768957 -371.950865) (xy 164.743212 -372.011032) (xy 164.726874 -372.039388)
			(xy 164.723516 -372.045406) (xy 164.719776 -372.058664) (xy 164.719508 -372.06555) (xy 164.719508 -372.351554)
			(xy 164.718937 -372.361672) (xy 164.711233 -372.380383) (xy 164.696973 -372.394739) (xy 164.678314 -372.402568)
			(xy 164.6682 -372.403116) (xy 163.95192 -372.403116) (xy 163.941769 -372.402662) (xy 163.92302 -372.394876)
			(xy 163.908697 -372.38049) (xy 163.900993 -372.361707) (xy 163.900612 -372.351554) (xy 163.900612 -372.06555)
			(xy 163.900393 -372.058656) (xy 163.896655 -372.045384) (xy 163.893246 -372.039388) (xy 163.87692 -372.011025)
			(xy 163.851175 -371.95086) (xy 163.833747 -371.887781) (xy 163.824952 -371.822933) (xy 163.824951 -371.757491)
			(xy 163.833742 -371.692642) (xy 163.851167 -371.629562) (xy 163.876909 -371.569396) (xy 163.893246 -371.54104)
			(xy 163.896631 -371.535035) (xy 163.900353 -371.521767) (xy 163.900612 -371.514878) (xy 163.900612 -370.765324)
			(xy 163.900403 -370.758429) (xy 163.896659 -370.745157) (xy 163.893246 -370.739162) (xy 163.876898 -370.710812)
			(xy 163.851155 -370.650644) (xy 163.833729 -370.587562) (xy 163.824938 -370.522712) (xy 160.395131 -370.522712)
			(xy 160.386339 -370.58756) (xy 160.368913 -370.65064) (xy 160.343169 -370.710806) (xy 160.326832 -370.739162)
			(xy 160.323533 -370.745195) (xy 160.319917 -370.758452) (xy 160.31972 -370.765324) (xy 160.31972 -371.514878)
			(xy 160.319918 -371.521751) (xy 160.323522 -371.535014) (xy 160.326832 -371.54104) (xy 160.343182 -371.569389)
			(xy 160.366031 -371.62279) (xy 161.624781 -371.62279) (xy 161.624786 -371.557345) (xy 161.633583 -371.492494)
			(xy 161.651013 -371.429412) (xy 161.676759 -371.369245) (xy 161.693098 -371.340888) (xy 161.696462 -371.334873)
			(xy 161.700199 -371.321613) (xy 161.700464 -371.314726) (xy 161.700464 -371.028722) (xy 161.700945 -371.018594)
			(xy 161.70867 -370.999868) (xy 161.722959 -370.985511) (xy 161.741646 -370.977695) (xy 161.751772 -370.97716)
			(xy 162.468052 -370.97716) (xy 162.478198 -370.97766) (xy 162.496942 -370.985432) (xy 162.511265 -370.999805)
			(xy 162.518974 -371.018575) (xy 162.51936 -371.028722) (xy 162.51936 -371.314726) (xy 162.519592 -371.321619)
			(xy 162.523321 -371.334891) (xy 162.526726 -371.340888) (xy 162.543032 -371.369262) (xy 162.568781 -371.429424)
			(xy 162.586212 -371.4925) (xy 162.59501 -371.557347) (xy 162.595014 -371.622788) (xy 162.586225 -371.687636)
			(xy 162.568803 -371.750715) (xy 162.543062 -371.81088) (xy 162.526726 -371.839236) (xy 162.523347 -371.845244)
			(xy 162.519621 -371.85851) (xy 162.51936 -371.865398) (xy 162.51936 -372.614698) (xy 162.519564 -372.621593)
			(xy 162.523312 -372.634865) (xy 162.526726 -372.64086) (xy 162.543093 -372.6692) (xy 162.568836 -372.72937)
			(xy 162.586261 -372.792454) (xy 162.595051 -372.857306) (xy 162.595047 -372.922752) (xy 162.586249 -372.987604)
			(xy 162.568817 -373.050685) (xy 162.543067 -373.110852) (xy 162.526726 -373.139208) (xy 162.523357 -373.145221)
			(xy 162.519625 -373.158483) (xy 162.51936 -373.16537) (xy 162.51936 -373.451374) (xy 162.518852 -373.461499)
			(xy 162.511133 -373.48022) (xy 162.496853 -373.494577) (xy 162.478174 -373.502397) (xy 162.468052 -373.502936)
			(xy 161.751772 -373.502936) (xy 161.741621 -373.502502) (xy 161.722874 -373.494704) (xy 161.708553 -373.480312)
			(xy 161.700848 -373.461527) (xy 161.700464 -373.451374) (xy 161.700464 -373.16537) (xy 161.700231 -373.158477)
			(xy 161.696502 -373.145205) (xy 161.693098 -373.139208) (xy 161.676791 -373.110835) (xy 161.651046 -373.050672)
			(xy 161.633618 -372.987595) (xy 161.624822 -372.922749) (xy 161.624819 -372.857309) (xy 161.633606 -372.792462)
			(xy 161.651027 -372.729383) (xy 161.676764 -372.669217) (xy 161.693098 -372.64086) (xy 161.696472 -372.63485)
			(xy 161.700202 -372.621586) (xy 161.700464 -372.614698) (xy 161.700464 -371.865398) (xy 161.700236 -371.858506)
			(xy 161.696491 -371.84524) (xy 161.693098 -371.839236) (xy 161.67673 -371.810897) (xy 161.650991 -371.750726)
			(xy 161.63357 -371.687642) (xy 161.624781 -371.62279) (xy 160.366031 -371.62279) (xy 160.368926 -371.629557)
			(xy 160.386353 -371.692639) (xy 160.395145 -371.75749) (xy 160.395143 -371.822934) (xy 160.386348 -371.887785)
			(xy 160.368919 -371.950865) (xy 160.343171 -372.011032) (xy 160.326832 -372.039388) (xy 160.323524 -372.045416)
			(xy 160.319914 -372.058677) (xy 160.31972 -372.06555) (xy 160.31972 -372.351554) (xy 160.319297 -372.361728)
			(xy 160.31152 -372.38053) (xy 160.297133 -372.394918) (xy 160.278332 -372.402697) (xy 160.268158 -372.403116)
			(xy 159.551878 -372.403116) (xy 159.541699 -372.402753) (xy 159.522895 -372.394952) (xy 159.50851 -372.380547)
			(xy 159.500734 -372.361733) (xy 159.500316 -372.351554) (xy 159.500316 -372.06555) (xy 159.500103 -372.058678)
			(xy 159.496509 -372.045416) (xy 159.493204 -372.039388) (xy 159.47688 -372.011025) (xy 159.451136 -371.950859)
			(xy 159.43371 -371.887781) (xy 159.424916 -371.822933) (xy 159.424915 -371.757491) (xy 159.433705 -371.692643)
			(xy 159.451128 -371.629563) (xy 159.476869 -371.569397) (xy 159.493204 -371.54104) (xy 159.496505 -371.535009)
			(xy 159.500119 -371.52175) (xy 159.500316 -371.514878) (xy 159.500316 -370.765324) (xy 159.500113 -370.758452)
			(xy 159.496512 -370.745189) (xy 159.493204 -370.739162) (xy 159.476858 -370.710811) (xy 159.451116 -370.650643)
			(xy 159.433692 -370.587562) (xy 159.424901 -370.522711) (xy 137.64567 -370.522711) (xy 136.850374 -372.158006)
			(xy 136.848036 -372.16323) (xy 136.845481 -372.174383) (xy 136.845294 -372.180104) (xy 136.845294 -374.422887)
			(xy 159.424884 -374.422887) (xy 159.424889 -374.357441) (xy 159.433687 -374.29259) (xy 159.451117 -374.229508)
			(xy 159.476865 -374.169341) (xy 159.493204 -374.140984) (xy 159.496525 -374.134962) (xy 159.500127 -374.121696)
			(xy 159.500316 -374.114822) (xy 159.500316 -373.828818) (xy 159.500847 -373.818664) (xy 159.508612 -373.799899)
			(xy 159.522966 -373.785534) (xy 159.541724 -373.777755) (xy 159.551878 -373.777256) (xy 160.268158 -373.777256)
			(xy 160.278329 -373.777699) (xy 160.297126 -373.785473) (xy 160.311513 -373.799854) (xy 160.319297 -373.818647)
			(xy 160.31972 -373.828818) (xy 160.31972 -374.114822) (xy 160.319901 -374.121696) (xy 160.323516 -374.134959)
			(xy 160.326832 -374.140984) (xy 160.343135 -374.16936) (xy 160.368883 -374.229521) (xy 160.386315 -374.292597)
			(xy 160.395113 -374.357444) (xy 160.395118 -374.422884) (xy 160.395118 -374.422887) (xy 163.82492 -374.422887)
			(xy 163.824925 -374.357441) (xy 163.833724 -374.292589) (xy 163.851156 -374.229508) (xy 163.876906 -374.16934)
			(xy 163.893246 -374.140984) (xy 163.896615 -374.134972) (xy 163.900347 -374.121709) (xy 163.900612 -374.114822)
			(xy 163.900612 -373.828818) (xy 163.90114 -373.818696) (xy 163.908857 -373.79998) (xy 163.92313 -373.785624)
			(xy 163.941801 -373.7778) (xy 163.95192 -373.777256) (xy 164.6682 -373.777256) (xy 164.678349 -373.777721)
			(xy 164.697092 -373.785508) (xy 164.711414 -373.799891) (xy 164.719122 -373.818668) (xy 164.719508 -373.828818)
			(xy 164.719508 -374.114822) (xy 164.71977 -374.121711) (xy 164.723493 -374.134977) (xy 164.726874 -374.140984)
			(xy 164.743175 -374.16936) (xy 164.768922 -374.229522) (xy 164.786352 -374.292598) (xy 164.795149 -374.357444)
			(xy 164.795154 -374.422884) (xy 164.795154 -374.422887) (xy 168.224957 -374.422887) (xy 168.224961 -374.357441)
			(xy 168.233761 -374.292588) (xy 168.251194 -374.229507) (xy 168.276946 -374.16934) (xy 168.293288 -374.140984)
			(xy 168.296608 -374.134962) (xy 168.30021 -374.121696) (xy 168.3004 -374.114822) (xy 168.3004 -373.828818)
			(xy 168.300947 -373.818666) (xy 168.308709 -373.799905) (xy 168.323058 -373.78554) (xy 168.341811 -373.777758)
			(xy 168.351962 -373.777256) (xy 169.068242 -373.777256) (xy 169.078405 -373.777699) (xy 169.097178 -373.785491)
			(xy 169.111543 -373.799872) (xy 169.119312 -373.818655) (xy 169.119804 -373.828818) (xy 169.119804 -374.114822)
			(xy 169.119987 -374.121696) (xy 169.123601 -374.134959) (xy 169.126916 -374.140984) (xy 169.143219 -374.169359)
			(xy 169.168969 -374.229521) (xy 169.186401 -374.292597) (xy 169.195199 -374.357444) (xy 169.195204 -374.422884)
			(xy 169.195204 -374.422887) (xy 172.624746 -374.422887) (xy 172.624751 -374.357441) (xy 172.63355 -374.292589)
			(xy 172.650983 -374.229507) (xy 172.676735 -374.16934) (xy 172.693076 -374.140984) (xy 172.696395 -374.134961)
			(xy 172.699998 -374.121696) (xy 172.700188 -374.114822) (xy 172.700188 -373.828818) (xy 172.70058 -373.818641)
			(xy 172.708368 -373.799837) (xy 172.722764 -373.78545) (xy 172.741573 -373.777673) (xy 172.75175 -373.777256)
			(xy 173.46803 -373.777256) (xy 173.478192 -373.777709) (xy 173.496965 -373.785497) (xy 173.51133 -373.799875)
			(xy 173.5191 -373.818656) (xy 173.519592 -373.828818) (xy 173.519592 -374.114822) (xy 173.519776 -374.121696)
			(xy 173.52339 -374.134959) (xy 173.526704 -374.140984) (xy 173.543004 -374.16936) (xy 173.568749 -374.229523)
			(xy 173.586178 -374.292599) (xy 173.594975 -374.357444) (xy 173.594977 -374.390158) (xy 177.023784 -374.390158)
			(xy 177.027775 -374.327991) (xy 177.039684 -374.266844) (xy 177.059313 -374.207723) (xy 177.086342 -374.151597)
			(xy 177.120326 -374.099388) (xy 177.160708 -374.051953) (xy 177.206824 -374.010072) (xy 177.257916 -373.974432)
			(xy 177.313147 -373.945618) (xy 177.371609 -373.924104) (xy 177.432343 -373.910242) (xy 177.49435 -373.90426)
			(xy 177.556613 -373.906256) (xy 177.61811 -373.916199) (xy 177.677831 -373.933923) (xy 177.734794 -373.95914)
			(xy 177.788065 -373.991433) (xy 177.83677 -374.030273) (xy 177.880107 -374.075023) (xy 177.917367 -374.124947)
			(xy 177.947936 -374.179226) (xy 177.971314 -374.236969) (xy 177.987115 -374.297227) (xy 177.995081 -374.35901)
			(xy 177.99558 -374.390158) (xy 177.995081 -374.421306) (xy 177.987115 -374.483089) (xy 177.971314 -374.543347)
			(xy 177.947936 -374.60109) (xy 177.917367 -374.655369) (xy 177.880107 -374.705293) (xy 177.83677 -374.750043)
			(xy 177.788065 -374.788883) (xy 177.734794 -374.821176) (xy 177.677831 -374.846393) (xy 177.61811 -374.864117)
			(xy 177.556613 -374.87406) (xy 177.49435 -374.876056) (xy 177.432343 -374.870074) (xy 177.371609 -374.856212)
			(xy 177.313147 -374.834698) (xy 177.257916 -374.805884) (xy 177.206824 -374.770244) (xy 177.160708 -374.728363)
			(xy 177.120326 -374.680928) (xy 177.086342 -374.628719) (xy 177.059313 -374.572593) (xy 177.039684 -374.513472)
			(xy 177.027775 -374.452325) (xy 177.023784 -374.390158) (xy 173.594977 -374.390158) (xy 173.59498 -374.422884)
			(xy 173.586193 -374.487731) (xy 173.568773 -374.550809) (xy 173.543037 -374.610975) (xy 173.526704 -374.639332)
			(xy 173.523378 -374.645351) (xy 173.519779 -374.658619) (xy 173.519592 -374.665494) (xy 173.519592 -375.414794)
			(xy 173.519787 -375.421667) (xy 173.523393 -375.43493) (xy 173.526704 -375.440956) (xy 173.543065 -375.469299)
			(xy 173.568805 -375.529469) (xy 173.586227 -375.592552) (xy 173.595016 -375.657403) (xy 173.595012 -375.722848)
			(xy 173.586216 -375.787699) (xy 173.568788 -375.85078) (xy 173.543042 -375.910947) (xy 173.526704 -375.939304)
			(xy 173.523388 -375.945328) (xy 173.519783 -375.958592) (xy 173.519592 -375.965466) (xy 173.519592 -376.25147)
			(xy 173.519043 -376.261622) (xy 173.511284 -376.280385) (xy 173.496935 -376.29475) (xy 173.478182 -376.302531)
			(xy 173.46803 -376.303032) (xy 172.75175 -376.303032) (xy 172.741578 -376.302595) (xy 172.722779 -376.29482)
			(xy 172.708391 -376.280438) (xy 172.700609 -376.261642) (xy 172.700188 -376.25147) (xy 172.700188 -375.965466)
			(xy 172.700011 -375.958592) (xy 172.696393 -375.945329) (xy 172.693076 -375.939304) (xy 172.676763 -375.910934)
			(xy 172.651015 -375.850771) (xy 172.633584 -375.787694) (xy 172.624787 -375.722846) (xy 172.624784 -375.657405)
			(xy 172.633574 -375.592557) (xy 172.650998 -375.529478) (xy 172.676739 -375.469312) (xy 172.693076 -375.440956)
			(xy 172.696405 -375.434938) (xy 172.700002 -375.421669) (xy 172.700188 -375.414794) (xy 172.700188 -374.665494)
			(xy 172.7 -374.65862) (xy 172.696389 -374.645358) (xy 172.693076 -374.639332) (xy 172.676702 -374.610996)
			(xy 172.650959 -374.550825) (xy 172.633535 -374.487741) (xy 172.624746 -374.422887) (xy 169.195204 -374.422887)
			(xy 169.186415 -374.487732) (xy 169.168993 -374.550811) (xy 169.143252 -374.610976) (xy 169.126916 -374.639332)
			(xy 169.123591 -374.645352) (xy 169.119992 -374.658619) (xy 169.119804 -374.665494) (xy 169.119804 -375.414794)
			(xy 169.119998 -375.421667) (xy 169.123605 -375.43493) (xy 169.126916 -375.440956) (xy 169.14328 -375.469298)
			(xy 169.169024 -375.529467) (xy 169.186449 -375.59255) (xy 169.19524 -375.657403) (xy 169.195237 -375.722849)
			(xy 169.186439 -375.7877) (xy 169.169007 -375.850781) (xy 169.143257 -375.910948) (xy 169.126916 -375.939304)
			(xy 169.123601 -375.945329) (xy 169.119995 -375.958592) (xy 169.119804 -375.965466) (xy 169.119804 -376.25147)
			(xy 169.119243 -376.261621) (xy 169.111487 -376.280381) (xy 169.097142 -376.294746) (xy 169.078392 -376.302529)
			(xy 169.068242 -376.303032) (xy 168.351962 -376.303032) (xy 168.341798 -376.302597) (xy 168.323022 -376.294804)
			(xy 168.308657 -376.280421) (xy 168.30089 -376.261635) (xy 168.3004 -376.25147) (xy 168.3004 -375.965466)
			(xy 168.300221 -375.958592) (xy 168.296604 -375.945329) (xy 168.293288 -375.939304) (xy 168.276975 -375.910934)
			(xy 168.251226 -375.850771) (xy 168.233795 -375.787694) (xy 168.224998 -375.722846) (xy 168.224994 -375.657405)
			(xy 168.233784 -375.592557) (xy 168.251209 -375.529477) (xy 168.276951 -375.469312) (xy 168.293288 -375.440956)
			(xy 168.296618 -375.434939) (xy 168.300214 -375.421669) (xy 168.3004 -375.414794) (xy 168.3004 -374.665494)
			(xy 168.30021 -374.658621) (xy 168.296601 -374.645358) (xy 168.293288 -374.639332) (xy 168.276913 -374.610996)
			(xy 168.25117 -374.550825) (xy 168.233746 -374.487741) (xy 168.224957 -374.422887) (xy 164.795154 -374.422887)
			(xy 164.786366 -374.487731) (xy 164.768946 -374.55081) (xy 164.743208 -374.610976) (xy 164.726874 -374.639332)
			(xy 164.723501 -374.645342) (xy 164.719771 -374.658606) (xy 164.719508 -374.665494) (xy 164.719508 -375.414794)
			(xy 164.719743 -375.421685) (xy 164.723484 -375.434951) (xy 164.726874 -375.440956) (xy 164.743236 -375.469298)
			(xy 164.768977 -375.529468) (xy 164.7864 -375.592551) (xy 164.79519 -375.657403) (xy 164.795186 -375.722848)
			(xy 164.78639 -375.787699) (xy 164.76896 -375.85078) (xy 164.743213 -375.910948) (xy 164.726874 -375.939304)
			(xy 164.72351 -375.945319) (xy 164.719774 -375.958579) (xy 164.719508 -375.965466) (xy 164.719508 -376.25147)
			(xy 164.71895 -376.261589) (xy 164.711241 -376.2803) (xy 164.696977 -376.294656) (xy 164.678316 -376.302485)
			(xy 164.6682 -376.303032) (xy 163.95192 -376.303032) (xy 163.941771 -376.302563) (xy 163.923025 -376.29478)
			(xy 163.908702 -376.280398) (xy 163.900996 -376.26162) (xy 163.900612 -376.25147) (xy 163.900612 -375.965466)
			(xy 163.900387 -375.958573) (xy 163.896653 -375.9453) (xy 163.893246 -375.939304) (xy 163.876934 -375.910934)
			(xy 163.851187 -375.85077) (xy 163.833758 -375.787693) (xy 163.824961 -375.722846) (xy 163.824958 -375.657405)
			(xy 163.833747 -375.592557) (xy 163.85117 -375.529478) (xy 163.87691 -375.469312) (xy 163.893246 -375.440956)
			(xy 163.896625 -375.434948) (xy 163.900351 -375.421682) (xy 163.900612 -375.414794) (xy 163.900612 -374.665494)
			(xy 163.900415 -374.658598) (xy 163.896663 -374.645326) (xy 163.893246 -374.639332) (xy 163.876873 -374.610996)
			(xy 163.851132 -374.550824) (xy 163.833709 -374.48774) (xy 163.82492 -374.422887) (xy 160.395118 -374.422887)
			(xy 160.386329 -374.487732) (xy 160.368907 -374.550811) (xy 160.343167 -374.610976) (xy 160.326832 -374.639332)
			(xy 160.323509 -374.645352) (xy 160.319908 -374.658619) (xy 160.31972 -374.665494) (xy 160.31972 -375.414794)
			(xy 160.319912 -375.421667) (xy 160.32352 -375.43493) (xy 160.326832 -375.440956) (xy 160.343196 -375.469298)
			(xy 160.368939 -375.529468) (xy 160.386363 -375.592551) (xy 160.395154 -375.657403) (xy 160.39515 -375.722848)
			(xy 160.386353 -375.7877) (xy 160.368922 -375.850781) (xy 160.343172 -375.910948) (xy 160.326832 -375.939304)
			(xy 160.323519 -375.945329) (xy 160.319912 -375.958592) (xy 160.31972 -375.965466) (xy 160.31972 -376.25147)
			(xy 160.31931 -376.261645) (xy 160.311528 -376.280447) (xy 160.297137 -376.294834) (xy 160.278333 -376.302613)
			(xy 160.268158 -376.303032) (xy 159.551878 -376.303032) (xy 159.541701 -376.302653) (xy 159.5229 -376.294855)
			(xy 159.508515 -376.280456) (xy 159.500737 -376.261647) (xy 159.500316 -376.25147) (xy 159.500316 -375.965466)
			(xy 159.500135 -375.958592) (xy 159.496519 -375.945329) (xy 159.493204 -375.939304) (xy 159.476893 -375.910933)
			(xy 159.451149 -375.85077) (xy 159.433721 -375.787693) (xy 159.424925 -375.722846) (xy 159.424922 -375.657405)
			(xy 159.43371 -375.592558) (xy 159.451132 -375.529479) (xy 159.47687 -375.469313) (xy 159.493204 -375.440956)
			(xy 159.496535 -375.434939) (xy 159.50013 -375.421669) (xy 159.500316 -375.414794) (xy 159.500316 -374.665494)
			(xy 159.500124 -374.658621) (xy 159.496516 -374.645358) (xy 159.493204 -374.639332) (xy 159.476832 -374.610995)
			(xy 159.451093 -374.550824) (xy 159.433672 -374.487739) (xy 159.424884 -374.422887) (xy 136.845294 -374.422887)
			(xy 136.845294 -376.822925) (xy 161.624805 -376.822925) (xy 161.624805 -376.757482) (xy 161.633597 -376.692633)
			(xy 161.651021 -376.629554) (xy 161.676762 -376.569387) (xy 161.693098 -376.54103) (xy 161.696448 -376.535008)
			(xy 161.700193 -376.521753) (xy 161.700464 -376.514868) (xy 161.700464 -375.765568) (xy 161.700231 -375.758675)
			(xy 161.696503 -375.745403) (xy 161.693098 -375.739406) (xy 161.676789 -375.711034) (xy 161.651045 -375.650871)
			(xy 161.633617 -375.587794) (xy 161.624821 -375.522948) (xy 161.624818 -375.457507) (xy 161.633606 -375.39266)
			(xy 161.651027 -375.329581) (xy 161.676764 -375.269415) (xy 161.693098 -375.241058) (xy 161.696473 -375.235048)
			(xy 161.700202 -375.221784) (xy 161.700464 -375.214896) (xy 161.700464 -374.928638) (xy 161.700959 -374.918511)
			(xy 161.708678 -374.899786) (xy 161.722963 -374.885428) (xy 161.741647 -374.877611) (xy 161.751772 -374.877076)
			(xy 162.468052 -374.877076) (xy 162.4782 -374.877561) (xy 162.496947 -374.885336) (xy 162.511271 -374.899713)
			(xy 162.518977 -374.918489) (xy 162.51936 -374.928638) (xy 162.51936 -375.214896) (xy 162.519565 -375.221791)
			(xy 162.523312 -375.235063) (xy 162.526726 -375.241058) (xy 162.543092 -375.269399) (xy 162.568835 -375.329569)
			(xy 162.58626 -375.392652) (xy 162.59505 -375.457505) (xy 162.595046 -375.52295) (xy 162.586248 -375.587802)
			(xy 162.568817 -375.650883) (xy 162.543067 -375.71105) (xy 162.526726 -375.739406) (xy 162.523358 -375.745419)
			(xy 162.519625 -375.758681) (xy 162.51936 -375.765568) (xy 162.51936 -376.514868) (xy 162.519576 -376.521762)
			(xy 162.523316 -376.535034) (xy 162.526726 -376.54103) (xy 162.543068 -376.569384) (xy 162.568813 -376.629551)
			(xy 162.586241 -376.692631) (xy 162.595034 -376.757482) (xy 162.595033 -376.822925) (xy 166.024841 -376.822925)
			(xy 166.024841 -376.757482) (xy 166.033634 -376.692633) (xy 166.051059 -376.629553) (xy 166.076803 -376.569386)
			(xy 166.09314 -376.54103) (xy 166.096439 -376.534998) (xy 166.100055 -376.52174) (xy 166.100252 -376.514868)
			(xy 166.100252 -375.765568) (xy 166.100078 -375.758693) (xy 166.096458 -375.74543) (xy 166.09314 -375.739406)
			(xy 166.07683 -375.711035) (xy 166.051083 -375.650872) (xy 166.033654 -375.587795) (xy 166.024857 -375.522948)
			(xy 166.024854 -375.457507) (xy 166.033643 -375.392659) (xy 166.051065 -375.32958) (xy 166.076805 -375.269414)
			(xy 166.09314 -375.241058) (xy 166.096465 -375.235038) (xy 166.100065 -375.221771) (xy 166.100252 -375.214896)
			(xy 166.100252 -374.928638) (xy 166.100695 -374.918467) (xy 166.10847 -374.899671) (xy 166.12285 -374.885284)
			(xy 166.141643 -374.8775) (xy 166.151814 -374.877076) (xy 166.868094 -374.877076) (xy 166.87827 -374.87747)
			(xy 166.897072 -374.88526) (xy 166.911458 -374.899655) (xy 166.919237 -374.918462) (xy 166.919656 -374.928638)
			(xy 166.919656 -375.214896) (xy 166.919842 -375.22177) (xy 166.923454 -375.235033) (xy 166.926768 -375.241058)
			(xy 166.943132 -375.269399) (xy 166.968873 -375.32957) (xy 166.986296 -375.392653) (xy 166.995086 -375.457505)
			(xy 166.995082 -375.52295) (xy 166.986285 -375.587801) (xy 166.968855 -375.650882) (xy 166.943107 -375.71105)
			(xy 166.926768 -375.739406) (xy 166.923449 -375.745428) (xy 166.919847 -375.758694) (xy 166.919656 -375.765568)
			(xy 166.919656 -376.514868) (xy 166.919853 -376.521741) (xy 166.923457 -376.535004) (xy 166.926768 -376.54103)
			(xy 166.943109 -376.569384) (xy 166.968852 -376.629552) (xy 166.986278 -376.692632) (xy 166.99507 -376.757482)
			(xy 170.424877 -376.757482) (xy 170.43367 -376.692632) (xy 170.451098 -376.629552) (xy 170.476844 -376.569386)
			(xy 170.493182 -376.54103) (xy 170.49653 -376.535007) (xy 170.500277 -376.521753) (xy 170.500548 -376.514868)
			(xy 170.500548 -375.765568) (xy 170.500317 -375.758675) (xy 170.496587 -375.745403) (xy 170.493182 -375.739406)
			(xy 170.47687 -375.711035) (xy 170.451122 -375.650872) (xy 170.433691 -375.587795) (xy 170.424894 -375.522948)
			(xy 170.42489 -375.457507) (xy 170.43368 -375.392658) (xy 170.451104 -375.329579) (xy 170.476845 -375.269414)
			(xy 170.493182 -375.241058) (xy 170.496556 -375.235048) (xy 170.500286 -375.221784) (xy 170.500548 -375.214896)
			(xy 170.500548 -374.928638) (xy 170.501058 -374.918513) (xy 170.508775 -374.899791) (xy 170.523054 -374.885433)
			(xy 170.541734 -374.877614) (xy 170.551856 -374.877076) (xy 171.268136 -374.877076) (xy 171.278289 -374.877492)
			(xy 171.297038 -374.885295) (xy 171.311359 -374.899692) (xy 171.319062 -374.918482) (xy 171.319444 -374.928638)
			(xy 171.319444 -375.214896) (xy 171.319651 -375.221791) (xy 171.323397 -375.235063) (xy 171.32681 -375.241058)
			(xy 171.343176 -375.269399) (xy 171.36892 -375.329568) (xy 171.386345 -375.392652) (xy 171.395136 -375.457505)
			(xy 171.395132 -375.52295) (xy 171.386334 -375.587802) (xy 171.368902 -375.650883) (xy 171.343151 -375.71105)
			(xy 171.32681 -375.739406) (xy 171.323448 -375.745422) (xy 171.31971 -375.758682) (xy 171.319444 -375.765568)
			(xy 171.319444 -376.514868) (xy 171.319662 -376.521762) (xy 171.323401 -376.535034) (xy 171.32681 -376.54103)
			(xy 171.343152 -376.569384) (xy 171.368899 -376.62955) (xy 171.386327 -376.692631) (xy 171.39512 -376.757481)
			(xy 171.39512 -376.757482) (xy 174.824927 -376.757482) (xy 174.833719 -376.692633) (xy 174.851145 -376.629553)
			(xy 174.876887 -376.569386) (xy 174.893224 -376.54103) (xy 174.89653 -376.535001) (xy 174.900141 -376.521741)
			(xy 174.900336 -376.514868) (xy 174.900336 -375.765568) (xy 174.900152 -375.758694) (xy 174.896538 -375.745432)
			(xy 174.893224 -375.739406) (xy 174.876914 -375.711035) (xy 174.851169 -375.650871) (xy 174.83374 -375.587794)
			(xy 174.824944 -375.522948) (xy 174.82494 -375.457507) (xy 174.833729 -375.392659) (xy 174.85115 -375.329581)
			(xy 174.876889 -375.269414) (xy 174.893224 -375.241058) (xy 174.896555 -375.235042) (xy 174.90015 -375.221771)
			(xy 174.900336 -375.214896) (xy 174.900336 -374.928638) (xy 174.900795 -374.918469) (xy 174.908567 -374.899676)
			(xy 174.922942 -374.88529) (xy 174.941729 -374.877503) (xy 174.951898 -374.877076) (xy 175.668178 -374.877076)
			(xy 175.678353 -374.877483) (xy 175.697154 -374.885268) (xy 175.711541 -374.899659) (xy 175.71932 -374.918463)
			(xy 175.71974 -374.928638) (xy 175.71974 -375.214896) (xy 175.719929 -375.22177) (xy 175.723539 -375.235032)
			(xy 175.726852 -375.241058) (xy 175.743217 -375.269399) (xy 175.768959 -375.329569) (xy 175.786382 -375.392652)
			(xy 175.795172 -375.457505) (xy 175.795168 -375.52295) (xy 175.786371 -375.587801) (xy 175.76894 -375.650883)
			(xy 175.752145 -375.69013) (xy 177.023784 -375.69013) (xy 177.027775 -375.627963) (xy 177.039684 -375.566816)
			(xy 177.059313 -375.507695) (xy 177.086342 -375.451569) (xy 177.120326 -375.39936) (xy 177.160708 -375.351925)
			(xy 177.206824 -375.310044) (xy 177.257916 -375.274404) (xy 177.313147 -375.24559) (xy 177.371609 -375.224076)
			(xy 177.432343 -375.210214) (xy 177.49435 -375.204232) (xy 177.556613 -375.206228) (xy 177.61811 -375.216171)
			(xy 177.677831 -375.233895) (xy 177.734794 -375.259112) (xy 177.788065 -375.291405) (xy 177.83677 -375.330245)
			(xy 177.880107 -375.374995) (xy 177.917367 -375.424919) (xy 177.947936 -375.479198) (xy 177.952403 -375.490232)
			(xy 179.223932 -375.490232) (xy 179.227923 -375.428065) (xy 179.239832 -375.366918) (xy 179.259461 -375.307797)
			(xy 179.28649 -375.251671) (xy 179.320474 -375.199462) (xy 179.360856 -375.152027) (xy 179.406972 -375.110146)
			(xy 179.458064 -375.074506) (xy 179.513295 -375.045692) (xy 179.571757 -375.024178) (xy 179.632491 -375.010316)
			(xy 179.694498 -375.004334) (xy 179.756761 -375.00633) (xy 179.818258 -375.016273) (xy 179.877979 -375.033997)
			(xy 179.934942 -375.059214) (xy 179.988213 -375.091507) (xy 180.036918 -375.130347) (xy 180.080255 -375.175097)
			(xy 180.117515 -375.225021) (xy 180.148084 -375.2793) (xy 180.171462 -375.337043) (xy 180.187263 -375.397301)
			(xy 180.195229 -375.459084) (xy 180.195728 -375.490232) (xy 180.195229 -375.52138) (xy 180.187263 -375.583163)
			(xy 180.171462 -375.643421) (xy 180.148084 -375.701164) (xy 180.117515 -375.755443) (xy 180.080255 -375.805367)
			(xy 180.036918 -375.850117) (xy 179.988213 -375.888957) (xy 179.934942 -375.92125) (xy 179.877979 -375.946467)
			(xy 179.818258 -375.964191) (xy 179.756761 -375.974134) (xy 179.694498 -375.97613) (xy 179.632491 -375.970148)
			(xy 179.571757 -375.956286) (xy 179.513295 -375.934772) (xy 179.458064 -375.905958) (xy 179.406972 -375.870318)
			(xy 179.360856 -375.828437) (xy 179.320474 -375.781002) (xy 179.28649 -375.728793) (xy 179.259461 -375.672667)
			(xy 179.239832 -375.613546) (xy 179.227923 -375.552399) (xy 179.223932 -375.490232) (xy 177.952403 -375.490232)
			(xy 177.971314 -375.536941) (xy 177.987115 -375.597199) (xy 177.995081 -375.658982) (xy 177.99558 -375.69013)
			(xy 177.995081 -375.721278) (xy 177.987115 -375.783061) (xy 177.971314 -375.843319) (xy 177.947936 -375.901062)
			(xy 177.917367 -375.955341) (xy 177.880107 -376.005265) (xy 177.83677 -376.050015) (xy 177.788065 -376.088855)
			(xy 177.734794 -376.121148) (xy 177.677831 -376.146365) (xy 177.61811 -376.164089) (xy 177.556613 -376.174032)
			(xy 177.49435 -376.176028) (xy 177.432343 -376.170046) (xy 177.371609 -376.156184) (xy 177.313147 -376.13467)
			(xy 177.257916 -376.105856) (xy 177.206824 -376.070216) (xy 177.160708 -376.028335) (xy 177.120326 -375.9809)
			(xy 177.086342 -375.928691) (xy 177.059313 -375.872565) (xy 177.039684 -375.813444) (xy 177.027775 -375.752297)
			(xy 177.023784 -375.69013) (xy 175.752145 -375.69013) (xy 175.743192 -375.71105) (xy 175.726852 -375.739406)
			(xy 175.723539 -375.745432) (xy 175.719932 -375.758695) (xy 175.71974 -375.765568) (xy 175.71974 -376.514868)
			(xy 175.719939 -376.521741) (xy 175.723542 -376.535004) (xy 175.726852 -376.54103) (xy 175.743193 -376.569384)
			(xy 175.768937 -376.629551) (xy 175.786363 -376.692632) (xy 175.795156 -376.757482) (xy 175.795156 -376.790204)
			(xy 179.223932 -376.790204) (xy 179.227923 -376.728037) (xy 179.239832 -376.66689) (xy 179.259461 -376.607769)
			(xy 179.28649 -376.551643) (xy 179.320474 -376.499434) (xy 179.360856 -376.451999) (xy 179.406972 -376.410118)
			(xy 179.458064 -376.374478) (xy 179.513295 -376.345664) (xy 179.571757 -376.32415) (xy 179.632491 -376.310288)
			(xy 179.694498 -376.304306) (xy 179.756761 -376.306302) (xy 179.818258 -376.316245) (xy 179.877979 -376.333969)
			(xy 179.934942 -376.359186) (xy 179.988213 -376.391479) (xy 180.036918 -376.430319) (xy 180.080255 -376.475069)
			(xy 180.117515 -376.524993) (xy 180.148084 -376.579272) (xy 180.171462 -376.637015) (xy 180.187263 -376.697273)
			(xy 180.195229 -376.759056) (xy 180.195728 -376.790204) (xy 180.195229 -376.821352) (xy 180.187263 -376.883135)
			(xy 180.171462 -376.943393) (xy 180.148084 -377.001136) (xy 180.117515 -377.055415) (xy 180.080255 -377.105339)
			(xy 180.036918 -377.150089) (xy 179.988213 -377.188929) (xy 179.934942 -377.221222) (xy 179.877979 -377.246439)
			(xy 179.818258 -377.264163) (xy 179.756761 -377.274106) (xy 179.694498 -377.276102) (xy 179.632491 -377.27012)
			(xy 179.571757 -377.256258) (xy 179.513295 -377.234744) (xy 179.458064 -377.20593) (xy 179.406972 -377.17029)
			(xy 179.360856 -377.128409) (xy 179.320474 -377.080974) (xy 179.28649 -377.028765) (xy 179.259461 -376.972639)
			(xy 179.239832 -376.913518) (xy 179.227923 -376.852371) (xy 179.223932 -376.790204) (xy 175.795156 -376.790204)
			(xy 175.795156 -376.822925) (xy 175.786362 -376.887775) (xy 175.768935 -376.950855) (xy 175.74319 -377.011022)
			(xy 175.726852 -377.039378) (xy 175.723549 -377.045409) (xy 175.719935 -377.058668) (xy 175.71974 -377.06554)
			(xy 175.71974 -377.35129) (xy 175.719328 -377.361464) (xy 175.711542 -377.380262) (xy 175.697152 -377.394648)
			(xy 175.678352 -377.40243) (xy 175.668178 -377.402852) (xy 174.951898 -377.402852) (xy 174.941725 -377.402438)
			(xy 174.922928 -377.39465) (xy 174.908543 -377.380262) (xy 174.90076 -377.361463) (xy 174.900336 -377.35129)
			(xy 174.900336 -377.06554) (xy 174.900124 -377.058668) (xy 174.896529 -377.045406) (xy 174.893224 -377.039378)
			(xy 174.87689 -377.01102) (xy 174.851147 -376.950853) (xy 174.833721 -376.887774) (xy 174.824928 -376.822925)
			(xy 174.824927 -376.757482) (xy 171.39512 -376.757482) (xy 171.39512 -376.822925) (xy 171.386325 -376.887776)
			(xy 171.368896 -376.950856) (xy 171.343149 -377.011022) (xy 171.32681 -377.039378) (xy 171.323458 -377.045399)
			(xy 171.319714 -377.058655) (xy 171.319444 -377.06554) (xy 171.319444 -377.35129) (xy 171.318965 -377.361418)
			(xy 171.311237 -377.380142) (xy 171.296948 -377.394499) (xy 171.278262 -377.402316) (xy 171.268136 -377.402852)
			(xy 170.551856 -377.402852) (xy 170.541706 -377.402415) (xy 170.522962 -377.394615) (xy 170.508642 -377.380224)
			(xy 170.500935 -377.361442) (xy 170.500548 -377.35129) (xy 170.500548 -377.06554) (xy 170.500328 -377.058646)
			(xy 170.496591 -377.045374) (xy 170.493182 -377.039378) (xy 170.476847 -377.01102) (xy 170.4511 -376.950855)
			(xy 170.433672 -376.887775) (xy 170.424878 -376.822925) (xy 170.424877 -376.757482) (xy 166.99507 -376.757482)
			(xy 166.995069 -376.822925) (xy 166.986276 -376.887775) (xy 166.968849 -376.950855) (xy 166.943105 -377.011022)
			(xy 166.926768 -377.039378) (xy 166.923459 -377.045405) (xy 166.91985 -377.058667) (xy 166.919656 -377.06554)
			(xy 166.919656 -377.35129) (xy 166.919228 -377.361462) (xy 166.911445 -377.380257) (xy 166.897061 -377.394643)
			(xy 166.878266 -377.402427) (xy 166.868094 -377.402852) (xy 166.151814 -377.402852) (xy 166.141642 -377.402425)
			(xy 166.122846 -377.394642) (xy 166.10846 -377.380258) (xy 166.100676 -377.361462) (xy 166.100252 -377.35129)
			(xy 166.100252 -377.06554) (xy 166.100051 -377.058667) (xy 166.09645 -377.045404) (xy 166.09314 -377.039378)
			(xy 166.076806 -377.01102) (xy 166.051062 -376.950854) (xy 166.033635 -376.887774) (xy 166.024841 -376.822925)
			(xy 162.595033 -376.822925) (xy 162.586239 -376.887775) (xy 162.568811 -376.950856) (xy 162.543065 -377.011022)
			(xy 162.526726 -377.039378) (xy 162.523368 -377.045396) (xy 162.519629 -377.058654) (xy 162.51936 -377.06554)
			(xy 162.51936 -377.35129) (xy 162.518865 -377.361416) (xy 162.511141 -377.380137) (xy 162.496857 -377.394494)
			(xy 162.478175 -377.402313) (xy 162.468052 -377.402852) (xy 161.751772 -377.402852) (xy 161.741623 -377.402402)
			(xy 161.72288 -377.394607) (xy 161.708559 -377.38022) (xy 161.700851 -377.361441) (xy 161.700464 -377.35129)
			(xy 161.700464 -377.06554) (xy 161.700242 -377.058646) (xy 161.696506 -377.045374) (xy 161.693098 -377.039378)
			(xy 161.676765 -377.01102) (xy 161.651023 -376.950853) (xy 161.633598 -376.887773) (xy 161.624805 -376.822925)
			(xy 136.845294 -376.822925) (xy 136.845294 -378.68733) (xy 149.188168 -378.68733) (xy 149.192239 -378.631708)
			(xy 149.204365 -378.577271) (xy 149.224288 -378.52518) (xy 149.251584 -378.476545) (xy 149.28567 -378.432402)
			(xy 149.325819 -378.393693) (xy 149.371177 -378.361242) (xy 149.420777 -378.335741) (xy 149.473561 -378.317734)
			(xy 149.528404 -378.307604) (xy 149.584138 -378.305567) (xy 149.639575 -378.311667) (xy 149.68216 -378.3228)
			(xy 159.424893 -378.3228) (xy 159.424896 -378.257356) (xy 159.433692 -378.192505) (xy 159.45112 -378.129424)
			(xy 159.476866 -378.069257) (xy 159.493204 -378.0409) (xy 159.496519 -378.034876) (xy 159.500124 -378.021612)
			(xy 159.500316 -378.014738) (xy 159.500316 -377.728734) (xy 159.500791 -377.718567) (xy 159.508561 -377.699778)
			(xy 159.522931 -377.685392) (xy 159.541712 -377.677602) (xy 159.551878 -377.677172) (xy 160.268158 -377.677172)
			(xy 160.278331 -377.677599) (xy 160.297131 -377.685377) (xy 160.311519 -377.699762) (xy 160.319299 -377.718561)
			(xy 160.31972 -377.728734) (xy 160.31972 -378.014738) (xy 160.319933 -378.02161) (xy 160.323527 -378.034873)
			(xy 160.326832 -378.0409) (xy 160.343148 -378.069268) (xy 160.368896 -378.129432) (xy 160.386326 -378.192509)
			(xy 160.395122 -378.257357) (xy 160.395125 -378.322798) (xy 160.395125 -378.3228) (xy 163.82493 -378.3228)
			(xy 163.824933 -378.257355) (xy 163.833729 -378.192504) (xy 163.851159 -378.129423) (xy 163.876907 -378.069256)
			(xy 163.893246 -378.0409) (xy 163.89661 -378.034885) (xy 163.900345 -378.021625) (xy 163.900612 -378.014738)
			(xy 163.900612 -377.728734) (xy 163.901154 -377.718613) (xy 163.908865 -377.699898) (xy 163.923134 -377.685542)
			(xy 163.941802 -377.677716) (xy 163.95192 -377.677172) (xy 164.6682 -377.677172) (xy 164.678351 -377.677621)
			(xy 164.697098 -377.685411) (xy 164.71142 -377.699799) (xy 164.719125 -377.718582) (xy 164.719508 -377.728734)
			(xy 164.719508 -378.014738) (xy 164.719764 -378.021628) (xy 164.723491 -378.034894) (xy 164.726874 -378.0409)
			(xy 164.743189 -378.069268) (xy 164.768934 -378.129432) (xy 164.786363 -378.19251) (xy 164.795158 -378.257357)
			(xy 164.795161 -378.322798) (xy 164.795161 -378.3228) (xy 168.224966 -378.3228) (xy 168.224969 -378.257355)
			(xy 168.233766 -378.192504) (xy 168.251197 -378.129422) (xy 168.276947 -378.069256) (xy 168.293288 -378.0409)
			(xy 168.296602 -378.034875) (xy 168.300208 -378.021612) (xy 168.3004 -378.014738) (xy 168.3004 -377.728734)
			(xy 168.30096 -377.718583) (xy 168.308717 -377.699822) (xy 168.323062 -377.685457) (xy 168.341812 -377.677675)
			(xy 168.351962 -377.677172) (xy 169.068242 -377.677172) (xy 169.078407 -377.6776) (xy 169.097183 -377.685394)
			(xy 169.111548 -377.699781) (xy 169.119315 -377.718569) (xy 169.119804 -377.728734) (xy 169.119804 -378.014738)
			(xy 169.120019 -378.02161) (xy 169.123612 -378.034872) (xy 169.126916 -378.0409) (xy 169.143233 -378.069268)
			(xy 169.168981 -378.129431) (xy 169.186412 -378.192509) (xy 169.195208 -378.257357) (xy 169.195211 -378.322799)
			(xy 169.195211 -378.3228) (xy 172.624755 -378.3228) (xy 172.624758 -378.257355) (xy 172.633555 -378.192504)
			(xy 172.650986 -378.129423) (xy 172.676736 -378.069256) (xy 172.693076 -378.0409) (xy 172.696389 -378.034874)
			(xy 172.699996 -378.021611) (xy 172.700188 -378.014738) (xy 172.700188 -377.728734) (xy 172.700593 -377.718558)
			(xy 172.708376 -377.699755) (xy 172.722768 -377.685367) (xy 172.741574 -377.67759) (xy 172.75175 -377.677172)
			(xy 173.46803 -377.677172) (xy 173.478208 -377.67754) (xy 173.49701 -377.685341) (xy 173.511395 -377.699744)
			(xy 173.519173 -377.718556) (xy 173.519592 -377.728734) (xy 173.519592 -378.014738) (xy 173.519809 -378.021609)
			(xy 173.5234 -378.034872) (xy 173.526704 -378.0409) (xy 173.543018 -378.069269) (xy 173.568762 -378.129433)
			(xy 173.586189 -378.19251) (xy 173.594984 -378.257357) (xy 173.594985 -378.290074) (xy 177.023784 -378.290074)
			(xy 177.027775 -378.227907) (xy 177.039684 -378.16676) (xy 177.059313 -378.107639) (xy 177.086342 -378.051513)
			(xy 177.120326 -377.999304) (xy 177.160708 -377.951869) (xy 177.206824 -377.909988) (xy 177.257916 -377.874348)
			(xy 177.313147 -377.845534) (xy 177.371609 -377.82402) (xy 177.432343 -377.810158) (xy 177.49435 -377.804176)
			(xy 177.556613 -377.806172) (xy 177.61811 -377.816115) (xy 177.677831 -377.833839) (xy 177.734794 -377.859056)
			(xy 177.788065 -377.891349) (xy 177.83677 -377.930189) (xy 177.880107 -377.974939) (xy 177.917367 -378.024863)
			(xy 177.947936 -378.079142) (xy 177.971314 -378.136885) (xy 177.987115 -378.197143) (xy 177.995081 -378.258926)
			(xy 177.99558 -378.290074) (xy 177.995081 -378.321222) (xy 177.987115 -378.383005) (xy 177.971314 -378.443263)
			(xy 177.947936 -378.501006) (xy 177.917367 -378.555285) (xy 177.880107 -378.605209) (xy 177.83677 -378.649959)
			(xy 177.788065 -378.688799) (xy 177.734794 -378.721092) (xy 177.677831 -378.746309) (xy 177.61811 -378.764033)
			(xy 177.600928 -378.766811) (xy 193.48983 -378.766811) (xy 193.48983 -378.633249) (xy 193.497894 -378.499931)
			(xy 193.513994 -378.367343) (xy 193.538069 -378.235969) (xy 193.570032 -378.106288) (xy 193.609767 -377.978774)
			(xy 193.657129 -377.853891) (xy 193.711944 -377.732096) (xy 193.774014 -377.613833) (xy 193.84311 -377.499534)
			(xy 193.918982 -377.389614) (xy 194.001352 -377.284477) (xy 194.08992 -377.184504) (xy 194.184362 -377.090062)
			(xy 194.284335 -377.001494) (xy 194.389472 -376.919124) (xy 194.499392 -376.843252) (xy 194.613691 -376.774156)
			(xy 194.731954 -376.712086) (xy 194.853749 -376.657271) (xy 194.978632 -376.609909) (xy 195.106146 -376.570174)
			(xy 195.235827 -376.538211) (xy 195.367201 -376.514136) (xy 195.499789 -376.498036) (xy 195.633107 -376.489972)
			(xy 195.766669 -376.489972) (xy 195.899987 -376.498036) (xy 196.032575 -376.514136) (xy 196.163949 -376.538211)
			(xy 196.29363 -376.570174) (xy 196.421144 -376.609909) (xy 196.546027 -376.657271) (xy 196.667822 -376.712086)
			(xy 196.786085 -376.774156) (xy 196.900384 -376.843252) (xy 197.010304 -376.919124) (xy 197.115441 -377.001494)
			(xy 197.215414 -377.090062) (xy 197.309856 -377.184504) (xy 197.398424 -377.284477) (xy 197.480794 -377.389614)
			(xy 197.556666 -377.499534) (xy 197.625762 -377.613833) (xy 197.687832 -377.732096) (xy 197.742647 -377.853891)
			(xy 197.790009 -377.978774) (xy 197.829744 -378.106288) (xy 197.861707 -378.235969) (xy 197.885782 -378.367343)
			(xy 197.901882 -378.499931) (xy 197.909946 -378.633249) (xy 197.91045 -378.70003) (xy 197.909946 -378.766811)
			(xy 197.901882 -378.900129) (xy 197.885782 -379.032717) (xy 197.861707 -379.164091) (xy 197.829744 -379.293772)
			(xy 197.790009 -379.421286) (xy 197.742647 -379.546169) (xy 197.687832 -379.667964) (xy 197.625762 -379.786227)
			(xy 197.556666 -379.900526) (xy 197.480794 -380.010446) (xy 197.398424 -380.115583) (xy 197.309856 -380.215556)
			(xy 197.215414 -380.309998) (xy 197.115441 -380.398566) (xy 197.010304 -380.480936) (xy 196.900384 -380.556808)
			(xy 196.786085 -380.625904) (xy 196.667822 -380.687974) (xy 196.546027 -380.742789) (xy 196.421144 -380.790151)
			(xy 196.29363 -380.829886) (xy 196.163949 -380.861849) (xy 196.032575 -380.885924) (xy 195.899987 -380.902024)
			(xy 195.766669 -380.910088) (xy 195.633107 -380.910088) (xy 195.499789 -380.902024) (xy 195.367201 -380.885924)
			(xy 195.235827 -380.861849) (xy 195.106146 -380.829886) (xy 194.978632 -380.790151) (xy 194.853749 -380.742789)
			(xy 194.731954 -380.687974) (xy 194.613691 -380.625904) (xy 194.499392 -380.556808) (xy 194.389472 -380.480936)
			(xy 194.284335 -380.398566) (xy 194.184362 -380.309998) (xy 194.08992 -380.215556) (xy 194.001352 -380.115583)
			(xy 193.918982 -380.010446) (xy 193.84311 -379.900526) (xy 193.774014 -379.786227) (xy 193.711944 -379.667964)
			(xy 193.657129 -379.546169) (xy 193.609767 -379.421286) (xy 193.570032 -379.293772) (xy 193.538069 -379.164091)
			(xy 193.513994 -379.032717) (xy 193.497894 -378.900129) (xy 193.48983 -378.766811) (xy 177.600928 -378.766811)
			(xy 177.556613 -378.773976) (xy 177.49435 -378.775972) (xy 177.432343 -378.76999) (xy 177.371609 -378.756128)
			(xy 177.313147 -378.734614) (xy 177.257916 -378.7058) (xy 177.206824 -378.67016) (xy 177.160708 -378.628279)
			(xy 177.120326 -378.580844) (xy 177.086342 -378.528635) (xy 177.059313 -378.472509) (xy 177.039684 -378.413388)
			(xy 177.027775 -378.352241) (xy 177.023784 -378.290074) (xy 173.594985 -378.290074) (xy 173.594987 -378.322798)
			(xy 173.586198 -378.387646) (xy 173.568776 -378.450725) (xy 173.543038 -378.510891) (xy 173.526704 -378.539248)
			(xy 173.523372 -378.545264) (xy 173.519777 -378.558535) (xy 173.519592 -378.56541) (xy 173.519592 -379.31471)
			(xy 173.519781 -379.321583) (xy 173.523391 -379.334846) (xy 173.526704 -379.340872) (xy 173.543079 -379.369207)
			(xy 173.568817 -379.429379) (xy 173.586238 -379.492464) (xy 173.595025 -379.557317) (xy 173.59502 -379.622762)
			(xy 173.586222 -379.687614) (xy 173.568791 -379.750695) (xy 173.543043 -379.810863) (xy 173.526704 -379.83922)
			(xy 173.523382 -379.845241) (xy 173.519781 -379.858508) (xy 173.519592 -379.865382) (xy 173.519592 -380.151386)
			(xy 173.519056 -380.161539) (xy 173.511292 -380.180302) (xy 173.496939 -380.194667) (xy 173.478183 -380.202447)
			(xy 173.46803 -380.202948) (xy 172.75175 -380.202948) (xy 172.74158 -380.202495) (xy 172.722784 -380.194724)
			(xy 172.708396 -380.180347) (xy 172.700612 -380.161556) (xy 172.700188 -380.151386) (xy 172.700188 -379.865382)
			(xy 172.700005 -379.858508) (xy 172.696391 -379.845245) (xy 172.693076 -379.83922) (xy 172.676776 -379.810843)
			(xy 172.651027 -379.750681) (xy 172.633595 -379.687606) (xy 172.624796 -379.62276) (xy 172.624791 -379.557319)
			(xy 172.633579 -379.492472) (xy 172.651001 -379.429393) (xy 172.676741 -379.369228) (xy 172.693076 -379.340872)
			(xy 172.696399 -379.334851) (xy 172.7 -379.321585) (xy 172.700188 -379.31471) (xy 172.700188 -378.56541)
			(xy 172.699994 -378.558537) (xy 172.696387 -378.545274) (xy 172.693076 -378.539248) (xy 172.676715 -378.510904)
			(xy 172.650972 -378.450735) (xy 172.633546 -378.387652) (xy 172.624755 -378.3228) (xy 169.195211 -378.3228)
			(xy 169.186421 -378.387647) (xy 169.168996 -378.450727) (xy 169.143253 -378.510892) (xy 169.126916 -378.539248)
			(xy 169.123585 -378.545265) (xy 169.119989 -378.558535) (xy 169.119804 -378.56541) (xy 169.119804 -379.31471)
			(xy 169.119991 -379.321584) (xy 169.123603 -379.334846) (xy 169.126916 -379.340872) (xy 169.143294 -379.369206)
			(xy 169.169036 -379.429377) (xy 169.18646 -379.492462) (xy 169.195249 -379.557316) (xy 169.195244 -379.622763)
			(xy 169.186444 -379.687615) (xy 169.16901 -379.750697) (xy 169.143258 -379.810864) (xy 169.126916 -379.83922)
			(xy 169.123595 -379.845242) (xy 169.119993 -379.858508) (xy 169.119804 -379.865382) (xy 169.119804 -380.151386)
			(xy 169.119256 -380.161538) (xy 169.111494 -380.180299) (xy 169.097146 -380.194663) (xy 169.078393 -380.202445)
			(xy 169.068242 -380.202948) (xy 168.351962 -380.202948) (xy 168.3418 -380.202497) (xy 168.323027 -380.194708)
			(xy 168.308663 -380.180329) (xy 168.300892 -380.161548) (xy 168.3004 -380.151386) (xy 168.3004 -379.865382)
			(xy 168.300215 -379.858508) (xy 168.296602 -379.845245) (xy 168.293288 -379.83922) (xy 168.276988 -379.810843)
			(xy 168.251238 -379.750682) (xy 168.233805 -379.687606) (xy 168.225007 -379.62276) (xy 168.225001 -379.557319)
			(xy 168.23379 -379.492472) (xy 168.251212 -379.429393) (xy 168.276952 -379.369228) (xy 168.293288 -379.340872)
			(xy 168.296612 -379.334852) (xy 168.300212 -379.321585) (xy 168.3004 -379.31471) (xy 168.3004 -378.56541)
			(xy 168.300204 -378.558537) (xy 168.296599 -378.545274) (xy 168.293288 -378.539248) (xy 168.276927 -378.510905)
			(xy 168.251183 -378.450735) (xy 168.233757 -378.387653) (xy 168.224966 -378.3228) (xy 164.795161 -378.3228)
			(xy 164.786372 -378.387646) (xy 164.768949 -378.450725) (xy 164.743209 -378.510892) (xy 164.726874 -378.539248)
			(xy 164.723495 -378.545256) (xy 164.719769 -378.558522) (xy 164.719508 -378.56541) (xy 164.719508 -379.31471)
			(xy 164.719736 -379.321602) (xy 164.723482 -379.334868) (xy 164.726874 -379.340872) (xy 164.74325 -379.369207)
			(xy 164.76899 -379.429379) (xy 164.786411 -379.492463) (xy 164.795199 -379.557316) (xy 164.795194 -379.622762)
			(xy 164.786395 -379.687614) (xy 164.768963 -379.750696) (xy 164.743214 -379.810864) (xy 164.726874 -379.83922)
			(xy 164.723505 -379.845233) (xy 164.719772 -379.858495) (xy 164.719508 -379.865382) (xy 164.719508 -380.151386)
			(xy 164.718963 -380.161506) (xy 164.711249 -380.180218) (xy 164.696981 -380.194573) (xy 164.678317 -380.202401)
			(xy 164.6682 -380.202948) (xy 163.95192 -380.202948) (xy 163.941773 -380.202463) (xy 163.92303 -380.194683)
			(xy 163.908708 -380.180306) (xy 163.900999 -380.161534) (xy 163.900612 -380.151386) (xy 163.900612 -379.865382)
			(xy 163.900381 -379.858489) (xy 163.896652 -379.845217) (xy 163.893246 -379.83922) (xy 163.876947 -379.810842)
			(xy 163.851199 -379.750681) (xy 163.833769 -379.687605) (xy 163.824971 -379.622759) (xy 163.824965 -379.55732)
			(xy 163.833753 -379.492472) (xy 163.851173 -379.429394) (xy 163.876911 -379.369228) (xy 163.893246 -379.340872)
			(xy 163.896619 -379.334862) (xy 163.900349 -379.321598) (xy 163.900612 -379.31471) (xy 163.900612 -378.56541)
			(xy 163.900409 -378.558515) (xy 163.896661 -378.545243) (xy 163.893246 -378.539248) (xy 163.876886 -378.510904)
			(xy 163.851144 -378.450735) (xy 163.83372 -378.387652) (xy 163.82493 -378.3228) (xy 160.395125 -378.3228)
			(xy 160.386335 -378.387647) (xy 160.36891 -378.450726) (xy 160.343169 -378.510892) (xy 160.326832 -378.539248)
			(xy 160.323503 -378.545266) (xy 160.319906 -378.558535) (xy 160.31972 -378.56541) (xy 160.31972 -379.31471)
			(xy 160.319906 -379.321584) (xy 160.323518 -379.334847) (xy 160.326832 -379.340872) (xy 160.343209 -379.369206)
			(xy 160.368951 -379.429378) (xy 160.386374 -379.492462) (xy 160.395163 -379.557316) (xy 160.395158 -379.622763)
			(xy 160.386358 -379.687615) (xy 160.368925 -379.750697) (xy 160.343173 -379.810864) (xy 160.326832 -379.83922)
			(xy 160.323513 -379.845243) (xy 160.31991 -379.858508) (xy 160.31972 -379.865382) (xy 160.31972 -380.151386)
			(xy 160.319324 -380.161562) (xy 160.311536 -380.180364) (xy 160.297141 -380.194751) (xy 160.278334 -380.202529)
			(xy 160.268158 -380.202948) (xy 159.551878 -380.202948) (xy 159.541717 -380.202484) (xy 159.522945 -380.1947)
			(xy 159.50858 -380.180325) (xy 159.500808 -380.161547) (xy 159.500316 -380.151386) (xy 159.500316 -379.865382)
			(xy 159.500129 -379.858508) (xy 159.496517 -379.845246) (xy 159.493204 -379.83922) (xy 159.476907 -379.810842)
			(xy 159.451161 -379.75068) (xy 159.433732 -379.687604) (xy 159.424934 -379.622759) (xy 159.424929 -379.55732)
			(xy 159.433716 -379.492473) (xy 159.451135 -379.429395) (xy 159.476871 -379.369228) (xy 159.493204 -379.340872)
			(xy 159.496529 -379.334852) (xy 159.500128 -379.321585) (xy 159.500316 -379.31471) (xy 159.500316 -378.56541)
			(xy 159.500118 -378.558537) (xy 159.496514 -378.545274) (xy 159.493204 -378.539248) (xy 159.476846 -378.510904)
			(xy 159.451106 -378.450734) (xy 159.433683 -378.387651) (xy 159.424893 -378.3228) (xy 149.68216 -378.3228)
			(xy 149.693532 -378.325773) (xy 149.744861 -378.347585) (xy 149.792467 -378.376639) (xy 149.835335 -378.412314)
			(xy 149.872552 -378.453851) (xy 149.903325 -378.500364) (xy 149.926997 -378.550861) (xy 149.943065 -378.604268)
			(xy 149.951185 -378.659444) (xy 149.951694 -378.68733) (xy 149.951185 -378.715216) (xy 149.943065 -378.770392)
			(xy 149.926997 -378.823799) (xy 149.903325 -378.874296) (xy 149.872552 -378.920809) (xy 149.835335 -378.962346)
			(xy 149.792467 -378.998021) (xy 149.744861 -379.027075) (xy 149.693532 -379.048887) (xy 149.639575 -379.062993)
			(xy 149.584138 -379.069093) (xy 149.528404 -379.067056) (xy 149.473561 -379.056926) (xy 149.420777 -379.038919)
			(xy 149.371177 -379.013418) (xy 149.325819 -378.980967) (xy 149.28567 -378.942258) (xy 149.251584 -378.898115)
			(xy 149.224288 -378.84948) (xy 149.204365 -378.797389) (xy 149.192239 -378.742952) (xy 149.188168 -378.68733)
			(xy 136.845294 -378.68733) (xy 136.845294 -379.396498) (xy 147.395944 -379.396498) (xy 147.400015 -379.340876)
			(xy 147.412141 -379.286439) (xy 147.432064 -379.234348) (xy 147.45936 -379.185713) (xy 147.493446 -379.14157)
			(xy 147.533595 -379.102861) (xy 147.578953 -379.07041) (xy 147.628553 -379.044909) (xy 147.681337 -379.026902)
			(xy 147.73618 -379.016772) (xy 147.791914 -379.014735) (xy 147.847351 -379.020835) (xy 147.901308 -379.034941)
			(xy 147.952637 -379.056753) (xy 148.000243 -379.085807) (xy 148.043111 -379.121482) (xy 148.080328 -379.163019)
			(xy 148.111101 -379.209532) (xy 148.134773 -379.260029) (xy 148.150841 -379.313436) (xy 148.158961 -379.368612)
			(xy 148.15947 -379.396498) (xy 148.158961 -379.424384) (xy 148.150841 -379.47956) (xy 148.134773 -379.532967)
			(xy 148.111101 -379.583464) (xy 148.080328 -379.629977) (xy 148.043111 -379.671514) (xy 148.000243 -379.707189)
			(xy 147.952637 -379.736243) (xy 147.901308 -379.758055) (xy 147.847351 -379.772161) (xy 147.791914 -379.778261)
			(xy 147.73618 -379.776224) (xy 147.681337 -379.766094) (xy 147.628553 -379.748087) (xy 147.578953 -379.722586)
			(xy 147.533595 -379.690135) (xy 147.493446 -379.651426) (xy 147.45936 -379.607283) (xy 147.432064 -379.558648)
			(xy 147.412141 -379.506557) (xy 147.400015 -379.45212) (xy 147.395944 -379.396498) (xy 136.845294 -379.396498)
			(xy 136.845294 -379.904752) (xy 149.687786 -379.904752) (xy 149.691857 -379.84913) (xy 149.703983 -379.794693)
			(xy 149.723906 -379.742602) (xy 149.751202 -379.693967) (xy 149.785288 -379.649824) (xy 149.825437 -379.611115)
			(xy 149.870795 -379.578664) (xy 149.920395 -379.553163) (xy 149.973179 -379.535156) (xy 150.028022 -379.525026)
			(xy 150.083756 -379.522989) (xy 150.139193 -379.529089) (xy 150.19315 -379.543195) (xy 150.244479 -379.565007)
			(xy 150.292085 -379.594061) (xy 150.334953 -379.629736) (xy 150.37217 -379.671273) (xy 150.402943 -379.717786)
			(xy 150.426615 -379.768283) (xy 150.442683 -379.82169) (xy 150.450803 -379.876866) (xy 150.451312 -379.904752)
			(xy 150.450803 -379.932638) (xy 150.442683 -379.987814) (xy 150.426615 -380.041221) (xy 150.402943 -380.091718)
			(xy 150.37217 -380.138231) (xy 150.334953 -380.179768) (xy 150.292085 -380.215443) (xy 150.244479 -380.244497)
			(xy 150.19315 -380.266309) (xy 150.139193 -380.280415) (xy 150.083756 -380.286515) (xy 150.028022 -380.284478)
			(xy 149.973179 -380.274348) (xy 149.920395 -380.256341) (xy 149.870795 -380.23084) (xy 149.825437 -380.198389)
			(xy 149.785288 -380.15968) (xy 149.751202 -380.115537) (xy 149.723906 -380.066902) (xy 149.703983 -380.014811)
			(xy 149.691857 -379.960374) (xy 149.687786 -379.904752) (xy 136.845294 -379.904752) (xy 136.845294 -380.430532)
			(xy 146.648168 -380.430532) (xy 146.652239 -380.37491) (xy 146.664365 -380.320473) (xy 146.684288 -380.268382)
			(xy 146.711584 -380.219747) (xy 146.74567 -380.175604) (xy 146.785819 -380.136895) (xy 146.831177 -380.104444)
			(xy 146.880777 -380.078943) (xy 146.933561 -380.060936) (xy 146.988404 -380.050806) (xy 147.044138 -380.048769)
			(xy 147.099575 -380.054869) (xy 147.153532 -380.068975) (xy 147.204861 -380.090787) (xy 147.252467 -380.119841)
			(xy 147.295335 -380.155516) (xy 147.332552 -380.197053) (xy 147.363325 -380.243566) (xy 147.386997 -380.294063)
			(xy 147.403065 -380.34747) (xy 147.411185 -380.402646) (xy 147.411694 -380.430532) (xy 147.411185 -380.458418)
			(xy 147.403065 -380.513594) (xy 147.386997 -380.567001) (xy 147.363325 -380.617498) (xy 147.336928 -380.657397)
			(xy 161.624812 -380.657397) (xy 161.633602 -380.592549) (xy 161.651024 -380.529469) (xy 161.676763 -380.469303)
			(xy 161.693098 -380.440946) (xy 161.696477 -380.434938) (xy 161.700204 -380.421672) (xy 161.700464 -380.414784)
			(xy 161.700464 -379.665484) (xy 161.700225 -379.658592) (xy 161.696501 -379.64532) (xy 161.693098 -379.639322)
			(xy 161.676803 -379.610943) (xy 161.651057 -379.550781) (xy 161.633628 -379.487706) (xy 161.62483 -379.422861)
			(xy 161.624825 -379.357422) (xy 161.633611 -379.292575) (xy 161.65103 -379.229497) (xy 161.676765 -379.169331)
			(xy 161.693098 -379.140974) (xy 161.696467 -379.134961) (xy 161.7002 -379.121699) (xy 161.700464 -379.114812)
			(xy 161.700464 -378.828554) (xy 161.70089 -378.818421) (xy 161.708637 -378.799695) (xy 161.722942 -378.785339)
			(xy 161.741641 -378.777526) (xy 161.751772 -378.776992) (xy 162.468052 -378.776992) (xy 162.478202 -378.777461)
			(xy 162.496952 -378.785239) (xy 162.511277 -378.799622) (xy 162.518979 -378.818402) (xy 162.51936 -378.828554)
			(xy 162.51936 -379.114812) (xy 162.519598 -379.121704) (xy 162.523323 -379.134976) (xy 162.526726 -379.140974)
			(xy 162.543105 -379.169307) (xy 162.568847 -379.229479) (xy 162.58627 -379.292564) (xy 162.595059 -379.357418)
			(xy 162.595053 -379.422865) (xy 162.586254 -379.487717) (xy 162.56882 -379.550799) (xy 162.543068 -379.610966)
			(xy 162.526726 -379.639322) (xy 162.523352 -379.645332) (xy 162.519623 -379.658596) (xy 162.51936 -379.665484)
			(xy 162.51936 -380.414784) (xy 162.51957 -380.421679) (xy 162.523314 -380.434951) (xy 162.526726 -380.440946)
			(xy 162.543081 -380.469292) (xy 162.568826 -380.529461) (xy 162.586251 -380.592543) (xy 162.595043 -380.657395)
			(xy 162.595043 -380.657396) (xy 166.024848 -380.657396) (xy 166.033639 -380.592548) (xy 166.051063 -380.529468)
			(xy 166.076804 -380.469302) (xy 166.09314 -380.440946) (xy 166.096434 -380.434911) (xy 166.100053 -380.421655)
			(xy 166.100252 -380.414784) (xy 166.100252 -379.665484) (xy 166.100072 -379.65861) (xy 166.096456 -379.645347)
			(xy 166.09314 -379.639322) (xy 166.076843 -379.610943) (xy 166.051096 -379.550782) (xy 166.033665 -379.487706)
			(xy 166.024867 -379.422861) (xy 166.024861 -379.357421) (xy 166.033648 -379.292574) (xy 166.051068 -379.229496)
			(xy 166.076806 -379.16933) (xy 166.09314 -379.140974) (xy 166.096459 -379.134952) (xy 166.100063 -379.121686)
			(xy 166.100252 -379.114812) (xy 166.100252 -378.828554) (xy 166.100696 -378.818392) (xy 166.108488 -378.799619)
			(xy 166.122869 -378.785255) (xy 166.141651 -378.777484) (xy 166.151814 -378.776992) (xy 166.868094 -378.776992)
			(xy 166.878246 -378.777537) (xy 166.897006 -378.785301) (xy 166.91137 -378.79965) (xy 166.919153 -378.818403)
			(xy 166.919656 -378.828554) (xy 166.919656 -379.114812) (xy 166.919836 -379.121686) (xy 166.923452 -379.134949)
			(xy 166.926768 -379.140974) (xy 166.943146 -379.169308) (xy 166.968886 -379.22948) (xy 166.986307 -379.292565)
			(xy 166.995095 -379.357418) (xy 166.995089 -379.422864) (xy 166.986291 -379.487716) (xy 166.968858 -379.550798)
			(xy 166.943108 -379.610966) (xy 166.926768 -379.639322) (xy 166.923443 -379.645342) (xy 166.919844 -379.658609)
			(xy 166.919656 -379.665484) (xy 166.919656 -380.414784) (xy 166.919847 -380.421657) (xy 166.923455 -380.43492)
			(xy 166.926768 -380.440946) (xy 166.943122 -380.469293) (xy 166.968864 -380.529462) (xy 166.986288 -380.592544)
			(xy 166.995079 -380.657395) (xy 166.995079 -380.657396) (xy 170.424884 -380.657396) (xy 170.433676 -380.592547)
			(xy 170.451101 -380.529468) (xy 170.476845 -380.469302) (xy 170.493182 -380.440946) (xy 170.49656 -380.434938)
			(xy 170.500288 -380.421672) (xy 170.500548 -380.414784) (xy 170.500548 -379.665484) (xy 170.500311 -379.658591)
			(xy 170.496586 -379.645319) (xy 170.493182 -379.639322) (xy 170.476884 -379.610944) (xy 170.451134 -379.550783)
			(xy 170.433702 -379.487707) (xy 170.424903 -379.422861) (xy 170.424897 -379.357421) (xy 170.433685 -379.292574)
			(xy 170.451107 -379.229495) (xy 170.476846 -379.16933) (xy 170.493182 -379.140974) (xy 170.49655 -379.134961)
			(xy 170.500284 -379.121699) (xy 170.500548 -379.114812) (xy 170.500548 -378.828554) (xy 170.500989 -378.818423)
			(xy 170.508734 -378.7997) (xy 170.523034 -378.785345) (xy 170.541727 -378.777529) (xy 170.551856 -378.776992)
			(xy 171.268136 -378.776992) (xy 171.278291 -378.777392) (xy 171.297043 -378.785198) (xy 171.311365 -378.799601)
			(xy 171.319065 -378.818396) (xy 171.319444 -378.828554) (xy 171.319444 -379.114812) (xy 171.319683 -379.121704)
			(xy 171.323407 -379.134976) (xy 171.32681 -379.140974) (xy 171.34319 -379.169307) (xy 171.368932 -379.229479)
			(xy 171.386356 -379.292564) (xy 171.395145 -379.357418) (xy 171.39514 -379.422865) (xy 171.38634 -379.487717)
			(xy 171.368905 -379.550799) (xy 171.343152 -379.610966) (xy 171.32681 -379.639322) (xy 171.323443 -379.645336)
			(xy 171.319708 -379.658597) (xy 171.319444 -379.665484) (xy 171.319444 -380.414784) (xy 171.319656 -380.421678)
			(xy 171.323399 -380.43495) (xy 171.32681 -380.440946) (xy 171.343166 -380.469292) (xy 171.368911 -380.529461)
			(xy 171.386337 -380.592543) (xy 171.395129 -380.657395) (xy 171.395129 -380.657396) (xy 174.824935 -380.657396)
			(xy 174.833725 -380.592548) (xy 174.851148 -380.529469) (xy 174.876888 -380.469302) (xy 174.893224 -380.440946)
			(xy 174.896524 -380.434914) (xy 174.900139 -380.421656) (xy 174.900336 -380.414784) (xy 174.900336 -379.665484)
			(xy 174.900146 -379.658611) (xy 174.896536 -379.645348) (xy 174.893224 -379.639322) (xy 174.876928 -379.610943)
			(xy 174.851181 -379.550782) (xy 174.833751 -379.487706) (xy 174.824953 -379.422861) (xy 174.824947 -379.357421)
			(xy 174.833734 -379.292575) (xy 174.851154 -379.229496) (xy 174.87689 -379.16933) (xy 174.893224 -379.140974)
			(xy 174.89655 -379.134955) (xy 174.900148 -379.121687) (xy 174.900336 -379.114812) (xy 174.900336 -378.828554)
			(xy 174.900796 -378.818394) (xy 174.908585 -378.799624) (xy 174.922961 -378.78526) (xy 174.941737 -378.777487)
			(xy 174.951898 -378.776992) (xy 175.668178 -378.776992) (xy 175.678329 -378.77755) (xy 175.697089 -378.785309)
			(xy 175.711453 -378.799654) (xy 175.719237 -378.818404) (xy 175.71974 -378.828554) (xy 175.71974 -379.114812)
			(xy 175.719922 -379.121686) (xy 175.723537 -379.134949) (xy 175.726852 -379.140974) (xy 175.74323 -379.169308)
			(xy 175.768971 -379.229479) (xy 175.786393 -379.292564) (xy 175.795181 -379.357418) (xy 175.795176 -379.422864)
			(xy 175.786377 -379.487717) (xy 175.768944 -379.550798) (xy 175.752146 -379.590046) (xy 177.023784 -379.590046)
			(xy 177.027775 -379.527879) (xy 177.039684 -379.466732) (xy 177.059313 -379.407611) (xy 177.086342 -379.351485)
			(xy 177.120326 -379.299276) (xy 177.160708 -379.251841) (xy 177.206824 -379.20996) (xy 177.257916 -379.17432)
			(xy 177.313147 -379.145506) (xy 177.371609 -379.123992) (xy 177.432343 -379.11013) (xy 177.49435 -379.104148)
			(xy 177.556613 -379.106144) (xy 177.61811 -379.116087) (xy 177.677831 -379.133811) (xy 177.734794 -379.159028)
			(xy 177.788065 -379.191321) (xy 177.83677 -379.230161) (xy 177.880107 -379.274911) (xy 177.917367 -379.324835)
			(xy 177.947936 -379.379114) (xy 177.952403 -379.390148) (xy 179.223932 -379.390148) (xy 179.227923 -379.327981)
			(xy 179.239832 -379.266834) (xy 179.259461 -379.207713) (xy 179.28649 -379.151587) (xy 179.320474 -379.099378)
			(xy 179.360856 -379.051943) (xy 179.406972 -379.010062) (xy 179.458064 -378.974422) (xy 179.513295 -378.945608)
			(xy 179.571757 -378.924094) (xy 179.632491 -378.910232) (xy 179.694498 -378.90425) (xy 179.756761 -378.906246)
			(xy 179.818258 -378.916189) (xy 179.877979 -378.933913) (xy 179.934942 -378.95913) (xy 179.988213 -378.991423)
			(xy 180.036918 -379.030263) (xy 180.080255 -379.075013) (xy 180.117515 -379.124937) (xy 180.148084 -379.179216)
			(xy 180.171462 -379.236959) (xy 180.187263 -379.297217) (xy 180.195229 -379.359) (xy 180.195728 -379.390148)
			(xy 180.195229 -379.421296) (xy 180.187263 -379.483079) (xy 180.171462 -379.543337) (xy 180.148084 -379.60108)
			(xy 180.117515 -379.655359) (xy 180.080255 -379.705283) (xy 180.036918 -379.750033) (xy 179.988213 -379.788873)
			(xy 179.934942 -379.821166) (xy 179.877979 -379.846383) (xy 179.818258 -379.864107) (xy 179.756761 -379.87405)
			(xy 179.694498 -379.876046) (xy 179.632491 -379.870064) (xy 179.571757 -379.856202) (xy 179.513295 -379.834688)
			(xy 179.458064 -379.805874) (xy 179.406972 -379.770234) (xy 179.360856 -379.728353) (xy 179.320474 -379.680918)
			(xy 179.28649 -379.628709) (xy 179.259461 -379.572583) (xy 179.239832 -379.513462) (xy 179.227923 -379.452315)
			(xy 179.223932 -379.390148) (xy 177.952403 -379.390148) (xy 177.971314 -379.436857) (xy 177.987115 -379.497115)
			(xy 177.995081 -379.558898) (xy 177.99558 -379.590046) (xy 177.995081 -379.621194) (xy 177.987115 -379.682977)
			(xy 177.971314 -379.743235) (xy 177.947936 -379.800978) (xy 177.917367 -379.855257) (xy 177.880107 -379.905181)
			(xy 177.83677 -379.949931) (xy 177.788065 -379.988771) (xy 177.734794 -380.021064) (xy 177.677831 -380.046281)
			(xy 177.61811 -380.064005) (xy 177.556613 -380.073948) (xy 177.49435 -380.075944) (xy 177.432343 -380.069962)
			(xy 177.371609 -380.0561) (xy 177.313147 -380.034586) (xy 177.257916 -380.005772) (xy 177.206824 -379.970132)
			(xy 177.160708 -379.928251) (xy 177.120326 -379.880816) (xy 177.086342 -379.828607) (xy 177.059313 -379.772481)
			(xy 177.039684 -379.71336) (xy 177.027775 -379.652213) (xy 177.023784 -379.590046) (xy 175.752146 -379.590046)
			(xy 175.743193 -379.610966) (xy 175.726852 -379.639322) (xy 175.723534 -379.645345) (xy 175.71993 -379.65861)
			(xy 175.71974 -379.665484) (xy 175.71974 -380.414784) (xy 175.719933 -380.421657) (xy 175.72354 -380.43492)
			(xy 175.726852 -380.440946) (xy 175.743207 -380.469293) (xy 175.768949 -380.529462) (xy 175.786374 -380.592544)
			(xy 175.795165 -380.657395) (xy 175.795164 -380.69012) (xy 179.223932 -380.69012) (xy 179.227923 -380.627953)
			(xy 179.239832 -380.566806) (xy 179.259461 -380.507685) (xy 179.28649 -380.451559) (xy 179.320474 -380.39935)
			(xy 179.360856 -380.351915) (xy 179.406972 -380.310034) (xy 179.458064 -380.274394) (xy 179.513295 -380.24558)
			(xy 179.571757 -380.224066) (xy 179.632491 -380.210204) (xy 179.694498 -380.204222) (xy 179.756761 -380.206218)
			(xy 179.818258 -380.216161) (xy 179.877979 -380.233885) (xy 179.934942 -380.259102) (xy 179.988213 -380.291395)
			(xy 180.036918 -380.330235) (xy 180.080255 -380.374985) (xy 180.117515 -380.424909) (xy 180.148084 -380.479188)
			(xy 180.171462 -380.536931) (xy 180.187263 -380.597189) (xy 180.195229 -380.658972) (xy 180.195728 -380.69012)
			(xy 180.195229 -380.721268) (xy 180.187263 -380.783051) (xy 180.171462 -380.843309) (xy 180.148084 -380.901052)
			(xy 180.117515 -380.955331) (xy 180.080255 -381.005255) (xy 180.036918 -381.050005) (xy 179.988213 -381.088845)
			(xy 179.934942 -381.121138) (xy 179.877979 -381.146355) (xy 179.818258 -381.164079) (xy 179.756761 -381.174022)
			(xy 179.694498 -381.176018) (xy 179.632491 -381.170036) (xy 179.571757 -381.156174) (xy 179.513295 -381.13466)
			(xy 179.458064 -381.105846) (xy 179.406972 -381.070206) (xy 179.360856 -381.028325) (xy 179.320474 -380.98089)
			(xy 179.28649 -380.928681) (xy 179.259461 -380.872555) (xy 179.239832 -380.813434) (xy 179.227923 -380.752287)
			(xy 179.223932 -380.69012) (xy 175.795164 -380.69012) (xy 175.795163 -380.722839) (xy 175.786367 -380.78769)
			(xy 175.768938 -380.850771) (xy 175.743191 -380.910938) (xy 175.726852 -380.939294) (xy 175.723544 -380.945322)
			(xy 175.719933 -380.958583) (xy 175.71974 -380.965456) (xy 175.71974 -381.251206) (xy 175.71934 -381.261381)
			(xy 175.711549 -381.28018) (xy 175.697156 -381.294565) (xy 175.678353 -381.302346) (xy 175.668178 -381.302768)
			(xy 174.951898 -381.302768) (xy 174.941741 -381.302268) (xy 174.922973 -381.294494) (xy 174.908608 -381.280131)
			(xy 174.900832 -381.261363) (xy 174.900336 -381.251206) (xy 174.900336 -380.965456) (xy 174.900118 -380.958585)
			(xy 174.896527 -380.945322) (xy 174.893224 -380.939294) (xy 174.876904 -380.910928) (xy 174.851159 -380.850764)
			(xy 174.833732 -380.787686) (xy 174.824937 -380.722838) (xy 174.824935 -380.657396) (xy 171.395129 -380.657396)
			(xy 171.395127 -380.72284) (xy 171.38633 -380.787691) (xy 171.3689 -380.850772) (xy 171.34315 -380.910938)
			(xy 171.32681 -380.939294) (xy 171.323453 -380.945313) (xy 171.319712 -380.95857) (xy 171.319444 -380.965456)
			(xy 171.319444 -381.251206) (xy 171.318978 -381.261335) (xy 171.311245 -381.280059) (xy 171.296952 -381.294416)
			(xy 171.278263 -381.302232) (xy 171.268136 -381.302768) (xy 170.551856 -381.302768) (xy 170.541695 -381.302414)
			(xy 170.522936 -381.294598) (xy 170.508613 -381.28018) (xy 170.50092 -381.26137) (xy 170.500548 -381.251206)
			(xy 170.500548 -380.965456) (xy 170.500322 -380.958563) (xy 170.496589 -380.945291) (xy 170.493182 -380.939294)
			(xy 170.47686 -380.910929) (xy 170.451112 -380.850765) (xy 170.433683 -380.787687) (xy 170.424887 -380.722838)
			(xy 170.424884 -380.657396) (xy 166.995079 -380.657396) (xy 166.995077 -380.722839) (xy 166.986281 -380.78769)
			(xy 166.968853 -380.850771) (xy 166.943106 -380.910938) (xy 166.926768 -380.939294) (xy 166.923453 -380.945318)
			(xy 166.919848 -380.958582) (xy 166.919656 -380.965456) (xy 166.919656 -381.251206) (xy 166.919171 -381.261365)
			(xy 166.911394 -381.280135) (xy 166.897025 -381.2945) (xy 166.878253 -381.302274) (xy 166.868094 -381.302768)
			(xy 166.151814 -381.302768) (xy 166.141644 -381.302325) (xy 166.122851 -381.294546) (xy 166.108466 -381.280166)
			(xy 166.100679 -381.261376) (xy 166.100252 -381.251206) (xy 166.100252 -380.965456) (xy 166.100045 -380.958584)
			(xy 166.096448 -380.945321) (xy 166.09314 -380.939294) (xy 166.07682 -380.910928) (xy 166.051074 -380.850764)
			(xy 166.033646 -380.787686) (xy 166.024851 -380.722838) (xy 166.024848 -380.657396) (xy 162.595043 -380.657396)
			(xy 162.595041 -380.72284) (xy 162.586245 -380.78769) (xy 162.568814 -380.850771) (xy 162.543066 -380.910938)
			(xy 162.526726 -380.939294) (xy 162.523362 -380.945309) (xy 162.519627 -380.958569) (xy 162.51936 -380.965456)
			(xy 162.51936 -381.251206) (xy 162.518878 -381.261333) (xy 162.511148 -381.280054) (xy 162.496861 -381.29441)
			(xy 162.478177 -381.302229) (xy 162.468052 -381.302768) (xy 161.751772 -381.302768) (xy 161.741612 -381.302401)
			(xy 161.722853 -381.29459) (xy 161.708529 -381.280176) (xy 161.700836 -381.261368) (xy 161.700464 -381.251206)
			(xy 161.700464 -380.965456) (xy 161.700236 -380.958563) (xy 161.696504 -380.945291) (xy 161.693098 -380.939294)
			(xy 161.676779 -380.910928) (xy 161.651036 -380.850763) (xy 161.633609 -380.787685) (xy 161.624814 -380.722838)
			(xy 161.624812 -380.657397) (xy 147.336928 -380.657397) (xy 147.332552 -380.664011) (xy 147.295335 -380.705548)
			(xy 147.252467 -380.741223) (xy 147.204861 -380.770277) (xy 147.153532 -380.792089) (xy 147.099575 -380.806195)
			(xy 147.044138 -380.812295) (xy 146.988404 -380.810258) (xy 146.933561 -380.800128) (xy 146.880777 -380.782121)
			(xy 146.831177 -380.75662) (xy 146.785819 -380.724169) (xy 146.74567 -380.68546) (xy 146.711584 -380.641317)
			(xy 146.684288 -380.592682) (xy 146.664365 -380.540591) (xy 146.652239 -380.486154) (xy 146.648168 -380.430532)
			(xy 136.845294 -380.430532) (xy 136.845294 -381.7112) (xy 147.45284 -381.7112) (xy 147.456911 -381.655578)
			(xy 147.469037 -381.601141) (xy 147.48896 -381.54905) (xy 147.516256 -381.500415) (xy 147.550342 -381.456272)
			(xy 147.590491 -381.417563) (xy 147.635849 -381.385112) (xy 147.685449 -381.359611) (xy 147.738233 -381.341604)
			(xy 147.793076 -381.331474) (xy 147.84881 -381.329437) (xy 147.904247 -381.335537) (xy 147.958204 -381.349643)
			(xy 148.009533 -381.371455) (xy 148.057139 -381.400509) (xy 148.090771 -381.428498) (xy 149.85568 -381.428498)
			(xy 149.859751 -381.372876) (xy 149.871877 -381.318439) (xy 149.8918 -381.266348) (xy 149.919096 -381.217713)
			(xy 149.953182 -381.17357) (xy 149.993331 -381.134861) (xy 150.038689 -381.10241) (xy 150.088289 -381.076909)
			(xy 150.141073 -381.058902) (xy 150.195916 -381.048772) (xy 150.25165 -381.046735) (xy 150.307087 -381.052835)
			(xy 150.361044 -381.066941) (xy 150.412373 -381.088753) (xy 150.459979 -381.117807) (xy 150.502847 -381.153482)
			(xy 150.540064 -381.195019) (xy 150.570837 -381.241532) (xy 150.594509 -381.292029) (xy 150.610577 -381.345436)
			(xy 150.618697 -381.400612) (xy 150.619206 -381.428498) (xy 150.618697 -381.456384) (xy 150.610577 -381.51156)
			(xy 150.594509 -381.564967) (xy 150.570837 -381.615464) (xy 150.540064 -381.661977) (xy 150.502847 -381.703514)
			(xy 150.459979 -381.739189) (xy 150.412373 -381.768243) (xy 150.361044 -381.790055) (xy 150.307087 -381.804161)
			(xy 150.25165 -381.810261) (xy 150.195916 -381.808224) (xy 150.141073 -381.798094) (xy 150.088289 -381.780087)
			(xy 150.038689 -381.754586) (xy 149.993331 -381.722135) (xy 149.953182 -381.683426) (xy 149.919096 -381.639283)
			(xy 149.8918 -381.590648) (xy 149.871877 -381.538557) (xy 149.859751 -381.48412) (xy 149.85568 -381.428498)
			(xy 148.090771 -381.428498) (xy 148.100007 -381.436184) (xy 148.137224 -381.477721) (xy 148.167997 -381.524234)
			(xy 148.191669 -381.574731) (xy 148.207737 -381.628138) (xy 148.215857 -381.683314) (xy 148.216366 -381.7112)
			(xy 148.215857 -381.739086) (xy 148.207737 -381.794262) (xy 148.191669 -381.847669) (xy 148.167997 -381.898166)
			(xy 148.137224 -381.944679) (xy 148.100007 -381.986216) (xy 148.057139 -382.021891) (xy 148.009533 -382.050945)
			(xy 147.958204 -382.072757) (xy 147.904247 -382.086863) (xy 147.84881 -382.092963) (xy 147.793076 -382.090926)
			(xy 147.738233 -382.080796) (xy 147.685449 -382.062789) (xy 147.635849 -382.037288) (xy 147.590491 -382.004837)
			(xy 147.550342 -381.966128) (xy 147.516256 -381.921985) (xy 147.48896 -381.87335) (xy 147.469037 -381.821259)
			(xy 147.456911 -381.766822) (xy 147.45284 -381.7112) (xy 136.845294 -381.7112) (xy 136.845294 -382.444498)
			(xy 146.412456 -382.444498) (xy 146.416527 -382.388876) (xy 146.428653 -382.334439) (xy 146.448576 -382.282348)
			(xy 146.475872 -382.233713) (xy 146.509958 -382.18957) (xy 146.550107 -382.150861) (xy 146.595465 -382.11841)
			(xy 146.645065 -382.092909) (xy 146.697849 -382.074902) (xy 146.752692 -382.064772) (xy 146.808426 -382.062735)
			(xy 146.863863 -382.068835) (xy 146.91782 -382.082941) (xy 146.969149 -382.104753) (xy 147.016755 -382.133807)
			(xy 147.059623 -382.169482) (xy 147.09684 -382.211019) (xy 147.104577 -382.222713) (xy 159.424903 -382.222713)
			(xy 159.424904 -382.15727) (xy 159.433697 -382.09242) (xy 159.451124 -382.02934) (xy 159.476867 -381.969173)
			(xy 159.493204 -381.940816) (xy 159.496513 -381.934789) (xy 159.500122 -381.921527) (xy 159.500316 -381.914654)
			(xy 159.500316 -381.628904) (xy 159.500725 -381.618748) (xy 159.508522 -381.599993) (xy 159.522923 -381.585669)
			(xy 159.54172 -381.577972) (xy 159.551878 -381.577596) (xy 160.268158 -381.577596) (xy 160.278277 -381.57816)
			(xy 160.296988 -381.585866) (xy 160.311345 -381.600128) (xy 160.319173 -381.618789) (xy 160.31972 -381.628904)
			(xy 160.31972 -381.914654) (xy 160.319927 -381.921526) (xy 160.323525 -381.934789) (xy 160.326832 -381.940816)
			(xy 160.343162 -381.969177) (xy 160.368908 -382.029342) (xy 160.386336 -382.092421) (xy 160.395131 -382.15727)
			(xy 160.395132 -382.222713) (xy 163.824939 -382.222713) (xy 163.82494 -382.15727) (xy 163.833734 -382.092419)
			(xy 163.851162 -382.029339) (xy 163.876908 -381.969172) (xy 163.893246 -381.940816) (xy 163.896604 -381.934798)
			(xy 163.900343 -381.92154) (xy 163.900612 -381.914654) (xy 163.900612 -381.628904) (xy 163.90102 -381.61878)
			(xy 163.908769 -381.600074) (xy 163.923088 -381.58576) (xy 163.941796 -381.578016) (xy 163.95192 -381.577596)
			(xy 164.6682 -381.577596) (xy 164.678322 -381.578016) (xy 164.697025 -381.585763) (xy 164.711339 -381.600079)
			(xy 164.719085 -381.618782) (xy 164.719508 -381.628904) (xy 164.719508 -381.914654) (xy 164.719758 -381.921544)
			(xy 164.723489 -381.93481) (xy 164.726874 -381.940816) (xy 164.743202 -381.969177) (xy 164.768946 -382.029343)
			(xy 164.786373 -382.092422) (xy 164.795167 -382.15727) (xy 164.795168 -382.222712) (xy 164.795168 -382.222714)
			(xy 168.224975 -382.222714) (xy 168.224976 -382.157269) (xy 168.233771 -382.092419) (xy 168.251201 -382.029338)
			(xy 168.276948 -381.969172) (xy 168.293288 -381.940816) (xy 168.296596 -381.934788) (xy 168.300206 -381.921527)
			(xy 168.3004 -381.914654) (xy 168.3004 -381.628904) (xy 168.300825 -381.61875) (xy 168.308619 -381.599998)
			(xy 168.323015 -381.585674) (xy 168.341806 -381.577975) (xy 168.351962 -381.577596) (xy 169.068242 -381.577596)
			(xy 169.078366 -381.578091) (xy 169.09708 -381.585824) (xy 169.111433 -381.600107) (xy 169.119258 -381.618783)
			(xy 169.119804 -381.628904) (xy 169.119804 -381.914654) (xy 169.120013 -381.921526) (xy 169.12361 -381.934789)
			(xy 169.126916 -381.940816) (xy 169.143246 -381.969176) (xy 169.168993 -382.029342) (xy 169.186422 -382.092421)
			(xy 169.195217 -382.15727) (xy 169.195218 -382.222713) (xy 172.624764 -382.222713) (xy 172.624766 -382.157269)
			(xy 172.633561 -382.092419) (xy 172.65099 -382.029338) (xy 172.676737 -381.969172) (xy 172.693076 -381.940816)
			(xy 172.696383 -381.934788) (xy 172.699994 -381.921527) (xy 172.700188 -381.914654) (xy 172.700188 -381.628904)
			(xy 172.700625 -381.618752) (xy 172.708417 -381.600002) (xy 172.722809 -381.585679) (xy 172.741596 -381.577977)
			(xy 172.75175 -381.577596) (xy 173.46803 -381.577596) (xy 173.478153 -381.578101) (xy 173.496867 -381.58583)
			(xy 173.51122 -381.60011) (xy 173.519046 -381.618783) (xy 173.519592 -381.628904) (xy 173.519592 -381.914654)
			(xy 173.519803 -381.921526) (xy 173.523398 -381.934789) (xy 173.526704 -381.940816) (xy 173.543032 -381.969177)
			(xy 173.568774 -382.029343) (xy 173.5862 -382.092422) (xy 173.594993 -382.157271) (xy 173.594993 -382.18999)
			(xy 177.023784 -382.18999) (xy 177.027775 -382.127823) (xy 177.039684 -382.066676) (xy 177.059313 -382.007555)
			(xy 177.086342 -381.951429) (xy 177.120326 -381.89922) (xy 177.160708 -381.851785) (xy 177.206824 -381.809904)
			(xy 177.257916 -381.774264) (xy 177.313147 -381.74545) (xy 177.371609 -381.723936) (xy 177.432343 -381.710074)
			(xy 177.49435 -381.704092) (xy 177.556613 -381.706088) (xy 177.61811 -381.716031) (xy 177.677831 -381.733755)
			(xy 177.734794 -381.758972) (xy 177.788065 -381.791265) (xy 177.83677 -381.830105) (xy 177.880107 -381.874855)
			(xy 177.917367 -381.924779) (xy 177.947936 -381.979058) (xy 177.971314 -382.036801) (xy 177.987115 -382.097059)
			(xy 177.995081 -382.158842) (xy 177.99558 -382.18999) (xy 177.995081 -382.221138) (xy 177.987115 -382.282921)
			(xy 177.971314 -382.343179) (xy 177.947936 -382.400922) (xy 177.917367 -382.455201) (xy 177.880107 -382.505125)
			(xy 177.83677 -382.549875) (xy 177.788065 -382.588715) (xy 177.734794 -382.621008) (xy 177.677831 -382.646225)
			(xy 177.61811 -382.663949) (xy 177.556613 -382.673892) (xy 177.49435 -382.675888) (xy 177.432343 -382.669906)
			(xy 177.371609 -382.656044) (xy 177.313147 -382.63453) (xy 177.257916 -382.605716) (xy 177.206824 -382.570076)
			(xy 177.160708 -382.528195) (xy 177.120326 -382.48076) (xy 177.086342 -382.428551) (xy 177.059313 -382.372425)
			(xy 177.039684 -382.313304) (xy 177.027775 -382.252157) (xy 177.023784 -382.18999) (xy 173.594993 -382.18999)
			(xy 173.594994 -382.222712) (xy 173.586203 -382.287561) (xy 173.56878 -382.35064) (xy 173.543039 -382.410807)
			(xy 173.526704 -382.439164) (xy 173.523402 -382.445195) (xy 173.519788 -382.458454) (xy 173.519592 -382.465326)
			(xy 173.519592 -383.21488) (xy 173.519792 -383.221753) (xy 173.523395 -383.235015) (xy 173.526704 -383.241042)
			(xy 173.543054 -383.269391) (xy 173.565899 -383.322792) (xy 174.824905 -383.322792) (xy 174.824909 -383.257347)
			(xy 174.833706 -383.192495) (xy 174.851137 -383.129414) (xy 174.876885 -383.069246) (xy 174.893224 -383.04089)
			(xy 174.896544 -383.034868) (xy 174.900146 -383.021602) (xy 174.900336 -383.014728) (xy 174.900336 -382.728724)
			(xy 174.900742 -382.718567) (xy 174.908536 -382.699808) (xy 174.922939 -382.685482) (xy 174.941739 -382.677788)
			(xy 174.951898 -382.677416) (xy 175.668178 -382.677416) (xy 175.6783 -382.677944) (xy 175.697017 -382.68566)
			(xy 175.711373 -382.699933) (xy 175.719197 -382.718605) (xy 175.71974 -382.728724) (xy 175.71974 -383.014728)
			(xy 175.719916 -383.021602) (xy 175.723535 -383.034865) (xy 175.726852 -383.04089) (xy 175.743159 -383.069263)
			(xy 175.768906 -383.129426) (xy 175.786336 -383.192502) (xy 175.795133 -383.257349) (xy 175.795138 -383.322789)
			(xy 175.786349 -383.387637) (xy 175.768927 -383.450716) (xy 175.752028 -383.490216) (xy 177.023784 -383.490216)
			(xy 177.027775 -383.428049) (xy 177.039684 -383.366902) (xy 177.059313 -383.307781) (xy 177.086342 -383.251655)
			(xy 177.120326 -383.199446) (xy 177.160708 -383.152011) (xy 177.206824 -383.11013) (xy 177.257916 -383.07449)
			(xy 177.313147 -383.045676) (xy 177.371609 -383.024162) (xy 177.432343 -383.0103) (xy 177.49435 -383.004318)
			(xy 177.556613 -383.006314) (xy 177.61811 -383.016257) (xy 177.677831 -383.033981) (xy 177.734794 -383.059198)
			(xy 177.788065 -383.091491) (xy 177.83677 -383.130331) (xy 177.880107 -383.175081) (xy 177.917367 -383.225005)
			(xy 177.947936 -383.279284) (xy 177.9523 -383.290064) (xy 179.223932 -383.290064) (xy 179.227923 -383.227897)
			(xy 179.239832 -383.16675) (xy 179.259461 -383.107629) (xy 179.28649 -383.051503) (xy 179.320474 -382.999294)
			(xy 179.360856 -382.951859) (xy 179.406972 -382.909978) (xy 179.458064 -382.874338) (xy 179.513295 -382.845524)
			(xy 179.571757 -382.82401) (xy 179.632491 -382.810148) (xy 179.694498 -382.804166) (xy 179.756761 -382.806162)
			(xy 179.818258 -382.816105) (xy 179.877979 -382.833829) (xy 179.934942 -382.859046) (xy 179.988213 -382.891339)
			(xy 180.036918 -382.930179) (xy 180.080255 -382.974929) (xy 180.117515 -383.024853) (xy 180.148084 -383.079132)
			(xy 180.171462 -383.136875) (xy 180.187263 -383.197133) (xy 180.195229 -383.258916) (xy 180.195728 -383.290064)
			(xy 180.195229 -383.321212) (xy 180.187263 -383.382995) (xy 180.171462 -383.443253) (xy 180.148084 -383.500996)
			(xy 180.117515 -383.555275) (xy 180.080255 -383.605199) (xy 180.036918 -383.649949) (xy 179.988213 -383.688789)
			(xy 179.934942 -383.721082) (xy 179.877979 -383.746299) (xy 179.818258 -383.764023) (xy 179.756761 -383.773966)
			(xy 179.694498 -383.775962) (xy 179.632491 -383.76998) (xy 179.571757 -383.756118) (xy 179.513295 -383.734604)
			(xy 179.458064 -383.70579) (xy 179.406972 -383.67015) (xy 179.360856 -383.628269) (xy 179.320474 -383.580834)
			(xy 179.28649 -383.528625) (xy 179.259461 -383.472499) (xy 179.239832 -383.413378) (xy 179.227923 -383.352231)
			(xy 179.223932 -383.290064) (xy 177.9523 -383.290064) (xy 177.971314 -383.337027) (xy 177.987115 -383.397285)
			(xy 177.995081 -383.459068) (xy 177.99558 -383.490216) (xy 177.995081 -383.521364) (xy 177.987115 -383.583147)
			(xy 177.971314 -383.643405) (xy 177.947936 -383.701148) (xy 177.917367 -383.755427) (xy 177.880107 -383.805351)
			(xy 177.83677 -383.850101) (xy 177.788065 -383.888941) (xy 177.734794 -383.921234) (xy 177.677831 -383.946451)
			(xy 177.61811 -383.964175) (xy 177.556613 -383.974118) (xy 177.49435 -383.976114) (xy 177.432343 -383.970132)
			(xy 177.371609 -383.95627) (xy 177.313147 -383.934756) (xy 177.257916 -383.905942) (xy 177.206824 -383.870302)
			(xy 177.160708 -383.828421) (xy 177.120326 -383.780986) (xy 177.086342 -383.728777) (xy 177.059313 -383.672651)
			(xy 177.039684 -383.61353) (xy 177.027775 -383.552383) (xy 177.023784 -383.490216) (xy 175.752028 -383.490216)
			(xy 175.743187 -383.510882) (xy 175.726852 -383.539238) (xy 175.723528 -383.545258) (xy 175.719928 -383.558525)
			(xy 175.71974 -383.5654) (xy 175.71974 -384.3147) (xy 175.719927 -384.321574) (xy 175.723538 -384.334837)
			(xy 175.726852 -384.340862) (xy 175.74322 -384.369201) (xy 175.768962 -384.429372) (xy 175.786385 -384.492455)
			(xy 175.795174 -384.557308) (xy 175.795172 -384.590036) (xy 179.223932 -384.590036) (xy 179.227923 -384.527869)
			(xy 179.239832 -384.466722) (xy 179.259461 -384.407601) (xy 179.28649 -384.351475) (xy 179.320474 -384.299266)
			(xy 179.360856 -384.251831) (xy 179.406972 -384.20995) (xy 179.458064 -384.17431) (xy 179.513295 -384.145496)
			(xy 179.571757 -384.123982) (xy 179.632491 -384.11012) (xy 179.694498 -384.104138) (xy 179.756761 -384.106134)
			(xy 179.818258 -384.116077) (xy 179.877979 -384.133801) (xy 179.934942 -384.159018) (xy 179.988213 -384.191311)
			(xy 180.036918 -384.230151) (xy 180.080255 -384.274901) (xy 180.117515 -384.324825) (xy 180.148084 -384.379104)
			(xy 180.171462 -384.436847) (xy 180.187263 -384.497105) (xy 180.195229 -384.558888) (xy 180.195728 -384.590036)
			(xy 180.195229 -384.621184) (xy 180.187263 -384.682967) (xy 180.171462 -384.743225) (xy 180.148084 -384.800968)
			(xy 180.117515 -384.855247) (xy 180.080255 -384.905171) (xy 180.036918 -384.949921) (xy 179.988213 -384.988761)
			(xy 179.934942 -385.021054) (xy 179.877979 -385.046271) (xy 179.818258 -385.063995) (xy 179.756761 -385.073938)
			(xy 179.694498 -385.075934) (xy 179.632491 -385.069952) (xy 179.571757 -385.05609) (xy 179.513295 -385.034576)
			(xy 179.458064 -385.005762) (xy 179.406972 -384.970122) (xy 179.360856 -384.928241) (xy 179.320474 -384.880806)
			(xy 179.28649 -384.828597) (xy 179.259461 -384.772471) (xy 179.239832 -384.71335) (xy 179.227923 -384.652203)
			(xy 179.223932 -384.590036) (xy 175.795172 -384.590036) (xy 175.79517 -384.622754) (xy 175.786373 -384.687605)
			(xy 175.768941 -384.750687) (xy 175.743192 -384.810854) (xy 175.726852 -384.83921) (xy 175.723538 -384.845235)
			(xy 175.719931 -384.858498) (xy 175.71974 -384.865372) (xy 175.71974 -385.151376) (xy 175.71926 -385.161524)
			(xy 175.71148 -385.180268) (xy 175.697101 -385.194591) (xy 175.678327 -385.202298) (xy 175.668178 -385.202684)
			(xy 174.951898 -385.202684) (xy 174.941774 -385.202176) (xy 174.923058 -385.194452) (xy 174.908702 -385.180172)
			(xy 174.900879 -385.161497) (xy 174.900336 -385.151376) (xy 174.900336 -384.865372) (xy 174.90015 -384.858498)
			(xy 174.896537 -384.845236) (xy 174.893224 -384.83921) (xy 174.876918 -384.810837) (xy 174.851172 -384.750674)
			(xy 174.833742 -384.687597) (xy 174.824946 -384.622751) (xy 174.824942 -384.557311) (xy 174.83373 -384.492463)
			(xy 174.851151 -384.429384) (xy 174.87689 -384.369218) (xy 174.893224 -384.340862) (xy 174.896554 -384.334845)
			(xy 174.90015 -384.321575) (xy 174.900336 -384.3147) (xy 174.900336 -383.5654) (xy 174.90014 -383.558527)
			(xy 174.896534 -383.545265) (xy 174.893224 -383.539238) (xy 174.876857 -383.510899) (xy 174.851116 -383.450728)
			(xy 174.833694 -383.387644) (xy 174.824905 -383.322792) (xy 173.565899 -383.322792) (xy 173.568794 -383.32956)
			(xy 173.586217 -383.392642) (xy 173.595008 -383.457492) (xy 173.595006 -383.522935) (xy 173.586212 -383.587785)
			(xy 173.568785 -383.650866) (xy 173.543041 -383.711033) (xy 173.526704 -383.73939) (xy 173.523393 -383.745417)
			(xy 173.519785 -383.758679) (xy 173.519592 -383.765552) (xy 173.519592 -384.051556) (xy 173.519142 -384.061708)
			(xy 173.51136 -384.080461) (xy 173.496971 -384.094786) (xy 173.478184 -384.102486) (xy 173.46803 -384.102864)
			(xy 172.75175 -384.102864) (xy 172.741627 -384.102333) (xy 172.722908 -384.094622) (xy 172.70855 -384.080349)
			(xy 172.700728 -384.061676) (xy 172.700188 -384.051556) (xy 172.700188 -383.765552) (xy 172.699978 -383.75868)
			(xy 172.696382 -383.745417) (xy 172.693076 -383.73939) (xy 172.676751 -383.711027) (xy 172.651004 -383.650862)
			(xy 172.633575 -383.587783) (xy 172.624779 -383.522935) (xy 172.624777 -383.457493) (xy 172.633569 -383.392643)
			(xy 172.650995 -383.329564) (xy 172.676739 -383.269398) (xy 172.693076 -383.241042) (xy 172.696374 -383.235009)
			(xy 172.699991 -383.221752) (xy 172.700188 -383.21488) (xy 172.700188 -382.465326) (xy 172.699987 -382.458453)
			(xy 172.696385 -382.445191) (xy 172.693076 -382.439164) (xy 172.676729 -382.410813) (xy 172.650984 -382.350645)
			(xy 172.633557 -382.287564) (xy 172.624764 -382.222713) (xy 169.195218 -382.222713) (xy 169.186426 -382.287562)
			(xy 169.168999 -382.350642) (xy 169.143254 -382.410808) (xy 169.126916 -382.439164) (xy 169.123615 -382.445195)
			(xy 169.12 -382.458454) (xy 169.119804 -382.465326) (xy 169.119804 -383.21488) (xy 169.120003 -383.221753)
			(xy 169.123607 -383.235015) (xy 169.126916 -383.241042) (xy 169.143268 -383.26939) (xy 169.166118 -383.322792)
			(xy 170.424855 -383.322792) (xy 170.424859 -383.257346) (xy 170.433657 -383.192494) (xy 170.45109 -383.129413)
			(xy 170.476841 -383.069246) (xy 170.493182 -383.04089) (xy 170.496544 -383.034874) (xy 170.500282 -383.021615)
			(xy 170.500548 -383.014728) (xy 170.500548 -382.728724) (xy 170.501103 -382.718623) (xy 170.508823 -382.699955)
			(xy 170.523098 -382.685662) (xy 170.541756 -382.677917) (xy 170.551856 -382.677416) (xy 171.268136 -382.677416)
			(xy 171.278249 -382.677856) (xy 171.296931 -382.685608) (xy 171.311225 -382.699919) (xy 171.318956 -382.71861)
			(xy 171.319444 -382.728724) (xy 171.319444 -383.014728) (xy 171.319677 -383.021621) (xy 171.323405 -383.034893)
			(xy 171.32681 -383.04089) (xy 171.343118 -383.069262) (xy 171.368868 -383.129425) (xy 171.3863 -383.192502)
			(xy 171.395097 -383.257349) (xy 171.395101 -383.32279) (xy 171.386312 -383.387638) (xy 171.368888 -383.450717)
			(xy 171.343147 -383.510882) (xy 171.32681 -383.539238) (xy 171.323437 -383.545249) (xy 171.319706 -383.558512)
			(xy 171.319444 -383.5654) (xy 171.319444 -384.3147) (xy 171.31965 -384.321595) (xy 171.323397 -384.334867)
			(xy 171.32681 -384.340862) (xy 171.343179 -384.369201) (xy 171.368923 -384.429371) (xy 171.386348 -384.492455)
			(xy 171.395138 -384.557308) (xy 171.395134 -384.622754) (xy 171.386336 -384.687606) (xy 171.368903 -384.750687)
			(xy 171.343151 -384.810854) (xy 171.32681 -384.83921) (xy 171.323447 -384.845226) (xy 171.31971 -384.858485)
			(xy 171.319444 -384.865372) (xy 171.319444 -385.151376) (xy 171.318896 -385.161478) (xy 171.311175 -385.180147)
			(xy 171.296897 -385.194441) (xy 171.278237 -385.202185) (xy 171.268136 -385.202684) (xy 170.551856 -385.202684)
			(xy 170.541742 -385.20225) (xy 170.52306 -385.194495) (xy 170.508766 -385.180183) (xy 170.501036 -385.16149)
			(xy 170.500548 -385.151376) (xy 170.500548 -384.865372) (xy 170.500316 -384.858479) (xy 170.496587 -384.845207)
			(xy 170.493182 -384.83921) (xy 170.476874 -384.810837) (xy 170.451125 -384.750675) (xy 170.433693 -384.687598)
			(xy 170.424896 -384.622751) (xy 170.424892 -384.55731) (xy 170.433681 -384.492462) (xy 170.451104 -384.429383)
			(xy 170.476846 -384.369218) (xy 170.493182 -384.340862) (xy 170.496554 -384.334851) (xy 170.500286 -384.321588)
			(xy 170.500548 -384.3147) (xy 170.500548 -383.5654) (xy 170.500344 -383.558505) (xy 170.496596 -383.545233)
			(xy 170.493182 -383.539238) (xy 170.476813 -383.510899) (xy 170.451069 -383.450729) (xy 170.433645 -383.387645)
			(xy 170.424855 -383.322792) (xy 169.166118 -383.322792) (xy 169.169013 -383.329558) (xy 169.18644 -383.39264)
			(xy 169.195232 -383.457491) (xy 169.19523 -383.522936) (xy 169.186434 -383.587787) (xy 169.169004 -383.650868)
			(xy 169.143256 -383.711034) (xy 169.126916 -383.73939) (xy 169.123606 -383.745417) (xy 169.119997 -383.758679)
			(xy 169.119804 -383.765552) (xy 169.119804 -384.051556) (xy 169.119342 -384.061707) (xy 169.111562 -384.080457)
			(xy 169.097177 -384.094782) (xy 169.078394 -384.102484) (xy 169.068242 -384.102864) (xy 168.351962 -384.102864)
			(xy 168.341833 -384.102405) (xy 168.323112 -384.094665) (xy 168.308757 -384.080371) (xy 168.300939 -384.061682)
			(xy 168.3004 -384.051556) (xy 168.3004 -383.765552) (xy 168.300188 -383.75868) (xy 168.296593 -383.745418)
			(xy 168.293288 -383.73939) (xy 168.276963 -383.711027) (xy 168.251215 -383.650862) (xy 168.233785 -383.587784)
			(xy 168.22499 -383.522935) (xy 168.224988 -383.457492) (xy 168.23378 -383.392643) (xy 168.251206 -383.329564)
			(xy 168.27695 -383.269398) (xy 168.293288 -383.241042) (xy 168.296587 -383.23501) (xy 168.300203 -383.221752)
			(xy 168.3004 -383.21488) (xy 168.3004 -382.465326) (xy 168.300198 -382.458454) (xy 168.296596 -382.445191)
			(xy 168.293288 -382.439164) (xy 168.276941 -382.410813) (xy 168.251195 -382.350646) (xy 168.233768 -382.287564)
			(xy 168.224975 -382.222714) (xy 164.795168 -382.222714) (xy 164.786377 -382.287561) (xy 164.768952 -382.350641)
			(xy 164.74321 -382.410808) (xy 164.726874 -382.439164) (xy 164.723524 -382.445186) (xy 164.719779 -382.458441)
			(xy 164.719508 -382.465326) (xy 164.719508 -383.21488) (xy 164.719748 -383.221771) (xy 164.723486 -383.235037)
			(xy 164.726874 -383.241042) (xy 164.743225 -383.269391) (xy 164.766071 -383.322792) (xy 166.024819 -383.322792)
			(xy 166.024823 -383.257346) (xy 166.03362 -383.192495) (xy 166.051051 -383.129414) (xy 166.0768 -383.069246)
			(xy 166.09314 -383.04089) (xy 166.096454 -383.034865) (xy 166.100061 -383.021602) (xy 166.100252 -383.014728)
			(xy 166.100252 -382.728724) (xy 166.10074 -382.718577) (xy 166.108519 -382.699835) (xy 166.122895 -382.685512)
			(xy 166.141666 -382.677803) (xy 166.151814 -382.677416) (xy 166.868094 -382.677416) (xy 166.878217 -382.677931)
			(xy 166.896934 -382.685652) (xy 166.911289 -382.699929) (xy 166.919113 -382.718603) (xy 166.919656 -382.728724)
			(xy 166.919656 -383.014728) (xy 166.91983 -383.021603) (xy 166.92345 -383.034866) (xy 166.926768 -383.04089)
			(xy 166.943075 -383.069263) (xy 166.968821 -383.129426) (xy 166.986251 -383.192503) (xy 166.995047 -383.257349)
			(xy 166.995051 -383.322789) (xy 166.986263 -383.387637) (xy 166.968841 -383.450716) (xy 166.943103 -383.510882)
			(xy 166.926768 -383.539238) (xy 166.923438 -383.545255) (xy 166.919842 -383.558525) (xy 166.919656 -383.5654)
			(xy 166.919656 -384.3147) (xy 166.919841 -384.321574) (xy 166.923453 -384.334837) (xy 166.926768 -384.340862)
			(xy 166.943136 -384.369201) (xy 166.968876 -384.429372) (xy 166.986299 -384.492456) (xy 166.995088 -384.557308)
			(xy 166.995084 -384.622754) (xy 166.986287 -384.687605) (xy 166.968856 -384.750686) (xy 166.943108 -384.810854)
			(xy 166.926768 -384.83921) (xy 166.923447 -384.845232) (xy 166.919846 -384.858498) (xy 166.919656 -384.865372)
			(xy 166.919656 -385.151376) (xy 166.91916 -385.161522) (xy 166.911383 -385.180263) (xy 166.89701 -385.194585)
			(xy 166.878241 -385.202296) (xy 166.868094 -385.202684) (xy 166.151814 -385.202684) (xy 166.141691 -385.202163)
			(xy 166.122975 -385.194444) (xy 166.108619 -385.180169) (xy 166.100795 -385.161496) (xy 166.100252 -385.151376)
			(xy 166.100252 -384.865372) (xy 166.100077 -384.858497) (xy 166.096458 -384.845234) (xy 166.09314 -384.83921)
			(xy 166.076833 -384.810837) (xy 166.051086 -384.750674) (xy 166.033656 -384.687598) (xy 166.02486 -384.622751)
			(xy 166.024856 -384.557311) (xy 166.033644 -384.492463) (xy 166.051066 -384.429384) (xy 166.076805 -384.369218)
			(xy 166.09314 -384.340862) (xy 166.096464 -384.334842) (xy 166.100064 -384.321575) (xy 166.100252 -384.3147)
			(xy 166.100252 -383.5654) (xy 166.100066 -383.558526) (xy 166.096454 -383.545263) (xy 166.09314 -383.539238)
			(xy 166.076772 -383.510899) (xy 166.051031 -383.450728) (xy 166.033608 -383.387644) (xy 166.024819 -383.322792)
			(xy 164.766071 -383.322792) (xy 164.768966 -383.329559) (xy 164.786391 -383.392641) (xy 164.795182 -383.457492)
			(xy 164.79518 -383.522936) (xy 164.786385 -383.587786) (xy 164.768957 -383.650867) (xy 164.743212 -383.711034)
			(xy 164.726874 -383.73939) (xy 164.723515 -383.745408) (xy 164.719776 -383.758666) (xy 164.719508 -383.765552)
			(xy 164.719508 -384.051556) (xy 164.719048 -384.061675) (xy 164.711316 -384.080376) (xy 164.697013 -384.094691)
			(xy 164.678318 -384.102439) (xy 164.6682 -384.102864) (xy 163.95192 -384.102864) (xy 163.941794 -384.102467)
			(xy 163.923084 -384.094719) (xy 163.908768 -384.080396) (xy 163.901028 -384.061682) (xy 163.900612 -384.051556)
			(xy 163.900612 -383.765552) (xy 163.900392 -383.758658) (xy 163.896655 -383.745386) (xy 163.893246 -383.73939)
			(xy 163.876922 -383.711026) (xy 163.851176 -383.650862) (xy 163.833748 -383.587783) (xy 163.824953 -383.522935)
			(xy 163.824952 -383.457493) (xy 163.833743 -383.392644) (xy 163.851167 -383.329564) (xy 163.876909 -383.269398)
			(xy 163.893246 -383.241042) (xy 163.89663 -383.235037) (xy 163.900353 -383.221769) (xy 163.900612 -383.21488)
			(xy 163.900612 -382.465326) (xy 163.900402 -382.458431) (xy 163.896659 -382.445159) (xy 163.893246 -382.439164)
			(xy 163.8769 -382.410813) (xy 163.851156 -382.350645) (xy 163.833731 -382.287564) (xy 163.824939 -382.222713)
			(xy 160.395132 -382.222713) (xy 160.38634 -382.287562) (xy 160.368914 -382.350642) (xy 160.34317 -382.410808)
			(xy 160.326832 -382.439164) (xy 160.323533 -382.445196) (xy 160.319917 -382.458454) (xy 160.31972 -382.465326)
			(xy 160.31972 -383.21488) (xy 160.319917 -383.221753) (xy 160.323522 -383.235016) (xy 160.326832 -383.241042)
			(xy 160.343184 -383.26939) (xy 160.366033 -383.322792) (xy 161.624783 -383.322792) (xy 161.624787 -383.257347)
			(xy 161.633583 -383.192496) (xy 161.651013 -383.129414) (xy 161.67676 -383.069247) (xy 161.693098 -383.04089)
			(xy 161.696462 -383.034875) (xy 161.700198 -383.021615) (xy 161.700464 -383.014728) (xy 161.700464 -382.728724)
			(xy 161.701004 -382.718621) (xy 161.708727 -382.69995) (xy 161.723007 -382.685656) (xy 161.74167 -382.677914)
			(xy 161.751772 -382.677416) (xy 162.468052 -382.677416) (xy 162.478173 -382.677856) (xy 162.496879 -382.685591)
			(xy 162.511195 -382.699901) (xy 162.51894 -382.718603) (xy 162.51936 -382.728724) (xy 162.51936 -383.014728)
			(xy 162.519591 -383.021621) (xy 162.523321 -383.034893) (xy 162.526726 -383.04089) (xy 162.543034 -383.069263)
			(xy 162.568783 -383.129425) (xy 162.586214 -383.192502) (xy 162.595011 -383.257349) (xy 162.595015 -383.32279)
			(xy 162.586226 -383.387638) (xy 162.568803 -383.450717) (xy 162.543062 -383.510882) (xy 162.526726 -383.539238)
			(xy 162.523347 -383.545245) (xy 162.519621 -383.558512) (xy 162.51936 -383.5654) (xy 162.51936 -384.3147)
			(xy 162.519563 -384.321595) (xy 162.523312 -384.334867) (xy 162.526726 -384.340862) (xy 162.543095 -384.369201)
			(xy 162.568838 -384.429371) (xy 162.586262 -384.492455) (xy 162.595052 -384.557308) (xy 162.595048 -384.622754)
			(xy 162.58625 -384.687606) (xy 162.568817 -384.750687) (xy 162.543067 -384.810854) (xy 162.526726 -384.83921)
			(xy 162.523356 -384.845222) (xy 162.519625 -384.858485) (xy 162.51936 -384.865372) (xy 162.51936 -385.151376)
			(xy 162.518964 -385.161502) (xy 162.511216 -385.180213) (xy 162.496893 -385.194529) (xy 162.478178 -385.202268)
			(xy 162.468052 -385.202684) (xy 161.751772 -385.202684) (xy 161.741659 -385.202238) (xy 161.722978 -385.194488)
			(xy 161.708683 -385.180179) (xy 161.700952 -385.161489) (xy 161.700464 -385.151376) (xy 161.700464 -384.865372)
			(xy 161.70023 -384.858479) (xy 161.696502 -384.845207) (xy 161.693098 -384.83921) (xy 161.676792 -384.810837)
			(xy 161.651048 -384.750673) (xy 161.63362 -384.687597) (xy 161.624824 -384.622751) (xy 161.624819 -384.557311)
			(xy 161.633607 -384.492464) (xy 161.651027 -384.429385) (xy 161.676764 -384.369219) (xy 161.693098 -384.340862)
			(xy 161.696471 -384.334851) (xy 161.700202 -384.321588) (xy 161.700464 -384.3147) (xy 161.700464 -383.5654)
			(xy 161.700236 -383.558508) (xy 161.69649 -383.545242) (xy 161.693098 -383.539238) (xy 161.676731 -383.510898)
			(xy 161.650993 -383.450727) (xy 161.633571 -383.387644) (xy 161.624783 -383.322792) (xy 160.366033 -383.322792)
			(xy 160.368928 -383.329559) (xy 160.386354 -383.39264) (xy 160.395146 -383.457492) (xy 160.395144 -383.522936)
			(xy 160.386348 -383.587787) (xy 160.368919 -383.650867) (xy 160.343171 -383.711034) (xy 160.326832 -383.73939)
			(xy 160.323524 -383.745418) (xy 160.319914 -383.758679) (xy 160.31972 -383.765552) (xy 160.31972 -384.051556)
			(xy 160.319243 -384.061705) (xy 160.311465 -384.080452) (xy 160.297086 -384.094777) (xy 160.278308 -384.102481)
			(xy 160.268158 -384.102864) (xy 159.551878 -384.102864) (xy 159.54175 -384.102392) (xy 159.523029 -384.094657)
			(xy 159.508674 -384.080367) (xy 159.500855 -384.061681) (xy 159.500316 -384.051556) (xy 159.500316 -383.765552)
			(xy 159.500102 -383.75868) (xy 159.496508 -383.745418) (xy 159.493204 -383.73939) (xy 159.476881 -383.711026)
			(xy 159.451138 -383.650861) (xy 159.433711 -383.587782) (xy 159.424917 -383.522934) (xy 159.424916 -383.457493)
			(xy 159.433706 -383.392645) (xy 159.451129 -383.329565) (xy 159.476869 -383.269399) (xy 159.493204 -383.241042)
			(xy 159.496504 -383.23501) (xy 159.500119 -383.221752) (xy 159.500316 -383.21488) (xy 159.500316 -382.465326)
			(xy 159.500112 -382.458454) (xy 159.496512 -382.445191) (xy 159.493204 -382.439164) (xy 159.476859 -382.410812)
			(xy 159.451118 -382.350644) (xy 159.433694 -382.287563) (xy 159.424903 -382.222713) (xy 147.104577 -382.222713)
			(xy 147.127613 -382.257532) (xy 147.151285 -382.308029) (xy 147.167353 -382.361436) (xy 147.175473 -382.416612)
			(xy 147.175982 -382.444498) (xy 147.175473 -382.472384) (xy 147.167353 -382.52756) (xy 147.151285 -382.580967)
			(xy 147.127613 -382.631464) (xy 147.09684 -382.677977) (xy 147.059623 -382.719514) (xy 147.016755 -382.755189)
			(xy 146.969149 -382.784243) (xy 146.91782 -382.806055) (xy 146.863863 -382.820161) (xy 146.808426 -382.826261)
			(xy 146.752692 -382.824224) (xy 146.697849 -382.814094) (xy 146.645065 -382.796087) (xy 146.595465 -382.770586)
			(xy 146.550107 -382.738135) (xy 146.509958 -382.699426) (xy 146.475872 -382.655283) (xy 146.448576 -382.606648)
			(xy 146.428653 -382.554557) (xy 146.416527 -382.50012) (xy 146.412456 -382.444498) (xy 136.845294 -382.444498)
			(xy 136.845294 -383.460498) (xy 147.395944 -383.460498) (xy 147.400015 -383.404876) (xy 147.412141 -383.350439)
			(xy 147.432064 -383.298348) (xy 147.45936 -383.249713) (xy 147.493446 -383.20557) (xy 147.533595 -383.166861)
			(xy 147.578953 -383.13441) (xy 147.628553 -383.108909) (xy 147.681337 -383.090902) (xy 147.73618 -383.080772)
			(xy 147.791914 -383.078735) (xy 147.847351 -383.084835) (xy 147.901308 -383.098941) (xy 147.952637 -383.120753)
			(xy 148.000243 -383.149807) (xy 148.043111 -383.185482) (xy 148.080328 -383.227019) (xy 148.111101 -383.273532)
			(xy 148.134773 -383.324029) (xy 148.147251 -383.365502) (xy 149.854156 -383.365502) (xy 149.858227 -383.30988)
			(xy 149.870353 -383.255443) (xy 149.890276 -383.203352) (xy 149.917572 -383.154717) (xy 149.951658 -383.110574)
			(xy 149.991807 -383.071865) (xy 150.037165 -383.039414) (xy 150.086765 -383.013913) (xy 150.139549 -382.995906)
			(xy 150.194392 -382.985776) (xy 150.250126 -382.983739) (xy 150.305563 -382.989839) (xy 150.35952 -383.003945)
			(xy 150.410849 -383.025757) (xy 150.458455 -383.054811) (xy 150.501323 -383.090486) (xy 150.53854 -383.132023)
			(xy 150.569313 -383.178536) (xy 150.592985 -383.229033) (xy 150.609053 -383.28244) (xy 150.617173 -383.337616)
			(xy 150.617682 -383.365502) (xy 150.617173 -383.393388) (xy 150.609053 -383.448564) (xy 150.592985 -383.501971)
			(xy 150.569313 -383.552468) (xy 150.53854 -383.598981) (xy 150.501323 -383.640518) (xy 150.458455 -383.676193)
			(xy 150.410849 -383.705247) (xy 150.35952 -383.727059) (xy 150.305563 -383.741165) (xy 150.250126 -383.747265)
			(xy 150.194392 -383.745228) (xy 150.139549 -383.735098) (xy 150.086765 -383.717091) (xy 150.037165 -383.69159)
			(xy 149.991807 -383.659139) (xy 149.951658 -383.62043) (xy 149.917572 -383.576287) (xy 149.890276 -383.527652)
			(xy 149.870353 -383.475561) (xy 149.858227 -383.421124) (xy 149.854156 -383.365502) (xy 148.147251 -383.365502)
			(xy 148.150841 -383.377436) (xy 148.158961 -383.432612) (xy 148.15947 -383.460498) (xy 148.158961 -383.488384)
			(xy 148.150841 -383.54356) (xy 148.134773 -383.596967) (xy 148.111101 -383.647464) (xy 148.080328 -383.693977)
			(xy 148.043111 -383.735514) (xy 148.000243 -383.771189) (xy 147.952637 -383.800243) (xy 147.901308 -383.822055)
			(xy 147.847351 -383.836161) (xy 147.791914 -383.842261) (xy 147.73618 -383.840224) (xy 147.681337 -383.830094)
			(xy 147.628553 -383.812087) (xy 147.578953 -383.786586) (xy 147.533595 -383.754135) (xy 147.493446 -383.715426)
			(xy 147.45936 -383.671283) (xy 147.432064 -383.622648) (xy 147.412141 -383.570557) (xy 147.400015 -383.51612)
			(xy 147.395944 -383.460498) (xy 136.845294 -383.460498) (xy 136.845294 -384.591814) (xy 149.09876 -384.591814)
			(xy 149.102831 -384.536192) (xy 149.114957 -384.481755) (xy 149.13488 -384.429664) (xy 149.162176 -384.381029)
			(xy 149.196262 -384.336886) (xy 149.236411 -384.298177) (xy 149.281769 -384.265726) (xy 149.331369 -384.240225)
			(xy 149.384153 -384.222218) (xy 149.438996 -384.212088) (xy 149.49473 -384.210051) (xy 149.550167 -384.216151)
			(xy 149.604124 -384.230257) (xy 149.655453 -384.252069) (xy 149.703059 -384.281123) (xy 149.745927 -384.316798)
			(xy 149.783144 -384.358335) (xy 149.813917 -384.404848) (xy 149.837589 -384.455345) (xy 149.853657 -384.508752)
			(xy 149.861777 -384.563928) (xy 149.862286 -384.591814) (xy 149.861777 -384.6197) (xy 149.853657 -384.674876)
			(xy 149.837589 -384.728283) (xy 149.813917 -384.77878) (xy 149.783144 -384.825293) (xy 149.745927 -384.86683)
			(xy 149.703059 -384.902505) (xy 149.655453 -384.931559) (xy 149.604124 -384.953371) (xy 149.550167 -384.967477)
			(xy 149.49473 -384.973577) (xy 149.438996 -384.97154) (xy 149.384153 -384.96141) (xy 149.331369 -384.943403)
			(xy 149.281769 -384.917902) (xy 149.236411 -384.885451) (xy 149.196262 -384.846742) (xy 149.162176 -384.802599)
			(xy 149.13488 -384.753964) (xy 149.114957 -384.701873) (xy 149.102831 -384.647436) (xy 149.09876 -384.591814)
			(xy 136.845294 -384.591814) (xy 136.845294 -386.451348) (xy 145.01622 -386.451348) (xy 145.016665 -386.424798)
			(xy 145.024028 -386.372211) (xy 145.038619 -386.321156) (xy 145.060154 -386.272619) (xy 145.088218 -386.227541)
			(xy 145.122267 -386.186795) (xy 145.161641 -386.151168) (xy 145.183352 -386.13588) (xy 145.192242 -386.129784)
			(xy 145.203418 -386.112004) (xy 145.217642 -386.017008) (xy 145.212308 -385.996688) (xy 145.20545 -385.988306)
			(xy 145.189739 -385.967951) (xy 145.16336 -385.923815) (xy 145.143146 -385.876536) (xy 145.129463 -385.826971)
			(xy 145.122558 -385.776017) (xy 145.122138 -385.750308) (xy 145.122624 -385.723057) (xy 145.13038 -385.669109)
			(xy 145.145735 -385.616814) (xy 145.168377 -385.567237) (xy 145.197843 -385.521387) (xy 145.233534 -385.480196)
			(xy 145.274725 -385.444505) (xy 145.320575 -385.415039) (xy 145.370152 -385.392397) (xy 145.422447 -385.377042)
			(xy 145.476395 -385.369286) (xy 145.530897 -385.369286) (xy 145.584845 -385.377042) (xy 145.63714 -385.392397)
			(xy 145.686717 -385.415039) (xy 145.732567 -385.444505) (xy 145.773758 -385.480196) (xy 145.809449 -385.521387)
			(xy 145.838915 -385.567237) (xy 145.849326 -385.590034) (xy 149.95347 -385.590034) (xy 149.957541 -385.534412)
			(xy 149.969667 -385.479975) (xy 149.98959 -385.427884) (xy 150.016886 -385.379249) (xy 150.050972 -385.335106)
			(xy 150.091121 -385.296397) (xy 150.136479 -385.263946) (xy 150.186079 -385.238445) (xy 150.238863 -385.220438)
			(xy 150.293706 -385.210308) (xy 150.34944 -385.208271) (xy 150.404877 -385.214371) (xy 150.458834 -385.228477)
			(xy 150.510163 -385.250289) (xy 150.557769 -385.279343) (xy 150.600637 -385.315018) (xy 150.637854 -385.356555)
			(xy 150.668627 -385.403068) (xy 150.692299 -385.453565) (xy 150.708367 -385.506972) (xy 150.716487 -385.562148)
			(xy 150.716996 -385.590034) (xy 150.716487 -385.61792) (xy 150.708367 -385.673096) (xy 150.692299 -385.726503)
			(xy 150.668627 -385.777) (xy 150.637854 -385.823513) (xy 150.600637 -385.86505) (xy 150.557769 -385.900725)
			(xy 150.510163 -385.929779) (xy 150.458834 -385.951591) (xy 150.404877 -385.965697) (xy 150.34944 -385.971797)
			(xy 150.293706 -385.96976) (xy 150.238863 -385.95963) (xy 150.186079 -385.941623) (xy 150.136479 -385.916122)
			(xy 150.091121 -385.883671) (xy 150.050972 -385.844962) (xy 150.016886 -385.800819) (xy 149.98959 -385.752184)
			(xy 149.969667 -385.700093) (xy 149.957541 -385.645656) (xy 149.95347 -385.590034) (xy 145.849326 -385.590034)
			(xy 145.861557 -385.616814) (xy 145.876912 -385.669109) (xy 145.884668 -385.723057) (xy 145.885154 -385.750308)
			(xy 145.884687 -385.776857) (xy 145.877329 -385.829443) (xy 145.862743 -385.880499) (xy 145.841212 -385.929036)
			(xy 145.813151 -385.974114) (xy 145.779105 -386.014861) (xy 145.739732 -386.050488) (xy 145.718022 -386.065776)
			(xy 145.709132 -386.071872) (xy 145.697956 -386.089652) (xy 145.683732 -386.184648) (xy 145.689066 -386.204968)
			(xy 145.695924 -386.21335) (xy 145.711625 -386.233711) (xy 145.738003 -386.277847) (xy 145.758218 -386.325125)
			(xy 145.771904 -386.374688) (xy 145.778813 -386.425639) (xy 145.779236 -386.451348) (xy 145.77875 -386.478599)
			(xy 145.770994 -386.532547) (xy 145.755639 -386.584842) (xy 145.732997 -386.634419) (xy 145.703531 -386.680269)
			(xy 145.66784 -386.72146) (xy 145.626649 -386.757151) (xy 145.580799 -386.786617) (xy 145.531222 -386.809259)
			(xy 145.478927 -386.824614) (xy 145.424979 -386.83237) (xy 145.370477 -386.83237) (xy 145.316529 -386.824614)
			(xy 145.264234 -386.809259) (xy 145.214657 -386.786617) (xy 145.168807 -386.757151) (xy 145.127616 -386.72146)
			(xy 145.091925 -386.680269) (xy 145.062459 -386.634419) (xy 145.039817 -386.584842) (xy 145.024462 -386.532547)
			(xy 145.016706 -386.478599) (xy 145.01622 -386.451348) (xy 136.845294 -386.451348) (xy 136.845294 -387.124702)
			(xy 187.712602 -387.124702) (xy 187.716673 -387.06908) (xy 187.728799 -387.014643) (xy 187.748722 -386.962552)
			(xy 187.776018 -386.913917) (xy 187.810104 -386.869774) (xy 187.850253 -386.831065) (xy 187.895611 -386.798614)
			(xy 187.945211 -386.773113) (xy 187.997995 -386.755106) (xy 188.052838 -386.744976) (xy 188.108572 -386.742939)
			(xy 188.164009 -386.749039) (xy 188.217966 -386.763145) (xy 188.269295 -386.784957) (xy 188.316901 -386.814011)
			(xy 188.359769 -386.849686) (xy 188.396986 -386.891223) (xy 188.427759 -386.937736) (xy 188.451431 -386.988233)
			(xy 188.467499 -387.04164) (xy 188.475619 -387.096816) (xy 188.476128 -387.124702) (xy 188.475619 -387.152588)
			(xy 188.467499 -387.207764) (xy 188.451431 -387.261171) (xy 188.427759 -387.311668) (xy 188.396986 -387.358181)
			(xy 188.359769 -387.399718) (xy 188.316901 -387.435393) (xy 188.269295 -387.464447) (xy 188.217966 -387.486259)
			(xy 188.164009 -387.500365) (xy 188.108572 -387.506465) (xy 188.052838 -387.504428) (xy 187.997995 -387.494298)
			(xy 187.945211 -387.476291) (xy 187.895611 -387.45079) (xy 187.850253 -387.418339) (xy 187.810104 -387.37963)
			(xy 187.776018 -387.335487) (xy 187.748722 -387.286852) (xy 187.728799 -387.234761) (xy 187.716673 -387.180324)
			(xy 187.712602 -387.124702) (xy 136.845294 -387.124702) (xy 136.845294 -388.150354) (xy 143.718278 -388.150354)
			(xy 143.722349 -388.094732) (xy 143.734475 -388.040295) (xy 143.754398 -387.988204) (xy 143.781694 -387.939569)
			(xy 143.81578 -387.895426) (xy 143.855929 -387.856717) (xy 143.901287 -387.824266) (xy 143.950887 -387.798765)
			(xy 144.003671 -387.780758) (xy 144.058514 -387.770628) (xy 144.114248 -387.768591) (xy 144.169685 -387.774691)
			(xy 144.223642 -387.788797) (xy 144.274971 -387.810609) (xy 144.322577 -387.839663) (xy 144.365445 -387.875338)
			(xy 144.402662 -387.916875) (xy 144.433435 -387.963388) (xy 144.457107 -388.013885) (xy 144.473175 -388.067292)
			(xy 144.481295 -388.122468) (xy 144.481804 -388.150354) (xy 144.481748 -388.153402) (xy 146.889468 -388.153402)
			(xy 146.893539 -388.09778) (xy 146.905665 -388.043343) (xy 146.925588 -387.991252) (xy 146.952884 -387.942617)
			(xy 146.98697 -387.898474) (xy 147.027119 -387.859765) (xy 147.072477 -387.827314) (xy 147.122077 -387.801813)
			(xy 147.174861 -387.783806) (xy 147.229704 -387.773676) (xy 147.285438 -387.771639) (xy 147.340875 -387.777739)
			(xy 147.394832 -387.791845) (xy 147.446161 -387.813657) (xy 147.493767 -387.842711) (xy 147.536635 -387.878386)
			(xy 147.573852 -387.919923) (xy 147.604625 -387.966436) (xy 147.628297 -388.016933) (xy 147.644365 -388.07034)
			(xy 147.652485 -388.125516) (xy 147.652994 -388.153402) (xy 147.652485 -388.181288) (xy 147.648141 -388.210806)
			(xy 148.921468 -388.210806) (xy 148.925539 -388.155184) (xy 148.937665 -388.100747) (xy 148.957588 -388.048656)
			(xy 148.984884 -388.000021) (xy 149.01897 -387.955878) (xy 149.059119 -387.917169) (xy 149.104477 -387.884718)
			(xy 149.154077 -387.859217) (xy 149.206861 -387.84121) (xy 149.261704 -387.83108) (xy 149.317438 -387.829043)
			(xy 149.372875 -387.835143) (xy 149.426832 -387.849249) (xy 149.478161 -387.871061) (xy 149.525767 -387.900115)
			(xy 149.568635 -387.93579) (xy 149.605852 -387.977327) (xy 149.636625 -388.02384) (xy 149.660297 -388.074337)
			(xy 149.676365 -388.127744) (xy 149.684485 -388.18292) (xy 149.684994 -388.210806) (xy 149.684485 -388.238692)
			(xy 149.676365 -388.293868) (xy 149.660297 -388.347275) (xy 149.636625 -388.397772) (xy 149.605852 -388.444285)
			(xy 149.568635 -388.485822) (xy 149.525767 -388.521497) (xy 149.478161 -388.550551) (xy 149.426832 -388.572363)
			(xy 149.372875 -388.586469) (xy 149.317438 -388.592569) (xy 149.261704 -388.590532) (xy 149.206861 -388.580402)
			(xy 149.154077 -388.562395) (xy 149.104477 -388.536894) (xy 149.059119 -388.504443) (xy 149.01897 -388.465734)
			(xy 148.984884 -388.421591) (xy 148.957588 -388.372956) (xy 148.937665 -388.320865) (xy 148.925539 -388.266428)
			(xy 148.921468 -388.210806) (xy 147.648141 -388.210806) (xy 147.644365 -388.236464) (xy 147.628297 -388.289871)
			(xy 147.604625 -388.340368) (xy 147.573852 -388.386881) (xy 147.536635 -388.428418) (xy 147.493767 -388.464093)
			(xy 147.446161 -388.493147) (xy 147.394832 -388.514959) (xy 147.340875 -388.529065) (xy 147.285438 -388.535165)
			(xy 147.229704 -388.533128) (xy 147.174861 -388.522998) (xy 147.122077 -388.504991) (xy 147.072477 -388.47949)
			(xy 147.027119 -388.447039) (xy 146.98697 -388.40833) (xy 146.952884 -388.364187) (xy 146.925588 -388.315552)
			(xy 146.905665 -388.263461) (xy 146.893539 -388.209024) (xy 146.889468 -388.153402) (xy 144.481748 -388.153402)
			(xy 144.481295 -388.17824) (xy 144.473175 -388.233416) (xy 144.457107 -388.286823) (xy 144.433435 -388.33732)
			(xy 144.402662 -388.383833) (xy 144.365445 -388.42537) (xy 144.322577 -388.461045) (xy 144.274971 -388.490099)
			(xy 144.223642 -388.511911) (xy 144.169685 -388.526017) (xy 144.114248 -388.532117) (xy 144.058514 -388.53008)
			(xy 144.003671 -388.51995) (xy 143.950887 -388.501943) (xy 143.901287 -388.476442) (xy 143.855929 -388.443991)
			(xy 143.81578 -388.405282) (xy 143.781694 -388.361139) (xy 143.754398 -388.312504) (xy 143.734475 -388.260413)
			(xy 143.722349 -388.205976) (xy 143.718278 -388.150354) (xy 136.845294 -388.150354) (xy 136.845294 -388.698486)
			(xy 144.600166 -388.698486) (xy 144.604237 -388.642864) (xy 144.616363 -388.588427) (xy 144.636286 -388.536336)
			(xy 144.663582 -388.487701) (xy 144.697668 -388.443558) (xy 144.737817 -388.404849) (xy 144.783175 -388.372398)
			(xy 144.832775 -388.346897) (xy 144.885559 -388.32889) (xy 144.940402 -388.31876) (xy 144.996136 -388.316723)
			(xy 145.051573 -388.322823) (xy 145.10553 -388.336929) (xy 145.156859 -388.358741) (xy 145.204465 -388.387795)
			(xy 145.247333 -388.42347) (xy 145.28455 -388.465007) (xy 145.315323 -388.51152) (xy 145.338995 -388.562017)
			(xy 145.355063 -388.615424) (xy 145.363183 -388.6706) (xy 145.363692 -388.698486) (xy 145.363183 -388.726372)
			(xy 145.355063 -388.781548) (xy 145.338995 -388.834955) (xy 145.315323 -388.885452) (xy 145.28455 -388.931965)
			(xy 145.247333 -388.973502) (xy 145.204465 -389.009177) (xy 145.156859 -389.038231) (xy 145.10553 -389.060043)
			(xy 145.051573 -389.074149) (xy 144.996136 -389.080249) (xy 144.940402 -389.078212) (xy 144.885559 -389.068082)
			(xy 144.832775 -389.050075) (xy 144.783175 -389.024574) (xy 144.737817 -388.992123) (xy 144.697668 -388.953414)
			(xy 144.663582 -388.909271) (xy 144.636286 -388.860636) (xy 144.616363 -388.808545) (xy 144.604237 -388.754108)
			(xy 144.600166 -388.698486) (xy 136.845294 -388.698486) (xy 136.845294 -389.359648) (xy 145.873468 -389.359648)
			(xy 145.877539 -389.304026) (xy 145.889665 -389.249589) (xy 145.909588 -389.197498) (xy 145.936884 -389.148863)
			(xy 145.97097 -389.10472) (xy 146.011119 -389.066011) (xy 146.056477 -389.03356) (xy 146.106077 -389.008059)
			(xy 146.158861 -388.990052) (xy 146.213704 -388.979922) (xy 146.269438 -388.977885) (xy 146.324875 -388.983985)
			(xy 146.378832 -388.998091) (xy 146.430161 -389.019903) (xy 146.477767 -389.048957) (xy 146.520635 -389.084632)
			(xy 146.557852 -389.126169) (xy 146.588625 -389.172682) (xy 146.612297 -389.223179) (xy 146.628365 -389.276586)
			(xy 146.636485 -389.331762) (xy 146.636994 -389.359648) (xy 146.636485 -389.387534) (xy 146.636365 -389.38835)
			(xy 147.905468 -389.38835) (xy 147.909539 -389.332728) (xy 147.921665 -389.278291) (xy 147.941588 -389.2262)
			(xy 147.968884 -389.177565) (xy 148.00297 -389.133422) (xy 148.043119 -389.094713) (xy 148.088477 -389.062262)
			(xy 148.138077 -389.036761) (xy 148.190861 -389.018754) (xy 148.245704 -389.008624) (xy 148.301438 -389.006587)
			(xy 148.356875 -389.012687) (xy 148.410832 -389.026793) (xy 148.462161 -389.048605) (xy 148.509767 -389.077659)
			(xy 148.552635 -389.113334) (xy 148.589852 -389.154871) (xy 148.594424 -389.161782) (xy 150.953468 -389.161782)
			(xy 150.957539 -389.10616) (xy 150.969665 -389.051723) (xy 150.989588 -388.999632) (xy 151.016884 -388.950997)
			(xy 151.05097 -388.906854) (xy 151.091119 -388.868145) (xy 151.136477 -388.835694) (xy 151.186077 -388.810193)
			(xy 151.238861 -388.792186) (xy 151.293704 -388.782056) (xy 151.349438 -388.780019) (xy 151.404875 -388.786119)
			(xy 151.458832 -388.800225) (xy 151.510161 -388.822037) (xy 151.557767 -388.851091) (xy 151.600635 -388.886766)
			(xy 151.637852 -388.928303) (xy 151.668625 -388.974816) (xy 151.692297 -389.025313) (xy 151.708365 -389.07872)
			(xy 151.716485 -389.133896) (xy 151.716994 -389.161782) (xy 151.716485 -389.189668) (xy 151.708365 -389.244844)
			(xy 151.692297 -389.298251) (xy 151.668625 -389.348748) (xy 151.637852 -389.395261) (xy 151.600635 -389.436798)
			(xy 151.557767 -389.472473) (xy 151.510161 -389.501527) (xy 151.458832 -389.523339) (xy 151.404875 -389.537445)
			(xy 151.349438 -389.543545) (xy 151.293704 -389.541508) (xy 151.238861 -389.531378) (xy 151.186077 -389.513371)
			(xy 151.136477 -389.48787) (xy 151.091119 -389.455419) (xy 151.05097 -389.41671) (xy 151.016884 -389.372567)
			(xy 150.989588 -389.323932) (xy 150.969665 -389.271841) (xy 150.957539 -389.217404) (xy 150.953468 -389.161782)
			(xy 148.594424 -389.161782) (xy 148.620625 -389.201384) (xy 148.644297 -389.251881) (xy 148.660365 -389.305288)
			(xy 148.668485 -389.360464) (xy 148.668994 -389.38835) (xy 148.668485 -389.416236) (xy 148.660365 -389.471412)
			(xy 148.644297 -389.524819) (xy 148.620625 -389.575316) (xy 148.589852 -389.621829) (xy 148.552635 -389.663366)
			(xy 148.509767 -389.699041) (xy 148.462161 -389.728095) (xy 148.410832 -389.749907) (xy 148.356875 -389.764013)
			(xy 148.301438 -389.770113) (xy 148.245704 -389.768076) (xy 148.190861 -389.757946) (xy 148.138077 -389.739939)
			(xy 148.088477 -389.714438) (xy 148.043119 -389.681987) (xy 148.00297 -389.643278) (xy 147.968884 -389.599135)
			(xy 147.941588 -389.5505) (xy 147.921665 -389.498409) (xy 147.909539 -389.443972) (xy 147.905468 -389.38835)
			(xy 146.636365 -389.38835) (xy 146.628365 -389.44271) (xy 146.612297 -389.496117) (xy 146.588625 -389.546614)
			(xy 146.557852 -389.593127) (xy 146.520635 -389.634664) (xy 146.477767 -389.670339) (xy 146.430161 -389.699393)
			(xy 146.378832 -389.721205) (xy 146.324875 -389.735311) (xy 146.269438 -389.741411) (xy 146.213704 -389.739374)
			(xy 146.158861 -389.729244) (xy 146.106077 -389.711237) (xy 146.056477 -389.685736) (xy 146.011119 -389.653285)
			(xy 145.97097 -389.614576) (xy 145.936884 -389.570433) (xy 145.909588 -389.521798) (xy 145.889665 -389.469707)
			(xy 145.877539 -389.41527) (xy 145.873468 -389.359648) (xy 136.845294 -389.359648) (xy 136.845294 -389.9154)
			(xy 143.229582 -389.9154) (xy 143.233653 -389.859778) (xy 143.245779 -389.805341) (xy 143.265702 -389.75325)
			(xy 143.292998 -389.704615) (xy 143.327084 -389.660472) (xy 143.367233 -389.621763) (xy 143.412591 -389.589312)
			(xy 143.462191 -389.563811) (xy 143.514975 -389.545804) (xy 143.569818 -389.535674) (xy 143.625552 -389.533637)
			(xy 143.680989 -389.539737) (xy 143.734946 -389.553843) (xy 143.786275 -389.575655) (xy 143.833881 -389.604709)
			(xy 143.876749 -389.640384) (xy 143.913966 -389.681921) (xy 143.944739 -389.728434) (xy 143.968411 -389.778931)
			(xy 143.984479 -389.832338) (xy 143.992599 -389.887514) (xy 143.993108 -389.9154) (xy 143.992599 -389.943286)
			(xy 143.984479 -389.998462) (xy 143.968411 -390.051869) (xy 143.944739 -390.102366) (xy 143.913966 -390.148879)
			(xy 143.876749 -390.190416) (xy 143.833881 -390.226091) (xy 143.786275 -390.255145) (xy 143.734946 -390.276957)
			(xy 143.680989 -390.291063) (xy 143.625552 -390.297163) (xy 143.569818 -390.295126) (xy 143.514975 -390.284996)
			(xy 143.462191 -390.266989) (xy 143.412591 -390.241488) (xy 143.367233 -390.209037) (xy 143.327084 -390.170328)
			(xy 143.292998 -390.126185) (xy 143.265702 -390.07755) (xy 143.245779 -390.025459) (xy 143.233653 -389.971022)
			(xy 143.229582 -389.9154) (xy 136.845294 -389.9154) (xy 136.845294 -390.763252) (xy 143.960848 -390.763252)
			(xy 143.964919 -390.70763) (xy 143.977045 -390.653193) (xy 143.996968 -390.601102) (xy 144.024264 -390.552467)
			(xy 144.05835 -390.508324) (xy 144.098499 -390.469615) (xy 144.143857 -390.437164) (xy 144.193457 -390.411663)
			(xy 144.246241 -390.393656) (xy 144.301084 -390.383526) (xy 144.356818 -390.381489) (xy 144.412255 -390.387589)
			(xy 144.466212 -390.401695) (xy 144.517541 -390.423507) (xy 144.565147 -390.452561) (xy 144.608015 -390.488236)
			(xy 144.645232 -390.529773) (xy 144.676005 -390.576286) (xy 144.699677 -390.626783) (xy 144.715745 -390.68019)
			(xy 144.723865 -390.735366) (xy 144.724374 -390.763252) (xy 144.723865 -390.791138) (xy 144.715745 -390.846314)
			(xy 144.699677 -390.899721) (xy 144.676005 -390.950218) (xy 144.645232 -390.996731) (xy 144.608015 -391.038268)
			(xy 144.565147 -391.073943) (xy 144.517541 -391.102997) (xy 144.466212 -391.124809) (xy 144.412255 -391.138915)
			(xy 144.356818 -391.145015) (xy 144.301084 -391.142978) (xy 144.246241 -391.132848) (xy 144.193457 -391.114841)
			(xy 144.143857 -391.08934) (xy 144.098499 -391.056889) (xy 144.05835 -391.01818) (xy 144.024264 -390.974037)
			(xy 143.996968 -390.925402) (xy 143.977045 -390.873311) (xy 143.964919 -390.818874) (xy 143.960848 -390.763252)
			(xy 136.845294 -390.763252) (xy 136.845294 -391.52703) (xy 142.865854 -391.52703) (xy 142.869925 -391.471408)
			(xy 142.882051 -391.416971) (xy 142.901974 -391.36488) (xy 142.92927 -391.316245) (xy 142.963356 -391.272102)
			(xy 143.003505 -391.233393) (xy 143.048863 -391.200942) (xy 143.098463 -391.175441) (xy 143.151247 -391.157434)
			(xy 143.20609 -391.147304) (xy 143.261824 -391.145267) (xy 143.317261 -391.151367) (xy 143.371218 -391.165473)
			(xy 143.422547 -391.187285) (xy 143.470153 -391.216339) (xy 143.513021 -391.252014) (xy 143.550238 -391.293551)
			(xy 143.581011 -391.340064) (xy 143.604683 -391.390561) (xy 143.620751 -391.443968) (xy 143.628871 -391.499144)
			(xy 143.629055 -391.50925) (xy 145.03476 -391.50925) (xy 145.038831 -391.453628) (xy 145.050957 -391.399191)
			(xy 145.07088 -391.3471) (xy 145.098176 -391.298465) (xy 145.132262 -391.254322) (xy 145.172411 -391.215613)
			(xy 145.217769 -391.183162) (xy 145.267369 -391.157661) (xy 145.320153 -391.139654) (xy 145.374996 -391.129524)
			(xy 145.43073 -391.127487) (xy 145.486167 -391.133587) (xy 145.540124 -391.147693) (xy 145.591453 -391.169505)
			(xy 145.639059 -391.198559) (xy 145.681927 -391.234234) (xy 145.719144 -391.275771) (xy 145.749917 -391.322284)
			(xy 145.773589 -391.372781) (xy 145.789657 -391.426188) (xy 145.797777 -391.481364) (xy 145.798286 -391.50925)
			(xy 145.797777 -391.537136) (xy 145.793209 -391.568178) (xy 147.905468 -391.568178) (xy 147.909539 -391.512556)
			(xy 147.921665 -391.458119) (xy 147.941588 -391.406028) (xy 147.968884 -391.357393) (xy 148.00297 -391.31325)
			(xy 148.043119 -391.274541) (xy 148.088477 -391.24209) (xy 148.138077 -391.216589) (xy 148.190861 -391.198582)
			(xy 148.245704 -391.188452) (xy 148.301438 -391.186415) (xy 148.356875 -391.192515) (xy 148.410832 -391.206621)
			(xy 148.462161 -391.228433) (xy 148.509767 -391.257487) (xy 148.552635 -391.293162) (xy 148.589852 -391.334699)
			(xy 148.620625 -391.381212) (xy 148.644297 -391.431709) (xy 148.660365 -391.485116) (xy 148.668485 -391.540292)
			(xy 148.668994 -391.568178) (xy 148.668485 -391.596064) (xy 148.660365 -391.65124) (xy 148.644297 -391.704647)
			(xy 148.620625 -391.755144) (xy 148.609885 -391.771378) (xy 149.937468 -391.771378) (xy 149.941539 -391.715756)
			(xy 149.953665 -391.661319) (xy 149.973588 -391.609228) (xy 150.000884 -391.560593) (xy 150.03497 -391.51645)
			(xy 150.075119 -391.477741) (xy 150.120477 -391.44529) (xy 150.170077 -391.419789) (xy 150.222861 -391.401782)
			(xy 150.277704 -391.391652) (xy 150.333438 -391.389615) (xy 150.388875 -391.395715) (xy 150.442832 -391.409821)
			(xy 150.494161 -391.431633) (xy 150.541767 -391.460687) (xy 150.584635 -391.496362) (xy 150.621852 -391.537899)
			(xy 150.652625 -391.584412) (xy 150.676297 -391.634909) (xy 150.692365 -391.688316) (xy 150.700485 -391.743492)
			(xy 150.700994 -391.771378) (xy 150.700485 -391.799264) (xy 150.692365 -391.85444) (xy 150.676297 -391.907847)
			(xy 150.652625 -391.958344) (xy 150.621852 -392.004857) (xy 150.584635 -392.046394) (xy 150.541767 -392.082069)
			(xy 150.494161 -392.111123) (xy 150.442832 -392.132935) (xy 150.388875 -392.147041) (xy 150.333438 -392.153141)
			(xy 150.277704 -392.151104) (xy 150.222861 -392.140974) (xy 150.170077 -392.122967) (xy 150.120477 -392.097466)
			(xy 150.075119 -392.065015) (xy 150.03497 -392.026306) (xy 150.000884 -391.982163) (xy 149.973588 -391.933528)
			(xy 149.953665 -391.881437) (xy 149.941539 -391.827) (xy 149.937468 -391.771378) (xy 148.609885 -391.771378)
			(xy 148.589852 -391.801657) (xy 148.552635 -391.843194) (xy 148.509767 -391.878869) (xy 148.462161 -391.907923)
			(xy 148.410832 -391.929735) (xy 148.356875 -391.943841) (xy 148.301438 -391.949941) (xy 148.245704 -391.947904)
			(xy 148.190861 -391.937774) (xy 148.138077 -391.919767) (xy 148.088477 -391.894266) (xy 148.043119 -391.861815)
			(xy 148.00297 -391.823106) (xy 147.968884 -391.778963) (xy 147.941588 -391.730328) (xy 147.921665 -391.678237)
			(xy 147.909539 -391.6238) (xy 147.905468 -391.568178) (xy 145.793209 -391.568178) (xy 145.789657 -391.592312)
			(xy 145.773589 -391.645719) (xy 145.749917 -391.696216) (xy 145.719144 -391.742729) (xy 145.681927 -391.784266)
			(xy 145.639059 -391.819941) (xy 145.591453 -391.848995) (xy 145.540124 -391.870807) (xy 145.486167 -391.884913)
			(xy 145.43073 -391.891013) (xy 145.374996 -391.888976) (xy 145.320153 -391.878846) (xy 145.267369 -391.860839)
			(xy 145.217769 -391.835338) (xy 145.172411 -391.802887) (xy 145.132262 -391.764178) (xy 145.098176 -391.720035)
			(xy 145.07088 -391.6714) (xy 145.050957 -391.619309) (xy 145.038831 -391.564872) (xy 145.03476 -391.50925)
			(xy 143.629055 -391.50925) (xy 143.62938 -391.52703) (xy 143.628871 -391.554916) (xy 143.620751 -391.610092)
			(xy 143.604683 -391.663499) (xy 143.581011 -391.713996) (xy 143.550238 -391.760509) (xy 143.513021 -391.802046)
			(xy 143.470153 -391.837721) (xy 143.422547 -391.866775) (xy 143.371218 -391.888587) (xy 143.317261 -391.902693)
			(xy 143.261824 -391.908793) (xy 143.20609 -391.906756) (xy 143.151247 -391.896626) (xy 143.098463 -391.878619)
			(xy 143.048863 -391.853118) (xy 143.003505 -391.820667) (xy 142.963356 -391.781958) (xy 142.92927 -391.737815)
			(xy 142.901974 -391.68918) (xy 142.882051 -391.637089) (xy 142.869925 -391.582652) (xy 142.865854 -391.52703)
			(xy 136.845294 -391.52703) (xy 136.845294 -392.026394) (xy 141.244318 -392.026394) (xy 141.248389 -391.970772)
			(xy 141.260515 -391.916335) (xy 141.280438 -391.864244) (xy 141.307734 -391.815609) (xy 141.34182 -391.771466)
			(xy 141.381969 -391.732757) (xy 141.427327 -391.700306) (xy 141.476927 -391.674805) (xy 141.529711 -391.656798)
			(xy 141.584554 -391.646668) (xy 141.640288 -391.644631) (xy 141.695725 -391.650731) (xy 141.749682 -391.664837)
			(xy 141.801011 -391.686649) (xy 141.848617 -391.715703) (xy 141.891485 -391.751378) (xy 141.928702 -391.792915)
			(xy 141.959475 -391.839428) (xy 141.983147 -391.889925) (xy 141.999215 -391.943332) (xy 142.007335 -391.998508)
			(xy 142.007844 -392.026394) (xy 142.007335 -392.05428) (xy 141.999215 -392.109456) (xy 141.983147 -392.162863)
			(xy 141.975441 -392.179302) (xy 146.321016 -392.179302) (xy 146.325087 -392.12368) (xy 146.337213 -392.069243)
			(xy 146.357136 -392.017152) (xy 146.384432 -391.968517) (xy 146.418518 -391.924374) (xy 146.458667 -391.885665)
			(xy 146.504025 -391.853214) (xy 146.553625 -391.827713) (xy 146.606409 -391.809706) (xy 146.661252 -391.799576)
			(xy 146.716986 -391.797539) (xy 146.772423 -391.803639) (xy 146.82638 -391.817745) (xy 146.877709 -391.839557)
			(xy 146.925315 -391.868611) (xy 146.968183 -391.904286) (xy 147.0054 -391.945823) (xy 147.036173 -391.992336)
			(xy 147.059845 -392.042833) (xy 147.075913 -392.09624) (xy 147.084033 -392.151416) (xy 147.084542 -392.179302)
			(xy 147.084033 -392.207188) (xy 147.075913 -392.262364) (xy 147.059845 -392.315771) (xy 147.036173 -392.366268)
			(xy 147.0054 -392.412781) (xy 146.968183 -392.454318) (xy 146.925315 -392.489993) (xy 146.877709 -392.519047)
			(xy 146.82638 -392.540859) (xy 146.772423 -392.554965) (xy 146.716986 -392.561065) (xy 146.661252 -392.559028)
			(xy 146.606409 -392.548898) (xy 146.553625 -392.530891) (xy 146.504025 -392.50539) (xy 146.458667 -392.472939)
			(xy 146.418518 -392.43423) (xy 146.384432 -392.390087) (xy 146.357136 -392.341452) (xy 146.337213 -392.289361)
			(xy 146.325087 -392.234924) (xy 146.321016 -392.179302) (xy 141.975441 -392.179302) (xy 141.959475 -392.21336)
			(xy 141.928702 -392.259873) (xy 141.891485 -392.30141) (xy 141.848617 -392.337085) (xy 141.801011 -392.366139)
			(xy 141.749682 -392.387951) (xy 141.695725 -392.402057) (xy 141.640288 -392.408157) (xy 141.584554 -392.40612)
			(xy 141.529711 -392.39599) (xy 141.476927 -392.377983) (xy 141.427327 -392.352482) (xy 141.381969 -392.320031)
			(xy 141.34182 -392.281322) (xy 141.307734 -392.237179) (xy 141.280438 -392.188544) (xy 141.260515 -392.136453)
			(xy 141.248389 -392.082016) (xy 141.244318 -392.026394) (xy 136.845294 -392.026394) (xy 136.845294 -392.646916)
			(xy 148.921468 -392.646916) (xy 148.925539 -392.591294) (xy 148.937665 -392.536857) (xy 148.957588 -392.484766)
			(xy 148.984884 -392.436131) (xy 149.01897 -392.391988) (xy 149.059119 -392.353279) (xy 149.104477 -392.320828)
			(xy 149.154077 -392.295327) (xy 149.206861 -392.27732) (xy 149.261704 -392.26719) (xy 149.317438 -392.265153)
			(xy 149.372875 -392.271253) (xy 149.426832 -392.285359) (xy 149.478161 -392.307171) (xy 149.525767 -392.336225)
			(xy 149.568635 -392.3719) (xy 149.605852 -392.413437) (xy 149.636625 -392.45995) (xy 149.660297 -392.510447)
			(xy 149.676365 -392.563854) (xy 149.684485 -392.61903) (xy 149.684994 -392.646916) (xy 149.684485 -392.674802)
			(xy 149.676365 -392.729978) (xy 149.673844 -392.738356) (xy 150.953468 -392.738356) (xy 150.957539 -392.682734)
			(xy 150.969665 -392.628297) (xy 150.989588 -392.576206) (xy 151.016884 -392.527571) (xy 151.05097 -392.483428)
			(xy 151.091119 -392.444719) (xy 151.136477 -392.412268) (xy 151.186077 -392.386767) (xy 151.238861 -392.36876)
			(xy 151.293704 -392.35863) (xy 151.349438 -392.356593) (xy 151.404875 -392.362693) (xy 151.458832 -392.376799)
			(xy 151.510161 -392.398611) (xy 151.557767 -392.427665) (xy 151.600635 -392.46334) (xy 151.637852 -392.504877)
			(xy 151.668625 -392.55139) (xy 151.692297 -392.601887) (xy 151.708365 -392.655294) (xy 151.716485 -392.71047)
			(xy 151.716994 -392.738356) (xy 151.716485 -392.766242) (xy 151.709637 -392.812778) (xy 155.507434 -392.812778)
			(xy 155.511505 -392.757156) (xy 155.523631 -392.702719) (xy 155.543554 -392.650628) (xy 155.57085 -392.601993)
			(xy 155.604936 -392.55785) (xy 155.645085 -392.519141) (xy 155.690443 -392.48669) (xy 155.740043 -392.461189)
			(xy 155.792827 -392.443182) (xy 155.84767 -392.433052) (xy 155.903404 -392.431015) (xy 155.958841 -392.437115)
			(xy 156.012798 -392.451221) (xy 156.064127 -392.473033) (xy 156.111733 -392.502087) (xy 156.154601 -392.537762)
			(xy 156.191818 -392.579299) (xy 156.222591 -392.625812) (xy 156.246263 -392.676309) (xy 156.262331 -392.729716)
			(xy 156.270451 -392.784892) (xy 156.27096 -392.812778) (xy 156.270451 -392.840664) (xy 156.262331 -392.89584)
			(xy 156.246263 -392.949247) (xy 156.222591 -392.999744) (xy 156.191818 -393.046257) (xy 156.154601 -393.087794)
			(xy 156.111733 -393.123469) (xy 156.064127 -393.152523) (xy 156.012798 -393.174335) (xy 155.958841 -393.188441)
			(xy 155.903404 -393.194541) (xy 155.84767 -393.192504) (xy 155.792827 -393.182374) (xy 155.740043 -393.164367)
			(xy 155.690443 -393.138866) (xy 155.645085 -393.106415) (xy 155.604936 -393.067706) (xy 155.57085 -393.023563)
			(xy 155.543554 -392.974928) (xy 155.523631 -392.922837) (xy 155.511505 -392.8684) (xy 155.507434 -392.812778)
			(xy 151.709637 -392.812778) (xy 151.708365 -392.821418) (xy 151.692297 -392.874825) (xy 151.668625 -392.925322)
			(xy 151.637852 -392.971835) (xy 151.600635 -393.013372) (xy 151.557767 -393.049047) (xy 151.510161 -393.078101)
			(xy 151.458832 -393.099913) (xy 151.404875 -393.114019) (xy 151.349438 -393.120119) (xy 151.293704 -393.118082)
			(xy 151.238861 -393.107952) (xy 151.186077 -393.089945) (xy 151.136477 -393.064444) (xy 151.091119 -393.031993)
			(xy 151.05097 -392.993284) (xy 151.016884 -392.949141) (xy 150.989588 -392.900506) (xy 150.969665 -392.848415)
			(xy 150.957539 -392.793978) (xy 150.953468 -392.738356) (xy 149.673844 -392.738356) (xy 149.660297 -392.783385)
			(xy 149.636625 -392.833882) (xy 149.605852 -392.880395) (xy 149.568635 -392.921932) (xy 149.525767 -392.957607)
			(xy 149.478161 -392.986661) (xy 149.426832 -393.008473) (xy 149.372875 -393.022579) (xy 149.317438 -393.028679)
			(xy 149.261704 -393.026642) (xy 149.206861 -393.016512) (xy 149.154077 -392.998505) (xy 149.104477 -392.973004)
			(xy 149.059119 -392.940553) (xy 149.01897 -392.901844) (xy 148.984884 -392.857701) (xy 148.957588 -392.809066)
			(xy 148.937665 -392.756975) (xy 148.925539 -392.702538) (xy 148.921468 -392.646916) (xy 136.845294 -392.646916)
			(xy 136.845294 -393.199112) (xy 136.845719 -393.209181) (xy 136.853436 -393.227783) (xy 136.86028 -393.23518)
			(xy 137.22096 -393.59586) (xy 137.22836 -393.602701) (xy 137.246958 -393.61042) (xy 137.257028 -393.610846)
			(xy 154.220164 -393.610846) (xy 154.230228 -393.611282) (xy 154.248811 -393.619018) (xy 154.256232 -393.625832)
			(xy 154.561794 -393.931394) (xy 154.568642 -393.938792) (xy 154.57638 -393.95739) (xy 154.57678 -393.967462)
			(xy 154.57678 -395.4272) (xy 157.53664 -395.4272) (xy 157.540711 -395.371578) (xy 157.552837 -395.317141)
			(xy 157.57276 -395.26505) (xy 157.600056 -395.216415) (xy 157.634142 -395.172272) (xy 157.674291 -395.133563)
			(xy 157.719649 -395.101112) (xy 157.769249 -395.075611) (xy 157.822033 -395.057604) (xy 157.876876 -395.047474)
			(xy 157.93261 -395.045437) (xy 157.988047 -395.051537) (xy 158.042004 -395.065643) (xy 158.093333 -395.087455)
			(xy 158.140939 -395.116509) (xy 158.183807 -395.152184) (xy 158.221024 -395.193721) (xy 158.251797 -395.240234)
			(xy 158.275469 -395.290731) (xy 158.291537 -395.344138) (xy 158.299657 -395.399314) (xy 158.300166 -395.4272)
			(xy 158.299657 -395.455086) (xy 158.291537 -395.510262) (xy 158.275469 -395.563669) (xy 158.251797 -395.614166)
			(xy 158.221024 -395.660679) (xy 158.183807 -395.702216) (xy 158.140939 -395.737891) (xy 158.093333 -395.766945)
			(xy 158.042004 -395.788757) (xy 157.988047 -395.802863) (xy 157.93261 -395.808963) (xy 157.876876 -395.806926)
			(xy 157.822033 -395.796796) (xy 157.769249 -395.778789) (xy 157.719649 -395.753288) (xy 157.674291 -395.720837)
			(xy 157.634142 -395.682128) (xy 157.600056 -395.637985) (xy 157.57276 -395.58935) (xy 157.552837 -395.537259)
			(xy 157.540711 -395.482822) (xy 157.53664 -395.4272) (xy 154.57678 -395.4272) (xy 154.57678 -397.82289)
			(xy 159.424887 -397.82289) (xy 159.424891 -397.757445) (xy 159.433688 -397.692594) (xy 159.451118 -397.629512)
			(xy 159.476865 -397.569345) (xy 159.493204 -397.540988) (xy 159.496523 -397.534966) (xy 159.500126 -397.5217)
			(xy 159.500316 -397.514826) (xy 159.500316 -396.765526) (xy 159.500112 -396.758654) (xy 159.496512 -396.745391)
			(xy 159.493204 -396.739364) (xy 159.476859 -396.711012) (xy 159.451118 -396.650844) (xy 159.433694 -396.587763)
			(xy 159.424903 -396.522913) (xy 159.424904 -396.45747) (xy 159.433697 -396.39262) (xy 159.451124 -396.32954)
			(xy 159.476867 -396.269373) (xy 159.493204 -396.241016) (xy 159.496513 -396.234989) (xy 159.500122 -396.221727)
			(xy 159.500316 -396.214854) (xy 159.500316 -395.92885) (xy 159.500804 -395.918684) (xy 159.508569 -395.899895)
			(xy 159.522934 -395.885509) (xy 159.541713 -395.877718) (xy 159.551878 -395.877288) (xy 160.268158 -395.877288)
			(xy 160.278333 -395.877699) (xy 160.297136 -395.88548) (xy 160.311525 -395.89987) (xy 160.319302 -395.918675)
			(xy 160.31972 -395.92885) (xy 160.31972 -396.214854) (xy 160.319927 -396.221726) (xy 160.323525 -396.234989)
			(xy 160.326832 -396.241016) (xy 160.343162 -396.269377) (xy 160.368908 -396.329542) (xy 160.386336 -396.392621)
			(xy 160.395131 -396.45747) (xy 160.395132 -396.522913) (xy 160.38634 -396.587762) (xy 160.368914 -396.650842)
			(xy 160.34317 -396.711008) (xy 160.326832 -396.739364) (xy 160.323533 -396.745396) (xy 160.319917 -396.758654)
			(xy 160.31972 -396.765526) (xy 160.31972 -397.514826) (xy 160.319899 -397.5217) (xy 160.323516 -397.534963)
			(xy 160.326832 -397.540988) (xy 160.336199 -397.557288) (xy 161.624808 -397.557288) (xy 161.633599 -397.492439)
			(xy 161.651022 -397.429359) (xy 161.676763 -397.369193) (xy 161.693098 -397.340836) (xy 161.696446 -397.334813)
			(xy 161.700192 -397.321559) (xy 161.700464 -397.314674) (xy 161.700464 -397.028924) (xy 161.701004 -397.018821)
			(xy 161.708727 -397.00015) (xy 161.723007 -396.985856) (xy 161.74167 -396.978114) (xy 161.751772 -396.977616)
			(xy 162.468052 -396.977616) (xy 162.478173 -396.978056) (xy 162.496879 -396.985791) (xy 162.511195 -397.000101)
			(xy 162.51894 -397.018803) (xy 162.51936 -397.028924) (xy 162.51936 -397.314674) (xy 162.519573 -397.321568)
			(xy 162.523315 -397.33484) (xy 162.526726 -397.340836) (xy 162.543073 -397.369187) (xy 162.568818 -397.429355)
			(xy 162.586245 -397.492436) (xy 162.595037 -397.557287) (xy 162.595036 -397.622731) (xy 162.586241 -397.687581)
			(xy 162.568812 -397.750662) (xy 162.543065 -397.810828) (xy 162.536115 -397.82289) (xy 163.824923 -397.82289)
			(xy 163.824927 -397.757445) (xy 163.833725 -397.692593) (xy 163.851157 -397.629511) (xy 163.876906 -397.569344)
			(xy 163.893246 -397.540988) (xy 163.896614 -397.534975) (xy 163.900347 -397.521713) (xy 163.900612 -397.514826)
			(xy 163.900612 -396.765526) (xy 163.900402 -396.758631) (xy 163.896659 -396.745359) (xy 163.893246 -396.739364)
			(xy 163.8769 -396.711013) (xy 163.851156 -396.650845) (xy 163.833731 -396.587764) (xy 163.824939 -396.522913)
			(xy 163.82494 -396.45747) (xy 163.833734 -396.392619) (xy 163.851162 -396.329539) (xy 163.876908 -396.269372)
			(xy 163.893246 -396.241016) (xy 163.896604 -396.234998) (xy 163.900343 -396.22174) (xy 163.900612 -396.214854)
			(xy 163.900612 -395.92885) (xy 163.901167 -395.91873) (xy 163.908873 -395.900015) (xy 163.923138 -395.885658)
			(xy 163.941803 -395.877832) (xy 163.95192 -395.877288) (xy 164.6682 -395.877288) (xy 164.678353 -395.877721)
			(xy 164.697103 -395.885515) (xy 164.711426 -395.899908) (xy 164.719127 -395.918695) (xy 164.719508 -395.92885)
			(xy 164.719508 -396.214854) (xy 164.719758 -396.221744) (xy 164.723489 -396.23501) (xy 164.726874 -396.241016)
			(xy 164.743202 -396.269377) (xy 164.768946 -396.329543) (xy 164.786373 -396.392622) (xy 164.795167 -396.45747)
			(xy 164.795168 -396.522912) (xy 164.786377 -396.587761) (xy 164.768952 -396.650841) (xy 164.74321 -396.711008)
			(xy 164.726874 -396.739364) (xy 164.723524 -396.745386) (xy 164.719779 -396.758641) (xy 164.719508 -396.765526)
			(xy 164.719508 -397.514826) (xy 164.719769 -397.521715) (xy 164.723492 -397.534981) (xy 164.726874 -397.540988)
			(xy 164.73624 -397.557287) (xy 166.024844 -397.557287) (xy 166.033635 -397.492438) (xy 166.051061 -397.429359)
			(xy 166.076803 -397.369192) (xy 166.09314 -397.340836) (xy 166.096437 -397.334803) (xy 166.100055 -397.321546)
			(xy 166.100252 -397.314674) (xy 166.100252 -397.028924) (xy 166.10074 -397.018777) (xy 166.108519 -397.000035)
			(xy 166.122895 -396.985712) (xy 166.141666 -396.978003) (xy 166.151814 -396.977616) (xy 166.868094 -396.977616)
			(xy 166.878217 -396.978131) (xy 166.896934 -396.985852) (xy 166.911289 -397.000129) (xy 166.919113 -397.018803)
			(xy 166.919656 -397.028924) (xy 166.919656 -397.314674) (xy 166.919851 -397.321547) (xy 166.923456 -397.33481)
			(xy 166.926768 -397.340836) (xy 166.943114 -397.369188) (xy 166.968856 -397.429355) (xy 166.986282 -397.492436)
			(xy 166.995073 -397.557287) (xy 166.995072 -397.62273) (xy 166.986278 -397.68758) (xy 166.968851 -397.750661)
			(xy 166.943106 -397.810828) (xy 166.936156 -397.822891) (xy 168.224959 -397.822891) (xy 168.224963 -397.757444)
			(xy 168.233762 -397.692592) (xy 168.251195 -397.629511) (xy 168.276947 -397.569344) (xy 168.293288 -397.540988)
			(xy 168.296606 -397.534965) (xy 168.30021 -397.5217) (xy 168.3004 -397.514826) (xy 168.3004 -396.765526)
			(xy 168.300198 -396.758654) (xy 168.296596 -396.745391) (xy 168.293288 -396.739364) (xy 168.276941 -396.711013)
			(xy 168.251195 -396.650846) (xy 168.233768 -396.587764) (xy 168.224975 -396.522914) (xy 168.224976 -396.457469)
			(xy 168.233771 -396.392619) (xy 168.251201 -396.329538) (xy 168.276948 -396.269372) (xy 168.293288 -396.241016)
			(xy 168.296596 -396.234988) (xy 168.300206 -396.221727) (xy 168.3004 -396.214854) (xy 168.3004 -395.92885)
			(xy 168.300904 -395.918686) (xy 168.308665 -395.8999) (xy 168.323026 -395.885515) (xy 168.341799 -395.877721)
			(xy 168.351962 -395.877288) (xy 169.068242 -395.877288) (xy 169.078423 -395.877631) (xy 169.097228 -395.885439)
			(xy 169.111613 -395.89985) (xy 169.119388 -395.918669) (xy 169.119804 -395.92885) (xy 169.119804 -396.214854)
			(xy 169.120013 -396.221726) (xy 169.12361 -396.234989) (xy 169.126916 -396.241016) (xy 169.143246 -396.269376)
			(xy 169.168993 -396.329542) (xy 169.186422 -396.392621) (xy 169.195217 -396.45747) (xy 169.195218 -396.522913)
			(xy 169.186426 -396.587762) (xy 169.168999 -396.650842) (xy 169.143254 -396.711008) (xy 169.126916 -396.739364)
			(xy 169.123615 -396.745395) (xy 169.12 -396.758654) (xy 169.119804 -396.765526) (xy 169.119804 -397.514826)
			(xy 169.119985 -397.5217) (xy 169.123601 -397.534963) (xy 169.126916 -397.540988) (xy 169.136284 -397.557287)
			(xy 170.42488 -397.557287) (xy 170.433672 -397.492438) (xy 170.451099 -397.429358) (xy 170.476844 -397.369192)
			(xy 170.493182 -397.340836) (xy 170.496528 -397.334812) (xy 170.500276 -397.321559) (xy 170.500548 -397.314674)
			(xy 170.500548 -397.028924) (xy 170.501103 -397.018823) (xy 170.508823 -397.000155) (xy 170.523098 -396.985862)
			(xy 170.541756 -396.978117) (xy 170.551856 -396.977616) (xy 171.268136 -396.977616) (xy 171.278249 -396.978056)
			(xy 171.296931 -396.985808) (xy 171.311225 -397.000119) (xy 171.318956 -397.01881) (xy 171.319444 -397.028924)
			(xy 171.319444 -397.314674) (xy 171.31966 -397.321568) (xy 171.3234 -397.33484) (xy 171.32681 -397.340836)
			(xy 171.343157 -397.369187) (xy 171.368903 -397.429354) (xy 171.386331 -397.492436) (xy 171.395123 -397.557286)
			(xy 171.395122 -397.622731) (xy 171.386327 -397.687581) (xy 171.368898 -397.750662) (xy 171.34315 -397.810828)
			(xy 171.336199 -397.82289) (xy 172.624749 -397.82289) (xy 172.624753 -397.757444) (xy 172.633551 -397.692592)
			(xy 172.650984 -397.629511) (xy 172.676735 -397.569344) (xy 172.693076 -397.540988) (xy 172.696393 -397.534965)
			(xy 172.699998 -397.5217) (xy 172.700188 -397.514826) (xy 172.700188 -396.765526) (xy 172.699987 -396.758653)
			(xy 172.696385 -396.745391) (xy 172.693076 -396.739364) (xy 172.676729 -396.711013) (xy 172.650984 -396.650845)
			(xy 172.633557 -396.587764) (xy 172.624764 -396.522913) (xy 172.624766 -396.457469) (xy 172.633561 -396.392619)
			(xy 172.65099 -396.329538) (xy 172.676737 -396.269372) (xy 172.693076 -396.241016) (xy 172.696383 -396.234988)
			(xy 172.699994 -396.221727) (xy 172.700188 -396.214854) (xy 172.700188 -395.92885) (xy 172.700606 -395.918675)
			(xy 172.708384 -395.899872) (xy 172.722772 -395.885484) (xy 172.741575 -395.877706) (xy 172.75175 -395.877288)
			(xy 173.46803 -395.877288) (xy 173.47821 -395.87764) (xy 173.497015 -395.885445) (xy 173.5114 -395.899852)
			(xy 173.519175 -395.91867) (xy 173.519592 -395.92885) (xy 173.519592 -396.214854) (xy 173.519803 -396.221726)
			(xy 173.523398 -396.234989) (xy 173.526704 -396.241016) (xy 173.543032 -396.269377) (xy 173.568774 -396.329543)
			(xy 173.5862 -396.392622) (xy 173.594993 -396.457471) (xy 173.594993 -396.49019) (xy 177.023784 -396.49019)
			(xy 177.027775 -396.428023) (xy 177.039684 -396.366876) (xy 177.059313 -396.307755) (xy 177.086342 -396.251629)
			(xy 177.120326 -396.19942) (xy 177.160708 -396.151985) (xy 177.206824 -396.110104) (xy 177.257916 -396.074464)
			(xy 177.313147 -396.04565) (xy 177.371609 -396.024136) (xy 177.432343 -396.010274) (xy 177.49435 -396.004292)
			(xy 177.556613 -396.006288) (xy 177.61811 -396.016231) (xy 177.677831 -396.033955) (xy 177.734794 -396.059172)
			(xy 177.788065 -396.091465) (xy 177.83677 -396.130305) (xy 177.880107 -396.175055) (xy 177.917367 -396.224979)
			(xy 177.947936 -396.279258) (xy 177.971314 -396.337001) (xy 177.987115 -396.397259) (xy 177.995081 -396.459042)
			(xy 177.99558 -396.49019) (xy 177.995081 -396.521338) (xy 177.987115 -396.583121) (xy 177.971314 -396.643379)
			(xy 177.947936 -396.701122) (xy 177.917367 -396.755401) (xy 177.880107 -396.805325) (xy 177.83677 -396.850075)
			(xy 177.788065 -396.888915) (xy 177.734794 -396.921208) (xy 177.677831 -396.946425) (xy 177.61811 -396.964149)
			(xy 177.556613 -396.974092) (xy 177.49435 -396.976088) (xy 177.432343 -396.970106) (xy 177.371609 -396.956244)
			(xy 177.313147 -396.93473) (xy 177.257916 -396.905916) (xy 177.206824 -396.870276) (xy 177.160708 -396.828395)
			(xy 177.120326 -396.78096) (xy 177.086342 -396.728751) (xy 177.059313 -396.672625) (xy 177.039684 -396.613504)
			(xy 177.027775 -396.552357) (xy 177.023784 -396.49019) (xy 173.594993 -396.49019) (xy 173.594994 -396.522912)
			(xy 173.586203 -396.587761) (xy 173.56878 -396.65084) (xy 173.543039 -396.711007) (xy 173.526704 -396.739364)
			(xy 173.523402 -396.745395) (xy 173.519788 -396.758654) (xy 173.519592 -396.765526) (xy 173.519592 -397.514826)
			(xy 173.519775 -397.5217) (xy 173.523389 -397.534963) (xy 173.526704 -397.540988) (xy 173.53607 -397.557288)
			(xy 174.82493 -397.557288) (xy 174.833721 -397.492439) (xy 174.851146 -397.429359) (xy 174.876888 -397.369192)
			(xy 174.893224 -397.340836) (xy 174.896528 -397.334806) (xy 174.90014 -397.321546) (xy 174.900336 -397.314674)
			(xy 174.900336 -397.028924) (xy 174.900742 -397.018767) (xy 174.908536 -397.000008) (xy 174.922939 -396.985682)
			(xy 174.941739 -396.977988) (xy 174.951898 -396.977616) (xy 175.668178 -396.977616) (xy 175.6783 -396.978144)
			(xy 175.697017 -396.98586) (xy 175.711373 -397.000133) (xy 175.719197 -397.018805) (xy 175.71974 -397.028924)
			(xy 175.71974 -397.314674) (xy 175.719937 -397.321547) (xy 175.723541 -397.33481) (xy 175.726852 -397.340836)
			(xy 175.743198 -397.369187) (xy 175.768942 -397.429355) (xy 175.786368 -397.492436) (xy 175.79516 -397.557287)
			(xy 175.795158 -397.62273) (xy 175.786364 -397.687581) (xy 175.768936 -397.750661) (xy 175.752033 -397.790162)
			(xy 177.023784 -397.790162) (xy 177.027775 -397.727995) (xy 177.039684 -397.666848) (xy 177.059313 -397.607727)
			(xy 177.086342 -397.551601) (xy 177.120326 -397.499392) (xy 177.160708 -397.451957) (xy 177.206824 -397.410076)
			(xy 177.257916 -397.374436) (xy 177.313147 -397.345622) (xy 177.371609 -397.324108) (xy 177.432343 -397.310246)
			(xy 177.49435 -397.304264) (xy 177.556613 -397.30626) (xy 177.61811 -397.316203) (xy 177.677831 -397.333927)
			(xy 177.734794 -397.359144) (xy 177.788065 -397.391437) (xy 177.83677 -397.430277) (xy 177.880107 -397.475027)
			(xy 177.917367 -397.524951) (xy 177.947936 -397.57923) (xy 177.9523 -397.59001) (xy 179.223932 -397.59001)
			(xy 179.227923 -397.527843) (xy 179.239832 -397.466696) (xy 179.259461 -397.407575) (xy 179.28649 -397.351449)
			(xy 179.320474 -397.29924) (xy 179.360856 -397.251805) (xy 179.406972 -397.209924) (xy 179.458064 -397.174284)
			(xy 179.513295 -397.14547) (xy 179.571757 -397.123956) (xy 179.632491 -397.110094) (xy 179.694498 -397.104112)
			(xy 179.756761 -397.106108) (xy 179.818258 -397.116051) (xy 179.877979 -397.133775) (xy 179.934942 -397.158992)
			(xy 179.988213 -397.191285) (xy 180.036918 -397.230125) (xy 180.080255 -397.274875) (xy 180.117515 -397.324799)
			(xy 180.148084 -397.379078) (xy 180.171462 -397.436821) (xy 180.187263 -397.497079) (xy 180.195229 -397.558862)
			(xy 180.195728 -397.59001) (xy 180.195229 -397.621158) (xy 180.187263 -397.682941) (xy 180.171462 -397.743199)
			(xy 180.148084 -397.800942) (xy 180.117515 -397.855221) (xy 180.080255 -397.905145) (xy 180.036918 -397.949895)
			(xy 179.988213 -397.988735) (xy 179.934942 -398.021028) (xy 179.877979 -398.046245) (xy 179.818258 -398.063969)
			(xy 179.756761 -398.073912) (xy 179.694498 -398.075908) (xy 179.632491 -398.069926) (xy 179.571757 -398.056064)
			(xy 179.513295 -398.03455) (xy 179.458064 -398.005736) (xy 179.406972 -397.970096) (xy 179.360856 -397.928215)
			(xy 179.320474 -397.88078) (xy 179.28649 -397.828571) (xy 179.259461 -397.772445) (xy 179.239832 -397.713324)
			(xy 179.227923 -397.652177) (xy 179.223932 -397.59001) (xy 177.9523 -397.59001) (xy 177.971314 -397.636973)
			(xy 177.987115 -397.697231) (xy 177.995081 -397.759014) (xy 177.99558 -397.790162) (xy 177.995081 -397.82131)
			(xy 177.987115 -397.883093) (xy 177.971314 -397.943351) (xy 177.947936 -398.001094) (xy 177.917367 -398.055373)
			(xy 177.880107 -398.105297) (xy 177.83677 -398.150047) (xy 177.788065 -398.188887) (xy 177.734794 -398.22118)
			(xy 177.677831 -398.246397) (xy 177.61811 -398.264121) (xy 177.556613 -398.274064) (xy 177.49435 -398.27606)
			(xy 177.432343 -398.270078) (xy 177.371609 -398.256216) (xy 177.313147 -398.234702) (xy 177.257916 -398.205888)
			(xy 177.206824 -398.170248) (xy 177.160708 -398.128367) (xy 177.120326 -398.080932) (xy 177.086342 -398.028723)
			(xy 177.059313 -397.972597) (xy 177.039684 -397.913476) (xy 177.027775 -397.852329) (xy 177.023784 -397.790162)
			(xy 175.752033 -397.790162) (xy 175.74319 -397.810828) (xy 175.726852 -397.839184) (xy 175.723547 -397.845214)
			(xy 175.719935 -397.858473) (xy 175.71974 -397.865346) (xy 175.71974 -398.6149) (xy 175.719927 -398.621774)
			(xy 175.723538 -398.635037) (xy 175.726852 -398.641062) (xy 175.74322 -398.669401) (xy 175.768962 -398.729572)
			(xy 175.786385 -398.792655) (xy 175.795174 -398.857508) (xy 175.795172 -398.890236) (xy 179.223932 -398.890236)
			(xy 179.227923 -398.828069) (xy 179.239832 -398.766922) (xy 179.259461 -398.707801) (xy 179.28649 -398.651675)
			(xy 179.320474 -398.599466) (xy 179.360856 -398.552031) (xy 179.406972 -398.51015) (xy 179.458064 -398.47451)
			(xy 179.513295 -398.445696) (xy 179.571757 -398.424182) (xy 179.632491 -398.41032) (xy 179.694498 -398.404338)
			(xy 179.756761 -398.406334) (xy 179.818258 -398.416277) (xy 179.877979 -398.434001) (xy 179.934942 -398.459218)
			(xy 179.988213 -398.491511) (xy 180.036918 -398.530351) (xy 180.080255 -398.575101) (xy 180.117515 -398.625025)
			(xy 180.148084 -398.679304) (xy 180.171462 -398.737047) (xy 180.187263 -398.797305) (xy 180.195229 -398.859088)
			(xy 180.195728 -398.890236) (xy 180.195229 -398.921384) (xy 180.187263 -398.983167) (xy 180.171462 -399.043425)
			(xy 180.148084 -399.101168) (xy 180.117515 -399.155447) (xy 180.080255 -399.205371) (xy 180.036918 -399.250121)
			(xy 179.988213 -399.288961) (xy 179.934942 -399.321254) (xy 179.877979 -399.346471) (xy 179.818258 -399.364195)
			(xy 179.756761 -399.374138) (xy 179.694498 -399.376134) (xy 179.632491 -399.370152) (xy 179.571757 -399.35629)
			(xy 179.513295 -399.334776) (xy 179.458064 -399.305962) (xy 179.406972 -399.270322) (xy 179.360856 -399.228441)
			(xy 179.320474 -399.181006) (xy 179.28649 -399.128797) (xy 179.259461 -399.072671) (xy 179.239832 -399.01355)
			(xy 179.227923 -398.952403) (xy 179.223932 -398.890236) (xy 175.795172 -398.890236) (xy 175.79517 -398.922954)
			(xy 175.786373 -398.987805) (xy 175.768941 -399.050887) (xy 175.743192 -399.111054) (xy 175.726852 -399.13941)
			(xy 175.723538 -399.145435) (xy 175.719931 -399.158698) (xy 175.71974 -399.165572) (xy 175.71974 -399.451576)
			(xy 175.71926 -399.461724) (xy 175.71148 -399.480468) (xy 175.697101 -399.494791) (xy 175.678327 -399.502498)
			(xy 175.668178 -399.502884) (xy 174.951898 -399.502884) (xy 174.941774 -399.502376) (xy 174.923058 -399.494652)
			(xy 174.908702 -399.480372) (xy 174.900879 -399.461697) (xy 174.900336 -399.451576) (xy 174.900336 -399.165572)
			(xy 174.90015 -399.158698) (xy 174.896537 -399.145436) (xy 174.893224 -399.13941) (xy 174.876918 -399.111037)
			(xy 174.851172 -399.050874) (xy 174.833742 -398.987797) (xy 174.824946 -398.922951) (xy 174.824942 -398.857511)
			(xy 174.83373 -398.792663) (xy 174.851151 -398.729584) (xy 174.87689 -398.669418) (xy 174.893224 -398.641062)
			(xy 174.896554 -398.635045) (xy 174.90015 -398.621775) (xy 174.900336 -398.6149) (xy 174.900336 -397.865346)
			(xy 174.900122 -397.858474) (xy 174.896528 -397.845212) (xy 174.893224 -397.839184) (xy 174.876896 -397.810823)
			(xy 174.851152 -397.750657) (xy 174.833725 -397.687578) (xy 174.824931 -397.62273) (xy 174.82493 -397.557288)
			(xy 173.53607 -397.557288) (xy 173.543008 -397.569362) (xy 173.568752 -397.629525) (xy 173.586181 -397.692602)
			(xy 173.594977 -397.757448) (xy 173.594981 -397.822887) (xy 173.586194 -397.887734) (xy 173.568774 -397.950813)
			(xy 173.543037 -398.010979) (xy 173.526704 -398.039336) (xy 173.523377 -398.045355) (xy 173.519779 -398.058623)
			(xy 173.519592 -398.065498) (xy 173.519592 -398.351502) (xy 173.519069 -398.361656) (xy 173.511299 -398.38042)
			(xy 173.496943 -398.394784) (xy 173.478184 -398.402563) (xy 173.46803 -398.403064) (xy 172.75175 -398.403064)
			(xy 172.741582 -398.402595) (xy 172.722789 -398.394827) (xy 172.708402 -398.380455) (xy 172.700615 -398.36167)
			(xy 172.700188 -398.351502) (xy 172.700188 -398.065498) (xy 172.699999 -398.058625) (xy 172.696389 -398.045362)
			(xy 172.693076 -398.039336) (xy 172.676705 -398.010998) (xy 172.650962 -397.950827) (xy 172.633538 -397.887744)
			(xy 172.624749 -397.82289) (xy 171.336199 -397.82289) (xy 171.32681 -397.839184) (xy 171.323456 -397.845204)
			(xy 171.319713 -397.85846) (xy 171.319444 -397.865346) (xy 171.319444 -398.6149) (xy 171.31965 -398.621795)
			(xy 171.323397 -398.635067) (xy 171.32681 -398.641062) (xy 171.343179 -398.669401) (xy 171.368923 -398.729571)
			(xy 171.386348 -398.792655) (xy 171.395138 -398.857508) (xy 171.395134 -398.922954) (xy 171.386336 -398.987806)
			(xy 171.368903 -399.050887) (xy 171.343151 -399.111054) (xy 171.32681 -399.13941) (xy 171.323447 -399.145426)
			(xy 171.31971 -399.158685) (xy 171.319444 -399.165572) (xy 171.319444 -399.451576) (xy 171.318896 -399.461678)
			(xy 171.311175 -399.480347) (xy 171.296897 -399.494641) (xy 171.278237 -399.502385) (xy 171.268136 -399.502884)
			(xy 170.551856 -399.502884) (xy 170.541742 -399.50245) (xy 170.52306 -399.494695) (xy 170.508766 -399.480383)
			(xy 170.501036 -399.46169) (xy 170.500548 -399.451576) (xy 170.500548 -399.165572) (xy 170.500316 -399.158679)
			(xy 170.496587 -399.145407) (xy 170.493182 -399.13941) (xy 170.476874 -399.111037) (xy 170.451125 -399.050875)
			(xy 170.433693 -398.987798) (xy 170.424896 -398.922951) (xy 170.424892 -398.85751) (xy 170.433681 -398.792662)
			(xy 170.451104 -398.729583) (xy 170.476846 -398.669418) (xy 170.493182 -398.641062) (xy 170.496554 -398.635051)
			(xy 170.500286 -398.621788) (xy 170.500548 -398.6149) (xy 170.500548 -397.865346) (xy 170.500326 -397.858452)
			(xy 170.49659 -397.84518) (xy 170.493182 -397.839184) (xy 170.476852 -397.810824) (xy 170.451105 -397.750658)
			(xy 170.433676 -397.687579) (xy 170.424881 -397.62273) (xy 170.42488 -397.557287) (xy 169.136284 -397.557287)
			(xy 169.143223 -397.569361) (xy 169.168972 -397.629524) (xy 169.186403 -397.6926) (xy 169.195201 -397.757447)
			(xy 169.195206 -397.822888) (xy 169.186417 -397.887736) (xy 169.168993 -397.950815) (xy 169.143252 -398.01098)
			(xy 169.126916 -398.039336) (xy 169.12359 -398.045355) (xy 169.119991 -398.058623) (xy 169.119804 -398.065498)
			(xy 169.119804 -398.351502) (xy 169.119269 -398.361655) (xy 169.111502 -398.380416) (xy 169.097149 -398.394779)
			(xy 169.078394 -398.402561) (xy 169.068242 -398.403064) (xy 168.351962 -398.403064) (xy 168.341802 -398.402598)
			(xy 168.323032 -398.394811) (xy 168.308669 -398.380437) (xy 168.300895 -398.361662) (xy 168.3004 -398.351502)
			(xy 168.3004 -398.065498) (xy 168.300209 -398.058625) (xy 168.2966 -398.045362) (xy 168.293288 -398.039336)
			(xy 168.276917 -398.010998) (xy 168.251173 -397.950828) (xy 168.233749 -397.887744) (xy 168.224959 -397.822891)
			(xy 166.936156 -397.822891) (xy 166.926768 -397.839184) (xy 166.923457 -397.84521) (xy 166.919849 -397.858473)
			(xy 166.919656 -397.865346) (xy 166.919656 -398.6149) (xy 166.919841 -398.621774) (xy 166.923453 -398.635037)
			(xy 166.926768 -398.641062) (xy 166.943136 -398.669401) (xy 166.968876 -398.729572) (xy 166.986299 -398.792656)
			(xy 166.995088 -398.857508) (xy 166.995084 -398.922954) (xy 166.986287 -398.987805) (xy 166.968856 -399.050886)
			(xy 166.943108 -399.111054) (xy 166.926768 -399.13941) (xy 166.923447 -399.145432) (xy 166.919846 -399.158698)
			(xy 166.919656 -399.165572) (xy 166.919656 -399.451576) (xy 166.91916 -399.461722) (xy 166.911383 -399.480463)
			(xy 166.89701 -399.494785) (xy 166.878241 -399.502496) (xy 166.868094 -399.502884) (xy 166.151814 -399.502884)
			(xy 166.141691 -399.502363) (xy 166.122975 -399.494644) (xy 166.108619 -399.480369) (xy 166.100795 -399.461696)
			(xy 166.100252 -399.451576) (xy 166.100252 -399.165572) (xy 166.100077 -399.158697) (xy 166.096458 -399.145434)
			(xy 166.09314 -399.13941) (xy 166.076833 -399.111037) (xy 166.051086 -399.050874) (xy 166.033656 -398.987798)
			(xy 166.02486 -398.922951) (xy 166.024856 -398.857511) (xy 166.033644 -398.792663) (xy 166.051066 -398.729584)
			(xy 166.076805 -398.669418) (xy 166.09314 -398.641062) (xy 166.096464 -398.635042) (xy 166.100064 -398.621775)
			(xy 166.100252 -398.6149) (xy 166.100252 -397.865346) (xy 166.100049 -397.858474) (xy 166.096449 -397.84521)
			(xy 166.09314 -397.839184) (xy 166.076811 -397.810823) (xy 166.051066 -397.750658) (xy 166.033639 -397.687578)
			(xy 166.024845 -397.62273) (xy 166.024844 -397.557287) (xy 164.73624 -397.557287) (xy 164.743179 -397.569362)
			(xy 164.768925 -397.629525) (xy 164.786354 -397.692601) (xy 164.795151 -397.757447) (xy 164.795156 -397.822888)
			(xy 164.786368 -397.887735) (xy 164.768947 -397.950814) (xy 164.743208 -398.01098) (xy 164.726874 -398.039336)
			(xy 164.723499 -398.045346) (xy 164.71977 -398.05861) (xy 164.719508 -398.065498) (xy 164.719508 -398.351502)
			(xy 164.718976 -398.361623) (xy 164.711257 -398.380335) (xy 164.696985 -398.394689) (xy 164.678318 -398.402517)
			(xy 164.6682 -398.403064) (xy 163.95192 -398.403064) (xy 163.941763 -398.402661) (xy 163.923004 -398.394866)
			(xy 163.908678 -398.380462) (xy 163.900984 -398.361662) (xy 163.900612 -398.351502) (xy 163.900612 -398.065498)
			(xy 163.900413 -398.058602) (xy 163.896662 -398.04533) (xy 163.893246 -398.039336) (xy 163.876876 -398.010998)
			(xy 163.851135 -397.950827) (xy 163.833712 -397.887743) (xy 163.824923 -397.82289) (xy 162.536115 -397.82289)
			(xy 162.526726 -397.839184) (xy 162.523365 -397.845201) (xy 162.519628 -397.85846) (xy 162.51936 -397.865346)
			(xy 162.51936 -398.6149) (xy 162.519563 -398.621795) (xy 162.523312 -398.635067) (xy 162.526726 -398.641062)
			(xy 162.543095 -398.669401) (xy 162.568838 -398.729571) (xy 162.586262 -398.792655) (xy 162.595052 -398.857508)
			(xy 162.595048 -398.922954) (xy 162.58625 -398.987806) (xy 162.568817 -399.050887) (xy 162.543067 -399.111054)
			(xy 162.526726 -399.13941) (xy 162.523356 -399.145422) (xy 162.519625 -399.158685) (xy 162.51936 -399.165572)
			(xy 162.51936 -399.451576) (xy 162.518964 -399.461702) (xy 162.511216 -399.480413) (xy 162.496893 -399.494729)
			(xy 162.478178 -399.502468) (xy 162.468052 -399.502884) (xy 161.751772 -399.502884) (xy 161.741659 -399.502438)
			(xy 161.722978 -399.494688) (xy 161.708683 -399.480379) (xy 161.700952 -399.461689) (xy 161.700464 -399.451576)
			(xy 161.700464 -399.165572) (xy 161.70023 -399.158679) (xy 161.696502 -399.145407) (xy 161.693098 -399.13941)
			(xy 161.676792 -399.111037) (xy 161.651048 -399.050873) (xy 161.63362 -398.987797) (xy 161.624824 -398.922951)
			(xy 161.624819 -398.857511) (xy 161.633607 -398.792664) (xy 161.651027 -398.729585) (xy 161.676764 -398.669419)
			(xy 161.693098 -398.641062) (xy 161.696471 -398.635051) (xy 161.700202 -398.621788) (xy 161.700464 -398.6149)
			(xy 161.700464 -397.865346) (xy 161.70024 -397.858453) (xy 161.696505 -397.845181) (xy 161.693098 -397.839184)
			(xy 161.67677 -397.810823) (xy 161.651028 -397.750657) (xy 161.633602 -397.687578) (xy 161.624809 -397.622729)
			(xy 161.624808 -397.557288) (xy 160.336199 -397.557288) (xy 160.343138 -397.569362) (xy 160.368886 -397.629524)
			(xy 160.386318 -397.6926) (xy 160.395115 -397.757447) (xy 160.395119 -397.822888) (xy 160.386331 -397.887736)
			(xy 160.368908 -397.950814) (xy 160.343168 -398.01098) (xy 160.326832 -398.039336) (xy 160.323507 -398.045356)
			(xy 160.319908 -398.058623) (xy 160.31972 -398.065498) (xy 160.31972 -398.351502) (xy 160.319337 -398.361679)
			(xy 160.311543 -398.380482) (xy 160.297145 -398.394868) (xy 160.278335 -398.402645) (xy 160.268158 -398.403064)
			(xy 159.551878 -398.403064) (xy 159.541719 -398.402585) (xy 159.52295 -398.394804) (xy 159.508585 -398.380433)
			(xy 159.500811 -398.361661) (xy 159.500316 -398.351502) (xy 159.500316 -398.065498) (xy 159.500123 -398.058625)
			(xy 159.496515 -398.045362) (xy 159.493204 -398.039336) (xy 159.476836 -398.010997) (xy 159.451096 -397.950826)
			(xy 159.433675 -397.887742) (xy 159.424887 -397.82289) (xy 154.57678 -397.82289) (xy 154.57678 -401.722803)
			(xy 159.424896 -401.722803) (xy 159.424898 -401.657359) (xy 159.433693 -401.592509) (xy 159.451121 -401.529428)
			(xy 159.476866 -401.469261) (xy 159.493204 -401.440904) (xy 159.496518 -401.434879) (xy 159.500124 -401.421615)
			(xy 159.500316 -401.414742) (xy 159.500316 -400.665442) (xy 159.500106 -400.65857) (xy 159.49651 -400.645307)
			(xy 159.493204 -400.63928) (xy 159.476873 -400.610921) (xy 159.45113 -400.550754) (xy 159.433705 -400.487675)
			(xy 159.424912 -400.422826) (xy 159.424911 -400.357384) (xy 159.433703 -400.292535) (xy 159.451127 -400.229455)
			(xy 159.476868 -400.169289) (xy 159.493204 -400.140932) (xy 159.496508 -400.134902) (xy 159.50012 -400.121642)
			(xy 159.500316 -400.11477) (xy 159.500316 -399.828766) (xy 159.500805 -399.818609) (xy 159.508586 -399.799843)
			(xy 159.522953 -399.78548) (xy 159.541721 -399.777703) (xy 159.551878 -399.777204) (xy 160.268158 -399.777204)
			(xy 160.278323 -399.777697) (xy 160.29711 -399.785462) (xy 160.311495 -399.799826) (xy 160.319288 -399.818602)
			(xy 160.31972 -399.828766) (xy 160.31972 -400.11477) (xy 160.319921 -400.121643) (xy 160.323523 -400.134905)
			(xy 160.326832 -400.140932) (xy 160.343175 -400.169285) (xy 160.36892 -400.229452) (xy 160.386347 -400.292533)
			(xy 160.39514 -400.357383) (xy 160.395139 -400.422827) (xy 160.386345 -400.487677) (xy 160.368917 -400.550758)
			(xy 160.343171 -400.610924) (xy 160.326832 -400.63928) (xy 160.323527 -400.645309) (xy 160.319915 -400.658569)
			(xy 160.31972 -400.665442) (xy 160.31972 -401.414742) (xy 160.319932 -401.421614) (xy 160.323526 -401.434877)
			(xy 160.326832 -401.440904) (xy 160.343152 -401.46927) (xy 160.368899 -401.529434) (xy 160.386328 -401.592512)
			(xy 160.395124 -401.65736) (xy 160.395127 -401.722802) (xy 160.386336 -401.787651) (xy 160.368911 -401.85073)
			(xy 160.343169 -401.910896) (xy 160.326832 -401.939252) (xy 160.323501 -401.945269) (xy 160.319906 -401.958539)
			(xy 160.31972 -401.965414) (xy 160.31972 -402.251418) (xy 160.31935 -402.261596) (xy 160.311551 -402.280399)
			(xy 160.297149 -402.294785) (xy 160.278336 -402.302562) (xy 160.268158 -402.30298) (xy 159.551878 -402.30298)
			(xy 159.541721 -402.302485) (xy 159.522955 -402.294707) (xy 159.508591 -402.280342) (xy 159.500814 -402.261575)
			(xy 159.500316 -402.251418) (xy 159.500316 -401.965414) (xy 159.500117 -401.958541) (xy 159.496513 -401.945279)
			(xy 159.493204 -401.939252) (xy 159.476849 -401.910906) (xy 159.451109 -401.850736) (xy 159.433686 -401.787654)
			(xy 159.424896 -401.722803) (xy 154.57678 -401.722803) (xy 154.57678 -402.822882) (xy 161.624776 -402.822882)
			(xy 161.624781 -402.757436) (xy 161.633579 -402.692584) (xy 161.651011 -402.629503) (xy 161.676759 -402.569335)
			(xy 161.693098 -402.540978) (xy 161.696466 -402.534965) (xy 161.7002 -402.521703) (xy 161.700464 -402.514816)
			(xy 161.700464 -401.765516) (xy 161.700251 -401.758622) (xy 161.696509 -401.74535) (xy 161.693098 -401.739354)
			(xy 161.676745 -401.711007) (xy 161.651005 -401.650838) (xy 161.633582 -401.587756) (xy 161.624792 -401.522905)
			(xy 161.624794 -401.457461) (xy 161.633589 -401.392611) (xy 161.651016 -401.32953) (xy 161.676761 -401.269363)
			(xy 161.693098 -401.241006) (xy 161.696456 -401.234988) (xy 161.700196 -401.22173) (xy 161.700464 -401.214844)
			(xy 161.700464 -400.92884) (xy 161.700948 -400.918725) (xy 161.708676 -400.900029) (xy 161.722972 -400.885714)
			(xy 161.741657 -400.877961) (xy 161.751772 -400.877532) (xy 162.468052 -400.877532) (xy 162.478175 -400.877956)
			(xy 162.496884 -400.885694) (xy 162.511201 -400.900009) (xy 162.518942 -400.918717) (xy 162.51936 -400.92884)
			(xy 162.51936 -401.214844) (xy 162.519585 -401.221737) (xy 162.523319 -401.23501) (xy 162.526726 -401.241006)
			(xy 162.543048 -401.269371) (xy 162.568795 -401.329535) (xy 162.586224 -401.392614) (xy 162.59502 -401.457462)
			(xy 162.595022 -401.522904) (xy 162.586231 -401.587753) (xy 162.568806 -401.650832) (xy 162.543063 -401.710998)
			(xy 162.536262 -401.722803) (xy 163.824932 -401.722803) (xy 163.824934 -401.657359) (xy 163.83373 -401.592508)
			(xy 163.85116 -401.529427) (xy 163.876907 -401.46926) (xy 163.893246 -401.440904) (xy 163.896608 -401.434888)
			(xy 163.900345 -401.421628) (xy 163.900612 -401.414742) (xy 163.900612 -400.665442) (xy 163.900396 -400.658548)
			(xy 163.896656 -400.645276) (xy 163.893246 -400.63928) (xy 163.876913 -400.610921) (xy 163.851169 -400.550755)
			(xy 163.833742 -400.487676) (xy 163.824948 -400.422826) (xy 163.824947 -400.357384) (xy 163.833739 -400.292535)
			(xy 163.851165 -400.229455) (xy 163.876909 -400.169288) (xy 163.893246 -400.140932) (xy 163.896598 -400.134911)
			(xy 163.900341 -400.121655) (xy 163.900612 -400.11477) (xy 163.900612 -399.828766) (xy 163.901098 -399.818641)
			(xy 163.908832 -399.799924) (xy 163.923117 -399.78557) (xy 163.941797 -399.777747) (xy 163.95192 -399.777204)
			(xy 164.6682 -399.777204) (xy 164.678355 -399.777622) (xy 164.697108 -399.785418) (xy 164.711431 -399.799816)
			(xy 164.71913 -399.818609) (xy 164.719508 -399.828766) (xy 164.719508 -400.11477) (xy 164.719752 -400.121661)
			(xy 164.723487 -400.134927) (xy 164.726874 -400.140932) (xy 164.743216 -400.169286) (xy 164.768959 -400.229453)
			(xy 164.786384 -400.292534) (xy 164.795176 -400.357384) (xy 164.795176 -400.422827) (xy 164.786382 -400.487676)
			(xy 164.768955 -400.550757) (xy 164.743211 -400.610924) (xy 164.726874 -400.63928) (xy 164.723519 -400.6453)
			(xy 164.719777 -400.658556) (xy 164.719508 -400.665442) (xy 164.719508 -401.414742) (xy 164.719762 -401.421632)
			(xy 164.72349 -401.434898) (xy 164.726874 -401.440904) (xy 164.743192 -401.469271) (xy 164.768937 -401.529435)
			(xy 164.786365 -401.592513) (xy 164.79516 -401.657361) (xy 164.795163 -401.722802) (xy 164.786373 -401.78765)
			(xy 164.76895 -401.850729) (xy 164.743209 -401.910896) (xy 164.726874 -401.939252) (xy 164.723494 -401.945259)
			(xy 164.719768 -401.958525) (xy 164.719508 -401.965414) (xy 164.719508 -402.251418) (xy 164.71899 -402.26154)
			(xy 164.711265 -402.280253) (xy 164.696989 -402.294607) (xy 164.678319 -402.302434) (xy 164.6682 -402.30298)
			(xy 163.95192 -402.30298) (xy 163.941765 -402.302562) (xy 163.923009 -402.294769) (xy 163.908684 -402.280371)
			(xy 163.900987 -402.261575) (xy 163.900612 -402.251418) (xy 163.900612 -401.965414) (xy 163.900407 -401.958519)
			(xy 163.89666 -401.945247) (xy 163.893246 -401.939252) (xy 163.87689 -401.910906) (xy 163.851147 -401.850737)
			(xy 163.833723 -401.787655) (xy 163.824932 -401.722803) (xy 162.536262 -401.722803) (xy 162.526726 -401.739354)
			(xy 162.523341 -401.745359) (xy 162.519619 -401.758627) (xy 162.51936 -401.765516) (xy 162.51936 -402.514816)
			(xy 162.519596 -402.521709) (xy 162.523322 -402.534981) (xy 162.526726 -402.540978) (xy 162.543024 -402.569356)
			(xy 162.568773 -402.629517) (xy 162.586206 -402.692593) (xy 162.595004 -402.757439) (xy 162.59501 -402.822879)
			(xy 162.59501 -402.822882) (xy 166.024812 -402.822882) (xy 166.024817 -402.757436) (xy 166.033616 -402.692584)
			(xy 166.051049 -402.629502) (xy 166.076799 -402.569334) (xy 166.09314 -402.540978) (xy 166.096458 -402.534955)
			(xy 166.100062 -402.52169) (xy 166.100252 -402.514816) (xy 166.100252 -401.765516) (xy 166.10006 -401.758643)
			(xy 166.096452 -401.74538) (xy 166.09314 -401.739354) (xy 166.076786 -401.711007) (xy 166.051043 -401.650838)
			(xy 166.033619 -401.587756) (xy 166.024828 -401.522905) (xy 166.02483 -401.457461) (xy 166.033626 -401.39261)
			(xy 166.051055 -401.329529) (xy 166.076801 -401.269362) (xy 166.09314 -401.241006) (xy 166.096448 -401.234978)
			(xy 166.100059 -401.221717) (xy 166.100252 -401.214844) (xy 166.100252 -400.92884) (xy 166.100754 -400.918694)
			(xy 166.108527 -400.899952) (xy 166.122899 -400.885629) (xy 166.141667 -400.87792) (xy 166.151814 -400.877532)
			(xy 166.868094 -400.877532) (xy 166.878219 -400.878031) (xy 166.896939 -400.885756) (xy 166.911295 -400.900038)
			(xy 166.919116 -400.918717) (xy 166.919656 -400.92884) (xy 166.919656 -401.214844) (xy 166.919862 -401.221716)
			(xy 166.92346 -401.234979) (xy 166.926768 -401.241006) (xy 166.943088 -401.269372) (xy 166.968833 -401.329536)
			(xy 166.986261 -401.392614) (xy 166.995056 -401.457462) (xy 166.995059 -401.522904) (xy 166.986268 -401.587752)
			(xy 166.968845 -401.650831) (xy 166.943104 -401.710998) (xy 166.936303 -401.722804) (xy 168.224968 -401.722804)
			(xy 168.224971 -401.657359) (xy 168.233767 -401.592507) (xy 168.251198 -401.529426) (xy 168.276948 -401.46926)
			(xy 168.293288 -401.440904) (xy 168.2966 -401.434878) (xy 168.300208 -401.421615) (xy 168.3004 -401.414742)
			(xy 168.3004 -400.665442) (xy 168.300192 -400.65857) (xy 168.296595 -400.645307) (xy 168.293288 -400.63928)
			(xy 168.276954 -400.610922) (xy 168.251207 -400.550756) (xy 168.233778 -400.487676) (xy 168.224984 -400.422827)
			(xy 168.224983 -400.357384) (xy 168.233776 -400.292534) (xy 168.251204 -400.229454) (xy 168.27695 -400.169288)
			(xy 168.293288 -400.140932) (xy 168.296591 -400.134901) (xy 168.300204 -400.121642) (xy 168.3004 -400.11477)
			(xy 168.3004 -399.828766) (xy 168.300905 -399.818611) (xy 168.308683 -399.799848) (xy 168.323045 -399.785485)
			(xy 168.341807 -399.777705) (xy 168.351962 -399.777204) (xy 169.068242 -399.777204) (xy 169.078398 -399.777698)
			(xy 169.097162 -399.78548) (xy 169.111524 -399.799845) (xy 169.119303 -399.81861) (xy 169.119804 -399.828766)
			(xy 169.119804 -400.11477) (xy 169.120007 -400.121642) (xy 169.123608 -400.134905) (xy 169.126916 -400.140932)
			(xy 169.14326 -400.169285) (xy 169.169006 -400.229452) (xy 169.186433 -400.292533) (xy 169.195226 -400.357383)
			(xy 169.195226 -400.422827) (xy 169.186431 -400.487677) (xy 169.169002 -400.550758) (xy 169.143255 -400.610924)
			(xy 169.126916 -400.63928) (xy 169.12361 -400.645309) (xy 169.119998 -400.658569) (xy 169.119804 -400.665442)
			(xy 169.119804 -401.414742) (xy 169.120018 -401.421614) (xy 169.123611 -401.434876) (xy 169.126916 -401.440904)
			(xy 169.143236 -401.46927) (xy 169.168984 -401.529434) (xy 169.186414 -401.592512) (xy 169.19521 -401.65736)
			(xy 169.195213 -401.722802) (xy 169.186422 -401.787651) (xy 169.168997 -401.85073) (xy 169.143253 -401.910896)
			(xy 169.126916 -401.939252) (xy 169.123584 -401.945268) (xy 169.119989 -401.958538) (xy 169.119804 -401.965414)
			(xy 169.119804 -402.251418) (xy 169.119283 -402.261572) (xy 169.11151 -402.280333) (xy 169.097154 -402.294697)
			(xy 169.078396 -402.302478) (xy 169.068242 -402.30298) (xy 168.351962 -402.30298) (xy 168.341804 -402.302498)
			(xy 168.323037 -402.294715) (xy 168.308674 -402.280346) (xy 168.300898 -402.261576) (xy 168.3004 -402.251418)
			(xy 168.3004 -401.965414) (xy 168.300203 -401.958541) (xy 168.296598 -401.945278) (xy 168.293288 -401.939252)
			(xy 168.27693 -401.910907) (xy 168.251186 -401.850738) (xy 168.23376 -401.787656) (xy 168.224968 -401.722804)
			(xy 166.936303 -401.722804) (xy 166.926768 -401.739354) (xy 166.923467 -401.745385) (xy 166.919853 -401.758644)
			(xy 166.919656 -401.765516) (xy 166.919656 -402.514816) (xy 166.919835 -402.52169) (xy 166.923451 -402.534953)
			(xy 166.926768 -402.540978) (xy 166.943064 -402.569357) (xy 166.968812 -402.629518) (xy 166.986242 -402.692594)
			(xy 166.99504 -402.757439) (xy 166.995046 -402.822879) (xy 166.995046 -402.822882) (xy 170.424848 -402.822882)
			(xy 170.424854 -402.757435) (xy 170.433653 -402.692583) (xy 170.451088 -402.629501) (xy 170.47684 -402.569334)
			(xy 170.493182 -402.540978) (xy 170.496549 -402.534964) (xy 170.500284 -402.521703) (xy 170.500548 -402.514816)
			(xy 170.500548 -401.765516) (xy 170.500337 -401.758621) (xy 170.496594 -401.745349) (xy 170.493182 -401.739354)
			(xy 170.476826 -401.711008) (xy 170.451082 -401.650839) (xy 170.433656 -401.587757) (xy 170.424864 -401.522905)
			(xy 170.424866 -401.45746) (xy 170.433663 -401.392609) (xy 170.451093 -401.329528) (xy 170.476842 -401.269362)
			(xy 170.493182 -401.241006) (xy 170.496539 -401.234987) (xy 170.50028 -401.22173) (xy 170.500548 -401.214844)
			(xy 170.500548 -400.92884) (xy 170.501117 -400.91874) (xy 170.508832 -400.900073) (xy 170.523102 -400.885779)
			(xy 170.541757 -400.878033) (xy 170.551856 -400.877532) (xy 171.268136 -400.877532) (xy 171.278265 -400.877887)
			(xy 171.296975 -400.885653) (xy 171.311289 -400.899989) (xy 171.319028 -400.918711) (xy 171.319444 -400.92884)
			(xy 171.319444 -401.214844) (xy 171.319671 -401.221737) (xy 171.323404 -401.235009) (xy 171.32681 -401.241006)
			(xy 171.343132 -401.269371) (xy 171.36888 -401.329535) (xy 171.38631 -401.392613) (xy 171.395106 -401.457462)
			(xy 171.395109 -401.522904) (xy 171.386317 -401.587753) (xy 171.368892 -401.650833) (xy 171.343148 -401.710998)
			(xy 171.336346 -401.722804) (xy 172.624758 -401.722804) (xy 172.62476 -401.657359) (xy 172.633557 -401.592508)
			(xy 172.650987 -401.529427) (xy 172.676736 -401.46926) (xy 172.693076 -401.440904) (xy 172.696388 -401.434878)
			(xy 172.699996 -401.421615) (xy 172.700188 -401.414742) (xy 172.700188 -400.665442) (xy 172.699981 -400.65857)
			(xy 172.696383 -400.645307) (xy 172.693076 -400.63928) (xy 172.676743 -400.610921) (xy 172.650996 -400.550756)
			(xy 172.633568 -400.487676) (xy 172.624774 -400.422827) (xy 172.624773 -400.357384) (xy 172.633566 -400.292534)
			(xy 172.650993 -400.229454) (xy 172.676738 -400.169288) (xy 172.693076 -400.140932) (xy 172.696378 -400.134901)
			(xy 172.699992 -400.121642) (xy 172.700188 -400.11477) (xy 172.700188 -399.828766) (xy 172.700537 -399.818586)
			(xy 172.708343 -399.799781) (xy 172.722752 -399.785395) (xy 172.741569 -399.777621) (xy 172.75175 -399.777204)
			(xy 173.46803 -399.777204) (xy 173.478186 -399.777708) (xy 173.496949 -399.785486) (xy 173.511312 -399.799848)
			(xy 173.519091 -399.818611) (xy 173.519592 -399.828766) (xy 173.519592 -400.11477) (xy 173.519796 -400.121642)
			(xy 173.523396 -400.134905) (xy 173.526704 -400.140932) (xy 173.543045 -400.169286) (xy 173.568786 -400.229454)
			(xy 173.586211 -400.292534) (xy 173.595002 -400.357384) (xy 173.595001 -400.390106) (xy 177.023784 -400.390106)
			(xy 177.027775 -400.327939) (xy 177.039684 -400.266792) (xy 177.059313 -400.207671) (xy 177.086342 -400.151545)
			(xy 177.120326 -400.099336) (xy 177.160708 -400.051901) (xy 177.206824 -400.01002) (xy 177.257916 -399.97438)
			(xy 177.313147 -399.945566) (xy 177.371609 -399.924052) (xy 177.432343 -399.91019) (xy 177.49435 -399.904208)
			(xy 177.556613 -399.906204) (xy 177.61811 -399.916147) (xy 177.677831 -399.933871) (xy 177.734794 -399.959088)
			(xy 177.788065 -399.991381) (xy 177.83677 -400.030221) (xy 177.880107 -400.074971) (xy 177.917367 -400.124895)
			(xy 177.947936 -400.179174) (xy 177.971314 -400.236917) (xy 177.987115 -400.297175) (xy 177.995081 -400.358958)
			(xy 177.99558 -400.390106) (xy 177.995081 -400.421254) (xy 177.987115 -400.483037) (xy 177.971314 -400.543295)
			(xy 177.947936 -400.601038) (xy 177.917367 -400.655317) (xy 177.880107 -400.705241) (xy 177.83677 -400.749991)
			(xy 177.788065 -400.788831) (xy 177.734794 -400.821124) (xy 177.677831 -400.846341) (xy 177.61811 -400.864065)
			(xy 177.556613 -400.874008) (xy 177.49435 -400.876004) (xy 177.432343 -400.870022) (xy 177.371609 -400.85616)
			(xy 177.313147 -400.834646) (xy 177.257916 -400.805832) (xy 177.206824 -400.770192) (xy 177.160708 -400.728311)
			(xy 177.120326 -400.680876) (xy 177.086342 -400.628667) (xy 177.059313 -400.572541) (xy 177.039684 -400.51342)
			(xy 177.027775 -400.452273) (xy 177.023784 -400.390106) (xy 173.595001 -400.390106) (xy 173.595001 -400.422827)
			(xy 173.586208 -400.487676) (xy 173.568783 -400.550756) (xy 173.54304 -400.610923) (xy 173.526704 -400.63928)
			(xy 173.523397 -400.645308) (xy 173.519786 -400.658569) (xy 173.519592 -400.665442) (xy 173.519592 -401.414742)
			(xy 173.519807 -401.421614) (xy 173.5234 -401.434876) (xy 173.526704 -401.440904) (xy 173.543021 -401.469271)
			(xy 173.568765 -401.529436) (xy 173.586192 -401.592513) (xy 173.594986 -401.657361) (xy 173.594989 -401.722802)
			(xy 173.586199 -401.78765) (xy 173.568777 -401.850729) (xy 173.543039 -401.910895) (xy 173.526704 -401.939252)
			(xy 173.523371 -401.945268) (xy 173.519777 -401.958538) (xy 173.519592 -401.965414) (xy 173.519592 -402.251418)
			(xy 173.519082 -402.261573) (xy 173.511308 -402.280337) (xy 173.496947 -402.294701) (xy 173.478185 -402.30248)
			(xy 173.46803 -402.30298) (xy 172.75175 -402.30298) (xy 172.741584 -402.302496) (xy 172.722794 -402.29473)
			(xy 172.708408 -402.280363) (xy 172.700618 -402.261584) (xy 172.700188 -402.251418) (xy 172.700188 -401.965414)
			(xy 172.699992 -401.958541) (xy 172.696387 -401.945278) (xy 172.693076 -401.939252) (xy 172.676719 -401.910907)
			(xy 172.650975 -401.850738) (xy 172.633549 -401.787655) (xy 172.624758 -401.722804) (xy 171.336346 -401.722804)
			(xy 171.32681 -401.739354) (xy 171.323432 -401.745362) (xy 171.319704 -401.758628) (xy 171.319444 -401.765516)
			(xy 171.319444 -402.514816) (xy 171.319682 -402.521708) (xy 171.323407 -402.53498) (xy 171.32681 -402.540978)
			(xy 171.343108 -402.569356) (xy 171.368859 -402.629517) (xy 171.386291 -402.692593) (xy 171.39509 -402.757439)
			(xy 171.395096 -402.822879) (xy 171.395096 -402.822882) (xy 174.824898 -402.822882) (xy 174.824904 -402.757436)
			(xy 174.833702 -402.692584) (xy 174.851134 -402.629502) (xy 174.876884 -402.569334) (xy 174.893224 -402.540978)
			(xy 174.896548 -402.534958) (xy 174.900147 -402.521691) (xy 174.900336 -402.514816) (xy 174.900336 -401.765516)
			(xy 174.900133 -401.758644) (xy 174.896532 -401.745381) (xy 174.893224 -401.739354) (xy 174.87687 -401.711007)
			(xy 174.851129 -401.650838) (xy 174.833705 -401.587756) (xy 174.824914 -401.522905) (xy 174.824916 -401.457461)
			(xy 174.833712 -401.39261) (xy 174.85114 -401.32953) (xy 174.876886 -401.269362) (xy 174.893224 -401.241006)
			(xy 174.896538 -401.234981) (xy 174.900144 -401.221718) (xy 174.900336 -401.214844) (xy 174.900336 -400.92884)
			(xy 174.900755 -400.918684) (xy 174.908544 -400.899926) (xy 174.922943 -400.8856) (xy 174.94174 -400.877905)
			(xy 174.951898 -400.877532) (xy 175.668178 -400.877532) (xy 175.678302 -400.878044) (xy 175.697022 -400.885763)
			(xy 175.711378 -400.900042) (xy 175.7192 -400.918718) (xy 175.71974 -400.92884) (xy 175.71974 -401.214844)
			(xy 175.719948 -401.221716) (xy 175.723545 -401.234979) (xy 175.726852 -401.241006) (xy 175.743173 -401.269371)
			(xy 175.768919 -401.329536) (xy 175.786347 -401.392614) (xy 175.795143 -401.457462) (xy 175.795145 -401.522904)
			(xy 175.786354 -401.587752) (xy 175.76893 -401.650832) (xy 175.752139 -401.690078) (xy 177.023784 -401.690078)
			(xy 177.027775 -401.627911) (xy 177.039684 -401.566764) (xy 177.059313 -401.507643) (xy 177.086342 -401.451517)
			(xy 177.120326 -401.399308) (xy 177.160708 -401.351873) (xy 177.206824 -401.309992) (xy 177.257916 -401.274352)
			(xy 177.313147 -401.245538) (xy 177.371609 -401.224024) (xy 177.432343 -401.210162) (xy 177.49435 -401.20418)
			(xy 177.556613 -401.206176) (xy 177.61811 -401.216119) (xy 177.677831 -401.233843) (xy 177.734794 -401.25906)
			(xy 177.788065 -401.291353) (xy 177.83677 -401.330193) (xy 177.880107 -401.374943) (xy 177.917367 -401.424867)
			(xy 177.947936 -401.479146) (xy 177.952403 -401.49018) (xy 179.223932 -401.49018) (xy 179.227923 -401.428013)
			(xy 179.239832 -401.366866) (xy 179.259461 -401.307745) (xy 179.28649 -401.251619) (xy 179.320474 -401.19941)
			(xy 179.360856 -401.151975) (xy 179.406972 -401.110094) (xy 179.458064 -401.074454) (xy 179.513295 -401.04564)
			(xy 179.571757 -401.024126) (xy 179.632491 -401.010264) (xy 179.694498 -401.004282) (xy 179.756761 -401.006278)
			(xy 179.818258 -401.016221) (xy 179.877979 -401.033945) (xy 179.934942 -401.059162) (xy 179.988213 -401.091455)
			(xy 180.036918 -401.130295) (xy 180.080255 -401.175045) (xy 180.117515 -401.224969) (xy 180.148084 -401.279248)
			(xy 180.171462 -401.336991) (xy 180.187263 -401.397249) (xy 180.195229 -401.459032) (xy 180.195728 -401.49018)
			(xy 180.195229 -401.521328) (xy 180.187263 -401.583111) (xy 180.171462 -401.643369) (xy 180.165097 -401.65909)
			(xy 189.391542 -401.65909) (xy 189.395613 -401.603468) (xy 189.407739 -401.549031) (xy 189.427662 -401.49694)
			(xy 189.454958 -401.448305) (xy 189.489044 -401.404162) (xy 189.529193 -401.365453) (xy 189.574551 -401.333002)
			(xy 189.624151 -401.307501) (xy 189.676935 -401.289494) (xy 189.731778 -401.279364) (xy 189.787512 -401.277327)
			(xy 189.842949 -401.283427) (xy 189.896906 -401.297533) (xy 189.948235 -401.319345) (xy 189.995841 -401.348399)
			(xy 190.038709 -401.384074) (xy 190.075926 -401.425611) (xy 190.106699 -401.472124) (xy 190.130371 -401.522621)
			(xy 190.13215 -401.528534) (xy 191.43548 -401.528534) (xy 191.439551 -401.472912) (xy 191.451677 -401.418475)
			(xy 191.4716 -401.366384) (xy 191.498896 -401.317749) (xy 191.532982 -401.273606) (xy 191.573131 -401.234897)
			(xy 191.618489 -401.202446) (xy 191.668089 -401.176945) (xy 191.720873 -401.158938) (xy 191.775716 -401.148808)
			(xy 191.83145 -401.146771) (xy 191.886887 -401.152871) (xy 191.940844 -401.166977) (xy 191.992173 -401.188789)
			(xy 192.039779 -401.217843) (xy 192.082647 -401.253518) (xy 192.119864 -401.295055) (xy 192.150637 -401.341568)
			(xy 192.174309 -401.392065) (xy 192.190377 -401.445472) (xy 192.198497 -401.500648) (xy 192.199006 -401.528534)
			(xy 192.198497 -401.55642) (xy 192.190377 -401.611596) (xy 192.174309 -401.665003) (xy 192.150637 -401.7155)
			(xy 192.119864 -401.762013) (xy 192.082647 -401.80355) (xy 192.039779 -401.839225) (xy 191.992173 -401.868279)
			(xy 191.940844 -401.890091) (xy 191.886887 -401.904197) (xy 191.83145 -401.910297) (xy 191.775716 -401.90826)
			(xy 191.720873 -401.89813) (xy 191.668089 -401.880123) (xy 191.618489 -401.854622) (xy 191.573131 -401.822171)
			(xy 191.532982 -401.783462) (xy 191.498896 -401.739319) (xy 191.4716 -401.690684) (xy 191.451677 -401.638593)
			(xy 191.439551 -401.584156) (xy 191.43548 -401.528534) (xy 190.13215 -401.528534) (xy 190.146439 -401.576028)
			(xy 190.154559 -401.631204) (xy 190.155068 -401.65909) (xy 190.154559 -401.686976) (xy 190.146439 -401.742152)
			(xy 190.130371 -401.795559) (xy 190.106699 -401.846056) (xy 190.075926 -401.892569) (xy 190.038709 -401.934106)
			(xy 189.995841 -401.969781) (xy 189.948235 -401.998835) (xy 189.896906 -402.020647) (xy 189.842949 -402.034753)
			(xy 189.787512 -402.040853) (xy 189.731778 -402.038816) (xy 189.676935 -402.028686) (xy 189.624151 -402.010679)
			(xy 189.574551 -401.985178) (xy 189.529193 -401.952727) (xy 189.489044 -401.914018) (xy 189.454958 -401.869875)
			(xy 189.427662 -401.82124) (xy 189.407739 -401.769149) (xy 189.395613 -401.714712) (xy 189.391542 -401.65909)
			(xy 180.165097 -401.65909) (xy 180.148084 -401.701112) (xy 180.117515 -401.755391) (xy 180.080255 -401.805315)
			(xy 180.036918 -401.850065) (xy 179.988213 -401.888905) (xy 179.934942 -401.921198) (xy 179.877979 -401.946415)
			(xy 179.818258 -401.964139) (xy 179.756761 -401.974082) (xy 179.694498 -401.976078) (xy 179.632491 -401.970096)
			(xy 179.571757 -401.956234) (xy 179.513295 -401.93472) (xy 179.458064 -401.905906) (xy 179.406972 -401.870266)
			(xy 179.360856 -401.828385) (xy 179.320474 -401.78095) (xy 179.28649 -401.728741) (xy 179.259461 -401.672615)
			(xy 179.239832 -401.613494) (xy 179.227923 -401.552347) (xy 179.223932 -401.49018) (xy 177.952403 -401.49018)
			(xy 177.971314 -401.536889) (xy 177.987115 -401.597147) (xy 177.995081 -401.65893) (xy 177.99558 -401.690078)
			(xy 177.995081 -401.721226) (xy 177.987115 -401.783009) (xy 177.971314 -401.843267) (xy 177.947936 -401.90101)
			(xy 177.917367 -401.955289) (xy 177.880107 -402.005213) (xy 177.83677 -402.049963) (xy 177.788065 -402.088803)
			(xy 177.734794 -402.121096) (xy 177.677831 -402.146313) (xy 177.61811 -402.164037) (xy 177.556613 -402.17398)
			(xy 177.49435 -402.175976) (xy 177.432343 -402.169994) (xy 177.371609 -402.156132) (xy 177.313147 -402.134618)
			(xy 177.257916 -402.105804) (xy 177.206824 -402.070164) (xy 177.160708 -402.028283) (xy 177.120326 -401.980848)
			(xy 177.086342 -401.928639) (xy 177.059313 -401.872513) (xy 177.039684 -401.813392) (xy 177.027775 -401.752245)
			(xy 177.023784 -401.690078) (xy 175.752139 -401.690078) (xy 175.743188 -401.710998) (xy 175.726852 -401.739354)
			(xy 175.723558 -401.745389) (xy 175.719939 -401.758645) (xy 175.71974 -401.765516) (xy 175.71974 -402.222462)
			(xy 198.023478 -402.222462) (xy 198.027549 -402.16684) (xy 198.039675 -402.112403) (xy 198.059598 -402.060312)
			(xy 198.086894 -402.011677) (xy 198.12098 -401.967534) (xy 198.161129 -401.928825) (xy 198.206487 -401.896374)
			(xy 198.256087 -401.870873) (xy 198.308871 -401.852866) (xy 198.363714 -401.842736) (xy 198.419448 -401.840699)
			(xy 198.474885 -401.846799) (xy 198.528842 -401.860905) (xy 198.580171 -401.882717) (xy 198.627777 -401.911771)
			(xy 198.670645 -401.947446) (xy 198.707862 -401.988983) (xy 198.738635 -402.035496) (xy 198.762307 -402.085993)
			(xy 198.778375 -402.1394) (xy 198.786495 -402.194576) (xy 198.787004 -402.222462) (xy 198.786495 -402.250348)
			(xy 198.778375 -402.305524) (xy 198.762307 -402.358931) (xy 198.738635 -402.409428) (xy 198.707862 -402.455941)
			(xy 198.670645 -402.497478) (xy 198.627777 -402.533153) (xy 198.580171 -402.562207) (xy 198.528842 -402.584019)
			(xy 198.474885 -402.598125) (xy 198.419448 -402.604225) (xy 198.363714 -402.602188) (xy 198.308871 -402.592058)
			(xy 198.256087 -402.574051) (xy 198.206487 -402.54855) (xy 198.161129 -402.516099) (xy 198.12098 -402.47739)
			(xy 198.086894 -402.433247) (xy 198.059598 -402.384612) (xy 198.039675 -402.332521) (xy 198.027549 -402.278084)
			(xy 198.023478 -402.222462) (xy 175.71974 -402.222462) (xy 175.71974 -402.514816) (xy 175.719921 -402.52169)
			(xy 175.723536 -402.534953) (xy 175.726852 -402.540978) (xy 175.743149 -402.569357) (xy 175.768897 -402.629518)
			(xy 175.786328 -402.692593) (xy 175.795127 -402.757439) (xy 175.795129 -402.790152) (xy 179.223932 -402.790152)
			(xy 179.227923 -402.727985) (xy 179.239832 -402.666838) (xy 179.259461 -402.607717) (xy 179.28649 -402.551591)
			(xy 179.320474 -402.499382) (xy 179.360856 -402.451947) (xy 179.406972 -402.410066) (xy 179.458064 -402.374426)
			(xy 179.513295 -402.345612) (xy 179.571757 -402.324098) (xy 179.632491 -402.310236) (xy 179.694498 -402.304254)
			(xy 179.756761 -402.30625) (xy 179.818258 -402.316193) (xy 179.877979 -402.333917) (xy 179.934942 -402.359134)
			(xy 179.988213 -402.391427) (xy 180.036918 -402.430267) (xy 180.080255 -402.475017) (xy 180.117515 -402.524941)
			(xy 180.148084 -402.57922) (xy 180.171462 -402.636963) (xy 180.187263 -402.697221) (xy 180.195229 -402.759004)
			(xy 180.195728 -402.790152) (xy 180.195229 -402.8213) (xy 180.187263 -402.883083) (xy 180.171462 -402.943341)
			(xy 180.148084 -403.001084) (xy 180.117515 -403.055363) (xy 180.080255 -403.105287) (xy 180.036918 -403.150037)
			(xy 179.988213 -403.188877) (xy 179.934942 -403.22117) (xy 179.877979 -403.246387) (xy 179.818258 -403.264111)
			(xy 179.756761 -403.274054) (xy 179.694498 -403.27605) (xy 179.632491 -403.270068) (xy 179.571757 -403.256206)
			(xy 179.513295 -403.234692) (xy 179.458064 -403.205878) (xy 179.406972 -403.170238) (xy 179.360856 -403.128357)
			(xy 179.320474 -403.080922) (xy 179.28649 -403.028713) (xy 179.259461 -402.972587) (xy 179.239832 -402.913466)
			(xy 179.227923 -402.852319) (xy 179.223932 -402.790152) (xy 175.795129 -402.790152) (xy 175.795132 -402.822879)
			(xy 175.786345 -402.887726) (xy 175.768924 -402.950804) (xy 175.743186 -403.01097) (xy 175.726852 -403.039326)
			(xy 175.723532 -403.045348) (xy 175.719929 -403.058614) (xy 175.71974 -403.065488) (xy 175.71974 -403.351492)
			(xy 175.719273 -403.361641) (xy 175.711487 -403.380385) (xy 175.697105 -403.394707) (xy 175.678328 -403.402415)
			(xy 175.668178 -403.4028) (xy 174.951898 -403.4028) (xy 174.941776 -403.402276) (xy 174.923063 -403.394555)
			(xy 174.908708 -403.380281) (xy 174.900882 -403.361611) (xy 174.900336 -403.351492) (xy 174.900336 -403.065488)
			(xy 174.900144 -403.058615) (xy 174.896535 -403.045352) (xy 174.893224 -403.039326) (xy 174.876846 -403.010992)
			(xy 174.851107 -402.95082) (xy 174.833686 -402.887735) (xy 174.824898 -402.822882) (xy 171.395096 -402.822882)
			(xy 171.386308 -402.887727) (xy 171.368886 -402.950805) (xy 171.343146 -403.01097) (xy 171.32681 -403.039326)
			(xy 171.323441 -403.045339) (xy 171.319708 -403.058601) (xy 171.319444 -403.065488) (xy 171.319444 -403.351492)
			(xy 171.318909 -403.361595) (xy 171.311183 -403.380264) (xy 171.296901 -403.394558) (xy 171.278238 -403.402301)
			(xy 171.268136 -403.4028) (xy 170.551856 -403.4028) (xy 170.541744 -403.402351) (xy 170.523065 -403.394599)
			(xy 170.508772 -403.380291) (xy 170.501039 -403.361604) (xy 170.500548 -403.351492) (xy 170.500548 -403.065488)
			(xy 170.500309 -403.058596) (xy 170.496585 -403.045324) (xy 170.493182 -403.039326) (xy 170.476803 -403.010993)
			(xy 170.45106 -402.950821) (xy 170.433637 -402.887736) (xy 170.424848 -402.822882) (xy 166.995046 -402.822882)
			(xy 166.986259 -402.887726) (xy 166.968839 -402.950804) (xy 166.943102 -403.01097) (xy 166.926768 -403.039326)
			(xy 166.923442 -403.045345) (xy 166.919844 -403.058613) (xy 166.919656 -403.065488) (xy 166.919656 -403.351492)
			(xy 166.919173 -403.361639) (xy 166.911391 -403.38038) (xy 166.897014 -403.394702) (xy 166.878242 -403.402412)
			(xy 166.868094 -403.4028) (xy 166.151814 -403.4028) (xy 166.141693 -403.402263) (xy 166.12298 -403.394547)
			(xy 166.108624 -403.380277) (xy 166.100798 -403.36161) (xy 166.100252 -403.351492) (xy 166.100252 -403.065488)
			(xy 166.100071 -403.058614) (xy 166.096456 -403.045351) (xy 166.09314 -403.039326) (xy 166.076762 -403.010992)
			(xy 166.051022 -402.95082) (xy 166.0336 -402.887736) (xy 166.024812 -402.822882) (xy 162.59501 -402.822882)
			(xy 162.586222 -402.887726) (xy 162.568801 -402.950805) (xy 162.543061 -403.01097) (xy 162.526726 -403.039326)
			(xy 162.523351 -403.045335) (xy 162.519623 -403.0586) (xy 162.51936 -403.065488) (xy 162.51936 -403.351492)
			(xy 162.518976 -403.361619) (xy 162.511224 -403.38033) (xy 162.496896 -403.394646) (xy 162.478179 -403.402384)
			(xy 162.468052 -403.4028) (xy 161.751772 -403.4028) (xy 161.741661 -403.402338) (xy 161.722983 -403.394591)
			(xy 161.708689 -403.380287) (xy 161.700955 -403.361603) (xy 161.700464 -403.351492) (xy 161.700464 -403.065488)
			(xy 161.700224 -403.058596) (xy 161.6965 -403.045324) (xy 161.693098 -403.039326) (xy 161.676721 -403.010992)
			(xy 161.650983 -402.95082) (xy 161.633563 -402.887735) (xy 161.624776 -402.822882) (xy 154.57678 -402.822882)
			(xy 154.57678 -405.622716) (xy 159.424905 -405.622716) (xy 159.424906 -405.557273) (xy 159.433699 -405.492424)
			(xy 159.451124 -405.429344) (xy 159.476867 -405.369177) (xy 159.493204 -405.34082) (xy 159.496512 -405.334792)
			(xy 159.500122 -405.321531) (xy 159.500316 -405.314658) (xy 159.500316 -404.565358) (xy 159.5001 -404.558487)
			(xy 159.496508 -404.545224) (xy 159.493204 -404.539196) (xy 159.476886 -404.510829) (xy 159.451143 -404.450665)
			(xy 159.433715 -404.387587) (xy 159.424921 -404.322739) (xy 159.424918 -404.257298) (xy 159.433708 -404.19245)
			(xy 159.45113 -404.129371) (xy 159.476869 -404.069205) (xy 159.493204 -404.040848) (xy 159.496538 -404.034833)
			(xy 159.500131 -404.021562) (xy 159.500316 -404.014686) (xy 159.500316 -403.728682) (xy 159.500818 -403.718526)
			(xy 159.508594 -403.69976) (xy 159.522957 -403.685396) (xy 159.541722 -403.677619) (xy 159.551878 -403.67712)
			(xy 160.268158 -403.67712) (xy 160.278325 -403.677598) (xy 160.297115 -403.685366) (xy 160.311501 -403.699735)
			(xy 160.31929 -403.718516) (xy 160.31972 -403.728682) (xy 160.31972 -404.014686) (xy 160.319915 -404.021559)
			(xy 160.323521 -404.034822) (xy 160.326832 -404.040848) (xy 160.343189 -404.069194) (xy 160.368933 -404.129362)
			(xy 160.386358 -404.192445) (xy 160.395149 -404.257296) (xy 160.395147 -404.322741) (xy 160.38635 -404.387592)
			(xy 160.36892 -404.450673) (xy 160.343172 -404.51084) (xy 160.326832 -404.539196) (xy 160.323521 -404.545223)
			(xy 160.319913 -404.558485) (xy 160.31972 -404.565358) (xy 160.31972 -405.314658) (xy 160.319926 -405.32153)
			(xy 160.323524 -405.334793) (xy 160.326832 -405.34082) (xy 160.343165 -405.369179) (xy 160.368911 -405.429344)
			(xy 160.386339 -405.492424) (xy 160.395133 -405.557273) (xy 160.395134 -405.622716) (xy 160.386341 -405.687566)
			(xy 160.368914 -405.750646) (xy 160.34317 -405.810812) (xy 160.326832 -405.839168) (xy 160.323531 -405.8452)
			(xy 160.319917 -405.858458) (xy 160.31972 -405.86533) (xy 160.31972 -406.151334) (xy 160.319363 -406.161513)
			(xy 160.311559 -406.180317) (xy 160.297153 -406.194702) (xy 160.278338 -406.202478) (xy 160.268158 -406.202896)
			(xy 159.551878 -406.202896) (xy 159.541723 -406.202386) (xy 159.52296 -406.19461) (xy 159.508596 -406.18025)
			(xy 159.500817 -406.161489) (xy 159.500316 -406.151334) (xy 159.500316 -405.86533) (xy 159.500111 -405.858458)
			(xy 159.496511 -405.845195) (xy 159.493204 -405.839168) (xy 159.476863 -405.810814) (xy 159.451121 -405.750647)
			(xy 159.433696 -405.687566) (xy 159.424905 -405.622716) (xy 154.57678 -405.622716) (xy 154.57678 -406.722795)
			(xy 161.624785 -406.722795) (xy 161.624789 -406.65735) (xy 161.633585 -406.592499) (xy 161.651014 -406.529418)
			(xy 161.67676 -406.469251) (xy 161.693098 -406.440894) (xy 161.69646 -406.434878) (xy 161.700198 -406.421618)
			(xy 161.700464 -406.414732) (xy 161.700464 -405.665432) (xy 161.700245 -405.658538) (xy 161.696507 -405.645266)
			(xy 161.693098 -405.63927) (xy 161.676759 -405.610915) (xy 161.651017 -405.550748) (xy 161.633593 -405.487667)
			(xy 161.624801 -405.422818) (xy 161.624801 -405.357375) (xy 161.633594 -405.292526) (xy 161.651019 -405.229446)
			(xy 161.676762 -405.169279) (xy 161.693098 -405.140922) (xy 161.69645 -405.134901) (xy 161.700194 -405.121645)
			(xy 161.700464 -405.11476) (xy 161.700464 -404.828756) (xy 161.700948 -404.818649) (xy 161.708694 -404.799977)
			(xy 161.72299 -404.785685) (xy 161.741665 -404.777945) (xy 161.751772 -404.777448) (xy 162.468052 -404.777448)
			(xy 162.478165 -404.777954) (xy 162.496858 -404.785677) (xy 162.511172 -404.799965) (xy 162.518928 -404.818644)
			(xy 162.51936 -404.828756) (xy 162.51936 -405.11476) (xy 162.519579 -405.121654) (xy 162.523317 -405.134926)
			(xy 162.526726 -405.140922) (xy 162.543061 -405.16928) (xy 162.568807 -405.229446) (xy 162.586235 -405.292525)
			(xy 162.595029 -405.357375) (xy 162.59503 -405.422818) (xy 162.586237 -405.487668) (xy 162.568809 -405.550748)
			(xy 162.543064 -405.610914) (xy 162.536263 -405.622717) (xy 163.824941 -405.622717) (xy 163.824942 -405.557273)
			(xy 163.833735 -405.492423) (xy 163.851163 -405.429343) (xy 163.876908 -405.369176) (xy 163.893246 -405.34082)
			(xy 163.896603 -405.334801) (xy 163.900343 -405.321544) (xy 163.900612 -405.314658) (xy 163.900612 -404.565358)
			(xy 163.90039 -404.558464) (xy 163.896654 -404.545192) (xy 163.893246 -404.539196) (xy 163.876927 -404.51083)
			(xy 163.851181 -404.450665) (xy 163.833752 -404.387587) (xy 163.824957 -404.32274) (xy 163.824954 -404.257298)
			(xy 163.833745 -404.19245) (xy 163.851169 -404.12937) (xy 163.87691 -404.069204) (xy 163.893246 -404.040848)
			(xy 163.896628 -404.034842) (xy 163.900352 -404.021575) (xy 163.900612 -404.014686) (xy 163.900612 -403.728682)
			(xy 163.901111 -403.718558) (xy 163.908839 -403.699841) (xy 163.923121 -403.685486) (xy 163.941798 -403.677663)
			(xy 163.95192 -403.67712) (xy 164.6682 -403.67712) (xy 164.678357 -403.677522) (xy 164.697113 -403.685321)
			(xy 164.711437 -403.699724) (xy 164.719133 -403.718523) (xy 164.719508 -403.728682) (xy 164.719508 -404.014686)
			(xy 164.719746 -404.021577) (xy 164.723485 -404.034843) (xy 164.726874 -404.040848) (xy 164.74323 -404.069194)
			(xy 164.768971 -404.129363) (xy 164.786395 -404.192445) (xy 164.795185 -404.257297) (xy 164.795183 -404.322741)
			(xy 164.786387 -404.387592) (xy 164.768959 -404.450672) (xy 164.743212 -404.51084) (xy 164.726874 -404.539196)
			(xy 164.723513 -404.545213) (xy 164.719775 -404.558472) (xy 164.719508 -404.565358) (xy 164.719508 -405.314658)
			(xy 164.719756 -405.321548) (xy 164.723488 -405.334814) (xy 164.726874 -405.34082) (xy 164.743206 -405.369179)
			(xy 164.76895 -405.429345) (xy 164.786376 -405.492425) (xy 164.795169 -405.557274) (xy 164.79517 -405.622716)
			(xy 164.786378 -405.687565) (xy 164.768953 -405.750645) (xy 164.743211 -405.810812) (xy 164.726874 -405.839168)
			(xy 164.723523 -405.84519) (xy 164.719779 -405.858445) (xy 164.719508 -405.86533) (xy 164.719508 -406.151334)
			(xy 164.719003 -406.161457) (xy 164.711273 -406.18017) (xy 164.696993 -406.194523) (xy 164.67832 -406.20235)
			(xy 164.6682 -406.202896) (xy 163.95192 -406.202896) (xy 163.941767 -406.202462) (xy 163.923014 -406.194672)
			(xy 163.90869 -406.180279) (xy 163.90099 -406.161489) (xy 163.900612 -406.151334) (xy 163.900612 -405.86533)
			(xy 163.9004 -405.858435) (xy 163.896658 -405.845163) (xy 163.893246 -405.839168) (xy 163.876903 -405.810815)
			(xy 163.85116 -405.750647) (xy 163.833733 -405.687567) (xy 163.824941 -405.622717) (xy 162.536263 -405.622717)
			(xy 162.526726 -405.63927) (xy 162.52337 -405.645289) (xy 162.51963 -405.658546) (xy 162.51936 -405.665432)
			(xy 162.51936 -406.414732) (xy 162.519589 -406.421625) (xy 162.52332 -406.434897) (xy 162.526726 -406.440894)
			(xy 162.543037 -406.469265) (xy 162.568786 -406.529428) (xy 162.586216 -406.592505) (xy 162.595013 -406.657352)
			(xy 162.595017 -406.722793) (xy 162.595017 -406.722795) (xy 166.024821 -406.722795) (xy 166.024825 -406.65735)
			(xy 166.033622 -406.592499) (xy 166.051052 -406.529417) (xy 166.0768 -406.46925) (xy 166.09314 -406.440894)
			(xy 166.096452 -406.434868) (xy 166.10006 -406.421605) (xy 166.100252 -406.414732) (xy 166.100252 -405.665432)
			(xy 166.100054 -405.658559) (xy 166.096451 -405.645296) (xy 166.09314 -405.63927) (xy 166.076799 -405.610916)
			(xy 166.051056 -405.550749) (xy 166.033629 -405.487668) (xy 166.024837 -405.422818) (xy 166.024837 -405.357375)
			(xy 166.033631 -405.292525) (xy 166.051058 -405.229445) (xy 166.076802 -405.169278) (xy 166.09314 -405.140922)
			(xy 166.096442 -405.134891) (xy 166.100057 -405.121632) (xy 166.100252 -405.11476) (xy 166.100252 -404.828756)
			(xy 166.100685 -404.818605) (xy 166.108486 -404.799861) (xy 166.122878 -404.785541) (xy 166.141661 -404.777834)
			(xy 166.151814 -404.777448) (xy 166.868094 -404.777448) (xy 166.878221 -404.777932) (xy 166.896944 -404.785659)
			(xy 166.911301 -404.799946) (xy 166.919119 -404.818631) (xy 166.919656 -404.828756) (xy 166.919656 -405.11476)
			(xy 166.919856 -405.121633) (xy 166.923458 -405.134896) (xy 166.926768 -405.140922) (xy 166.943102 -405.16928)
			(xy 166.968846 -405.229446) (xy 166.986272 -405.292526) (xy 166.995065 -405.357375) (xy 166.995066 -405.422818)
			(xy 166.986274 -405.487667) (xy 166.968848 -405.550747) (xy 166.943105 -405.610914) (xy 166.936305 -405.622717)
			(xy 168.224977 -405.622717) (xy 168.224978 -405.557273) (xy 168.233772 -405.492422) (xy 168.251201 -405.429342)
			(xy 168.276949 -405.369176) (xy 168.293288 -405.34082) (xy 168.296595 -405.334791) (xy 168.300206 -405.321531)
			(xy 168.3004 -405.314658) (xy 168.3004 -404.565358) (xy 168.300186 -404.558486) (xy 168.296593 -404.545224)
			(xy 168.293288 -404.539196) (xy 168.276968 -404.51083) (xy 168.25122 -404.450666) (xy 168.233789 -404.387588)
			(xy 168.224993 -404.32274) (xy 168.224991 -404.257298) (xy 168.233782 -404.192449) (xy 168.251207 -404.129369)
			(xy 168.276951 -404.069204) (xy 168.293288 -404.040848) (xy 168.29662 -404.034832) (xy 168.300215 -404.021562)
			(xy 168.3004 -404.014686) (xy 168.3004 -403.728682) (xy 168.300917 -403.718528) (xy 168.308691 -403.699765)
			(xy 168.323049 -403.685402) (xy 168.341808 -403.677621) (xy 168.351962 -403.67712) (xy 169.068242 -403.67712)
			(xy 169.0784 -403.677599) (xy 169.097167 -403.685383) (xy 169.11153 -403.699753) (xy 169.119306 -403.718524)
			(xy 169.119804 -403.728682) (xy 169.119804 -404.014686) (xy 169.120001 -404.021559) (xy 169.123606 -404.034822)
			(xy 169.126916 -404.040848) (xy 169.143273 -404.069193) (xy 169.169018 -404.129362) (xy 169.186444 -404.192444)
			(xy 169.195235 -404.257296) (xy 169.195233 -404.322741) (xy 169.186436 -404.387593) (xy 169.169005 -404.450674)
			(xy 169.143256 -404.51084) (xy 169.126916 -404.539196) (xy 169.123604 -404.545222) (xy 169.119996 -404.558485)
			(xy 169.119804 -404.565358) (xy 169.119804 -405.314658) (xy 169.120012 -405.32153) (xy 169.123609 -405.334793)
			(xy 169.126916 -405.34082) (xy 169.14325 -405.369179) (xy 169.168996 -405.429344) (xy 169.186425 -405.492424)
			(xy 169.19522 -405.557273) (xy 169.19522 -405.622716) (xy 169.186427 -405.687566) (xy 169.169 -405.750646)
			(xy 169.143254 -405.810812) (xy 169.126916 -405.839168) (xy 169.123614 -405.845199) (xy 169.12 -405.858458)
			(xy 169.119804 -405.86533) (xy 169.119804 -406.151334) (xy 169.119296 -406.161489) (xy 169.111518 -406.180251)
			(xy 169.097157 -406.194613) (xy 169.078397 -406.202394) (xy 169.068242 -406.202896) (xy 168.351962 -406.202896)
			(xy 168.341806 -406.202399) (xy 168.323042 -406.194618) (xy 168.30868 -406.180254) (xy 168.300901 -406.16149)
			(xy 168.3004 -406.151334) (xy 168.3004 -405.86533) (xy 168.300196 -405.858458) (xy 168.296596 -405.845195)
			(xy 168.293288 -405.839168) (xy 168.276944 -405.810815) (xy 168.251198 -405.750648) (xy 168.23377 -405.687567)
			(xy 168.224977 -405.622717) (xy 166.936305 -405.622717) (xy 166.926768 -405.63927) (xy 166.923462 -405.645299)
			(xy 166.919851 -405.658559) (xy 166.919656 -405.665432) (xy 166.919656 -406.414732) (xy 166.919829 -406.421607)
			(xy 166.923449 -406.43487) (xy 166.926768 -406.440894) (xy 166.943078 -406.469265) (xy 166.968824 -406.529428)
			(xy 166.986253 -406.592505) (xy 166.995049 -406.657352) (xy 166.995053 -406.722793) (xy 166.995053 -406.722795)
			(xy 170.424857 -406.722795) (xy 170.424861 -406.65735) (xy 170.433659 -406.592498) (xy 170.451091 -406.529417)
			(xy 170.476841 -406.46925) (xy 170.493182 -406.440894) (xy 170.496543 -406.434877) (xy 170.500282 -406.421618)
			(xy 170.500548 -406.414732) (xy 170.500548 -405.665432) (xy 170.500331 -405.658538) (xy 170.496592 -405.645266)
			(xy 170.493182 -405.63927) (xy 170.47684 -405.610916) (xy 170.451094 -405.550749) (xy 170.433666 -405.487669)
			(xy 170.424873 -405.422818) (xy 170.424874 -405.357375) (xy 170.433668 -405.292524) (xy 170.451096 -405.229444)
			(xy 170.476843 -405.169278) (xy 170.493182 -405.140922) (xy 170.496533 -405.1349) (xy 170.500278 -405.121645)
			(xy 170.500548 -405.11476) (xy 170.500548 -404.828756) (xy 170.501048 -404.818651) (xy 170.50879 -404.799982)
			(xy 170.523082 -404.78569) (xy 170.541751 -404.777948) (xy 170.551856 -404.777448) (xy 171.268136 -404.777448)
			(xy 171.278241 -404.777954) (xy 171.29691 -404.785694) (xy 171.311201 -404.799984) (xy 171.318944 -404.818651)
			(xy 171.319444 -404.828756) (xy 171.319444 -405.11476) (xy 171.319665 -405.121654) (xy 171.323402 -405.134926)
			(xy 171.32681 -405.140922) (xy 171.343146 -405.16928) (xy 171.368892 -405.229445) (xy 171.386321 -405.292525)
			(xy 171.395115 -405.357375) (xy 171.395116 -405.422818) (xy 171.386323 -405.487668) (xy 171.368895 -405.550748)
			(xy 171.343149 -405.610914) (xy 171.336348 -405.622717) (xy 172.624767 -405.622717) (xy 172.624767 -405.557273)
			(xy 172.633562 -405.492423) (xy 172.65099 -405.429342) (xy 172.676737 -405.369176) (xy 172.693076 -405.34082)
			(xy 172.696382 -405.334791) (xy 172.699994 -405.321531) (xy 172.700188 -405.314658) (xy 172.700188 -404.565358)
			(xy 172.699975 -404.558486) (xy 172.696381 -404.545223) (xy 172.693076 -404.539196) (xy 172.676756 -404.51083)
			(xy 172.651009 -404.450666) (xy 172.633579 -404.387588) (xy 172.624783 -404.32274) (xy 172.62478 -404.257298)
			(xy 172.633571 -404.192449) (xy 172.650996 -404.12937) (xy 172.676739 -404.069204) (xy 172.693076 -404.040848)
			(xy 172.696408 -404.034832) (xy 172.700003 -404.021562) (xy 172.700188 -404.014686) (xy 172.700188 -403.728682)
			(xy 172.70055 -403.718503) (xy 172.708351 -403.699698) (xy 172.722756 -403.685313) (xy 172.74157 -403.677537)
			(xy 172.75175 -403.67712) (xy 173.46803 -403.67712) (xy 173.478187 -403.677608) (xy 173.496954 -403.685389)
			(xy 173.511317 -403.699756) (xy 173.519094 -403.718524) (xy 173.519592 -403.728682) (xy 173.519592 -404.014686)
			(xy 173.51979 -404.021559) (xy 173.523394 -404.034822) (xy 173.526704 -404.040848) (xy 173.543059 -404.069194)
			(xy 173.568799 -404.129364) (xy 173.586221 -404.192446) (xy 173.595011 -404.257297) (xy 173.59501 -404.290022)
			(xy 177.023784 -404.290022) (xy 177.027775 -404.227855) (xy 177.039684 -404.166708) (xy 177.059313 -404.107587)
			(xy 177.086342 -404.051461) (xy 177.120326 -403.999252) (xy 177.160708 -403.951817) (xy 177.206824 -403.909936)
			(xy 177.257916 -403.874296) (xy 177.313147 -403.845482) (xy 177.371609 -403.823968) (xy 177.432343 -403.810106)
			(xy 177.49435 -403.804124) (xy 177.556613 -403.80612) (xy 177.61811 -403.816063) (xy 177.677831 -403.833787)
			(xy 177.734794 -403.859004) (xy 177.788065 -403.891297) (xy 177.83677 -403.930137) (xy 177.880107 -403.974887)
			(xy 177.89237 -403.991318) (xy 190.063626 -403.991318) (xy 190.067697 -403.935696) (xy 190.079823 -403.881259)
			(xy 190.099746 -403.829168) (xy 190.127042 -403.780533) (xy 190.161128 -403.73639) (xy 190.201277 -403.697681)
			(xy 190.246635 -403.66523) (xy 190.296235 -403.639729) (xy 190.349019 -403.621722) (xy 190.403862 -403.611592)
			(xy 190.459596 -403.609555) (xy 190.515033 -403.615655) (xy 190.56899 -403.629761) (xy 190.620319 -403.651573)
			(xy 190.667925 -403.680627) (xy 190.710793 -403.716302) (xy 190.74801 -403.757839) (xy 190.778783 -403.804352)
			(xy 190.802455 -403.854849) (xy 190.818523 -403.908256) (xy 190.826643 -403.963432) (xy 190.827152 -403.991318)
			(xy 190.826643 -404.019204) (xy 190.818523 -404.07438) (xy 190.816996 -404.079456) (xy 192.60769 -404.079456)
			(xy 192.611761 -404.023834) (xy 192.623887 -403.969397) (xy 192.64381 -403.917306) (xy 192.671106 -403.868671)
			(xy 192.705192 -403.824528) (xy 192.745341 -403.785819) (xy 192.790699 -403.753368) (xy 192.840299 -403.727867)
			(xy 192.893083 -403.70986) (xy 192.947926 -403.69973) (xy 193.00366 -403.697693) (xy 193.059097 -403.703793)
			(xy 193.113054 -403.717899) (xy 193.164383 -403.739711) (xy 193.211989 -403.768765) (xy 193.254857 -403.80444)
			(xy 193.292074 -403.845977) (xy 193.322847 -403.89249) (xy 193.329763 -403.907244) (xy 193.55765 -403.907244)
			(xy 193.561721 -403.851622) (xy 193.573847 -403.797185) (xy 193.59377 -403.745094) (xy 193.621066 -403.696459)
			(xy 193.655152 -403.652316) (xy 193.695301 -403.613607) (xy 193.740659 -403.581156) (xy 193.790259 -403.555655)
			(xy 193.843043 -403.537648) (xy 193.897886 -403.527518) (xy 193.95362 -403.525481) (xy 194.009057 -403.531581)
			(xy 194.063014 -403.545687) (xy 194.114343 -403.567499) (xy 194.161949 -403.596553) (xy 194.204817 -403.632228)
			(xy 194.242034 -403.673765) (xy 194.272807 -403.720278) (xy 194.296479 -403.770775) (xy 194.312547 -403.824182)
			(xy 194.320667 -403.879358) (xy 194.321176 -403.907244) (xy 194.320667 -403.93513) (xy 194.312547 -403.990306)
			(xy 194.296479 -404.043713) (xy 194.272807 -404.09421) (xy 194.242034 -404.140723) (xy 194.204817 -404.18226)
			(xy 194.161949 -404.217935) (xy 194.114343 -404.246989) (xy 194.063014 -404.268801) (xy 194.009057 -404.282907)
			(xy 193.95362 -404.289007) (xy 193.897886 -404.28697) (xy 193.843043 -404.27684) (xy 193.790259 -404.258833)
			(xy 193.740659 -404.233332) (xy 193.695301 -404.200881) (xy 193.655152 -404.162172) (xy 193.621066 -404.118029)
			(xy 193.59377 -404.069394) (xy 193.573847 -404.017303) (xy 193.561721 -403.962866) (xy 193.55765 -403.907244)
			(xy 193.329763 -403.907244) (xy 193.346519 -403.942987) (xy 193.362587 -403.996394) (xy 193.370707 -404.05157)
			(xy 193.371216 -404.079456) (xy 193.370707 -404.107342) (xy 193.362587 -404.162518) (xy 193.346519 -404.215925)
			(xy 193.322847 -404.266422) (xy 193.292074 -404.312935) (xy 193.254857 -404.354472) (xy 193.211989 -404.390147)
			(xy 193.164383 -404.419201) (xy 193.113054 -404.441013) (xy 193.059097 -404.455119) (xy 193.00366 -404.461219)
			(xy 192.947926 -404.459182) (xy 192.893083 -404.449052) (xy 192.840299 -404.431045) (xy 192.790699 -404.405544)
			(xy 192.745341 -404.373093) (xy 192.705192 -404.334384) (xy 192.671106 -404.290241) (xy 192.64381 -404.241606)
			(xy 192.623887 -404.189515) (xy 192.611761 -404.135078) (xy 192.60769 -404.079456) (xy 190.816996 -404.079456)
			(xy 190.802455 -404.127787) (xy 190.778783 -404.178284) (xy 190.74801 -404.224797) (xy 190.710793 -404.266334)
			(xy 190.667925 -404.302009) (xy 190.620319 -404.331063) (xy 190.56899 -404.352875) (xy 190.515033 -404.366981)
			(xy 190.459596 -404.373081) (xy 190.403862 -404.371044) (xy 190.349019 -404.360914) (xy 190.296235 -404.342907)
			(xy 190.246635 -404.317406) (xy 190.201277 -404.284955) (xy 190.161128 -404.246246) (xy 190.127042 -404.202103)
			(xy 190.099746 -404.153468) (xy 190.079823 -404.101377) (xy 190.067697 -404.04694) (xy 190.063626 -403.991318)
			(xy 177.89237 -403.991318) (xy 177.917367 -404.024811) (xy 177.947936 -404.07909) (xy 177.971314 -404.136833)
			(xy 177.987115 -404.197091) (xy 177.995081 -404.258874) (xy 177.99558 -404.290022) (xy 177.995081 -404.32117)
			(xy 177.987115 -404.382953) (xy 177.971314 -404.443211) (xy 177.947936 -404.500954) (xy 177.917367 -404.555233)
			(xy 177.880107 -404.605157) (xy 177.83677 -404.649907) (xy 177.788065 -404.688747) (xy 177.734794 -404.72104)
			(xy 177.677831 -404.746257) (xy 177.61811 -404.763981) (xy 177.556613 -404.773924) (xy 177.49435 -404.77592)
			(xy 177.432343 -404.769938) (xy 177.371609 -404.756076) (xy 177.313147 -404.734562) (xy 177.257916 -404.705748)
			(xy 177.206824 -404.670108) (xy 177.160708 -404.628227) (xy 177.120326 -404.580792) (xy 177.086342 -404.528583)
			(xy 177.059313 -404.472457) (xy 177.039684 -404.413336) (xy 177.027775 -404.352189) (xy 177.023784 -404.290022)
			(xy 173.59501 -404.290022) (xy 173.595009 -404.322741) (xy 173.586214 -404.387591) (xy 173.568786 -404.450672)
			(xy 173.543041 -404.510839) (xy 173.526704 -404.539196) (xy 173.523391 -404.545221) (xy 173.519784 -404.558485)
			(xy 173.519592 -404.565358) (xy 173.519592 -405.314658) (xy 173.519801 -405.32153) (xy 173.523398 -405.334793)
			(xy 173.526704 -405.34082) (xy 173.543035 -405.369179) (xy 173.568777 -405.429346) (xy 173.586202 -405.492425)
			(xy 173.594995 -405.557274) (xy 173.594996 -405.622716) (xy 173.586205 -405.687565) (xy 173.56878 -405.750644)
			(xy 173.54304 -405.810811) (xy 173.526704 -405.839168) (xy 173.523401 -405.845198) (xy 173.519788 -405.858458)
			(xy 173.519592 -405.86533) (xy 173.519592 -406.151334) (xy 173.519095 -406.16149) (xy 173.511315 -406.180254)
			(xy 173.496951 -406.194617) (xy 173.478186 -406.202396) (xy 173.46803 -406.202896) (xy 172.75175 -406.202896)
			(xy 172.741586 -406.202396) (xy 172.722799 -406.194634) (xy 172.708413 -406.180272) (xy 172.70062 -406.161497)
			(xy 172.700188 -406.151334) (xy 172.700188 -405.86533) (xy 172.699986 -405.858458) (xy 172.696385 -405.845195)
			(xy 172.693076 -405.839168) (xy 172.676732 -405.810815) (xy 172.650987 -405.750648) (xy 172.63356 -405.687567)
			(xy 172.624767 -405.622717) (xy 171.336348 -405.622717) (xy 171.32681 -405.63927) (xy 171.323461 -405.645293)
			(xy 171.319715 -405.658547) (xy 171.319444 -405.665432) (xy 171.319444 -406.414732) (xy 171.319676 -406.421625)
			(xy 171.323405 -406.434897) (xy 171.32681 -406.440894) (xy 171.343122 -406.469265) (xy 171.368871 -406.529427)
			(xy 171.386302 -406.592505) (xy 171.3951 -406.657352) (xy 171.395103 -406.722793) (xy 171.395103 -406.722795)
			(xy 174.824907 -406.722795) (xy 174.824911 -406.65735) (xy 174.833708 -406.592499) (xy 174.851138 -406.529418)
			(xy 174.876885 -406.46925) (xy 174.893224 -406.440894) (xy 174.896543 -406.434871) (xy 174.900145 -406.421606)
			(xy 174.900336 -406.414732) (xy 174.900336 -405.665432) (xy 174.900127 -405.65856) (xy 174.89653 -405.645297)
			(xy 174.893224 -405.63927) (xy 174.876884 -405.610916) (xy 174.851141 -405.550748) (xy 174.833715 -405.487668)
			(xy 174.824923 -405.422818) (xy 174.824924 -405.357375) (xy 174.833717 -405.292525) (xy 174.851143 -405.229445)
			(xy 174.876887 -405.169278) (xy 174.893224 -405.140922) (xy 174.896533 -405.134894) (xy 174.900142 -405.121633)
			(xy 174.900336 -405.11476) (xy 174.900336 -404.828756) (xy 174.900686 -404.818594) (xy 174.908503 -404.799834)
			(xy 174.922922 -404.785511) (xy 174.941734 -404.77782) (xy 174.951898 -404.777448) (xy 175.668178 -404.777448)
			(xy 175.678304 -404.777945) (xy 175.697027 -404.785667) (xy 175.711384 -404.79995) (xy 175.719202 -404.818632)
			(xy 175.71974 -404.828756) (xy 175.71974 -405.11476) (xy 175.719942 -405.121633) (xy 175.723543 -405.134896)
			(xy 175.726852 -405.140922) (xy 175.743186 -405.16928) (xy 175.768931 -405.229446) (xy 175.786358 -405.292526)
			(xy 175.795152 -405.357375) (xy 175.795152 -405.422818) (xy 175.786359 -405.487667) (xy 175.768933 -405.550747)
			(xy 175.75214 -405.589994) (xy 177.023784 -405.589994) (xy 177.027775 -405.527827) (xy 177.039684 -405.46668)
			(xy 177.059313 -405.407559) (xy 177.086342 -405.351433) (xy 177.120326 -405.299224) (xy 177.160708 -405.251789)
			(xy 177.206824 -405.209908) (xy 177.257916 -405.174268) (xy 177.313147 -405.145454) (xy 177.371609 -405.12394)
			(xy 177.432343 -405.110078) (xy 177.49435 -405.104096) (xy 177.556613 -405.106092) (xy 177.61811 -405.116035)
			(xy 177.677831 -405.133759) (xy 177.734794 -405.158976) (xy 177.788065 -405.191269) (xy 177.83677 -405.230109)
			(xy 177.880107 -405.274859) (xy 177.917367 -405.324783) (xy 177.947936 -405.379062) (xy 177.952403 -405.390096)
			(xy 179.223932 -405.390096) (xy 179.227923 -405.327929) (xy 179.239832 -405.266782) (xy 179.259461 -405.207661)
			(xy 179.28649 -405.151535) (xy 179.320474 -405.099326) (xy 179.360856 -405.051891) (xy 179.406972 -405.01001)
			(xy 179.458064 -404.97437) (xy 179.513295 -404.945556) (xy 179.571757 -404.924042) (xy 179.632491 -404.91018)
			(xy 179.694498 -404.904198) (xy 179.756761 -404.906194) (xy 179.818258 -404.916137) (xy 179.877979 -404.933861)
			(xy 179.934942 -404.959078) (xy 179.988213 -404.991371) (xy 180.036918 -405.030211) (xy 180.080255 -405.074961)
			(xy 180.117515 -405.124885) (xy 180.148084 -405.179164) (xy 180.154299 -405.194516) (xy 198.019922 -405.194516)
			(xy 198.023993 -405.138894) (xy 198.036119 -405.084457) (xy 198.056042 -405.032366) (xy 198.083338 -404.983731)
			(xy 198.117424 -404.939588) (xy 198.157573 -404.900879) (xy 198.202931 -404.868428) (xy 198.252531 -404.842927)
			(xy 198.305315 -404.82492) (xy 198.360158 -404.81479) (xy 198.415892 -404.812753) (xy 198.471329 -404.818853)
			(xy 198.525286 -404.832959) (xy 198.576615 -404.854771) (xy 198.624221 -404.883825) (xy 198.667089 -404.9195)
			(xy 198.704306 -404.961037) (xy 198.735079 -405.00755) (xy 198.758751 -405.058047) (xy 198.774819 -405.111454)
			(xy 198.782939 -405.16663) (xy 198.783448 -405.194516) (xy 198.782939 -405.222402) (xy 198.774819 -405.277578)
			(xy 198.758751 -405.330985) (xy 198.735079 -405.381482) (xy 198.704306 -405.427995) (xy 198.667089 -405.469532)
			(xy 198.624221 -405.505207) (xy 198.576615 -405.534261) (xy 198.525286 -405.556073) (xy 198.471329 -405.570179)
			(xy 198.415892 -405.576279) (xy 198.360158 -405.574242) (xy 198.305315 -405.564112) (xy 198.252531 -405.546105)
			(xy 198.202931 -405.520604) (xy 198.157573 -405.488153) (xy 198.117424 -405.449444) (xy 198.083338 -405.405301)
			(xy 198.056042 -405.356666) (xy 198.036119 -405.304575) (xy 198.023993 -405.250138) (xy 198.019922 -405.194516)
			(xy 180.154299 -405.194516) (xy 180.171462 -405.236907) (xy 180.187263 -405.297165) (xy 180.195229 -405.358948)
			(xy 180.195728 -405.390096) (xy 180.195229 -405.421244) (xy 180.187263 -405.483027) (xy 180.171462 -405.543285)
			(xy 180.148084 -405.601028) (xy 180.117515 -405.655307) (xy 180.080255 -405.705231) (xy 180.036918 -405.749981)
			(xy 179.988213 -405.788821) (xy 179.934942 -405.821114) (xy 179.877979 -405.846331) (xy 179.838782 -405.857964)
			(xy 187.266832 -405.857964) (xy 187.270903 -405.802342) (xy 187.283029 -405.747905) (xy 187.302952 -405.695814)
			(xy 187.330248 -405.647179) (xy 187.364334 -405.603036) (xy 187.404483 -405.564327) (xy 187.449841 -405.531876)
			(xy 187.499441 -405.506375) (xy 187.552225 -405.488368) (xy 187.607068 -405.478238) (xy 187.662802 -405.476201)
			(xy 187.718239 -405.482301) (xy 187.772196 -405.496407) (xy 187.823525 -405.518219) (xy 187.871131 -405.547273)
			(xy 187.913999 -405.582948) (xy 187.951216 -405.624485) (xy 187.981989 -405.670998) (xy 188.005661 -405.721495)
			(xy 188.021729 -405.774902) (xy 188.029849 -405.830078) (xy 188.030358 -405.857964) (xy 188.029849 -405.88585)
			(xy 188.021729 -405.941026) (xy 188.005661 -405.994433) (xy 187.981989 -406.04493) (xy 187.951216 -406.091443)
			(xy 187.913999 -406.13298) (xy 187.871131 -406.168655) (xy 187.823525 -406.197709) (xy 187.772196 -406.219521)
			(xy 187.718239 -406.233627) (xy 187.662802 -406.239727) (xy 187.607068 -406.23769) (xy 187.552225 -406.22756)
			(xy 187.499441 -406.209553) (xy 187.449841 -406.184052) (xy 187.404483 -406.151601) (xy 187.364334 -406.112892)
			(xy 187.330248 -406.068749) (xy 187.302952 -406.020114) (xy 187.283029 -405.968023) (xy 187.270903 -405.913586)
			(xy 187.266832 -405.857964) (xy 179.838782 -405.857964) (xy 179.818258 -405.864055) (xy 179.756761 -405.873998)
			(xy 179.694498 -405.875994) (xy 179.632491 -405.870012) (xy 179.571757 -405.85615) (xy 179.513295 -405.834636)
			(xy 179.458064 -405.805822) (xy 179.406972 -405.770182) (xy 179.360856 -405.728301) (xy 179.320474 -405.680866)
			(xy 179.28649 -405.628657) (xy 179.259461 -405.572531) (xy 179.239832 -405.51341) (xy 179.227923 -405.452263)
			(xy 179.223932 -405.390096) (xy 177.952403 -405.390096) (xy 177.971314 -405.436805) (xy 177.987115 -405.497063)
			(xy 177.995081 -405.558846) (xy 177.99558 -405.589994) (xy 177.995081 -405.621142) (xy 177.987115 -405.682925)
			(xy 177.971314 -405.743183) (xy 177.947936 -405.800926) (xy 177.917367 -405.855205) (xy 177.880107 -405.905129)
			(xy 177.83677 -405.949879) (xy 177.788065 -405.988719) (xy 177.734794 -406.021012) (xy 177.677831 -406.046229)
			(xy 177.61811 -406.063953) (xy 177.556613 -406.073896) (xy 177.49435 -406.075892) (xy 177.432343 -406.06991)
			(xy 177.371609 -406.056048) (xy 177.313147 -406.034534) (xy 177.257916 -406.00572) (xy 177.206824 -405.97008)
			(xy 177.160708 -405.928199) (xy 177.120326 -405.880764) (xy 177.086342 -405.828555) (xy 177.059313 -405.772429)
			(xy 177.039684 -405.713308) (xy 177.027775 -405.652161) (xy 177.023784 -405.589994) (xy 175.75214 -405.589994)
			(xy 175.743189 -405.610914) (xy 175.726852 -405.63927) (xy 175.723552 -405.645302) (xy 175.719936 -405.65856)
			(xy 175.71974 -405.665432) (xy 175.71974 -406.414732) (xy 175.719915 -406.421607) (xy 175.723534 -406.434869)
			(xy 175.726852 -406.440894) (xy 175.743163 -406.469265) (xy 175.768909 -406.529428) (xy 175.786339 -406.592505)
			(xy 175.795136 -406.657352) (xy 175.795137 -406.690068) (xy 179.223932 -406.690068) (xy 179.227923 -406.627901)
			(xy 179.239832 -406.566754) (xy 179.259461 -406.507633) (xy 179.28649 -406.451507) (xy 179.320474 -406.399298)
			(xy 179.360856 -406.351863) (xy 179.406972 -406.309982) (xy 179.458064 -406.274342) (xy 179.513295 -406.245528)
			(xy 179.571757 -406.224014) (xy 179.632491 -406.210152) (xy 179.694498 -406.20417) (xy 179.756761 -406.206166)
			(xy 179.818258 -406.216109) (xy 179.877979 -406.233833) (xy 179.934942 -406.25905) (xy 179.988213 -406.291343)
			(xy 180.036918 -406.330183) (xy 180.080255 -406.374933) (xy 180.117515 -406.424857) (xy 180.148084 -406.479136)
			(xy 180.161087 -406.511252) (xy 198.765666 -406.511252) (xy 198.769737 -406.45563) (xy 198.781863 -406.401193)
			(xy 198.801786 -406.349102) (xy 198.829082 -406.300467) (xy 198.863168 -406.256324) (xy 198.903317 -406.217615)
			(xy 198.948675 -406.185164) (xy 198.998275 -406.159663) (xy 199.051059 -406.141656) (xy 199.105902 -406.131526)
			(xy 199.161636 -406.129489) (xy 199.217073 -406.135589) (xy 199.27103 -406.149695) (xy 199.322359 -406.171507)
			(xy 199.369965 -406.200561) (xy 199.412833 -406.236236) (xy 199.45005 -406.277773) (xy 199.480823 -406.324286)
			(xy 199.504495 -406.374783) (xy 199.520563 -406.42819) (xy 199.528683 -406.483366) (xy 199.529192 -406.511252)
			(xy 199.528683 -406.539138) (xy 199.520563 -406.594314) (xy 199.504495 -406.647721) (xy 199.480823 -406.698218)
			(xy 199.45005 -406.744731) (xy 199.412833 -406.786268) (xy 199.369965 -406.821943) (xy 199.322359 -406.850997)
			(xy 199.27103 -406.872809) (xy 199.217073 -406.886915) (xy 199.161636 -406.893015) (xy 199.105902 -406.890978)
			(xy 199.051059 -406.880848) (xy 198.998275 -406.862841) (xy 198.948675 -406.83734) (xy 198.903317 -406.804889)
			(xy 198.863168 -406.76618) (xy 198.829082 -406.722037) (xy 198.801786 -406.673402) (xy 198.781863 -406.621311)
			(xy 198.769737 -406.566874) (xy 198.765666 -406.511252) (xy 180.161087 -406.511252) (xy 180.171462 -406.536879)
			(xy 180.187263 -406.597137) (xy 180.195229 -406.65892) (xy 180.195728 -406.690068) (xy 180.195229 -406.721216)
			(xy 180.187263 -406.782999) (xy 180.171462 -406.843257) (xy 180.148084 -406.901) (xy 180.117515 -406.955279)
			(xy 180.088348 -406.99436) (xy 187.04255 -406.99436) (xy 187.046621 -406.938738) (xy 187.058747 -406.884301)
			(xy 187.07867 -406.83221) (xy 187.105966 -406.783575) (xy 187.140052 -406.739432) (xy 187.180201 -406.700723)
			(xy 187.225559 -406.668272) (xy 187.275159 -406.642771) (xy 187.327943 -406.624764) (xy 187.382786 -406.614634)
			(xy 187.43852 -406.612597) (xy 187.493957 -406.618697) (xy 187.547914 -406.632803) (xy 187.599243 -406.654615)
			(xy 187.646849 -406.683669) (xy 187.689717 -406.719344) (xy 187.726934 -406.760881) (xy 187.757707 -406.807394)
			(xy 187.781379 -406.857891) (xy 187.797447 -406.911298) (xy 187.805567 -406.966474) (xy 187.806076 -406.99436)
			(xy 187.805567 -407.022246) (xy 187.797447 -407.077422) (xy 187.781379 -407.130829) (xy 187.757707 -407.181326)
			(xy 187.726934 -407.227839) (xy 187.689717 -407.269376) (xy 187.646849 -407.305051) (xy 187.599243 -407.334105)
			(xy 187.547914 -407.355917) (xy 187.493957 -407.370023) (xy 187.43852 -407.376123) (xy 187.382786 -407.374086)
			(xy 187.327943 -407.363956) (xy 187.275159 -407.345949) (xy 187.225559 -407.320448) (xy 187.180201 -407.287997)
			(xy 187.140052 -407.249288) (xy 187.105966 -407.205145) (xy 187.07867 -407.15651) (xy 187.058747 -407.104419)
			(xy 187.046621 -407.049982) (xy 187.04255 -406.99436) (xy 180.088348 -406.99436) (xy 180.080255 -407.005203)
			(xy 180.036918 -407.049953) (xy 179.988213 -407.088793) (xy 179.934942 -407.121086) (xy 179.877979 -407.146303)
			(xy 179.818258 -407.164027) (xy 179.756761 -407.17397) (xy 179.694498 -407.175966) (xy 179.632491 -407.169984)
			(xy 179.571757 -407.156122) (xy 179.513295 -407.134608) (xy 179.458064 -407.105794) (xy 179.406972 -407.070154)
			(xy 179.360856 -407.028273) (xy 179.320474 -406.980838) (xy 179.28649 -406.928629) (xy 179.259461 -406.872503)
			(xy 179.239832 -406.813382) (xy 179.227923 -406.752235) (xy 179.223932 -406.690068) (xy 175.795137 -406.690068)
			(xy 175.795139 -406.722793) (xy 175.78635 -406.787641) (xy 175.768928 -406.85072) (xy 175.743188 -406.910886)
			(xy 175.726852 -406.939242) (xy 175.723526 -406.945261) (xy 175.719927 -406.958529) (xy 175.71974 -406.965404)
			(xy 175.71974 -407.251408) (xy 175.719286 -407.261558) (xy 175.711495 -407.280302) (xy 175.697109 -407.294624)
			(xy 175.678329 -407.302331) (xy 175.668178 -407.302716) (xy 174.951898 -407.302716) (xy 174.941766 -407.302274)
			(xy 174.923036 -407.294537) (xy 174.908679 -407.280237) (xy 174.900867 -407.261538) (xy 174.900336 -407.251408)
			(xy 174.900336 -406.965404) (xy 174.900138 -406.958531) (xy 174.896533 -406.945269) (xy 174.893224 -406.939242)
			(xy 174.87686 -406.910901) (xy 174.851119 -406.85073) (xy 174.833696 -406.787647) (xy 174.824907 -406.722795)
			(xy 171.395103 -406.722795) (xy 171.386313 -406.787642) (xy 171.368889 -406.850721) (xy 171.343147 -406.910886)
			(xy 171.32681 -406.939242) (xy 171.323436 -406.945252) (xy 171.319706 -406.958516) (xy 171.319444 -406.965404)
			(xy 171.319444 -407.251408) (xy 171.318922 -407.261512) (xy 171.31119 -407.280182) (xy 171.296905 -407.294475)
			(xy 171.278239 -407.302217) (xy 171.268136 -407.302716) (xy 170.551856 -407.302716) (xy 170.541746 -407.302251)
			(xy 170.52307 -407.294502) (xy 170.508778 -407.280199) (xy 170.501042 -407.261518) (xy 170.500548 -407.251408)
			(xy 170.500548 -406.965404) (xy 170.500342 -406.958509) (xy 170.496595 -406.945237) (xy 170.493182 -406.939242)
			(xy 170.476816 -406.910901) (xy 170.451073 -406.850731) (xy 170.433648 -406.787648) (xy 170.424857 -406.722795)
			(xy 166.995053 -406.722795) (xy 166.986264 -406.787641) (xy 166.968842 -406.85072) (xy 166.943103 -406.910886)
			(xy 166.926768 -406.939242) (xy 166.923436 -406.945258) (xy 166.919842 -406.958529) (xy 166.919656 -406.965404)
			(xy 166.919656 -407.251408) (xy 166.919186 -407.261556) (xy 166.911398 -407.280297) (xy 166.897017 -407.294618)
			(xy 166.878243 -407.302328) (xy 166.868094 -407.302716) (xy 166.151814 -407.302716) (xy 166.141683 -407.302261)
			(xy 166.122954 -407.294529) (xy 166.108595 -407.280233) (xy 166.100783 -407.261537) (xy 166.100252 -407.251408)
			(xy 166.100252 -406.965404) (xy 166.100064 -406.95853) (xy 166.096454 -406.945267) (xy 166.09314 -406.939242)
			(xy 166.076775 -406.910901) (xy 166.051034 -406.850731) (xy 166.033611 -406.787647) (xy 166.024821 -406.722795)
			(xy 162.595017 -406.722795) (xy 162.586227 -406.787641) (xy 162.568804 -406.85072) (xy 162.543062 -406.910886)
			(xy 162.526726 -406.939242) (xy 162.523345 -406.945249) (xy 162.51962 -406.958516) (xy 162.51936 -406.965404)
			(xy 162.51936 -407.251408) (xy 162.518989 -407.261536) (xy 162.511231 -407.280247) (xy 162.4969 -407.294563)
			(xy 162.47818 -407.3023) (xy 162.468052 -407.302716) (xy 161.751772 -407.302716) (xy 161.741663 -407.302238)
			(xy 161.722988 -407.294494) (xy 161.708694 -407.280196) (xy 161.700958 -407.261517) (xy 161.700464 -407.251408)
			(xy 161.700464 -406.965404) (xy 161.700234 -406.958512) (xy 161.69649 -406.945246) (xy 161.693098 -406.939242)
			(xy 161.676735 -406.9109) (xy 161.650996 -406.85073) (xy 161.633574 -406.787647) (xy 161.624785 -406.722795)
			(xy 154.57678 -406.722795) (xy 154.57678 -407.4414) (xy 185.755532 -407.4414) (xy 185.759603 -407.385778)
			(xy 185.771729 -407.331341) (xy 185.791652 -407.27925) (xy 185.818948 -407.230615) (xy 185.853034 -407.186472)
			(xy 185.893183 -407.147763) (xy 185.938541 -407.115312) (xy 185.988141 -407.089811) (xy 186.040925 -407.071804)
			(xy 186.095768 -407.061674) (xy 186.151502 -407.059637) (xy 186.206939 -407.065737) (xy 186.260896 -407.079843)
			(xy 186.312225 -407.101655) (xy 186.359831 -407.130709) (xy 186.402699 -407.166384) (xy 186.439916 -407.207921)
			(xy 186.470689 -407.254434) (xy 186.494361 -407.304931) (xy 186.510429 -407.358338) (xy 186.518549 -407.413514)
			(xy 186.519058 -407.4414) (xy 186.518549 -407.469286) (xy 186.510429 -407.524462) (xy 186.494361 -407.577869)
			(xy 186.470689 -407.628366) (xy 186.439916 -407.674879) (xy 186.402699 -407.716416) (xy 186.359831 -407.752091)
			(xy 186.312225 -407.781145) (xy 186.260896 -407.802957) (xy 186.206939 -407.817063) (xy 186.151502 -407.823163)
			(xy 186.095768 -407.821126) (xy 186.040925 -407.810996) (xy 185.988141 -407.792989) (xy 185.938541 -407.767488)
			(xy 185.893183 -407.735037) (xy 185.853034 -407.696328) (xy 185.818948 -407.652185) (xy 185.791652 -407.60355)
			(xy 185.771729 -407.551459) (xy 185.759603 -407.497022) (xy 185.755532 -407.4414) (xy 154.57678 -407.4414)
			(xy 154.57678 -409.522892) (xy 159.424888 -409.522892) (xy 159.424892 -409.457447) (xy 159.433689 -409.392596)
			(xy 159.451118 -409.329514) (xy 159.476865 -409.269347) (xy 159.493204 -409.24099) (xy 159.496523 -409.234967)
			(xy 159.500126 -409.221702) (xy 159.500316 -409.214828) (xy 159.500316 -408.465528) (xy 159.500112 -408.458656)
			(xy 159.496512 -408.445393) (xy 159.493204 -408.439366) (xy 159.476861 -408.411013) (xy 159.45112 -408.350845)
			(xy 159.433695 -408.287765) (xy 159.424904 -408.222915) (xy 159.424905 -408.157472) (xy 159.433698 -408.092622)
			(xy 159.451124 -408.029542) (xy 159.476867 -407.969375) (xy 159.493204 -407.941018) (xy 159.496513 -407.93499)
			(xy 159.500122 -407.921729) (xy 159.500316 -407.914856) (xy 159.500316 -407.628852) (xy 159.500683 -407.618693)
			(xy 159.508497 -407.599936) (xy 159.522911 -407.585614) (xy 159.541716 -407.577919) (xy 159.551878 -407.577544)
			(xy 160.268158 -407.577544) (xy 160.278283 -407.578061) (xy 160.297003 -407.585776) (xy 160.311361 -407.600053)
			(xy 160.319181 -407.61873) (xy 160.31972 -407.628852) (xy 160.31972 -407.914856) (xy 160.319926 -407.921728)
			(xy 160.323525 -407.934991) (xy 160.326832 -407.941018) (xy 160.343163 -407.969378) (xy 160.36891 -408.029543)
			(xy 160.386338 -408.092623) (xy 160.395132 -408.157472) (xy 160.395133 -408.222915) (xy 160.386341 -408.287764)
			(xy 160.368914 -408.350844) (xy 160.34317 -408.41101) (xy 160.326832 -408.439366) (xy 160.323532 -408.445398)
			(xy 160.319917 -408.458656) (xy 160.31972 -408.465528) (xy 160.31972 -409.214828) (xy 160.319899 -409.221702)
			(xy 160.323516 -409.234965) (xy 160.326832 -409.24099) (xy 160.34314 -409.269363) (xy 160.368888 -409.329525)
			(xy 160.386319 -409.392602) (xy 160.395116 -409.457449) (xy 160.39512 -409.52289) (xy 160.386331 -409.587737)
			(xy 160.368908 -409.650816) (xy 160.343168 -409.710982) (xy 160.326832 -409.739338) (xy 160.323506 -409.745357)
			(xy 160.319907 -409.758625) (xy 160.31972 -409.7655) (xy 160.31972 -410.051504) (xy 160.319282 -410.061656)
			(xy 160.311489 -410.080404) (xy 160.297098 -410.094727) (xy 160.278312 -410.10243) (xy 160.268158 -410.102812)
			(xy 159.551878 -410.102812) (xy 159.541756 -410.102293) (xy 159.523044 -410.094568) (xy 159.508691 -410.080292)
			(xy 159.500863 -410.061623) (xy 159.500316 -410.051504) (xy 159.500316 -409.7655) (xy 159.500122 -409.758627)
			(xy 159.496515 -409.745364) (xy 159.493204 -409.739338) (xy 159.476837 -409.710998) (xy 159.451098 -409.650827)
			(xy 159.433676 -409.587744) (xy 159.424888 -409.522892) (xy 154.57678 -409.522892) (xy 154.57678 -410.622708)
			(xy 161.624794 -410.622708) (xy 161.624796 -410.557265) (xy 161.63359 -410.492415) (xy 161.651017 -410.429334)
			(xy 161.676761 -410.369167) (xy 161.693098 -410.34081) (xy 161.696455 -410.334791) (xy 161.700196 -410.321534)
			(xy 161.700464 -410.314648) (xy 161.700464 -409.565348) (xy 161.700239 -409.558455) (xy 161.696505 -409.545183)
			(xy 161.693098 -409.539186) (xy 161.676772 -409.510824) (xy 161.651029 -409.450658) (xy 161.633603 -409.387579)
			(xy 161.62481 -409.322731) (xy 161.624809 -409.257289) (xy 161.633599 -409.192441) (xy 161.651023 -409.129361)
			(xy 161.676763 -409.069195) (xy 161.693098 -409.040838) (xy 161.69648 -409.034832) (xy 161.700205 -409.021565)
			(xy 161.700464 -409.014676) (xy 161.700464 -408.728672) (xy 161.700961 -408.718566) (xy 161.708701 -408.699894)
			(xy 161.722994 -408.685601) (xy 161.741666 -408.677861) (xy 161.751772 -408.677364) (xy 162.468052 -408.677364)
			(xy 162.478167 -408.677854) (xy 162.496863 -408.68558) (xy 162.511177 -408.699874) (xy 162.518931 -408.718558)
			(xy 162.51936 -408.728672) (xy 162.51936 -409.014676) (xy 162.519573 -409.02157) (xy 162.523315 -409.034842)
			(xy 162.526726 -409.040838) (xy 162.543075 -409.069188) (xy 162.568819 -409.129356) (xy 162.586246 -409.192437)
			(xy 162.595038 -409.257288) (xy 162.595037 -409.322732) (xy 162.586242 -409.387583) (xy 162.568813 -409.450664)
			(xy 162.543065 -409.51083) (xy 162.536115 -409.522892) (xy 163.824924 -409.522892) (xy 163.824928 -409.457446)
			(xy 163.833726 -409.392595) (xy 163.851157 -409.329513) (xy 163.876906 -409.269346) (xy 163.893246 -409.24099)
			(xy 163.896613 -409.234976) (xy 163.900347 -409.221715) (xy 163.900612 -409.214828) (xy 163.900612 -408.465528)
			(xy 163.900401 -408.458633) (xy 163.896658 -408.445361) (xy 163.893246 -408.439366) (xy 163.876902 -408.411014)
			(xy 163.851158 -408.350846) (xy 163.833732 -408.287765) (xy 163.82494 -408.222915) (xy 163.824941 -408.157471)
			(xy 163.833735 -408.092621) (xy 163.851163 -408.029541) (xy 163.876908 -407.969374) (xy 163.893246 -407.941018)
			(xy 163.896603 -407.935) (xy 163.900343 -407.921742) (xy 163.900612 -407.914856) (xy 163.900612 -407.628852)
			(xy 163.901046 -407.618739) (xy 163.908802 -407.600057) (xy 163.923114 -407.585764) (xy 163.941806 -407.578033)
			(xy 163.95192 -407.577544) (xy 164.6682 -407.577544) (xy 164.678302 -407.578084) (xy 164.696969 -407.585811)
			(xy 164.711262 -407.60009) (xy 164.719007 -407.618751) (xy 164.719508 -407.628852) (xy 164.719508 -407.914856)
			(xy 164.719757 -407.921746) (xy 164.723488 -407.935012) (xy 164.726874 -407.941018) (xy 164.743204 -407.969378)
			(xy 164.768948 -408.029544) (xy 164.786375 -408.092623) (xy 164.795168 -408.157472) (xy 164.795169 -408.222914)
			(xy 164.786377 -408.287763) (xy 164.768953 -408.350843) (xy 164.74321 -408.41101) (xy 164.726874 -408.439366)
			(xy 164.723524 -408.445388) (xy 164.719779 -408.458643) (xy 164.719508 -408.465528) (xy 164.719508 -409.214828)
			(xy 164.719768 -409.221717) (xy 164.723492 -409.234983) (xy 164.726874 -409.24099) (xy 164.74318 -409.269363)
			(xy 164.768927 -409.329526) (xy 164.786356 -409.392603) (xy 164.795152 -409.457449) (xy 164.795156 -409.522889)
			(xy 164.786368 -409.587737) (xy 164.768947 -409.650816) (xy 164.743209 -409.710982) (xy 164.726874 -409.739338)
			(xy 164.723498 -409.745347) (xy 164.71977 -409.758612) (xy 164.719508 -409.7655) (xy 164.719508 -410.051504)
			(xy 164.719018 -410.061612) (xy 164.711281 -410.080289) (xy 164.696985 -410.094583) (xy 164.678308 -410.102319)
			(xy 164.6682 -410.102812) (xy 163.95192 -410.102812) (xy 163.9418 -410.102368) (xy 163.923099 -410.094629)
			(xy 163.908785 -410.080321) (xy 163.901037 -410.061624) (xy 163.900612 -410.051504) (xy 163.900612 -409.7655)
			(xy 163.900412 -409.758604) (xy 163.896662 -409.745332) (xy 163.893246 -409.739338) (xy 163.876878 -409.710999)
			(xy 163.851136 -409.650828) (xy 163.833713 -409.587745) (xy 163.824924 -409.522892) (xy 162.536115 -409.522892)
			(xy 162.526726 -409.539186) (xy 162.523365 -409.545202) (xy 162.519628 -409.558462) (xy 162.51936 -409.565348)
			(xy 162.51936 -410.314648) (xy 162.519583 -410.321542) (xy 162.523318 -410.334814) (xy 162.526726 -410.34081)
			(xy 162.543051 -410.369173) (xy 162.568798 -410.429338) (xy 162.586227 -410.492417) (xy 162.595022 -410.557265)
			(xy 162.595024 -410.622707) (xy 162.595024 -410.622708) (xy 166.02483 -410.622708) (xy 166.024832 -410.557264)
			(xy 166.033627 -410.492414) (xy 166.051055 -410.429333) (xy 166.076802 -410.369166) (xy 166.09314 -410.34081)
			(xy 166.096446 -410.334781) (xy 166.100058 -410.321521) (xy 166.100252 -410.314648) (xy 166.100252 -409.565348)
			(xy 166.100048 -409.558476) (xy 166.096449 -409.545213) (xy 166.09314 -409.539186) (xy 166.076813 -409.510824)
			(xy 166.051068 -409.450659) (xy 166.03364 -409.38758) (xy 166.024846 -409.322731) (xy 166.024845 -409.257289)
			(xy 166.033636 -409.19244) (xy 166.051061 -409.129361) (xy 166.076803 -409.069194) (xy 166.09314 -409.040838)
			(xy 166.096437 -409.034804) (xy 166.100054 -409.021548) (xy 166.100252 -409.014676) (xy 166.100252 -408.728672)
			(xy 166.100698 -408.718522) (xy 166.108493 -408.699778) (xy 166.122882 -408.685458) (xy 166.141662 -408.67775)
			(xy 166.151814 -408.677364) (xy 166.868094 -408.677364) (xy 166.878223 -408.677832) (xy 166.896949 -408.685562)
			(xy 166.911306 -408.699855) (xy 166.919121 -408.718545) (xy 166.919656 -408.728672) (xy 166.919656 -409.014676)
			(xy 166.91985 -409.021549) (xy 166.923456 -409.034812) (xy 166.926768 -409.040838) (xy 166.943115 -409.069189)
			(xy 166.968858 -409.129357) (xy 166.986283 -409.192438) (xy 166.995075 -409.257288) (xy 166.995073 -409.322732)
			(xy 166.986279 -409.387582) (xy 166.968851 -409.450663) (xy 166.943106 -409.51083) (xy 166.936156 -409.522892)
			(xy 168.22496 -409.522892) (xy 168.224964 -409.457446) (xy 168.233762 -409.392594) (xy 168.251195 -409.329513)
			(xy 168.276947 -409.269346) (xy 168.293288 -409.24099) (xy 168.296605 -409.234967) (xy 168.30021 -409.221702)
			(xy 168.3004 -409.214828) (xy 168.3004 -408.465528) (xy 168.300197 -408.458656) (xy 168.296596 -408.445393)
			(xy 168.293288 -408.439366) (xy 168.276942 -408.411014) (xy 168.251196 -408.350847) (xy 168.233769 -408.287766)
			(xy 168.224976 -408.222915) (xy 168.224977 -408.157471) (xy 168.233772 -408.092621) (xy 168.251201 -408.02954)
			(xy 168.276949 -407.969374) (xy 168.293288 -407.941018) (xy 168.296595 -407.93499) (xy 168.300206 -407.921729)
			(xy 168.3004 -407.914856) (xy 168.3004 -407.628852) (xy 168.300782 -407.618695) (xy 168.308594 -407.599941)
			(xy 168.323002 -407.58562) (xy 168.341802 -407.577922) (xy 168.351962 -407.577544) (xy 169.068242 -407.577544)
			(xy 169.078372 -407.577992) (xy 169.097095 -407.585735) (xy 169.11145 -407.600032) (xy 169.119267 -407.618724)
			(xy 169.119804 -407.628852) (xy 169.119804 -407.914856) (xy 169.120012 -407.921728) (xy 169.123609 -407.934991)
			(xy 169.126916 -407.941018) (xy 169.143248 -407.969377) (xy 169.168995 -408.029543) (xy 169.186424 -408.092622)
			(xy 169.195218 -408.157472) (xy 169.195219 -408.222915) (xy 169.186426 -408.287764) (xy 169.168999 -408.350844)
			(xy 169.143254 -408.41101) (xy 169.126916 -408.439366) (xy 169.123614 -408.445397) (xy 169.12 -408.458656)
			(xy 169.119804 -408.465528) (xy 169.119804 -409.214828) (xy 169.119985 -409.221702) (xy 169.1236 -409.234965)
			(xy 169.126916 -409.24099) (xy 169.143224 -409.269363) (xy 169.168973 -409.329525) (xy 169.186405 -409.392602)
			(xy 169.195202 -409.457449) (xy 169.195207 -409.52289) (xy 169.186417 -409.587738) (xy 169.168994 -409.650817)
			(xy 169.143252 -409.710982) (xy 169.126916 -409.739338) (xy 169.123589 -409.745357) (xy 169.119991 -409.758625)
			(xy 169.119804 -409.7655) (xy 169.119804 -410.051504) (xy 169.119382 -410.061658) (xy 169.111586 -410.08041)
			(xy 169.097189 -410.094733) (xy 169.078398 -410.102433) (xy 169.068242 -410.102812) (xy 168.351962 -410.102812)
			(xy 168.341839 -410.102306) (xy 168.323127 -410.094575) (xy 168.308774 -410.080296) (xy 168.300947 -410.061624)
			(xy 168.3004 -410.051504) (xy 168.3004 -409.7655) (xy 168.300208 -409.758627) (xy 168.2966 -409.745364)
			(xy 168.293288 -409.739338) (xy 168.276919 -409.710999) (xy 168.251175 -409.650829) (xy 168.23375 -409.587745)
			(xy 168.22496 -409.522892) (xy 166.936156 -409.522892) (xy 166.926768 -409.539186) (xy 166.923456 -409.545212)
			(xy 166.919849 -409.558475) (xy 166.919656 -409.565348) (xy 166.919656 -410.314648) (xy 166.919861 -410.32152)
			(xy 166.923459 -410.334783) (xy 166.926768 -410.34081) (xy 166.943092 -410.369174) (xy 166.968836 -410.429339)
			(xy 166.986264 -410.492417) (xy 166.995059 -410.557265) (xy 166.99506 -410.622707) (xy 166.99506 -410.622709)
			(xy 170.424866 -410.622709) (xy 170.424868 -410.557264) (xy 170.433664 -410.492413) (xy 170.451094 -410.429332)
			(xy 170.476842 -410.369166) (xy 170.493182 -410.34081) (xy 170.496537 -410.33479) (xy 170.50028 -410.321534)
			(xy 170.500548 -410.314648) (xy 170.500548 -409.565348) (xy 170.500325 -409.558454) (xy 170.49659 -409.545182)
			(xy 170.493182 -409.539186) (xy 170.476853 -409.510825) (xy 170.451106 -409.45066) (xy 170.433677 -409.387581)
			(xy 170.424882 -409.322732) (xy 170.424881 -409.257289) (xy 170.433673 -409.19244) (xy 170.4511 -409.12936)
			(xy 170.476844 -409.069194) (xy 170.493182 -409.040838) (xy 170.496563 -409.034831) (xy 170.500289 -409.021565)
			(xy 170.500548 -409.014676) (xy 170.500548 -408.728672) (xy 170.501061 -408.718568) (xy 170.508798 -408.699899)
			(xy 170.523086 -408.685607) (xy 170.541752 -408.677864) (xy 170.551856 -408.677364) (xy 171.268136 -408.677364)
			(xy 171.278243 -408.677855) (xy 171.296915 -408.685598) (xy 171.311207 -408.699892) (xy 171.318947 -408.718565)
			(xy 171.319444 -408.728672) (xy 171.319444 -409.014676) (xy 171.319659 -409.02157) (xy 171.3234 -409.034842)
			(xy 171.32681 -409.040838) (xy 171.343159 -409.069188) (xy 171.368905 -409.129356) (xy 171.386332 -409.192437)
			(xy 171.395125 -409.257288) (xy 171.395123 -409.322732) (xy 171.386328 -409.387583) (xy 171.368898 -409.450664)
			(xy 171.34315 -409.51083) (xy 171.336199 -409.522892) (xy 172.62475 -409.522892) (xy 172.624754 -409.457446)
			(xy 172.633552 -409.392594) (xy 172.650984 -409.329513) (xy 172.676735 -409.269346) (xy 172.693076 -409.24099)
			(xy 172.696393 -409.234966) (xy 172.699998 -409.221702) (xy 172.700188 -409.214828) (xy 172.700188 -408.465528)
			(xy 172.699987 -408.458655) (xy 172.696385 -408.445393) (xy 172.693076 -408.439366) (xy 172.676731 -408.411014)
			(xy 172.650985 -408.350847) (xy 172.633558 -408.287766) (xy 172.624766 -408.222915) (xy 172.624767 -408.157471)
			(xy 172.633561 -408.092621) (xy 172.65099 -408.02954) (xy 172.676737 -407.969374) (xy 172.693076 -407.941018)
			(xy 172.696383 -407.934989) (xy 172.699994 -407.921729) (xy 172.700188 -407.914856) (xy 172.700188 -407.628852)
			(xy 172.700582 -407.618696) (xy 172.708391 -407.599945) (xy 172.722796 -407.585624) (xy 172.741592 -407.577924)
			(xy 172.75175 -407.577544) (xy 173.46803 -407.577544) (xy 173.478159 -407.578002) (xy 173.496882 -407.58574)
			(xy 173.511237 -407.600035) (xy 173.519055 -407.618725) (xy 173.519592 -407.628852) (xy 173.519592 -407.914856)
			(xy 173.519802 -407.921728) (xy 173.523398 -407.934991) (xy 173.526704 -407.941018) (xy 173.543033 -407.969378)
			(xy 173.568776 -408.029545) (xy 173.586201 -408.092624) (xy 173.594994 -408.157472) (xy 173.594994 -408.190192)
			(xy 177.023784 -408.190192) (xy 177.027775 -408.128025) (xy 177.039684 -408.066878) (xy 177.059313 -408.007757)
			(xy 177.086342 -407.951631) (xy 177.120326 -407.899422) (xy 177.160708 -407.851987) (xy 177.206824 -407.810106)
			(xy 177.257916 -407.774466) (xy 177.313147 -407.745652) (xy 177.371609 -407.724138) (xy 177.432343 -407.710276)
			(xy 177.49435 -407.704294) (xy 177.556613 -407.70629) (xy 177.61811 -407.716233) (xy 177.677831 -407.733957)
			(xy 177.734794 -407.759174) (xy 177.788065 -407.791467) (xy 177.83677 -407.830307) (xy 177.880107 -407.875057)
			(xy 177.917367 -407.924981) (xy 177.947936 -407.97926) (xy 177.971314 -408.037003) (xy 177.987115 -408.097261)
			(xy 177.995081 -408.159044) (xy 177.99558 -408.190192) (xy 177.995081 -408.22134) (xy 177.987115 -408.283123)
			(xy 177.971314 -408.343381) (xy 177.947936 -408.401124) (xy 177.917367 -408.455403) (xy 177.880107 -408.505327)
			(xy 177.83677 -408.550077) (xy 177.788065 -408.588917) (xy 177.782527 -408.592274) (xy 190.042798 -408.592274)
			(xy 190.046869 -408.536652) (xy 190.058995 -408.482215) (xy 190.078918 -408.430124) (xy 190.106214 -408.381489)
			(xy 190.1403 -408.337346) (xy 190.180449 -408.298637) (xy 190.225807 -408.266186) (xy 190.275407 -408.240685)
			(xy 190.328191 -408.222678) (xy 190.383034 -408.212548) (xy 190.438768 -408.210511) (xy 190.494205 -408.216611)
			(xy 190.548162 -408.230717) (xy 190.599491 -408.252529) (xy 190.647097 -408.281583) (xy 190.689965 -408.317258)
			(xy 190.727182 -408.358795) (xy 190.757955 -408.405308) (xy 190.781627 -408.455805) (xy 190.797695 -408.509212)
			(xy 190.805815 -408.564388) (xy 190.806324 -408.592274) (xy 190.805815 -408.62016) (xy 190.797695 -408.675336)
			(xy 190.781627 -408.728743) (xy 190.757955 -408.77924) (xy 190.727182 -408.825753) (xy 190.689965 -408.86729)
			(xy 190.647097 -408.902965) (xy 190.599491 -408.932019) (xy 190.548162 -408.953831) (xy 190.520426 -408.961082)
			(xy 194.781676 -408.961082) (xy 194.785747 -408.90546) (xy 194.797873 -408.851023) (xy 194.817796 -408.798932)
			(xy 194.845092 -408.750297) (xy 194.879178 -408.706154) (xy 194.919327 -408.667445) (xy 194.964685 -408.634994)
			(xy 195.014285 -408.609493) (xy 195.067069 -408.591486) (xy 195.121912 -408.581356) (xy 195.177646 -408.579319)
			(xy 195.233083 -408.585419) (xy 195.28704 -408.599525) (xy 195.338369 -408.621337) (xy 195.385975 -408.650391)
			(xy 195.42327 -408.681428) (xy 196.990968 -408.681428) (xy 196.995039 -408.625806) (xy 197.007165 -408.571369)
			(xy 197.027088 -408.519278) (xy 197.054384 -408.470643) (xy 197.08847 -408.4265) (xy 197.128619 -408.387791)
			(xy 197.173977 -408.35534) (xy 197.223577 -408.329839) (xy 197.276361 -408.311832) (xy 197.331204 -408.301702)
			(xy 197.386938 -408.299665) (xy 197.442375 -408.305765) (xy 197.496332 -408.319871) (xy 197.547661 -408.341683)
			(xy 197.595267 -408.370737) (xy 197.638135 -408.406412) (xy 197.675352 -408.447949) (xy 197.706125 -408.494462)
			(xy 197.729797 -408.544959) (xy 197.745865 -408.598366) (xy 197.753985 -408.653542) (xy 197.754494 -408.681428)
			(xy 197.753985 -408.709314) (xy 197.745865 -408.76449) (xy 197.729797 -408.817897) (xy 197.706125 -408.868394)
			(xy 197.675352 -408.914907) (xy 197.638135 -408.956444) (xy 197.595267 -408.992119) (xy 197.547661 -409.021173)
			(xy 197.496332 -409.042985) (xy 197.442375 -409.057091) (xy 197.386938 -409.063191) (xy 197.331204 -409.061154)
			(xy 197.276361 -409.051024) (xy 197.223577 -409.033017) (xy 197.173977 -409.007516) (xy 197.128619 -408.975065)
			(xy 197.08847 -408.936356) (xy 197.054384 -408.892213) (xy 197.027088 -408.843578) (xy 197.007165 -408.791487)
			(xy 196.995039 -408.73705) (xy 196.990968 -408.681428) (xy 195.42327 -408.681428) (xy 195.428843 -408.686066)
			(xy 195.46606 -408.727603) (xy 195.496833 -408.774116) (xy 195.520505 -408.824613) (xy 195.536573 -408.87802)
			(xy 195.544693 -408.933196) (xy 195.545202 -408.961082) (xy 195.544693 -408.988968) (xy 195.536573 -409.044144)
			(xy 195.520505 -409.097551) (xy 195.496833 -409.148048) (xy 195.46606 -409.194561) (xy 195.428843 -409.236098)
			(xy 195.385975 -409.271773) (xy 195.338369 -409.300827) (xy 195.28704 -409.322639) (xy 195.233083 -409.336745)
			(xy 195.177646 -409.342845) (xy 195.121912 -409.340808) (xy 195.067069 -409.330678) (xy 195.014285 -409.312671)
			(xy 194.964685 -409.28717) (xy 194.919327 -409.254719) (xy 194.879178 -409.21601) (xy 194.845092 -409.171867)
			(xy 194.817796 -409.123232) (xy 194.797873 -409.071141) (xy 194.785747 -409.016704) (xy 194.781676 -408.961082)
			(xy 190.520426 -408.961082) (xy 190.494205 -408.967937) (xy 190.438768 -408.974037) (xy 190.383034 -408.972)
			(xy 190.328191 -408.96187) (xy 190.275407 -408.943863) (xy 190.225807 -408.918362) (xy 190.180449 -408.885911)
			(xy 190.1403 -408.847202) (xy 190.106214 -408.803059) (xy 190.078918 -408.754424) (xy 190.058995 -408.702333)
			(xy 190.046869 -408.647896) (xy 190.042798 -408.592274) (xy 177.782527 -408.592274) (xy 177.734794 -408.62121)
			(xy 177.677831 -408.646427) (xy 177.61811 -408.664151) (xy 177.556613 -408.674094) (xy 177.49435 -408.67609)
			(xy 177.432343 -408.670108) (xy 177.371609 -408.656246) (xy 177.313147 -408.634732) (xy 177.257916 -408.605918)
			(xy 177.206824 -408.570278) (xy 177.160708 -408.528397) (xy 177.120326 -408.480962) (xy 177.086342 -408.428753)
			(xy 177.059313 -408.372627) (xy 177.039684 -408.313506) (xy 177.027775 -408.252359) (xy 177.023784 -408.190192)
			(xy 173.594994 -408.190192) (xy 173.594995 -408.222914) (xy 173.586204 -408.287763) (xy 173.56878 -408.350842)
			(xy 173.543039 -408.411009) (xy 173.526704 -408.439366) (xy 173.523402 -408.445397) (xy 173.519788 -408.458656)
			(xy 173.519592 -408.465528) (xy 173.519592 -409.214828) (xy 173.519774 -409.221702) (xy 173.523389 -409.234965)
			(xy 173.526704 -409.24099) (xy 173.54301 -409.269363) (xy 173.568754 -409.329527) (xy 173.586182 -409.392603)
			(xy 173.594978 -409.457449) (xy 173.594982 -409.522889) (xy 173.586195 -409.587736) (xy 173.568774 -409.650815)
			(xy 173.543038 -409.710981) (xy 173.526704 -409.739338) (xy 173.523376 -409.745356) (xy 173.519779 -409.758625)
			(xy 173.519592 -409.7655) (xy 173.519592 -410.051504) (xy 173.519181 -410.061659) (xy 173.511383 -410.080413)
			(xy 173.496983 -410.094737) (xy 173.478187 -410.102435) (xy 173.46803 -410.102812) (xy 172.75175 -410.102812)
			(xy 172.741633 -410.102234) (xy 172.722923 -410.094532) (xy 172.708567 -410.080274) (xy 172.700736 -410.061618)
			(xy 172.700188 -410.051504) (xy 172.700188 -409.7655) (xy 172.699997 -409.758627) (xy 172.696388 -409.745364)
			(xy 172.693076 -409.739338) (xy 172.676707 -409.710999) (xy 172.650964 -409.650829) (xy 172.63354 -409.587745)
			(xy 172.62475 -409.522892) (xy 171.336199 -409.522892) (xy 171.32681 -409.539186) (xy 171.323455 -409.545206)
			(xy 171.319713 -409.558462) (xy 171.319444 -409.565348) (xy 171.319444 -410.314648) (xy 171.319669 -410.321541)
			(xy 171.323403 -410.334813) (xy 171.32681 -410.34081) (xy 171.343135 -410.369173) (xy 171.368883 -410.429338)
			(xy 171.386313 -410.492416) (xy 171.395109 -410.557265) (xy 171.39511 -410.622708) (xy 174.824916 -410.622708)
			(xy 174.824918 -410.557264) (xy 174.833713 -410.492414) (xy 174.851141 -410.429333) (xy 174.876886 -410.369166)
			(xy 174.893224 -410.34081) (xy 174.896537 -410.334785) (xy 174.900143 -410.321521) (xy 174.900336 -410.314648)
			(xy 174.900336 -409.565348) (xy 174.900121 -409.558476) (xy 174.896528 -409.545214) (xy 174.893224 -409.539186)
			(xy 174.876897 -409.510824) (xy 174.851153 -409.450659) (xy 174.833726 -409.38758) (xy 174.824932 -409.322731)
			(xy 174.824931 -409.257289) (xy 174.833722 -409.192441) (xy 174.851146 -409.129361) (xy 174.876888 -409.069194)
			(xy 174.893224 -409.040838) (xy 174.896527 -409.034808) (xy 174.90014 -409.021548) (xy 174.900336 -409.014676)
			(xy 174.900336 -408.728672) (xy 174.900699 -408.718512) (xy 174.908511 -408.699752) (xy 174.922926 -408.685428)
			(xy 174.941735 -408.677736) (xy 174.951898 -408.677364) (xy 175.668178 -408.677364) (xy 175.678306 -408.677845)
			(xy 175.697032 -408.68557) (xy 175.711389 -408.699859) (xy 175.719205 -408.718546) (xy 175.71974 -408.728672)
			(xy 175.71974 -409.014676) (xy 175.719936 -409.021549) (xy 175.723541 -409.034812) (xy 175.726852 -409.040838)
			(xy 175.7432 -409.069188) (xy 175.768943 -409.129356) (xy 175.786369 -409.192438) (xy 175.795161 -409.257288)
			(xy 175.795159 -409.322732) (xy 175.786365 -409.387583) (xy 175.768936 -409.450663) (xy 175.752033 -409.490164)
			(xy 177.023784 -409.490164) (xy 177.027775 -409.427997) (xy 177.039684 -409.36685) (xy 177.059313 -409.307729)
			(xy 177.086342 -409.251603) (xy 177.120326 -409.199394) (xy 177.160708 -409.151959) (xy 177.206824 -409.110078)
			(xy 177.257916 -409.074438) (xy 177.313147 -409.045624) (xy 177.371609 -409.02411) (xy 177.432343 -409.010248)
			(xy 177.49435 -409.004266) (xy 177.556613 -409.006262) (xy 177.61811 -409.016205) (xy 177.677831 -409.033929)
			(xy 177.734794 -409.059146) (xy 177.788065 -409.091439) (xy 177.83677 -409.130279) (xy 177.880107 -409.175029)
			(xy 177.917367 -409.224953) (xy 177.947936 -409.279232) (xy 177.9523 -409.290012) (xy 179.223932 -409.290012)
			(xy 179.227923 -409.227845) (xy 179.239832 -409.166698) (xy 179.259461 -409.107577) (xy 179.28649 -409.051451)
			(xy 179.320474 -408.999242) (xy 179.360856 -408.951807) (xy 179.406972 -408.909926) (xy 179.458064 -408.874286)
			(xy 179.513295 -408.845472) (xy 179.571757 -408.823958) (xy 179.632491 -408.810096) (xy 179.694498 -408.804114)
			(xy 179.756761 -408.80611) (xy 179.818258 -408.816053) (xy 179.877979 -408.833777) (xy 179.934942 -408.858994)
			(xy 179.988213 -408.891287) (xy 180.036918 -408.930127) (xy 180.080255 -408.974877) (xy 180.117515 -409.024801)
			(xy 180.148084 -409.07908) (xy 180.171462 -409.136823) (xy 180.187263 -409.197081) (xy 180.195229 -409.258864)
			(xy 180.195728 -409.290012) (xy 180.195229 -409.32116) (xy 180.187263 -409.382943) (xy 180.177397 -409.420568)
			(xy 186.579 -409.420568) (xy 186.583071 -409.364946) (xy 186.595197 -409.310509) (xy 186.61512 -409.258418)
			(xy 186.642416 -409.209783) (xy 186.676502 -409.16564) (xy 186.716651 -409.126931) (xy 186.762009 -409.09448)
			(xy 186.811609 -409.068979) (xy 186.864393 -409.050972) (xy 186.919236 -409.040842) (xy 186.97497 -409.038805)
			(xy 187.030407 -409.044905) (xy 187.084364 -409.059011) (xy 187.135693 -409.080823) (xy 187.183299 -409.109877)
			(xy 187.226167 -409.145552) (xy 187.263384 -409.187089) (xy 187.294157 -409.233602) (xy 187.317829 -409.284099)
			(xy 187.333897 -409.337506) (xy 187.342017 -409.392682) (xy 187.342526 -409.420568) (xy 187.342017 -409.448454)
			(xy 187.333897 -409.50363) (xy 187.317829 -409.557037) (xy 187.294157 -409.607534) (xy 187.263384 -409.654047)
			(xy 187.226167 -409.695584) (xy 187.183299 -409.731259) (xy 187.135693 -409.760313) (xy 187.084364 -409.782125)
			(xy 187.030407 -409.796231) (xy 186.97497 -409.802331) (xy 186.919236 -409.800294) (xy 186.864393 -409.790164)
			(xy 186.811609 -409.772157) (xy 186.762009 -409.746656) (xy 186.716651 -409.714205) (xy 186.676502 -409.675496)
			(xy 186.642416 -409.631353) (xy 186.61512 -409.582718) (xy 186.595197 -409.530627) (xy 186.583071 -409.47619)
			(xy 186.579 -409.420568) (xy 180.177397 -409.420568) (xy 180.171462 -409.443201) (xy 180.148084 -409.500944)
			(xy 180.117515 -409.555223) (xy 180.080255 -409.605147) (xy 180.036918 -409.649897) (xy 179.988213 -409.688737)
			(xy 179.934942 -409.72103) (xy 179.877979 -409.746247) (xy 179.818258 -409.763971) (xy 179.756761 -409.773914)
			(xy 179.694498 -409.77591) (xy 179.632491 -409.769928) (xy 179.571757 -409.756066) (xy 179.513295 -409.734552)
			(xy 179.458064 -409.705738) (xy 179.406972 -409.670098) (xy 179.360856 -409.628217) (xy 179.320474 -409.580782)
			(xy 179.28649 -409.528573) (xy 179.259461 -409.472447) (xy 179.239832 -409.413326) (xy 179.227923 -409.352179)
			(xy 179.223932 -409.290012) (xy 177.9523 -409.290012) (xy 177.971314 -409.336975) (xy 177.987115 -409.397233)
			(xy 177.995081 -409.459016) (xy 177.99558 -409.490164) (xy 177.995081 -409.521312) (xy 177.987115 -409.583095)
			(xy 177.971314 -409.643353) (xy 177.947936 -409.701096) (xy 177.917367 -409.755375) (xy 177.880107 -409.805299)
			(xy 177.83677 -409.850049) (xy 177.788065 -409.888889) (xy 177.774985 -409.896818) (xy 191.732914 -409.896818)
			(xy 191.736985 -409.841196) (xy 191.749111 -409.786759) (xy 191.769034 -409.734668) (xy 191.79633 -409.686033)
			(xy 191.830416 -409.64189) (xy 191.870565 -409.603181) (xy 191.915923 -409.57073) (xy 191.965523 -409.545229)
			(xy 192.018307 -409.527222) (xy 192.07315 -409.517092) (xy 192.128884 -409.515055) (xy 192.184321 -409.521155)
			(xy 192.238278 -409.535261) (xy 192.289607 -409.557073) (xy 192.337213 -409.586127) (xy 192.380081 -409.621802)
			(xy 192.417298 -409.663339) (xy 192.448071 -409.709852) (xy 192.471743 -409.760349) (xy 192.487811 -409.813756)
			(xy 192.495931 -409.868932) (xy 192.49644 -409.896818) (xy 192.495931 -409.924704) (xy 192.487811 -409.97988)
			(xy 192.471743 -410.033287) (xy 192.448071 -410.083784) (xy 192.417298 -410.130297) (xy 192.380081 -410.171834)
			(xy 192.337213 -410.207509) (xy 192.289607 -410.236563) (xy 192.238278 -410.258375) (xy 192.184321 -410.272481)
			(xy 192.128884 -410.278581) (xy 192.07315 -410.276544) (xy 192.018307 -410.266414) (xy 191.965523 -410.248407)
			(xy 191.915923 -410.222906) (xy 191.870565 -410.190455) (xy 191.830416 -410.151746) (xy 191.79633 -410.107603)
			(xy 191.769034 -410.058968) (xy 191.749111 -410.006877) (xy 191.736985 -409.95244) (xy 191.732914 -409.896818)
			(xy 177.774985 -409.896818) (xy 177.734794 -409.921182) (xy 177.677831 -409.946399) (xy 177.61811 -409.964123)
			(xy 177.556613 -409.974066) (xy 177.49435 -409.976062) (xy 177.432343 -409.97008) (xy 177.371609 -409.956218)
			(xy 177.313147 -409.934704) (xy 177.257916 -409.90589) (xy 177.206824 -409.87025) (xy 177.160708 -409.828369)
			(xy 177.120326 -409.780934) (xy 177.086342 -409.728725) (xy 177.059313 -409.672599) (xy 177.039684 -409.613478)
			(xy 177.027775 -409.552331) (xy 177.023784 -409.490164) (xy 175.752033 -409.490164) (xy 175.74319 -409.51083)
			(xy 175.726852 -409.539186) (xy 175.723546 -409.545215) (xy 175.719934 -409.558475) (xy 175.71974 -409.565348)
			(xy 175.71974 -410.314648) (xy 175.719947 -410.32152) (xy 175.723544 -410.334783) (xy 175.726852 -410.34081)
			(xy 175.743176 -410.369174) (xy 175.768922 -410.429338) (xy 175.78635 -410.492417) (xy 175.795145 -410.557265)
			(xy 175.795146 -410.589984) (xy 179.223932 -410.589984) (xy 179.227923 -410.527817) (xy 179.239832 -410.46667)
			(xy 179.259461 -410.407549) (xy 179.28649 -410.351423) (xy 179.320474 -410.299214) (xy 179.360856 -410.251779)
			(xy 179.406972 -410.209898) (xy 179.458064 -410.174258) (xy 179.513295 -410.145444) (xy 179.571757 -410.12393)
			(xy 179.632491 -410.110068) (xy 179.694498 -410.104086) (xy 179.756761 -410.106082) (xy 179.818258 -410.116025)
			(xy 179.877979 -410.133749) (xy 179.934942 -410.158966) (xy 179.988213 -410.191259) (xy 180.036918 -410.230099)
			(xy 180.080255 -410.274849) (xy 180.117515 -410.324773) (xy 180.148084 -410.379052) (xy 180.171462 -410.436795)
			(xy 180.187263 -410.497053) (xy 180.195229 -410.558836) (xy 180.195728 -410.589984) (xy 180.195229 -410.621132)
			(xy 180.187263 -410.682915) (xy 180.171462 -410.743173) (xy 180.148084 -410.800916) (xy 180.117515 -410.855195)
			(xy 180.080255 -410.905119) (xy 180.036918 -410.949869) (xy 179.988213 -410.988709) (xy 179.934942 -411.021002)
			(xy 179.896455 -411.03804) (xy 185.614054 -411.03804) (xy 185.618125 -410.982418) (xy 185.630251 -410.927981)
			(xy 185.650174 -410.87589) (xy 185.67747 -410.827255) (xy 185.711556 -410.783112) (xy 185.751705 -410.744403)
			(xy 185.797063 -410.711952) (xy 185.846663 -410.686451) (xy 185.899447 -410.668444) (xy 185.95429 -410.658314)
			(xy 186.010024 -410.656277) (xy 186.065461 -410.662377) (xy 186.119418 -410.676483) (xy 186.170747 -410.698295)
			(xy 186.218353 -410.727349) (xy 186.261221 -410.763024) (xy 186.298438 -410.804561) (xy 186.329211 -410.851074)
			(xy 186.351249 -410.898086) (xy 188.828678 -410.898086) (xy 188.832749 -410.842464) (xy 188.844875 -410.788027)
			(xy 188.864798 -410.735936) (xy 188.892094 -410.687301) (xy 188.92618 -410.643158) (xy 188.966329 -410.604449)
			(xy 189.011687 -410.571998) (xy 189.061287 -410.546497) (xy 189.114071 -410.52849) (xy 189.168914 -410.51836)
			(xy 189.224648 -410.516323) (xy 189.280085 -410.522423) (xy 189.334042 -410.536529) (xy 189.385371 -410.558341)
			(xy 189.432977 -410.587395) (xy 189.475845 -410.62307) (xy 189.513062 -410.664607) (xy 189.534439 -410.696918)
			(xy 195.549264 -410.696918) (xy 195.553335 -410.641296) (xy 195.565461 -410.586859) (xy 195.585384 -410.534768)
			(xy 195.61268 -410.486133) (xy 195.646766 -410.44199) (xy 195.686915 -410.403281) (xy 195.732273 -410.37083)
			(xy 195.781873 -410.345329) (xy 195.834657 -410.327322) (xy 195.8895 -410.317192) (xy 195.945234 -410.315155)
			(xy 196.000671 -410.321255) (xy 196.054628 -410.335361) (xy 196.105957 -410.357173) (xy 196.153563 -410.386227)
			(xy 196.196431 -410.421902) (xy 196.233648 -410.463439) (xy 196.264421 -410.509952) (xy 196.288093 -410.560449)
			(xy 196.304161 -410.613856) (xy 196.312281 -410.669032) (xy 196.31279 -410.696918) (xy 196.312281 -410.724804)
			(xy 196.304161 -410.77998) (xy 196.288093 -410.833387) (xy 196.264421 -410.883884) (xy 196.233648 -410.930397)
			(xy 196.196431 -410.971934) (xy 196.153563 -411.007609) (xy 196.105957 -411.036663) (xy 196.054628 -411.058475)
			(xy 196.000671 -411.072581) (xy 195.945234 -411.078681) (xy 195.8895 -411.076644) (xy 195.834657 -411.066514)
			(xy 195.781873 -411.048507) (xy 195.732273 -411.023006) (xy 195.686915 -410.990555) (xy 195.646766 -410.951846)
			(xy 195.61268 -410.907703) (xy 195.585384 -410.859068) (xy 195.565461 -410.806977) (xy 195.553335 -410.75254)
			(xy 195.549264 -410.696918) (xy 189.534439 -410.696918) (xy 189.543835 -410.71112) (xy 189.567507 -410.761617)
			(xy 189.583575 -410.815024) (xy 189.591695 -410.8702) (xy 189.592204 -410.898086) (xy 189.591695 -410.925972)
			(xy 189.583575 -410.981148) (xy 189.567507 -411.034555) (xy 189.543835 -411.085052) (xy 189.513062 -411.131565)
			(xy 189.475845 -411.173102) (xy 189.432977 -411.208777) (xy 189.385371 -411.237831) (xy 189.334042 -411.259643)
			(xy 189.280085 -411.273749) (xy 189.224648 -411.279849) (xy 189.168914 -411.277812) (xy 189.114071 -411.267682)
			(xy 189.061287 -411.249675) (xy 189.011687 -411.224174) (xy 188.966329 -411.191723) (xy 188.92618 -411.153014)
			(xy 188.892094 -411.108871) (xy 188.864798 -411.060236) (xy 188.844875 -411.008145) (xy 188.832749 -410.953708)
			(xy 188.828678 -410.898086) (xy 186.351249 -410.898086) (xy 186.352883 -410.901571) (xy 186.368951 -410.954978)
			(xy 186.377071 -411.010154) (xy 186.37758 -411.03804) (xy 186.377071 -411.065926) (xy 186.368951 -411.121102)
			(xy 186.352883 -411.174509) (xy 186.329211 -411.225006) (xy 186.298438 -411.271519) (xy 186.261221 -411.313056)
			(xy 186.253817 -411.319218) (xy 193.336416 -411.319218) (xy 193.340487 -411.263596) (xy 193.352613 -411.209159)
			(xy 193.372536 -411.157068) (xy 193.399832 -411.108433) (xy 193.433918 -411.06429) (xy 193.474067 -411.025581)
			(xy 193.519425 -410.99313) (xy 193.569025 -410.967629) (xy 193.621809 -410.949622) (xy 193.676652 -410.939492)
			(xy 193.732386 -410.937455) (xy 193.787823 -410.943555) (xy 193.84178 -410.957661) (xy 193.893109 -410.979473)
			(xy 193.940715 -411.008527) (xy 193.983583 -411.044202) (xy 194.0208 -411.085739) (xy 194.051573 -411.132252)
			(xy 194.075245 -411.182749) (xy 194.091313 -411.236156) (xy 194.099433 -411.291332) (xy 194.099942 -411.319218)
			(xy 194.099812 -411.32633) (xy 197.241412 -411.32633) (xy 197.245483 -411.270708) (xy 197.257609 -411.216271)
			(xy 197.277532 -411.16418) (xy 197.304828 -411.115545) (xy 197.338914 -411.071402) (xy 197.379063 -411.032693)
			(xy 197.424421 -411.000242) (xy 197.474021 -410.974741) (xy 197.526805 -410.956734) (xy 197.581648 -410.946604)
			(xy 197.637382 -410.944567) (xy 197.692819 -410.950667) (xy 197.746776 -410.964773) (xy 197.798105 -410.986585)
			(xy 197.845711 -411.015639) (xy 197.888579 -411.051314) (xy 197.925796 -411.092851) (xy 197.956569 -411.139364)
			(xy 197.980241 -411.189861) (xy 197.996309 -411.243268) (xy 198.004429 -411.298444) (xy 198.004938 -411.32633)
			(xy 198.004429 -411.354216) (xy 197.996309 -411.409392) (xy 197.980241 -411.462799) (xy 197.956569 -411.513296)
			(xy 197.925796 -411.559809) (xy 197.888579 -411.601346) (xy 197.845711 -411.637021) (xy 197.798105 -411.666075)
			(xy 197.746776 -411.687887) (xy 197.692819 -411.701993) (xy 197.637382 -411.708093) (xy 197.581648 -411.706056)
			(xy 197.526805 -411.695926) (xy 197.474021 -411.677919) (xy 197.424421 -411.652418) (xy 197.379063 -411.619967)
			(xy 197.338914 -411.581258) (xy 197.304828 -411.537115) (xy 197.277532 -411.48848) (xy 197.257609 -411.436389)
			(xy 197.245483 -411.381952) (xy 197.241412 -411.32633) (xy 194.099812 -411.32633) (xy 194.099433 -411.347104)
			(xy 194.091313 -411.40228) (xy 194.075245 -411.455687) (xy 194.051573 -411.506184) (xy 194.0208 -411.552697)
			(xy 193.983583 -411.594234) (xy 193.940715 -411.629909) (xy 193.893109 -411.658963) (xy 193.84178 -411.680775)
			(xy 193.787823 -411.694881) (xy 193.732386 -411.700981) (xy 193.676652 -411.698944) (xy 193.621809 -411.688814)
			(xy 193.569025 -411.670807) (xy 193.519425 -411.645306) (xy 193.474067 -411.612855) (xy 193.433918 -411.574146)
			(xy 193.399832 -411.530003) (xy 193.372536 -411.481368) (xy 193.352613 -411.429277) (xy 193.340487 -411.37484)
			(xy 193.336416 -411.319218) (xy 186.253817 -411.319218) (xy 186.218353 -411.348731) (xy 186.170747 -411.377785)
			(xy 186.119418 -411.399597) (xy 186.065461 -411.413703) (xy 186.010024 -411.419803) (xy 185.95429 -411.417766)
			(xy 185.899447 -411.407636) (xy 185.846663 -411.389629) (xy 185.797063 -411.364128) (xy 185.751705 -411.331677)
			(xy 185.711556 -411.292968) (xy 185.67747 -411.248825) (xy 185.650174 -411.20019) (xy 185.630251 -411.148099)
			(xy 185.618125 -411.093662) (xy 185.614054 -411.03804) (xy 179.896455 -411.03804) (xy 179.877979 -411.046219)
			(xy 179.818258 -411.063943) (xy 179.756761 -411.073886) (xy 179.694498 -411.075882) (xy 179.632491 -411.0699)
			(xy 179.571757 -411.056038) (xy 179.513295 -411.034524) (xy 179.458064 -411.00571) (xy 179.406972 -410.97007)
			(xy 179.360856 -410.928189) (xy 179.320474 -410.880754) (xy 179.28649 -410.828545) (xy 179.259461 -410.772419)
			(xy 179.239832 -410.713298) (xy 179.227923 -410.652151) (xy 179.223932 -410.589984) (xy 175.795146 -410.589984)
			(xy 175.795147 -410.622707) (xy 175.786355 -410.687556) (xy 175.768931 -410.750636) (xy 175.743189 -410.810802)
			(xy 175.726852 -410.839158) (xy 175.723556 -410.845192) (xy 175.719938 -410.858448) (xy 175.71974 -410.86532)
			(xy 175.71974 -411.151324) (xy 175.719299 -411.161475) (xy 175.711503 -411.18022) (xy 175.697113 -411.194541)
			(xy 175.678331 -411.202247) (xy 175.668178 -411.202632) (xy 174.951898 -411.202632) (xy 174.941768 -411.202174)
			(xy 174.923041 -411.194441) (xy 174.908684 -411.180145) (xy 174.90087 -411.161452) (xy 174.900336 -411.151324)
			(xy 174.900336 -410.86532) (xy 174.900132 -410.858448) (xy 174.896531 -410.845185) (xy 174.893224 -410.839158)
			(xy 174.876874 -410.810809) (xy 174.851132 -410.750641) (xy 174.833707 -410.687559) (xy 174.824916 -410.622708)
			(xy 171.39511 -410.622708) (xy 171.386319 -410.687557) (xy 171.368892 -410.750636) (xy 171.343148 -410.810802)
			(xy 171.32681 -410.839158) (xy 171.32343 -410.845165) (xy 171.319704 -410.858431) (xy 171.319444 -410.86532)
			(xy 171.319444 -411.151324) (xy 171.318936 -411.161429) (xy 171.311198 -411.180099) (xy 171.296909 -411.194392)
			(xy 171.278241 -411.202133) (xy 171.268136 -411.202632) (xy 170.551856 -411.202632) (xy 170.541748 -411.202152)
			(xy 170.523075 -411.194405) (xy 170.508783 -411.180108) (xy 170.501044 -411.161432) (xy 170.500548 -411.151324)
			(xy 170.500548 -410.86532) (xy 170.500336 -410.858426) (xy 170.496593 -410.845154) (xy 170.493182 -410.839158)
			(xy 170.47683 -410.81081) (xy 170.451085 -410.750642) (xy 170.433658 -410.68756) (xy 170.424866 -410.622709)
			(xy 166.99506 -410.622709) (xy 166.98627 -410.687556) (xy 166.968845 -410.750635) (xy 166.943104 -410.810802)
			(xy 166.926768 -410.839158) (xy 166.923466 -410.845189) (xy 166.919853 -410.858448) (xy 166.919656 -410.86532)
			(xy 166.919656 -411.151324) (xy 166.919199 -411.161473) (xy 166.911406 -411.180215) (xy 166.897021 -411.194535)
			(xy 166.878245 -411.202244) (xy 166.868094 -411.202632) (xy 166.151814 -411.202632) (xy 166.141685 -411.202161)
			(xy 166.122959 -411.194433) (xy 166.108601 -411.180141) (xy 166.100786 -411.161451) (xy 166.100252 -411.151324)
			(xy 166.100252 -410.86532) (xy 166.100058 -410.858447) (xy 166.096452 -410.845184) (xy 166.09314 -410.839158)
			(xy 166.076789 -410.810809) (xy 166.051046 -410.750641) (xy 166.033621 -410.687559) (xy 166.02483 -410.622708)
			(xy 162.595024 -410.622708) (xy 162.586233 -410.687556) (xy 162.568807 -410.750636) (xy 162.543063 -410.810802)
			(xy 162.526726 -410.839158) (xy 162.52334 -410.845162) (xy 162.519618 -410.858431) (xy 162.51936 -410.86532)
			(xy 162.51936 -411.151324) (xy 162.519003 -411.161453) (xy 162.511239 -411.180165) (xy 162.496904 -411.19448)
			(xy 162.478182 -411.202217) (xy 162.468052 -411.202632) (xy 161.751772 -411.202632) (xy 161.741665 -411.202139)
			(xy 161.722993 -411.194398) (xy 161.7087 -411.180104) (xy 161.700961 -411.161431) (xy 161.700464 -411.151324)
			(xy 161.700464 -410.86532) (xy 161.70025 -410.858426) (xy 161.696508 -410.845154) (xy 161.693098 -410.839158)
			(xy 161.676748 -410.810809) (xy 161.651008 -410.75064) (xy 161.633584 -410.687559) (xy 161.624794 -410.622708)
			(xy 154.57678 -410.622708) (xy 154.57678 -412.090108) (xy 159.42387 -412.090108) (xy 159.427861 -412.027941)
			(xy 159.43977 -411.966794) (xy 159.459399 -411.907673) (xy 159.486428 -411.851547) (xy 159.520412 -411.799338)
			(xy 159.560794 -411.751903) (xy 159.60691 -411.710022) (xy 159.658002 -411.674382) (xy 159.713233 -411.645568)
			(xy 159.771695 -411.624054) (xy 159.832429 -411.610192) (xy 159.894436 -411.60421) (xy 159.956699 -411.606206)
			(xy 160.018196 -411.616149) (xy 160.077917 -411.633873) (xy 160.13488 -411.65909) (xy 160.188151 -411.691383)
			(xy 160.236856 -411.730223) (xy 160.280193 -411.774973) (xy 160.317453 -411.824897) (xy 160.348022 -411.879176)
			(xy 160.3714 -411.936919) (xy 160.387201 -411.997177) (xy 160.395167 -412.05896) (xy 160.395666 -412.090108)
			(xy 163.823912 -412.090108) (xy 163.827903 -412.027941) (xy 163.839812 -411.966794) (xy 163.859441 -411.907673)
			(xy 163.88647 -411.851547) (xy 163.920454 -411.799338) (xy 163.960836 -411.751903) (xy 164.006952 -411.710022)
			(xy 164.058044 -411.674382) (xy 164.113275 -411.645568) (xy 164.171737 -411.624054) (xy 164.232471 -411.610192)
			(xy 164.294478 -411.60421) (xy 164.356741 -411.606206) (xy 164.418238 -411.616149) (xy 164.477959 -411.633873)
			(xy 164.534922 -411.65909) (xy 164.588193 -411.691383) (xy 164.636898 -411.730223) (xy 164.680235 -411.774973)
			(xy 164.717495 -411.824897) (xy 164.748064 -411.879176) (xy 164.771442 -411.936919) (xy 164.787243 -411.997177)
			(xy 164.795209 -412.05896) (xy 164.795708 -412.090108) (xy 168.223954 -412.090108) (xy 168.227945 -412.027941)
			(xy 168.239854 -411.966794) (xy 168.259483 -411.907673) (xy 168.286512 -411.851547) (xy 168.320496 -411.799338)
			(xy 168.360878 -411.751903) (xy 168.406994 -411.710022) (xy 168.458086 -411.674382) (xy 168.513317 -411.645568)
			(xy 168.571779 -411.624054) (xy 168.632513 -411.610192) (xy 168.69452 -411.60421) (xy 168.756783 -411.606206)
			(xy 168.81828 -411.616149) (xy 168.878001 -411.633873) (xy 168.934964 -411.65909) (xy 168.988235 -411.691383)
			(xy 169.03694 -411.730223) (xy 169.080277 -411.774973) (xy 169.117537 -411.824897) (xy 169.148106 -411.879176)
			(xy 169.171484 -411.936919) (xy 169.187285 -411.997177) (xy 169.195251 -412.05896) (xy 169.19575 -412.090108)
			(xy 172.623742 -412.090108) (xy 172.627733 -412.027941) (xy 172.639642 -411.966794) (xy 172.659271 -411.907673)
			(xy 172.6863 -411.851547) (xy 172.720284 -411.799338) (xy 172.760666 -411.751903) (xy 172.806782 -411.710022)
			(xy 172.857874 -411.674382) (xy 172.913105 -411.645568) (xy 172.971567 -411.624054) (xy 173.032301 -411.610192)
			(xy 173.094308 -411.60421) (xy 173.156571 -411.606206) (xy 173.218068 -411.616149) (xy 173.277789 -411.633873)
			(xy 173.334752 -411.65909) (xy 173.388023 -411.691383) (xy 173.436728 -411.730223) (xy 173.480065 -411.774973)
			(xy 173.517325 -411.824897) (xy 173.547894 -411.879176) (xy 173.571272 -411.936919) (xy 173.587073 -411.997177)
			(xy 173.595039 -412.05896) (xy 173.595538 -412.090108) (xy 177.023784 -412.090108) (xy 177.027775 -412.027941)
			(xy 177.039684 -411.966794) (xy 177.059313 -411.907673) (xy 177.086342 -411.851547) (xy 177.120326 -411.799338)
			(xy 177.160708 -411.751903) (xy 177.206824 -411.710022) (xy 177.257916 -411.674382) (xy 177.313147 -411.645568)
			(xy 177.371609 -411.624054) (xy 177.432343 -411.610192) (xy 177.49435 -411.60421) (xy 177.556613 -411.606206)
			(xy 177.61811 -411.616149) (xy 177.677831 -411.633873) (xy 177.734794 -411.65909) (xy 177.788065 -411.691383)
			(xy 177.83677 -411.730223) (xy 177.880107 -411.774973) (xy 177.917367 -411.824897) (xy 177.947936 -411.879176)
			(xy 177.971314 -411.936919) (xy 177.985708 -411.99181) (xy 188.011052 -411.99181) (xy 188.015123 -411.936188)
			(xy 188.027249 -411.881751) (xy 188.047172 -411.82966) (xy 188.074468 -411.781025) (xy 188.108554 -411.736882)
			(xy 188.148703 -411.698173) (xy 188.194061 -411.665722) (xy 188.243661 -411.640221) (xy 188.296445 -411.622214)
			(xy 188.351288 -411.612084) (xy 188.407022 -411.610047) (xy 188.462459 -411.616147) (xy 188.516416 -411.630253)
			(xy 188.567745 -411.652065) (xy 188.615351 -411.681119) (xy 188.658219 -411.716794) (xy 188.695436 -411.758331)
			(xy 188.726209 -411.804844) (xy 188.749881 -411.855341) (xy 188.765949 -411.908748) (xy 188.774069 -411.963924)
			(xy 188.774578 -411.99181) (xy 188.774069 -412.019696) (xy 188.765949 -412.074872) (xy 188.749881 -412.128279)
			(xy 188.726209 -412.178776) (xy 188.695436 -412.225289) (xy 188.658219 -412.266826) (xy 188.615351 -412.302501)
			(xy 188.567745 -412.331555) (xy 188.516416 -412.353367) (xy 188.462459 -412.367473) (xy 188.407022 -412.373573)
			(xy 188.351288 -412.371536) (xy 188.296445 -412.361406) (xy 188.243661 -412.343399) (xy 188.194061 -412.317898)
			(xy 188.148703 -412.285447) (xy 188.108554 -412.246738) (xy 188.074468 -412.202595) (xy 188.047172 -412.15396)
			(xy 188.027249 -412.101869) (xy 188.015123 -412.047432) (xy 188.011052 -411.99181) (xy 177.985708 -411.99181)
			(xy 177.987115 -411.997177) (xy 177.995081 -412.05896) (xy 177.99558 -412.090108) (xy 177.995081 -412.121256)
			(xy 177.987115 -412.183039) (xy 177.971314 -412.243297) (xy 177.947936 -412.30104) (xy 177.917367 -412.355319)
			(xy 177.880107 -412.405243) (xy 177.83677 -412.449993) (xy 177.788065 -412.488833) (xy 177.734794 -412.521126)
			(xy 177.677831 -412.546343) (xy 177.61811 -412.564067) (xy 177.556613 -412.57401) (xy 177.49435 -412.576006)
			(xy 177.432343 -412.570024) (xy 177.371609 -412.556162) (xy 177.313147 -412.534648) (xy 177.257916 -412.505834)
			(xy 177.206824 -412.470194) (xy 177.160708 -412.428313) (xy 177.120326 -412.380878) (xy 177.086342 -412.328669)
			(xy 177.059313 -412.272543) (xy 177.039684 -412.213422) (xy 177.027775 -412.152275) (xy 177.023784 -412.090108)
			(xy 173.595538 -412.090108) (xy 173.595039 -412.121256) (xy 173.587073 -412.183039) (xy 173.571272 -412.243297)
			(xy 173.547894 -412.30104) (xy 173.517325 -412.355319) (xy 173.480065 -412.405243) (xy 173.436728 -412.449993)
			(xy 173.388023 -412.488833) (xy 173.334752 -412.521126) (xy 173.277789 -412.546343) (xy 173.218068 -412.564067)
			(xy 173.156571 -412.57401) (xy 173.094308 -412.576006) (xy 173.032301 -412.570024) (xy 172.971567 -412.556162)
			(xy 172.913105 -412.534648) (xy 172.857874 -412.505834) (xy 172.806782 -412.470194) (xy 172.760666 -412.428313)
			(xy 172.720284 -412.380878) (xy 172.6863 -412.328669) (xy 172.659271 -412.272543) (xy 172.639642 -412.213422)
			(xy 172.627733 -412.152275) (xy 172.623742 -412.090108) (xy 169.19575 -412.090108) (xy 169.195251 -412.121256)
			(xy 169.187285 -412.183039) (xy 169.171484 -412.243297) (xy 169.148106 -412.30104) (xy 169.117537 -412.355319)
			(xy 169.080277 -412.405243) (xy 169.03694 -412.449993) (xy 168.988235 -412.488833) (xy 168.934964 -412.521126)
			(xy 168.878001 -412.546343) (xy 168.81828 -412.564067) (xy 168.756783 -412.57401) (xy 168.69452 -412.576006)
			(xy 168.632513 -412.570024) (xy 168.571779 -412.556162) (xy 168.513317 -412.534648) (xy 168.458086 -412.505834)
			(xy 168.406994 -412.470194) (xy 168.360878 -412.428313) (xy 168.320496 -412.380878) (xy 168.286512 -412.328669)
			(xy 168.259483 -412.272543) (xy 168.239854 -412.213422) (xy 168.227945 -412.152275) (xy 168.223954 -412.090108)
			(xy 164.795708 -412.090108) (xy 164.795209 -412.121256) (xy 164.787243 -412.183039) (xy 164.771442 -412.243297)
			(xy 164.748064 -412.30104) (xy 164.717495 -412.355319) (xy 164.680235 -412.405243) (xy 164.636898 -412.449993)
			(xy 164.588193 -412.488833) (xy 164.534922 -412.521126) (xy 164.477959 -412.546343) (xy 164.418238 -412.564067)
			(xy 164.356741 -412.57401) (xy 164.294478 -412.576006) (xy 164.232471 -412.570024) (xy 164.171737 -412.556162)
			(xy 164.113275 -412.534648) (xy 164.058044 -412.505834) (xy 164.006952 -412.470194) (xy 163.960836 -412.428313)
			(xy 163.920454 -412.380878) (xy 163.88647 -412.328669) (xy 163.859441 -412.272543) (xy 163.839812 -412.213422)
			(xy 163.827903 -412.152275) (xy 163.823912 -412.090108) (xy 160.395666 -412.090108) (xy 160.395167 -412.121256)
			(xy 160.387201 -412.183039) (xy 160.3714 -412.243297) (xy 160.348022 -412.30104) (xy 160.317453 -412.355319)
			(xy 160.280193 -412.405243) (xy 160.236856 -412.449993) (xy 160.188151 -412.488833) (xy 160.13488 -412.521126)
			(xy 160.077917 -412.546343) (xy 160.018196 -412.564067) (xy 159.956699 -412.57401) (xy 159.894436 -412.576006)
			(xy 159.832429 -412.570024) (xy 159.771695 -412.556162) (xy 159.713233 -412.534648) (xy 159.658002 -412.505834)
			(xy 159.60691 -412.470194) (xy 159.560794 -412.428313) (xy 159.520412 -412.380878) (xy 159.486428 -412.328669)
			(xy 159.459399 -412.272543) (xy 159.43977 -412.213422) (xy 159.427861 -412.152275) (xy 159.42387 -412.090108)
			(xy 154.57678 -412.090108) (xy 154.57678 -412.79191) (xy 184.936382 -412.79191) (xy 184.940453 -412.736288)
			(xy 184.952579 -412.681851) (xy 184.972502 -412.62976) (xy 184.999798 -412.581125) (xy 185.033884 -412.536982)
			(xy 185.074033 -412.498273) (xy 185.119391 -412.465822) (xy 185.168991 -412.440321) (xy 185.221775 -412.422314)
			(xy 185.276618 -412.412184) (xy 185.332352 -412.410147) (xy 185.387789 -412.416247) (xy 185.441746 -412.430353)
			(xy 185.493075 -412.452165) (xy 185.540681 -412.481219) (xy 185.583549 -412.516894) (xy 185.620766 -412.558431)
			(xy 185.651539 -412.604944) (xy 185.675211 -412.655441) (xy 185.691279 -412.708848) (xy 185.699399 -412.764024)
			(xy 185.699908 -412.79191) (xy 185.699399 -412.819796) (xy 185.691279 -412.874972) (xy 185.675211 -412.928379)
			(xy 185.651539 -412.978876) (xy 185.620766 -413.025389) (xy 185.583549 -413.066926) (xy 185.540681 -413.102601)
			(xy 185.493075 -413.131655) (xy 185.441746 -413.153467) (xy 185.387789 -413.167573) (xy 185.332352 -413.173673)
			(xy 185.276618 -413.171636) (xy 185.221775 -413.161506) (xy 185.168991 -413.143499) (xy 185.119391 -413.117998)
			(xy 185.074033 -413.085547) (xy 185.033884 -413.046838) (xy 184.999798 -413.002695) (xy 184.972502 -412.95406)
			(xy 184.952579 -412.901969) (xy 184.940453 -412.847532) (xy 184.936382 -412.79191) (xy 154.57678 -412.79191)
			(xy 154.57678 -413.479234) (xy 188.424056 -413.479234) (xy 188.428127 -413.423612) (xy 188.440253 -413.369175)
			(xy 188.460176 -413.317084) (xy 188.487472 -413.268449) (xy 188.521558 -413.224306) (xy 188.561707 -413.185597)
			(xy 188.607065 -413.153146) (xy 188.656665 -413.127645) (xy 188.709449 -413.109638) (xy 188.764292 -413.099508)
			(xy 188.820026 -413.097471) (xy 188.875463 -413.103571) (xy 188.92942 -413.117677) (xy 188.980749 -413.139489)
			(xy 189.028355 -413.168543) (xy 189.071223 -413.204218) (xy 189.10844 -413.245755) (xy 189.139213 -413.292268)
			(xy 189.162885 -413.342765) (xy 189.169325 -413.364172) (xy 197.320914 -413.364172) (xy 197.324985 -413.30855)
			(xy 197.337111 -413.254113) (xy 197.357034 -413.202022) (xy 197.38433 -413.153387) (xy 197.418416 -413.109244)
			(xy 197.458565 -413.070535) (xy 197.503923 -413.038084) (xy 197.553523 -413.012583) (xy 197.606307 -412.994576)
			(xy 197.66115 -412.984446) (xy 197.716884 -412.982409) (xy 197.772321 -412.988509) (xy 197.826278 -413.002615)
			(xy 197.877607 -413.024427) (xy 197.925213 -413.053481) (xy 197.968081 -413.089156) (xy 198.005298 -413.130693)
			(xy 198.036071 -413.177206) (xy 198.059743 -413.227703) (xy 198.075811 -413.28111) (xy 198.083931 -413.336286)
			(xy 198.08444 -413.364172) (xy 198.083931 -413.392058) (xy 198.075811 -413.447234) (xy 198.059743 -413.500641)
			(xy 198.036071 -413.551138) (xy 198.005298 -413.597651) (xy 197.968081 -413.639188) (xy 197.925213 -413.674863)
			(xy 197.877607 -413.703917) (xy 197.826278 -413.725729) (xy 197.772321 -413.739835) (xy 197.716884 -413.745935)
			(xy 197.66115 -413.743898) (xy 197.606307 -413.733768) (xy 197.553523 -413.715761) (xy 197.503923 -413.69026)
			(xy 197.458565 -413.657809) (xy 197.418416 -413.6191) (xy 197.38433 -413.574957) (xy 197.357034 -413.526322)
			(xy 197.337111 -413.474231) (xy 197.324985 -413.419794) (xy 197.320914 -413.364172) (xy 189.169325 -413.364172)
			(xy 189.178953 -413.396172) (xy 189.187073 -413.451348) (xy 189.187582 -413.479234) (xy 189.187073 -413.50712)
			(xy 189.178953 -413.562296) (xy 189.162885 -413.615703) (xy 189.139213 -413.6662) (xy 189.10844 -413.712713)
			(xy 189.071223 -413.75425) (xy 189.028355 -413.789925) (xy 188.980749 -413.818979) (xy 188.92942 -413.840791)
			(xy 188.875463 -413.854897) (xy 188.820026 -413.860997) (xy 188.764292 -413.85896) (xy 188.709449 -413.84883)
			(xy 188.656665 -413.830823) (xy 188.607065 -413.805322) (xy 188.561707 -413.772871) (xy 188.521558 -413.734162)
			(xy 188.487472 -413.690019) (xy 188.460176 -413.641384) (xy 188.440253 -413.589293) (xy 188.428127 -413.534856)
			(xy 188.424056 -413.479234) (xy 154.57678 -413.479234) (xy 154.57678 -415.15919) (xy 187.152532 -415.15919)
			(xy 187.156603 -415.103568) (xy 187.168729 -415.049131) (xy 187.188652 -414.99704) (xy 187.215948 -414.948405)
			(xy 187.250034 -414.904262) (xy 187.290183 -414.865553) (xy 187.335541 -414.833102) (xy 187.385141 -414.807601)
			(xy 187.437925 -414.789594) (xy 187.492768 -414.779464) (xy 187.548502 -414.777427) (xy 187.603939 -414.783527)
			(xy 187.657896 -414.797633) (xy 187.709225 -414.819445) (xy 187.756831 -414.848499) (xy 187.799699 -414.884174)
			(xy 187.836916 -414.925711) (xy 187.867689 -414.972224) (xy 187.891361 -415.022721) (xy 187.907429 -415.076128)
			(xy 187.915549 -415.131304) (xy 187.916058 -415.15919) (xy 187.915549 -415.187076) (xy 187.907429 -415.242252)
			(xy 187.891361 -415.295659) (xy 187.867689 -415.346156) (xy 187.836916 -415.392669) (xy 187.799699 -415.434206)
			(xy 187.756831 -415.469881) (xy 187.709225 -415.498935) (xy 187.657896 -415.520747) (xy 187.603939 -415.534853)
			(xy 187.548502 -415.540953) (xy 187.492768 -415.538916) (xy 187.437925 -415.528786) (xy 187.385141 -415.510779)
			(xy 187.335541 -415.485278) (xy 187.290183 -415.452827) (xy 187.250034 -415.414118) (xy 187.215948 -415.369975)
			(xy 187.188652 -415.32134) (xy 187.168729 -415.269249) (xy 187.156603 -415.214812) (xy 187.152532 -415.15919)
			(xy 154.57678 -415.15919) (xy 154.57678 -416.298634) (xy 154.577242 -416.30851) (xy 154.584687 -416.326807)
			(xy 154.591258 -416.334194) (xy 154.993086 -416.736022) (xy 155.000485 -416.742863) (xy 155.019085 -416.750579)
			(xy 155.029154 -416.751008) (xy 200.490836 -416.751008) (xy 200.499218 -416.750246) (xy 200.506823 -416.748731)
			(xy 200.520657 -416.741745) (xy 200.526396 -416.73653) (xy 201.279506 -415.98342) (xy 201.286904 -415.976572)
			(xy 201.305502 -415.968837) (xy 201.315574 -415.968434) (xy 272.419318 -415.968434) (xy 272.429385 -415.968006)
			(xy 272.447979 -415.960279) (xy 272.455386 -415.953448) (xy 272.766282 -415.642552) (xy 272.76679 -415.642044)
			(xy 272.773368 -415.634661) (xy 272.780811 -415.616362) (xy 272.781268 -415.606484) (xy 272.781268 -385.807712)
			(xy 272.781688 -385.79764) (xy 272.789396 -385.77903) (xy 272.796254 -385.771644) (xy 275.058632 -383.509266)
			(xy 275.066029 -383.502417) (xy 275.084628 -383.494684) (xy 275.0947 -383.49428) (xy 281.78379 -383.49428)
			(xy 281.793861 -383.494701) (xy 281.81247 -383.50241) (xy 281.819858 -383.509266) (xy 283.286962 -384.97637)
			(xy 283.293802 -384.98377) (xy 283.301516 -385.002369) (xy 283.301948 -385.012438) (xy 283.301948 -385.98983)
			(xy 318.109598 -385.98983) (xy 318.113669 -385.934208) (xy 318.125795 -385.879771) (xy 318.145718 -385.82768)
			(xy 318.173014 -385.779045) (xy 318.2071 -385.734902) (xy 318.247249 -385.696193) (xy 318.292607 -385.663742)
			(xy 318.342207 -385.638241) (xy 318.394991 -385.620234) (xy 318.449834 -385.610104) (xy 318.505568 -385.608067)
			(xy 318.561005 -385.614167) (xy 318.614962 -385.628273) (xy 318.666291 -385.650085) (xy 318.713897 -385.679139)
			(xy 318.756765 -385.714814) (xy 318.793982 -385.756351) (xy 318.824755 -385.802864) (xy 318.848427 -385.853361)
			(xy 318.864495 -385.906768) (xy 318.872615 -385.961944) (xy 318.873124 -385.98983) (xy 318.872615 -386.017716)
			(xy 318.864495 -386.072892) (xy 318.848427 -386.126299) (xy 318.824755 -386.176796) (xy 318.793982 -386.223309)
			(xy 318.756765 -386.264846) (xy 318.713897 -386.300521) (xy 318.666291 -386.329575) (xy 318.614962 -386.351387)
			(xy 318.561005 -386.365493) (xy 318.505568 -386.371593) (xy 318.449834 -386.369556) (xy 318.394991 -386.359426)
			(xy 318.342207 -386.341419) (xy 318.292607 -386.315918) (xy 318.247249 -386.283467) (xy 318.2071 -386.244758)
			(xy 318.173014 -386.200615) (xy 318.145718 -386.15198) (xy 318.125795 -386.099889) (xy 318.113669 -386.045452)
			(xy 318.109598 -385.98983) (xy 283.301948 -385.98983) (xy 283.301948 -388.06247) (xy 317.091058 -388.06247)
			(xy 317.095129 -388.006848) (xy 317.107255 -387.952411) (xy 317.127178 -387.90032) (xy 317.154474 -387.851685)
			(xy 317.18856 -387.807542) (xy 317.228709 -387.768833) (xy 317.274067 -387.736382) (xy 317.323667 -387.710881)
			(xy 317.376451 -387.692874) (xy 317.431294 -387.682744) (xy 317.487028 -387.680707) (xy 317.542465 -387.686807)
			(xy 317.596422 -387.700913) (xy 317.647751 -387.722725) (xy 317.695357 -387.751779) (xy 317.738225 -387.787454)
			(xy 317.775442 -387.828991) (xy 317.806215 -387.875504) (xy 317.829887 -387.926001) (xy 317.834952 -387.942836)
			(xy 320.392296 -387.942836) (xy 320.396367 -387.887214) (xy 320.408493 -387.832777) (xy 320.428416 -387.780686)
			(xy 320.455712 -387.732051) (xy 320.489798 -387.687908) (xy 320.529947 -387.649199) (xy 320.575305 -387.616748)
			(xy 320.624905 -387.591247) (xy 320.677689 -387.57324) (xy 320.732532 -387.56311) (xy 320.788266 -387.561073)
			(xy 320.843703 -387.567173) (xy 320.89766 -387.581279) (xy 320.948989 -387.603091) (xy 320.996595 -387.632145)
			(xy 321.039463 -387.66782) (xy 321.07668 -387.709357) (xy 321.107453 -387.75587) (xy 321.131125 -387.806367)
			(xy 321.147193 -387.859774) (xy 321.155313 -387.91495) (xy 321.155822 -387.942836) (xy 321.155313 -387.970722)
			(xy 321.147193 -388.025898) (xy 321.131125 -388.079305) (xy 321.107453 -388.129802) (xy 321.07668 -388.176315)
			(xy 321.039463 -388.217852) (xy 320.996595 -388.253527) (xy 320.948989 -388.282581) (xy 320.89766 -388.304393)
			(xy 320.843703 -388.318499) (xy 320.788266 -388.324599) (xy 320.732532 -388.322562) (xy 320.677689 -388.312432)
			(xy 320.624905 -388.294425) (xy 320.575305 -388.268924) (xy 320.529947 -388.236473) (xy 320.489798 -388.197764)
			(xy 320.455712 -388.153621) (xy 320.428416 -388.104986) (xy 320.408493 -388.052895) (xy 320.396367 -387.998458)
			(xy 320.392296 -387.942836) (xy 317.834952 -387.942836) (xy 317.845955 -387.979408) (xy 317.854075 -388.034584)
			(xy 317.854584 -388.06247) (xy 317.854075 -388.090356) (xy 317.845955 -388.145532) (xy 317.829887 -388.198939)
			(xy 317.806215 -388.249436) (xy 317.775442 -388.295949) (xy 317.738225 -388.337486) (xy 317.695357 -388.373161)
			(xy 317.647751 -388.402215) (xy 317.596422 -388.424027) (xy 317.542465 -388.438133) (xy 317.487028 -388.444233)
			(xy 317.431294 -388.442196) (xy 317.376451 -388.432066) (xy 317.323667 -388.414059) (xy 317.274067 -388.388558)
			(xy 317.228709 -388.356107) (xy 317.18856 -388.317398) (xy 317.154474 -388.273255) (xy 317.127178 -388.22462)
			(xy 317.107255 -388.172529) (xy 317.095129 -388.118092) (xy 317.091058 -388.06247) (xy 283.301948 -388.06247)
			(xy 283.301948 -388.958836) (xy 318.203832 -388.958836) (xy 318.207903 -388.903214) (xy 318.220029 -388.848777)
			(xy 318.239952 -388.796686) (xy 318.267248 -388.748051) (xy 318.301334 -388.703908) (xy 318.341483 -388.665199)
			(xy 318.386841 -388.632748) (xy 318.436441 -388.607247) (xy 318.489225 -388.58924) (xy 318.544068 -388.57911)
			(xy 318.599802 -388.577073) (xy 318.655239 -388.583173) (xy 318.709196 -388.597279) (xy 318.760525 -388.619091)
			(xy 318.808131 -388.648145) (xy 318.850999 -388.68382) (xy 318.888216 -388.725357) (xy 318.918989 -388.77187)
			(xy 318.942661 -388.822367) (xy 318.958729 -388.875774) (xy 318.966849 -388.93095) (xy 318.967358 -388.958836)
			(xy 321.520564 -388.958836) (xy 321.524635 -388.903214) (xy 321.536761 -388.848777) (xy 321.556684 -388.796686)
			(xy 321.58398 -388.748051) (xy 321.618066 -388.703908) (xy 321.658215 -388.665199) (xy 321.703573 -388.632748)
			(xy 321.753173 -388.607247) (xy 321.805957 -388.58924) (xy 321.8608 -388.57911) (xy 321.916534 -388.577073)
			(xy 321.971971 -388.583173) (xy 322.025928 -388.597279) (xy 322.077257 -388.619091) (xy 322.124863 -388.648145)
			(xy 322.167731 -388.68382) (xy 322.204948 -388.725357) (xy 322.235721 -388.77187) (xy 322.259393 -388.822367)
			(xy 322.275461 -388.875774) (xy 322.283581 -388.93095) (xy 322.28409 -388.958836) (xy 322.283581 -388.986722)
			(xy 322.275461 -389.041898) (xy 322.259393 -389.095305) (xy 322.235721 -389.145802) (xy 322.204948 -389.192315)
			(xy 322.167731 -389.233852) (xy 322.124863 -389.269527) (xy 322.077257 -389.298581) (xy 322.025928 -389.320393)
			(xy 321.971971 -389.334499) (xy 321.916534 -389.340599) (xy 321.8608 -389.338562) (xy 321.805957 -389.328432)
			(xy 321.753173 -389.310425) (xy 321.703573 -389.284924) (xy 321.658215 -389.252473) (xy 321.618066 -389.213764)
			(xy 321.58398 -389.169621) (xy 321.556684 -389.120986) (xy 321.536761 -389.068895) (xy 321.524635 -389.014458)
			(xy 321.520564 -388.958836) (xy 318.967358 -388.958836) (xy 318.966849 -388.986722) (xy 318.958729 -389.041898)
			(xy 318.942661 -389.095305) (xy 318.918989 -389.145802) (xy 318.888216 -389.192315) (xy 318.850999 -389.233852)
			(xy 318.808131 -389.269527) (xy 318.760525 -389.298581) (xy 318.709196 -389.320393) (xy 318.655239 -389.334499)
			(xy 318.599802 -389.340599) (xy 318.544068 -389.338562) (xy 318.489225 -389.328432) (xy 318.436441 -389.310425)
			(xy 318.386841 -389.284924) (xy 318.341483 -389.252473) (xy 318.301334 -389.213764) (xy 318.267248 -389.169621)
			(xy 318.239952 -389.120986) (xy 318.220029 -389.068895) (xy 318.207903 -389.014458) (xy 318.203832 -388.958836)
			(xy 283.301948 -388.958836) (xy 283.301948 -389.974836) (xy 317.228218 -389.974836) (xy 317.232289 -389.919214)
			(xy 317.244415 -389.864777) (xy 317.264338 -389.812686) (xy 317.291634 -389.764051) (xy 317.32572 -389.719908)
			(xy 317.365869 -389.681199) (xy 317.411227 -389.648748) (xy 317.460827 -389.623247) (xy 317.513611 -389.60524)
			(xy 317.568454 -389.59511) (xy 317.624188 -389.593073) (xy 317.679625 -389.599173) (xy 317.733582 -389.613279)
			(xy 317.784911 -389.635091) (xy 317.832517 -389.664145) (xy 317.875385 -389.69982) (xy 317.912602 -389.741357)
			(xy 317.943375 -389.78787) (xy 317.967047 -389.838367) (xy 317.983115 -389.891774) (xy 317.991235 -389.94695)
			(xy 317.991744 -389.974836) (xy 320.392296 -389.974836) (xy 320.396367 -389.919214) (xy 320.408493 -389.864777)
			(xy 320.428416 -389.812686) (xy 320.455712 -389.764051) (xy 320.489798 -389.719908) (xy 320.529947 -389.681199)
			(xy 320.575305 -389.648748) (xy 320.624905 -389.623247) (xy 320.677689 -389.60524) (xy 320.732532 -389.59511)
			(xy 320.788266 -389.593073) (xy 320.843703 -389.599173) (xy 320.89766 -389.613279) (xy 320.948989 -389.635091)
			(xy 320.996595 -389.664145) (xy 321.039463 -389.69982) (xy 321.07668 -389.741357) (xy 321.107453 -389.78787)
			(xy 321.131125 -389.838367) (xy 321.147193 -389.891774) (xy 321.155313 -389.94695) (xy 321.155822 -389.974836)
			(xy 321.155313 -390.002722) (xy 321.147193 -390.057898) (xy 321.131125 -390.111305) (xy 321.107453 -390.161802)
			(xy 321.07668 -390.208315) (xy 321.039463 -390.249852) (xy 320.996595 -390.285527) (xy 320.948989 -390.314581)
			(xy 320.89766 -390.336393) (xy 320.843703 -390.350499) (xy 320.788266 -390.356599) (xy 320.732532 -390.354562)
			(xy 320.677689 -390.344432) (xy 320.624905 -390.326425) (xy 320.575305 -390.300924) (xy 320.529947 -390.268473)
			(xy 320.489798 -390.229764) (xy 320.455712 -390.185621) (xy 320.428416 -390.136986) (xy 320.408493 -390.084895)
			(xy 320.396367 -390.030458) (xy 320.392296 -389.974836) (xy 317.991744 -389.974836) (xy 317.991235 -390.002722)
			(xy 317.983115 -390.057898) (xy 317.967047 -390.111305) (xy 317.943375 -390.161802) (xy 317.912602 -390.208315)
			(xy 317.875385 -390.249852) (xy 317.832517 -390.285527) (xy 317.784911 -390.314581) (xy 317.733582 -390.336393)
			(xy 317.679625 -390.350499) (xy 317.624188 -390.356599) (xy 317.568454 -390.354562) (xy 317.513611 -390.344432)
			(xy 317.460827 -390.326425) (xy 317.411227 -390.300924) (xy 317.365869 -390.268473) (xy 317.32572 -390.229764)
			(xy 317.291634 -390.185621) (xy 317.264338 -390.136986) (xy 317.244415 -390.084895) (xy 317.232289 -390.030458)
			(xy 317.228218 -389.974836) (xy 283.301948 -389.974836) (xy 283.301948 -390.990836) (xy 318.203832 -390.990836)
			(xy 318.207903 -390.935214) (xy 318.220029 -390.880777) (xy 318.239952 -390.828686) (xy 318.267248 -390.780051)
			(xy 318.301334 -390.735908) (xy 318.341483 -390.697199) (xy 318.386841 -390.664748) (xy 318.436441 -390.639247)
			(xy 318.489225 -390.62124) (xy 318.544068 -390.61111) (xy 318.599802 -390.609073) (xy 318.655239 -390.615173)
			(xy 318.709196 -390.629279) (xy 318.760525 -390.651091) (xy 318.808131 -390.680145) (xy 318.850999 -390.71582)
			(xy 318.888216 -390.757357) (xy 318.918989 -390.80387) (xy 318.942661 -390.854367) (xy 318.958729 -390.907774)
			(xy 318.966849 -390.96295) (xy 318.967358 -390.990836) (xy 321.482464 -390.990836) (xy 321.486535 -390.935214)
			(xy 321.498661 -390.880777) (xy 321.518584 -390.828686) (xy 321.54588 -390.780051) (xy 321.579966 -390.735908)
			(xy 321.620115 -390.697199) (xy 321.665473 -390.664748) (xy 321.715073 -390.639247) (xy 321.767857 -390.62124)
			(xy 321.8227 -390.61111) (xy 321.878434 -390.609073) (xy 321.933871 -390.615173) (xy 321.987828 -390.629279)
			(xy 322.039157 -390.651091) (xy 322.086763 -390.680145) (xy 322.129631 -390.71582) (xy 322.166848 -390.757357)
			(xy 322.197621 -390.80387) (xy 322.221293 -390.854367) (xy 322.237361 -390.907774) (xy 322.245481 -390.96295)
			(xy 322.24599 -390.990836) (xy 322.245481 -391.018722) (xy 322.237361 -391.073898) (xy 322.221293 -391.127305)
			(xy 322.197621 -391.177802) (xy 322.166848 -391.224315) (xy 322.129631 -391.265852) (xy 322.086763 -391.301527)
			(xy 322.039157 -391.330581) (xy 321.987828 -391.352393) (xy 321.933871 -391.366499) (xy 321.878434 -391.372599)
			(xy 321.8227 -391.370562) (xy 321.767857 -391.360432) (xy 321.715073 -391.342425) (xy 321.665473 -391.316924)
			(xy 321.620115 -391.284473) (xy 321.579966 -391.245764) (xy 321.54588 -391.201621) (xy 321.518584 -391.152986)
			(xy 321.498661 -391.100895) (xy 321.486535 -391.046458) (xy 321.482464 -390.990836) (xy 318.967358 -390.990836)
			(xy 318.966849 -391.018722) (xy 318.958729 -391.073898) (xy 318.942661 -391.127305) (xy 318.918989 -391.177802)
			(xy 318.888216 -391.224315) (xy 318.850999 -391.265852) (xy 318.808131 -391.301527) (xy 318.760525 -391.330581)
			(xy 318.709196 -391.352393) (xy 318.655239 -391.366499) (xy 318.599802 -391.372599) (xy 318.544068 -391.370562)
			(xy 318.489225 -391.360432) (xy 318.436441 -391.342425) (xy 318.386841 -391.316924) (xy 318.341483 -391.284473)
			(xy 318.301334 -391.245764) (xy 318.267248 -391.201621) (xy 318.239952 -391.152986) (xy 318.220029 -391.100895)
			(xy 318.207903 -391.046458) (xy 318.203832 -390.990836) (xy 283.301948 -390.990836) (xy 283.301948 -397.822891)
			(xy 287.004757 -397.822891) (xy 287.004762 -397.757444) (xy 287.01356 -397.692592) (xy 287.030993 -397.629511)
			(xy 287.056745 -397.569344) (xy 287.073086 -397.540988) (xy 287.076449 -397.534972) (xy 287.080186 -397.521713)
			(xy 287.080452 -397.514826) (xy 287.080452 -396.765526) (xy 287.080237 -396.758632) (xy 287.076496 -396.74536)
			(xy 287.073086 -396.739364) (xy 287.056739 -396.711013) (xy 287.030993 -396.650846) (xy 287.013566 -396.587764)
			(xy 287.004773 -396.522914) (xy 287.004774 -396.457469) (xy 287.013569 -396.392619) (xy 287.030999 -396.329538)
			(xy 287.056746 -396.269372) (xy 287.073086 -396.241016) (xy 287.07644 -396.234996) (xy 287.080183 -396.22174)
			(xy 287.080452 -396.214854) (xy 287.080452 -395.92885) (xy 287.080968 -395.918725) (xy 287.088682 -395.900003)
			(xy 287.102959 -395.885644) (xy 287.121638 -395.877825) (xy 287.13176 -395.877288) (xy 287.84804 -395.877288)
			(xy 287.858195 -395.877689) (xy 287.876946 -395.885495) (xy 287.891268 -395.899898) (xy 287.898968 -395.918693)
			(xy 287.899348 -395.92885) (xy 287.899348 -396.214854) (xy 287.899571 -396.221748) (xy 287.903306 -396.23502)
			(xy 287.906714 -396.241016) (xy 287.923044 -396.269376) (xy 287.948792 -396.329542) (xy 287.966221 -396.392621)
			(xy 287.975015 -396.45747) (xy 287.975017 -396.522913) (xy 287.966224 -396.587762) (xy 287.948797 -396.650842)
			(xy 287.923052 -396.711008) (xy 287.906714 -396.739364) (xy 287.903367 -396.745388) (xy 287.89962 -396.758641)
			(xy 287.899348 -396.765526) (xy 287.899348 -397.514826) (xy 287.899581 -397.521719) (xy 287.903309 -397.534991)
			(xy 287.906714 -397.540988) (xy 287.916082 -397.557287) (xy 289.204678 -397.557287) (xy 289.213471 -397.492438)
			(xy 289.230897 -397.429358) (xy 289.256642 -397.369192) (xy 289.27298 -397.340836) (xy 289.276281 -397.334804)
			(xy 289.279896 -397.321546) (xy 289.280092 -397.314674) (xy 289.280092 -397.028924) (xy 289.280541 -397.018772)
			(xy 289.288327 -397.000022) (xy 289.302715 -396.985698) (xy 289.321501 -396.977996) (xy 289.331654 -396.977616)
			(xy 290.047934 -396.977616) (xy 290.05806 -396.978098) (xy 290.076777 -396.985832) (xy 290.091132 -397.00012)
			(xy 290.098954 -397.0188) (xy 290.099496 -397.028924) (xy 290.099496 -397.314674) (xy 290.099698 -397.321546)
			(xy 290.103299 -397.334809) (xy 290.106608 -397.340836) (xy 290.122956 -397.369187) (xy 290.148701 -397.429354)
			(xy 290.166129 -397.492435) (xy 290.174922 -397.557286) (xy 290.174921 -397.622731) (xy 290.166125 -397.687581)
			(xy 290.148696 -397.750662) (xy 290.122948 -397.810828) (xy 290.115997 -397.82289) (xy 291.404807 -397.82289)
			(xy 291.404812 -397.757445) (xy 291.413609 -397.692593) (xy 291.43104 -397.629512) (xy 291.456788 -397.569344)
			(xy 291.473128 -397.540988) (xy 291.476449 -397.534966) (xy 291.48005 -397.5217) (xy 291.48024 -397.514826)
			(xy 291.48024 -396.765526) (xy 291.480033 -396.758654) (xy 291.476435 -396.745391) (xy 291.473128 -396.739364)
			(xy 291.456782 -396.711012) (xy 291.43104 -396.650845) (xy 291.413615 -396.587763) (xy 291.404823 -396.522913)
			(xy 291.404824 -396.45747) (xy 291.413618 -396.39262) (xy 291.431046 -396.329539) (xy 291.45679 -396.269372)
			(xy 291.473128 -396.241016) (xy 291.476439 -396.23499) (xy 291.480047 -396.221727) (xy 291.48024 -396.214854)
			(xy 291.48024 -395.92885) (xy 291.480705 -395.918681) (xy 291.488474 -395.899887) (xy 291.502847 -395.885501)
			(xy 291.521634 -395.877714) (xy 291.531802 -395.877288) (xy 292.248082 -395.877288) (xy 292.258259 -395.87768)
			(xy 292.277063 -395.885468) (xy 292.29145 -395.899864) (xy 292.299227 -395.918673) (xy 292.299644 -395.92885)
			(xy 292.299644 -396.214854) (xy 292.299848 -396.221726) (xy 292.303447 -396.234989) (xy 292.306756 -396.241016)
			(xy 292.323085 -396.269377) (xy 292.34883 -396.329542) (xy 292.366258 -396.392622) (xy 292.375052 -396.45747)
			(xy 292.375053 -396.522913) (xy 292.366261 -396.587762) (xy 292.348836 -396.650841) (xy 292.323093 -396.711008)
			(xy 292.306756 -396.739364) (xy 292.303458 -396.745397) (xy 292.299841 -396.758654) (xy 292.299644 -396.765526)
			(xy 292.299644 -397.514826) (xy 292.299821 -397.5217) (xy 292.303439 -397.534963) (xy 292.306756 -397.540988)
			(xy 292.316123 -397.557288) (xy 293.604728 -397.557288) (xy 293.61352 -397.492439) (xy 293.630944 -397.429359)
			(xy 293.656686 -397.369192) (xy 293.673022 -397.340836) (xy 293.676371 -397.334813) (xy 293.680117 -397.321559)
			(xy 293.680388 -397.314674) (xy 293.680388 -397.028924) (xy 293.680835 -397.018805) (xy 293.688573 -397.000104)
			(xy 293.70288 -396.985789) (xy 293.721577 -396.978041) (xy 293.731696 -396.977616) (xy 294.447976 -396.977616)
			(xy 294.458099 -396.978036) (xy 294.476805 -396.985779) (xy 294.491121 -397.000095) (xy 294.498864 -397.018801)
			(xy 294.499284 -397.028924) (xy 294.499284 -397.314674) (xy 294.499494 -397.321569) (xy 294.503238 -397.334841)
			(xy 294.50665 -397.340836) (xy 294.522996 -397.369187) (xy 294.54874 -397.429355) (xy 294.566166 -397.492436)
			(xy 294.574958 -397.557287) (xy 294.574957 -397.62273) (xy 294.566162 -397.687581) (xy 294.548734 -397.750661)
			(xy 294.522988 -397.810828) (xy 294.516038 -397.82289) (xy 295.804843 -397.82289) (xy 295.804848 -397.757444)
			(xy 295.813646 -397.692593) (xy 295.831079 -397.629511) (xy 295.856829 -397.569344) (xy 295.87317 -397.540988)
			(xy 295.87654 -397.534976) (xy 295.880272 -397.521713) (xy 295.880536 -397.514826) (xy 295.880536 -396.765526)
			(xy 295.880323 -396.758632) (xy 295.876581 -396.74536) (xy 295.87317 -396.739364) (xy 295.856823 -396.711013)
			(xy 295.831078 -396.650845) (xy 295.813652 -396.587764) (xy 295.804859 -396.522913) (xy 295.80486 -396.457469)
			(xy 295.813655 -396.392619) (xy 295.831084 -396.329538) (xy 295.856831 -396.269372) (xy 295.87317 -396.241016)
			(xy 295.87653 -396.234999) (xy 295.880268 -396.22174) (xy 295.880536 -396.214854) (xy 295.880536 -395.92885)
			(xy 295.881067 -395.918727) (xy 295.888778 -395.900008) (xy 295.903051 -395.88565) (xy 295.921724 -395.877828)
			(xy 295.931844 -395.877288) (xy 296.648124 -395.877288) (xy 296.658278 -395.877702) (xy 296.677029 -395.885503)
			(xy 296.691351 -395.899902) (xy 296.699052 -395.918694) (xy 296.699432 -395.92885) (xy 296.699432 -396.214854)
			(xy 296.699657 -396.221747) (xy 296.703391 -396.235019) (xy 296.706798 -396.241016) (xy 296.723126 -396.269377)
			(xy 296.748868 -396.329543) (xy 296.766294 -396.392622) (xy 296.775088 -396.457471) (xy 296.775089 -396.522912)
			(xy 296.766298 -396.587761) (xy 296.748874 -396.650841) (xy 296.723134 -396.711007) (xy 296.706798 -396.739364)
			(xy 296.70345 -396.745387) (xy 296.699704 -396.758641) (xy 296.699432 -396.765526) (xy 296.699432 -397.514826)
			(xy 296.699668 -397.521719) (xy 296.703394 -397.534991) (xy 296.706798 -397.540988) (xy 296.716164 -397.557287)
			(xy 298.004764 -397.557287) (xy 298.013557 -397.492438) (xy 298.030983 -397.429358) (xy 298.056727 -397.369192)
			(xy 298.073064 -397.340836) (xy 298.076363 -397.334804) (xy 298.079979 -397.321546) (xy 298.080176 -397.314674)
			(xy 298.080176 -397.028924) (xy 298.080641 -397.018774) (xy 298.088424 -397.000027) (xy 298.102807 -396.985704)
			(xy 298.121587 -396.977999) (xy 298.131738 -396.977616) (xy 298.848018 -396.977616) (xy 298.858143 -396.978111)
			(xy 298.87686 -396.98584) (xy 298.891215 -397.000123) (xy 298.899038 -397.018802) (xy 298.89958 -397.028924)
			(xy 298.89958 -397.314674) (xy 298.899784 -397.321546) (xy 298.903384 -397.334809) (xy 298.906692 -397.340836)
			(xy 298.923037 -397.369188) (xy 298.948778 -397.429356) (xy 298.966203 -397.492437) (xy 298.974994 -397.557287)
			(xy 298.974993 -397.62273) (xy 298.966199 -397.68758) (xy 298.948773 -397.75066) (xy 298.923029 -397.810827)
			(xy 298.916079 -397.82289) (xy 300.204633 -397.82289) (xy 300.204637 -397.757445) (xy 300.213435 -397.692593)
			(xy 300.230868 -397.629511) (xy 300.256617 -397.569344) (xy 300.272958 -397.540988) (xy 300.276327 -397.534975)
			(xy 300.28006 -397.521713) (xy 300.280324 -397.514826) (xy 300.280324 -396.765526) (xy 300.280113 -396.758631)
			(xy 300.27637 -396.745359) (xy 300.272958 -396.739364) (xy 300.256612 -396.711013) (xy 300.230867 -396.650845)
			(xy 300.213441 -396.587764) (xy 300.204649 -396.522913) (xy 300.20465 -396.457469) (xy 300.213445 -396.392619)
			(xy 300.230873 -396.329539) (xy 300.256619 -396.269372) (xy 300.272958 -396.241016) (xy 300.276317 -396.234999)
			(xy 300.280056 -396.22174) (xy 300.280324 -396.214854) (xy 300.280324 -395.92885) (xy 300.280867 -395.918728)
			(xy 300.288576 -395.900011) (xy 300.302845 -395.885654) (xy 300.321514 -395.87783) (xy 300.331632 -395.877288)
			(xy 301.047912 -395.877288) (xy 301.058065 -395.877711) (xy 301.076816 -395.885509) (xy 301.091138 -395.899904)
			(xy 301.09884 -395.918694) (xy 301.09922 -395.92885) (xy 301.09922 -396.214854) (xy 301.099468 -396.221744)
			(xy 301.1032 -396.23501) (xy 301.106586 -396.241016) (xy 301.122914 -396.269377) (xy 301.148657 -396.329543)
			(xy 301.166084 -396.392622) (xy 301.174877 -396.45747) (xy 301.174878 -396.49019) (xy 304.603666 -396.49019)
			(xy 304.607657 -396.428023) (xy 304.619566 -396.366876) (xy 304.639195 -396.307755) (xy 304.666224 -396.251629)
			(xy 304.700208 -396.19942) (xy 304.74059 -396.151985) (xy 304.786706 -396.110104) (xy 304.837798 -396.074464)
			(xy 304.893029 -396.04565) (xy 304.951491 -396.024136) (xy 305.012225 -396.010274) (xy 305.074232 -396.004292)
			(xy 305.136495 -396.006288) (xy 305.197992 -396.016231) (xy 305.257713 -396.033955) (xy 305.314676 -396.059172)
			(xy 305.367947 -396.091465) (xy 305.416652 -396.130305) (xy 305.459989 -396.175055) (xy 305.497249 -396.224979)
			(xy 305.527818 -396.279258) (xy 305.551196 -396.337001) (xy 305.566997 -396.397259) (xy 305.574963 -396.459042)
			(xy 305.575462 -396.49019) (xy 305.574963 -396.521338) (xy 305.566997 -396.583121) (xy 305.551196 -396.643379)
			(xy 305.527818 -396.701122) (xy 305.497249 -396.755401) (xy 305.459989 -396.805325) (xy 305.416652 -396.850075)
			(xy 305.367947 -396.888915) (xy 305.314676 -396.921208) (xy 305.257713 -396.946425) (xy 305.197992 -396.964149)
			(xy 305.136495 -396.974092) (xy 305.074232 -396.976088) (xy 305.012225 -396.970106) (xy 304.951491 -396.956244)
			(xy 304.893029 -396.93473) (xy 304.837798 -396.905916) (xy 304.786706 -396.870276) (xy 304.74059 -396.828395)
			(xy 304.700208 -396.78096) (xy 304.666224 -396.728751) (xy 304.639195 -396.672625) (xy 304.619566 -396.613504)
			(xy 304.607657 -396.552357) (xy 304.603666 -396.49019) (xy 301.174878 -396.49019) (xy 301.174879 -396.522912)
			(xy 301.166087 -396.587761) (xy 301.148663 -396.650841) (xy 301.122922 -396.711008) (xy 301.106586 -396.739364)
			(xy 301.103237 -396.745387) (xy 301.099492 -396.758641) (xy 301.09922 -396.765526) (xy 301.09922 -397.514826)
			(xy 301.099457 -397.521718) (xy 301.103183 -397.53499) (xy 301.106586 -397.540988) (xy 301.115952 -397.557288)
			(xy 302.404814 -397.557288) (xy 302.413606 -397.492439) (xy 302.43103 -397.429359) (xy 302.45677 -397.369193)
			(xy 302.473106 -397.340836) (xy 302.476454 -397.334813) (xy 302.4802 -397.321559) (xy 302.480472 -397.314674)
			(xy 302.480472 -397.028924) (xy 302.480935 -397.018806) (xy 302.48867 -397.000109) (xy 302.502972 -396.985795)
			(xy 302.521663 -396.978043) (xy 302.53178 -396.977616) (xy 303.24806 -396.977616) (xy 303.258182 -396.978049)
			(xy 303.276888 -396.985787) (xy 303.291204 -397.000099) (xy 303.298948 -397.018802) (xy 303.299368 -397.028924)
			(xy 303.299368 -397.314674) (xy 303.29958 -397.321568) (xy 303.303323 -397.334841) (xy 303.306734 -397.340836)
			(xy 303.323081 -397.369187) (xy 303.348825 -397.429355) (xy 303.366252 -397.492436) (xy 303.375044 -397.557287)
			(xy 303.375043 -397.622731) (xy 303.366248 -397.687581) (xy 303.34882 -397.750661) (xy 303.331917 -397.790162)
			(xy 304.603666 -397.790162) (xy 304.607657 -397.727995) (xy 304.619566 -397.666848) (xy 304.639195 -397.607727)
			(xy 304.666224 -397.551601) (xy 304.700208 -397.499392) (xy 304.74059 -397.451957) (xy 304.786706 -397.410076)
			(xy 304.837798 -397.374436) (xy 304.893029 -397.345622) (xy 304.951491 -397.324108) (xy 305.012225 -397.310246)
			(xy 305.074232 -397.304264) (xy 305.136495 -397.30626) (xy 305.197992 -397.316203) (xy 305.257713 -397.333927)
			(xy 305.314676 -397.359144) (xy 305.367947 -397.391437) (xy 305.416652 -397.430277) (xy 305.459989 -397.475027)
			(xy 305.497249 -397.524951) (xy 305.527818 -397.57923) (xy 305.532182 -397.59001) (xy 306.803814 -397.59001)
			(xy 306.807805 -397.527843) (xy 306.819714 -397.466696) (xy 306.839343 -397.407575) (xy 306.866372 -397.351449)
			(xy 306.900356 -397.29924) (xy 306.940738 -397.251805) (xy 306.986854 -397.209924) (xy 307.037946 -397.174284)
			(xy 307.093177 -397.14547) (xy 307.151639 -397.123956) (xy 307.212373 -397.110094) (xy 307.27438 -397.104112)
			(xy 307.336643 -397.106108) (xy 307.39814 -397.116051) (xy 307.457861 -397.133775) (xy 307.514824 -397.158992)
			(xy 307.568095 -397.191285) (xy 307.6168 -397.230125) (xy 307.660137 -397.274875) (xy 307.697397 -397.324799)
			(xy 307.727966 -397.379078) (xy 307.751344 -397.436821) (xy 307.767145 -397.497079) (xy 307.775111 -397.558862)
			(xy 307.77561 -397.59001) (xy 307.775111 -397.621158) (xy 307.767145 -397.682941) (xy 307.751344 -397.743199)
			(xy 307.727966 -397.800942) (xy 307.697397 -397.855221) (xy 307.660137 -397.905145) (xy 307.6168 -397.949895)
			(xy 307.568095 -397.988735) (xy 307.514824 -398.021028) (xy 307.457861 -398.046245) (xy 307.39814 -398.063969)
			(xy 307.336643 -398.073912) (xy 307.27438 -398.075908) (xy 307.212373 -398.069926) (xy 307.151639 -398.056064)
			(xy 307.093177 -398.03455) (xy 307.037946 -398.005736) (xy 306.986854 -397.970096) (xy 306.940738 -397.928215)
			(xy 306.900356 -397.88078) (xy 306.866372 -397.828571) (xy 306.839343 -397.772445) (xy 306.819714 -397.713324)
			(xy 306.807805 -397.652177) (xy 306.803814 -397.59001) (xy 305.532182 -397.59001) (xy 305.551196 -397.636973)
			(xy 305.566997 -397.697231) (xy 305.574963 -397.759014) (xy 305.575462 -397.790162) (xy 305.574963 -397.82131)
			(xy 305.566997 -397.883093) (xy 305.551196 -397.943351) (xy 305.527818 -398.001094) (xy 305.497249 -398.055373)
			(xy 305.459989 -398.105297) (xy 305.416652 -398.150047) (xy 305.367947 -398.188887) (xy 305.314676 -398.22118)
			(xy 305.257713 -398.246397) (xy 305.197992 -398.264121) (xy 305.136495 -398.274064) (xy 305.074232 -398.27606)
			(xy 305.012225 -398.270078) (xy 304.951491 -398.256216) (xy 304.893029 -398.234702) (xy 304.837798 -398.205888)
			(xy 304.786706 -398.170248) (xy 304.74059 -398.128367) (xy 304.700208 -398.080932) (xy 304.666224 -398.028723)
			(xy 304.639195 -397.972597) (xy 304.619566 -397.913476) (xy 304.607657 -397.852329) (xy 304.603666 -397.790162)
			(xy 303.331917 -397.790162) (xy 303.323073 -397.810828) (xy 303.306734 -397.839184) (xy 303.303374 -397.845201)
			(xy 303.299636 -397.85846) (xy 303.299368 -397.865346) (xy 303.299368 -398.6149) (xy 303.29957 -398.621795)
			(xy 303.303319 -398.635067) (xy 303.306734 -398.641062) (xy 303.323103 -398.669401) (xy 303.348845 -398.729571)
			(xy 303.366269 -398.792655) (xy 303.375059 -398.857508) (xy 303.375057 -398.890236) (xy 306.803814 -398.890236)
			(xy 306.807805 -398.828069) (xy 306.819714 -398.766922) (xy 306.839343 -398.707801) (xy 306.866372 -398.651675)
			(xy 306.900356 -398.599466) (xy 306.940738 -398.552031) (xy 306.986854 -398.51015) (xy 307.037946 -398.47451)
			(xy 307.093177 -398.445696) (xy 307.151639 -398.424182) (xy 307.212373 -398.41032) (xy 307.27438 -398.404338)
			(xy 307.336643 -398.406334) (xy 307.39814 -398.416277) (xy 307.457861 -398.434001) (xy 307.514824 -398.459218)
			(xy 307.568095 -398.491511) (xy 307.6168 -398.530351) (xy 307.660137 -398.575101) (xy 307.697397 -398.625025)
			(xy 307.727966 -398.679304) (xy 307.751344 -398.737047) (xy 307.767145 -398.797305) (xy 307.775111 -398.859088)
			(xy 307.77561 -398.890236) (xy 307.775111 -398.921384) (xy 307.767145 -398.983167) (xy 307.751344 -399.043425)
			(xy 307.727966 -399.101168) (xy 307.697397 -399.155447) (xy 307.660137 -399.205371) (xy 307.6168 -399.250121)
			(xy 307.568095 -399.288961) (xy 307.514824 -399.321254) (xy 307.457861 -399.346471) (xy 307.39814 -399.364195)
			(xy 307.336643 -399.374138) (xy 307.27438 -399.376134) (xy 307.212373 -399.370152) (xy 307.151639 -399.35629)
			(xy 307.093177 -399.334776) (xy 307.037946 -399.305962) (xy 306.986854 -399.270322) (xy 306.940738 -399.228441)
			(xy 306.900356 -399.181006) (xy 306.866372 -399.128797) (xy 306.839343 -399.072671) (xy 306.819714 -399.01355)
			(xy 306.807805 -398.952403) (xy 306.803814 -398.890236) (xy 303.375057 -398.890236) (xy 303.375055 -398.922954)
			(xy 303.366257 -398.987805) (xy 303.348825 -399.050887) (xy 303.323075 -399.111054) (xy 303.306734 -399.13941)
			(xy 303.303365 -399.145423) (xy 303.299633 -399.158685) (xy 303.299368 -399.165572) (xy 303.299368 -399.451576)
			(xy 303.298964 -399.461701) (xy 303.291218 -399.48041) (xy 303.276897 -399.494727) (xy 303.258185 -399.502467)
			(xy 303.24806 -399.502884) (xy 302.53178 -399.502884) (xy 302.521654 -399.5025) (xy 302.502947 -399.494742)
			(xy 302.488633 -399.480416) (xy 302.480891 -399.461702) (xy 302.480472 -399.451576) (xy 302.480472 -399.165572)
			(xy 302.480237 -399.158679) (xy 302.47651 -399.145408) (xy 302.473106 -399.13941) (xy 302.4568 -399.111037)
			(xy 302.431055 -399.050874) (xy 302.413627 -398.987797) (xy 302.40483 -398.922951) (xy 302.404826 -398.857511)
			(xy 302.413614 -398.792664) (xy 302.431035 -398.729585) (xy 302.456772 -398.669418) (xy 302.473106 -398.641062)
			(xy 302.47648 -398.635052) (xy 302.48021 -398.621788) (xy 302.480472 -398.6149) (xy 302.480472 -397.865346)
			(xy 302.480247 -397.858453) (xy 302.476513 -397.845181) (xy 302.473106 -397.839184) (xy 302.456778 -397.810823)
			(xy 302.431035 -397.750657) (xy 302.413609 -397.687578) (xy 302.404816 -397.622729) (xy 302.404814 -397.557288)
			(xy 301.115952 -397.557288) (xy 301.12289 -397.569362) (xy 301.148636 -397.629525) (xy 301.166065 -397.692601)
			(xy 301.174862 -397.757447) (xy 301.174866 -397.822887) (xy 301.166078 -397.887735) (xy 301.148658 -397.950813)
			(xy 301.12292 -398.01098) (xy 301.106586 -398.039336) (xy 301.103212 -398.045346) (xy 301.099482 -398.05861)
			(xy 301.09922 -398.065498) (xy 301.09922 -398.351502) (xy 301.098774 -398.361634) (xy 301.091038 -398.380362)
			(xy 301.076739 -398.39472) (xy 301.058042 -398.402532) (xy 301.047912 -398.403064) (xy 300.331632 -398.403064)
			(xy 300.321475 -398.402652) (xy 300.302717 -398.39486) (xy 300.288391 -398.38046) (xy 300.280696 -398.361661)
			(xy 300.280324 -398.351502) (xy 300.280324 -398.065498) (xy 300.280124 -398.058603) (xy 300.276373 -398.04533)
			(xy 300.272958 -398.039336) (xy 300.256588 -398.010998) (xy 300.230846 -397.950827) (xy 300.213422 -397.887743)
			(xy 300.204633 -397.82289) (xy 298.916079 -397.82289) (xy 298.906692 -397.839184) (xy 298.903382 -397.845211)
			(xy 298.899774 -397.858473) (xy 298.89958 -397.865346) (xy 298.89958 -398.6149) (xy 298.899774 -398.621773)
			(xy 298.903381 -398.635036) (xy 298.906692 -398.641062) (xy 298.923059 -398.669402) (xy 298.948798 -398.729573)
			(xy 298.96622 -398.792656) (xy 298.975009 -398.857508) (xy 298.975005 -398.922953) (xy 298.966208 -398.987805)
			(xy 298.948778 -399.050886) (xy 298.923031 -399.111053) (xy 298.906692 -399.13941) (xy 298.903373 -399.145433)
			(xy 298.89977 -399.158698) (xy 298.89958 -399.165572) (xy 298.89958 -399.451576) (xy 298.899159 -399.461731)
			(xy 298.891367 -399.480487) (xy 298.87697 -399.494812) (xy 298.858175 -399.502509) (xy 298.848018 -399.502884)
			(xy 298.131738 -399.502884) (xy 298.121617 -399.502343) (xy 298.102901 -399.494632) (xy 298.088544 -399.480362)
			(xy 298.08072 -399.461694) (xy 298.080176 -399.451576) (xy 298.080176 -399.165572) (xy 298.079998 -399.158698)
			(xy 298.076381 -399.145435) (xy 298.073064 -399.13941) (xy 298.056756 -399.111037) (xy 298.031008 -399.050875)
			(xy 298.013578 -398.987798) (xy 298.00478 -398.922951) (xy 298.004776 -398.85751) (xy 298.013565 -398.792663)
			(xy 298.030988 -398.729584) (xy 298.056728 -398.669418) (xy 298.073064 -398.641062) (xy 298.076389 -398.635042)
			(xy 298.079989 -398.621775) (xy 298.080176 -398.6149) (xy 298.080176 -397.865346) (xy 298.079969 -397.858474)
			(xy 298.076371 -397.845211) (xy 298.073064 -397.839184) (xy 298.056734 -397.810823) (xy 298.030988 -397.750658)
			(xy 298.01356 -397.687579) (xy 298.004766 -397.62273) (xy 298.004764 -397.557287) (xy 296.716164 -397.557287)
			(xy 296.723102 -397.569362) (xy 296.748847 -397.629525) (xy 296.766276 -397.692602) (xy 296.775072 -397.757447)
			(xy 296.775076 -397.822887) (xy 296.766289 -397.887735) (xy 296.748869 -397.950813) (xy 296.723132 -398.010979)
			(xy 296.706798 -398.039336) (xy 296.703425 -398.045347) (xy 296.699694 -398.05861) (xy 296.699432 -398.065498)
			(xy 296.699432 -398.351502) (xy 296.698974 -398.361632) (xy 296.691241 -398.380359) (xy 296.676945 -398.394716)
			(xy 296.658252 -398.40253) (xy 296.648124 -398.403064) (xy 295.931844 -398.403064) (xy 295.921688 -398.402642)
			(xy 295.90293 -398.394854) (xy 295.888604 -398.380456) (xy 295.880909 -398.36166) (xy 295.880536 -398.351502)
			(xy 295.880536 -398.065498) (xy 295.880334 -398.058603) (xy 295.876585 -398.045331) (xy 295.87317 -398.039336)
			(xy 295.856799 -398.010998) (xy 295.831057 -397.950827) (xy 295.813633 -397.887743) (xy 295.804843 -397.82289)
			(xy 294.516038 -397.82289) (xy 294.50665 -397.839184) (xy 294.503292 -397.845202) (xy 294.499553 -397.85846)
			(xy 294.499284 -397.865346) (xy 294.499284 -398.6149) (xy 294.499484 -398.621796) (xy 294.503234 -398.635068)
			(xy 294.50665 -398.641062) (xy 294.523018 -398.669401) (xy 294.54876 -398.729572) (xy 294.566183 -398.792655)
			(xy 294.574973 -398.857508) (xy 294.574969 -398.922954) (xy 294.566171 -398.987805) (xy 294.548739 -399.050887)
			(xy 294.52299 -399.111054) (xy 294.50665 -399.13941) (xy 294.503283 -399.145423) (xy 294.499549 -399.158685)
			(xy 294.499284 -399.165572) (xy 294.499284 -399.451576) (xy 294.498864 -399.461699) (xy 294.491121 -399.480405)
			(xy 294.476805 -399.494721) (xy 294.458099 -399.502464) (xy 294.447976 -399.502884) (xy 293.731696 -399.502884)
			(xy 293.721571 -399.502487) (xy 293.702865 -399.494734) (xy 293.68855 -399.480412) (xy 293.680808 -399.461701)
			(xy 293.680388 -399.451576) (xy 293.680388 -399.165572) (xy 293.680129 -399.158683) (xy 293.676404 -399.145417)
			(xy 293.673022 -399.13941) (xy 293.656716 -399.111037) (xy 293.63097 -399.050874) (xy 293.613541 -398.987797)
			(xy 293.604744 -398.922951) (xy 293.60474 -398.857511) (xy 293.613528 -398.792663) (xy 293.630949 -398.729585)
			(xy 293.656688 -398.669418) (xy 293.673022 -398.641062) (xy 293.676397 -398.635052) (xy 293.680126 -398.621788)
			(xy 293.680388 -398.6149) (xy 293.680388 -397.865346) (xy 293.680139 -397.858456) (xy 293.676408 -397.84519)
			(xy 293.673022 -397.839184) (xy 293.656694 -397.810823) (xy 293.63095 -397.750657) (xy 293.613523 -397.687578)
			(xy 293.604729 -397.62273) (xy 293.604728 -397.557288) (xy 292.316123 -397.557288) (xy 292.323061 -397.569362)
			(xy 292.348808 -397.629524) (xy 292.366239 -397.692601) (xy 292.375036 -397.757447) (xy 292.37504 -397.822888)
			(xy 292.366252 -397.887735) (xy 292.34883 -397.950814) (xy 292.323091 -398.01098) (xy 292.306756 -398.039336)
			(xy 292.303433 -398.045357) (xy 292.299832 -398.058623) (xy 292.299644 -398.065498) (xy 292.299644 -398.351502)
			(xy 292.299237 -398.361676) (xy 292.291448 -398.380474) (xy 292.277057 -398.39486) (xy 292.258256 -398.402641)
			(xy 292.248082 -398.403064) (xy 291.531802 -398.403064) (xy 291.521645 -398.402565) (xy 291.502876 -398.394792)
			(xy 291.488511 -398.380427) (xy 291.480736 -398.361659) (xy 291.48024 -398.351502) (xy 291.48024 -398.065498)
			(xy 291.480044 -398.058625) (xy 291.476438 -398.045363) (xy 291.473128 -398.039336) (xy 291.456759 -398.010997)
			(xy 291.431018 -397.950827) (xy 291.413596 -397.887743) (xy 291.404807 -397.82289) (xy 290.115997 -397.82289)
			(xy 290.106608 -397.839184) (xy 290.1033 -397.845212) (xy 290.09969 -397.858473) (xy 290.099496 -397.865346)
			(xy 290.099496 -398.6149) (xy 290.099688 -398.621773) (xy 290.103296 -398.635036) (xy 290.106608 -398.641062)
			(xy 290.122978 -398.669401) (xy 290.148721 -398.729571) (xy 290.166146 -398.792655) (xy 290.174937 -398.857508)
			(xy 290.174932 -398.922954) (xy 290.166134 -398.987806) (xy 290.148701 -399.050887) (xy 290.122949 -399.111054)
			(xy 290.106608 -399.13941) (xy 290.10329 -399.145433) (xy 290.099686 -399.158698) (xy 290.099496 -399.165572)
			(xy 290.099496 -399.451576) (xy 290.099059 -399.461729) (xy 290.09127 -399.480482) (xy 290.076878 -399.494806)
			(xy 290.058089 -399.502506) (xy 290.047934 -399.502884) (xy 289.331654 -399.502884) (xy 289.321527 -399.502412)
			(xy 289.30281 -399.494673) (xy 289.288456 -399.480383) (xy 289.280634 -399.4617) (xy 289.280092 -399.451576)
			(xy 289.280092 -399.165572) (xy 289.279912 -399.158698) (xy 289.276296 -399.145435) (xy 289.27298 -399.13941)
			(xy 289.256672 -399.111037) (xy 289.230923 -399.050875) (xy 289.213492 -398.987798) (xy 289.204694 -398.922951)
			(xy 289.20469 -398.85751) (xy 289.213479 -398.792662) (xy 289.230903 -398.729583) (xy 289.256644 -398.669418)
			(xy 289.27298 -398.641062) (xy 289.276307 -398.635043) (xy 289.279905 -398.621775) (xy 289.280092 -398.6149)
			(xy 289.280092 -397.865346) (xy 289.279883 -397.858474) (xy 289.276287 -397.845211) (xy 289.27298 -397.839184)
			(xy 289.25665 -397.810824) (xy 289.230903 -397.750658) (xy 289.213474 -397.687579) (xy 289.204679 -397.62273)
			(xy 289.204678 -397.557287) (xy 287.916082 -397.557287) (xy 287.923021 -397.569361) (xy 287.94877 -397.629524)
			(xy 287.966202 -397.6926) (xy 287.975 -397.757447) (xy 287.975004 -397.822888) (xy 287.966215 -397.887736)
			(xy 287.948792 -397.950815) (xy 287.92305 -398.01098) (xy 287.906714 -398.039336) (xy 287.903342 -398.045347)
			(xy 287.89961 -398.05861) (xy 287.899348 -398.065498) (xy 287.899348 -398.351502) (xy 287.898875 -398.36163)
			(xy 287.891144 -398.380354) (xy 287.876853 -398.39471) (xy 287.858166 -398.402527) (xy 287.84804 -398.403064)
			(xy 287.13176 -398.403064) (xy 287.121599 -398.40271) (xy 287.102839 -398.394895) (xy 287.088515 -398.380477)
			(xy 287.080824 -398.361666) (xy 287.080452 -398.351502) (xy 287.080452 -398.065498) (xy 287.080248 -398.058603)
			(xy 287.0765 -398.045331) (xy 287.073086 -398.039336) (xy 287.056715 -398.010998) (xy 287.030972 -397.950828)
			(xy 287.013547 -397.887744) (xy 287.004757 -397.822891) (xy 283.301948 -397.822891) (xy 283.301948 -401.722804)
			(xy 287.004766 -401.722804) (xy 287.004769 -401.657359) (xy 287.013565 -401.592507) (xy 287.030996 -401.529426)
			(xy 287.056746 -401.46926) (xy 287.073086 -401.440904) (xy 287.076444 -401.434886) (xy 287.080184 -401.421628)
			(xy 287.080452 -401.414742) (xy 287.080452 -400.665442) (xy 287.080231 -400.658548) (xy 287.076494 -400.645276)
			(xy 287.073086 -400.63928) (xy 287.056752 -400.610922) (xy 287.031005 -400.550756) (xy 287.013577 -400.487676)
			(xy 287.004782 -400.422827) (xy 287.004782 -400.357384) (xy 287.013575 -400.292534) (xy 287.031002 -400.229454)
			(xy 287.056748 -400.169288) (xy 287.073086 -400.140932) (xy 287.076434 -400.134909) (xy 287.080181 -400.121655)
			(xy 287.080452 -400.11477) (xy 287.080452 -399.828766) (xy 287.080899 -399.818636) (xy 287.08864 -399.799911)
			(xy 287.102939 -399.785556) (xy 287.121632 -399.77774) (xy 287.13176 -399.777204) (xy 287.84804 -399.777204)
			(xy 287.858197 -399.777589) (xy 287.876951 -399.785399) (xy 287.891273 -399.799806) (xy 287.898971 -399.818606)
			(xy 287.899348 -399.828766) (xy 287.899348 -400.11477) (xy 287.899565 -400.121664) (xy 287.903304 -400.134936)
			(xy 287.906714 -400.140932) (xy 287.923058 -400.169285) (xy 287.948804 -400.229452) (xy 287.966231 -400.292533)
			(xy 287.975025 -400.357383) (xy 287.975024 -400.422827) (xy 287.966229 -400.487677) (xy 287.9488 -400.550758)
			(xy 287.923053 -400.610924) (xy 287.906714 -400.63928) (xy 287.903362 -400.645301) (xy 287.899618 -400.658557)
			(xy 287.899348 -400.665442) (xy 287.899348 -401.414742) (xy 287.899575 -401.421635) (xy 287.903308 -401.434907)
			(xy 287.906714 -401.440904) (xy 287.923034 -401.46927) (xy 287.948782 -401.529434) (xy 287.966213 -401.592512)
			(xy 287.975009 -401.65736) (xy 287.975011 -401.722802) (xy 287.96622 -401.787651) (xy 287.948795 -401.85073)
			(xy 287.923051 -401.910896) (xy 287.906714 -401.939252) (xy 287.903336 -401.945261) (xy 287.899608 -401.958526)
			(xy 287.899348 -401.965414) (xy 287.899348 -402.251418) (xy 287.898888 -402.261547) (xy 287.891152 -402.280271)
			(xy 287.876858 -402.294627) (xy 287.858167 -402.302444) (xy 287.84804 -402.30298) (xy 287.13176 -402.30298)
			(xy 287.121601 -402.302611) (xy 287.102844 -402.294798) (xy 287.088521 -402.280385) (xy 287.080826 -402.26158)
			(xy 287.080452 -402.251418) (xy 287.080452 -401.965414) (xy 287.080242 -401.958519) (xy 287.076498 -401.945247)
			(xy 287.073086 -401.939252) (xy 287.056729 -401.910907) (xy 287.030984 -401.850738) (xy 287.013558 -401.787656)
			(xy 287.004766 -401.722804) (xy 283.301948 -401.722804) (xy 283.301948 -402.822882) (xy 289.204646 -402.822882)
			(xy 289.204652 -402.757435) (xy 289.213451 -402.692583) (xy 289.230886 -402.629501) (xy 289.256638 -402.569334)
			(xy 289.27298 -402.540978) (xy 289.276301 -402.534956) (xy 289.279903 -402.52169) (xy 289.280092 -402.514816)
			(xy 289.280092 -401.765516) (xy 289.279895 -401.758643) (xy 289.27629 -401.74538) (xy 289.27298 -401.739354)
			(xy 289.256624 -401.711008) (xy 289.23088 -401.650839) (xy 289.213454 -401.587757) (xy 289.204662 -401.522905)
			(xy 289.204665 -401.45746) (xy 289.213461 -401.392609) (xy 289.230891 -401.329528) (xy 289.25664 -401.269362)
			(xy 289.27298 -401.241006) (xy 289.276291 -401.23498) (xy 289.279899 -401.221717) (xy 289.280092 -401.214844)
			(xy 289.280092 -400.92884) (xy 289.280554 -400.918689) (xy 289.288335 -400.89994) (xy 289.30272 -400.885615)
			(xy 289.321502 -400.877913) (xy 289.331654 -400.877532) (xy 290.047934 -400.877532) (xy 290.058062 -400.877998)
			(xy 290.076782 -400.885736) (xy 290.091137 -400.900028) (xy 290.098957 -400.918714) (xy 290.099496 -400.92884)
			(xy 290.099496 -401.214844) (xy 290.09971 -401.221716) (xy 290.103303 -401.234978) (xy 290.106608 -401.241006)
			(xy 290.12293 -401.269371) (xy 290.148678 -401.329535) (xy 290.166109 -401.392613) (xy 290.174905 -401.457462)
			(xy 290.174907 -401.522904) (xy 290.166115 -401.587753) (xy 290.14869 -401.650833) (xy 290.122946 -401.710998)
			(xy 290.116144 -401.722803) (xy 291.404816 -401.722803) (xy 291.404819 -401.657359) (xy 291.413614 -401.592508)
			(xy 291.431043 -401.529428) (xy 291.45679 -401.46926) (xy 291.473128 -401.440904) (xy 291.476443 -401.43488)
			(xy 291.480048 -401.421616) (xy 291.48024 -401.414742) (xy 291.48024 -400.665442) (xy 291.480027 -400.65857)
			(xy 291.476433 -400.645308) (xy 291.473128 -400.63928) (xy 291.456796 -400.610921) (xy 291.431052 -400.550755)
			(xy 291.413626 -400.487675) (xy 291.404832 -400.422826) (xy 291.404832 -400.357384) (xy 291.413624 -400.292535)
			(xy 291.431049 -400.229455) (xy 291.456791 -400.169288) (xy 291.473128 -400.140932) (xy 291.476433 -400.134903)
			(xy 291.480044 -400.121643) (xy 291.48024 -400.11477) (xy 291.48024 -399.828766) (xy 291.480706 -399.818606)
			(xy 291.488492 -399.799835) (xy 291.502866 -399.785471) (xy 291.521641 -399.777698) (xy 291.531802 -399.777204)
			(xy 292.248082 -399.777204) (xy 292.258234 -399.777747) (xy 292.276997 -399.785509) (xy 292.291361 -399.79986)
			(xy 292.299143 -399.818614) (xy 292.299644 -399.828766) (xy 292.299644 -400.11477) (xy 292.299842 -400.121643)
			(xy 292.303445 -400.134906) (xy 292.306756 -400.140932) (xy 292.323099 -400.169285) (xy 292.348842 -400.229453)
			(xy 292.366268 -400.292533) (xy 292.375061 -400.357383) (xy 292.37506 -400.422827) (xy 292.366266 -400.487677)
			(xy 292.348839 -400.550757) (xy 292.323094 -400.610924) (xy 292.306756 -400.63928) (xy 292.303453 -400.64531)
			(xy 292.299839 -400.65857) (xy 292.299644 -400.665442) (xy 292.299644 -401.414742) (xy 292.299853 -401.421614)
			(xy 292.303449 -401.434877) (xy 292.306756 -401.440904) (xy 292.323075 -401.46927) (xy 292.348821 -401.529435)
			(xy 292.366249 -401.592513) (xy 292.375045 -401.65736) (xy 292.375047 -401.722802) (xy 292.366257 -401.78765)
			(xy 292.348833 -401.85073) (xy 292.323092 -401.910896) (xy 292.306756 -401.939252) (xy 292.303427 -401.94527)
			(xy 292.29983 -401.958539) (xy 292.299644 -401.965414) (xy 292.299644 -402.251418) (xy 292.299181 -402.261579)
			(xy 292.291397 -402.280352) (xy 292.277022 -402.294718) (xy 292.258244 -402.302488) (xy 292.248082 -402.30298)
			(xy 291.531802 -402.30298) (xy 291.521647 -402.302465) (xy 291.502881 -402.294695) (xy 291.488516 -402.280336)
			(xy 291.480739 -402.261573) (xy 291.48024 -402.251418) (xy 291.48024 -401.965414) (xy 291.480038 -401.958542)
			(xy 291.476436 -401.945279) (xy 291.473128 -401.939252) (xy 291.456772 -401.910906) (xy 291.431031 -401.850737)
			(xy 291.413607 -401.787655) (xy 291.404816 -401.722803) (xy 290.116144 -401.722803) (xy 290.106608 -401.739354)
			(xy 290.10331 -401.745387) (xy 290.099694 -401.758644) (xy 290.099496 -401.765516) (xy 290.099496 -402.514816)
			(xy 290.099682 -402.52169) (xy 290.103294 -402.534952) (xy 290.106608 -402.540978) (xy 290.122906 -402.569356)
			(xy 290.148657 -402.629517) (xy 290.16609 -402.692593) (xy 290.174889 -402.757439) (xy 290.174894 -402.822879)
			(xy 290.174894 -402.822882) (xy 293.604696 -402.822882) (xy 293.604702 -402.757436) (xy 293.6135 -402.692584)
			(xy 293.630933 -402.629502) (xy 293.656682 -402.569334) (xy 293.673022 -402.540978) (xy 293.676392 -402.534966)
			(xy 293.680124 -402.521703) (xy 293.680388 -402.514816) (xy 293.680388 -401.765516) (xy 293.68015 -401.758625)
			(xy 293.676411 -401.745359) (xy 293.673022 -401.739354) (xy 293.656668 -401.711007) (xy 293.630927 -401.650838)
			(xy 293.613503 -401.587756) (xy 293.604712 -401.522905) (xy 293.604715 -401.457461) (xy 293.61351 -401.39261)
			(xy 293.630938 -401.32953) (xy 293.656684 -401.269362) (xy 293.673022 -401.241006) (xy 293.676382 -401.234989)
			(xy 293.68012 -401.22173) (xy 293.680388 -401.214844) (xy 293.680388 -400.92884) (xy 293.680849 -400.918722)
			(xy 293.688581 -400.900021) (xy 293.702884 -400.885706) (xy 293.721578 -400.877957) (xy 293.731696 -400.877532)
			(xy 294.447976 -400.877532) (xy 294.458101 -400.877936) (xy 294.47681 -400.885682) (xy 294.491127 -400.900003)
			(xy 294.498867 -400.918715) (xy 294.499284 -400.92884) (xy 294.499284 -401.214844) (xy 294.499506 -401.221738)
			(xy 294.503242 -401.23501) (xy 294.50665 -401.241006) (xy 294.522971 -401.269371) (xy 294.548717 -401.329536)
			(xy 294.566146 -401.392614) (xy 294.574941 -401.457462) (xy 294.574943 -401.522904) (xy 294.566152 -401.587752)
			(xy 294.548728 -401.650832) (xy 294.522986 -401.710998) (xy 294.516185 -401.722804) (xy 295.804852 -401.722804)
			(xy 295.804855 -401.657359) (xy 295.813651 -401.592508) (xy 295.831082 -401.529427) (xy 295.85683 -401.46926)
			(xy 295.87317 -401.440904) (xy 295.876534 -401.434889) (xy 295.88027 -401.421629) (xy 295.880536 -401.414742)
			(xy 295.880536 -400.665442) (xy 295.880317 -400.658548) (xy 295.876579 -400.645276) (xy 295.87317 -400.63928)
			(xy 295.856837 -400.610921) (xy 295.831091 -400.550756) (xy 295.813663 -400.487676) (xy 295.804868 -400.422827)
			(xy 295.804868 -400.357384) (xy 295.813661 -400.292534) (xy 295.831087 -400.229454) (xy 295.856832 -400.169288)
			(xy 295.87317 -400.140932) (xy 295.876525 -400.134912) (xy 295.880266 -400.121656) (xy 295.880536 -400.11477)
			(xy 295.880536 -399.828766) (xy 295.880999 -399.818638) (xy 295.888737 -399.799916) (xy 295.90303 -399.785561)
			(xy 295.921718 -399.777743) (xy 295.931844 -399.777204) (xy 296.648124 -399.777204) (xy 296.65828 -399.777602)
			(xy 296.677034 -399.785406) (xy 296.691357 -399.79981) (xy 296.699055 -399.818608) (xy 296.699432 -399.828766)
			(xy 296.699432 -400.11477) (xy 296.699672 -400.121661) (xy 296.703409 -400.134927) (xy 296.706798 -400.140932)
			(xy 296.723139 -400.169286) (xy 296.748881 -400.229453) (xy 296.766305 -400.292534) (xy 296.775097 -400.357384)
			(xy 296.775096 -400.422827) (xy 296.766303 -400.487676) (xy 296.748877 -400.550756) (xy 296.723135 -400.610923)
			(xy 296.706798 -400.63928) (xy 296.703445 -400.645301) (xy 296.699702 -400.658557) (xy 296.699432 -400.665442)
			(xy 296.699432 -401.414742) (xy 296.699661 -401.421635) (xy 296.703393 -401.434907) (xy 296.706798 -401.440904)
			(xy 296.723116 -401.469271) (xy 296.748859 -401.529435) (xy 296.766286 -401.592513) (xy 296.775081 -401.657361)
			(xy 296.775083 -401.722802) (xy 296.766294 -401.78765) (xy 296.748872 -401.850729) (xy 296.723133 -401.910895)
			(xy 296.706798 -401.939252) (xy 296.703419 -401.94526) (xy 296.699692 -401.958526) (xy 296.699432 -401.965414)
			(xy 296.699432 -402.251418) (xy 296.698988 -402.261549) (xy 296.691249 -402.280276) (xy 296.676949 -402.294633)
			(xy 296.658253 -402.302447) (xy 296.648124 -402.30298) (xy 295.931844 -402.30298) (xy 295.92169 -402.302542)
			(xy 295.902935 -402.294757) (xy 295.888609 -402.280365) (xy 295.880912 -402.261574) (xy 295.880536 -402.251418)
			(xy 295.880536 -401.965414) (xy 295.880328 -401.958519) (xy 295.876583 -401.945247) (xy 295.87317 -401.939252)
			(xy 295.856813 -401.910906) (xy 295.831069 -401.850738) (xy 295.813644 -401.787655) (xy 295.804852 -401.722804)
			(xy 294.516185 -401.722804) (xy 294.50665 -401.739354) (xy 294.503267 -401.74536) (xy 294.499544 -401.758627)
			(xy 294.499284 -401.765516) (xy 294.499284 -402.514816) (xy 294.499517 -402.521709) (xy 294.503245 -402.534981)
			(xy 294.50665 -402.540978) (xy 294.522947 -402.569357) (xy 294.548695 -402.629518) (xy 294.566127 -402.692593)
			(xy 294.574925 -402.757439) (xy 294.57493 -402.822879) (xy 294.57493 -402.822882) (xy 298.004733 -402.822882)
			(xy 298.004738 -402.757436) (xy 298.013537 -402.692583) (xy 298.030971 -402.629501) (xy 298.056723 -402.569334)
			(xy 298.073064 -402.540978) (xy 298.076384 -402.534956) (xy 298.079986 -402.52169) (xy 298.080176 -402.514816)
			(xy 298.080176 -401.765516) (xy 298.079981 -401.758643) (xy 298.076375 -401.74538) (xy 298.073064 -401.739354)
			(xy 298.056709 -401.711007) (xy 298.030965 -401.650839) (xy 298.01354 -401.587757) (xy 298.004748 -401.522905)
			(xy 298.004751 -401.457461) (xy 298.013547 -401.39261) (xy 298.030977 -401.329529) (xy 298.056725 -401.269362)
			(xy 298.073064 -401.241006) (xy 298.076374 -401.234979) (xy 298.079983 -401.221717) (xy 298.080176 -401.214844)
			(xy 298.080176 -400.92884) (xy 298.080654 -400.918691) (xy 298.088432 -400.899945) (xy 298.102811 -400.885621)
			(xy 298.121588 -400.877915) (xy 298.131738 -400.877532) (xy 298.848018 -400.877532) (xy 298.858145 -400.878011)
			(xy 298.876865 -400.885744) (xy 298.89122 -400.900032) (xy 298.89904 -400.918716) (xy 298.89958 -400.92884)
			(xy 298.89958 -401.214844) (xy 298.899796 -401.221715) (xy 298.903388 -401.234978) (xy 298.906692 -401.241006)
			(xy 298.923011 -401.269372) (xy 298.948755 -401.329537) (xy 298.966182 -401.392615) (xy 298.974977 -401.457462)
			(xy 298.974979 -401.522903) (xy 298.966189 -401.587752) (xy 298.948767 -401.650831) (xy 298.923027 -401.710998)
			(xy 298.916227 -401.722803) (xy 300.204642 -401.722803) (xy 300.204645 -401.657359) (xy 300.213441 -401.592508)
			(xy 300.230871 -401.529427) (xy 300.256619 -401.46926) (xy 300.272958 -401.440904) (xy 300.276322 -401.434889)
			(xy 300.280057 -401.421629) (xy 300.280324 -401.414742) (xy 300.280324 -400.665442) (xy 300.280107 -400.658548)
			(xy 300.276368 -400.645276) (xy 300.272958 -400.63928) (xy 300.256625 -400.610921) (xy 300.23088 -400.550755)
			(xy 300.213452 -400.487676) (xy 300.204658 -400.422827) (xy 300.204657 -400.357384) (xy 300.21345 -400.292534)
			(xy 300.230876 -400.229454) (xy 300.25662 -400.169288) (xy 300.272958 -400.140932) (xy 300.276312 -400.134912)
			(xy 300.280054 -400.121655) (xy 300.280324 -400.11477) (xy 300.280324 -399.828766) (xy 300.280798 -399.818639)
			(xy 300.288534 -399.79992) (xy 300.302824 -399.785566) (xy 300.321507 -399.777745) (xy 300.331632 -399.777204)
			(xy 301.047912 -399.777204) (xy 301.058067 -399.777612) (xy 301.076821 -399.785412) (xy 301.091144 -399.799813)
			(xy 301.098843 -399.818608) (xy 301.09922 -399.828766) (xy 301.09922 -400.11477) (xy 301.099462 -400.121661)
			(xy 301.103198 -400.134927) (xy 301.106586 -400.140932) (xy 301.122928 -400.169286) (xy 301.14867 -400.229453)
			(xy 301.166095 -400.292534) (xy 301.174887 -400.357384) (xy 301.174886 -400.390106) (xy 304.603666 -400.390106)
			(xy 304.607657 -400.327939) (xy 304.619566 -400.266792) (xy 304.639195 -400.207671) (xy 304.666224 -400.151545)
			(xy 304.700208 -400.099336) (xy 304.74059 -400.051901) (xy 304.786706 -400.01002) (xy 304.837798 -399.97438)
			(xy 304.893029 -399.945566) (xy 304.951491 -399.924052) (xy 305.012225 -399.91019) (xy 305.074232 -399.904208)
			(xy 305.136495 -399.906204) (xy 305.197992 -399.916147) (xy 305.257713 -399.933871) (xy 305.314676 -399.959088)
			(xy 305.367947 -399.991381) (xy 305.416652 -400.030221) (xy 305.459989 -400.074971) (xy 305.497249 -400.124895)
			(xy 305.527818 -400.179174) (xy 305.551196 -400.236917) (xy 305.566997 -400.297175) (xy 305.574963 -400.358958)
			(xy 305.575462 -400.390106) (xy 305.574963 -400.421254) (xy 305.566997 -400.483037) (xy 305.551196 -400.543295)
			(xy 305.527818 -400.601038) (xy 305.497249 -400.655317) (xy 305.459989 -400.705241) (xy 305.416652 -400.749991)
			(xy 305.367947 -400.788831) (xy 305.314676 -400.821124) (xy 305.257713 -400.846341) (xy 305.197992 -400.864065)
			(xy 305.136495 -400.874008) (xy 305.074232 -400.876004) (xy 305.012225 -400.870022) (xy 304.951491 -400.85616)
			(xy 304.893029 -400.834646) (xy 304.837798 -400.805832) (xy 304.786706 -400.770192) (xy 304.74059 -400.728311)
			(xy 304.700208 -400.680876) (xy 304.666224 -400.628667) (xy 304.639195 -400.572541) (xy 304.619566 -400.51342)
			(xy 304.607657 -400.452273) (xy 304.603666 -400.390106) (xy 301.174886 -400.390106) (xy 301.174886 -400.422827)
			(xy 301.166093 -400.487676) (xy 301.148666 -400.550757) (xy 301.122923 -400.610924) (xy 301.106586 -400.63928)
			(xy 301.103232 -400.6453) (xy 301.099489 -400.658556) (xy 301.09922 -400.665442) (xy 301.09922 -401.414742)
			(xy 301.099473 -401.421632) (xy 301.103201 -401.434898) (xy 301.106586 -401.440904) (xy 301.122904 -401.469271)
			(xy 301.148648 -401.529435) (xy 301.166076 -401.592513) (xy 301.174871 -401.657361) (xy 301.174873 -401.722802)
			(xy 301.166083 -401.78765) (xy 301.148661 -401.850729) (xy 301.122921 -401.910896) (xy 301.106586 -401.939252)
			(xy 301.103206 -401.945259) (xy 301.09948 -401.958526) (xy 301.09922 -401.965414) (xy 301.09922 -402.251418)
			(xy 301.098787 -402.261551) (xy 301.091046 -402.28028) (xy 301.076743 -402.294637) (xy 301.058043 -402.302449)
			(xy 301.047912 -402.30298) (xy 300.331632 -402.30298) (xy 300.321477 -402.302552) (xy 300.302722 -402.294763)
			(xy 300.288396 -402.280368) (xy 300.280699 -402.261575) (xy 300.280324 -402.251418) (xy 300.280324 -401.965414)
			(xy 300.280117 -401.958519) (xy 300.276371 -401.945247) (xy 300.272958 -401.939252) (xy 300.256601 -401.910906)
			(xy 300.230858 -401.850737) (xy 300.213433 -401.787655) (xy 300.204642 -401.722803) (xy 298.916227 -401.722803)
			(xy 298.906692 -401.739354) (xy 298.903393 -401.745386) (xy 298.899778 -401.758644) (xy 298.89958 -401.765516)
			(xy 298.89958 -402.514816) (xy 298.899768 -402.521689) (xy 298.903379 -402.534952) (xy 298.906692 -402.540978)
			(xy 298.922988 -402.569357) (xy 298.948734 -402.629519) (xy 298.966164 -402.692594) (xy 298.974961 -402.757439)
			(xy 298.974967 -402.822878) (xy 298.974966 -402.822882) (xy 302.404783 -402.822882) (xy 302.404788 -402.757436)
			(xy 302.413586 -402.692584) (xy 302.431018 -402.629502) (xy 302.456766 -402.569335) (xy 302.473106 -402.540978)
			(xy 302.476474 -402.534965) (xy 302.480208 -402.521703) (xy 302.480472 -402.514816) (xy 302.480472 -401.765516)
			(xy 302.480236 -401.758625) (xy 302.476496 -401.745359) (xy 302.473106 -401.739354) (xy 302.456753 -401.711007)
			(xy 302.431012 -401.650838) (xy 302.413589 -401.587756) (xy 302.404799 -401.522905) (xy 302.404801 -401.457461)
			(xy 302.413596 -401.392611) (xy 302.431023 -401.32953) (xy 302.456768 -401.269363) (xy 302.473106 -401.241006)
			(xy 302.476465 -401.234988) (xy 302.480204 -401.22173) (xy 302.480472 -401.214844) (xy 302.480472 -400.92884)
			(xy 302.480948 -400.918724) (xy 302.488678 -400.900026) (xy 302.502976 -400.885712) (xy 302.521664 -400.87796)
			(xy 302.53178 -400.877532) (xy 303.24806 -400.877532) (xy 303.258184 -400.87795) (xy 303.276893 -400.885691)
			(xy 303.291209 -400.900007) (xy 303.29895 -400.918716) (xy 303.299368 -400.92884) (xy 303.299368 -401.214844)
			(xy 303.299592 -401.221738) (xy 303.303326 -401.23501) (xy 303.306734 -401.241006) (xy 303.323055 -401.269371)
			(xy 303.348802 -401.329536) (xy 303.366231 -401.392614) (xy 303.375027 -401.457462) (xy 303.375029 -401.522904)
			(xy 303.366238 -401.587753) (xy 303.348814 -401.650832) (xy 303.332022 -401.690078) (xy 304.603666 -401.690078)
			(xy 304.607657 -401.627911) (xy 304.619566 -401.566764) (xy 304.639195 -401.507643) (xy 304.666224 -401.451517)
			(xy 304.700208 -401.399308) (xy 304.74059 -401.351873) (xy 304.786706 -401.309992) (xy 304.837798 -401.274352)
			(xy 304.893029 -401.245538) (xy 304.951491 -401.224024) (xy 305.012225 -401.210162) (xy 305.074232 -401.20418)
			(xy 305.136495 -401.206176) (xy 305.197992 -401.216119) (xy 305.257713 -401.233843) (xy 305.314676 -401.25906)
			(xy 305.367947 -401.291353) (xy 305.416652 -401.330193) (xy 305.459989 -401.374943) (xy 305.497249 -401.424867)
			(xy 305.527818 -401.479146) (xy 305.532285 -401.49018) (xy 306.803814 -401.49018) (xy 306.807805 -401.428013)
			(xy 306.819714 -401.366866) (xy 306.839343 -401.307745) (xy 306.866372 -401.251619) (xy 306.900356 -401.19941)
			(xy 306.940738 -401.151975) (xy 306.986854 -401.110094) (xy 307.037946 -401.074454) (xy 307.093177 -401.04564)
			(xy 307.151639 -401.024126) (xy 307.212373 -401.010264) (xy 307.27438 -401.004282) (xy 307.336643 -401.006278)
			(xy 307.39814 -401.016221) (xy 307.457861 -401.033945) (xy 307.514824 -401.059162) (xy 307.568095 -401.091455)
			(xy 307.6168 -401.130295) (xy 307.660137 -401.175045) (xy 307.697397 -401.224969) (xy 307.727966 -401.279248)
			(xy 307.751344 -401.336991) (xy 307.767145 -401.397249) (xy 307.775111 -401.459032) (xy 307.77561 -401.49018)
			(xy 307.775111 -401.521328) (xy 307.767145 -401.583111) (xy 307.751344 -401.643369) (xy 307.727966 -401.701112)
			(xy 307.697397 -401.755391) (xy 307.660137 -401.805315) (xy 307.6168 -401.850065) (xy 307.568095 -401.888905)
			(xy 307.514824 -401.921198) (xy 307.457861 -401.946415) (xy 307.39814 -401.964139) (xy 307.336643 -401.974082)
			(xy 307.27438 -401.976078) (xy 307.212373 -401.970096) (xy 307.151639 -401.956234) (xy 307.093177 -401.93472)
			(xy 307.037946 -401.905906) (xy 306.986854 -401.870266) (xy 306.940738 -401.828385) (xy 306.900356 -401.78095)
			(xy 306.866372 -401.728741) (xy 306.839343 -401.672615) (xy 306.819714 -401.613494) (xy 306.807805 -401.552347)
			(xy 306.803814 -401.49018) (xy 305.532285 -401.49018) (xy 305.551196 -401.536889) (xy 305.566997 -401.597147)
			(xy 305.574963 -401.65893) (xy 305.575462 -401.690078) (xy 305.574963 -401.721226) (xy 305.566997 -401.783009)
			(xy 305.551196 -401.843267) (xy 305.527818 -401.90101) (xy 305.497249 -401.955289) (xy 305.459989 -402.005213)
			(xy 305.416652 -402.049963) (xy 305.367947 -402.088803) (xy 305.314676 -402.121096) (xy 305.257713 -402.146313)
			(xy 305.197992 -402.164037) (xy 305.136495 -402.17398) (xy 305.074232 -402.175976) (xy 305.012225 -402.169994)
			(xy 304.951491 -402.156132) (xy 304.893029 -402.134618) (xy 304.837798 -402.105804) (xy 304.786706 -402.070164)
			(xy 304.74059 -402.028283) (xy 304.700208 -401.980848) (xy 304.666224 -401.928639) (xy 304.639195 -401.872513)
			(xy 304.619566 -401.813392) (xy 304.607657 -401.752245) (xy 304.603666 -401.690078) (xy 303.332022 -401.690078)
			(xy 303.323071 -401.710998) (xy 303.306734 -401.739354) (xy 303.30335 -401.745359) (xy 303.299627 -401.758627)
			(xy 303.299368 -401.765516) (xy 303.299368 -402.514816) (xy 303.299603 -402.521709) (xy 303.30333 -402.534981)
			(xy 303.306734 -402.540978) (xy 303.323032 -402.569356) (xy 303.348781 -402.629518) (xy 303.366213 -402.692593)
			(xy 303.375011 -402.757439) (xy 303.375014 -402.790152) (xy 306.803814 -402.790152) (xy 306.807805 -402.727985)
			(xy 306.819714 -402.666838) (xy 306.839343 -402.607717) (xy 306.866372 -402.551591) (xy 306.900356 -402.499382)
			(xy 306.940738 -402.451947) (xy 306.986854 -402.410066) (xy 307.037946 -402.374426) (xy 307.093177 -402.345612)
			(xy 307.151639 -402.324098) (xy 307.212373 -402.310236) (xy 307.27438 -402.304254) (xy 307.336643 -402.30625)
			(xy 307.39814 -402.316193) (xy 307.457861 -402.333917) (xy 307.514824 -402.359134) (xy 307.568095 -402.391427)
			(xy 307.6168 -402.430267) (xy 307.660137 -402.475017) (xy 307.697397 -402.524941) (xy 307.727966 -402.57922)
			(xy 307.751344 -402.636963) (xy 307.767145 -402.697221) (xy 307.775111 -402.759004) (xy 307.77561 -402.790152)
			(xy 307.775111 -402.8213) (xy 307.767145 -402.883083) (xy 307.751344 -402.943341) (xy 307.727966 -403.001084)
			(xy 307.697397 -403.055363) (xy 307.660137 -403.105287) (xy 307.6168 -403.150037) (xy 307.568095 -403.188877)
			(xy 307.514824 -403.22117) (xy 307.457861 -403.246387) (xy 307.39814 -403.264111) (xy 307.336643 -403.274054)
			(xy 307.27438 -403.27605) (xy 307.212373 -403.270068) (xy 307.151639 -403.256206) (xy 307.093177 -403.234692)
			(xy 307.037946 -403.205878) (xy 306.986854 -403.170238) (xy 306.940738 -403.128357) (xy 306.900356 -403.080922)
			(xy 306.866372 -403.028713) (xy 306.839343 -402.972587) (xy 306.819714 -402.913466) (xy 306.807805 -402.852319)
			(xy 306.803814 -402.790152) (xy 303.375014 -402.790152) (xy 303.375017 -402.822879) (xy 303.366229 -402.887726)
			(xy 303.348808 -402.950805) (xy 303.323069 -403.01097) (xy 303.306734 -403.039326) (xy 303.303359 -403.045336)
			(xy 303.299631 -403.0586) (xy 303.299368 -403.065488) (xy 303.299368 -403.351492) (xy 303.298977 -403.361618)
			(xy 303.291225 -403.380328) (xy 303.276901 -403.394643) (xy 303.258186 -403.402383) (xy 303.24806 -403.4028)
			(xy 302.53178 -403.4028) (xy 302.52167 -403.402331) (xy 302.502991 -403.394587) (xy 302.488697 -403.380285)
			(xy 302.480963 -403.361602) (xy 302.480472 -403.351492) (xy 302.480472 -403.065488) (xy 302.480231 -403.058596)
			(xy 302.476508 -403.045324) (xy 302.473106 -403.039326) (xy 302.456729 -403.010992) (xy 302.430991 -402.95082)
			(xy 302.41357 -402.887735) (xy 302.404783 -402.822882) (xy 298.974966 -402.822882) (xy 298.96618 -402.887725)
			(xy 298.948761 -402.950803) (xy 298.923025 -403.01097) (xy 298.906692 -403.039326) (xy 298.903367 -403.045346)
			(xy 298.899768 -403.058613) (xy 298.89958 -403.065488) (xy 298.89958 -403.351492) (xy 298.899171 -403.361648)
			(xy 298.891375 -403.380404) (xy 298.876974 -403.394729) (xy 298.858176 -403.402425) (xy 298.848018 -403.4028)
			(xy 298.131738 -403.4028) (xy 298.121619 -403.402243) (xy 298.102906 -403.394535) (xy 298.08855 -403.380271)
			(xy 298.080722 -403.361608) (xy 298.080176 -403.351492) (xy 298.080176 -403.065488) (xy 298.079991 -403.058614)
			(xy 298.076378 -403.045351) (xy 298.073064 -403.039326) (xy 298.056685 -403.010993) (xy 298.030944 -402.950821)
			(xy 298.013521 -402.887736) (xy 298.004733 -402.822882) (xy 294.57493 -402.822882) (xy 294.566143 -402.887726)
			(xy 294.548723 -402.950804) (xy 294.522985 -403.01097) (xy 294.50665 -403.039326) (xy 294.503277 -403.045337)
			(xy 294.499547 -403.0586) (xy 294.499284 -403.065488) (xy 294.499284 -403.351492) (xy 294.498877 -403.361616)
			(xy 294.491129 -403.380322) (xy 294.476809 -403.394638) (xy 294.4581 -403.40238) (xy 294.447976 -403.4028)
			(xy 293.731696 -403.4028) (xy 293.721573 -403.402387) (xy 293.70287 -403.394638) (xy 293.688556 -403.38032)
			(xy 293.68081 -403.361615) (xy 293.680388 -403.351492) (xy 293.680388 -403.065488) (xy 293.680122 -403.058599)
			(xy 293.676402 -403.045333) (xy 293.673022 -403.039326) (xy 293.656644 -403.010992) (xy 293.630905 -402.95082)
			(xy 293.613484 -402.887735) (xy 293.604696 -402.822882) (xy 290.174894 -402.822882) (xy 290.166106 -402.887727)
			(xy 290.148684 -402.950805) (xy 290.122944 -403.01097) (xy 290.106608 -403.039326) (xy 290.103285 -403.045346)
			(xy 290.099684 -403.058613) (xy 290.099496 -403.065488) (xy 290.099496 -403.351492) (xy 290.099072 -403.361646)
			(xy 290.091278 -403.380399) (xy 290.076882 -403.394723) (xy 290.05809 -403.402422) (xy 290.047934 -403.4028)
			(xy 289.331654 -403.4028) (xy 289.321529 -403.402312) (xy 289.302815 -403.394577) (xy 289.288461 -403.380292)
			(xy 289.280637 -403.361614) (xy 289.280092 -403.351492) (xy 289.280092 -403.065488) (xy 289.279906 -403.058614)
			(xy 289.276294 -403.045351) (xy 289.27298 -403.039326) (xy 289.256601 -403.010993) (xy 289.230858 -402.950821)
			(xy 289.213435 -402.887736) (xy 289.204646 -402.822882) (xy 283.301948 -402.822882) (xy 283.301948 -405.622717)
			(xy 287.004775 -405.622717) (xy 287.004776 -405.557273) (xy 287.013571 -405.492423) (xy 287.031 -405.429342)
			(xy 287.056747 -405.369176) (xy 287.073086 -405.34082) (xy 287.076438 -405.334799) (xy 287.080182 -405.321543)
			(xy 287.080452 -405.314658) (xy 287.080452 -404.565358) (xy 287.080225 -404.558465) (xy 287.076492 -404.545193)
			(xy 287.073086 -404.539196) (xy 287.056766 -404.51083) (xy 287.031018 -404.450666) (xy 287.013587 -404.387588)
			(xy 287.004791 -404.32274) (xy 287.004789 -404.257298) (xy 287.01358 -404.192449) (xy 287.031005 -404.12937)
			(xy 287.056749 -404.069204) (xy 287.073086 -404.040848) (xy 287.076464 -404.034839) (xy 287.080192 -404.021574)
			(xy 287.080452 -404.014686) (xy 287.080452 -403.728682) (xy 287.080912 -403.718553) (xy 287.088648 -403.699829)
			(xy 287.102942 -403.685473) (xy 287.121633 -403.677656) (xy 287.13176 -403.67712) (xy 287.84804 -403.67712)
			(xy 287.858199 -403.677489) (xy 287.876956 -403.685302) (xy 287.891279 -403.699715) (xy 287.898974 -403.71852)
			(xy 287.899348 -403.728682) (xy 287.899348 -404.014686) (xy 287.899558 -404.021581) (xy 287.903302 -404.034853)
			(xy 287.906714 -404.040848) (xy 287.923071 -404.069193) (xy 287.948816 -404.129362) (xy 287.966242 -404.192444)
			(xy 287.975034 -404.257296) (xy 287.975031 -404.322741) (xy 287.966235 -404.387593) (xy 287.948804 -404.450674)
			(xy 287.923054 -404.51084) (xy 287.906714 -404.539196) (xy 287.903356 -404.545214) (xy 287.899616 -404.558472)
			(xy 287.899348 -404.565358) (xy 287.899348 -405.314658) (xy 287.899569 -405.321552) (xy 287.903306 -405.334824)
			(xy 287.906714 -405.34082) (xy 287.923048 -405.369178) (xy 287.948795 -405.429344) (xy 287.966223 -405.492424)
			(xy 287.975018 -405.557273) (xy 287.975018 -405.622716) (xy 287.966225 -405.687566) (xy 287.948798 -405.750646)
			(xy 287.923052 -405.810812) (xy 287.906714 -405.839168) (xy 287.903366 -405.845191) (xy 287.899619 -405.858445)
			(xy 287.899348 -405.86533) (xy 287.899348 -406.151334) (xy 287.898901 -406.161464) (xy 287.89116 -406.180189)
			(xy 287.876861 -406.194544) (xy 287.858168 -406.20236) (xy 287.84804 -406.202896) (xy 287.13176 -406.202896)
			(xy 287.121603 -406.202511) (xy 287.102849 -406.194701) (xy 287.088527 -406.180294) (xy 287.080829 -406.161494)
			(xy 287.080452 -406.151334) (xy 287.080452 -405.86533) (xy 287.080235 -405.858436) (xy 287.076496 -405.845164)
			(xy 287.073086 -405.839168) (xy 287.056742 -405.810815) (xy 287.030996 -405.750648) (xy 287.013569 -405.687567)
			(xy 287.004775 -405.622717) (xy 283.301948 -405.622717) (xy 283.301948 -406.722795) (xy 289.204655 -406.722795)
			(xy 289.204659 -406.65735) (xy 289.213457 -406.592498) (xy 289.230889 -406.529417) (xy 289.256639 -406.46925)
			(xy 289.27298 -406.440894) (xy 289.276295 -406.43487) (xy 289.279901 -406.421606) (xy 289.280092 -406.414732)
			(xy 289.280092 -405.665432) (xy 289.279889 -405.65856) (xy 289.276288 -405.645297) (xy 289.27298 -405.63927)
			(xy 289.256638 -405.610916) (xy 289.230892 -405.550749) (xy 289.213465 -405.487669) (xy 289.204671 -405.422818)
			(xy 289.204672 -405.357375) (xy 289.213466 -405.292525) (xy 289.230894 -405.229444) (xy 289.256641 -405.169278)
			(xy 289.27298 -405.140922) (xy 289.276286 -405.134893) (xy 289.279897 -405.121633) (xy 289.280092 -405.11476)
			(xy 289.280092 -404.828756) (xy 289.280486 -404.8186) (xy 289.288294 -404.799848) (xy 289.302699 -404.785527)
			(xy 289.321496 -404.777827) (xy 289.331654 -404.777448) (xy 290.047934 -404.777448) (xy 290.058064 -404.777899)
			(xy 290.076787 -404.785639) (xy 290.091143 -404.799936) (xy 290.098959 -404.818628) (xy 290.099496 -404.828756)
			(xy 290.099496 -405.11476) (xy 290.099704 -405.121632) (xy 290.103301 -405.134895) (xy 290.106608 -405.140922)
			(xy 290.122944 -405.169279) (xy 290.148691 -405.229445) (xy 290.166119 -405.292525) (xy 290.174914 -405.357375)
			(xy 290.174914 -405.422818) (xy 290.166121 -405.487668) (xy 290.148693 -405.550748) (xy 290.122947 -405.610914)
			(xy 290.116147 -405.622716) (xy 291.404825 -405.622716) (xy 291.404826 -405.557273) (xy 291.41362 -405.492423)
			(xy 291.431046 -405.429343) (xy 291.456791 -405.369176) (xy 291.473128 -405.34082) (xy 291.476438 -405.334793)
			(xy 291.480046 -405.321531) (xy 291.48024 -405.314658) (xy 291.48024 -404.565358) (xy 291.480021 -404.558487)
			(xy 291.476431 -404.545224) (xy 291.473128 -404.539196) (xy 291.45681 -404.510829) (xy 291.431065 -404.450665)
			(xy 291.413636 -404.387587) (xy 291.404841 -404.32274) (xy 291.404839 -404.257298) (xy 291.413629 -404.19245)
			(xy 291.431052 -404.129371) (xy 291.456792 -404.069204) (xy 291.473128 -404.040848) (xy 291.476463 -404.034833)
			(xy 291.480055 -404.021562) (xy 291.48024 -404.014686) (xy 291.48024 -403.728682) (xy 291.480718 -403.718523)
			(xy 291.488499 -403.699753) (xy 291.50287 -403.685388) (xy 291.521643 -403.677615) (xy 291.531802 -403.67712)
			(xy 292.248082 -403.67712) (xy 292.258236 -403.677648) (xy 292.277002 -403.685413) (xy 292.291367 -403.699768)
			(xy 292.299145 -403.718528) (xy 292.299644 -403.728682) (xy 292.299644 -404.014686) (xy 292.299836 -404.021559)
			(xy 292.303444 -404.034822) (xy 292.306756 -404.040848) (xy 292.323112 -404.069194) (xy 292.348855 -404.129363)
			(xy 292.366279 -404.192445) (xy 292.37507 -404.257297) (xy 292.375067 -404.322741) (xy 292.366272 -404.387592)
			(xy 292.348842 -404.450673) (xy 292.323095 -404.51084) (xy 292.306756 -404.539196) (xy 292.303447 -404.545224)
			(xy 292.299837 -404.558485) (xy 292.299644 -404.565358) (xy 292.299644 -405.314658) (xy 292.299846 -405.321531)
			(xy 292.303447 -405.334794) (xy 292.306756 -405.34082) (xy 292.323088 -405.369179) (xy 292.348833 -405.429345)
			(xy 292.36626 -405.492424) (xy 292.375054 -405.557274) (xy 292.375055 -405.622716) (xy 292.366262 -405.687565)
			(xy 292.348836 -405.750645) (xy 292.323093 -405.810812) (xy 292.306756 -405.839168) (xy 292.303457 -405.8452)
			(xy 292.299841 -405.858458) (xy 292.299644 -405.86533) (xy 292.299644 -406.151334) (xy 292.299194 -406.161496)
			(xy 292.291405 -406.18027) (xy 292.277026 -406.194634) (xy 292.258245 -406.202404) (xy 292.248082 -406.202896)
			(xy 291.531802 -406.202896) (xy 291.521649 -406.202366) (xy 291.502886 -406.194598) (xy 291.488522 -406.180244)
			(xy 291.480741 -406.161487) (xy 291.48024 -406.151334) (xy 291.48024 -405.86533) (xy 291.480032 -405.858458)
			(xy 291.476434 -405.845195) (xy 291.473128 -405.839168) (xy 291.456786 -405.810815) (xy 291.431043 -405.750647)
			(xy 291.413618 -405.687566) (xy 291.404825 -405.622716) (xy 290.116147 -405.622716) (xy 290.106608 -405.63927)
			(xy 290.103304 -405.6453) (xy 290.099692 -405.65856) (xy 290.099496 -405.665432) (xy 290.099496 -406.414732)
			(xy 290.099676 -406.421606) (xy 290.103292 -406.434869) (xy 290.106608 -406.440894) (xy 290.12292 -406.469265)
			(xy 290.148669 -406.529427) (xy 290.1661 -406.592504) (xy 290.174898 -406.657352) (xy 290.174901 -406.722793)
			(xy 290.174901 -406.722795) (xy 293.604705 -406.722795) (xy 293.604709 -406.65735) (xy 293.613506 -406.592499)
			(xy 293.630936 -406.529418) (xy 293.656683 -406.46925) (xy 293.673022 -406.440894) (xy 293.676386 -406.434879)
			(xy 293.680122 -406.421619) (xy 293.680388 -406.414732) (xy 293.680388 -405.665432) (xy 293.680144 -405.658541)
			(xy 293.676409 -405.645275) (xy 293.673022 -405.63927) (xy 293.656682 -405.610916) (xy 293.630939 -405.550748)
			(xy 293.613514 -405.487668) (xy 293.604721 -405.422818) (xy 293.604722 -405.357375) (xy 293.613515 -405.292525)
			(xy 293.630941 -405.229445) (xy 293.656685 -405.169278) (xy 293.673022 -405.140922) (xy 293.676376 -405.134902)
			(xy 293.680118 -405.121646) (xy 293.680388 -405.11476) (xy 293.680388 -404.828756) (xy 293.680849 -404.818646)
			(xy 293.688599 -404.799969) (xy 293.702903 -404.785676) (xy 293.721586 -404.777941) (xy 293.731696 -404.777448)
			(xy 294.447976 -404.777448) (xy 294.458077 -404.778003) (xy 294.476745 -404.785723) (xy 294.491038 -404.799998)
			(xy 294.498783 -404.818656) (xy 294.499284 -404.828756) (xy 294.499284 -405.11476) (xy 294.4995 -405.121654)
			(xy 294.50324 -405.134926) (xy 294.50665 -405.140922) (xy 294.522984 -405.16928) (xy 294.548729 -405.229446)
			(xy 294.566156 -405.292526) (xy 294.57495 -405.357375) (xy 294.57495 -405.422818) (xy 294.566158 -405.487667)
			(xy 294.548731 -405.550747) (xy 294.522987 -405.610914) (xy 294.516187 -405.622717) (xy 295.804862 -405.622717)
			(xy 295.804862 -405.557273) (xy 295.813657 -405.492423) (xy 295.831085 -405.429342) (xy 295.856831 -405.369176)
			(xy 295.87317 -405.34082) (xy 295.876529 -405.334802) (xy 295.880268 -405.321544) (xy 295.880536 -405.314658)
			(xy 295.880536 -404.565358) (xy 295.880311 -404.558465) (xy 295.876577 -404.545192) (xy 295.87317 -404.539196)
			(xy 295.85685 -404.51083) (xy 295.831103 -404.450666) (xy 295.813673 -404.387588) (xy 295.804878 -404.32274)
			(xy 295.804875 -404.257298) (xy 295.813666 -404.192449) (xy 295.831091 -404.12937) (xy 295.856833 -404.069204)
			(xy 295.87317 -404.040848) (xy 295.876554 -404.034843) (xy 295.880277 -404.021575) (xy 295.880536 -404.014686)
			(xy 295.880536 -403.728682) (xy 295.881011 -403.718555) (xy 295.888744 -403.699834) (xy 295.903034 -403.685478)
			(xy 295.921719 -403.677659) (xy 295.931844 -403.67712) (xy 296.648124 -403.67712) (xy 296.658282 -403.677502)
			(xy 296.677039 -403.685309) (xy 296.691362 -403.699718) (xy 296.699058 -403.718521) (xy 296.699432 -403.728682)
			(xy 296.699432 -404.014686) (xy 296.699666 -404.021577) (xy 296.703407 -404.034843) (xy 296.706798 -404.040848)
			(xy 296.723153 -404.069194) (xy 296.748893 -404.129364) (xy 296.766316 -404.192446) (xy 296.775106 -404.257297)
			(xy 296.775103 -404.322741) (xy 296.766309 -404.387591) (xy 296.748881 -404.450672) (xy 296.723136 -404.510839)
			(xy 296.706798 -404.539196) (xy 296.703439 -404.545214) (xy 296.6997 -404.558472) (xy 296.699432 -404.565358)
			(xy 296.699432 -405.314658) (xy 296.699655 -405.321552) (xy 296.703391 -405.334823) (xy 296.706798 -405.34082)
			(xy 296.723129 -405.369179) (xy 296.748872 -405.429346) (xy 296.766297 -405.492425) (xy 296.77509 -405.557274)
			(xy 296.775091 -405.622716) (xy 296.766299 -405.687565) (xy 296.748875 -405.750645) (xy 296.723134 -405.810811)
			(xy 296.706798 -405.839168) (xy 296.703449 -405.845191) (xy 296.699703 -405.858445) (xy 296.699432 -405.86533)
			(xy 296.699432 -406.151334) (xy 296.699001 -406.161466) (xy 296.691256 -406.180194) (xy 296.676953 -406.19455)
			(xy 296.658254 -406.202363) (xy 296.648124 -406.202896) (xy 295.931844 -406.202896) (xy 295.921692 -406.202442)
			(xy 295.90294 -406.19466) (xy 295.888615 -406.180273) (xy 295.880915 -406.161487) (xy 295.880536 -406.151334)
			(xy 295.880536 -405.86533) (xy 295.880322 -405.858436) (xy 295.876581 -405.845164) (xy 295.87317 -405.839168)
			(xy 295.856827 -405.810815) (xy 295.831082 -405.750648) (xy 295.813655 -405.687567) (xy 295.804862 -405.622717)
			(xy 294.516187 -405.622717) (xy 294.50665 -405.63927) (xy 294.503297 -405.64529) (xy 294.499554 -405.658547)
			(xy 294.499284 -405.665432) (xy 294.499284 -406.414732) (xy 294.499511 -406.421625) (xy 294.503243 -406.434897)
			(xy 294.50665 -406.440894) (xy 294.522961 -406.469265) (xy 294.548708 -406.529428) (xy 294.566137 -406.592505)
			(xy 294.574934 -406.657352) (xy 294.574938 -406.722793) (xy 294.574938 -406.722795) (xy 298.004742 -406.722795)
			(xy 298.004745 -406.65735) (xy 298.013543 -406.592498) (xy 298.030974 -406.529417) (xy 298.056724 -406.46925)
			(xy 298.073064 -406.440894) (xy 298.076378 -406.434869) (xy 298.079984 -406.421606) (xy 298.080176 -406.414732)
			(xy 298.080176 -405.665432) (xy 298.079975 -405.658559) (xy 298.076373 -405.645297) (xy 298.073064 -405.63927)
			(xy 298.056722 -405.610916) (xy 298.030978 -405.550749) (xy 298.013551 -405.487668) (xy 298.004758 -405.422818)
			(xy 298.004758 -405.357375) (xy 298.013552 -405.292525) (xy 298.03098 -405.229444) (xy 298.056726 -405.169278)
			(xy 298.073064 -405.140922) (xy 298.076368 -405.134892) (xy 298.079981 -405.121632) (xy 298.080176 -405.11476)
			(xy 298.080176 -404.828756) (xy 298.080585 -404.818602) (xy 298.088391 -404.799853) (xy 298.102791 -404.785532)
			(xy 298.121582 -404.77783) (xy 298.131738 -404.777448) (xy 298.848018 -404.777448) (xy 298.858147 -404.777912)
			(xy 298.87687 -404.785647) (xy 298.891226 -404.79994) (xy 298.899043 -404.818629) (xy 298.89958 -404.828756)
			(xy 298.89958 -405.11476) (xy 298.89979 -405.121632) (xy 298.903386 -405.134895) (xy 298.906692 -405.140922)
			(xy 298.923025 -405.16928) (xy 298.948768 -405.229447) (xy 298.966193 -405.292527) (xy 298.974986 -405.357375)
			(xy 298.974987 -405.422818) (xy 298.966195 -405.487667) (xy 298.94877 -405.550747) (xy 298.923028 -405.610914)
			(xy 298.916228 -405.622717) (xy 300.204651 -405.622717) (xy 300.204652 -405.557273) (xy 300.213446 -405.492423)
			(xy 300.230874 -405.429343) (xy 300.25662 -405.369176) (xy 300.272958 -405.34082) (xy 300.276316 -405.334802)
			(xy 300.280055 -405.321544) (xy 300.280324 -405.314658) (xy 300.280324 -404.565358) (xy 300.2801 -404.558464)
			(xy 300.276366 -404.545192) (xy 300.272958 -404.539196) (xy 300.256639 -404.51083) (xy 300.230892 -404.450666)
			(xy 300.213463 -404.387588) (xy 300.204667 -404.32274) (xy 300.204665 -404.257298) (xy 300.213455 -404.192449)
			(xy 300.23088 -404.12937) (xy 300.256622 -404.069204) (xy 300.272958 -404.040848) (xy 300.276341 -404.034842)
			(xy 300.280065 -404.021575) (xy 300.280324 -404.014686) (xy 300.280324 -403.728682) (xy 300.280811 -403.718556)
			(xy 300.288542 -403.699837) (xy 300.302828 -403.685482) (xy 300.321509 -403.677661) (xy 300.331632 -403.67712)
			(xy 301.047912 -403.67712) (xy 301.058069 -403.677512) (xy 301.076826 -403.685315) (xy 301.09115 -403.699721)
			(xy 301.098846 -403.718522) (xy 301.09922 -403.728682) (xy 301.09922 -404.014686) (xy 301.099456 -404.021577)
			(xy 301.103196 -404.034843) (xy 301.106586 -404.040848) (xy 301.122941 -404.069194) (xy 301.148682 -404.129363)
			(xy 301.166106 -404.192446) (xy 301.174896 -404.257297) (xy 301.174894 -404.290022) (xy 304.603666 -404.290022)
			(xy 304.607657 -404.227855) (xy 304.619566 -404.166708) (xy 304.639195 -404.107587) (xy 304.666224 -404.051461)
			(xy 304.700208 -403.999252) (xy 304.74059 -403.951817) (xy 304.786706 -403.909936) (xy 304.837798 -403.874296)
			(xy 304.893029 -403.845482) (xy 304.951491 -403.823968) (xy 305.012225 -403.810106) (xy 305.074232 -403.804124)
			(xy 305.136495 -403.80612) (xy 305.197992 -403.816063) (xy 305.257713 -403.833787) (xy 305.314676 -403.859004)
			(xy 305.367947 -403.891297) (xy 305.416652 -403.930137) (xy 305.459989 -403.974887) (xy 305.497249 -404.024811)
			(xy 305.527818 -404.07909) (xy 305.551196 -404.136833) (xy 305.566997 -404.197091) (xy 305.574963 -404.258874)
			(xy 305.575462 -404.290022) (xy 305.574963 -404.32117) (xy 305.566997 -404.382953) (xy 305.551196 -404.443211)
			(xy 305.527818 -404.500954) (xy 305.497249 -404.555233) (xy 305.459989 -404.605157) (xy 305.416652 -404.649907)
			(xy 305.367947 -404.688747) (xy 305.314676 -404.72104) (xy 305.257713 -404.746257) (xy 305.197992 -404.763981)
			(xy 305.136495 -404.773924) (xy 305.074232 -404.77592) (xy 305.012225 -404.769938) (xy 304.951491 -404.756076)
			(xy 304.893029 -404.734562) (xy 304.837798 -404.705748) (xy 304.786706 -404.670108) (xy 304.74059 -404.628227)
			(xy 304.700208 -404.580792) (xy 304.666224 -404.528583) (xy 304.639195 -404.472457) (xy 304.619566 -404.413336)
			(xy 304.607657 -404.352189) (xy 304.603666 -404.290022) (xy 301.174894 -404.290022) (xy 301.174893 -404.322741)
			(xy 301.166098 -404.387591) (xy 301.14867 -404.450672) (xy 301.122924 -404.51084) (xy 301.106586 -404.539196)
			(xy 301.103226 -404.545213) (xy 301.099487 -404.558472) (xy 301.09922 -404.565358) (xy 301.09922 -405.314658)
			(xy 301.099467 -405.321548) (xy 301.1032 -405.334814) (xy 301.106586 -405.34082) (xy 301.122918 -405.369179)
			(xy 301.148661 -405.429346) (xy 301.166087 -405.492425) (xy 301.17488 -405.557274) (xy 301.17488 -405.622716)
			(xy 301.166089 -405.687565) (xy 301.148664 -405.750645) (xy 301.122922 -405.810812) (xy 301.106586 -405.839168)
			(xy 301.103236 -405.84519) (xy 301.099491 -405.858445) (xy 301.09922 -405.86533) (xy 301.09922 -406.151334)
			(xy 301.0988 -406.161468) (xy 301.091054 -406.180197) (xy 301.076747 -406.194554) (xy 301.058044 -406.202365)
			(xy 301.047912 -406.202896) (xy 300.331632 -406.202896) (xy 300.321479 -406.202452) (xy 300.302727 -406.194667)
			(xy 300.288402 -406.180276) (xy 300.280702 -406.161488) (xy 300.280324 -406.151334) (xy 300.280324 -405.86533)
			(xy 300.280111 -405.858436) (xy 300.276369 -405.845163) (xy 300.272958 -405.839168) (xy 300.256615 -405.810815)
			(xy 300.230871 -405.750648) (xy 300.213444 -405.687567) (xy 300.204651 -405.622717) (xy 298.916228 -405.622717)
			(xy 298.906692 -405.63927) (xy 298.903387 -405.6453) (xy 298.899775 -405.65856) (xy 298.89958 -405.665432)
			(xy 298.89958 -406.414732) (xy 298.899762 -406.421606) (xy 298.903377 -406.434869) (xy 298.906692 -406.440894)
			(xy 298.923001 -406.469265) (xy 298.948746 -406.529429) (xy 298.966174 -406.592506) (xy 298.97497 -406.657352)
			(xy 298.974974 -406.722793) (xy 298.974974 -406.722795) (xy 302.404792 -406.722795) (xy 302.404795 -406.65735)
			(xy 302.413592 -406.592499) (xy 302.431021 -406.529418) (xy 302.456768 -406.469251) (xy 302.473106 -406.440894)
			(xy 302.476469 -406.434878) (xy 302.480206 -406.421619) (xy 302.480472 -406.414732) (xy 302.480472 -405.665432)
			(xy 302.48023 -405.658541) (xy 302.476494 -405.645275) (xy 302.473106 -405.63927) (xy 302.456766 -405.610915)
			(xy 302.431024 -405.550748) (xy 302.4136 -405.487668) (xy 302.404808 -405.422818) (xy 302.404808 -405.357375)
			(xy 302.413601 -405.292526) (xy 302.431027 -405.229446) (xy 302.456769 -405.169279) (xy 302.473106 -405.140922)
			(xy 302.476459 -405.134901) (xy 302.480202 -405.121645) (xy 302.480472 -405.11476) (xy 302.480472 -404.828756)
			(xy 302.480948 -404.818648) (xy 302.488695 -404.799974) (xy 302.502994 -404.785682) (xy 302.521672 -404.777944)
			(xy 302.53178 -404.777448) (xy 303.24806 -404.777448) (xy 303.25816 -404.778017) (xy 303.276827 -404.785732)
			(xy 303.291121 -404.800002) (xy 303.298867 -404.818657) (xy 303.299368 -404.828756) (xy 303.299368 -405.11476)
			(xy 303.299586 -405.121654) (xy 303.303324 -405.134926) (xy 303.306734 -405.140922) (xy 303.323069 -405.16928)
			(xy 303.348814 -405.229446) (xy 303.366242 -405.292526) (xy 303.375036 -405.357375) (xy 303.375037 -405.422818)
			(xy 303.366244 -405.487668) (xy 303.348817 -405.550748) (xy 303.332024 -405.589994) (xy 304.603666 -405.589994)
			(xy 304.607657 -405.527827) (xy 304.619566 -405.46668) (xy 304.639195 -405.407559) (xy 304.666224 -405.351433)
			(xy 304.700208 -405.299224) (xy 304.74059 -405.251789) (xy 304.786706 -405.209908) (xy 304.837798 -405.174268)
			(xy 304.893029 -405.145454) (xy 304.951491 -405.12394) (xy 305.012225 -405.110078) (xy 305.074232 -405.104096)
			(xy 305.136495 -405.106092) (xy 305.197992 -405.116035) (xy 305.257713 -405.133759) (xy 305.314676 -405.158976)
			(xy 305.367947 -405.191269) (xy 305.416652 -405.230109) (xy 305.459989 -405.274859) (xy 305.497249 -405.324783)
			(xy 305.527818 -405.379062) (xy 305.532285 -405.390096) (xy 306.803814 -405.390096) (xy 306.807805 -405.327929)
			(xy 306.819714 -405.266782) (xy 306.839343 -405.207661) (xy 306.866372 -405.151535) (xy 306.900356 -405.099326)
			(xy 306.940738 -405.051891) (xy 306.986854 -405.01001) (xy 307.037946 -404.97437) (xy 307.093177 -404.945556)
			(xy 307.151639 -404.924042) (xy 307.212373 -404.91018) (xy 307.27438 -404.904198) (xy 307.336643 -404.906194)
			(xy 307.39814 -404.916137) (xy 307.457861 -404.933861) (xy 307.514824 -404.959078) (xy 307.568095 -404.991371)
			(xy 307.6168 -405.030211) (xy 307.660137 -405.074961) (xy 307.697397 -405.124885) (xy 307.727966 -405.179164)
			(xy 307.751344 -405.236907) (xy 307.767145 -405.297165) (xy 307.775111 -405.358948) (xy 307.77561 -405.390096)
			(xy 307.775111 -405.421244) (xy 307.767145 -405.483027) (xy 307.751344 -405.543285) (xy 307.727966 -405.601028)
			(xy 307.697397 -405.655307) (xy 307.660137 -405.705231) (xy 307.6168 -405.749981) (xy 307.568095 -405.788821)
			(xy 307.514824 -405.821114) (xy 307.457861 -405.846331) (xy 307.39814 -405.864055) (xy 307.336643 -405.873998)
			(xy 307.27438 -405.875994) (xy 307.212373 -405.870012) (xy 307.151639 -405.85615) (xy 307.093177 -405.834636)
			(xy 307.037946 -405.805822) (xy 306.986854 -405.770182) (xy 306.940738 -405.728301) (xy 306.900356 -405.680866)
			(xy 306.866372 -405.628657) (xy 306.839343 -405.572531) (xy 306.819714 -405.51341) (xy 306.807805 -405.452263)
			(xy 306.803814 -405.390096) (xy 305.532285 -405.390096) (xy 305.551196 -405.436805) (xy 305.566997 -405.497063)
			(xy 305.574963 -405.558846) (xy 305.575462 -405.589994) (xy 305.574963 -405.621142) (xy 305.566997 -405.682925)
			(xy 305.551196 -405.743183) (xy 305.527818 -405.800926) (xy 305.497249 -405.855205) (xy 305.459989 -405.905129)
			(xy 305.416652 -405.949879) (xy 305.367947 -405.988719) (xy 305.314676 -406.021012) (xy 305.257713 -406.046229)
			(xy 305.197992 -406.063953) (xy 305.136495 -406.073896) (xy 305.074232 -406.075892) (xy 305.012225 -406.06991)
			(xy 304.951491 -406.056048) (xy 304.893029 -406.034534) (xy 304.837798 -406.00572) (xy 304.786706 -405.97008)
			(xy 304.74059 -405.928199) (xy 304.700208 -405.880764) (xy 304.666224 -405.828555) (xy 304.639195 -405.772429)
			(xy 304.619566 -405.713308) (xy 304.607657 -405.652161) (xy 304.603666 -405.589994) (xy 303.332024 -405.589994)
			(xy 303.323072 -405.610914) (xy 303.306734 -405.63927) (xy 303.303379 -405.64529) (xy 303.299638 -405.658546)
			(xy 303.299368 -405.665432) (xy 303.299368 -406.414732) (xy 303.299597 -406.421625) (xy 303.303328 -406.434897)
			(xy 303.306734 -406.440894) (xy 303.323045 -406.469265) (xy 303.348793 -406.529428) (xy 303.366223 -406.592505)
			(xy 303.37502 -406.657352) (xy 303.375022 -406.690068) (xy 306.803814 -406.690068) (xy 306.807805 -406.627901)
			(xy 306.819714 -406.566754) (xy 306.839343 -406.507633) (xy 306.866372 -406.451507) (xy 306.900356 -406.399298)
			(xy 306.940738 -406.351863) (xy 306.986854 -406.309982) (xy 307.037946 -406.274342) (xy 307.093177 -406.245528)
			(xy 307.151639 -406.224014) (xy 307.212373 -406.210152) (xy 307.27438 -406.20417) (xy 307.336643 -406.206166)
			(xy 307.39814 -406.216109) (xy 307.457861 -406.233833) (xy 307.514824 -406.25905) (xy 307.568095 -406.291343)
			(xy 307.6168 -406.330183) (xy 307.660137 -406.374933) (xy 307.697397 -406.424857) (xy 307.727966 -406.479136)
			(xy 307.751344 -406.536879) (xy 307.767145 -406.597137) (xy 307.775111 -406.65892) (xy 307.77561 -406.690068)
			(xy 307.775111 -406.721216) (xy 307.767145 -406.782999) (xy 307.751344 -406.843257) (xy 307.727966 -406.901)
			(xy 307.697397 -406.955279) (xy 307.660137 -407.005203) (xy 307.6168 -407.049953) (xy 307.568095 -407.088793)
			(xy 307.514824 -407.121086) (xy 307.457861 -407.146303) (xy 307.39814 -407.164027) (xy 307.336643 -407.17397)
			(xy 307.27438 -407.175966) (xy 307.212373 -407.169984) (xy 307.151639 -407.156122) (xy 307.093177 -407.134608)
			(xy 307.037946 -407.105794) (xy 306.986854 -407.070154) (xy 306.940738 -407.028273) (xy 306.900356 -406.980838)
			(xy 306.866372 -406.928629) (xy 306.839343 -406.872503) (xy 306.819714 -406.813382) (xy 306.807805 -406.752235)
			(xy 306.803814 -406.690068) (xy 303.375022 -406.690068) (xy 303.375024 -406.722793) (xy 303.366234 -406.787641)
			(xy 303.348811 -406.85072) (xy 303.32307 -406.910886) (xy 303.306734 -406.939242) (xy 303.303354 -406.945249)
			(xy 303.299629 -406.958516) (xy 303.299368 -406.965404) (xy 303.299368 -407.251408) (xy 303.29899 -407.261535)
			(xy 303.291233 -407.280245) (xy 303.276904 -407.29456) (xy 303.258187 -407.302299) (xy 303.24806 -407.302716)
			(xy 302.53178 -407.302716) (xy 302.521672 -407.302232) (xy 302.502996 -407.294491) (xy 302.488703 -407.280194)
			(xy 302.480966 -407.261516) (xy 302.480472 -407.251408) (xy 302.480472 -406.965404) (xy 302.480241 -406.958512)
			(xy 302.476498 -406.945246) (xy 302.473106 -406.939242) (xy 302.456743 -406.9109) (xy 302.431003 -406.85073)
			(xy 302.413581 -406.787647) (xy 302.404792 -406.722795) (xy 298.974974 -406.722795) (xy 298.966185 -406.78764)
			(xy 298.948764 -406.850719) (xy 298.923026 -406.910886) (xy 298.906692 -406.939242) (xy 298.903362 -406.945259)
			(xy 298.899766 -406.958529) (xy 298.89958 -406.965404) (xy 298.89958 -407.251408) (xy 298.899184 -407.261565)
			(xy 298.891382 -407.280321) (xy 298.876978 -407.294645) (xy 298.858177 -407.302341) (xy 298.848018 -407.302716)
			(xy 298.131738 -407.302716) (xy 298.121608 -407.302241) (xy 298.10288 -407.294517) (xy 298.088521 -407.280227)
			(xy 298.080708 -407.261535) (xy 298.080176 -407.251408) (xy 298.080176 -406.965404) (xy 298.079985 -406.958531)
			(xy 298.076376 -406.945268) (xy 298.073064 -406.939242) (xy 298.056699 -406.910901) (xy 298.030956 -406.850731)
			(xy 298.013532 -406.787648) (xy 298.004742 -406.722795) (xy 294.574938 -406.722795) (xy 294.566148 -406.787641)
			(xy 294.548726 -406.85072) (xy 294.522986 -406.910886) (xy 294.50665 -406.939242) (xy 294.503271 -406.94525)
			(xy 294.499545 -406.958516) (xy 294.499284 -406.965404) (xy 294.499284 -407.251408) (xy 294.49889 -407.261533)
			(xy 294.491136 -407.28024) (xy 294.476813 -407.294554) (xy 294.458101 -407.302296) (xy 294.447976 -407.302716)
			(xy 293.731696 -407.302716) (xy 293.721589 -407.302218) (xy 293.702914 -407.294482) (xy 293.68862 -407.28019)
			(xy 293.680882 -407.261515) (xy 293.680388 -407.251408) (xy 293.680388 -406.965404) (xy 293.680155 -406.958513)
			(xy 293.676413 -406.945247) (xy 293.673022 -406.939242) (xy 293.656658 -406.910901) (xy 293.630918 -406.85073)
			(xy 293.613495 -406.787647) (xy 293.604705 -406.722795) (xy 290.174901 -406.722795) (xy 290.166112 -406.787642)
			(xy 290.148687 -406.850721) (xy 290.122945 -406.910886) (xy 290.106608 -406.939242) (xy 290.103279 -406.94526)
			(xy 290.099682 -406.958529) (xy 290.099496 -406.965404) (xy 290.099496 -407.251408) (xy 290.099085 -407.261563)
			(xy 290.091286 -407.280316) (xy 290.076886 -407.29464) (xy 290.058091 -407.302338) (xy 290.047934 -407.302716)
			(xy 289.331654 -407.302716) (xy 289.321519 -407.30231) (xy 289.302788 -407.294559) (xy 289.288432 -407.280248)
			(xy 289.280622 -407.261541) (xy 289.280092 -407.251408) (xy 289.280092 -406.965404) (xy 289.2799 -406.958531)
			(xy 289.276292 -406.945268) (xy 289.27298 -406.939242) (xy 289.256614 -406.910901) (xy 289.230871 -406.850731)
			(xy 289.213446 -406.787648) (xy 289.204655 -406.722795) (xy 283.301948 -406.722795) (xy 283.301948 -409.522892)
			(xy 287.004758 -409.522892) (xy 287.004762 -409.457446) (xy 287.013561 -409.392594) (xy 287.030994 -409.329513)
			(xy 287.056745 -409.269346) (xy 287.073086 -409.24099) (xy 287.076449 -409.234974) (xy 287.080186 -409.221715)
			(xy 287.080452 -409.214828) (xy 287.080452 -408.465528) (xy 287.080236 -408.458634) (xy 287.076496 -408.445362)
			(xy 287.073086 -408.439366) (xy 287.05674 -408.411014) (xy 287.030995 -408.350847) (xy 287.013567 -408.287766)
			(xy 287.004774 -408.222915) (xy 287.004775 -408.157471) (xy 287.01357 -408.092621) (xy 287.030999 -408.02954)
			(xy 287.056747 -407.969374) (xy 287.073086 -407.941018) (xy 287.076439 -407.934997) (xy 287.080183 -407.921741)
			(xy 287.080452 -407.914856) (xy 287.080452 -407.628852) (xy 287.080945 -407.618746) (xy 287.088689 -407.600076)
			(xy 287.102983 -407.585785) (xy 287.121654 -407.578043) (xy 287.13176 -407.577544) (xy 287.84804 -407.577544)
			(xy 287.858144 -407.578051) (xy 287.876813 -407.585791) (xy 287.891104 -407.600081) (xy 287.898847 -407.618748)
			(xy 287.899348 -407.628852) (xy 287.899348 -407.914856) (xy 287.89957 -407.92175) (xy 287.903306 -407.935022)
			(xy 287.906714 -407.941018) (xy 287.923046 -407.969377) (xy 287.948793 -408.029543) (xy 287.966222 -408.092622)
			(xy 287.975017 -408.157472) (xy 287.975018 -408.222915) (xy 287.966225 -408.287764) (xy 287.948798 -408.350844)
			(xy 287.923052 -408.41101) (xy 287.906714 -408.439366) (xy 287.903367 -408.44539) (xy 287.89962 -408.458643)
			(xy 287.899348 -408.465528) (xy 287.899348 -409.214828) (xy 287.899581 -409.221721) (xy 287.903309 -409.234993)
			(xy 287.906714 -409.24099) (xy 287.923022 -409.269363) (xy 287.948772 -409.329525) (xy 287.966203 -409.392602)
			(xy 287.975001 -409.457449) (xy 287.975005 -409.52289) (xy 287.966215 -409.587738) (xy 287.948792 -409.650817)
			(xy 287.92305 -409.710982) (xy 287.906714 -409.739338) (xy 287.903341 -409.745349) (xy 287.89961 -409.758612)
			(xy 287.899348 -409.7655) (xy 287.899348 -410.051504) (xy 287.898819 -410.061607) (xy 287.891089 -410.080276)
			(xy 287.876806 -410.094569) (xy 287.858143 -410.102312) (xy 287.84804 -410.102812) (xy 287.13176 -410.102812)
			(xy 287.12165 -410.102348) (xy 287.102973 -410.094599) (xy 287.08868 -410.080296) (xy 287.080945 -410.061614)
			(xy 287.080452 -410.051504) (xy 287.080452 -409.7655) (xy 287.080247 -409.758605) (xy 287.076499 -409.745333)
			(xy 287.073086 -409.739338) (xy 287.056717 -409.710999) (xy 287.030973 -409.650829) (xy 287.013548 -409.587745)
			(xy 287.004758 -409.522892) (xy 283.301948 -409.522892) (xy 283.301948 -410.622709) (xy 289.204665 -410.622709)
			(xy 289.204666 -410.557264) (xy 289.213462 -410.492413) (xy 289.230892 -410.429332) (xy 289.25664 -410.369166)
			(xy 289.27298 -410.34081) (xy 289.27629 -410.334783) (xy 289.279899 -410.321521) (xy 289.280092 -410.314648)
			(xy 289.280092 -409.565348) (xy 289.279883 -409.558476) (xy 289.276286 -409.545213) (xy 289.27298 -409.539186)
			(xy 289.256652 -409.510825) (xy 289.230905 -409.45066) (xy 289.213475 -409.387581) (xy 289.20468 -409.322732)
			(xy 289.204679 -409.257289) (xy 289.213471 -409.19244) (xy 289.230898 -409.12936) (xy 289.256642 -409.069194)
			(xy 289.27298 -409.040838) (xy 289.27628 -409.034806) (xy 289.279895 -409.021548) (xy 289.280092 -409.014676)
			(xy 289.280092 -408.728672) (xy 289.280498 -408.718517) (xy 289.288302 -408.699766) (xy 289.302703 -408.685443)
			(xy 289.321497 -408.677743) (xy 289.331654 -408.677364) (xy 290.047934 -408.677364) (xy 290.058066 -408.677799)
			(xy 290.076792 -408.685543) (xy 290.091148 -408.699845) (xy 290.098962 -408.718542) (xy 290.099496 -408.728672)
			(xy 290.099496 -409.014676) (xy 290.099697 -409.021549) (xy 290.103299 -409.034811) (xy 290.106608 -409.040838)
			(xy 290.122957 -409.069188) (xy 290.148703 -409.129356) (xy 290.16613 -409.192437) (xy 290.174923 -409.257288)
			(xy 290.174921 -409.322733) (xy 290.166126 -409.387583) (xy 290.148696 -409.450664) (xy 290.122948 -409.51083)
			(xy 290.115997 -409.522892) (xy 291.404808 -409.522892) (xy 291.404813 -409.457446) (xy 291.41361 -409.392595)
			(xy 291.43104 -409.329514) (xy 291.456789 -409.269346) (xy 291.473128 -409.24099) (xy 291.476448 -409.234968)
			(xy 291.48005 -409.221702) (xy 291.48024 -409.214828) (xy 291.48024 -408.465528) (xy 291.480032 -408.458656)
			(xy 291.476434 -408.445393) (xy 291.473128 -408.439366) (xy 291.456784 -408.411013) (xy 291.431042 -408.350846)
			(xy 291.413616 -408.287765) (xy 291.404824 -408.222915) (xy 291.404825 -408.157471) (xy 291.413619 -408.092622)
			(xy 291.431046 -408.029541) (xy 291.45679 -407.969374) (xy 291.473128 -407.941018) (xy 291.476438 -407.934991)
			(xy 291.480046 -407.921729) (xy 291.48024 -407.914856) (xy 291.48024 -407.628852) (xy 291.480583 -407.61869)
			(xy 291.488402 -407.599929) (xy 291.502823 -407.585606) (xy 291.521637 -407.577915) (xy 291.531802 -407.577544)
			(xy 292.248082 -407.577544) (xy 292.258208 -407.578041) (xy 292.27693 -407.585764) (xy 292.291287 -407.600047)
			(xy 292.299106 -407.618729) (xy 292.299644 -407.628852) (xy 292.299644 -407.914856) (xy 292.299847 -407.921728)
			(xy 292.303447 -407.934991) (xy 292.306756 -407.941018) (xy 292.323087 -407.969378) (xy 292.348832 -408.029544)
			(xy 292.366259 -408.092623) (xy 292.375053 -408.157472) (xy 292.375054 -408.222914) (xy 292.366262 -408.287764)
			(xy 292.348836 -408.350843) (xy 292.323093 -408.41101) (xy 292.306756 -408.439366) (xy 292.303458 -408.445399)
			(xy 292.299841 -408.458656) (xy 292.299644 -408.465528) (xy 292.299644 -409.214828) (xy 292.29982 -409.221703)
			(xy 292.303439 -409.234965) (xy 292.306756 -409.24099) (xy 292.323063 -409.269363) (xy 292.34881 -409.329526)
			(xy 292.36624 -409.392602) (xy 292.375037 -409.457449) (xy 292.375041 -409.522889) (xy 292.366252 -409.587737)
			(xy 292.34883 -409.650816) (xy 292.323091 -409.710982) (xy 292.306756 -409.739338) (xy 292.303432 -409.745358)
			(xy 292.299832 -409.758625) (xy 292.299644 -409.7655) (xy 292.299644 -410.051504) (xy 292.299182 -410.061653)
			(xy 292.291394 -410.080397) (xy 292.27701 -410.094718) (xy 292.258233 -410.102426) (xy 292.248082 -410.102812)
			(xy 291.531802 -410.102812) (xy 291.521682 -410.102273) (xy 291.502971 -410.094556) (xy 291.488616 -410.080286)
			(xy 291.480788 -410.061621) (xy 291.48024 -410.051504) (xy 291.48024 -409.7655) (xy 291.480043 -409.758627)
			(xy 291.476438 -409.745365) (xy 291.473128 -409.739338) (xy 291.45676 -409.710999) (xy 291.43102 -409.650828)
			(xy 291.413597 -409.587744) (xy 291.404808 -409.522892) (xy 290.115997 -409.522892) (xy 290.106608 -409.539186)
			(xy 290.103299 -409.545213) (xy 290.09969 -409.558475) (xy 290.099496 -409.565348) (xy 290.099496 -410.314648)
			(xy 290.099709 -410.32152) (xy 290.103303 -410.334782) (xy 290.106608 -410.34081) (xy 290.122933 -410.369173)
			(xy 290.148681 -410.429338) (xy 290.166111 -410.492416) (xy 290.174907 -410.557265) (xy 290.174909 -410.622708)
			(xy 293.604715 -410.622708) (xy 293.604716 -410.557264) (xy 293.613511 -410.492414) (xy 293.630939 -410.429334)
			(xy 293.656684 -410.369166) (xy 293.673022 -410.34081) (xy 293.67638 -410.334792) (xy 293.68012 -410.321534)
			(xy 293.680388 -410.314648) (xy 293.680388 -409.565348) (xy 293.680138 -409.558458) (xy 293.676407 -409.545192)
			(xy 293.673022 -409.539186) (xy 293.656695 -409.510824) (xy 293.630951 -409.450658) (xy 293.613524 -409.38758)
			(xy 293.604731 -409.322731) (xy 293.604729 -409.257289) (xy 293.61352 -409.192441) (xy 293.630945 -409.129361)
			(xy 293.656686 -409.069194) (xy 293.673022 -409.040838) (xy 293.676406 -409.034833) (xy 293.680129 -409.021565)
			(xy 293.680388 -409.014676) (xy 293.680388 -408.728672) (xy 293.680862 -408.718563) (xy 293.688606 -408.699886)
			(xy 293.702907 -408.685593) (xy 293.721587 -408.677857) (xy 293.731696 -408.677364) (xy 294.447976 -408.677364)
			(xy 294.458079 -408.677904) (xy 294.47675 -408.685627) (xy 294.491044 -408.699907) (xy 294.498786 -408.71857)
			(xy 294.499284 -408.728672) (xy 294.499284 -409.014676) (xy 294.499493 -409.021571) (xy 294.503237 -409.034843)
			(xy 294.50665 -409.040838) (xy 294.522998 -409.069188) (xy 294.548741 -409.129356) (xy 294.566167 -409.192438)
			(xy 294.574959 -409.257288) (xy 294.574958 -409.322732) (xy 294.566163 -409.387583) (xy 294.548735 -409.450663)
			(xy 294.522989 -409.51083) (xy 294.516039 -409.522892) (xy 295.804845 -409.522892) (xy 295.804849 -409.457446)
			(xy 295.813647 -409.392594) (xy 295.831079 -409.329513) (xy 295.856829 -409.269346) (xy 295.87317 -409.24099)
			(xy 295.876539 -409.234978) (xy 295.880271 -409.221715) (xy 295.880536 -409.214828) (xy 295.880536 -408.465528)
			(xy 295.880322 -408.458634) (xy 295.876581 -408.445362) (xy 295.87317 -408.439366) (xy 295.856825 -408.411014)
			(xy 295.83108 -408.350847) (xy 295.813653 -408.287766) (xy 295.80486 -408.222915) (xy 295.804861 -408.157471)
			(xy 295.813656 -408.092621) (xy 295.831085 -408.02954) (xy 295.856831 -407.969374) (xy 295.87317 -407.941018)
			(xy 295.87653 -407.935001) (xy 295.880268 -407.921742) (xy 295.880536 -407.914856) (xy 295.880536 -407.628852)
			(xy 295.880947 -407.618736) (xy 295.888707 -407.60005) (xy 295.903027 -407.585755) (xy 295.921727 -407.578029)
			(xy 295.931844 -407.577544) (xy 296.648124 -407.577544) (xy 296.658227 -407.578064) (xy 296.676895 -407.585799)
			(xy 296.691187 -407.600084) (xy 296.698931 -407.618749) (xy 296.699432 -407.628852) (xy 296.699432 -407.914856)
			(xy 296.699656 -407.921749) (xy 296.703391 -407.935021) (xy 296.706798 -407.941018) (xy 296.723127 -407.969378)
			(xy 296.74887 -408.029544) (xy 296.766296 -408.092624) (xy 296.775089 -408.157472) (xy 296.77509 -408.222914)
			(xy 296.766299 -408.287763) (xy 296.748875 -408.350843) (xy 296.723134 -408.411009) (xy 296.706798 -408.439366)
			(xy 296.703449 -408.445389) (xy 296.699703 -408.458643) (xy 296.699432 -408.465528) (xy 296.699432 -409.214828)
			(xy 296.699667 -409.221721) (xy 296.703394 -409.234993) (xy 296.706798 -409.24099) (xy 296.723104 -409.269363)
			(xy 296.748848 -409.329527) (xy 296.766277 -409.392603) (xy 296.775073 -409.457449) (xy 296.775077 -409.522889)
			(xy 296.766289 -409.587736) (xy 296.748869 -409.650815) (xy 296.723132 -409.710981) (xy 296.706798 -409.739338)
			(xy 296.703424 -409.745348) (xy 296.699694 -409.758612) (xy 296.699432 -409.7655) (xy 296.699432 -410.051504)
			(xy 296.698919 -410.061609) (xy 296.691186 -410.080281) (xy 296.676898 -410.094575) (xy 296.658229 -410.102315)
			(xy 296.648124 -410.102812) (xy 295.931844 -410.102812) (xy 295.921726 -410.102348) (xy 295.903026 -410.094617)
			(xy 295.88871 -410.080315) (xy 295.880961 -410.061622) (xy 295.880536 -410.051504) (xy 295.880536 -409.7655)
			(xy 295.880333 -409.758605) (xy 295.876584 -409.745333) (xy 295.87317 -409.739338) (xy 295.856801 -409.710999)
			(xy 295.831058 -409.650829) (xy 295.813634 -409.587745) (xy 295.804845 -409.522892) (xy 294.516039 -409.522892)
			(xy 294.50665 -409.539186) (xy 294.503291 -409.545204) (xy 294.499552 -409.558462) (xy 294.499284 -409.565348)
			(xy 294.499284 -410.314648) (xy 294.499505 -410.321542) (xy 294.503241 -410.334814) (xy 294.50665 -410.34081)
			(xy 294.522974 -410.369174) (xy 294.54872 -410.429338) (xy 294.566148 -410.492417) (xy 294.574943 -410.557265)
			(xy 294.574945 -410.622707) (xy 294.574945 -410.622708) (xy 298.004751 -410.622708) (xy 298.004753 -410.557264)
			(xy 298.013548 -410.492413) (xy 298.030977 -410.429333) (xy 298.056725 -410.369166) (xy 298.073064 -410.34081)
			(xy 298.076372 -410.334782) (xy 298.079982 -410.321521) (xy 298.080176 -410.314648) (xy 298.080176 -409.565348)
			(xy 298.079969 -409.558476) (xy 298.076371 -409.545213) (xy 298.073064 -409.539186) (xy 298.056736 -409.510824)
			(xy 298.03099 -409.450659) (xy 298.013561 -409.38758) (xy 298.004767 -409.322732) (xy 298.004765 -409.257289)
			(xy 298.013557 -409.19244) (xy 298.030983 -409.12936) (xy 298.056727 -409.069194) (xy 298.073064 -409.040838)
			(xy 298.076362 -409.034805) (xy 298.079979 -409.021548) (xy 298.080176 -409.014676) (xy 298.080176 -408.728672)
			(xy 298.080598 -408.718519) (xy 298.088398 -408.699771) (xy 298.102794 -408.685449) (xy 298.121583 -408.677746)
			(xy 298.131738 -408.677364) (xy 298.848018 -408.677364) (xy 298.858149 -408.677812) (xy 298.876875 -408.68555)
			(xy 298.891232 -408.699849) (xy 298.899046 -408.718543) (xy 298.89958 -408.728672) (xy 298.89958 -409.014676)
			(xy 298.899783 -409.021548) (xy 298.903384 -409.034811) (xy 298.906692 -409.040838) (xy 298.923039 -409.069189)
			(xy 298.94878 -409.129357) (xy 298.966204 -409.192438) (xy 298.974995 -409.257289) (xy 298.974994 -409.322732)
			(xy 298.9662 -409.387582) (xy 298.948773 -409.450662) (xy 298.923029 -409.510829) (xy 298.916079 -409.522892)
			(xy 300.204634 -409.522892) (xy 300.204638 -409.457446) (xy 300.213436 -409.392595) (xy 300.230868 -409.329513)
			(xy 300.256618 -409.269346) (xy 300.272958 -409.24099) (xy 300.276326 -409.234977) (xy 300.280059 -409.221715)
			(xy 300.280324 -409.214828) (xy 300.280324 -408.465528) (xy 300.280112 -408.458633) (xy 300.27637 -408.445361)
			(xy 300.272958 -408.439366) (xy 300.256613 -408.411014) (xy 300.230869 -408.350846) (xy 300.213443 -408.287765)
			(xy 300.20465 -408.222915) (xy 300.204651 -408.157471) (xy 300.213445 -408.092621) (xy 300.230874 -408.029541)
			(xy 300.25662 -407.969374) (xy 300.272958 -407.941018) (xy 300.276317 -407.935) (xy 300.280056 -407.921742)
			(xy 300.280324 -407.914856) (xy 300.280324 -407.628852) (xy 300.280747 -407.618737) (xy 300.288504 -407.600053)
			(xy 300.302821 -407.585759) (xy 300.321516 -407.578031) (xy 300.331632 -407.577544) (xy 301.047912 -407.577544)
			(xy 301.058015 -407.578074) (xy 301.076682 -407.585805) (xy 301.090975 -407.600088) (xy 301.098719 -407.61875)
			(xy 301.09922 -407.628852) (xy 301.09922 -407.914856) (xy 301.099467 -407.921746) (xy 301.1032 -407.935012)
			(xy 301.106586 -407.941018) (xy 301.122916 -407.969378) (xy 301.148659 -408.029544) (xy 301.166085 -408.092623)
			(xy 301.174879 -408.157472) (xy 301.174879 -408.190192) (xy 304.603666 -408.190192) (xy 304.607657 -408.128025)
			(xy 304.619566 -408.066878) (xy 304.639195 -408.007757) (xy 304.666224 -407.951631) (xy 304.700208 -407.899422)
			(xy 304.74059 -407.851987) (xy 304.786706 -407.810106) (xy 304.837798 -407.774466) (xy 304.893029 -407.745652)
			(xy 304.951491 -407.724138) (xy 305.012225 -407.710276) (xy 305.074232 -407.704294) (xy 305.136495 -407.70629)
			(xy 305.197992 -407.716233) (xy 305.257713 -407.733957) (xy 305.314676 -407.759174) (xy 305.367947 -407.791467)
			(xy 305.416652 -407.830307) (xy 305.459989 -407.875057) (xy 305.497249 -407.924981) (xy 305.527818 -407.97926)
			(xy 305.551196 -408.037003) (xy 305.566997 -408.097261) (xy 305.574963 -408.159044) (xy 305.575462 -408.190192)
			(xy 305.574963 -408.22134) (xy 305.566997 -408.283123) (xy 305.551196 -408.343381) (xy 305.527818 -408.401124)
			(xy 305.497249 -408.455403) (xy 305.459989 -408.505327) (xy 305.416652 -408.550077) (xy 305.367947 -408.588917)
			(xy 305.314676 -408.62121) (xy 305.257713 -408.646427) (xy 305.197992 -408.664151) (xy 305.136495 -408.674094)
			(xy 305.074232 -408.67609) (xy 305.012225 -408.670108) (xy 304.951491 -408.656246) (xy 304.893029 -408.634732)
			(xy 304.837798 -408.605918) (xy 304.786706 -408.570278) (xy 304.74059 -408.528397) (xy 304.700208 -408.480962)
			(xy 304.666224 -408.428753) (xy 304.639195 -408.372627) (xy 304.619566 -408.313506) (xy 304.607657 -408.252359)
			(xy 304.603666 -408.190192) (xy 301.174879 -408.190192) (xy 301.17488 -408.222914) (xy 301.166088 -408.287763)
			(xy 301.148664 -408.350843) (xy 301.122922 -408.41101) (xy 301.106586 -408.439366) (xy 301.103237 -408.445388)
			(xy 301.099491 -408.458643) (xy 301.09922 -408.465528) (xy 301.09922 -409.214828) (xy 301.099479 -409.221717)
			(xy 301.103204 -409.234983) (xy 301.106586 -409.24099) (xy 301.122892 -409.269363) (xy 301.148638 -409.329526)
			(xy 301.166066 -409.392603) (xy 301.174863 -409.457449) (xy 301.174867 -409.522889) (xy 301.166079 -409.587737)
			(xy 301.148658 -409.650815) (xy 301.12292 -409.710982) (xy 301.106586 -409.739338) (xy 301.103211 -409.745348)
			(xy 301.099482 -409.758612) (xy 301.09922 -409.7655) (xy 301.09922 -410.051504) (xy 301.098719 -410.06161)
			(xy 301.090983 -410.080285) (xy 301.076692 -410.094579) (xy 301.058018 -410.102317) (xy 301.047912 -410.102812)
			(xy 300.331632 -410.102812) (xy 300.321513 -410.102358) (xy 300.302812 -410.094623) (xy 300.288497 -410.080318)
			(xy 300.280749 -410.061623) (xy 300.280324 -410.051504) (xy 300.280324 -409.7655) (xy 300.280123 -409.758605)
			(xy 300.276373 -409.745333) (xy 300.272958 -409.739338) (xy 300.25659 -409.710999) (xy 300.230847 -409.650828)
			(xy 300.213424 -409.587745) (xy 300.204634 -409.522892) (xy 298.916079 -409.522892) (xy 298.906692 -409.539186)
			(xy 298.903382 -409.545213) (xy 298.899773 -409.558475) (xy 298.89958 -409.565348) (xy 298.89958 -410.314648)
			(xy 298.899794 -410.32152) (xy 298.903387 -410.334782) (xy 298.906692 -410.34081) (xy 298.923015 -410.369174)
			(xy 298.948758 -410.429339) (xy 298.966185 -410.492418) (xy 298.974979 -410.557266) (xy 298.974981 -410.622707)
			(xy 298.974981 -410.622708) (xy 302.404801 -410.622708) (xy 302.404803 -410.557264) (xy 302.413597 -410.492414)
			(xy 302.431024 -410.429334) (xy 302.456769 -410.369167) (xy 302.473106 -410.34081) (xy 302.476463 -410.334791)
			(xy 302.480204 -410.321534) (xy 302.480472 -410.314648) (xy 302.480472 -409.565348) (xy 302.480246 -409.558455)
			(xy 302.476512 -409.545183) (xy 302.473106 -409.539186) (xy 302.45678 -409.510824) (xy 302.431037 -409.450658)
			(xy 302.41361 -409.387579) (xy 302.404817 -409.322731) (xy 302.404815 -409.257289) (xy 302.413606 -409.192441)
			(xy 302.43103 -409.129361) (xy 302.45677 -409.069195) (xy 302.473106 -409.040838) (xy 302.476488 -409.034832)
			(xy 302.480213 -409.021565) (xy 302.480472 -409.014676) (xy 302.480472 -408.728672) (xy 302.480961 -408.718565)
			(xy 302.488703 -408.699891) (xy 302.502998 -408.685599) (xy 302.521673 -408.67786) (xy 302.53178 -408.677364)
			(xy 303.24806 -408.677364) (xy 303.258175 -408.677848) (xy 303.276871 -408.685576) (xy 303.291186 -408.699872)
			(xy 303.298939 -408.718557) (xy 303.299368 -408.728672) (xy 303.299368 -409.014676) (xy 303.299579 -409.021571)
			(xy 303.303322 -409.034843) (xy 303.306734 -409.040838) (xy 303.323082 -409.069188) (xy 303.348827 -409.129356)
			(xy 303.366253 -409.192437) (xy 303.375045 -409.257288) (xy 303.375044 -409.322732) (xy 303.366249 -409.387583)
			(xy 303.34882 -409.450663) (xy 303.331917 -409.490164) (xy 304.603666 -409.490164) (xy 304.607657 -409.427997)
			(xy 304.619566 -409.36685) (xy 304.639195 -409.307729) (xy 304.666224 -409.251603) (xy 304.700208 -409.199394)
			(xy 304.74059 -409.151959) (xy 304.786706 -409.110078) (xy 304.837798 -409.074438) (xy 304.893029 -409.045624)
			(xy 304.951491 -409.02411) (xy 305.012225 -409.010248) (xy 305.074232 -409.004266) (xy 305.136495 -409.006262)
			(xy 305.197992 -409.016205) (xy 305.257713 -409.033929) (xy 305.314676 -409.059146) (xy 305.367947 -409.091439)
			(xy 305.416652 -409.130279) (xy 305.459989 -409.175029) (xy 305.497249 -409.224953) (xy 305.527818 -409.279232)
			(xy 305.532182 -409.290012) (xy 306.803814 -409.290012) (xy 306.807805 -409.227845) (xy 306.819714 -409.166698)
			(xy 306.839343 -409.107577) (xy 306.866372 -409.051451) (xy 306.900356 -408.999242) (xy 306.940738 -408.951807)
			(xy 306.986854 -408.909926) (xy 307.037946 -408.874286) (xy 307.093177 -408.845472) (xy 307.151639 -408.823958)
			(xy 307.212373 -408.810096) (xy 307.27438 -408.804114) (xy 307.336643 -408.80611) (xy 307.39814 -408.816053)
			(xy 307.457861 -408.833777) (xy 307.514824 -408.858994) (xy 307.568095 -408.891287) (xy 307.6168 -408.930127)
			(xy 307.660137 -408.974877) (xy 307.697397 -409.024801) (xy 307.727966 -409.07908) (xy 307.751344 -409.136823)
			(xy 307.767145 -409.197081) (xy 307.775111 -409.258864) (xy 307.77561 -409.290012) (xy 307.775111 -409.32116)
			(xy 307.767145 -409.382943) (xy 307.751344 -409.443201) (xy 307.727966 -409.500944) (xy 307.697397 -409.555223)
			(xy 307.660137 -409.605147) (xy 307.6168 -409.649897) (xy 307.568095 -409.688737) (xy 307.514824 -409.72103)
			(xy 307.457861 -409.746247) (xy 307.39814 -409.763971) (xy 307.336643 -409.773914) (xy 307.27438 -409.77591)
			(xy 307.212373 -409.769928) (xy 307.151639 -409.756066) (xy 307.093177 -409.734552) (xy 307.037946 -409.705738)
			(xy 306.986854 -409.670098) (xy 306.940738 -409.628217) (xy 306.900356 -409.580782) (xy 306.866372 -409.528573)
			(xy 306.839343 -409.472447) (xy 306.819714 -409.413326) (xy 306.807805 -409.352179) (xy 306.803814 -409.290012)
			(xy 305.532182 -409.290012) (xy 305.551196 -409.336975) (xy 305.566997 -409.397233) (xy 305.574963 -409.459016)
			(xy 305.575462 -409.490164) (xy 305.574963 -409.521312) (xy 305.566997 -409.583095) (xy 305.551196 -409.643353)
			(xy 305.527818 -409.701096) (xy 305.497249 -409.755375) (xy 305.459989 -409.805299) (xy 305.416652 -409.850049)
			(xy 305.367947 -409.888889) (xy 305.314676 -409.921182) (xy 305.257713 -409.946399) (xy 305.197992 -409.964123)
			(xy 305.136495 -409.974066) (xy 305.074232 -409.976062) (xy 305.012225 -409.97008) (xy 304.951491 -409.956218)
			(xy 304.893029 -409.934704) (xy 304.837798 -409.90589) (xy 304.786706 -409.87025) (xy 304.74059 -409.828369)
			(xy 304.700208 -409.780934) (xy 304.666224 -409.728725) (xy 304.639195 -409.672599) (xy 304.619566 -409.613478)
			(xy 304.607657 -409.552331) (xy 304.603666 -409.490164) (xy 303.331917 -409.490164) (xy 303.323073 -409.51083)
			(xy 303.306734 -409.539186) (xy 303.303373 -409.545203) (xy 303.299636 -409.558462) (xy 303.299368 -409.565348)
			(xy 303.299368 -410.314648) (xy 303.29959 -410.321542) (xy 303.303326 -410.334814) (xy 303.306734 -410.34081)
			(xy 303.323059 -410.369173) (xy 303.348805 -410.429338) (xy 303.366234 -410.492417) (xy 303.375029 -410.557265)
			(xy 303.37503 -410.589984) (xy 306.803814 -410.589984) (xy 306.807805 -410.527817) (xy 306.819714 -410.46667)
			(xy 306.839343 -410.407549) (xy 306.866372 -410.351423) (xy 306.900356 -410.299214) (xy 306.940738 -410.251779)
			(xy 306.986854 -410.209898) (xy 307.037946 -410.174258) (xy 307.093177 -410.145444) (xy 307.151639 -410.12393)
			(xy 307.212373 -410.110068) (xy 307.27438 -410.104086) (xy 307.336643 -410.106082) (xy 307.39814 -410.116025)
			(xy 307.457861 -410.133749) (xy 307.514824 -410.158966) (xy 307.568095 -410.191259) (xy 307.6168 -410.230099)
			(xy 307.660137 -410.274849) (xy 307.697397 -410.324773) (xy 307.727966 -410.379052) (xy 307.751344 -410.436795)
			(xy 307.767145 -410.497053) (xy 307.775111 -410.558836) (xy 307.77561 -410.589984) (xy 307.775111 -410.621132)
			(xy 307.767145 -410.682915) (xy 307.751344 -410.743173) (xy 307.727966 -410.800916) (xy 307.697397 -410.855195)
			(xy 307.660137 -410.905119) (xy 307.6168 -410.949869) (xy 307.568095 -410.988709) (xy 307.514824 -411.021002)
			(xy 307.457861 -411.046219) (xy 307.39814 -411.063943) (xy 307.336643 -411.073886) (xy 307.27438 -411.075882)
			(xy 307.212373 -411.0699) (xy 307.151639 -411.056038) (xy 307.093177 -411.034524) (xy 307.037946 -411.00571)
			(xy 306.986854 -410.97007) (xy 306.940738 -410.928189) (xy 306.900356 -410.880754) (xy 306.866372 -410.828545)
			(xy 306.839343 -410.772419) (xy 306.819714 -410.713298) (xy 306.807805 -410.652151) (xy 306.803814 -410.589984)
			(xy 303.37503 -410.589984) (xy 303.375031 -410.622707) (xy 303.36624 -410.687556) (xy 303.348814 -410.750636)
			(xy 303.323071 -410.810802) (xy 303.306734 -410.839158) (xy 303.303348 -410.845162) (xy 303.299626 -410.858431)
			(xy 303.299368 -410.86532) (xy 303.299368 -411.151324) (xy 303.299003 -411.161452) (xy 303.291241 -411.180162)
			(xy 303.276909 -411.194477) (xy 303.258189 -411.202216) (xy 303.24806 -411.202632) (xy 302.53178 -411.202632)
			(xy 302.521674 -411.202132) (xy 302.503001 -411.194394) (xy 302.488708 -411.180102) (xy 302.480969 -411.16143)
			(xy 302.480472 -411.151324) (xy 302.480472 -410.86532) (xy 302.480235 -410.858429) (xy 302.476496 -410.845163)
			(xy 302.473106 -410.839158) (xy 302.456756 -410.810809) (xy 302.431015 -410.75064) (xy 302.413591 -410.687559)
			(xy 302.404801 -410.622708) (xy 298.974981 -410.622708) (xy 298.966191 -410.687555) (xy 298.948767 -410.750635)
			(xy 298.923027 -410.810802) (xy 298.906692 -410.839158) (xy 298.903392 -410.84519) (xy 298.899777 -410.858448)
			(xy 298.89958 -410.86532) (xy 298.89958 -411.151324) (xy 298.899198 -411.161482) (xy 298.891391 -411.180239)
			(xy 298.876982 -411.194562) (xy 298.858179 -411.202258) (xy 298.848018 -411.202632) (xy 298.131738 -411.202632)
			(xy 298.12161 -411.202141) (xy 298.102885 -411.194421) (xy 298.088526 -411.180135) (xy 298.080711 -411.161449)
			(xy 298.080176 -411.151324) (xy 298.080176 -410.86532) (xy 298.079979 -410.858447) (xy 298.076375 -410.845184)
			(xy 298.073064 -410.839158) (xy 298.056712 -410.81081) (xy 298.030968 -410.750641) (xy 298.013542 -410.68756)
			(xy 298.004751 -410.622708) (xy 294.574945 -410.622708) (xy 294.566154 -410.687556) (xy 294.548729 -410.750636)
			(xy 294.522987 -410.810802) (xy 294.50665 -410.839158) (xy 294.503266 -410.845163) (xy 294.499543 -410.858431)
			(xy 294.499284 -410.86532) (xy 294.499284 -411.151324) (xy 294.498834 -411.161436) (xy 294.491086 -411.180118)
			(xy 294.476778 -411.194413) (xy 294.458089 -411.202144) (xy 294.447976 -411.202632) (xy 293.731696 -411.202632)
			(xy 293.721591 -411.202119) (xy 293.702919 -411.194386) (xy 293.688625 -411.180098) (xy 293.680885 -411.161429)
			(xy 293.680388 -411.151324) (xy 293.680388 -410.86532) (xy 293.680149 -410.858429) (xy 293.676411 -410.845163)
			(xy 293.673022 -410.839158) (xy 293.656672 -410.810809) (xy 293.63093 -410.750641) (xy 293.613506 -410.687559)
			(xy 293.604715 -410.622708) (xy 290.174909 -410.622708) (xy 290.166117 -410.687557) (xy 290.148691 -410.750636)
			(xy 290.122946 -410.810802) (xy 290.106608 -410.839158) (xy 290.103309 -410.84519) (xy 290.099693 -410.858448)
			(xy 290.099496 -410.86532) (xy 290.099496 -411.151324) (xy 290.099098 -411.16148) (xy 290.091294 -411.180234)
			(xy 290.07689 -411.194557) (xy 290.058092 -411.202255) (xy 290.047934 -411.202632) (xy 289.331654 -411.202632)
			(xy 289.321521 -411.20221) (xy 289.302793 -411.194462) (xy 289.288438 -411.180156) (xy 289.280625 -411.161455)
			(xy 289.280092 -411.151324) (xy 289.280092 -410.86532) (xy 289.279893 -410.858447) (xy 289.27629 -410.845185)
			(xy 289.27298 -410.839158) (xy 289.256628 -410.81081) (xy 289.230883 -410.750642) (xy 289.213457 -410.68756)
			(xy 289.204665 -410.622709) (xy 283.301948 -410.622709) (xy 283.301948 -412.090108) (xy 287.003752 -412.090108)
			(xy 287.007743 -412.027941) (xy 287.019652 -411.966794) (xy 287.039281 -411.907673) (xy 287.06631 -411.851547)
			(xy 287.100294 -411.799338) (xy 287.140676 -411.751903) (xy 287.186792 -411.710022) (xy 287.237884 -411.674382)
			(xy 287.293115 -411.645568) (xy 287.351577 -411.624054) (xy 287.412311 -411.610192) (xy 287.474318 -411.60421)
			(xy 287.536581 -411.606206) (xy 287.598078 -411.616149) (xy 287.657799 -411.633873) (xy 287.714762 -411.65909)
			(xy 287.768033 -411.691383) (xy 287.816738 -411.730223) (xy 287.860075 -411.774973) (xy 287.897335 -411.824897)
			(xy 287.927904 -411.879176) (xy 287.951282 -411.936919) (xy 287.967083 -411.997177) (xy 287.975049 -412.05896)
			(xy 287.975548 -412.090108) (xy 291.403794 -412.090108) (xy 291.407785 -412.027941) (xy 291.419694 -411.966794)
			(xy 291.439323 -411.907673) (xy 291.466352 -411.851547) (xy 291.500336 -411.799338) (xy 291.540718 -411.751903)
			(xy 291.586834 -411.710022) (xy 291.637926 -411.674382) (xy 291.693157 -411.645568) (xy 291.751619 -411.624054)
			(xy 291.812353 -411.610192) (xy 291.87436 -411.60421) (xy 291.936623 -411.606206) (xy 291.99812 -411.616149)
			(xy 292.057841 -411.633873) (xy 292.114804 -411.65909) (xy 292.168075 -411.691383) (xy 292.21678 -411.730223)
			(xy 292.260117 -411.774973) (xy 292.297377 -411.824897) (xy 292.327946 -411.879176) (xy 292.351324 -411.936919)
			(xy 292.367125 -411.997177) (xy 292.375091 -412.05896) (xy 292.37559 -412.090108) (xy 295.803836 -412.090108)
			(xy 295.807827 -412.027941) (xy 295.819736 -411.966794) (xy 295.839365 -411.907673) (xy 295.866394 -411.851547)
			(xy 295.900378 -411.799338) (xy 295.94076 -411.751903) (xy 295.986876 -411.710022) (xy 296.037968 -411.674382)
			(xy 296.093199 -411.645568) (xy 296.151661 -411.624054) (xy 296.212395 -411.610192) (xy 296.274402 -411.60421)
			(xy 296.336665 -411.606206) (xy 296.398162 -411.616149) (xy 296.457883 -411.633873) (xy 296.514846 -411.65909)
			(xy 296.568117 -411.691383) (xy 296.616822 -411.730223) (xy 296.660159 -411.774973) (xy 296.697419 -411.824897)
			(xy 296.727988 -411.879176) (xy 296.751366 -411.936919) (xy 296.767167 -411.997177) (xy 296.775133 -412.05896)
			(xy 296.775632 -412.090108) (xy 300.203624 -412.090108) (xy 300.207615 -412.027941) (xy 300.219524 -411.966794)
			(xy 300.239153 -411.907673) (xy 300.266182 -411.851547) (xy 300.300166 -411.799338) (xy 300.340548 -411.751903)
			(xy 300.386664 -411.710022) (xy 300.437756 -411.674382) (xy 300.492987 -411.645568) (xy 300.551449 -411.624054)
			(xy 300.612183 -411.610192) (xy 300.67419 -411.60421) (xy 300.736453 -411.606206) (xy 300.79795 -411.616149)
			(xy 300.857671 -411.633873) (xy 300.914634 -411.65909) (xy 300.967905 -411.691383) (xy 301.01661 -411.730223)
			(xy 301.059947 -411.774973) (xy 301.097207 -411.824897) (xy 301.127776 -411.879176) (xy 301.151154 -411.936919)
			(xy 301.166955 -411.997177) (xy 301.174921 -412.05896) (xy 301.17542 -412.090108) (xy 304.603666 -412.090108)
			(xy 304.607657 -412.027941) (xy 304.619566 -411.966794) (xy 304.639195 -411.907673) (xy 304.666224 -411.851547)
			(xy 304.700208 -411.799338) (xy 304.74059 -411.751903) (xy 304.786706 -411.710022) (xy 304.837798 -411.674382)
			(xy 304.893029 -411.645568) (xy 304.951491 -411.624054) (xy 305.012225 -411.610192) (xy 305.074232 -411.60421)
			(xy 305.136495 -411.606206) (xy 305.197992 -411.616149) (xy 305.257713 -411.633873) (xy 305.314676 -411.65909)
			(xy 305.367947 -411.691383) (xy 305.416652 -411.730223) (xy 305.459989 -411.774973) (xy 305.497249 -411.824897)
			(xy 305.527818 -411.879176) (xy 305.551196 -411.936919) (xy 305.566997 -411.997177) (xy 305.574963 -412.05896)
			(xy 305.575462 -412.090108) (xy 305.574963 -412.121256) (xy 305.566997 -412.183039) (xy 305.551196 -412.243297)
			(xy 305.527818 -412.30104) (xy 305.497249 -412.355319) (xy 305.459989 -412.405243) (xy 305.416652 -412.449993)
			(xy 305.367947 -412.488833) (xy 305.314676 -412.521126) (xy 305.257713 -412.546343) (xy 305.197992 -412.564067)
			(xy 305.136495 -412.57401) (xy 305.074232 -412.576006) (xy 305.012225 -412.570024) (xy 304.951491 -412.556162)
			(xy 304.893029 -412.534648) (xy 304.837798 -412.505834) (xy 304.786706 -412.470194) (xy 304.74059 -412.428313)
			(xy 304.700208 -412.380878) (xy 304.666224 -412.328669) (xy 304.639195 -412.272543) (xy 304.619566 -412.213422)
			(xy 304.607657 -412.152275) (xy 304.603666 -412.090108) (xy 301.17542 -412.090108) (xy 301.174921 -412.121256)
			(xy 301.166955 -412.183039) (xy 301.151154 -412.243297) (xy 301.127776 -412.30104) (xy 301.097207 -412.355319)
			(xy 301.059947 -412.405243) (xy 301.01661 -412.449993) (xy 300.967905 -412.488833) (xy 300.914634 -412.521126)
			(xy 300.857671 -412.546343) (xy 300.79795 -412.564067) (xy 300.736453 -412.57401) (xy 300.67419 -412.576006)
			(xy 300.612183 -412.570024) (xy 300.551449 -412.556162) (xy 300.492987 -412.534648) (xy 300.437756 -412.505834)
			(xy 300.386664 -412.470194) (xy 300.340548 -412.428313) (xy 300.300166 -412.380878) (xy 300.266182 -412.328669)
			(xy 300.239153 -412.272543) (xy 300.219524 -412.213422) (xy 300.207615 -412.152275) (xy 300.203624 -412.090108)
			(xy 296.775632 -412.090108) (xy 296.775133 -412.121256) (xy 296.767167 -412.183039) (xy 296.751366 -412.243297)
			(xy 296.727988 -412.30104) (xy 296.697419 -412.355319) (xy 296.660159 -412.405243) (xy 296.616822 -412.449993)
			(xy 296.568117 -412.488833) (xy 296.514846 -412.521126) (xy 296.457883 -412.546343) (xy 296.398162 -412.564067)
			(xy 296.336665 -412.57401) (xy 296.274402 -412.576006) (xy 296.212395 -412.570024) (xy 296.151661 -412.556162)
			(xy 296.093199 -412.534648) (xy 296.037968 -412.505834) (xy 295.986876 -412.470194) (xy 295.94076 -412.428313)
			(xy 295.900378 -412.380878) (xy 295.866394 -412.328669) (xy 295.839365 -412.272543) (xy 295.819736 -412.213422)
			(xy 295.807827 -412.152275) (xy 295.803836 -412.090108) (xy 292.37559 -412.090108) (xy 292.375091 -412.121256)
			(xy 292.367125 -412.183039) (xy 292.351324 -412.243297) (xy 292.327946 -412.30104) (xy 292.297377 -412.355319)
			(xy 292.260117 -412.405243) (xy 292.21678 -412.449993) (xy 292.168075 -412.488833) (xy 292.114804 -412.521126)
			(xy 292.057841 -412.546343) (xy 291.99812 -412.564067) (xy 291.936623 -412.57401) (xy 291.87436 -412.576006)
			(xy 291.812353 -412.570024) (xy 291.751619 -412.556162) (xy 291.693157 -412.534648) (xy 291.637926 -412.505834)
			(xy 291.586834 -412.470194) (xy 291.540718 -412.428313) (xy 291.500336 -412.380878) (xy 291.466352 -412.328669)
			(xy 291.439323 -412.272543) (xy 291.419694 -412.213422) (xy 291.407785 -412.152275) (xy 291.403794 -412.090108)
			(xy 287.975548 -412.090108) (xy 287.975049 -412.121256) (xy 287.967083 -412.183039) (xy 287.951282 -412.243297)
			(xy 287.927904 -412.30104) (xy 287.897335 -412.355319) (xy 287.860075 -412.405243) (xy 287.816738 -412.449993)
			(xy 287.768033 -412.488833) (xy 287.714762 -412.521126) (xy 287.657799 -412.546343) (xy 287.598078 -412.564067)
			(xy 287.536581 -412.57401) (xy 287.474318 -412.576006) (xy 287.412311 -412.570024) (xy 287.351577 -412.556162)
			(xy 287.293115 -412.534648) (xy 287.237884 -412.505834) (xy 287.186792 -412.470194) (xy 287.140676 -412.428313)
			(xy 287.100294 -412.380878) (xy 287.06631 -412.328669) (xy 287.039281 -412.272543) (xy 287.019652 -412.213422)
			(xy 287.007743 -412.152275) (xy 287.003752 -412.090108) (xy 283.301948 -412.090108) (xy 283.301948 -417.298886)
			(xy 283.302388 -417.308948) (xy 283.31013 -417.327525) (xy 283.316934 -417.334954) (xy 283.939488 -417.957508)
			(xy 283.946886 -417.964355) (xy 283.965484 -417.972093) (xy 283.975556 -417.972494) (xy 321.860418 -417.972494)
		)
		(stroke
			(width 0)
			(type solid)
		)
		(fill yes)
		(layer "In13.Cu")
		(net "GND")
	)
)
